(kicad_pcb
	(version 20260206)
	(generator "pcbnew")
	(generator_version "10.0")
	(general
		(thickness 1.6)
		(legacy_teardrops no)
	)
	(paper "A4")
	(layers
		(0 "F.Cu" signal "TOP")
		(4 "In1.Cu" signal "GND")
		(6 "In2.Cu" signal "IN1")
		(8 "In3.Cu" signal "GND1")
		(10 "In4.Cu" signal "IN2")
		(12 "In5.Cu" signal "GND2")
		(14 "In6.Cu" signal "IN3")
		(16 "In7.Cu" signal "GND3")
		(18 "In8.Cu" signal "VCC")
		(20 "In9.Cu" signal "VCC1")
		(22 "In10.Cu" signal "GND4")
		(24 "In11.Cu" signal "IN4")
		(26 "In12.Cu" signal "GND5")
		(28 "In13.Cu" signal "IN5")
		(30 "In14.Cu" signal "GND6")
		(32 "In15.Cu" signal "IN6")
		(34 "In16.Cu" signal "GND7")
		(2 "B.Cu" signal "BOTTOM")
		(9 "F.Adhes" user "F.Adhesive")
		(11 "B.Adhes" user "B.Adhesive")
		(13 "F.Paste" user "Package Geometry/Pastemask Top")
		(15 "B.Paste" user "Package Geometry/Pastemask Bottom")
		(5 "F.SilkS" user "Ref Des/Silkscreen Top")
		(7 "B.SilkS" user "Ref Des/Silkscreen Bottom")
		(1 "F.Mask" user "Board Geometry/Soldermask Top")
		(3 "B.Mask" user "Board Geometry/Soldermask Bottom")
		(17 "Dwgs.User" user "User.Drawings")
		(19 "Cmts.User" user "User.Comments")
		(21 "Eco1.User" user "User.Eco1")
		(23 "Eco2.User" user "User.Eco2")
		(25 "Edge.Cuts" user "Board Geometry/Outline")
		(27 "Margin" user)
		(31 "F.CrtYd" user "Package Geometry/Place Bound Top")
		(29 "B.CrtYd" user "Package Geometry/Place Bound Bottom")
		(35 "F.Fab" user "Ref Des/Assembly Top")
		(33 "B.Fab" user "Ref Des/Assembly Bottom")
	)
	(setup
		(pad_to_mask_clearance 0)
		(allow_soldermask_bridges_in_footprints no)
		(tenting
			(front yes)
			(back yes)
		)
		(covering
			(front no)
			(back no)
		)
		(plugging
			(front no)
			(back no)
		)
		(capping no)
		(filling no)
		(pcbplotparams
			(layerselection 0x00000000_00000000_55555555_5755f5ff)
			(plot_on_all_layers_selection 0x00000000_00000000_00000000_00000000)
			(disableapertmacros no)
			(usegerberextensions no)
			(usegerberattributes yes)
			(usegerberadvancedattributes yes)
			(creategerberjobfile yes)
			(dashed_line_dash_ratio 12)
			(dashed_line_gap_ratio 3)
			(svgprecision 4)
			(plotframeref no)
			(mode 1)
			(useauxorigin no)
			(pdf_front_fp_property_popups yes)
			(pdf_back_fp_property_popups yes)
			(pdf_metadata yes)
			(pdf_single_document no)
			(dxfpolygonmode yes)
			(dxfimperialunits yes)
			(dxfusepcbnewfont yes)
			(psnegative no)
			(psa4output no)
			(plot_black_and_white yes)
			(sketchpadsonfab no)
			(plotpadnumbers no)
			(hidednponfab no)
			(sketchdnponfab yes)
			(crossoutdnponfab yes)
			(subtractmaskfromsilk no)
			(outputformat 1)
			(mirror no)
			(drillshape 1)
			(scaleselection 1)
			(outputdirectory "")
		)
	)
	(gr_poly
		(pts
			(xy 195.113402 -76.844144) (xy 195.123009 -76.843724) (xy 195.140879 -76.836665) (xy 195.1482 -76.830428)
			(xy 195.155312 -76.823824) (xy 195.16344 -76.806806) (xy 195.164202 -76.797154) (xy 195.166694 -76.770057)
			(xy 195.178383 -76.716915) (xy 195.197505 -76.665972) (xy 195.22367 -76.618262) (xy 195.256347 -76.574754)
			(xy 195.294875 -76.536329) (xy 195.338471 -76.503769) (xy 195.386251 -76.477732) (xy 195.437245 -76.458747)
			(xy 195.490419 -76.447201) (xy 195.544694 -76.443325) (xy 195.598969 -76.447201) (xy 195.652143 -76.458747)
			(xy 195.703137 -76.477732) (xy 195.750917 -76.503769) (xy 195.794513 -76.536329) (xy 195.833041 -76.574754)
			(xy 195.865718 -76.618262) (xy 195.891883 -76.665972) (xy 195.911005 -76.716915) (xy 195.922694 -76.770057)
			(xy 195.925186 -76.797154) (xy 195.925948 -76.806806) (xy 195.934076 -76.823824) (xy 195.941188 -76.830428)
			(xy 195.948476 -76.836717) (xy 195.966367 -76.843781) (xy 195.975986 -76.844144) (xy 197.561454 -76.844144)
			(xy 197.572779 -76.843532) (xy 197.593213 -76.833759) (xy 197.600824 -76.825348) (xy 197.619042 -76.803768)
			(xy 197.660753 -76.765698) (xy 197.707622 -76.734193) (xy 197.758623 -76.709941) (xy 197.812641 -76.693473)
			(xy 197.868497 -76.685148) (xy 197.924971 -76.685148) (xy 197.980827 -76.693473) (xy 198.034845 -76.709941)
			(xy 198.085846 -76.734193) (xy 198.132715 -76.765698) (xy 198.174426 -76.803768) (xy 198.192644 -76.825348)
			(xy 198.200261 -76.833744) (xy 198.220696 -76.843495) (xy 198.232014 -76.844144) (xy 199.442324 -76.844144)
			(xy 199.452332 -76.843652) (xy 199.470823 -76.83599) (xy 199.484979 -76.82184) (xy 199.492648 -76.803351)
			(xy 199.493124 -76.793344) (xy 199.493124 -75.359514) (xy 199.492635 -75.349553) (xy 199.485045 -75.331131)
			(xy 199.478392 -75.3237) (xy 197.869302 -73.71461) (xy 197.852225 -73.696909) (xy 197.823293 -73.657134)
			(xy 197.800947 -73.613319) (xy 197.785737 -73.566546) (xy 197.778039 -73.517968) (xy 197.777608 -73.493376)
			(xy 197.777608 -71.787004) (xy 197.777442 -71.77969) (xy 197.773439 -71.765626) (xy 197.769734 -71.759318)
			(xy 197.755371 -71.736148) (xy 197.732692 -71.686576) (xy 197.717303 -71.634281) (xy 197.709517 -71.580326)
			(xy 197.709028 -71.55307) (xy 197.709514 -71.525819) (xy 197.71727 -71.471871) (xy 197.732625 -71.419576)
			(xy 197.755267 -71.369999) (xy 197.784733 -71.324149) (xy 197.820424 -71.282958) (xy 197.861615 -71.247267)
			(xy 197.907465 -71.217801) (xy 197.957042 -71.195159) (xy 198.009337 -71.179804) (xy 198.063285 -71.172048)
			(xy 198.117787 -71.172048) (xy 198.171735 -71.179804) (xy 198.22403 -71.195159) (xy 198.273607 -71.217801)
			(xy 198.319457 -71.247267) (xy 198.360648 -71.282958) (xy 198.396339 -71.324149) (xy 198.425805 -71.369999)
			(xy 198.448447 -71.419576) (xy 198.463802 -71.471871) (xy 198.471558 -71.525819) (xy 198.472044 -71.55307)
			(xy 198.471539 -71.580325) (xy 198.463745 -71.634274) (xy 198.448354 -71.686566) (xy 198.425679 -71.736136)
			(xy 198.411338 -71.759318) (xy 198.407624 -71.765623) (xy 198.403616 -71.779689) (xy 198.403464 -71.787004)
			(xy 198.403464 -73.342754) (xy 198.403947 -73.352718) (xy 198.411528 -73.371149) (xy 198.418196 -73.378568)
			(xy 200.027286 -74.987658) (xy 200.04436 -75.005361) (xy 200.073284 -75.045137) (xy 200.095621 -75.088952)
			(xy 200.110822 -75.135725) (xy 200.11851 -75.184301) (xy 200.118805 -75.199748) (xy 201.096116 -75.199748)
			(xy 201.100187 -75.144126) (xy 201.112313 -75.089689) (xy 201.132236 -75.037598) (xy 201.159532 -74.988963)
			(xy 201.193618 -74.94482) (xy 201.233767 -74.906111) (xy 201.279125 -74.87366) (xy 201.328725 -74.848159)
			(xy 201.381509 -74.830152) (xy 201.436352 -74.820022) (xy 201.492086 -74.817985) (xy 201.547523 -74.824085)
			(xy 201.60148 -74.838191) (xy 201.652809 -74.860003) (xy 201.700415 -74.889057) (xy 201.743283 -74.924732)
			(xy 201.7805 -74.966269) (xy 201.811273 -75.012782) (xy 201.834945 -75.063279) (xy 201.851013 -75.116686)
			(xy 201.859133 -75.171862) (xy 201.859642 -75.199748) (xy 201.859133 -75.227634) (xy 201.851013 -75.28281)
			(xy 201.834945 -75.336217) (xy 201.811273 -75.386714) (xy 201.7805 -75.433227) (xy 201.743283 -75.474764)
			(xy 201.700415 -75.510439) (xy 201.652809 -75.539493) (xy 201.60148 -75.561305) (xy 201.547523 -75.575411)
			(xy 201.492086 -75.581511) (xy 201.436352 -75.579474) (xy 201.381509 -75.569344) (xy 201.328725 -75.551337)
			(xy 201.279125 -75.525836) (xy 201.233767 -75.493385) (xy 201.193618 -75.454676) (xy 201.159532 -75.410533)
			(xy 201.132236 -75.361898) (xy 201.112313 -75.309807) (xy 201.100187 -75.25537) (xy 201.096116 -75.199748)
			(xy 200.118805 -75.199748) (xy 200.11898 -75.208892) (xy 200.11898 -75.624182) (xy 202.592684 -75.624182)
			(xy 202.596755 -75.56856) (xy 202.608881 -75.514123) (xy 202.628804 -75.462032) (xy 202.6561 -75.413397)
			(xy 202.690186 -75.369254) (xy 202.730335 -75.330545) (xy 202.775693 -75.298094) (xy 202.825293 -75.272593)
			(xy 202.878077 -75.254586) (xy 202.93292 -75.244456) (xy 202.988654 -75.242419) (xy 203.044091 -75.248519)
			(xy 203.098048 -75.262625) (xy 203.149377 -75.284437) (xy 203.196983 -75.313491) (xy 203.239851 -75.349166)
			(xy 203.277068 -75.390703) (xy 203.307841 -75.437216) (xy 203.331513 -75.487713) (xy 203.347581 -75.54112)
			(xy 203.355701 -75.596296) (xy 203.35621 -75.624182) (xy 203.355701 -75.652068) (xy 203.347581 -75.707244)
			(xy 203.331513 -75.760651) (xy 203.307841 -75.811148) (xy 203.277068 -75.857661) (xy 203.239851 -75.899198)
			(xy 203.196983 -75.934873) (xy 203.149377 -75.963927) (xy 203.098048 -75.985739) (xy 203.044091 -75.999845)
			(xy 202.988654 -76.005945) (xy 202.93292 -76.003908) (xy 202.878077 -75.993778) (xy 202.825293 -75.975771)
			(xy 202.775693 -75.95027) (xy 202.730335 -75.917819) (xy 202.690186 -75.87911) (xy 202.6561 -75.834967)
			(xy 202.628804 -75.786332) (xy 202.608881 -75.734241) (xy 202.596755 -75.679804) (xy 202.592684 -75.624182)
			(xy 200.11898 -75.624182) (xy 200.11898 -76.793344) (xy 200.119475 -76.803347) (xy 200.127142 -76.821828)
			(xy 200.141293 -76.835972) (xy 200.159776 -76.84363) (xy 200.16978 -76.844144) (xy 201.229722 -76.844144)
			(xy 201.241385 -76.843567) (xy 201.262295 -76.833234) (xy 201.269854 -76.824332) (xy 201.270362 -76.823824)
			(xy 201.326242 -76.747624) (xy 201.330052 -76.723494) (xy 201.326496 -76.712064) (xy 201.318573 -76.684929)
			(xy 201.309901 -76.629072) (xy 201.309224 -76.600812) (xy 201.309224 -76.59497) (xy 201.309951 -76.567885)
			(xy 201.318116 -76.514321) (xy 201.333777 -76.462452) (xy 201.356618 -76.41332) (xy 201.386181 -76.367914)
			(xy 201.42187 -76.327147) (xy 201.462968 -76.291839) (xy 201.508648 -76.262701) (xy 201.557991 -76.240318)
			(xy 201.610004 -76.225141) (xy 201.663641 -76.217476) (xy 201.717823 -76.217476) (xy 201.77146 -76.225141)
			(xy 201.823473 -76.240318) (xy 201.872816 -76.262701) (xy 201.918496 -76.291839) (xy 201.959594 -76.327147)
			(xy 201.995283 -76.367914) (xy 202.024846 -76.41332) (xy 202.047687 -76.462452) (xy 202.063348 -76.514321)
			(xy 202.071513 -76.567885) (xy 202.07224 -76.59497) (xy 202.07224 -76.59878) (xy 202.071698 -76.627552)
			(xy 202.063029 -76.684439) (xy 202.054968 -76.712064) (xy 202.051412 -76.723494) (xy 202.055222 -76.747624)
			(xy 202.110848 -76.823316) (xy 202.11161 -76.824078) (xy 202.11161 -76.824332) (xy 202.119187 -76.833211)
			(xy 202.140086 -76.843555) (xy 202.151742 -76.844144) (xy 202.374246 -76.844144) (xy 202.386894 -76.84348)
			(xy 202.409167 -76.831491) (xy 202.416664 -76.821284) (xy 202.470512 -76.739242) (xy 202.472544 -76.713842)
			(xy 202.467464 -76.702158) (xy 202.457423 -76.67802) (xy 202.443289 -76.627687) (xy 202.436152 -76.575898)
			(xy 202.435714 -76.549758) (xy 202.4362 -76.522507) (xy 202.443956 -76.468559) (xy 202.459311 -76.416264)
			(xy 202.481953 -76.366687) (xy 202.511419 -76.320837) (xy 202.54711 -76.279646) (xy 202.588301 -76.243955)
			(xy 202.634151 -76.214489) (xy 202.683728 -76.191847) (xy 202.736023 -76.176492) (xy 202.789971 -76.168736)
			(xy 202.844473 -76.168736) (xy 202.898421 -76.176492) (xy 202.950716 -76.191847) (xy 203.000293 -76.214489)
			(xy 203.046143 -76.243955) (xy 203.087334 -76.279646) (xy 203.123025 -76.320837) (xy 203.152491 -76.366687)
			(xy 203.175133 -76.416264) (xy 203.190488 -76.468559) (xy 203.198244 -76.522507) (xy 203.19873 -76.549758)
			(xy 203.198303 -76.575899) (xy 203.191171 -76.627691) (xy 203.177033 -76.678024) (xy 203.16698 -76.702158)
			(xy 203.1619 -76.713842) (xy 203.163932 -76.739242) (xy 203.21778 -76.821284) (xy 203.225301 -76.831464)
			(xy 203.247559 -76.843447) (xy 203.260198 -76.844144) (xy 203.707492 -76.844144) (xy 203.719684 -76.84262)
			(xy 203.726909 -76.840599) (xy 203.739828 -76.832987) (xy 203.745084 -76.827634) (xy 203.802996 -76.764388)
			(xy 203.809854 -76.744576) (xy 203.808838 -76.733654) (xy 203.807314 -76.700126) (xy 203.8078 -76.672875)
			(xy 203.815556 -76.618927) (xy 203.830911 -76.566632) (xy 203.853553 -76.517055) (xy 203.883019 -76.471205)
			(xy 203.91871 -76.430014) (xy 203.959901 -76.394323) (xy 204.005751 -76.364857) (xy 204.055328 -76.342215)
			(xy 204.107623 -76.32686) (xy 204.161571 -76.319104) (xy 204.216073 -76.319104) (xy 204.270021 -76.32686)
			(xy 204.322316 -76.342215) (xy 204.371893 -76.364857) (xy 204.417743 -76.394323) (xy 204.458934 -76.430014)
			(xy 204.494625 -76.471205) (xy 204.524091 -76.517055) (xy 204.546733 -76.566632) (xy 204.562088 -76.618927)
			(xy 204.569844 -76.672875) (xy 204.57033 -76.700126) (xy 204.568806 -76.733654) (xy 204.56779 -76.744576)
			(xy 204.574648 -76.764388) (xy 204.63256 -76.827634) (xy 204.640056 -76.835186) (xy 204.65952 -76.84374)
			(xy 204.670152 -76.844144) (xy 205.189836 -76.844144) (xy 205.199842 -76.84365) (xy 205.218329 -76.835986)
			(xy 205.232481 -76.821836) (xy 205.240149 -76.80335) (xy 205.240636 -76.793344) (xy 205.240636 -76.117196)
			(xy 205.240162 -76.107228) (xy 205.232594 -76.088784) (xy 205.225904 -76.081382) (xy 203.60513 -74.460608)
			(xy 203.588051 -74.442907) (xy 203.559118 -74.403133) (xy 203.53677 -74.359319) (xy 203.521559 -74.312545)
			(xy 203.51386 -74.263966) (xy 203.513436 -74.239374) (xy 203.513436 -73.278746) (xy 203.513122 -73.269971)
			(xy 203.507271 -73.253432) (xy 203.496144 -73.239867) (xy 203.488798 -73.235058) (xy 203.402438 -73.183496)
			(xy 203.375768 -73.182734) (xy 203.36383 -73.189084) (xy 203.335931 -73.203353) (xy 203.276629 -73.223589)
			(xy 203.214819 -73.23387) (xy 203.18349 -73.23455) (xy 203.156236 -73.234063) (xy 203.102284 -73.226305)
			(xy 203.049984 -73.210947) (xy 203.000403 -73.188303) (xy 202.954549 -73.158833) (xy 202.913355 -73.123138)
			(xy 202.877661 -73.081943) (xy 202.848192 -73.036088) (xy 202.825549 -72.986506) (xy 202.810193 -72.934207)
			(xy 202.802436 -72.880254) (xy 202.802436 -72.825746) (xy 202.810193 -72.771793) (xy 202.825549 -72.719494)
			(xy 202.848192 -72.669912) (xy 202.877661 -72.624057) (xy 202.913355 -72.582862) (xy 202.954549 -72.547167)
			(xy 203.000403 -72.517697) (xy 203.049984 -72.495053) (xy 203.102284 -72.479695) (xy 203.156236 -72.471937)
			(xy 203.18349 -72.471534) (xy 203.214822 -72.472183) (xy 203.276637 -72.482461) (xy 203.33594 -72.502709)
			(xy 203.36383 -72.517) (xy 203.375768 -72.52335) (xy 203.402438 -72.522588) (xy 203.488798 -72.471026)
			(xy 203.496118 -72.466189) (xy 203.507215 -72.452615) (xy 203.513112 -72.436104) (xy 203.513436 -72.427338)
			(xy 203.513436 -71.338186) (xy 203.51296 -71.328219) (xy 203.50539 -71.309778) (xy 203.498704 -71.302372)
			(xy 203.4794 -71.283068) (xy 203.466954 -71.27621) (xy 203.459588 -71.274686) (xy 203.43158 -71.268072)
			(xy 203.377814 -71.247555) (xy 203.327743 -71.219188) (xy 203.282506 -71.183616) (xy 203.243131 -71.141648)
			(xy 203.226416 -71.118222) (xy 203.219304 -71.107808) (xy 203.197206 -71.096124) (xy 203.087986 -71.096378)
			(xy 203.066142 -71.108062) (xy 203.05903 -71.118476) (xy 203.043702 -71.140063) (xy 203.008044 -71.179198)
			(xy 202.967322 -71.213031) (xy 202.922317 -71.240916) (xy 202.873891 -71.262318) (xy 202.822974 -71.276826)
			(xy 202.770542 -71.284162) (xy 202.74407 -71.284592) (xy 202.716821 -71.284104) (xy 202.662879 -71.276344)
			(xy 202.61059 -71.260987) (xy 202.561019 -71.238345) (xy 202.515174 -71.208879) (xy 202.473989 -71.173189)
			(xy 202.438303 -71.132002) (xy 202.40884 -71.086155) (xy 202.386202 -71.036582) (xy 202.37085 -70.984291)
			(xy 202.363094 -70.930349) (xy 202.363094 -70.875851) (xy 202.37085 -70.821909) (xy 202.386202 -70.769618)
			(xy 202.40884 -70.720045) (xy 202.438303 -70.674198) (xy 202.473989 -70.633011) (xy 202.515174 -70.597321)
			(xy 202.561019 -70.567855) (xy 202.61059 -70.545213) (xy 202.662879 -70.529856) (xy 202.716821 -70.522096)
			(xy 202.74407 -70.521576) (xy 202.770451 -70.52202) (xy 202.822711 -70.529286) (xy 202.873471 -70.543685)
			(xy 202.921763 -70.56494) (xy 202.966666 -70.592647) (xy 203.007322 -70.626277) (xy 203.042956 -70.665189)
			(xy 203.058268 -70.686676) (xy 203.06538 -70.69709) (xy 203.087478 -70.708774) (xy 203.196698 -70.70852)
			(xy 203.218542 -70.696836) (xy 203.225654 -70.686422) (xy 203.240982 -70.664834) (xy 203.27664 -70.625698)
			(xy 203.317362 -70.591863) (xy 203.362366 -70.563976) (xy 203.410792 -70.542573) (xy 203.461709 -70.528063)
			(xy 203.514142 -70.520725) (xy 203.540614 -70.520306) (xy 203.56939 -70.52083) (xy 203.626289 -70.529473)
			(xy 203.681246 -70.54656) (xy 203.733015 -70.571704) (xy 203.780423 -70.604335) (xy 203.822393 -70.643714)
			(xy 203.857977 -70.688947) (xy 203.886365 -70.73901) (xy 203.906916 -70.792768) (xy 203.913486 -70.820788)
			(xy 203.91501 -70.828154) (xy 203.91627 -70.83044) (xy 206.0862 -70.83044) (xy 206.090271 -70.774818)
			(xy 206.102397 -70.720381) (xy 206.12232 -70.66829) (xy 206.149616 -70.619655) (xy 206.183702 -70.575512)
			(xy 206.223851 -70.536803) (xy 206.269209 -70.504352) (xy 206.318809 -70.478851) (xy 206.371593 -70.460844)
			(xy 206.426436 -70.450714) (xy 206.48217 -70.448677) (xy 206.537607 -70.454777) (xy 206.591564 -70.468883)
			(xy 206.642893 -70.490695) (xy 206.690499 -70.519749) (xy 206.733367 -70.555424) (xy 206.770584 -70.596961)
			(xy 206.801357 -70.643474) (xy 206.825029 -70.693971) (xy 206.841097 -70.747378) (xy 206.849217 -70.802554)
			(xy 206.849726 -70.83044) (xy 206.849217 -70.858326) (xy 206.841097 -70.913502) (xy 206.825029 -70.966909)
			(xy 206.801357 -71.017406) (xy 206.770584 -71.063919) (xy 206.733367 -71.105456) (xy 206.690499 -71.141131)
			(xy 206.642893 -71.170185) (xy 206.591564 -71.191997) (xy 206.537607 -71.206103) (xy 206.48217 -71.212203)
			(xy 206.426436 -71.210166) (xy 206.371593 -71.200036) (xy 206.318809 -71.182029) (xy 206.269209 -71.156528)
			(xy 206.223851 -71.124077) (xy 206.183702 -71.085368) (xy 206.149616 -71.041225) (xy 206.12232 -70.99259)
			(xy 206.102397 -70.940499) (xy 206.090271 -70.886062) (xy 206.0862 -70.83044) (xy 203.91627 -70.83044)
			(xy 203.921868 -70.8406) (xy 204.047598 -70.96633) (xy 204.067416 -70.987143) (xy 204.099875 -71.034561)
			(xy 204.112114 -71.060564) (xy 204.11607 -71.068623) (xy 204.128572 -71.081491) (xy 204.136498 -71.08571)
			(xy 204.164438 -71.099172) (xy 204.172862 -71.102757) (xy 204.191088 -71.104323) (xy 204.199998 -71.10222)
			(xy 204.224486 -71.096024) (xy 204.274563 -71.089401) (xy 204.29982 -71.089012) (xy 204.327069 -71.0895)
			(xy 204.381012 -71.097258) (xy 204.433301 -71.112614) (xy 204.482873 -71.135255) (xy 204.528719 -71.16472)
			(xy 204.569904 -71.20041) (xy 204.605592 -71.241597) (xy 204.635054 -71.287444) (xy 204.657693 -71.337018)
			(xy 204.673046 -71.389308) (xy 204.680802 -71.443251) (xy 204.680802 -71.480426) (xy 214.549988 -71.480426)
			(xy 214.554059 -71.424804) (xy 214.566185 -71.370367) (xy 214.586108 -71.318276) (xy 214.613404 -71.269641)
			(xy 214.64749 -71.225498) (xy 214.687639 -71.186789) (xy 214.732997 -71.154338) (xy 214.782597 -71.128837)
			(xy 214.835381 -71.11083) (xy 214.890224 -71.1007) (xy 214.945958 -71.098663) (xy 215.001395 -71.104763)
			(xy 215.055352 -71.118869) (xy 215.058611 -71.120254) (xy 218.878402 -71.120254) (xy 218.882473 -71.064632)
			(xy 218.894599 -71.010195) (xy 218.914522 -70.958104) (xy 218.941818 -70.909469) (xy 218.975904 -70.865326)
			(xy 219.016053 -70.826617) (xy 219.061411 -70.794166) (xy 219.111011 -70.768665) (xy 219.163795 -70.750658)
			(xy 219.218638 -70.740528) (xy 219.274372 -70.738491) (xy 219.329809 -70.744591) (xy 219.383766 -70.758697)
			(xy 219.435095 -70.780509) (xy 219.455313 -70.792848) (xy 224.154998 -70.792848) (xy 224.159069 -70.737226)
			(xy 224.171195 -70.682789) (xy 224.191118 -70.630698) (xy 224.218414 -70.582063) (xy 224.2525 -70.53792)
			(xy 224.292649 -70.499211) (xy 224.338007 -70.46676) (xy 224.387607 -70.441259) (xy 224.440391 -70.423252)
			(xy 224.495234 -70.413122) (xy 224.550968 -70.411085) (xy 224.606405 -70.417185) (xy 224.660362 -70.431291)
			(xy 224.711691 -70.453103) (xy 224.759297 -70.482157) (xy 224.802165 -70.517832) (xy 224.839382 -70.559369)
			(xy 224.870155 -70.605882) (xy 224.893827 -70.656379) (xy 224.909895 -70.709786) (xy 224.918015 -70.764962)
			(xy 224.918524 -70.792848) (xy 224.918015 -70.820734) (xy 224.909895 -70.87591) (xy 224.893827 -70.929317)
			(xy 224.870155 -70.979814) (xy 224.839382 -71.026327) (xy 224.802165 -71.067864) (xy 224.759297 -71.103539)
			(xy 224.711691 -71.132593) (xy 224.660362 -71.154405) (xy 224.606405 -71.168511) (xy 224.550968 -71.174611)
			(xy 224.495234 -71.172574) (xy 224.440391 -71.162444) (xy 224.387607 -71.144437) (xy 224.338007 -71.118936)
			(xy 224.292649 -71.086485) (xy 224.2525 -71.047776) (xy 224.218414 -71.003633) (xy 224.191118 -70.954998)
			(xy 224.171195 -70.902907) (xy 224.159069 -70.84847) (xy 224.154998 -70.792848) (xy 219.455313 -70.792848)
			(xy 219.482701 -70.809563) (xy 219.525569 -70.845238) (xy 219.562786 -70.886775) (xy 219.593559 -70.933288)
			(xy 219.617231 -70.983785) (xy 219.633299 -71.037192) (xy 219.641419 -71.092368) (xy 219.641928 -71.120254)
			(xy 219.641419 -71.14814) (xy 219.633299 -71.203316) (xy 219.617231 -71.256723) (xy 219.593559 -71.30722)
			(xy 219.562786 -71.353733) (xy 219.525569 -71.39527) (xy 219.482701 -71.430945) (xy 219.435095 -71.459999)
			(xy 219.383766 -71.481811) (xy 219.329809 -71.495917) (xy 219.274372 -71.502017) (xy 219.218638 -71.49998)
			(xy 219.163795 -71.48985) (xy 219.111011 -71.471843) (xy 219.061411 -71.446342) (xy 219.016053 -71.413891)
			(xy 218.975904 -71.375182) (xy 218.941818 -71.331039) (xy 218.914522 -71.282404) (xy 218.894599 -71.230313)
			(xy 218.882473 -71.175876) (xy 218.878402 -71.120254) (xy 215.058611 -71.120254) (xy 215.106681 -71.140681)
			(xy 215.154287 -71.169735) (xy 215.197155 -71.20541) (xy 215.234372 -71.246947) (xy 215.265145 -71.29346)
			(xy 215.288817 -71.343957) (xy 215.304885 -71.397364) (xy 215.313005 -71.45254) (xy 215.313514 -71.480426)
			(xy 215.313005 -71.508312) (xy 215.304885 -71.563488) (xy 215.288817 -71.616895) (xy 215.265145 -71.667392)
			(xy 215.234372 -71.713905) (xy 215.197155 -71.755442) (xy 215.154287 -71.791117) (xy 215.106681 -71.820171)
			(xy 215.055352 -71.841983) (xy 215.001395 -71.856089) (xy 214.945958 -71.862189) (xy 214.890224 -71.860152)
			(xy 214.835381 -71.850022) (xy 214.782597 -71.832015) (xy 214.732997 -71.806514) (xy 214.687639 -71.774063)
			(xy 214.64749 -71.735354) (xy 214.613404 -71.691211) (xy 214.586108 -71.642576) (xy 214.566185 -71.590485)
			(xy 214.554059 -71.536048) (xy 214.549988 -71.480426) (xy 204.680802 -71.480426) (xy 204.680802 -71.497749)
			(xy 204.673046 -71.551692) (xy 204.657693 -71.603982) (xy 204.635054 -71.653556) (xy 204.605592 -71.699403)
			(xy 204.569904 -71.74059) (xy 204.528719 -71.77628) (xy 204.482873 -71.805745) (xy 204.433301 -71.828386)
			(xy 204.381012 -71.843742) (xy 204.327069 -71.8515) (xy 204.29982 -71.852028) (xy 204.288106 -71.851966)
			(xy 204.264721 -71.850571) (xy 204.253084 -71.849234) (xy 204.242416 -71.84771) (xy 204.221588 -71.854314)
			(xy 204.15631 -71.911972) (xy 204.148575 -71.919535) (xy 204.139743 -71.939264) (xy 204.139292 -71.950072)
			(xy 204.139292 -72.34555) (xy 222.489774 -72.34555) (xy 222.493845 -72.289928) (xy 222.505971 -72.235491)
			(xy 222.525894 -72.1834) (xy 222.55319 -72.134765) (xy 222.587276 -72.090622) (xy 222.627425 -72.051913)
			(xy 222.672783 -72.019462) (xy 222.722383 -71.993961) (xy 222.775167 -71.975954) (xy 222.83001 -71.965824)
			(xy 222.885744 -71.963787) (xy 222.941181 -71.969887) (xy 222.995138 -71.983993) (xy 223.046467 -72.005805)
			(xy 223.094073 -72.034859) (xy 223.136941 -72.070534) (xy 223.174158 -72.112071) (xy 223.204931 -72.158584)
			(xy 223.228603 -72.209081) (xy 223.234203 -72.227694) (xy 224.602038 -72.227694) (xy 224.606109 -72.172072)
			(xy 224.618235 -72.117635) (xy 224.638158 -72.065544) (xy 224.665454 -72.016909) (xy 224.69954 -71.972766)
			(xy 224.739689 -71.934057) (xy 224.785047 -71.901606) (xy 224.834647 -71.876105) (xy 224.887431 -71.858098)
			(xy 224.942274 -71.847968) (xy 224.998008 -71.845931) (xy 225.053445 -71.852031) (xy 225.107402 -71.866137)
			(xy 225.158731 -71.887949) (xy 225.206337 -71.917003) (xy 225.249205 -71.952678) (xy 225.286422 -71.994215)
			(xy 225.317195 -72.040728) (xy 225.340867 -72.091225) (xy 225.356935 -72.144632) (xy 225.365055 -72.199808)
			(xy 225.365564 -72.227694) (xy 225.365055 -72.25558) (xy 225.356935 -72.310756) (xy 225.340867 -72.364163)
			(xy 225.317195 -72.41466) (xy 225.286422 -72.461173) (xy 225.249205 -72.50271) (xy 225.206337 -72.538385)
			(xy 225.158731 -72.567439) (xy 225.107402 -72.589251) (xy 225.053445 -72.603357) (xy 224.998008 -72.609457)
			(xy 224.942274 -72.60742) (xy 224.887431 -72.59729) (xy 224.834647 -72.579283) (xy 224.785047 -72.553782)
			(xy 224.739689 -72.521331) (xy 224.69954 -72.482622) (xy 224.665454 -72.438479) (xy 224.638158 -72.389844)
			(xy 224.618235 -72.337753) (xy 224.606109 -72.283316) (xy 224.602038 -72.227694) (xy 223.234203 -72.227694)
			(xy 223.244671 -72.262488) (xy 223.252791 -72.317664) (xy 223.2533 -72.34555) (xy 223.252791 -72.373436)
			(xy 223.244671 -72.428612) (xy 223.228603 -72.482019) (xy 223.204931 -72.532516) (xy 223.174158 -72.579029)
			(xy 223.136941 -72.620566) (xy 223.094073 -72.656241) (xy 223.046467 -72.685295) (xy 222.995138 -72.707107)
			(xy 222.941181 -72.721213) (xy 222.885744 -72.727313) (xy 222.83001 -72.725276) (xy 222.775167 -72.715146)
			(xy 222.722383 -72.697139) (xy 222.672783 -72.671638) (xy 222.627425 -72.639187) (xy 222.587276 -72.600478)
			(xy 222.55319 -72.556335) (xy 222.525894 -72.5077) (xy 222.505971 -72.455609) (xy 222.493845 -72.401172)
			(xy 222.489774 -72.34555) (xy 204.139292 -72.34555) (xy 204.139292 -73.168002) (xy 207.854294 -73.168002)
			(xy 207.858365 -73.11238) (xy 207.870491 -73.057943) (xy 207.890414 -73.005852) (xy 207.91771 -72.957217)
			(xy 207.951796 -72.913074) (xy 207.991945 -72.874365) (xy 208.037303 -72.841914) (xy 208.086903 -72.816413)
			(xy 208.139687 -72.798406) (xy 208.19453 -72.788276) (xy 208.250264 -72.786239) (xy 208.305701 -72.792339)
			(xy 208.359658 -72.806445) (xy 208.410987 -72.828257) (xy 208.458593 -72.857311) (xy 208.501461 -72.892986)
			(xy 208.538678 -72.934523) (xy 208.569451 -72.981036) (xy 208.593123 -73.031533) (xy 208.598952 -73.050908)
			(xy 213.867998 -73.050908) (xy 213.872069 -72.995286) (xy 213.884195 -72.940849) (xy 213.904118 -72.888758)
			(xy 213.931414 -72.840123) (xy 213.9655 -72.79598) (xy 214.005649 -72.757271) (xy 214.051007 -72.72482)
			(xy 214.100607 -72.699319) (xy 214.153391 -72.681312) (xy 214.208234 -72.671182) (xy 214.263968 -72.669145)
			(xy 214.319405 -72.675245) (xy 214.373362 -72.689351) (xy 214.424691 -72.711163) (xy 214.472297 -72.740217)
			(xy 214.49311 -72.757538) (xy 217.103958 -72.757538) (xy 217.108029 -72.701916) (xy 217.120155 -72.647479)
			(xy 217.140078 -72.595388) (xy 217.167374 -72.546753) (xy 217.20146 -72.50261) (xy 217.241609 -72.463901)
			(xy 217.286967 -72.43145) (xy 217.336567 -72.405949) (xy 217.389351 -72.387942) (xy 217.444194 -72.377812)
			(xy 217.499928 -72.375775) (xy 217.555365 -72.381875) (xy 217.609322 -72.395981) (xy 217.660651 -72.417793)
			(xy 217.708257 -72.446847) (xy 217.751125 -72.482522) (xy 217.788342 -72.524059) (xy 217.819115 -72.570572)
			(xy 217.842787 -72.621069) (xy 217.858855 -72.674476) (xy 217.866975 -72.729652) (xy 217.867484 -72.757538)
			(xy 217.866975 -72.785424) (xy 217.858855 -72.8406) (xy 217.856793 -72.847454) (xy 219.739208 -72.847454)
			(xy 219.743279 -72.791832) (xy 219.755405 -72.737395) (xy 219.775328 -72.685304) (xy 219.802624 -72.636669)
			(xy 219.83671 -72.592526) (xy 219.876859 -72.553817) (xy 219.922217 -72.521366) (xy 219.971817 -72.495865)
			(xy 220.024601 -72.477858) (xy 220.079444 -72.467728) (xy 220.135178 -72.465691) (xy 220.190615 -72.471791)
			(xy 220.244572 -72.485897) (xy 220.295901 -72.507709) (xy 220.343507 -72.536763) (xy 220.386375 -72.572438)
			(xy 220.423592 -72.613975) (xy 220.454365 -72.660488) (xy 220.478037 -72.710985) (xy 220.494105 -72.764392)
			(xy 220.502225 -72.819568) (xy 220.502734 -72.847454) (xy 220.502225 -72.87534) (xy 220.497133 -72.909938)
			(xy 221.675958 -72.909938) (xy 221.680029 -72.854316) (xy 221.692155 -72.799879) (xy 221.712078 -72.747788)
			(xy 221.739374 -72.699153) (xy 221.77346 -72.65501) (xy 221.813609 -72.616301) (xy 221.858967 -72.58385)
			(xy 221.908567 -72.558349) (xy 221.961351 -72.540342) (xy 222.016194 -72.530212) (xy 222.071928 -72.528175)
			(xy 222.127365 -72.534275) (xy 222.181322 -72.548381) (xy 222.232651 -72.570193) (xy 222.280257 -72.599247)
			(xy 222.323125 -72.634922) (xy 222.360342 -72.676459) (xy 222.391115 -72.722972) (xy 222.414787 -72.773469)
			(xy 222.430855 -72.826876) (xy 222.438975 -72.882052) (xy 222.439484 -72.909938) (xy 222.438975 -72.937824)
			(xy 222.430855 -72.993) (xy 222.414787 -73.046407) (xy 222.391115 -73.096904) (xy 222.360342 -73.143417)
			(xy 222.323125 -73.184954) (xy 222.280257 -73.220629) (xy 222.232651 -73.249683) (xy 222.181322 -73.271495)
			(xy 222.127365 -73.285601) (xy 222.071928 -73.291701) (xy 222.016194 -73.289664) (xy 221.961351 -73.279534)
			(xy 221.908567 -73.261527) (xy 221.858967 -73.236026) (xy 221.813609 -73.203575) (xy 221.77346 -73.164866)
			(xy 221.739374 -73.120723) (xy 221.712078 -73.072088) (xy 221.692155 -73.019997) (xy 221.680029 -72.96556)
			(xy 221.675958 -72.909938) (xy 220.497133 -72.909938) (xy 220.494105 -72.930516) (xy 220.478037 -72.983923)
			(xy 220.454365 -73.03442) (xy 220.423592 -73.080933) (xy 220.386375 -73.12247) (xy 220.343507 -73.158145)
			(xy 220.295901 -73.187199) (xy 220.244572 -73.209011) (xy 220.190615 -73.223117) (xy 220.135178 -73.229217)
			(xy 220.079444 -73.22718) (xy 220.024601 -73.21705) (xy 219.971817 -73.199043) (xy 219.922217 -73.173542)
			(xy 219.876859 -73.141091) (xy 219.83671 -73.102382) (xy 219.802624 -73.058239) (xy 219.775328 -73.009604)
			(xy 219.755405 -72.957513) (xy 219.743279 -72.903076) (xy 219.739208 -72.847454) (xy 217.856793 -72.847454)
			(xy 217.842787 -72.894007) (xy 217.819115 -72.944504) (xy 217.788342 -72.991017) (xy 217.751125 -73.032554)
			(xy 217.708257 -73.068229) (xy 217.660651 -73.097283) (xy 217.609322 -73.119095) (xy 217.555365 -73.133201)
			(xy 217.499928 -73.139301) (xy 217.444194 -73.137264) (xy 217.389351 -73.127134) (xy 217.336567 -73.109127)
			(xy 217.286967 -73.083626) (xy 217.241609 -73.051175) (xy 217.20146 -73.012466) (xy 217.167374 -72.968323)
			(xy 217.140078 -72.919688) (xy 217.120155 -72.867597) (xy 217.108029 -72.81316) (xy 217.103958 -72.757538)
			(xy 214.49311 -72.757538) (xy 214.515165 -72.775892) (xy 214.552382 -72.817429) (xy 214.583155 -72.863942)
			(xy 214.606827 -72.914439) (xy 214.622895 -72.967846) (xy 214.631015 -73.023022) (xy 214.631524 -73.050908)
			(xy 214.631015 -73.078794) (xy 214.622895 -73.13397) (xy 214.606827 -73.187377) (xy 214.583155 -73.237874)
			(xy 214.552382 -73.284387) (xy 214.515165 -73.325924) (xy 214.472297 -73.361599) (xy 214.424691 -73.390653)
			(xy 214.373362 -73.412465) (xy 214.319405 -73.426571) (xy 214.263968 -73.432671) (xy 214.208234 -73.430634)
			(xy 214.153391 -73.420504) (xy 214.100607 -73.402497) (xy 214.051007 -73.376996) (xy 214.005649 -73.344545)
			(xy 213.9655 -73.305836) (xy 213.931414 -73.261693) (xy 213.904118 -73.213058) (xy 213.884195 -73.160967)
			(xy 213.872069 -73.10653) (xy 213.867998 -73.050908) (xy 208.598952 -73.050908) (xy 208.609191 -73.08494)
			(xy 208.617311 -73.140116) (xy 208.61782 -73.168002) (xy 208.617311 -73.195888) (xy 208.609191 -73.251064)
			(xy 208.593123 -73.304471) (xy 208.569451 -73.354968) (xy 208.538678 -73.401481) (xy 208.501461 -73.443018)
			(xy 208.458593 -73.478693) (xy 208.410987 -73.507747) (xy 208.359658 -73.529559) (xy 208.305701 -73.543665)
			(xy 208.250264 -73.549765) (xy 208.19453 -73.547728) (xy 208.139687 -73.537598) (xy 208.086903 -73.519591)
			(xy 208.037303 -73.49409) (xy 207.991945 -73.461639) (xy 207.951796 -73.42293) (xy 207.91771 -73.378787)
			(xy 207.890414 -73.330152) (xy 207.870491 -73.278061) (xy 207.858365 -73.223624) (xy 207.854294 -73.168002)
			(xy 204.139292 -73.168002) (xy 204.139292 -74.088752) (xy 204.139776 -74.098715) (xy 204.147359 -74.117144)
			(xy 204.154024 -74.124566) (xy 204.451458 -74.422) (xy 225.169982 -74.422) (xy 225.174053 -74.366378)
			(xy 225.186179 -74.311941) (xy 225.206102 -74.25985) (xy 225.233398 -74.211215) (xy 225.267484 -74.167072)
			(xy 225.307633 -74.128363) (xy 225.352991 -74.095912) (xy 225.402591 -74.070411) (xy 225.455375 -74.052404)
			(xy 225.510218 -74.042274) (xy 225.565952 -74.040237) (xy 225.621389 -74.046337) (xy 225.675346 -74.060443)
			(xy 225.726675 -74.082255) (xy 225.774281 -74.111309) (xy 225.817149 -74.146984) (xy 225.854366 -74.188521)
			(xy 225.885139 -74.235034) (xy 225.908811 -74.285531) (xy 225.924879 -74.338938) (xy 225.932999 -74.394114)
			(xy 225.933508 -74.422) (xy 225.932999 -74.449886) (xy 225.924879 -74.505062) (xy 225.908811 -74.558469)
			(xy 225.885139 -74.608966) (xy 225.854366 -74.655479) (xy 225.817149 -74.697016) (xy 225.774281 -74.732691)
			(xy 225.726675 -74.761745) (xy 225.675346 -74.783557) (xy 225.621389 -74.797663) (xy 225.565952 -74.803763)
			(xy 225.510218 -74.801726) (xy 225.455375 -74.791596) (xy 225.402591 -74.773589) (xy 225.352991 -74.748088)
			(xy 225.307633 -74.715637) (xy 225.267484 -74.676928) (xy 225.233398 -74.632785) (xy 225.206102 -74.58415)
			(xy 225.186179 -74.532059) (xy 225.174053 -74.477622) (xy 225.169982 -74.422) (xy 204.451458 -74.422)
			(xy 205.109909 -75.080451) (xy 220.769668 -75.080451) (xy 220.769668 -75.025949) (xy 220.777424 -74.972)
			(xy 220.792779 -74.919705) (xy 220.81542 -74.870128) (xy 220.844886 -74.824277) (xy 220.880577 -74.783086)
			(xy 220.921767 -74.747393) (xy 220.967617 -74.717926) (xy 221.017194 -74.695283) (xy 221.069489 -74.679927)
			(xy 221.123437 -74.672169) (xy 221.150688 -74.671682) (xy 221.178059 -74.672135) (xy 221.232239 -74.679953)
			(xy 221.284743 -74.695444) (xy 221.33449 -74.718289) (xy 221.380456 -74.748018) (xy 221.401386 -74.765662)
			(xy 221.408498 -74.771758) (xy 221.425516 -74.778108) (xy 221.51086 -74.778108) (xy 221.527878 -74.771758)
			(xy 221.53499 -74.765662) (xy 221.55591 -74.748008) (xy 221.601887 -74.718299) (xy 221.651637 -74.695467)
			(xy 221.70414 -74.679979) (xy 221.758318 -74.672154) (xy 221.785688 -74.671682) (xy 221.812941 -74.672164)
			(xy 221.866892 -74.67992) (xy 221.919189 -74.695274) (xy 221.96877 -74.717916) (xy 222.014623 -74.747383)
			(xy 222.055816 -74.783075) (xy 222.09151 -74.824267) (xy 222.120979 -74.87012) (xy 222.143621 -74.919699)
			(xy 222.158978 -74.971997) (xy 222.166735 -75.025947) (xy 222.166735 -75.080453) (xy 222.158978 -75.134403)
			(xy 222.143621 -75.186701) (xy 222.120979 -75.23628) (xy 222.09151 -75.282133) (xy 222.055816 -75.323325)
			(xy 222.014623 -75.359017) (xy 221.96877 -75.388484) (xy 221.919189 -75.411126) (xy 221.866892 -75.42648)
			(xy 221.812941 -75.434236) (xy 221.785688 -75.434698) (xy 221.758317 -75.434239) (xy 221.704138 -75.42642)
			(xy 221.651635 -75.410929) (xy 221.601888 -75.388086) (xy 221.555922 -75.35836) (xy 221.53499 -75.340718)
			(xy 221.527878 -75.334622) (xy 221.51086 -75.328272) (xy 221.425516 -75.328272) (xy 221.408498 -75.334622)
			(xy 221.401386 -75.340718) (xy 221.380435 -75.358333) (xy 221.334467 -75.388048) (xy 221.284724 -75.410888)
			(xy 221.232228 -75.426385) (xy 221.178056 -75.43422) (xy 221.150688 -75.434698) (xy 221.123437 -75.434231)
			(xy 221.069489 -75.426473) (xy 221.017194 -75.411117) (xy 220.967617 -75.388474) (xy 220.921767 -75.359007)
			(xy 220.880577 -75.323314) (xy 220.844886 -75.282123) (xy 220.81542 -75.236272) (xy 220.792779 -75.186695)
			(xy 220.777424 -75.1344) (xy 220.769668 -75.080451) (xy 205.109909 -75.080451) (xy 205.774798 -75.74534)
			(xy 205.791872 -75.763042) (xy 205.820797 -75.802819) (xy 205.843137 -75.846634) (xy 205.858339 -75.893407)
			(xy 205.866029 -75.941983) (xy 205.866492 -75.966574) (xy 205.866492 -76.121768) (xy 216.910156 -76.121768)
			(xy 216.914227 -76.066146) (xy 216.926353 -76.011709) (xy 216.946276 -75.959618) (xy 216.973572 -75.910983)
			(xy 217.007658 -75.86684) (xy 217.047807 -75.828131) (xy 217.093165 -75.79568) (xy 217.142765 -75.770179)
			(xy 217.195549 -75.752172) (xy 217.250392 -75.742042) (xy 217.306126 -75.740005) (xy 217.361563 -75.746105)
			(xy 217.41552 -75.760211) (xy 217.466849 -75.782023) (xy 217.514455 -75.811077) (xy 217.557323 -75.846752)
			(xy 217.59454 -75.888289) (xy 217.625313 -75.934802) (xy 217.648985 -75.985299) (xy 217.665053 -76.038706)
			(xy 217.673173 -76.093882) (xy 217.673682 -76.121768) (xy 217.673173 -76.149654) (xy 217.665053 -76.20483)
			(xy 217.648985 -76.258237) (xy 217.625313 -76.308734) (xy 217.59454 -76.355247) (xy 217.557323 -76.396784)
			(xy 217.514455 -76.432459) (xy 217.466849 -76.461513) (xy 217.41552 -76.483325) (xy 217.361563 -76.497431)
			(xy 217.306126 -76.503531) (xy 217.250392 -76.501494) (xy 217.195549 -76.491364) (xy 217.142765 -76.473357)
			(xy 217.093165 -76.447856) (xy 217.047807 -76.415405) (xy 217.007658 -76.376696) (xy 216.973572 -76.332553)
			(xy 216.946276 -76.283918) (xy 216.926353 -76.231827) (xy 216.914227 -76.17739) (xy 216.910156 -76.121768)
			(xy 205.866492 -76.121768) (xy 205.866492 -76.793344) (xy 205.866988 -76.803346) (xy 205.874655 -76.821824)
			(xy 205.888806 -76.835965) (xy 205.907289 -76.843619) (xy 205.917292 -76.844144) (xy 209.813652 -76.844144)
			(xy 209.823742 -76.843623) (xy 209.842366 -76.835847) (xy 209.856599 -76.821538) (xy 209.860896 -76.812394)
			(xy 209.860896 -76.811886) (xy 209.871886 -76.785605) (xy 209.90052 -76.736361) (xy 209.936154 -76.69192)
			(xy 209.977997 -76.653268) (xy 210.025119 -76.621263) (xy 210.076474 -76.596615) (xy 210.130922 -76.579873)
			(xy 210.187252 -76.571408) (xy 210.244216 -76.571408) (xy 210.300546 -76.579873) (xy 210.354994 -76.596615)
			(xy 210.406349 -76.621263) (xy 210.453471 -76.653268) (xy 210.495314 -76.69192) (xy 210.530948 -76.736361)
			(xy 210.559582 -76.785605) (xy 210.570572 -76.811886) (xy 210.570572 -76.812394) (xy 210.574751 -76.821625)
			(xy 210.588984 -76.836023) (xy 210.607691 -76.843766) (xy 210.617816 -76.844144) (xy 220.49994 -76.844144)
			(xy 220.509457 -76.843737) (xy 220.527185 -76.836806) (xy 220.534484 -76.830682) (xy 220.59265 -76.776834)
			(xy 220.600778 -76.759816) (xy 220.60154 -76.74991) (xy 220.60411 -76.721418) (xy 220.616704 -76.665615)
			(xy 220.637487 -76.612317) (xy 220.665994 -76.56272) (xy 220.701586 -76.517934) (xy 220.743466 -76.478964)
			(xy 220.790694 -76.446683) (xy 220.842212 -76.421814) (xy 220.896865 -76.404915) (xy 220.953429 -76.396364)
			(xy 220.982032 -76.395834) (xy 221.009401 -76.396308) (xy 221.063577 -76.404137) (xy 221.116077 -76.419628)
			(xy 221.165824 -76.442465) (xy 221.211796 -76.472178) (xy 221.23273 -76.489814) (xy 221.239842 -76.49591)
			(xy 221.256606 -76.50226) (xy 221.342458 -76.50226) (xy 221.359222 -76.49591) (xy 221.366334 -76.489814)
			(xy 221.387266 -76.472173) (xy 221.433233 -76.44245) (xy 221.48298 -76.419611) (xy 221.535483 -76.404125)
			(xy 221.589662 -76.396311) (xy 221.617032 -76.395834) (xy 221.64564 -76.39634) (xy 221.702216 -76.404875)
			(xy 221.756883 -76.421764) (xy 221.808414 -76.446628) (xy 221.855654 -76.478909) (xy 221.897543 -76.517884)
			(xy 221.933141 -76.562677) (xy 221.96165 -76.612285) (xy 221.982431 -76.665594) (xy 221.995017 -76.721408)
			(xy 221.997524 -76.74991) (xy 221.998286 -76.759816) (xy 222.006414 -76.776834) (xy 222.06458 -76.830682)
			(xy 222.071835 -76.836877) (xy 222.089591 -76.843815) (xy 222.099124 -76.844144) (xy 225.711004 -76.844144)
			(xy 225.720883 -76.843688) (xy 225.739189 -76.836253) (xy 225.746564 -76.829666) (xy 225.746818 -76.829412)
			(xy 228.643942 -73.932288) (xy 228.64445 -73.93178) (xy 228.651038 -73.924401) (xy 228.6585 -73.906102)
			(xy 228.658928 -73.89622) (xy 228.658928 -53.45049) (xy 228.658504 -53.44042) (xy 228.65079 -53.421816)
			(xy 228.643942 -53.414422) (xy 228.100382 -52.870862) (xy 228.092948 -52.864146) (xy 228.074448 -52.85651)
			(xy 228.054434 -52.85651) (xy 228.035934 -52.864146) (xy 228.0285 -52.870862) (xy 228.027484 -52.871878)
			(xy 228.026468 -52.872894) (xy 228.0158 -52.884578) (xy 228.015546 -52.884832) (xy 228.015292 -52.885086)
			(xy 228.015038 -52.88534) (xy 228.00995 -52.890942) (xy 228.002989 -52.904373) (xy 228.001322 -52.911756)
			(xy 228.00056 -52.9209) (xy 228.00056 -52.952396) (xy 228.001322 -52.96154) (xy 228.002954 -52.968934)
			(xy 228.009932 -52.982364) (xy 228.015038 -52.987956) (xy 228.035212 -53.009455) (xy 228.069359 -53.057513)
			(xy 228.095706 -53.110252) (xy 228.113625 -53.166417) (xy 228.122688 -53.224671) (xy 228.123242 -53.254148)
			(xy 228.122753 -53.281398) (xy 228.114991 -53.335342) (xy 228.099632 -53.387633) (xy 228.076989 -53.437207)
			(xy 228.047522 -53.483053) (xy 228.011831 -53.524241) (xy 227.970642 -53.55993) (xy 227.924794 -53.589395)
			(xy 227.87522 -53.612037) (xy 227.822929 -53.627394) (xy 227.768984 -53.635154) (xy 227.741734 -53.635656)
			(xy 227.714366 -53.63518) (xy 227.660193 -53.627346) (xy 227.607696 -53.611851) (xy 227.557952 -53.589011)
			(xy 227.511984 -53.559295) (xy 227.491036 -53.541676) (xy 227.483924 -53.53558) (xy 227.46716 -53.52923)
			(xy 227.381308 -53.52923) (xy 227.364544 -53.53558) (xy 227.357432 -53.541676) (xy 227.336499 -53.559317)
			(xy 227.290531 -53.589041) (xy 227.240785 -53.611887) (xy 227.188283 -53.627383) (xy 227.134105 -53.635212)
			(xy 227.079363 -53.635212) (xy 227.025185 -53.627383) (xy 226.972683 -53.611887) (xy 226.922937 -53.589041)
			(xy 226.876969 -53.559317) (xy 226.856036 -53.541676) (xy 226.848924 -53.53558) (xy 226.83216 -53.52923)
			(xy 226.746308 -53.52923) (xy 226.729544 -53.53558) (xy 226.722432 -53.541676) (xy 226.701502 -53.559321)
			(xy 226.655537 -53.589053) (xy 226.60579 -53.611901) (xy 226.553286 -53.627397) (xy 226.499105 -53.635221)
			(xy 226.471734 -53.635656) (xy 226.442502 -53.635099) (xy 226.384721 -53.626181) (xy 226.328979 -53.608548)
			(xy 226.276582 -53.582613) (xy 226.228757 -53.548985) (xy 226.186625 -53.508451) (xy 226.168458 -53.485542)
			(xy 226.162362 -53.477414) (xy 226.153472 -53.472334) (xy 226.149027 -53.469915) (xy 226.139429 -53.466716)
			(xy 226.134422 -53.465984) (xy 226.05238 -53.45557) (xy 226.032822 -53.460904) (xy 226.024694 -53.467508)
			(xy 226.004403 -53.482976) (xy 225.960493 -53.508961) (xy 225.913513 -53.528864) (xy 225.8643 -53.542329)
			(xy 225.813731 -53.549117) (xy 225.78822 -53.54955) (xy 225.760967 -53.549066) (xy 225.707015 -53.541312)
			(xy 225.654715 -53.525959) (xy 225.605133 -53.503319) (xy 225.559277 -53.473854) (xy 225.518081 -53.438163)
			(xy 225.482383 -53.396973) (xy 225.452911 -53.351122) (xy 225.430263 -53.301543) (xy 225.414902 -53.249246)
			(xy 225.407139 -53.195295) (xy 225.406712 -53.168042) (xy 225.407188 -53.140673) (xy 225.415019 -53.086499)
			(xy 225.430513 -53.034001) (xy 225.453351 -52.984256) (xy 225.483064 -52.938285) (xy 225.500692 -52.917344)
			(xy 225.506788 -52.910232) (xy 225.513138 -52.893468) (xy 225.513138 -52.807616) (xy 225.506788 -52.790852)
			(xy 225.500692 -52.78374) (xy 225.483054 -52.762807) (xy 225.453336 -52.716839) (xy 225.430501 -52.667092)
			(xy 225.415019 -52.614589) (xy 225.407209 -52.560411) (xy 225.406712 -52.533042) (xy 225.407172 -52.505788)
			(xy 225.414925 -52.451833) (xy 225.430277 -52.399532) (xy 225.452918 -52.349947) (xy 225.482385 -52.30409)
			(xy 225.518079 -52.262894) (xy 225.559273 -52.227198) (xy 225.605128 -52.197728) (xy 225.654711 -52.175085)
			(xy 225.707012 -52.159729) (xy 225.760966 -52.151974) (xy 225.78822 -52.151534) (xy 225.817454 -52.152087)
			(xy 225.875239 -52.161) (xy 225.930986 -52.178627) (xy 225.983389 -52.204558) (xy 226.03122 -52.238183)
			(xy 226.073358 -52.278715) (xy 226.091496 -52.301648) (xy 226.097592 -52.309776) (xy 226.106482 -52.314856)
			(xy 226.110925 -52.317279) (xy 226.120522 -52.320488) (xy 226.125532 -52.321206) (xy 226.207574 -52.33162)
			(xy 226.227132 -52.326286) (xy 226.23526 -52.319682) (xy 226.255551 -52.304212) (xy 226.299459 -52.278222)
			(xy 226.346439 -52.258314) (xy 226.395653 -52.244843) (xy 226.446222 -52.23805) (xy 226.471734 -52.23764)
			(xy 226.499103 -52.238114) (xy 226.553278 -52.245943) (xy 226.605778 -52.261435) (xy 226.655525 -52.284272)
			(xy 226.701496 -52.313986) (xy 226.722432 -52.33162) (xy 226.729544 -52.337716) (xy 226.746308 -52.344066)
			(xy 226.83216 -52.344066) (xy 226.848924 -52.337716) (xy 226.856036 -52.33162) (xy 226.876968 -52.313979)
			(xy 226.922935 -52.284256) (xy 226.972682 -52.261416) (xy 227.025185 -52.24593) (xy 227.079364 -52.238116)
			(xy 227.106734 -52.23764) (xy 227.13621 -52.238191) (xy 227.194461 -52.247264) (xy 227.250623 -52.265187)
			(xy 227.303359 -52.291536) (xy 227.351416 -52.325682) (xy 227.372926 -52.345844) (xy 227.378527 -52.350935)
			(xy 227.391956 -52.357902) (xy 227.399342 -52.35956) (xy 227.408486 -52.360322) (xy 227.439982 -52.360322)
			(xy 227.449126 -52.35956) (xy 227.45653 -52.357957) (xy 227.469969 -52.350976) (xy 227.475542 -52.345844)
			(xy 227.475796 -52.34559) (xy 227.47605 -52.345336) (xy 227.476304 -52.345082) (xy 227.487988 -52.334414)
			(xy 227.489512 -52.282344) (xy 227.489277 -52.271951) (xy 227.481542 -52.252677) (xy 227.474526 -52.245006)
			(xy 226.86899 -51.63947) (xy 226.861878 -51.632104) (xy 226.843082 -51.624484) (xy 214.857076 -51.624484)
			(xy 214.847133 -51.624946) (xy 214.828735 -51.632493) (xy 214.814599 -51.646478) (xy 214.81034 -51.655472)
			(xy 214.767922 -51.755802) (xy 214.77351 -51.785774) (xy 214.784178 -51.796696) (xy 214.804182 -51.81816)
			(xy 214.838025 -51.866087) (xy 214.864128 -51.918632) (xy 214.881876 -51.974555) (xy 214.890851 -52.032536)
			(xy 214.891366 -52.061872) (xy 214.89088 -52.089123) (xy 214.883124 -52.143071) (xy 214.867769 -52.195366)
			(xy 214.845127 -52.244943) (xy 214.815661 -52.290793) (xy 214.77997 -52.331984) (xy 214.738779 -52.367675)
			(xy 214.692929 -52.397141) (xy 214.643352 -52.419783) (xy 214.591057 -52.435138) (xy 214.537109 -52.442894)
			(xy 214.482607 -52.442894) (xy 214.428659 -52.435138) (xy 214.376364 -52.419783) (xy 214.326787 -52.397141)
			(xy 214.280937 -52.367675) (xy 214.239746 -52.331984) (xy 214.204055 -52.290793) (xy 214.174589 -52.244943)
			(xy 214.151947 -52.195366) (xy 214.136592 -52.143071) (xy 214.128836 -52.089123) (xy 214.12835 -52.061872)
			(xy 214.128889 -52.032538) (xy 214.137872 -51.974563) (xy 214.15562 -51.918644) (xy 214.181717 -51.866101)
			(xy 214.215547 -51.818169) (xy 214.235538 -51.796696) (xy 214.246206 -51.785774) (xy 214.251794 -51.755802)
			(xy 214.209376 -51.655472) (xy 214.205058 -51.646514) (xy 214.190936 -51.63254) (xy 214.172572 -51.624961)
			(xy 214.16264 -51.624484) (xy 212.826092 -51.624484) (xy 212.816022 -51.624908) (xy 212.797418 -51.632623)
			(xy 212.790024 -51.63947) (xy 211.884006 -52.545488) (xy 212.678516 -52.545488) (xy 212.682587 -52.489866)
			(xy 212.694713 -52.435429) (xy 212.714636 -52.383338) (xy 212.741932 -52.334703) (xy 212.776018 -52.29056)
			(xy 212.816167 -52.251851) (xy 212.861525 -52.2194) (xy 212.911125 -52.193899) (xy 212.963909 -52.175892)
			(xy 213.018752 -52.165762) (xy 213.074486 -52.163725) (xy 213.129923 -52.169825) (xy 213.18388 -52.183931)
			(xy 213.235209 -52.205743) (xy 213.282815 -52.234797) (xy 213.325683 -52.270472) (xy 213.3629 -52.312009)
			(xy 213.393673 -52.358522) (xy 213.417345 -52.409019) (xy 213.433413 -52.462426) (xy 213.441533 -52.517602)
			(xy 213.442042 -52.545488) (xy 213.441533 -52.573374) (xy 213.433413 -52.62855) (xy 213.417345 -52.681957)
			(xy 213.393673 -52.732454) (xy 213.3629 -52.778967) (xy 213.325683 -52.820504) (xy 213.282815 -52.856179)
			(xy 213.235209 -52.885233) (xy 213.18388 -52.907045) (xy 213.129923 -52.921151) (xy 213.074486 -52.927251)
			(xy 213.018752 -52.925214) (xy 212.963909 -52.915084) (xy 212.911125 -52.897077) (xy 212.861525 -52.871576)
			(xy 212.816167 -52.839125) (xy 212.776018 -52.800416) (xy 212.741932 -52.756273) (xy 212.714636 -52.707638)
			(xy 212.694713 -52.655547) (xy 212.682587 -52.60111) (xy 212.678516 -52.545488) (xy 211.884006 -52.545488)
			(xy 210.274916 -54.154578) (xy 212.256876 -54.154578) (xy 212.260947 -54.098956) (xy 212.273073 -54.044519)
			(xy 212.292996 -53.992428) (xy 212.320292 -53.943793) (xy 212.354378 -53.89965) (xy 212.394527 -53.860941)
			(xy 212.439885 -53.82849) (xy 212.489485 -53.802989) (xy 212.542269 -53.784982) (xy 212.597112 -53.774852)
			(xy 212.652846 -53.772815) (xy 212.708283 -53.778915) (xy 212.76224 -53.793021) (xy 212.813569 -53.814833)
			(xy 212.861175 -53.843887) (xy 212.904043 -53.879562) (xy 212.94126 -53.921099) (xy 212.964317 -53.95595)
			(xy 217.006678 -53.95595) (xy 217.007164 -53.928699) (xy 217.01492 -53.874751) (xy 217.030275 -53.822456)
			(xy 217.052917 -53.772879) (xy 217.082383 -53.727029) (xy 217.118074 -53.685838) (xy 217.159265 -53.650147)
			(xy 217.205115 -53.620681) (xy 217.254692 -53.598039) (xy 217.306987 -53.582684) (xy 217.360935 -53.574928)
			(xy 217.415437 -53.574928) (xy 217.469385 -53.582684) (xy 217.52168 -53.598039) (xy 217.571257 -53.620681)
			(xy 217.617107 -53.650147) (xy 217.658298 -53.685838) (xy 217.693989 -53.727029) (xy 217.723455 -53.772879)
			(xy 217.746097 -53.822456) (xy 217.761452 -53.874751) (xy 217.769208 -53.928699) (xy 217.769694 -53.95595)
			(xy 217.769188 -53.98339) (xy 217.761342 -54.037707) (xy 217.745792 -54.090337) (xy 217.722858 -54.140196)
			(xy 217.693014 -54.186252) (xy 217.656876 -54.227554) (xy 217.636344 -54.245764) (xy 217.627454 -54.253384)
			(xy 217.61831 -54.273958) (xy 217.62085 -54.376066) (xy 217.63101 -54.396132) (xy 217.640408 -54.403244)
			(xy 217.663052 -54.421452) (xy 217.703119 -54.463528) (xy 217.736346 -54.511191) (xy 217.761964 -54.56334)
			(xy 217.779382 -54.61877) (xy 217.788196 -54.676199) (xy 217.788744 -54.70525) (xy 217.788258 -54.732501)
			(xy 217.780502 -54.786449) (xy 217.765147 -54.838744) (xy 217.742505 -54.888321) (xy 217.713039 -54.934171)
			(xy 217.677348 -54.975362) (xy 217.636157 -55.011053) (xy 217.590307 -55.040519) (xy 217.54073 -55.063161)
			(xy 217.488435 -55.078516) (xy 217.434487 -55.086272) (xy 217.379985 -55.086272) (xy 217.326037 -55.078516)
			(xy 217.273742 -55.063161) (xy 217.224165 -55.040519) (xy 217.178315 -55.011053) (xy 217.137124 -54.975362)
			(xy 217.101433 -54.934171) (xy 217.071967 -54.888321) (xy 217.049325 -54.838744) (xy 217.03397 -54.786449)
			(xy 217.026214 -54.732501) (xy 217.025728 -54.70525) (xy 217.026227 -54.677809) (xy 217.034072 -54.623492)
			(xy 217.049624 -54.570861) (xy 217.072559 -54.521003) (xy 217.102405 -54.474947) (xy 217.138545 -54.433646)
			(xy 217.159078 -54.415436) (xy 217.167968 -54.407816) (xy 217.177112 -54.387242) (xy 217.174572 -54.285134)
			(xy 217.164412 -54.265068) (xy 217.155014 -54.257956) (xy 217.132354 -54.239768) (xy 217.092291 -54.197685)
			(xy 217.059068 -54.150017) (xy 217.033454 -54.097865) (xy 217.016039 -54.042433) (xy 217.007226 -53.985002)
			(xy 217.006678 -53.95595) (xy 212.964317 -53.95595) (xy 212.972033 -53.967612) (xy 212.995705 -54.018109)
			(xy 213.011773 -54.071516) (xy 213.019893 -54.126692) (xy 213.020402 -54.154578) (xy 213.019893 -54.182464)
			(xy 213.011773 -54.23764) (xy 212.995705 -54.291047) (xy 212.972033 -54.341544) (xy 212.94126 -54.388057)
			(xy 212.904043 -54.429594) (xy 212.861175 -54.465269) (xy 212.813569 -54.494323) (xy 212.76224 -54.516135)
			(xy 212.708283 -54.530241) (xy 212.652846 -54.536341) (xy 212.597112 -54.534304) (xy 212.542269 -54.524174)
			(xy 212.489485 -54.506167) (xy 212.439885 -54.480666) (xy 212.394527 -54.448215) (xy 212.354378 -54.409506)
			(xy 212.320292 -54.365363) (xy 212.292996 -54.316728) (xy 212.273073 -54.264637) (xy 212.260947 -54.2102)
			(xy 212.256876 -54.154578) (xy 210.274916 -54.154578) (xy 209.003646 -55.425848) (xy 212.256876 -55.425848)
			(xy 212.260947 -55.370226) (xy 212.273073 -55.315789) (xy 212.292996 -55.263698) (xy 212.320292 -55.215063)
			(xy 212.354378 -55.17092) (xy 212.394527 -55.132211) (xy 212.439885 -55.09976) (xy 212.489485 -55.074259)
			(xy 212.542269 -55.056252) (xy 212.597112 -55.046122) (xy 212.652846 -55.044085) (xy 212.708283 -55.050185)
			(xy 212.76224 -55.064291) (xy 212.813569 -55.086103) (xy 212.861175 -55.115157) (xy 212.904043 -55.150832)
			(xy 212.94126 -55.192369) (xy 212.972033 -55.238882) (xy 212.995705 -55.289379) (xy 213.011773 -55.342786)
			(xy 213.019893 -55.397962) (xy 213.020402 -55.425848) (xy 213.019893 -55.453734) (xy 213.011773 -55.50891)
			(xy 212.995705 -55.562317) (xy 212.972033 -55.612814) (xy 212.94126 -55.659327) (xy 212.904043 -55.700864)
			(xy 212.861175 -55.736539) (xy 212.813569 -55.765593) (xy 212.76224 -55.787405) (xy 212.708283 -55.801511)
			(xy 212.652846 -55.807611) (xy 212.597112 -55.805574) (xy 212.542269 -55.795444) (xy 212.489485 -55.777437)
			(xy 212.439885 -55.751936) (xy 212.394527 -55.719485) (xy 212.354378 -55.680776) (xy 212.320292 -55.636633)
			(xy 212.292996 -55.587998) (xy 212.273073 -55.535907) (xy 212.260947 -55.48147) (xy 212.256876 -55.425848)
			(xy 209.003646 -55.425848) (xy 206.100426 -58.329068) (xy 212.343236 -58.329068) (xy 212.347307 -58.273446)
			(xy 212.359433 -58.219009) (xy 212.379356 -58.166918) (xy 212.406652 -58.118283) (xy 212.440738 -58.07414)
			(xy 212.480887 -58.035431) (xy 212.526245 -58.00298) (xy 212.575845 -57.977479) (xy 212.628629 -57.959472)
			(xy 212.683472 -57.949342) (xy 212.739206 -57.947305) (xy 212.794643 -57.953405) (xy 212.8486 -57.967511)
			(xy 212.899929 -57.989323) (xy 212.947535 -58.018377) (xy 212.990403 -58.054052) (xy 213.02762 -58.095589)
			(xy 213.058393 -58.142102) (xy 213.082065 -58.192599) (xy 213.098133 -58.246006) (xy 213.106253 -58.301182)
			(xy 213.106762 -58.329068) (xy 213.106253 -58.356954) (xy 213.098133 -58.41213) (xy 213.082065 -58.465537)
			(xy 213.058393 -58.516034) (xy 213.02762 -58.562547) (xy 212.990403 -58.604084) (xy 212.947535 -58.639759)
			(xy 212.899929 -58.668813) (xy 212.8486 -58.690625) (xy 212.794643 -58.704731) (xy 212.739206 -58.710831)
			(xy 212.683472 -58.708794) (xy 212.628629 -58.698664) (xy 212.575845 -58.680657) (xy 212.526245 -58.655156)
			(xy 212.480887 -58.622705) (xy 212.440738 -58.583996) (xy 212.406652 -58.539853) (xy 212.379356 -58.491218)
			(xy 212.359433 -58.439127) (xy 212.347307 -58.38469) (xy 212.343236 -58.329068) (xy 206.100426 -58.329068)
			(xy 205.445106 -58.984388) (xy 214.903556 -58.984388) (xy 214.907627 -58.928766) (xy 214.919753 -58.874329)
			(xy 214.939676 -58.822238) (xy 214.966972 -58.773603) (xy 215.001058 -58.72946) (xy 215.041207 -58.690751)
			(xy 215.086565 -58.6583) (xy 215.136165 -58.632799) (xy 215.188949 -58.614792) (xy 215.243792 -58.604662)
			(xy 215.299526 -58.602625) (xy 215.354963 -58.608725) (xy 215.40892 -58.622831) (xy 215.460249 -58.644643)
			(xy 215.507855 -58.673697) (xy 215.550723 -58.709372) (xy 215.58794 -58.750909) (xy 215.618713 -58.797422)
			(xy 215.642385 -58.847919) (xy 215.650277 -58.874152) (xy 219.970348 -58.874152) (xy 219.974419 -58.81853)
			(xy 219.986545 -58.764093) (xy 220.006468 -58.712002) (xy 220.033764 -58.663367) (xy 220.06785 -58.619224)
			(xy 220.107999 -58.580515) (xy 220.153357 -58.548064) (xy 220.202957 -58.522563) (xy 220.255741 -58.504556)
			(xy 220.310584 -58.494426) (xy 220.366318 -58.492389) (xy 220.421755 -58.498489) (xy 220.475712 -58.512595)
			(xy 220.527041 -58.534407) (xy 220.574647 -58.563461) (xy 220.617515 -58.599136) (xy 220.654732 -58.640673)
			(xy 220.685505 -58.687186) (xy 220.709177 -58.737683) (xy 220.725245 -58.79109) (xy 220.733365 -58.846266)
			(xy 220.733874 -58.874152) (xy 220.733365 -58.902038) (xy 220.725245 -58.957214) (xy 220.709177 -59.010621)
			(xy 220.685505 -59.061118) (xy 220.654732 -59.107631) (xy 220.617515 -59.149168) (xy 220.574647 -59.184843)
			(xy 220.527041 -59.213897) (xy 220.475712 -59.235709) (xy 220.421755 -59.249815) (xy 220.366318 -59.255915)
			(xy 220.310584 -59.253878) (xy 220.255741 -59.243748) (xy 220.202957 -59.225741) (xy 220.153357 -59.20024)
			(xy 220.107999 -59.167789) (xy 220.06785 -59.12908) (xy 220.033764 -59.084937) (xy 220.006468 -59.036302)
			(xy 219.986545 -58.984211) (xy 219.974419 -58.929774) (xy 219.970348 -58.874152) (xy 215.650277 -58.874152)
			(xy 215.658453 -58.901326) (xy 215.666573 -58.956502) (xy 215.667082 -58.984388) (xy 215.666573 -59.012274)
			(xy 215.658453 -59.06745) (xy 215.642385 -59.120857) (xy 215.618713 -59.171354) (xy 215.58794 -59.217867)
			(xy 215.550723 -59.259404) (xy 215.507855 -59.295079) (xy 215.460249 -59.324133) (xy 215.40892 -59.345945)
			(xy 215.354963 -59.360051) (xy 215.299526 -59.366151) (xy 215.243792 -59.364114) (xy 215.188949 -59.353984)
			(xy 215.136165 -59.335977) (xy 215.086565 -59.310476) (xy 215.041207 -59.278025) (xy 215.001058 -59.239316)
			(xy 214.966972 -59.195173) (xy 214.939676 -59.146538) (xy 214.919753 -59.094447) (xy 214.907627 -59.04001)
			(xy 214.903556 -58.984388) (xy 205.445106 -58.984388) (xy 202.96632 -61.463174) (xy 202.958918 -61.470011)
			(xy 202.94032 -61.47772) (xy 202.930252 -61.47816) (xy 191.757554 -61.47816) (xy 191.747489 -61.478593)
			(xy 191.728902 -61.486326) (xy 191.721486 -61.493146) (xy 191.298068 -61.916564) (xy 191.291224 -61.923963)
			(xy 191.283502 -61.942562) (xy 191.283082 -61.952632) (xy 191.283082 -65.188592) (xy 197.079614 -65.188592)
			(xy 197.083685 -65.13297) (xy 197.095811 -65.078533) (xy 197.115734 -65.026442) (xy 197.14303 -64.977807)
			(xy 197.177116 -64.933664) (xy 197.217265 -64.894955) (xy 197.262623 -64.862504) (xy 197.312223 -64.837003)
			(xy 197.365007 -64.818996) (xy 197.41985 -64.808866) (xy 197.475584 -64.806829) (xy 197.531021 -64.812929)
			(xy 197.584978 -64.827035) (xy 197.636307 -64.848847) (xy 197.683913 -64.877901) (xy 197.726781 -64.913576)
			(xy 197.763998 -64.955113) (xy 197.794771 -65.001626) (xy 197.818443 -65.052123) (xy 197.834511 -65.10553)
			(xy 197.842631 -65.160706) (xy 197.84314 -65.188592) (xy 197.842631 -65.216478) (xy 197.834511 -65.271654)
			(xy 197.818443 -65.325061) (xy 197.794771 -65.375558) (xy 197.763998 -65.422071) (xy 197.726781 -65.463608)
			(xy 197.683913 -65.499283) (xy 197.636307 -65.528337) (xy 197.584978 -65.550149) (xy 197.531021 -65.564255)
			(xy 197.475584 -65.570355) (xy 197.41985 -65.568318) (xy 197.365007 -65.558188) (xy 197.312223 -65.540181)
			(xy 197.262623 -65.51468) (xy 197.217265 -65.482229) (xy 197.177116 -65.44352) (xy 197.14303 -65.399377)
			(xy 197.115734 -65.350742) (xy 197.095811 -65.298651) (xy 197.083685 -65.244214) (xy 197.079614 -65.188592)
			(xy 191.283082 -65.188592) (xy 191.283082 -66.158364) (xy 198.42683 -66.158364) (xy 198.430901 -66.102742)
			(xy 198.443027 -66.048305) (xy 198.46295 -65.996214) (xy 198.490246 -65.947579) (xy 198.524332 -65.903436)
			(xy 198.564481 -65.864727) (xy 198.609839 -65.832276) (xy 198.659439 -65.806775) (xy 198.712223 -65.788768)
			(xy 198.767066 -65.778638) (xy 198.8228 -65.776601) (xy 198.878237 -65.782701) (xy 198.932194 -65.796807)
			(xy 198.983523 -65.818619) (xy 199.031129 -65.847673) (xy 199.073997 -65.883348) (xy 199.111214 -65.924885)
			(xy 199.141987 -65.971398) (xy 199.165659 -66.021895) (xy 199.181727 -66.075302) (xy 199.189847 -66.130478)
			(xy 199.190356 -66.158364) (xy 199.189847 -66.18625) (xy 199.181727 -66.241426) (xy 199.165659 -66.294833)
			(xy 199.141987 -66.34533) (xy 199.111214 -66.391843) (xy 199.073997 -66.43338) (xy 199.031129 -66.469055)
			(xy 198.983523 -66.498109) (xy 198.932194 -66.519921) (xy 198.878237 -66.534027) (xy 198.8228 -66.540127)
			(xy 198.767066 -66.53809) (xy 198.712223 -66.52796) (xy 198.659439 -66.509953) (xy 198.609839 -66.484452)
			(xy 198.564481 -66.452001) (xy 198.524332 -66.413292) (xy 198.490246 -66.369149) (xy 198.46295 -66.320514)
			(xy 198.443027 -66.268423) (xy 198.430901 -66.213986) (xy 198.42683 -66.158364) (xy 191.283082 -66.158364)
			(xy 191.283082 -66.562478) (xy 216.490548 -66.562478) (xy 216.494619 -66.506856) (xy 216.506745 -66.452419)
			(xy 216.526668 -66.400328) (xy 216.553964 -66.351693) (xy 216.58805 -66.30755) (xy 216.628199 -66.268841)
			(xy 216.673557 -66.23639) (xy 216.723157 -66.210889) (xy 216.775941 -66.192882) (xy 216.830784 -66.182752)
			(xy 216.886518 -66.180715) (xy 216.941955 -66.186815) (xy 216.995912 -66.200921) (xy 217.047241 -66.222733)
			(xy 217.094847 -66.251787) (xy 217.137715 -66.287462) (xy 217.174932 -66.328999) (xy 217.205705 -66.375512)
			(xy 217.229377 -66.426009) (xy 217.245445 -66.479416) (xy 217.253565 -66.534592) (xy 217.254074 -66.562478)
			(xy 217.253565 -66.590364) (xy 217.245445 -66.64554) (xy 217.229377 -66.698947) (xy 217.205705 -66.749444)
			(xy 217.174932 -66.795957) (xy 217.137715 -66.837494) (xy 217.094847 -66.873169) (xy 217.047241 -66.902223)
			(xy 216.995912 -66.924035) (xy 216.941955 -66.938141) (xy 216.886518 -66.944241) (xy 216.830784 -66.942204)
			(xy 216.775941 -66.932074) (xy 216.723157 -66.914067) (xy 216.673557 -66.888566) (xy 216.628199 -66.856115)
			(xy 216.58805 -66.817406) (xy 216.553964 -66.773263) (xy 216.526668 -66.724628) (xy 216.506745 -66.672537)
			(xy 216.494619 -66.6181) (xy 216.490548 -66.562478) (xy 191.283082 -66.562478) (xy 191.283082 -67.525392)
			(xy 203.65669 -67.525392) (xy 203.660761 -67.46977) (xy 203.672887 -67.415333) (xy 203.69281 -67.363242)
			(xy 203.720106 -67.314607) (xy 203.754192 -67.270464) (xy 203.794341 -67.231755) (xy 203.839699 -67.199304)
			(xy 203.889299 -67.173803) (xy 203.942083 -67.155796) (xy 203.996926 -67.145666) (xy 204.05266 -67.143629)
			(xy 204.108097 -67.149729) (xy 204.162054 -67.163835) (xy 204.213383 -67.185647) (xy 204.260989 -67.214701)
			(xy 204.303857 -67.250376) (xy 204.341074 -67.291913) (xy 204.371847 -67.338426) (xy 204.395519 -67.388923)
			(xy 204.411587 -67.44233) (xy 204.419707 -67.497506) (xy 204.420216 -67.525392) (xy 204.419707 -67.553278)
			(xy 204.415699 -67.58051) (xy 206.291686 -67.58051) (xy 206.295757 -67.524888) (xy 206.307883 -67.470451)
			(xy 206.327806 -67.41836) (xy 206.355102 -67.369725) (xy 206.389188 -67.325582) (xy 206.429337 -67.286873)
			(xy 206.474695 -67.254422) (xy 206.524295 -67.228921) (xy 206.577079 -67.210914) (xy 206.631922 -67.200784)
			(xy 206.687656 -67.198747) (xy 206.743093 -67.204847) (xy 206.79705 -67.218953) (xy 206.848379 -67.240765)
			(xy 206.895985 -67.269819) (xy 206.938853 -67.305494) (xy 206.97607 -67.347031) (xy 207.006843 -67.393544)
			(xy 207.030515 -67.444041) (xy 207.046583 -67.497448) (xy 207.054703 -67.552624) (xy 207.055212 -67.58051)
			(xy 207.054703 -67.608396) (xy 207.046583 -67.663572) (xy 207.030515 -67.716979) (xy 207.006843 -67.767476)
			(xy 206.97607 -67.813989) (xy 206.938853 -67.855526) (xy 206.895985 -67.891201) (xy 206.848379 -67.920255)
			(xy 206.79705 -67.942067) (xy 206.743093 -67.956173) (xy 206.687656 -67.962273) (xy 206.631922 -67.960236)
			(xy 206.577079 -67.950106) (xy 206.524295 -67.932099) (xy 206.474695 -67.906598) (xy 206.429337 -67.874147)
			(xy 206.389188 -67.835438) (xy 206.355102 -67.791295) (xy 206.327806 -67.74266) (xy 206.307883 -67.690569)
			(xy 206.295757 -67.636132) (xy 206.291686 -67.58051) (xy 204.415699 -67.58051) (xy 204.411587 -67.608454)
			(xy 204.395519 -67.661861) (xy 204.371847 -67.712358) (xy 204.341074 -67.758871) (xy 204.303857 -67.800408)
			(xy 204.260989 -67.836083) (xy 204.213383 -67.865137) (xy 204.162054 -67.886949) (xy 204.108097 -67.901055)
			(xy 204.05266 -67.907155) (xy 203.996926 -67.905118) (xy 203.942083 -67.894988) (xy 203.889299 -67.876981)
			(xy 203.839699 -67.85148) (xy 203.794341 -67.819029) (xy 203.754192 -67.78032) (xy 203.720106 -67.736177)
			(xy 203.69281 -67.687542) (xy 203.672887 -67.635451) (xy 203.660761 -67.581014) (xy 203.65669 -67.525392)
			(xy 191.283082 -67.525392) (xy 191.283082 -68.230496) (xy 212.039452 -68.230496) (xy 212.043523 -68.174874)
			(xy 212.055649 -68.120437) (xy 212.075572 -68.068346) (xy 212.102868 -68.019711) (xy 212.136954 -67.975568)
			(xy 212.177103 -67.936859) (xy 212.222461 -67.904408) (xy 212.272061 -67.878907) (xy 212.324845 -67.8609)
			(xy 212.379688 -67.85077) (xy 212.435422 -67.848733) (xy 212.490859 -67.854833) (xy 212.544816 -67.868939)
			(xy 212.596145 -67.890751) (xy 212.643751 -67.919805) (xy 212.685319 -67.954398) (xy 220.014036 -67.954398)
			(xy 220.018107 -67.898776) (xy 220.030233 -67.844339) (xy 220.050156 -67.792248) (xy 220.077452 -67.743613)
			(xy 220.111538 -67.69947) (xy 220.151687 -67.660761) (xy 220.197045 -67.62831) (xy 220.246645 -67.602809)
			(xy 220.299429 -67.584802) (xy 220.354272 -67.574672) (xy 220.410006 -67.572635) (xy 220.465443 -67.578735)
			(xy 220.5194 -67.592841) (xy 220.570729 -67.614653) (xy 220.618335 -67.643707) (xy 220.661203 -67.679382)
			(xy 220.69842 -67.720919) (xy 220.729193 -67.767432) (xy 220.752865 -67.817929) (xy 220.768933 -67.871336)
			(xy 220.776297 -67.921378) (xy 223.481898 -67.921378) (xy 223.485969 -67.865756) (xy 223.498095 -67.811319)
			(xy 223.518018 -67.759228) (xy 223.545314 -67.710593) (xy 223.5794 -67.66645) (xy 223.619549 -67.627741)
			(xy 223.664907 -67.59529) (xy 223.714507 -67.569789) (xy 223.767291 -67.551782) (xy 223.822134 -67.541652)
			(xy 223.877868 -67.539615) (xy 223.933305 -67.545715) (xy 223.987262 -67.559821) (xy 224.038591 -67.581633)
			(xy 224.086197 -67.610687) (xy 224.129065 -67.646362) (xy 224.166282 -67.687899) (xy 224.197055 -67.734412)
			(xy 224.220727 -67.784909) (xy 224.236795 -67.838316) (xy 224.244915 -67.893492) (xy 224.245424 -67.921378)
			(xy 224.244915 -67.949264) (xy 224.236795 -68.00444) (xy 224.220727 -68.057847) (xy 224.197055 -68.108344)
			(xy 224.166282 -68.154857) (xy 224.129065 -68.196394) (xy 224.086197 -68.232069) (xy 224.038591 -68.261123)
			(xy 223.987262 -68.282935) (xy 223.933305 -68.297041) (xy 223.877868 -68.303141) (xy 223.822134 -68.301104)
			(xy 223.767291 -68.290974) (xy 223.714507 -68.272967) (xy 223.664907 -68.247466) (xy 223.619549 -68.215015)
			(xy 223.5794 -68.176306) (xy 223.545314 -68.132163) (xy 223.518018 -68.083528) (xy 223.498095 -68.031437)
			(xy 223.485969 -67.977) (xy 223.481898 -67.921378) (xy 220.776297 -67.921378) (xy 220.777053 -67.926512)
			(xy 220.777562 -67.954398) (xy 220.777053 -67.982284) (xy 220.768933 -68.03746) (xy 220.752865 -68.090867)
			(xy 220.729193 -68.141364) (xy 220.69842 -68.187877) (xy 220.661203 -68.229414) (xy 220.618335 -68.265089)
			(xy 220.570729 -68.294143) (xy 220.5194 -68.315955) (xy 220.465443 -68.330061) (xy 220.410006 -68.336161)
			(xy 220.354272 -68.334124) (xy 220.299429 -68.323994) (xy 220.246645 -68.305987) (xy 220.197045 -68.280486)
			(xy 220.151687 -68.248035) (xy 220.111538 -68.209326) (xy 220.077452 -68.165183) (xy 220.050156 -68.116548)
			(xy 220.030233 -68.064457) (xy 220.018107 -68.01002) (xy 220.014036 -67.954398) (xy 212.685319 -67.954398)
			(xy 212.686619 -67.95548) (xy 212.723836 -67.997017) (xy 212.754609 -68.04353) (xy 212.778281 -68.094027)
			(xy 212.794349 -68.147434) (xy 212.802469 -68.20261) (xy 212.802978 -68.230496) (xy 212.802469 -68.258382)
			(xy 212.794349 -68.313558) (xy 212.78625 -68.340478) (xy 216.437716 -68.340478) (xy 216.441787 -68.284856)
			(xy 216.453913 -68.230419) (xy 216.473836 -68.178328) (xy 216.501132 -68.129693) (xy 216.535218 -68.08555)
			(xy 216.575367 -68.046841) (xy 216.620725 -68.01439) (xy 216.670325 -67.988889) (xy 216.723109 -67.970882)
			(xy 216.777952 -67.960752) (xy 216.833686 -67.958715) (xy 216.889123 -67.964815) (xy 216.94308 -67.978921)
			(xy 216.994409 -68.000733) (xy 217.042015 -68.029787) (xy 217.084883 -68.065462) (xy 217.1221 -68.106999)
			(xy 217.152873 -68.153512) (xy 217.176545 -68.204009) (xy 217.192613 -68.257416) (xy 217.200733 -68.312592)
			(xy 217.201242 -68.340478) (xy 217.200733 -68.368364) (xy 217.192613 -68.42354) (xy 217.176545 -68.476947)
			(xy 217.152873 -68.527444) (xy 217.1221 -68.573957) (xy 217.084883 -68.615494) (xy 217.042015 -68.651169)
			(xy 216.994409 -68.680223) (xy 216.94308 -68.702035) (xy 216.889123 -68.716141) (xy 216.833686 -68.722241)
			(xy 216.777952 -68.720204) (xy 216.723109 -68.710074) (xy 216.670325 -68.692067) (xy 216.620725 -68.666566)
			(xy 216.575367 -68.634115) (xy 216.535218 -68.595406) (xy 216.501132 -68.551263) (xy 216.473836 -68.502628)
			(xy 216.453913 -68.450537) (xy 216.441787 -68.3961) (xy 216.437716 -68.340478) (xy 212.78625 -68.340478)
			(xy 212.778281 -68.366965) (xy 212.754609 -68.417462) (xy 212.723836 -68.463975) (xy 212.686619 -68.505512)
			(xy 212.643751 -68.541187) (xy 212.596145 -68.570241) (xy 212.544816 -68.592053) (xy 212.490859 -68.606159)
			(xy 212.435422 -68.612259) (xy 212.379688 -68.610222) (xy 212.324845 -68.600092) (xy 212.272061 -68.582085)
			(xy 212.222461 -68.556584) (xy 212.177103 -68.524133) (xy 212.136954 -68.485424) (xy 212.102868 -68.441281)
			(xy 212.075572 -68.392646) (xy 212.055649 -68.340555) (xy 212.043523 -68.286118) (xy 212.039452 -68.230496)
			(xy 191.283082 -68.230496) (xy 191.283082 -68.696586) (xy 199.142348 -68.696586) (xy 199.146419 -68.640964)
			(xy 199.158545 -68.586527) (xy 199.178468 -68.534436) (xy 199.205764 -68.485801) (xy 199.23985 -68.441658)
			(xy 199.279999 -68.402949) (xy 199.325357 -68.370498) (xy 199.374957 -68.344997) (xy 199.427741 -68.32699)
			(xy 199.482584 -68.31686) (xy 199.538318 -68.314823) (xy 199.593755 -68.320923) (xy 199.647712 -68.335029)
			(xy 199.699041 -68.356841) (xy 199.746647 -68.385895) (xy 199.789515 -68.42157) (xy 199.826732 -68.463107)
			(xy 199.857505 -68.50962) (xy 199.881177 -68.560117) (xy 199.897245 -68.613524) (xy 199.905365 -68.6687)
			(xy 199.905874 -68.696586) (xy 199.905365 -68.724472) (xy 199.897245 -68.779648) (xy 199.881177 -68.833055)
			(xy 199.857505 -68.883552) (xy 199.826732 -68.930065) (xy 199.789515 -68.971602) (xy 199.746647 -69.007277)
			(xy 199.699041 -69.036331) (xy 199.647712 -69.058143) (xy 199.593755 -69.072249) (xy 199.538318 -69.078349)
			(xy 199.482584 -69.076312) (xy 199.427741 -69.066182) (xy 199.374957 -69.048175) (xy 199.325357 -69.022674)
			(xy 199.279999 -68.990223) (xy 199.23985 -68.951514) (xy 199.205764 -68.907371) (xy 199.178468 -68.858736)
			(xy 199.158545 -68.806645) (xy 199.146419 -68.752208) (xy 199.142348 -68.696586) (xy 191.283082 -68.696586)
			(xy 191.283082 -69.620892) (xy 205.393288 -69.620892) (xy 205.397359 -69.56527) (xy 205.409485 -69.510833)
			(xy 205.429408 -69.458742) (xy 205.456704 -69.410107) (xy 205.49079 -69.365964) (xy 205.530939 -69.327255)
			(xy 205.576297 -69.294804) (xy 205.625897 -69.269303) (xy 205.678681 -69.251296) (xy 205.733524 -69.241166)
			(xy 205.789258 -69.239129) (xy 205.844695 -69.245229) (xy 205.898652 -69.259335) (xy 205.949981 -69.281147)
			(xy 205.997587 -69.310201) (xy 206.040455 -69.345876) (xy 206.077672 -69.387413) (xy 206.108445 -69.433926)
			(xy 206.132117 -69.484423) (xy 206.148185 -69.53783) (xy 206.156305 -69.593006) (xy 206.156814 -69.620892)
			(xy 206.156305 -69.648778) (xy 206.148185 -69.703954) (xy 206.132117 -69.757361) (xy 206.108445 -69.807858)
			(xy 206.077672 -69.854371) (xy 206.040455 -69.895908) (xy 205.997587 -69.931583) (xy 205.949981 -69.960637)
			(xy 205.898652 -69.982449) (xy 205.844695 -69.996555) (xy 205.789258 -70.002655) (xy 205.733524 -70.000618)
			(xy 205.678681 -69.990488) (xy 205.625897 -69.972481) (xy 205.576297 -69.94698) (xy 205.530939 -69.914529)
			(xy 205.49079 -69.87582) (xy 205.456704 -69.831677) (xy 205.429408 -69.783042) (xy 205.409485 -69.730951)
			(xy 205.397359 -69.676514) (xy 205.393288 -69.620892) (xy 191.283082 -69.620892) (xy 191.283082 -70.180454)
			(xy 208.670144 -70.180454) (xy 208.67059 -70.154517) (xy 208.677612 -70.103121) (xy 208.691535 -70.053152)
			(xy 208.712102 -70.005529) (xy 208.738932 -69.961134) (xy 208.771532 -69.920784) (xy 208.809298 -69.885224)
			(xy 208.830164 -69.869812) (xy 208.841062 -69.861507) (xy 208.858321 -69.840238) (xy 208.869306 -69.815148)
			(xy 208.873229 -69.78804) (xy 208.869806 -69.760865) (xy 208.859284 -69.735576) (xy 208.84242 -69.713993)
			(xy 208.831688 -69.705474) (xy 208.808203 -69.687355) (xy 208.766604 -69.645073) (xy 208.732055 -69.59686)
			(xy 208.705388 -69.543879) (xy 208.687247 -69.487407) (xy 208.67807 -69.428807) (xy 208.67751 -69.39915)
			(xy 208.677996 -69.371899) (xy 208.685752 -69.317951) (xy 208.701107 -69.265656) (xy 208.723749 -69.216079)
			(xy 208.753215 -69.170229) (xy 208.788906 -69.129038) (xy 208.830097 -69.093347) (xy 208.875947 -69.063881)
			(xy 208.925524 -69.041239) (xy 208.977819 -69.025884) (xy 209.031767 -69.018128) (xy 209.086269 -69.018128)
			(xy 209.140217 -69.025884) (xy 209.192512 -69.041239) (xy 209.242089 -69.063881) (xy 209.287939 -69.093347)
			(xy 209.32913 -69.129038) (xy 209.364821 -69.170229) (xy 209.394287 -69.216079) (xy 209.416929 -69.265656)
			(xy 209.432284 -69.317951) (xy 209.439503 -69.368162) (xy 218.846398 -69.368162) (xy 218.850469 -69.31254)
			(xy 218.862595 -69.258103) (xy 218.882518 -69.206012) (xy 218.909814 -69.157377) (xy 218.9439 -69.113234)
			(xy 218.984049 -69.074525) (xy 219.029407 -69.042074) (xy 219.079007 -69.016573) (xy 219.131791 -68.998566)
			(xy 219.186634 -68.988436) (xy 219.242368 -68.986399) (xy 219.297805 -68.992499) (xy 219.351762 -69.006605)
			(xy 219.403091 -69.028417) (xy 219.450697 -69.057471) (xy 219.493565 -69.093146) (xy 219.530782 -69.134683)
			(xy 219.561555 -69.181196) (xy 219.585227 -69.231693) (xy 219.601295 -69.2851) (xy 219.609415 -69.340276)
			(xy 219.609924 -69.368162) (xy 220.116398 -69.368162) (xy 220.120469 -69.31254) (xy 220.132595 -69.258103)
			(xy 220.152518 -69.206012) (xy 220.179814 -69.157377) (xy 220.2139 -69.113234) (xy 220.254049 -69.074525)
			(xy 220.299407 -69.042074) (xy 220.349007 -69.016573) (xy 220.401791 -68.998566) (xy 220.456634 -68.988436)
			(xy 220.512368 -68.986399) (xy 220.567805 -68.992499) (xy 220.621762 -69.006605) (xy 220.673091 -69.028417)
			(xy 220.720697 -69.057471) (xy 220.763565 -69.093146) (xy 220.800782 -69.134683) (xy 220.831555 -69.181196)
			(xy 220.855227 -69.231693) (xy 220.871295 -69.2851) (xy 220.879415 -69.340276) (xy 220.879924 -69.368162)
			(xy 220.879415 -69.396048) (xy 220.871295 -69.451224) (xy 220.855227 -69.504631) (xy 220.831555 -69.555128)
			(xy 220.800782 -69.601641) (xy 220.763565 -69.643178) (xy 220.720697 -69.678853) (xy 220.673091 -69.707907)
			(xy 220.648332 -69.718428) (xy 224.155508 -69.718428) (xy 224.155975 -69.691825) (xy 224.163353 -69.639132)
			(xy 224.177984 -69.587977) (xy 224.199583 -69.539352) (xy 224.227732 -69.494201) (xy 224.261884 -69.453402)
			(xy 224.301375 -69.417745) (xy 224.323148 -69.402452) (xy 224.334654 -69.394148) (xy 224.352868 -69.372401)
			(xy 224.36439 -69.346479) (xy 224.36833 -69.318388) (xy 224.364383 -69.290297) (xy 224.352855 -69.264378)
			(xy 224.334636 -69.242635) (xy 224.323148 -69.234304) (xy 224.301373 -69.219016) (xy 224.261893 -69.183349)
			(xy 224.22775 -69.142544) (xy 224.199605 -69.097393) (xy 224.178003 -69.048771) (xy 224.163364 -68.997619)
			(xy 224.155971 -68.94493) (xy 224.155508 -68.918328) (xy 224.155994 -68.891077) (xy 224.16375 -68.837129)
			(xy 224.179105 -68.784834) (xy 224.201747 -68.735257) (xy 224.231213 -68.689407) (xy 224.266904 -68.648216)
			(xy 224.308095 -68.612525) (xy 224.353945 -68.583059) (xy 224.403522 -68.560417) (xy 224.455817 -68.545062)
			(xy 224.509765 -68.537306) (xy 224.564267 -68.537306) (xy 224.618215 -68.545062) (xy 224.67051 -68.560417)
			(xy 224.720087 -68.583059) (xy 224.765937 -68.612525) (xy 224.807128 -68.648216) (xy 224.842819 -68.689407)
			(xy 224.872285 -68.735257) (xy 224.894927 -68.784834) (xy 224.910282 -68.837129) (xy 224.918038 -68.891077)
			(xy 224.918524 -68.918328) (xy 224.918054 -68.944932) (xy 224.91068 -68.997625) (xy 224.896052 -69.048782)
			(xy 224.874454 -69.097408) (xy 224.846305 -69.142559) (xy 224.812152 -69.183358) (xy 224.772658 -69.219012)
			(xy 224.750884 -69.234304) (xy 224.739427 -69.242667) (xy 224.721227 -69.264405) (xy 224.709711 -69.290312)
			(xy 224.705769 -69.318388) (xy 224.709704 -69.346464) (xy 224.721214 -69.372374) (xy 224.739408 -69.394117)
			(xy 224.750884 -69.402452) (xy 224.772646 -69.417758) (xy 224.812124 -69.453423) (xy 224.846267 -69.494225)
			(xy 224.874413 -69.539373) (xy 224.896017 -69.587992) (xy 224.91066 -69.639141) (xy 224.918058 -69.691827)
			(xy 224.918524 -69.718428) (xy 224.918038 -69.745679) (xy 224.910282 -69.799627) (xy 224.894927 -69.851922)
			(xy 224.872285 -69.901499) (xy 224.842819 -69.947349) (xy 224.807128 -69.98854) (xy 224.765937 -70.024231)
			(xy 224.720087 -70.053697) (xy 224.67051 -70.076339) (xy 224.618215 -70.091694) (xy 224.564267 -70.09945)
			(xy 224.509765 -70.09945) (xy 224.455817 -70.091694) (xy 224.403522 -70.076339) (xy 224.353945 -70.053697)
			(xy 224.308095 -70.024231) (xy 224.266904 -69.98854) (xy 224.231213 -69.947349) (xy 224.201747 -69.901499)
			(xy 224.179105 -69.851922) (xy 224.16375 -69.799627) (xy 224.155994 -69.745679) (xy 224.155508 -69.718428)
			(xy 220.648332 -69.718428) (xy 220.621762 -69.729719) (xy 220.567805 -69.743825) (xy 220.512368 -69.749925)
			(xy 220.456634 -69.747888) (xy 220.401791 -69.737758) (xy 220.349007 -69.719751) (xy 220.299407 -69.69425)
			(xy 220.254049 -69.661799) (xy 220.2139 -69.62309) (xy 220.179814 -69.578947) (xy 220.152518 -69.530312)
			(xy 220.132595 -69.478221) (xy 220.120469 -69.423784) (xy 220.116398 -69.368162) (xy 219.609924 -69.368162)
			(xy 219.609415 -69.396048) (xy 219.601295 -69.451224) (xy 219.585227 -69.504631) (xy 219.561555 -69.555128)
			(xy 219.530782 -69.601641) (xy 219.493565 -69.643178) (xy 219.450697 -69.678853) (xy 219.403091 -69.707907)
			(xy 219.351762 -69.729719) (xy 219.297805 -69.743825) (xy 219.242368 -69.749925) (xy 219.186634 -69.747888)
			(xy 219.131791 -69.737758) (xy 219.079007 -69.719751) (xy 219.029407 -69.69425) (xy 218.984049 -69.661799)
			(xy 218.9439 -69.62309) (xy 218.909814 -69.578947) (xy 218.882518 -69.530312) (xy 218.862595 -69.478221)
			(xy 218.850469 -69.423784) (xy 218.846398 -69.368162) (xy 209.439503 -69.368162) (xy 209.44004 -69.371899)
			(xy 209.440526 -69.39915) (xy 209.440054 -69.425086) (xy 209.433033 -69.476479) (xy 209.419112 -69.526447)
			(xy 209.398549 -69.574068) (xy 209.371723 -69.618464) (xy 209.339129 -69.658815) (xy 209.301368 -69.694378)
			(xy 209.280506 -69.709792) (xy 209.269607 -69.718093) (xy 209.252353 -69.739365) (xy 209.241371 -69.764455)
			(xy 209.23745 -69.791562) (xy 209.240873 -69.818736) (xy 209.251392 -69.844025) (xy 209.268252 -69.865609)
			(xy 209.278982 -69.87413) (xy 209.302463 -69.892255) (xy 209.344063 -69.934534) (xy 209.378614 -69.982746)
			(xy 209.399502 -70.024244) (xy 212.007956 -70.024244) (xy 212.012027 -69.968622) (xy 212.024153 -69.914185)
			(xy 212.044076 -69.862094) (xy 212.071372 -69.813459) (xy 212.105458 -69.769316) (xy 212.145607 -69.730607)
			(xy 212.190965 -69.698156) (xy 212.240565 -69.672655) (xy 212.293349 -69.654648) (xy 212.348192 -69.644518)
			(xy 212.403926 -69.642481) (xy 212.459363 -69.648581) (xy 212.51332 -69.662687) (xy 212.564649 -69.684499)
			(xy 212.612255 -69.713553) (xy 212.655123 -69.749228) (xy 212.69234 -69.790765) (xy 212.723113 -69.837278)
			(xy 212.746785 -69.887775) (xy 212.762853 -69.941182) (xy 212.770973 -69.996358) (xy 212.771482 -70.024244)
			(xy 212.770973 -70.05213) (xy 212.762853 -70.107306) (xy 212.746785 -70.160713) (xy 212.723113 -70.21121)
			(xy 212.69234 -70.257723) (xy 212.655123 -70.29926) (xy 212.612255 -70.334935) (xy 212.564649 -70.363989)
			(xy 212.51332 -70.385801) (xy 212.459363 -70.399907) (xy 212.403926 -70.406007) (xy 212.348192 -70.40397)
			(xy 212.293349 -70.39384) (xy 212.240565 -70.375833) (xy 212.190965 -70.350332) (xy 212.145607 -70.317881)
			(xy 212.105458 -70.279172) (xy 212.071372 -70.235029) (xy 212.044076 -70.186394) (xy 212.024153 -70.134303)
			(xy 212.012027 -70.079866) (xy 212.007956 -70.024244) (xy 209.399502 -70.024244) (xy 209.405282 -70.035726)
			(xy 209.423423 -70.092198) (xy 209.4326 -70.150797) (xy 209.43316 -70.180454) (xy 209.432674 -70.207705)
			(xy 209.424918 -70.261653) (xy 209.409563 -70.313948) (xy 209.386921 -70.363525) (xy 209.357455 -70.409375)
			(xy 209.321764 -70.450566) (xy 209.280573 -70.486257) (xy 209.234723 -70.515723) (xy 209.185146 -70.538365)
			(xy 209.132851 -70.55372) (xy 209.078903 -70.561476) (xy 209.024401 -70.561476) (xy 208.970453 -70.55372)
			(xy 208.918158 -70.538365) (xy 208.868581 -70.515723) (xy 208.822731 -70.486257) (xy 208.78154 -70.450566)
			(xy 208.745849 -70.409375) (xy 208.716383 -70.363525) (xy 208.693741 -70.313948) (xy 208.678386 -70.261653)
			(xy 208.67063 -70.207705) (xy 208.670144 -70.180454) (xy 191.283082 -70.180454) (xy 191.283082 -71.017638)
			(xy 191.283566 -71.027407) (xy 191.290942 -71.045503) (xy 191.304538 -71.05954) (xy 191.313308 -71.063866)
			(xy 191.412114 -71.107808) (xy 191.441578 -71.102982) (xy 191.452754 -71.092822) (xy 191.473914 -71.074361)
			(xy 191.520635 -71.043212) (xy 191.571416 -71.019244) (xy 191.625161 -71.002977) (xy 191.680709 -70.994761)
			(xy 191.708786 -70.99427) (xy 191.736041 -70.994732) (xy 191.789997 -71.002488) (xy 191.842299 -71.017843)
			(xy 191.891884 -71.040486) (xy 191.937742 -71.069956) (xy 191.978938 -71.105652) (xy 192.014636 -71.146847)
			(xy 192.044107 -71.192704) (xy 192.066752 -71.242288) (xy 192.082109 -71.29459) (xy 192.089867 -71.348545)
			(xy 192.089867 -71.403055) (xy 192.082109 -71.45701) (xy 192.066752 -71.509312) (xy 192.044107 -71.558896)
			(xy 192.014636 -71.604753) (xy 191.978938 -71.645948) (xy 191.937742 -71.681644) (xy 191.891884 -71.711114)
			(xy 191.842299 -71.733757) (xy 191.789997 -71.749112) (xy 191.736041 -71.756868) (xy 191.708786 -71.757286)
			(xy 191.68071 -71.756789) (xy 191.625163 -71.748566) (xy 191.571418 -71.7323) (xy 191.520634 -71.708341)
			(xy 191.473904 -71.677205) (xy 191.452754 -71.658734) (xy 191.441578 -71.648574) (xy 191.412114 -71.643748)
			(xy 191.313308 -71.68769) (xy 191.304549 -71.692042) (xy 191.290928 -71.706055) (xy 191.283546 -71.724149)
			(xy 191.283082 -71.733918) (xy 191.283082 -72.188649) (xy 192.814978 -72.188649) (xy 192.814978 -72.134151)
			(xy 192.822733 -72.080207) (xy 192.838086 -72.027916) (xy 192.860724 -71.978341) (xy 192.890186 -71.932493)
			(xy 192.925873 -71.891304) (xy 192.967058 -71.855612) (xy 193.012903 -71.826145) (xy 193.062474 -71.803501)
			(xy 193.114764 -71.788142) (xy 193.168707 -71.780381) (xy 193.195956 -71.779892) (xy 193.224921 -71.780462)
			(xy 193.282184 -71.789227) (xy 193.337464 -71.806546) (xy 193.389491 -71.832023) (xy 193.437069 -71.865071)
			(xy 193.479105 -71.904931) (xy 193.514633 -71.950687) (xy 193.529204 -71.975726) (xy 193.535805 -71.986037)
			(xy 193.556232 -71.999451) (xy 193.56832 -72.00138) (xy 193.60007 -72.004936) (xy 193.612348 -72.00546)
			(xy 193.635168 -71.996451) (xy 193.643758 -71.987664) (xy 193.644774 -71.986394) (xy 193.651124 -71.979282)
			(xy 193.657728 -71.961502) (xy 193.656204 -71.873872) (xy 193.648838 -71.856346) (xy 193.642488 -71.849488)
			(xy 193.623979 -71.829167) (xy 193.592336 -71.784226) (xy 193.567466 -71.735212) (xy 193.549882 -71.683137)
			(xy 193.544444 -71.656194) (xy 193.542412 -71.645526) (xy 193.530474 -71.627746) (xy 193.447924 -71.576692)
			(xy 193.426842 -71.573898) (xy 193.416428 -71.576946) (xy 193.390629 -71.58387) (xy 193.337727 -71.591266)
			(xy 193.311018 -71.591678) (xy 193.283762 -71.591276) (xy 193.229805 -71.583521) (xy 193.177501 -71.568165)
			(xy 193.127914 -71.545522) (xy 193.082055 -71.516052) (xy 193.040857 -71.480355) (xy 193.005159 -71.439159)
			(xy 192.975687 -71.393301) (xy 192.953041 -71.343716) (xy 192.937683 -71.291413) (xy 192.929925 -71.237456)
			(xy 192.929925 -71.182944) (xy 192.937683 -71.128987) (xy 192.953041 -71.076684) (xy 192.975687 -71.027099)
			(xy 193.005159 -70.981241) (xy 193.040857 -70.940045) (xy 193.082055 -70.904348) (xy 193.127914 -70.874878)
			(xy 193.177501 -70.852235) (xy 193.229805 -70.836879) (xy 193.283762 -70.829124) (xy 193.311018 -70.828662)
			(xy 193.338862 -70.829175) (xy 193.39395 -70.837333) (xy 193.420746 -70.844918) (xy 193.430144 -70.847712)
			(xy 193.44894 -70.846188) (xy 193.528188 -70.80758) (xy 193.541142 -70.793864) (xy 193.544698 -70.78472)
			(xy 193.555651 -70.758394) (xy 193.584216 -70.709048) (xy 193.61981 -70.664506) (xy 193.661639 -70.62576)
			(xy 193.708771 -70.593674) (xy 193.760155 -70.568963) (xy 193.814645 -70.552179) (xy 193.871027 -70.543694)
			(xy 193.899536 -70.543166) (xy 193.926787 -70.543644) (xy 193.980734 -70.551405) (xy 194.033027 -70.566763)
			(xy 194.082603 -70.589407) (xy 194.102738 -70.602348) (xy 197.082916 -70.602348) (xy 197.086987 -70.546726)
			(xy 197.099113 -70.492289) (xy 197.119036 -70.440198) (xy 197.146332 -70.391563) (xy 197.180418 -70.34742)
			(xy 197.220567 -70.308711) (xy 197.265925 -70.27626) (xy 197.315525 -70.250759) (xy 197.368309 -70.232752)
			(xy 197.423152 -70.222622) (xy 197.478886 -70.220585) (xy 197.534323 -70.226685) (xy 197.58828 -70.240791)
			(xy 197.639609 -70.262603) (xy 197.687215 -70.291657) (xy 197.730083 -70.327332) (xy 197.7673 -70.368869)
			(xy 197.798073 -70.415382) (xy 197.821745 -70.465879) (xy 197.837813 -70.519286) (xy 197.845933 -70.574462)
			(xy 197.846442 -70.602348) (xy 197.845933 -70.630234) (xy 197.837813 -70.68541) (xy 197.821745 -70.738817)
			(xy 197.798073 -70.789314) (xy 197.7673 -70.835827) (xy 197.730083 -70.877364) (xy 197.687215 -70.913039)
			(xy 197.639609 -70.942093) (xy 197.58828 -70.963905) (xy 197.534323 -70.978011) (xy 197.478886 -70.984111)
			(xy 197.423152 -70.982074) (xy 197.368309 -70.971944) (xy 197.315525 -70.953937) (xy 197.265925 -70.928436)
			(xy 197.220567 -70.895985) (xy 197.180418 -70.857276) (xy 197.146332 -70.813133) (xy 197.119036 -70.764498)
			(xy 197.099113 -70.712407) (xy 197.086987 -70.65797) (xy 197.082916 -70.602348) (xy 194.102738 -70.602348)
			(xy 194.128451 -70.618874) (xy 194.169641 -70.654566) (xy 194.205332 -70.695757) (xy 194.234798 -70.741606)
			(xy 194.25744 -70.791183) (xy 194.272797 -70.843476) (xy 194.280556 -70.897423) (xy 194.281044 -70.924674)
			(xy 194.280559 -70.952384) (xy 194.272527 -71.007218) (xy 194.256642 -71.060313) (xy 194.23324 -71.110549)
			(xy 194.202812 -71.156868) (xy 194.184778 -71.177912) (xy 194.178428 -71.185278) (xy 194.171824 -71.203312)
			(xy 194.174364 -71.29272) (xy 194.182238 -71.3105) (xy 194.189096 -71.317358) (xy 194.209958 -71.338948)
			(xy 194.245291 -71.387484) (xy 194.272581 -71.440958) (xy 194.291155 -71.498048) (xy 194.300553 -71.557342)
			(xy 194.30111 -71.58736) (xy 194.300639 -71.61493) (xy 194.292705 -71.669495) (xy 194.276997 -71.722349)
			(xy 194.253842 -71.772391) (xy 194.223723 -71.818577) (xy 194.20586 -71.839582) (xy 194.19951 -71.846694)
			(xy 194.192906 -71.864474) (xy 194.19443 -71.952104) (xy 194.201796 -71.96963) (xy 194.208146 -71.976488)
			(xy 194.227652 -71.997842) (xy 194.260609 -72.045369) (xy 194.28601 -72.097327) (xy 194.303275 -72.152526)
			(xy 194.312006 -72.209698) (xy 194.31254 -72.238616) (xy 194.312037 -72.265866) (xy 194.304279 -72.319812)
			(xy 194.288924 -72.372104) (xy 194.266283 -72.421679) (xy 194.236818 -72.467528) (xy 194.201129 -72.508717)
			(xy 194.159941 -72.544409) (xy 194.114093 -72.573875) (xy 194.064519 -72.596518) (xy 194.012227 -72.611876)
			(xy 193.958282 -72.619636) (xy 193.931032 -72.620124) (xy 193.904427 -72.619684) (xy 193.851732 -72.612305)
			(xy 193.800575 -72.597672) (xy 193.751949 -72.576069) (xy 193.706798 -72.547915) (xy 193.666 -72.513758)
			(xy 193.630347 -72.47426) (xy 193.615056 -72.452484) (xy 193.608706 -72.443086) (xy 193.589656 -72.431656)
			(xy 193.48958 -72.421242) (xy 193.468752 -72.428354) (xy 193.460624 -72.436228) (xy 193.439168 -72.456134)
			(xy 193.391304 -72.489813) (xy 193.338857 -72.515788) (xy 193.283059 -72.533448) (xy 193.225219 -72.542379)
			(xy 193.195956 -72.542908) (xy 193.168707 -72.542419) (xy 193.114764 -72.534658) (xy 193.062474 -72.519299)
			(xy 193.012903 -72.496655) (xy 192.967058 -72.467188) (xy 192.925873 -72.431496) (xy 192.890186 -72.390307)
			(xy 192.860724 -72.344459) (xy 192.838086 -72.294884) (xy 192.822733 -72.242593) (xy 192.814978 -72.188649)
			(xy 191.283082 -72.188649) (xy 191.283082 -75.098148) (xy 192.77533 -75.098148) (xy 192.779401 -75.042526)
			(xy 192.791527 -74.988089) (xy 192.81145 -74.935998) (xy 192.838746 -74.887363) (xy 192.872832 -74.84322)
			(xy 192.912981 -74.804511) (xy 192.958339 -74.77206) (xy 193.007939 -74.746559) (xy 193.060723 -74.728552)
			(xy 193.115566 -74.718422) (xy 193.1713 -74.716385) (xy 193.226737 -74.722485) (xy 193.280694 -74.736591)
			(xy 193.332023 -74.758403) (xy 193.379629 -74.787457) (xy 193.422497 -74.823132) (xy 193.459714 -74.864669)
			(xy 193.490487 -74.911182) (xy 193.514159 -74.961679) (xy 193.530227 -75.015086) (xy 193.538347 -75.070262)
			(xy 193.538856 -75.098148) (xy 193.538347 -75.126034) (xy 193.530227 -75.18121) (xy 193.514159 -75.234617)
			(xy 193.510382 -75.242674) (xy 195.144642 -75.242674) (xy 195.148713 -75.187052) (xy 195.160839 -75.132615)
			(xy 195.180762 -75.080524) (xy 195.208058 -75.031889) (xy 195.242144 -74.987746) (xy 195.282293 -74.949037)
			(xy 195.327651 -74.916586) (xy 195.377251 -74.891085) (xy 195.430035 -74.873078) (xy 195.484878 -74.862948)
			(xy 195.540612 -74.860911) (xy 195.596049 -74.867011) (xy 195.650006 -74.881117) (xy 195.701335 -74.902929)
			(xy 195.748941 -74.931983) (xy 195.791809 -74.967658) (xy 195.829026 -75.009195) (xy 195.859799 -75.055708)
			(xy 195.883471 -75.106205) (xy 195.899539 -75.159612) (xy 195.907659 -75.214788) (xy 195.908168 -75.242674)
			(xy 195.907779 -75.26401) (xy 197.094854 -75.26401) (xy 197.098925 -75.208388) (xy 197.111051 -75.153951)
			(xy 197.130974 -75.10186) (xy 197.15827 -75.053225) (xy 197.192356 -75.009082) (xy 197.232505 -74.970373)
			(xy 197.277863 -74.937922) (xy 197.327463 -74.912421) (xy 197.380247 -74.894414) (xy 197.43509 -74.884284)
			(xy 197.490824 -74.882247) (xy 197.546261 -74.888347) (xy 197.600218 -74.902453) (xy 197.651547 -74.924265)
			(xy 197.699153 -74.953319) (xy 197.742021 -74.988994) (xy 197.779238 -75.030531) (xy 197.810011 -75.077044)
			(xy 197.833683 -75.127541) (xy 197.849751 -75.180948) (xy 197.857871 -75.236124) (xy 197.85838 -75.26401)
			(xy 197.857871 -75.291896) (xy 197.849751 -75.347072) (xy 197.833683 -75.400479) (xy 197.810011 -75.450976)
			(xy 197.779238 -75.497489) (xy 197.742021 -75.539026) (xy 197.699153 -75.574701) (xy 197.651547 -75.603755)
			(xy 197.600218 -75.625567) (xy 197.546261 -75.639673) (xy 197.490824 -75.645773) (xy 197.43509 -75.643736)
			(xy 197.380247 -75.633606) (xy 197.327463 -75.615599) (xy 197.277863 -75.590098) (xy 197.232505 -75.557647)
			(xy 197.192356 -75.518938) (xy 197.15827 -75.474795) (xy 197.130974 -75.42616) (xy 197.111051 -75.374069)
			(xy 197.098925 -75.319632) (xy 197.094854 -75.26401) (xy 195.907779 -75.26401) (xy 195.907659 -75.27056)
			(xy 195.899539 -75.325736) (xy 195.883471 -75.379143) (xy 195.859799 -75.42964) (xy 195.829026 -75.476153)
			(xy 195.791809 -75.51769) (xy 195.748941 -75.553365) (xy 195.701335 -75.582419) (xy 195.650006 -75.604231)
			(xy 195.596049 -75.618337) (xy 195.540612 -75.624437) (xy 195.484878 -75.6224) (xy 195.430035 -75.61227)
			(xy 195.377251 -75.594263) (xy 195.327651 -75.568762) (xy 195.282293 -75.536311) (xy 195.242144 -75.497602)
			(xy 195.208058 -75.453459) (xy 195.180762 -75.404824) (xy 195.160839 -75.352733) (xy 195.148713 -75.298296)
			(xy 195.144642 -75.242674) (xy 193.510382 -75.242674) (xy 193.490487 -75.285114) (xy 193.459714 -75.331627)
			(xy 193.422497 -75.373164) (xy 193.379629 -75.408839) (xy 193.332023 -75.437893) (xy 193.280694 -75.459705)
			(xy 193.226737 -75.473811) (xy 193.1713 -75.479911) (xy 193.115566 -75.477874) (xy 193.060723 -75.467744)
			(xy 193.007939 -75.449737) (xy 192.958339 -75.424236) (xy 192.912981 -75.391785) (xy 192.872832 -75.353076)
			(xy 192.838746 -75.308933) (xy 192.81145 -75.260298) (xy 192.791527 -75.208207) (xy 192.779401 -75.15377)
			(xy 192.77533 -75.098148) (xy 191.283082 -75.098148) (xy 191.283082 -75.84948) (xy 192.279522 -75.84948)
			(xy 192.283593 -75.793858) (xy 192.295719 -75.739421) (xy 192.315642 -75.68733) (xy 192.342938 -75.638695)
			(xy 192.377024 -75.594552) (xy 192.417173 -75.555843) (xy 192.462531 -75.523392) (xy 192.512131 -75.497891)
			(xy 192.564915 -75.479884) (xy 192.619758 -75.469754) (xy 192.675492 -75.467717) (xy 192.730929 -75.473817)
			(xy 192.784886 -75.487923) (xy 192.836215 -75.509735) (xy 192.883821 -75.538789) (xy 192.926689 -75.574464)
			(xy 192.963906 -75.616001) (xy 192.994679 -75.662514) (xy 193.018351 -75.713011) (xy 193.034419 -75.766418)
			(xy 193.042539 -75.821594) (xy 193.043048 -75.84948) (xy 193.042539 -75.877366) (xy 193.034419 -75.932542)
			(xy 193.018351 -75.985949) (xy 192.994679 -76.036446) (xy 192.963906 -76.082959) (xy 192.926689 -76.124496)
			(xy 192.883821 -76.160171) (xy 192.836215 -76.189225) (xy 192.784886 -76.211037) (xy 192.730929 -76.225143)
			(xy 192.675492 -76.231243) (xy 192.619758 -76.229206) (xy 192.564915 -76.219076) (xy 192.512131 -76.201069)
			(xy 192.462531 -76.175568) (xy 192.417173 -76.143117) (xy 192.377024 -76.104408) (xy 192.342938 -76.060265)
			(xy 192.315642 -76.01163) (xy 192.295719 -75.959539) (xy 192.283593 -75.905102) (xy 192.279522 -75.84948)
			(xy 191.283082 -75.84948) (xy 191.283082 -75.876912) (xy 191.283507 -75.886982) (xy 191.291222 -75.905585)
			(xy 191.298068 -75.91298) (xy 192.210436 -76.825348) (xy 192.217834 -76.832194) (xy 192.236433 -76.839924)
			(xy 192.246504 -76.840334) (xy 192.369186 -76.840334) (xy 192.378076 -76.836778) (xy 192.40014 -76.828609)
			(xy 192.445774 -76.817158) (xy 192.492473 -76.811426) (xy 192.515998 -76.811124) (xy 192.541035 -76.811515)
			(xy 192.590679 -76.81807) (xy 192.639034 -76.831081) (xy 192.662302 -76.840334) (xy 192.6717 -76.844144)
		)
		(stroke
			(width 0)
			(type solid)
		)
		(fill yes)
		(layer "In11.Cu")
		(net "GND")
	)
	(gr_poly
		(pts
			(xy 430.188116 -372.10746) (xy 430.19472 -372.09476) (xy 430.207858 -372.069997) (xy 430.240288 -372.024276)
			(xy 430.279055 -371.983788) (xy 430.323326 -371.949404) (xy 430.372148 -371.921862) (xy 430.424473 -371.901756)
			(xy 430.479176 -371.889516) (xy 430.53508 -371.885407) (xy 430.590984 -371.889516) (xy 430.645687 -371.901756)
			(xy 430.698012 -371.921862) (xy 430.746834 -371.949404) (xy 430.791105 -371.983788) (xy 430.829872 -372.024276)
			(xy 430.862302 -372.069997) (xy 430.87544 -372.09476) (xy 430.882044 -372.10746) (xy 430.906174 -372.122446)
			(xy 432.047142 -372.122446) (xy 432.057018 -372.121983) (xy 432.075315 -372.114538) (xy 432.082702 -372.107968)
			(xy 437.358282 -366.832388) (xy 437.365681 -366.825545) (xy 437.38428 -366.817826) (xy 437.39435 -366.817402)
			(xy 442.989716 -366.817402) (xy 442.999593 -366.816942) (xy 443.017892 -366.8095) (xy 443.025276 -366.802924)
			(xy 449.31457 -360.51363) (xy 449.315078 -360.513122) (xy 449.321654 -360.505738) (xy 449.329091 -360.48744)
			(xy 449.329556 -360.477562) (xy 449.329556 -342.932258) (xy 449.321936 -342.913462) (xy 449.31457 -342.90635)
			(xy 448.711066 -342.302846) (xy 448.703668 -342.296) (xy 448.685069 -342.288271) (xy 448.674998 -342.28786)
			(xy 409.908502 -342.28786) (xy 409.889706 -342.29548) (xy 409.882594 -342.302846) (xy 409.170378 -343.015062)
			(xy 409.163533 -343.02246) (xy 409.155809 -343.041059) (xy 409.155392 -343.05113) (xy 409.155392 -344.14206)
			(xy 409.155805 -344.152087) (xy 409.163467 -344.170619) (xy 409.17764 -344.184806) (xy 409.196165 -344.192486)
			(xy 409.206192 -344.19286) (xy 414.706054 -344.19286) (xy 414.734 -344.193377) (xy 414.789203 -344.202117)
			(xy 414.842358 -344.219389) (xy 414.892155 -344.244767) (xy 414.937367 -344.277626) (xy 414.957514 -344.297)
			(xy 418.05352 -347.393006) (xy 418.072879 -347.413163) (xy 418.10571 -347.458387) (xy 418.131075 -347.508184)
			(xy 418.148352 -347.561331) (xy 418.157116 -347.616524) (xy 418.15766 -347.644466) (xy 418.15766 -352.769678)
			(xy 419.579552 -352.769678) (xy 419.580041 -352.741767) (xy 419.588178 -352.686542) (xy 419.604275 -352.633091)
			(xy 419.627988 -352.582556) (xy 419.658812 -352.536016) (xy 419.677088 -352.514916) (xy 419.682976 -352.507732)
			(xy 419.689633 -352.490412) (xy 419.690042 -352.481134) (xy 419.690042 -352.412808) (xy 419.689606 -352.403535)
			(xy 419.682959 -352.386217) (xy 419.677088 -352.379026) (xy 419.658799 -352.357936) (xy 419.627973 -352.311395)
			(xy 419.604261 -352.260858) (xy 419.588167 -352.207404) (xy 419.580036 -352.152176) (xy 419.579552 -352.124264)
			(xy 419.580038 -352.097013) (xy 419.587794 -352.043065) (xy 419.603149 -351.99077) (xy 419.625791 -351.941193)
			(xy 419.655257 -351.895343) (xy 419.690948 -351.854152) (xy 419.732139 -351.818461) (xy 419.777989 -351.788995)
			(xy 419.827566 -351.766353) (xy 419.879861 -351.750998) (xy 419.933809 -351.743242) (xy 419.988311 -351.743242)
			(xy 420.042259 -351.750998) (xy 420.094554 -351.766353) (xy 420.144131 -351.788995) (xy 420.189981 -351.818461)
			(xy 420.231172 -351.854152) (xy 420.266863 -351.895343) (xy 420.296329 -351.941193) (xy 420.318971 -351.99077)
			(xy 420.334326 -352.043065) (xy 420.342082 -352.097013) (xy 420.342568 -352.124264) (xy 420.342099 -352.152176)
			(xy 420.333956 -352.207402) (xy 420.317855 -352.260852) (xy 420.294137 -352.311386) (xy 420.26331 -352.357926)
			(xy 420.245032 -352.379026) (xy 420.239116 -352.386189) (xy 420.232478 -352.403525) (xy 420.232078 -352.412808)
			(xy 420.232078 -352.481134) (xy 420.232538 -352.490404) (xy 420.239168 -352.507723) (xy 420.245032 -352.514916)
			(xy 420.263297 -352.536026) (xy 420.294125 -352.582562) (xy 420.317842 -352.633094) (xy 420.333942 -352.686543)
			(xy 420.34208 -352.741768) (xy 420.342568 -352.769678) (xy 420.342082 -352.796929) (xy 420.334326 -352.850877)
			(xy 420.318971 -352.903172) (xy 420.296329 -352.952749) (xy 420.266863 -352.998599) (xy 420.231172 -353.03979)
			(xy 420.189981 -353.075481) (xy 420.146849 -353.1032) (xy 423.961713 -353.1032) (xy 423.965882 -353.047576)
			(xy 423.978295 -352.993194) (xy 423.998676 -352.94127) (xy 424.026567 -352.892964) (xy 424.061348 -352.849355)
			(xy 424.10224 -352.811417) (xy 424.14833 -352.779998) (xy 424.198588 -352.755799) (xy 424.251892 -352.739362)
			(xy 424.30705 -352.731054) (xy 424.33494 -352.730562) (xy 424.362137 -352.731022) (xy 424.415952 -352.738937)
			(xy 424.468049 -352.754579) (xy 424.517324 -352.777616) (xy 424.562733 -352.807561) (xy 424.583352 -352.825304)
			(xy 424.591226 -352.828606) (xy 424.605704 -352.8314) (xy 424.61561 -352.832416) (xy 424.68673 -352.832416)
			(xy 424.695874 -352.828606) (xy 424.699582 -352.827006) (xy 424.706472 -352.822791) (xy 424.70959 -352.820224)
			(xy 424.730272 -352.803157) (xy 424.775569 -352.774463) (xy 424.824509 -352.752554) (xy 424.876083 -352.737881)
			(xy 424.929227 -352.730747) (xy 424.982845 -352.731299) (xy 425.03583 -352.739526) (xy 425.087091 -352.755259)
			(xy 425.135569 -352.778171) (xy 425.180266 -352.807792) (xy 425.200572 -352.825304) (xy 425.208446 -352.828606)
			(xy 425.222924 -352.8314) (xy 425.23283 -352.832416) (xy 425.29379 -352.832416) (xy 425.299511 -352.832226)
			(xy 425.310664 -352.829673) (xy 425.315888 -352.827336) (xy 425.316142 -352.827336) (xy 425.32681 -352.820224)
			(xy 425.340704 -352.80864) (xy 425.370347 -352.787903) (xy 425.385992 -352.778822) (xy 425.395891 -352.772634)
			(xy 425.409136 -352.753445) (xy 425.411392 -352.741992) (xy 425.424854 -352.65106) (xy 425.421298 -352.63963)
			(xy 425.419408 -352.634292) (xy 425.413641 -352.624549) (xy 425.409868 -352.620326) (xy 425.409614 -352.620072)
			(xy 425.390078 -352.598697) (xy 425.357038 -352.551143) (xy 425.33157 -352.499139) (xy 425.314259 -352.443882)
			(xy 425.305504 -352.386643) (xy 425.304966 -352.35769) (xy 425.305471 -352.330117) (xy 425.313412 -352.275545)
			(xy 425.329128 -352.222684) (xy 425.352291 -352.172638) (xy 425.382418 -352.126448) (xy 425.418881 -352.085076)
			(xy 425.439586 -352.06686) (xy 425.445936 -352.061526) (xy 425.454318 -352.04781) (xy 425.45635 -352.039682)
			(xy 425.45762 -352.027998) (xy 425.45762 -351.950782) (xy 425.45635 -351.939098) (xy 425.454318 -351.93097)
			(xy 425.445936 -351.917254) (xy 425.439586 -351.91192) (xy 425.418879 -351.893705) (xy 425.382409 -351.852337)
			(xy 425.352276 -351.806147) (xy 425.32911 -351.7561) (xy 425.313393 -351.703239) (xy 425.305452 -351.648664)
			(xy 425.304966 -351.62109) (xy 425.305452 -351.593839) (xy 425.313208 -351.539891) (xy 425.328563 -351.487596)
			(xy 425.351205 -351.438019) (xy 425.380671 -351.392169) (xy 425.416362 -351.350978) (xy 425.457553 -351.315287)
			(xy 425.503403 -351.285821) (xy 425.55298 -351.263179) (xy 425.605275 -351.247824) (xy 425.659223 -351.240068)
			(xy 425.713725 -351.240068) (xy 425.767673 -351.247824) (xy 425.819968 -351.263179) (xy 425.869545 -351.285821)
			(xy 425.915395 -351.315287) (xy 425.956586 -351.350978) (xy 425.992277 -351.392169) (xy 426.021743 -351.438019)
			(xy 426.044385 -351.487596) (xy 426.05974 -351.539891) (xy 426.067496 -351.593839) (xy 426.067982 -351.62109)
			(xy 426.067516 -351.648665) (xy 426.059564 -351.703238) (xy 426.04384 -351.756098) (xy 426.02067 -351.806144)
			(xy 425.990537 -351.852333) (xy 425.954069 -351.893704) (xy 425.933362 -351.91192) (xy 425.927012 -351.917254)
			(xy 425.91863 -351.93097) (xy 425.916598 -351.939098) (xy 425.915328 -351.950782) (xy 425.915328 -352.027998)
			(xy 425.916598 -352.039682) (xy 425.91863 -352.04781) (xy 425.927012 -352.061526) (xy 425.933362 -352.06686)
			(xy 425.954049 -352.085097) (xy 425.990523 -352.126459) (xy 426.020659 -352.172644) (xy 426.043829 -352.222687)
			(xy 426.05955 -352.275545) (xy 426.067495 -352.330117) (xy 426.067982 -352.35769) (xy 426.067441 -352.38698)
			(xy 426.058494 -352.444873) (xy 426.040809 -352.50072) (xy 426.0148 -352.553209) (xy 425.981078 -352.60111)
			(xy 425.940436 -352.643298) (xy 425.893825 -352.678782) (xy 425.868338 -352.693224) (xy 425.852336 -352.70186)
			(xy 425.839128 -352.731832) (xy 425.84012 -352.736725) (xy 425.840374 -352.746706) (xy 425.839636 -352.751644)
			(xy 425.832593 -352.795078) (xy 427.90618 -352.795078) (xy 427.906662 -352.767167) (xy 427.914799 -352.711941)
			(xy 427.930898 -352.65849) (xy 427.954613 -352.607955) (xy 427.985438 -352.561416) (xy 428.003716 -352.540316)
			(xy 428.009608 -352.533135) (xy 428.016262 -352.515813) (xy 428.01667 -352.506534) (xy 428.01667 -352.438208)
			(xy 428.016227 -352.428936) (xy 428.009584 -352.411618) (xy 428.003716 -352.404426) (xy 427.985431 -352.383332)
			(xy 427.954604 -352.336792) (xy 427.93089 -352.286256) (xy 427.914795 -352.232804) (xy 427.906664 -352.177576)
			(xy 427.90618 -352.149664) (xy 427.906666 -352.122413) (xy 427.914422 -352.068465) (xy 427.929777 -352.01617)
			(xy 427.952419 -351.966593) (xy 427.981885 -351.920743) (xy 428.017576 -351.879552) (xy 428.058767 -351.843861)
			(xy 428.104617 -351.814395) (xy 428.154194 -351.791753) (xy 428.206489 -351.776398) (xy 428.260437 -351.768642)
			(xy 428.314939 -351.768642) (xy 428.368887 -351.776398) (xy 428.421182 -351.791753) (xy 428.470759 -351.814395)
			(xy 428.516609 -351.843861) (xy 428.5578 -351.879552) (xy 428.593491 -351.920743) (xy 428.622957 -351.966593)
			(xy 428.645599 -352.01617) (xy 428.660954 -352.068465) (xy 428.66871 -352.122413) (xy 428.669196 -352.149664)
			(xy 428.66872 -352.177575) (xy 428.660578 -352.232801) (xy 428.644477 -352.286251) (xy 428.620762 -352.336785)
			(xy 428.589937 -352.383325) (xy 428.57166 -352.404426) (xy 428.565747 -352.411592) (xy 428.559107 -352.428926)
			(xy 428.558706 -352.438208) (xy 428.558706 -352.506534) (xy 428.559182 -352.515802) (xy 428.565802 -352.53312)
			(xy 428.57166 -352.540316) (xy 428.589929 -352.561423) (xy 428.620756 -352.60796) (xy 428.644472 -352.658493)
			(xy 428.660571 -352.711942) (xy 428.668708 -352.767167) (xy 428.669196 -352.795078) (xy 428.66871 -352.822329)
			(xy 428.660954 -352.876277) (xy 428.645599 -352.928572) (xy 428.622957 -352.978149) (xy 428.593491 -353.023999)
			(xy 428.5578 -353.06519) (xy 428.516609 -353.100881) (xy 428.473477 -353.1286) (xy 432.288439 -353.1286)
			(xy 432.292607 -353.072986) (xy 432.305016 -353.018615) (xy 432.32539 -352.9667) (xy 432.353273 -352.918401)
			(xy 432.388044 -352.874798) (xy 432.428924 -352.836863) (xy 432.475001 -352.805444) (xy 432.525246 -352.781244)
			(xy 432.578537 -352.764802) (xy 432.633683 -352.756485) (xy 432.661568 -352.755962) (xy 432.688763 -352.756464)
			(xy 432.742577 -352.764369) (xy 432.794673 -352.780001) (xy 432.843949 -352.803029) (xy 432.88936 -352.832966)
			(xy 432.90998 -352.850704) (xy 432.917854 -352.854006) (xy 432.932332 -352.8568) (xy 432.942238 -352.857816)
			(xy 433.013358 -352.857816) (xy 433.022502 -352.854006) (xy 433.026213 -352.852411) (xy 433.033101 -352.848193)
			(xy 433.036218 -352.845624) (xy 433.056878 -352.828529) (xy 433.102179 -352.799837) (xy 433.151123 -352.777929)
			(xy 433.2027 -352.763258) (xy 433.255847 -352.756127) (xy 433.309467 -352.756682) (xy 433.362455 -352.764913)
			(xy 433.413717 -352.780649) (xy 433.462197 -352.803565) (xy 433.506894 -352.83319) (xy 433.5272 -352.850704)
			(xy 433.535074 -352.854006) (xy 433.549552 -352.8568) (xy 433.559458 -352.857816) (xy 433.620418 -352.857816)
			(xy 433.626139 -352.857635) (xy 433.637293 -352.855076) (xy 433.642516 -352.852736) (xy 433.64277 -352.852736)
			(xy 433.653438 -352.845624) (xy 433.66733 -352.834037) (xy 433.696974 -352.813302) (xy 433.71262 -352.804222)
			(xy 433.722524 -352.798041) (xy 433.735765 -352.778847) (xy 433.73802 -352.767392) (xy 433.751482 -352.67646)
			(xy 433.747926 -352.66503) (xy 433.746032 -352.659693) (xy 433.740268 -352.649949) (xy 433.736496 -352.645726)
			(xy 433.736242 -352.645472) (xy 433.716694 -352.624108) (xy 433.683659 -352.576549) (xy 433.658194 -352.524543)
			(xy 433.640886 -352.469284) (xy 433.632131 -352.412043) (xy 433.631594 -352.38309) (xy 433.632124 -352.355518)
			(xy 433.640063 -352.300948) (xy 433.655776 -352.248089) (xy 433.678934 -352.198043) (xy 433.709055 -352.151852)
			(xy 433.745512 -352.110478) (xy 433.766214 -352.09226) (xy 433.772564 -352.086926) (xy 433.780946 -352.07321)
			(xy 433.782978 -352.065082) (xy 433.784248 -352.053398) (xy 433.784248 -351.976182) (xy 433.782978 -351.964498)
			(xy 433.780946 -351.95637) (xy 433.772564 -351.942654) (xy 433.766214 -351.93732) (xy 433.745512 -351.919099)
			(xy 433.709041 -351.877732) (xy 433.678907 -351.831545) (xy 433.655739 -351.781499) (xy 433.640021 -351.728638)
			(xy 433.63208 -351.674064) (xy 433.631594 -351.64649) (xy 433.63208 -351.619239) (xy 433.639836 -351.565291)
			(xy 433.655191 -351.512996) (xy 433.677833 -351.463419) (xy 433.707299 -351.417569) (xy 433.74299 -351.376378)
			(xy 433.784181 -351.340687) (xy 433.830031 -351.311221) (xy 433.879608 -351.288579) (xy 433.931903 -351.273224)
			(xy 433.985851 -351.265468) (xy 434.040353 -351.265468) (xy 434.094301 -351.273224) (xy 434.146596 -351.288579)
			(xy 434.196173 -351.311221) (xy 434.242023 -351.340687) (xy 434.283214 -351.376378) (xy 434.318905 -351.417569)
			(xy 434.348371 -351.463419) (xy 434.371013 -351.512996) (xy 434.386368 -351.565291) (xy 434.394124 -351.619239)
			(xy 434.39461 -351.64649) (xy 434.394134 -351.674064) (xy 434.386183 -351.728636) (xy 434.37046 -351.781496)
			(xy 434.347292 -351.831542) (xy 434.317161 -351.877732) (xy 434.280696 -351.919104) (xy 434.25999 -351.93732)
			(xy 434.25364 -351.942654) (xy 434.245258 -351.95637) (xy 434.243226 -351.964498) (xy 434.241956 -351.976182)
			(xy 434.241956 -352.053398) (xy 434.243226 -352.065082) (xy 434.245258 -352.07321) (xy 434.25364 -352.086926)
			(xy 434.25999 -352.09226) (xy 434.280683 -352.110491) (xy 434.317155 -352.151855) (xy 434.34729 -352.198041)
			(xy 434.370459 -352.248085) (xy 434.386179 -352.300944) (xy 434.394123 -352.355516) (xy 434.39461 -352.38309)
			(xy 434.394106 -352.412382) (xy 434.385157 -352.470278) (xy 434.367468 -352.526128) (xy 434.341454 -352.578619)
			(xy 434.307726 -352.626519) (xy 434.267075 -352.668705) (xy 434.220457 -352.704184) (xy 434.194966 -352.718624)
			(xy 434.178964 -352.72726) (xy 434.165756 -352.757232) (xy 434.166748 -352.762125) (xy 434.167001 -352.772106)
			(xy 434.166264 -352.777044) (xy 434.15712 -352.833432) (xy 434.155849 -352.8449) (xy 434.16244 -352.866984)
			(xy 434.16982 -352.87585) (xy 434.18828 -352.896625) (xy 434.219491 -352.942607) (xy 434.243527 -352.992715)
			(xy 434.259854 -353.045836) (xy 434.268111 -353.100793) (xy 434.268626 -353.12858) (xy 434.268147 -353.155197)
			(xy 434.260574 -353.207889) (xy 434.245579 -353.258968) (xy 434.223467 -353.307392) (xy 434.194688 -353.352176)
			(xy 434.159829 -353.392409) (xy 434.119599 -353.427271) (xy 434.074817 -353.456053) (xy 434.026394 -353.478169)
			(xy 433.975317 -353.493168) (xy 433.922625 -353.500745) (xy 433.896008 -353.501198) (xy 433.868813 -353.500695)
			(xy 433.815 -353.492789) (xy 433.762904 -353.477156) (xy 433.713629 -353.454128) (xy 433.668216 -353.424194)
			(xy 433.647596 -353.406456) (xy 433.639722 -353.403154) (xy 433.625244 -353.40036) (xy 433.615338 -353.399344)
			(xy 433.544218 -353.399344) (xy 433.535074 -353.403154) (xy 433.531372 -353.404768) (xy 433.524479 -353.408973)
			(xy 433.521358 -353.411536) (xy 433.500718 -353.428657) (xy 433.455414 -353.457351) (xy 433.406467 -353.47926)
			(xy 433.354887 -353.49393) (xy 433.301736 -353.50106) (xy 433.248113 -353.500502) (xy 433.195123 -353.492268)
			(xy 433.143858 -353.476527) (xy 433.095378 -353.453605) (xy 433.050681 -353.423973) (xy 433.030376 -353.406456)
			(xy 433.022502 -353.403154) (xy 433.008024 -353.40036) (xy 432.998118 -353.399344) (xy 432.926998 -353.399344)
			(xy 432.917854 -353.403154) (xy 432.91415 -353.404764) (xy 432.907258 -353.408972) (xy 432.904138 -353.411536)
			(xy 432.883751 -353.428346) (xy 432.839168 -353.456708) (xy 432.791029 -353.478494) (xy 432.740297 -353.493268)
			(xy 432.687988 -353.500734) (xy 432.661568 -353.501198) (xy 432.633683 -353.500715) (xy 432.578537 -353.492398)
			(xy 432.525246 -353.475956) (xy 432.475001 -353.451756) (xy 432.428924 -353.420337) (xy 432.388044 -353.382402)
			(xy 432.353273 -353.338799) (xy 432.32539 -353.2905) (xy 432.305016 -353.238585) (xy 432.292607 -353.184214)
			(xy 432.288439 -353.1286) (xy 428.473477 -353.1286) (xy 428.470759 -353.130347) (xy 428.421182 -353.152989)
			(xy 428.368887 -353.168344) (xy 428.314939 -353.1761) (xy 428.260437 -353.1761) (xy 428.206489 -353.168344)
			(xy 428.154194 -353.152989) (xy 428.104617 -353.130347) (xy 428.058767 -353.100881) (xy 428.017576 -353.06519)
			(xy 427.981885 -353.023999) (xy 427.952419 -352.978149) (xy 427.929777 -352.928572) (xy 427.914422 -352.876277)
			(xy 427.906666 -352.822329) (xy 427.90618 -352.795078) (xy 425.832593 -352.795078) (xy 425.830492 -352.808032)
			(xy 425.829203 -352.8195) (xy 425.835803 -352.841587) (xy 425.843192 -352.85045) (xy 425.861647 -352.871229)
			(xy 425.89286 -352.91721) (xy 425.916897 -352.967316) (xy 425.933226 -353.020437) (xy 425.941483 -353.075393)
			(xy 425.941998 -353.10318) (xy 425.941547 -353.129798) (xy 425.933973 -353.182493) (xy 425.918976 -353.233574)
			(xy 425.896862 -353.282) (xy 425.868081 -353.326785) (xy 425.833219 -353.367019) (xy 425.792985 -353.401881)
			(xy 425.7482 -353.430662) (xy 425.699774 -353.452776) (xy 425.648693 -353.467773) (xy 425.595998 -353.475347)
			(xy 425.56938 -353.475798) (xy 425.542184 -353.475312) (xy 425.488371 -353.467401) (xy 425.436275 -353.451765)
			(xy 425.386999 -353.428733) (xy 425.341588 -353.398795) (xy 425.320968 -353.381056) (xy 425.313094 -353.377754)
			(xy 425.298616 -353.37496) (xy 425.28871 -353.373944) (xy 425.21759 -353.373944) (xy 425.208446 -353.377754)
			(xy 425.204742 -353.379362) (xy 425.19785 -353.383572) (xy 425.19473 -353.386136) (xy 425.174033 -353.403186)
			(xy 425.12874 -353.431883) (xy 425.079802 -353.453796) (xy 425.02823 -353.468472) (xy 424.975088 -353.475609)
			(xy 424.921471 -353.475059) (xy 424.868486 -353.466833) (xy 424.817226 -353.451102) (xy 424.768748 -353.428189)
			(xy 424.724053 -353.398568) (xy 424.703748 -353.381056) (xy 424.695874 -353.377754) (xy 424.681396 -353.37496)
			(xy 424.67149 -353.373944) (xy 424.60037 -353.373944) (xy 424.591226 -353.377754) (xy 424.58752 -353.379359)
			(xy 424.580629 -353.38357) (xy 424.57751 -353.386136) (xy 424.557133 -353.40296) (xy 424.512547 -353.431319)
			(xy 424.464405 -353.453102) (xy 424.413671 -353.467873) (xy 424.36136 -353.475336) (xy 424.33494 -353.475798)
			(xy 424.30705 -353.475346) (xy 424.251892 -353.467038) (xy 424.198588 -353.450601) (xy 424.14833 -353.426402)
			(xy 424.10224 -353.394983) (xy 424.061348 -353.357045) (xy 424.026567 -353.313436) (xy 423.998676 -353.26513)
			(xy 423.978295 -353.213206) (xy 423.965882 -353.158824) (xy 423.961713 -353.1032) (xy 420.146849 -353.1032)
			(xy 420.144131 -353.104947) (xy 420.094554 -353.127589) (xy 420.042259 -353.142944) (xy 419.988311 -353.1507)
			(xy 419.933809 -353.1507) (xy 419.879861 -353.142944) (xy 419.827566 -353.127589) (xy 419.777989 -353.104947)
			(xy 419.732139 -353.075481) (xy 419.690948 -353.03979) (xy 419.655257 -352.998599) (xy 419.625791 -352.952749)
			(xy 419.603149 -352.903172) (xy 419.587794 -352.850877) (xy 419.580038 -352.796929) (xy 419.579552 -352.769678)
			(xy 418.15766 -352.769678) (xy 418.15766 -353.648518) (xy 418.157146 -353.676465) (xy 418.148411 -353.731672)
			(xy 418.131144 -353.784831) (xy 418.10577 -353.834633) (xy 418.072915 -353.87985) (xy 418.05352 -353.899978)
			(xy 417.952174 -354.001324) (xy 420.537384 -354.001324) (xy 420.541455 -353.945702) (xy 420.553581 -353.891265)
			(xy 420.573504 -353.839174) (xy 420.6008 -353.790539) (xy 420.634886 -353.746396) (xy 420.675035 -353.707687)
			(xy 420.720393 -353.675236) (xy 420.769993 -353.649735) (xy 420.822777 -353.631728) (xy 420.87762 -353.621598)
			(xy 420.933354 -353.619561) (xy 420.988791 -353.625661) (xy 421.042748 -353.639767) (xy 421.094077 -353.661579)
			(xy 421.141683 -353.690633) (xy 421.184551 -353.726308) (xy 421.221768 -353.767845) (xy 421.252541 -353.814358)
			(xy 421.276213 -353.864855) (xy 421.292281 -353.918262) (xy 421.300401 -353.973438) (xy 421.30091 -354.001324)
			(xy 421.300401 -354.02921) (xy 421.292281 -354.084386) (xy 421.276213 -354.137793) (xy 421.252541 -354.18829)
			(xy 421.221768 -354.234803) (xy 421.184551 -354.27634) (xy 421.141683 -354.312015) (xy 421.094077 -354.341069)
			(xy 421.042748 -354.362881) (xy 420.988791 -354.376987) (xy 420.933354 -354.383087) (xy 420.87762 -354.38105)
			(xy 420.822777 -354.37092) (xy 420.769993 -354.352913) (xy 420.720393 -354.327412) (xy 420.675035 -354.294961)
			(xy 420.634886 -354.256252) (xy 420.6008 -354.212109) (xy 420.573504 -354.163474) (xy 420.553581 -354.111383)
			(xy 420.541455 -354.056946) (xy 420.537384 -354.001324) (xy 417.952174 -354.001324) (xy 417.185094 -354.768404)
			(xy 417.18307 -354.772722) (xy 418.51402 -354.772722) (xy 418.518091 -354.7171) (xy 418.530217 -354.662663)
			(xy 418.55014 -354.610572) (xy 418.577436 -354.561937) (xy 418.611522 -354.517794) (xy 418.651671 -354.479085)
			(xy 418.697029 -354.446634) (xy 418.746629 -354.421133) (xy 418.799413 -354.403126) (xy 418.854256 -354.392996)
			(xy 418.90999 -354.390959) (xy 418.965427 -354.397059) (xy 419.019384 -354.411165) (xy 419.070713 -354.432977)
			(xy 419.118319 -354.462031) (xy 419.161187 -354.497706) (xy 419.198404 -354.539243) (xy 419.229177 -354.585756)
			(xy 419.252849 -354.636253) (xy 419.268917 -354.68966) (xy 419.277037 -354.744836) (xy 419.277546 -354.772722)
			(xy 419.277037 -354.800608) (xy 419.268917 -354.855784) (xy 419.256615 -354.896674) (xy 419.958264 -354.896674)
			(xy 419.962335 -354.841052) (xy 419.974461 -354.786615) (xy 419.994384 -354.734524) (xy 420.02168 -354.685889)
			(xy 420.055766 -354.641746) (xy 420.095915 -354.603037) (xy 420.141273 -354.570586) (xy 420.190873 -354.545085)
			(xy 420.243657 -354.527078) (xy 420.2985 -354.516948) (xy 420.354234 -354.514911) (xy 420.409671 -354.521011)
			(xy 420.463628 -354.535117) (xy 420.514957 -354.556929) (xy 420.562563 -354.585983) (xy 420.605431 -354.621658)
			(xy 420.642648 -354.663195) (xy 420.673421 -354.709708) (xy 420.697093 -354.760205) (xy 420.713161 -354.813612)
			(xy 420.721281 -354.868788) (xy 420.72179 -354.896674) (xy 420.721281 -354.92456) (xy 420.713161 -354.979736)
			(xy 420.697093 -355.033143) (xy 420.673421 -355.08364) (xy 420.642648 -355.130153) (xy 420.605431 -355.17169)
			(xy 420.562563 -355.207365) (xy 420.514957 -355.236419) (xy 420.463628 -355.258231) (xy 420.409671 -355.272337)
			(xy 420.354234 -355.278437) (xy 420.2985 -355.2764) (xy 420.243657 -355.26627) (xy 420.190873 -355.248263)
			(xy 420.141273 -355.222762) (xy 420.095915 -355.190311) (xy 420.055766 -355.151602) (xy 420.02168 -355.107459)
			(xy 419.994384 -355.058824) (xy 419.974461 -355.006733) (xy 419.962335 -354.952296) (xy 419.958264 -354.896674)
			(xy 419.256615 -354.896674) (xy 419.252849 -354.909191) (xy 419.229177 -354.959688) (xy 419.198404 -355.006201)
			(xy 419.161187 -355.047738) (xy 419.118319 -355.083413) (xy 419.070713 -355.112467) (xy 419.019384 -355.134279)
			(xy 418.965427 -355.148385) (xy 418.90999 -355.154485) (xy 418.854256 -355.152448) (xy 418.799413 -355.142318)
			(xy 418.746629 -355.124311) (xy 418.697029 -355.09881) (xy 418.651671 -355.066359) (xy 418.611522 -355.02765)
			(xy 418.577436 -354.983507) (xy 418.55014 -354.934872) (xy 418.530217 -354.882781) (xy 418.518091 -354.828344)
			(xy 418.51402 -354.772722) (xy 417.18307 -354.772722) (xy 417.181284 -354.776532) (xy 417.169653 -354.800191)
			(xy 417.140842 -354.84434) (xy 417.106227 -354.884103) (xy 417.066468 -354.918721) (xy 417.022321 -354.947536)
			(xy 416.998658 -354.959158) (xy 416.99053 -354.962968) (xy 416.381184 -355.572314) (xy 421.2971 -355.572314)
			(xy 421.297577 -355.544877) (xy 421.305482 -355.490574) (xy 421.321073 -355.43796) (xy 421.344029 -355.388118)
			(xy 421.37388 -355.342071) (xy 421.391588 -355.321108) (xy 421.397938 -355.313996) (xy 421.404288 -355.296978)
			(xy 421.404288 -355.210618) (xy 421.397938 -355.1936) (xy 421.391588 -355.186488) (xy 421.373851 -355.165545)
			(xy 421.343969 -355.119511) (xy 421.321004 -355.069665) (xy 421.30543 -355.017039) (xy 421.29757 -354.962723)
			(xy 421.2971 -354.935282) (xy 421.297586 -354.908031) (xy 421.305342 -354.854083) (xy 421.320697 -354.801788)
			(xy 421.343339 -354.752211) (xy 421.372805 -354.706361) (xy 421.408496 -354.66517) (xy 421.449687 -354.629479)
			(xy 421.495537 -354.600013) (xy 421.545114 -354.577371) (xy 421.597409 -354.562016) (xy 421.651357 -354.55426)
			(xy 421.705859 -354.55426) (xy 421.759807 -354.562016) (xy 421.812102 -354.577371) (xy 421.861679 -354.600013)
			(xy 421.907529 -354.629479) (xy 421.94872 -354.66517) (xy 421.984411 -354.706361) (xy 422.013877 -354.752211)
			(xy 422.036519 -354.801788) (xy 422.051874 -354.854083) (xy 422.05963 -354.908031) (xy 422.060116 -354.935282)
			(xy 422.059632 -354.962719) (xy 422.051729 -355.017021) (xy 422.036139 -355.069635) (xy 422.033413 -355.075553)
			(xy 422.301867 -355.075553) (xy 422.301867 -355.021047) (xy 422.309625 -354.967096) (xy 422.324981 -354.914797)
			(xy 422.347625 -354.865217) (xy 422.377094 -354.819364) (xy 422.412789 -354.778172) (xy 422.453984 -354.74248)
			(xy 422.499838 -354.713014) (xy 422.54942 -354.690373) (xy 422.601719 -354.67502) (xy 422.655671 -354.667266)
			(xy 422.682924 -354.666804) (xy 422.683178 -354.666804) (xy 422.708381 -354.667218) (xy 422.758348 -354.673854)
			(xy 422.807003 -354.687027) (xy 422.853493 -354.706505) (xy 422.875456 -354.718874) (xy 422.885362 -354.724716)
			(xy 422.907206 -354.726748) (xy 422.991026 -354.69703) (xy 422.999662 -354.692966) (xy 423.009568 -354.6856)
			(xy 423.018204 -354.677218) (xy 423.022014 -354.666804) (xy 423.032674 -354.640051) (xy 423.060986 -354.5899)
			(xy 423.096519 -354.54458) (xy 423.138466 -354.50512) (xy 423.185872 -354.47242) (xy 423.237658 -354.447224)
			(xy 423.292645 -354.430105) (xy 423.349581 -354.421453) (xy 423.378376 -354.420932) (xy 423.40563 -354.421378)
			(xy 423.459584 -354.429133) (xy 423.511884 -354.444488) (xy 423.561467 -354.46713) (xy 423.607322 -354.496599)
			(xy 423.648516 -354.532295) (xy 423.68421 -354.573491) (xy 423.713678 -354.619347) (xy 423.736318 -354.668931)
			(xy 423.74904 -354.71227) (xy 425.889928 -354.71227) (xy 425.890432 -354.684697) (xy 425.898375 -354.630125)
			(xy 425.914092 -354.577266) (xy 425.937255 -354.527219) (xy 425.967381 -354.481029) (xy 426.003843 -354.439656)
			(xy 426.024548 -354.42144) (xy 426.032772 -354.413673) (xy 426.042139 -354.393118) (xy 426.042582 -354.381816)
			(xy 426.042582 -354.306124) (xy 426.042178 -354.294813) (xy 426.032806 -354.274242) (xy 426.024548 -354.2665)
			(xy 426.003843 -354.248282) (xy 425.96737 -354.206916) (xy 425.937236 -354.160728) (xy 425.914069 -354.110681)
			(xy 425.898352 -354.057819) (xy 425.890413 -354.003245) (xy 425.889928 -353.97567) (xy 425.890327 -353.948415)
			(xy 425.898089 -353.89446) (xy 425.913451 -353.842158) (xy 425.936099 -353.792576) (xy 425.965574 -353.746721)
			(xy 426.001274 -353.705528) (xy 426.042474 -353.669834) (xy 426.088334 -353.640368) (xy 426.13792 -353.617728)
			(xy 426.190224 -353.602375) (xy 426.244181 -353.594622) (xy 426.271436 -353.594162) (xy 426.271944 -353.594162)
			(xy 426.305726 -353.595686) (xy 426.315886 -353.596702) (xy 426.33519 -353.590606) (xy 426.397928 -353.538028)
			(xy 426.401593 -353.534755) (xy 426.407727 -353.52708) (xy 426.41012 -353.522788) (xy 426.4152 -353.513136)
			(xy 426.416216 -353.502976) (xy 426.419155 -353.474826) (xy 426.432351 -353.419787) (xy 426.453537 -353.367303)
			(xy 426.482247 -353.318526) (xy 426.517851 -353.274529) (xy 426.559567 -353.236277) (xy 426.606478 -353.20461)
			(xy 426.657554 -353.180225) (xy 426.711673 -353.163657) (xy 426.767647 -353.155269) (xy 426.795946 -353.154742)
			(xy 426.7962 -353.154742) (xy 426.816552 -353.155003) (xy 426.857026 -353.159327) (xy 426.876972 -353.163378)
			(xy 426.887386 -353.161346) (xy 426.891887 -353.16032) (xy 426.90045 -353.156871) (xy 426.904404 -353.154488)
			(xy 426.963078 -353.11715) (xy 426.967185 -353.114419) (xy 426.974349 -353.107639) (xy 426.977302 -353.103688)
			(xy 426.982636 -353.096068) (xy 426.985176 -353.08667) (xy 426.985176 -353.086416) (xy 426.992603 -353.059392)
			(xy 427.014254 -353.007699) (xy 427.043232 -352.959729) (xy 427.078914 -352.916512) (xy 427.120533 -352.878978)
			(xy 427.167193 -352.847934) (xy 427.217891 -352.824047) (xy 427.271537 -352.807832) (xy 427.326978 -352.799636)
			(xy 427.355 -352.799142) (xy 427.382255 -352.799555) (xy 427.43621 -352.807314) (xy 427.488512 -352.822672)
			(xy 427.538096 -352.845318) (xy 427.583951 -352.874791) (xy 427.625145 -352.91049) (xy 427.660839 -352.951689)
			(xy 427.690306 -352.997548) (xy 427.712945 -353.047135) (xy 427.728297 -353.099438) (xy 427.736048 -353.153395)
			(xy 427.736508 -353.18065) (xy 427.736005 -353.208223) (xy 427.72806 -353.262794) (xy 427.712342 -353.315653)
			(xy 427.689179 -353.365699) (xy 427.659053 -353.41189) (xy 427.622592 -353.453263) (xy 427.601888 -353.47148)
			(xy 427.593661 -353.479244) (xy 427.584294 -353.499801) (xy 427.583854 -353.511104) (xy 427.583854 -353.586796)
			(xy 427.584235 -353.59811) (xy 427.593622 -353.618682) (xy 427.601888 -353.62642) (xy 427.622644 -353.644581)
			(xy 427.659109 -353.685959) (xy 427.689236 -353.732156) (xy 427.712397 -353.78221) (xy 427.728109 -353.835077)
			(xy 427.736046 -353.889656) (xy 427.736041 -353.944809) (xy 427.728095 -353.999386) (xy 427.719965 -354.026724)
			(xy 428.864012 -354.026724) (xy 428.868083 -353.971102) (xy 428.880209 -353.916665) (xy 428.900132 -353.864574)
			(xy 428.927428 -353.815939) (xy 428.961514 -353.771796) (xy 429.001663 -353.733087) (xy 429.047021 -353.700636)
			(xy 429.096621 -353.675135) (xy 429.149405 -353.657128) (xy 429.204248 -353.646998) (xy 429.259982 -353.644961)
			(xy 429.315419 -353.651061) (xy 429.369376 -353.665167) (xy 429.420705 -353.686979) (xy 429.468311 -353.716033)
			(xy 429.511179 -353.751708) (xy 429.548396 -353.793245) (xy 429.579169 -353.839758) (xy 429.602841 -353.890255)
			(xy 429.618909 -353.943662) (xy 429.627029 -353.998838) (xy 429.627538 -354.026724) (xy 429.627029 -354.05461)
			(xy 429.618909 -354.109786) (xy 429.602841 -354.163193) (xy 429.579169 -354.21369) (xy 429.548396 -354.260203)
			(xy 429.511179 -354.30174) (xy 429.468311 -354.337415) (xy 429.420705 -354.366469) (xy 429.369376 -354.388281)
			(xy 429.315419 -354.402387) (xy 429.259982 -354.408487) (xy 429.204248 -354.40645) (xy 429.149405 -354.39632)
			(xy 429.096621 -354.378313) (xy 429.047021 -354.352812) (xy 429.001663 -354.320361) (xy 428.961514 -354.281652)
			(xy 428.927428 -354.237509) (xy 428.900132 -354.188874) (xy 428.880209 -354.136783) (xy 428.868083 -354.082346)
			(xy 428.864012 -354.026724) (xy 427.719965 -354.026724) (xy 427.712374 -354.052251) (xy 427.689204 -354.102301)
			(xy 427.65907 -354.148493) (xy 427.622598 -354.189865) (xy 427.601888 -354.20808) (xy 427.593661 -354.215844)
			(xy 427.584294 -354.236401) (xy 427.583854 -354.247704) (xy 427.583854 -354.323396) (xy 427.584235 -354.33471)
			(xy 427.593622 -354.355282) (xy 427.601888 -354.36302) (xy 427.62261 -354.38122) (xy 427.65908 -354.422591)
			(xy 427.689211 -354.468783) (xy 427.712375 -354.518833) (xy 427.728089 -354.571698) (xy 427.736025 -354.626275)
			(xy 427.736508 -354.65385) (xy 427.735998 -354.681102) (xy 427.728248 -354.735051) (xy 427.712898 -354.787348)
			(xy 427.690262 -354.836928) (xy 427.660799 -354.882781) (xy 427.626756 -354.922074) (xy 428.284892 -354.922074)
			(xy 428.288963 -354.866452) (xy 428.301089 -354.812015) (xy 428.321012 -354.759924) (xy 428.348308 -354.711289)
			(xy 428.382394 -354.667146) (xy 428.422543 -354.628437) (xy 428.467901 -354.595986) (xy 428.517501 -354.570485)
			(xy 428.570285 -354.552478) (xy 428.625128 -354.542348) (xy 428.680862 -354.540311) (xy 428.736299 -354.546411)
			(xy 428.790256 -354.560517) (xy 428.841585 -354.582329) (xy 428.889191 -354.611383) (xy 428.932059 -354.647058)
			(xy 428.969276 -354.688595) (xy 429.000049 -354.735108) (xy 429.023721 -354.785605) (xy 429.039789 -354.839012)
			(xy 429.047909 -354.894188) (xy 429.048418 -354.922074) (xy 429.047909 -354.94996) (xy 429.039789 -355.005136)
			(xy 429.023721 -355.058543) (xy 429.000049 -355.10904) (xy 428.969276 -355.155553) (xy 428.932059 -355.19709)
			(xy 428.889191 -355.232765) (xy 428.841585 -355.261819) (xy 428.790256 -355.283631) (xy 428.736299 -355.297737)
			(xy 428.680862 -355.303837) (xy 428.625128 -355.3018) (xy 428.570285 -355.29167) (xy 428.517501 -355.273663)
			(xy 428.467901 -355.248162) (xy 428.422543 -355.215711) (xy 428.382394 -355.177002) (xy 428.348308 -355.132859)
			(xy 428.321012 -355.084224) (xy 428.301089 -355.032133) (xy 428.288963 -354.977696) (xy 428.284892 -354.922074)
			(xy 427.626756 -354.922074) (xy 427.62511 -354.923974) (xy 427.583921 -354.959669) (xy 427.538072 -354.989138)
			(xy 427.488495 -355.011781) (xy 427.4362 -355.027137) (xy 427.382252 -355.034895) (xy 427.355 -355.035358)
			(xy 427.327151 -355.034916) (xy 427.272047 -355.02681) (xy 427.218706 -355.010783) (xy 427.168258 -354.987177)
			(xy 427.121776 -354.956491) (xy 427.080245 -354.919378) (xy 427.044547 -354.876625) (xy 427.01544 -354.829139)
			(xy 426.99354 -354.777928) (xy 426.985938 -354.751132) (xy 426.985938 -354.750878) (xy 426.983398 -354.741734)
			(xy 426.978318 -354.734368) (xy 426.975474 -354.730507) (xy 426.968569 -354.723854) (xy 426.964602 -354.72116)
			(xy 426.901102 -354.678996) (xy 426.883068 -354.674932) (xy 426.873924 -354.676202) (xy 426.86097 -354.677861)
			(xy 426.834913 -354.679643) (xy 426.821854 -354.679758) (xy 426.8216 -354.679758) (xy 426.807388 -354.679679)
			(xy 426.779037 -354.677642) (xy 426.764958 -354.675694) (xy 426.755052 -354.67417) (xy 426.735494 -354.67925)
			(xy 426.661326 -354.734876) (xy 426.650912 -354.752148) (xy 426.649642 -354.762562) (xy 426.645543 -354.789713)
			(xy 426.630569 -354.842542) (xy 426.608178 -354.892679) (xy 426.578831 -354.939088) (xy 426.543134 -354.980811)
			(xy 426.501826 -355.016988) (xy 426.455759 -355.046869) (xy 426.405885 -355.069839) (xy 426.353233 -355.085422)
			(xy 426.298891 -355.093298) (xy 426.271436 -355.093778) (xy 426.244183 -355.093311) (xy 426.19023 -355.085558)
			(xy 426.137931 -355.070205) (xy 426.088349 -355.047565) (xy 426.042494 -355.018098) (xy 426.0013 -354.982404)
			(xy 425.965606 -354.941211) (xy 425.936138 -354.895357) (xy 425.913497 -354.845775) (xy 425.898143 -354.793476)
			(xy 425.890389 -354.739523) (xy 425.889928 -354.71227) (xy 423.74904 -354.71227) (xy 423.751671 -354.721232)
			(xy 423.759423 -354.775186) (xy 423.759884 -354.80244) (xy 423.75919 -354.833918) (xy 423.748789 -354.896011)
			(xy 423.728326 -354.95555) (xy 423.71391 -354.983542) (xy 423.71391 -354.983796) (xy 423.713656 -354.984304)
			(xy 423.709473 -354.99316) (xy 423.707525 -355.012634) (xy 423.709846 -355.02215) (xy 423.729912 -355.090984)
			(xy 423.73143 -355.095726) (xy 423.736038 -355.10455) (xy 423.739056 -355.10851) (xy 423.745152 -355.11613)
			(xy 423.754042 -355.12121) (xy 423.759884 -355.124766) (xy 423.78433 -355.139452) (xy 423.828916 -355.175008)
			(xy 423.867705 -355.216813) (xy 423.899829 -355.263932) (xy 423.924572 -355.315312) (xy 423.94138 -355.369807)
			(xy 423.949878 -355.426198) (xy 423.950384 -355.454712) (xy 423.949898 -355.481963) (xy 423.942142 -355.535911)
			(xy 423.926787 -355.588206) (xy 423.922445 -355.597714) (xy 429.623728 -355.597714) (xy 429.624198 -355.570277)
			(xy 429.632104 -355.515973) (xy 429.647696 -355.463359) (xy 429.670654 -355.413516) (xy 429.700507 -355.367471)
			(xy 429.718216 -355.346508) (xy 429.724566 -355.339396) (xy 429.730916 -355.322378) (xy 429.730916 -355.236018)
			(xy 429.724566 -355.219) (xy 429.718216 -355.211888) (xy 429.700483 -355.190941) (xy 429.6706 -355.144909)
			(xy 429.647633 -355.095064) (xy 429.632059 -355.042439) (xy 429.624198 -354.988123) (xy 429.623728 -354.960682)
			(xy 429.624214 -354.933431) (xy 429.63197 -354.879483) (xy 429.647325 -354.827188) (xy 429.669967 -354.777611)
			(xy 429.699433 -354.731761) (xy 429.735124 -354.69057) (xy 429.776315 -354.654879) (xy 429.822165 -354.625413)
			(xy 429.871742 -354.602771) (xy 429.924037 -354.587416) (xy 429.977985 -354.57966) (xy 430.032487 -354.57966)
			(xy 430.086435 -354.587416) (xy 430.13873 -354.602771) (xy 430.188307 -354.625413) (xy 430.234157 -354.654879)
			(xy 430.275348 -354.69057) (xy 430.311039 -354.731761) (xy 430.340505 -354.777611) (xy 430.363147 -354.827188)
			(xy 430.378502 -354.879483) (xy 430.386258 -354.933431) (xy 430.386744 -354.960682) (xy 430.386278 -354.98812)
			(xy 430.378373 -355.042424) (xy 430.36278 -355.095038) (xy 430.360058 -355.100948) (xy 430.62859 -355.100948)
			(xy 430.62859 -355.046452) (xy 430.636345 -354.99251) (xy 430.651697 -354.940221) (xy 430.674334 -354.890648)
			(xy 430.703795 -354.844802) (xy 430.73948 -354.803614) (xy 430.780663 -354.767924) (xy 430.826506 -354.738457)
			(xy 430.876076 -354.715814) (xy 430.928363 -354.700455) (xy 430.982304 -354.692694) (xy 431.009552 -354.692204)
			(xy 431.009806 -354.692204) (xy 431.03501 -354.692606) (xy 431.084977 -354.699246) (xy 431.133632 -354.712421)
			(xy 431.180122 -354.731903) (xy 431.202084 -354.744274) (xy 431.21199 -354.750116) (xy 431.233834 -354.752148)
			(xy 431.317654 -354.72243) (xy 431.32629 -354.718366) (xy 431.336196 -354.711) (xy 431.344832 -354.702618)
			(xy 431.348642 -354.692204) (xy 431.359362 -354.665477) (xy 431.387667 -354.615329) (xy 431.423192 -354.570009)
			(xy 431.465131 -354.530549) (xy 431.512528 -354.497847) (xy 431.564304 -354.472645) (xy 431.619283 -354.455519)
			(xy 431.676212 -354.446858) (xy 431.705004 -354.446332) (xy 431.732259 -354.446752) (xy 431.786213 -354.45451)
			(xy 431.838514 -354.469869) (xy 431.888097 -354.492515) (xy 431.933952 -354.521987) (xy 431.975146 -354.557685)
			(xy 432.01084 -354.598883) (xy 432.040306 -354.644741) (xy 432.062947 -354.694327) (xy 432.075669 -354.73767)
			(xy 434.216556 -354.73767) (xy 434.21705 -354.710096) (xy 434.224994 -354.655524) (xy 434.240712 -354.602664)
			(xy 434.263877 -354.552617) (xy 434.294005 -354.506427) (xy 434.33047 -354.465056) (xy 434.351176 -354.44684)
			(xy 434.359389 -354.439062) (xy 434.368765 -354.418516) (xy 434.36921 -354.407216) (xy 434.36921 -354.331524)
			(xy 434.368797 -354.320214) (xy 434.35943 -354.299643) (xy 434.351176 -354.2919) (xy 434.330457 -354.273698)
			(xy 434.293988 -354.232326) (xy 434.263858 -354.186135) (xy 434.240693 -354.136085) (xy 434.224979 -354.083221)
			(xy 434.217041 -354.028645) (xy 434.216556 -354.00107) (xy 434.21705 -353.97382) (xy 434.224809 -353.919874)
			(xy 434.240167 -353.867582) (xy 434.262809 -353.818007) (xy 434.292275 -353.772158) (xy 434.327965 -353.730969)
			(xy 434.369153 -353.695278) (xy 434.415001 -353.665811) (xy 434.464576 -353.643169) (xy 434.516868 -353.627811)
			(xy 434.570814 -353.62005) (xy 434.598064 -353.619562) (xy 434.598572 -353.619562) (xy 434.632354 -353.621086)
			(xy 434.642514 -353.622102) (xy 434.661818 -353.616006) (xy 434.724556 -353.563428) (xy 434.728224 -353.560158)
			(xy 434.734356 -353.552481) (xy 434.736748 -353.548188) (xy 434.741828 -353.538536) (xy 434.742844 -353.528376)
			(xy 434.745854 -353.500235) (xy 434.759046 -353.445202) (xy 434.780227 -353.392723) (xy 434.80893 -353.34395)
			(xy 434.844526 -353.299955) (xy 434.886233 -353.261703) (xy 434.933135 -353.230035) (xy 434.984202 -353.205645)
			(xy 435.038312 -353.18907) (xy 435.094278 -353.180674) (xy 435.122574 -353.180142) (xy 435.122828 -353.180142)
			(xy 435.14318 -353.180398) (xy 435.183654 -353.184725) (xy 435.2036 -353.188778) (xy 435.214014 -353.186746)
			(xy 435.218517 -353.185727) (xy 435.227079 -353.182273) (xy 435.231032 -353.179888) (xy 435.289706 -353.14255)
			(xy 435.293817 -353.139823) (xy 435.300978 -353.13304) (xy 435.30393 -353.129088) (xy 435.309264 -353.121468)
			(xy 435.311804 -353.11207) (xy 435.311804 -353.111816) (xy 435.319206 -353.084784) (xy 435.340859 -353.03309)
			(xy 435.36984 -352.985118) (xy 435.405525 -352.941901) (xy 435.447146 -352.904367) (xy 435.49381 -352.873324)
			(xy 435.544511 -352.849439) (xy 435.598161 -352.833226) (xy 435.653605 -352.825034) (xy 435.681628 -352.824542)
			(xy 435.708884 -352.824929) (xy 435.76284 -352.832691) (xy 435.815143 -352.848053) (xy 435.864726 -352.870703)
			(xy 435.910582 -352.900178) (xy 435.951775 -352.93588) (xy 435.987469 -352.977081) (xy 436.016935 -353.022942)
			(xy 436.039574 -353.072531) (xy 436.054926 -353.124836) (xy 436.062677 -353.178794) (xy 436.063136 -353.20605)
			(xy 436.062658 -353.233624) (xy 436.054711 -353.288198) (xy 436.03899 -353.341058) (xy 436.015823 -353.391105)
			(xy 435.985691 -353.437295) (xy 435.949223 -353.478665) (xy 435.928516 -353.49688) (xy 435.920293 -353.504648)
			(xy 435.910923 -353.525202) (xy 435.910482 -353.536504) (xy 435.910482 -353.612196) (xy 435.910886 -353.623507)
			(xy 435.92026 -353.644077) (xy 435.928516 -353.65182) (xy 435.949271 -353.669981) (xy 435.985733 -353.711361)
			(xy 436.015858 -353.757558) (xy 436.039017 -353.807612) (xy 436.054728 -353.860479) (xy 436.062664 -353.915056)
			(xy 436.062659 -353.970208) (xy 436.054714 -354.024785) (xy 436.038994 -354.077649) (xy 436.015826 -354.127698)
			(xy 435.985694 -354.173891) (xy 435.949225 -354.215264) (xy 435.928516 -354.23348) (xy 435.920293 -354.241248)
			(xy 435.910923 -354.261802) (xy 435.910482 -354.273104) (xy 435.910482 -354.348796) (xy 435.910886 -354.360107)
			(xy 435.92026 -354.380677) (xy 435.928516 -354.38842) (xy 435.949243 -354.406614) (xy 435.985712 -354.447986)
			(xy 436.015841 -354.49418) (xy 436.039004 -354.544232) (xy 436.054717 -354.597097) (xy 436.062653 -354.651674)
			(xy 436.063136 -354.67925) (xy 436.062598 -354.7065) (xy 436.054849 -354.760447) (xy 436.039501 -354.812742)
			(xy 436.016866 -354.86232) (xy 435.987406 -354.908172) (xy 435.95172 -354.949365) (xy 435.910535 -354.985059)
			(xy 435.864689 -355.014528) (xy 435.815115 -355.037173) (xy 435.762823 -355.052532) (xy 435.708878 -355.060293)
			(xy 435.681628 -355.060758) (xy 435.65378 -355.060291) (xy 435.598677 -355.052189) (xy 435.545336 -355.036166)
			(xy 435.494889 -355.012563) (xy 435.448407 -354.981881) (xy 435.406875 -354.94477) (xy 435.371177 -354.90202)
			(xy 435.342068 -354.854536) (xy 435.320168 -354.803327) (xy 435.312566 -354.776532) (xy 435.312566 -354.776278)
			(xy 435.310026 -354.767134) (xy 435.304946 -354.759768) (xy 435.302097 -354.75591) (xy 435.295196 -354.749256)
			(xy 435.29123 -354.74656) (xy 435.22773 -354.704396) (xy 435.209696 -354.700332) (xy 435.200552 -354.701602)
			(xy 435.187599 -354.703269) (xy 435.161541 -354.705046) (xy 435.148482 -354.705158) (xy 435.148228 -354.705158)
			(xy 435.134016 -354.705076) (xy 435.105665 -354.703041) (xy 435.091586 -354.701094) (xy 435.08168 -354.69957)
			(xy 435.062122 -354.70465) (xy 434.987954 -354.760276) (xy 434.97754 -354.777548) (xy 434.97627 -354.787962)
			(xy 434.972144 -354.815109) (xy 434.957172 -354.867935) (xy 434.934782 -354.91807) (xy 434.905438 -354.964478)
			(xy 434.869745 -355.006201) (xy 434.82844 -355.042377) (xy 434.782376 -355.07226) (xy 434.732505 -355.095231)
			(xy 434.679857 -355.110817) (xy 434.625518 -355.118696) (xy 434.598064 -355.119178) (xy 434.57081 -355.118756)
			(xy 434.516859 -355.110993) (xy 434.464561 -355.095632) (xy 434.414982 -355.072985) (xy 434.36913 -355.043512)
			(xy 434.32794 -355.007814) (xy 434.292249 -354.966617) (xy 434.262784 -354.92076) (xy 434.240145 -354.871177)
			(xy 434.224793 -354.818876) (xy 434.21704 -354.764924) (xy 434.216556 -354.73767) (xy 432.075669 -354.73767)
			(xy 432.078299 -354.74663) (xy 432.086051 -354.800585) (xy 432.086512 -354.82784) (xy 432.085815 -354.859318)
			(xy 432.075415 -354.921411) (xy 432.054953 -354.98095) (xy 432.040538 -355.008942) (xy 432.040538 -355.009196)
			(xy 432.040284 -355.009704) (xy 432.036101 -355.018561) (xy 432.034152 -355.038034) (xy 432.036474 -355.04755)
			(xy 432.05654 -355.116384) (xy 432.058068 -355.121122) (xy 432.062669 -355.129948) (xy 432.065684 -355.13391)
			(xy 432.07178 -355.14153) (xy 432.08067 -355.14661) (xy 432.086512 -355.150166) (xy 432.11095 -355.164864)
			(xy 432.155531 -355.20042) (xy 432.194316 -355.242224) (xy 432.226437 -355.289341) (xy 432.251177 -355.34072)
			(xy 432.267983 -355.395212) (xy 432.27648 -355.4516) (xy 432.277012 -355.480112) (xy 432.276526 -355.507363)
			(xy 432.26877 -355.561311) (xy 432.253415 -355.613606) (xy 432.230773 -355.663183) (xy 432.201307 -355.709033)
			(xy 432.165616 -355.750224) (xy 432.124425 -355.785915) (xy 432.078575 -355.815381) (xy 432.028998 -355.838023)
			(xy 431.976703 -355.853378) (xy 431.922755 -355.861134) (xy 431.868253 -355.861134) (xy 431.814305 -355.853378)
			(xy 431.76201 -355.838023) (xy 431.712433 -355.815381) (xy 431.666583 -355.785915) (xy 431.625392 -355.750224)
			(xy 431.589701 -355.709033) (xy 431.560235 -355.663183) (xy 431.537593 -355.613606) (xy 431.522238 -355.561311)
			(xy 431.514482 -355.507363) (xy 431.513996 -355.480112) (xy 431.514673 -355.448633) (xy 431.525082 -355.38654)
			(xy 431.545551 -355.327001) (xy 431.55997 -355.29901) (xy 431.55997 -355.298756) (xy 431.560224 -355.298248)
			(xy 431.564379 -355.289381) (xy 431.566346 -355.269917) (xy 431.564034 -355.260402) (xy 431.543968 -355.191568)
			(xy 431.542421 -355.186742) (xy 431.537688 -355.177783) (xy 431.53457 -355.173788) (xy 431.52822 -355.165914)
			(xy 431.51933 -355.161088) (xy 431.511964 -355.157024) (xy 431.51171 -355.15677) (xy 431.501946 -355.151912)
			(xy 431.480239 -355.15006) (xy 431.4698 -355.153214) (xy 431.396902 -355.179122) (xy 431.38979 -355.18217)
			(xy 431.38668 -355.183898) (xy 431.380941 -355.188103) (xy 431.37836 -355.190552) (xy 431.369724 -355.198934)
			(xy 431.365914 -355.209348) (xy 431.355205 -355.236081) (xy 431.326902 -355.286231) (xy 431.291377 -355.331554)
			(xy 431.249437 -355.371015) (xy 431.202038 -355.403718) (xy 431.150258 -355.428918) (xy 431.095277 -355.446041)
			(xy 431.038345 -355.454697) (xy 431.009552 -355.45522) (xy 430.982304 -355.454706) (xy 430.928363 -355.446945)
			(xy 430.876076 -355.431586) (xy 430.826506 -355.408943) (xy 430.780663 -355.379476) (xy 430.73948 -355.343786)
			(xy 430.703795 -355.302598) (xy 430.674334 -355.256752) (xy 430.651697 -355.207179) (xy 430.636345 -355.15489)
			(xy 430.62859 -355.100948) (xy 430.360058 -355.100948) (xy 430.33982 -355.144881) (xy 430.309966 -355.190926)
			(xy 430.292256 -355.211888) (xy 430.285906 -355.219) (xy 430.279556 -355.236018) (xy 430.279556 -355.322378)
			(xy 430.285906 -355.339396) (xy 430.292256 -355.346508) (xy 430.309982 -355.36746) (xy 430.339867 -355.413491)
			(xy 430.362836 -355.463334) (xy 430.378412 -355.515958) (xy 430.386273 -355.570273) (xy 430.386744 -355.597714)
			(xy 430.386258 -355.624965) (xy 430.378502 -355.678913) (xy 430.363147 -355.731208) (xy 430.340505 -355.780785)
			(xy 430.311039 -355.826635) (xy 430.275348 -355.867826) (xy 430.234157 -355.903517) (xy 430.188307 -355.932983)
			(xy 430.13873 -355.955625) (xy 430.086435 -355.97098) (xy 430.032487 -355.978736) (xy 429.977985 -355.978736)
			(xy 429.924037 -355.97098) (xy 429.871742 -355.955625) (xy 429.822165 -355.932983) (xy 429.776315 -355.903517)
			(xy 429.735124 -355.867826) (xy 429.699433 -355.826635) (xy 429.669967 -355.780785) (xy 429.647325 -355.731208)
			(xy 429.63197 -355.678913) (xy 429.624214 -355.624965) (xy 429.623728 -355.597714) (xy 423.922445 -355.597714)
			(xy 423.904145 -355.637783) (xy 423.874679 -355.683633) (xy 423.838988 -355.724824) (xy 423.797797 -355.760515)
			(xy 423.751947 -355.789981) (xy 423.70237 -355.812623) (xy 423.650075 -355.827978) (xy 423.596127 -355.835734)
			(xy 423.541625 -355.835734) (xy 423.487677 -355.827978) (xy 423.435382 -355.812623) (xy 423.385805 -355.789981)
			(xy 423.339955 -355.760515) (xy 423.298764 -355.724824) (xy 423.263073 -355.683633) (xy 423.233607 -355.637783)
			(xy 423.210965 -355.588206) (xy 423.19561 -355.535911) (xy 423.187854 -355.481963) (xy 423.187368 -355.454712)
			(xy 423.188037 -355.423232) (xy 423.198447 -355.361139) (xy 423.218921 -355.3016) (xy 423.233342 -355.27361)
			(xy 423.233342 -355.273356) (xy 423.233596 -355.272848) (xy 423.237751 -355.263981) (xy 423.239716 -355.244517)
			(xy 423.237406 -355.235002) (xy 423.21734 -355.166168) (xy 423.215797 -355.16134) (xy 423.211061 -355.152383)
			(xy 423.207942 -355.148388) (xy 423.201592 -355.140514) (xy 423.192702 -355.135688) (xy 423.185336 -355.131624)
			(xy 423.185082 -355.13137) (xy 423.175325 -355.126495) (xy 423.153611 -355.124654) (xy 423.143172 -355.127814)
			(xy 423.070274 -355.153722) (xy 423.063162 -355.15677) (xy 423.060049 -355.158494) (xy 423.054312 -355.162702)
			(xy 423.051732 -355.165152) (xy 423.043096 -355.173534) (xy 423.039286 -355.183948) (xy 423.0286 -355.210691)
			(xy 423.000295 -355.260843) (xy 422.964766 -355.306165) (xy 422.922823 -355.345626) (xy 422.875421 -355.378328)
			(xy 422.823637 -355.403526) (xy 422.768653 -355.420646) (xy 422.711718 -355.429299) (xy 422.682924 -355.42982)
			(xy 422.655671 -355.429334) (xy 422.601719 -355.42158) (xy 422.54942 -355.406227) (xy 422.499838 -355.383586)
			(xy 422.453984 -355.35412) (xy 422.412789 -355.318428) (xy 422.377094 -355.277236) (xy 422.347625 -355.231383)
			(xy 422.324981 -355.181803) (xy 422.309625 -355.129504) (xy 422.301867 -355.075553) (xy 422.033413 -355.075553)
			(xy 422.013184 -355.119478) (xy 421.983335 -355.165524) (xy 421.965628 -355.186488) (xy 421.959278 -355.1936)
			(xy 421.952928 -355.210618) (xy 421.952928 -355.296978) (xy 421.959278 -355.313996) (xy 421.965628 -355.321108)
			(xy 421.98335 -355.342064) (xy 422.013237 -355.388093) (xy 422.036206 -355.437935) (xy 422.051783 -355.490559)
			(xy 422.059645 -355.544874) (xy 422.060116 -355.572314) (xy 422.05963 -355.599565) (xy 422.051874 -355.653513)
			(xy 422.036519 -355.705808) (xy 422.013877 -355.755385) (xy 421.984411 -355.801235) (xy 421.94872 -355.842426)
			(xy 421.907529 -355.878117) (xy 421.861679 -355.907583) (xy 421.812102 -355.930225) (xy 421.759807 -355.94558)
			(xy 421.705859 -355.953336) (xy 421.651357 -355.953336) (xy 421.597409 -355.94558) (xy 421.545114 -355.930225)
			(xy 421.495537 -355.907583) (xy 421.449687 -355.878117) (xy 421.408496 -355.842426) (xy 421.372805 -355.801235)
			(xy 421.343339 -355.755385) (xy 421.320697 -355.705808) (xy 421.305342 -355.653513) (xy 421.297586 -355.599565)
			(xy 421.2971 -355.572314) (xy 416.381184 -355.572314) (xy 414.729676 -357.223822) (xy 416.449002 -357.223822)
			(xy 416.449535 -357.194906) (xy 416.458261 -357.137735) (xy 416.475516 -357.082537) (xy 416.500905 -357.030575)
			(xy 416.533846 -356.983041) (xy 416.573584 -356.941023) (xy 416.596068 -356.922832) (xy 416.604822 -356.915264)
			(xy 416.615007 -356.894509) (xy 416.615626 -356.882954) (xy 416.615626 -356.80269) (xy 416.615087 -356.791117)
			(xy 416.604873 -356.770345) (xy 416.596068 -356.762812) (xy 416.573584 -356.744622) (xy 416.53385 -356.702601)
			(xy 416.500912 -356.655066) (xy 416.475524 -356.603104) (xy 416.458268 -356.547907) (xy 416.449538 -356.490738)
			(xy 416.449002 -356.461822) (xy 416.449488 -356.434571) (xy 416.457244 -356.380623) (xy 416.472599 -356.328328)
			(xy 416.495241 -356.278751) (xy 416.524707 -356.232901) (xy 416.560398 -356.19171) (xy 416.601589 -356.156019)
			(xy 416.647439 -356.126553) (xy 416.697016 -356.103911) (xy 416.749311 -356.088556) (xy 416.803259 -356.0808)
			(xy 416.857761 -356.0808) (xy 416.911709 -356.088556) (xy 416.964004 -356.103911) (xy 417.013581 -356.126553)
			(xy 417.059431 -356.156019) (xy 417.100622 -356.19171) (xy 417.136313 -356.232901) (xy 417.165779 -356.278751)
			(xy 417.188421 -356.328328) (xy 417.203776 -356.380623) (xy 417.211532 -356.434571) (xy 417.212018 -356.461822)
			(xy 417.211475 -356.490738) (xy 417.202755 -356.54791) (xy 417.185504 -356.603109) (xy 417.160117 -356.655072)
			(xy 417.127177 -356.702606) (xy 417.087437 -356.744622) (xy 417.064952 -356.762812) (xy 417.056181 -356.770365)
			(xy 417.046005 -356.791131) (xy 417.045394 -356.80269) (xy 417.045394 -356.882954) (xy 417.045993 -356.894518)
			(xy 417.056168 -356.915289) (xy 417.064952 -356.922832) (xy 417.087446 -356.940977) (xy 417.127153 -356.98297)
			(xy 417.160074 -357.03047) (xy 417.185456 -357.082391) (xy 417.202719 -357.137545) (xy 417.211468 -357.194672)
			(xy 417.212018 -357.223568) (xy 417.212018 -357.22433) (xy 417.211764 -357.240332) (xy 417.211256 -357.254556)
			(xy 417.224972 -357.279194) (xy 417.328096 -357.338122) (xy 417.35629 -357.33736) (xy 417.368482 -357.329486)
			(xy 417.391776 -357.314972) (xy 417.441627 -357.292016) (xy 417.494249 -357.276425) (xy 417.548559 -357.26852)
			(xy 417.576 -357.268018) (xy 417.576254 -357.268018) (xy 417.603511 -357.268426) (xy 417.657471 -357.276178)
			(xy 417.709778 -357.291531) (xy 417.759367 -357.314173) (xy 417.805229 -357.343641) (xy 417.84643 -357.379337)
			(xy 417.882131 -357.420534) (xy 417.911605 -357.466393) (xy 417.934253 -357.515979) (xy 417.949612 -357.568284)
			(xy 417.957371 -357.622243) (xy 417.957371 -357.676757) (xy 417.949612 -357.730716) (xy 417.934253 -357.783021)
			(xy 417.911605 -357.832607) (xy 417.882131 -357.878466) (xy 417.84643 -357.919663) (xy 417.805229 -357.955359)
			(xy 417.759367 -357.984827) (xy 417.709778 -358.007469) (xy 417.657471 -358.022822) (xy 417.603511 -358.030574)
			(xy 417.576254 -358.031034) (xy 417.549014 -358.030566) (xy 417.49509 -358.02281) (xy 417.442816 -358.007464)
			(xy 417.393258 -357.984838) (xy 417.347421 -357.955392) (xy 417.306239 -357.919727) (xy 417.270548 -357.878567)
			(xy 417.241075 -357.832748) (xy 417.218418 -357.783203) (xy 417.203039 -357.730939) (xy 417.195251 -357.677019)
			(xy 417.194746 -357.64978) (xy 417.194746 -357.649018) (xy 417.195 -357.633016) (xy 417.195508 -357.618792)
			(xy 417.181792 -357.594154) (xy 417.078668 -357.535226) (xy 417.050474 -357.535988) (xy 417.038282 -357.543862)
			(xy 417.014993 -357.558385) (xy 416.965141 -357.58134) (xy 416.912517 -357.596928) (xy 416.858205 -357.60483)
			(xy 416.830764 -357.60533) (xy 416.83051 -357.60533) (xy 416.80326 -357.604812) (xy 416.749315 -357.597058)
			(xy 416.697022 -357.581705) (xy 416.647446 -357.559067) (xy 416.601597 -357.529604) (xy 416.560407 -357.493916)
			(xy 416.524716 -357.452729) (xy 416.495249 -357.406882) (xy 416.472606 -357.357308) (xy 416.457249 -357.305017)
			(xy 416.44949 -357.251072) (xy 416.449002 -357.223822) (xy 414.729676 -357.223822) (xy 413.673036 -358.280462)
			(xy 413.666342 -358.287868) (xy 413.65874 -358.306304) (xy 413.658304 -358.316276) (xy 413.658304 -358.836214)
			(xy 417.824664 -358.836214) (xy 417.828735 -358.780592) (xy 417.840861 -358.726155) (xy 417.860784 -358.674064)
			(xy 417.88808 -358.625429) (xy 417.922166 -358.581286) (xy 417.962315 -358.542577) (xy 418.007673 -358.510126)
			(xy 418.057273 -358.484625) (xy 418.110057 -358.466618) (xy 418.1649 -358.456488) (xy 418.220634 -358.454451)
			(xy 418.276071 -358.460551) (xy 418.330028 -358.474657) (xy 418.381357 -358.496469) (xy 418.428963 -358.525523)
			(xy 418.471831 -358.561198) (xy 418.509048 -358.602735) (xy 418.539821 -358.649248) (xy 418.563493 -358.699745)
			(xy 418.579561 -358.753152) (xy 418.587681 -358.808328) (xy 418.58819 -358.836214) (xy 418.587681 -358.8641)
			(xy 418.579561 -358.919276) (xy 418.563493 -358.972683) (xy 418.539821 -359.02318) (xy 418.509048 -359.069693)
			(xy 418.471831 -359.11123) (xy 418.428963 -359.146905) (xy 418.381357 -359.175959) (xy 418.330028 -359.197771)
			(xy 418.276071 -359.211877) (xy 418.220634 -359.217977) (xy 418.1649 -359.21594) (xy 418.110057 -359.20581)
			(xy 418.057273 -359.187803) (xy 418.007673 -359.162302) (xy 417.962315 -359.129851) (xy 417.922166 -359.091142)
			(xy 417.88808 -359.046999) (xy 417.860784 -358.998364) (xy 417.840861 -358.946273) (xy 417.828735 -358.891836)
			(xy 417.824664 -358.836214) (xy 413.658304 -358.836214) (xy 413.658304 -359.904792) (xy 421.716706 -359.904792)
			(xy 421.720779 -359.849133) (xy 421.732914 -359.79466) (xy 421.75285 -359.742534) (xy 421.780164 -359.693866)
			(xy 421.814272 -359.649694) (xy 421.854449 -359.610959) (xy 421.899837 -359.578487) (xy 421.949469 -359.552969)
			(xy 422.002289 -359.53495) (xy 422.057168 -359.524813) (xy 422.112939 -359.522775) (xy 422.168413 -359.528878)
			(xy 422.222406 -359.542994) (xy 422.273769 -359.564821) (xy 422.321407 -359.593894) (xy 422.364303 -359.629593)
			(xy 422.401545 -359.671157) (xy 422.432339 -359.717701) (xy 422.456027 -359.768232) (xy 422.472105 -359.821674)
			(xy 422.474245 -359.836212) (xy 424.432982 -359.836212) (xy 424.437055 -359.780553) (xy 424.44919 -359.72608)
			(xy 424.469126 -359.673954) (xy 424.49644 -359.625286) (xy 424.530548 -359.581114) (xy 424.570725 -359.542379)
			(xy 424.616113 -359.509907) (xy 424.665745 -359.484389) (xy 424.718565 -359.46637) (xy 424.773444 -359.456233)
			(xy 424.829215 -359.454195) (xy 424.884689 -359.460298) (xy 424.938682 -359.474414) (xy 424.990045 -359.496241)
			(xy 425.037683 -359.525314) (xy 425.080579 -359.561013) (xy 425.117821 -359.602577) (xy 425.148615 -359.649121)
			(xy 425.172303 -359.699652) (xy 425.188381 -359.753094) (xy 425.196507 -359.808308) (xy 425.197016 -359.836212)
			(xy 425.196507 -359.864116) (xy 425.188381 -359.91933) (xy 425.172303 -359.972772) (xy 425.148615 -360.023303)
			(xy 425.117821 -360.069847) (xy 425.080579 -360.111411) (xy 425.037683 -360.14711) (xy 424.990045 -360.176183)
			(xy 424.938682 -360.19801) (xy 424.884689 -360.212126) (xy 424.829215 -360.218229) (xy 424.773444 -360.216191)
			(xy 424.718565 -360.206054) (xy 424.665745 -360.188035) (xy 424.616113 -360.162517) (xy 424.570725 -360.130045)
			(xy 424.530548 -360.09131) (xy 424.49644 -360.047138) (xy 424.469126 -359.99847) (xy 424.44919 -359.946344)
			(xy 424.437055 -359.891871) (xy 424.432982 -359.836212) (xy 422.474245 -359.836212) (xy 422.480231 -359.876888)
			(xy 422.48074 -359.904792) (xy 422.480231 -359.932696) (xy 422.472105 -359.98791) (xy 422.456027 -360.041352)
			(xy 422.432339 -360.091883) (xy 422.401545 -360.138427) (xy 422.364303 -360.179991) (xy 422.321407 -360.21569)
			(xy 422.273769 -360.244763) (xy 422.222406 -360.26659) (xy 422.168413 -360.280706) (xy 422.112939 -360.286809)
			(xy 422.057168 -360.284771) (xy 422.002289 -360.274634) (xy 421.949469 -360.256615) (xy 421.899837 -360.231097)
			(xy 421.854449 -360.198625) (xy 421.814272 -360.15989) (xy 421.780164 -360.115718) (xy 421.75285 -360.06705)
			(xy 421.732914 -360.014924) (xy 421.720779 -359.960451) (xy 421.716706 -359.904792) (xy 413.658304 -359.904792)
			(xy 413.658304 -360.642916) (xy 413.659066 -360.651806) (xy 413.66059 -360.660696) (xy 413.662622 -360.66857)
			(xy 413.672539 -360.698988) (xy 413.683259 -360.762059) (xy 413.683958 -360.794046) (xy 413.683958 -360.7943)
			(xy 413.683489 -360.821333) (xy 413.675862 -360.87486) (xy 413.660762 -360.926775) (xy 413.63849 -360.976042)
			(xy 413.609491 -361.021674) (xy 413.574345 -361.06276) (xy 413.533756 -361.098477) (xy 413.488534 -361.128112)
			(xy 413.464248 -361.139994) (xy 413.45612 -361.143804) (xy 413.297624 -361.3023) (xy 414.979102 -361.3023)
			(xy 414.983175 -361.246641) (xy 414.99531 -361.192168) (xy 415.015246 -361.140042) (xy 415.04256 -361.091374)
			(xy 415.076668 -361.047202) (xy 415.116845 -361.008467) (xy 415.162233 -360.975995) (xy 415.211865 -360.950477)
			(xy 415.264685 -360.932458) (xy 415.319564 -360.922321) (xy 415.375335 -360.920283) (xy 415.430809 -360.926386)
			(xy 415.484802 -360.940502) (xy 415.536165 -360.962329) (xy 415.583803 -360.991402) (xy 415.626699 -361.027101)
			(xy 415.663941 -361.068665) (xy 415.694735 -361.115209) (xy 415.718423 -361.16574) (xy 415.734501 -361.219182)
			(xy 415.742627 -361.274396) (xy 415.743136 -361.3023) (xy 415.742627 -361.330204) (xy 415.734501 -361.385418)
			(xy 415.718423 -361.43886) (xy 415.694735 -361.489391) (xy 415.663941 -361.535935) (xy 415.626699 -361.577499)
			(xy 415.583803 -361.613198) (xy 415.536165 -361.642271) (xy 415.484802 -361.664098) (xy 415.430809 -361.678214)
			(xy 415.375335 -361.684317) (xy 415.319564 -361.682279) (xy 415.264685 -361.672142) (xy 415.211865 -361.654123)
			(xy 415.162233 -361.628605) (xy 415.116845 -361.596133) (xy 415.076668 -361.557398) (xy 415.04256 -361.513226)
			(xy 415.015246 -361.464558) (xy 414.99531 -361.412432) (xy 414.983175 -361.357959) (xy 414.979102 -361.3023)
			(xy 413.297624 -361.3023) (xy 412.858712 -361.741212) (xy 421.889936 -361.741212) (xy 421.890455 -361.71297)
			(xy 421.898776 -361.657101) (xy 421.915239 -361.603069) (xy 421.939483 -361.552052) (xy 421.970981 -361.505164)
			(xy 422.009043 -361.463429) (xy 422.05284 -361.427759) (xy 422.101415 -361.398931) (xy 422.153707 -361.377576)
			(xy 422.18102 -361.370372) (xy 422.181274 -361.370372) (xy 422.191912 -361.367145) (xy 422.209174 -361.353179)
			(xy 422.214548 -361.343448) (xy 422.253918 -361.2642) (xy 422.254426 -361.242102) (xy 422.2496 -361.231688)
			(xy 422.239454 -361.207445) (xy 422.225187 -361.156865) (xy 422.218012 -361.104803) (xy 422.217596 -361.078526)
			(xy 422.217596 -361.078272) (xy 422.218082 -361.051003) (xy 422.225844 -360.997019) (xy 422.241209 -360.944689)
			(xy 422.263866 -360.895079) (xy 422.293352 -360.849198) (xy 422.329067 -360.807981) (xy 422.370284 -360.772266)
			(xy 422.416165 -360.74278) (xy 422.465775 -360.720123) (xy 422.518105 -360.704758) (xy 422.572089 -360.696996)
			(xy 422.626627 -360.696996) (xy 422.680611 -360.704758) (xy 422.732941 -360.720123) (xy 422.763547 -360.734101)
			(xy 435.087316 -360.734101) (xy 435.091052 -360.680797) (xy 435.102185 -360.628535) (xy 435.120499 -360.578336)
			(xy 435.145635 -360.531182) (xy 435.177102 -360.487995) (xy 435.214285 -360.449619) (xy 435.235096 -360.432858)
			(xy 435.243872 -360.425309) (xy 435.254048 -360.404541) (xy 435.254654 -360.39298) (xy 435.254654 -360.313224)
			(xy 435.254086 -360.301655) (xy 435.243891 -360.280884) (xy 435.235096 -360.273346) (xy 435.212606 -360.255115)
			(xy 435.172795 -360.213085) (xy 435.139791 -360.165524) (xy 435.114351 -360.113522) (xy 435.097059 -360.058274)
			(xy 435.088313 -360.001048) (xy 435.087776 -359.972102) (xy 435.088203 -359.944829) (xy 435.095966 -359.890839)
			(xy 435.111334 -359.838504) (xy 435.133994 -359.788888) (xy 435.163485 -359.743002) (xy 435.199207 -359.701781)
			(xy 435.240431 -359.666064) (xy 435.286319 -359.636577) (xy 435.335937 -359.613922) (xy 435.388274 -359.598559)
			(xy 435.442265 -359.590801) (xy 435.469538 -359.59034) (xy 435.498483 -359.590894) (xy 435.555706 -359.59965)
			(xy 435.610953 -359.616942) (xy 435.662958 -359.642373) (xy 435.71053 -359.675361) (xy 435.752579 -359.715149)
			(xy 435.770782 -359.73766) (xy 435.778346 -359.746419) (xy 435.799103 -359.756602) (xy 435.81066 -359.757218)
			(xy 435.890416 -359.757218) (xy 435.901984 -359.75665) (xy 435.922754 -359.746453) (xy 435.930294 -359.73766)
			(xy 435.948493 -359.715143) (xy 435.99053 -359.675335) (xy 436.038099 -359.642335) (xy 436.090107 -359.6169)
			(xy 436.14536 -359.599614) (xy 436.202591 -359.590874) (xy 436.231538 -359.59034) (xy 436.258808 -359.590789)
			(xy 436.312793 -359.598556) (xy 436.365124 -359.613926) (xy 436.414734 -359.636587) (xy 436.460615 -359.666077)
			(xy 436.501832 -359.701796) (xy 436.537547 -359.743017) (xy 436.567032 -359.788901) (xy 436.589688 -359.838514)
			(xy 436.605053 -359.890846) (xy 436.612814 -359.944832) (xy 436.6133 -359.972102) (xy 436.612744 -360.001047)
			(xy 436.603991 -360.058272) (xy 436.586701 -360.11352) (xy 436.561271 -360.165525) (xy 436.528283 -360.213096)
			(xy 436.488492 -360.255144) (xy 436.46598 -360.273346) (xy 436.457198 -360.280889) (xy 436.447026 -360.301662)
			(xy 436.446422 -360.313224) (xy 436.446422 -360.39298) (xy 436.446996 -360.404548) (xy 436.457187 -360.425319)
			(xy 436.46598 -360.432858) (xy 436.48679 -360.449619) (xy 436.523966 -360.487998) (xy 436.555427 -360.531187)
			(xy 436.580558 -360.578341) (xy 436.598868 -360.628539) (xy 436.609999 -360.680799) (xy 436.613734 -360.734101)
			(xy 436.609999 -360.787403) (xy 436.598867 -360.839664) (xy 436.580557 -360.889861) (xy 436.555426 -360.937015)
			(xy 436.523964 -360.980204) (xy 436.486788 -361.018583) (xy 436.46598 -361.035346) (xy 436.457198 -361.042889)
			(xy 436.447026 -361.063662) (xy 436.446422 -361.075224) (xy 436.446422 -361.15498) (xy 436.446996 -361.166548)
			(xy 436.457187 -361.187319) (xy 436.46598 -361.194858) (xy 436.488488 -361.213068) (xy 436.528294 -361.255104)
			(xy 436.561294 -361.30267) (xy 436.58673 -361.354676) (xy 436.604019 -361.409927) (xy 436.612764 -361.467156)
			(xy 436.6133 -361.496102) (xy 436.612778 -361.52337) (xy 436.605017 -361.57735) (xy 436.589653 -361.629677)
			(xy 436.566999 -361.679284) (xy 436.537517 -361.725163) (xy 436.501805 -361.76638) (xy 436.460592 -361.802095)
			(xy 436.414716 -361.831582) (xy 436.36511 -361.85424) (xy 436.312785 -361.869609) (xy 436.258806 -361.877375)
			(xy 436.231538 -361.877864) (xy 436.202593 -361.877326) (xy 436.145368 -361.868566) (xy 436.090121 -361.851271)
			(xy 436.038116 -361.825837) (xy 435.990545 -361.792847) (xy 435.948497 -361.753056) (xy 435.930294 -361.730544)
			(xy 435.92274 -361.721774) (xy 435.901975 -361.711597) (xy 435.890416 -361.710986) (xy 435.81066 -361.710986)
			(xy 435.799097 -361.711596) (xy 435.778326 -361.721763) (xy 435.770782 -361.730544) (xy 435.752597 -361.753073)
			(xy 435.710557 -361.79288) (xy 435.662986 -361.825878) (xy 435.610975 -361.851311) (xy 435.555719 -361.868595)
			(xy 435.498486 -361.877332) (xy 435.469538 -361.877864) (xy 435.442268 -361.877363) (xy 435.388283 -361.869606)
			(xy 435.335951 -361.854245) (xy 435.286338 -361.831592) (xy 435.240454 -361.802108) (xy 435.199234 -361.766395)
			(xy 435.163516 -361.725178) (xy 435.134027 -361.679297) (xy 435.111369 -361.629687) (xy 435.096002 -361.577357)
			(xy 435.08824 -361.523372) (xy 435.087776 -361.496102) (xy 435.088344 -361.467158) (xy 435.097096 -361.409934)
			(xy 435.114384 -361.354687) (xy 435.139812 -361.302681) (xy 435.172798 -361.255109) (xy 435.212585 -361.213061)
			(xy 435.235096 -361.194858) (xy 435.243872 -361.187309) (xy 435.254048 -361.166541) (xy 435.254654 -361.15498)
			(xy 435.254654 -361.075224) (xy 435.254086 -361.063655) (xy 435.243891 -361.042884) (xy 435.235096 -361.035346)
			(xy 435.214287 -361.018583) (xy 435.177103 -360.980207) (xy 435.145636 -360.93702) (xy 435.1205 -360.889866)
			(xy 435.102186 -360.839668) (xy 435.091052 -360.787406) (xy 435.087316 -360.734101) (xy 422.763547 -360.734101)
			(xy 422.782551 -360.74278) (xy 422.828432 -360.772266) (xy 422.869649 -360.807981) (xy 422.905364 -360.849198)
			(xy 422.93485 -360.895079) (xy 422.957507 -360.944689) (xy 422.972872 -360.997019) (xy 422.980634 -361.051003)
			(xy 422.98112 -361.078272) (xy 422.98062 -361.106516) (xy 422.9723 -361.162387) (xy 422.955837 -361.216421)
			(xy 422.931591 -361.26744) (xy 422.900092 -361.314329) (xy 422.862026 -361.356064) (xy 422.818226 -361.391733)
			(xy 422.769647 -361.420559) (xy 422.717351 -361.441911) (xy 422.690036 -361.449112) (xy 422.689782 -361.449112)
			(xy 422.679156 -361.45237) (xy 422.661888 -361.466313) (xy 422.656508 -361.476036) (xy 422.627359 -361.53471)
			(xy 424.407582 -361.53471) (xy 424.411655 -361.479051) (xy 424.42379 -361.424578) (xy 424.443726 -361.372452)
			(xy 424.47104 -361.323784) (xy 424.505148 -361.279612) (xy 424.545325 -361.240877) (xy 424.590713 -361.208405)
			(xy 424.640345 -361.182887) (xy 424.693165 -361.164868) (xy 424.748044 -361.154731) (xy 424.803815 -361.152693)
			(xy 424.859289 -361.158796) (xy 424.913282 -361.172912) (xy 424.964645 -361.194739) (xy 425.012283 -361.223812)
			(xy 425.055179 -361.259511) (xy 425.092421 -361.301075) (xy 425.123215 -361.347619) (xy 425.146903 -361.39815)
			(xy 425.162981 -361.451592) (xy 425.171107 -361.506806) (xy 425.171616 -361.53471) (xy 425.171107 -361.562614)
			(xy 425.162981 -361.617828) (xy 425.146903 -361.67127) (xy 425.123215 -361.721801) (xy 425.092421 -361.768345)
			(xy 425.055179 -361.809909) (xy 425.012283 -361.845608) (xy 424.972009 -361.870187) (xy 431.124102 -361.870187)
			(xy 431.124102 -361.785465) (xy 431.132155 -361.701128) (xy 431.148189 -361.617938) (xy 431.172057 -361.536648)
			(xy 431.203545 -361.457996) (xy 431.242367 -361.382693) (xy 431.28817 -361.311421) (xy 431.340541 -361.244825)
			(xy 431.399006 -361.18351) (xy 431.463034 -361.128029) (xy 431.532046 -361.078886) (xy 431.605416 -361.036526)
			(xy 431.682481 -361.001331) (xy 431.762543 -360.973622) (xy 431.844876 -360.953648) (xy 431.928735 -360.941591)
			(xy 432.01336 -360.93756) (xy 432.097985 -360.941591) (xy 432.181844 -360.953648) (xy 432.264177 -360.973622)
			(xy 432.344239 -361.001331) (xy 432.421304 -361.036526) (xy 432.494674 -361.078886) (xy 432.563686 -361.128029)
			(xy 432.627714 -361.18351) (xy 432.686179 -361.244825) (xy 432.73855 -361.311421) (xy 432.784353 -361.382693)
			(xy 432.823175 -361.457996) (xy 432.854663 -361.536648) (xy 432.878531 -361.617938) (xy 432.894565 -361.701128)
			(xy 432.902618 -361.785465) (xy 432.903122 -361.827826) (xy 432.902618 -361.870187) (xy 432.894565 -361.954524)
			(xy 432.878531 -362.037714) (xy 432.854663 -362.119004) (xy 432.823175 -362.197656) (xy 432.784353 -362.272959)
			(xy 432.73855 -362.344231) (xy 432.686179 -362.410827) (xy 432.627714 -362.472142) (xy 432.563686 -362.527623)
			(xy 432.494674 -362.576766) (xy 432.421304 -362.619126) (xy 432.344239 -362.654321) (xy 432.264177 -362.68203)
			(xy 432.181844 -362.702004) (xy 432.097985 -362.714061) (xy 432.01336 -362.718093) (xy 431.928735 -362.714061)
			(xy 431.844876 -362.702004) (xy 431.762543 -362.68203) (xy 431.682481 -362.654321) (xy 431.605416 -362.619126)
			(xy 431.532046 -362.576766) (xy 431.463034 -362.527623) (xy 431.399006 -362.472142) (xy 431.340541 -362.410827)
			(xy 431.28817 -362.344231) (xy 431.242367 -362.272959) (xy 431.203545 -362.197656) (xy 431.172057 -362.119004)
			(xy 431.148189 -362.037714) (xy 431.132155 -361.954524) (xy 431.124102 -361.870187) (xy 424.972009 -361.870187)
			(xy 424.964645 -361.874681) (xy 424.913282 -361.896508) (xy 424.859289 -361.910624) (xy 424.803815 -361.916727)
			(xy 424.748044 -361.914689) (xy 424.693165 -361.904552) (xy 424.640345 -361.886533) (xy 424.590713 -361.861015)
			(xy 424.545325 -361.828543) (xy 424.505148 -361.789808) (xy 424.47104 -361.745636) (xy 424.443726 -361.696968)
			(xy 424.42379 -361.644842) (xy 424.411655 -361.590369) (xy 424.407582 -361.53471) (xy 422.627359 -361.53471)
			(xy 422.617138 -361.555284) (xy 422.61663 -361.577382) (xy 422.621456 -361.587796) (xy 422.6316 -361.61204)
			(xy 422.645867 -361.66262) (xy 422.653043 -361.714681) (xy 422.65346 -361.740958) (xy 422.65346 -361.741212)
			(xy 422.653357 -361.751393) (xy 422.652215 -361.771724) (xy 422.651174 -361.781852) (xy 422.651174 -361.782614)
			(xy 422.650585 -361.792678) (xy 422.656487 -361.811938) (xy 422.662604 -361.819952) (xy 422.709086 -361.875832)
			(xy 422.715993 -361.883395) (xy 422.734216 -361.8927) (xy 422.744392 -361.893866) (xy 422.772872 -361.896416)
			(xy 422.828628 -361.909108) (xy 422.881867 -361.929973) (xy 422.931401 -361.958543) (xy 422.97612 -361.994179)
			(xy 423.015026 -362.036085) (xy 423.047249 -362.083323) (xy 423.072068 -362.134838) (xy 423.088928 -362.189478)
			(xy 423.097453 -362.246021) (xy 423.09796 -362.274612) (xy 423.097505 -362.301647) (xy 423.089887 -362.355176)
			(xy 423.07479 -362.407095) (xy 423.052518 -362.456363) (xy 423.023514 -362.501995) (xy 422.988362 -362.543077)
			(xy 422.947763 -362.578787) (xy 422.902531 -362.608409) (xy 422.87825 -362.620306) (xy 422.869868 -362.62437)
			(xy 422.856914 -362.637578) (xy 422.826942 -362.707174) (xy 422.825189 -362.711618) (xy 422.823141 -362.720946)
			(xy 422.822878 -362.725716) (xy 422.822624 -362.73486) (xy 422.825418 -362.743242) (xy 422.834314 -362.772217)
			(xy 422.843886 -362.832064) (xy 422.844468 -362.862368) (xy 422.843982 -362.889637) (xy 422.838042 -362.930948)
			(xy 439.741056 -362.930948) (xy 439.741537 -362.903578) (xy 439.749349 -362.849399) (xy 439.764834 -362.796896)
			(xy 439.787673 -362.747148) (xy 439.817395 -362.701182) (xy 439.835036 -362.68025) (xy 439.841132 -362.673138)
			(xy 439.847482 -362.656374) (xy 439.847482 -362.570522) (xy 439.841132 -362.553758) (xy 439.835036 -362.546646)
			(xy 439.817411 -362.525703) (xy 439.787695 -362.479734) (xy 439.764856 -362.429989) (xy 439.749362 -362.377491)
			(xy 439.741531 -362.323317) (xy 439.741056 -362.295948) (xy 439.7416 -362.268698) (xy 439.749349 -362.214752)
			(xy 439.764697 -362.162458) (xy 439.787332 -362.11288) (xy 439.816791 -362.067028) (xy 439.852477 -362.025836)
			(xy 439.893661 -361.990142) (xy 439.939506 -361.960672) (xy 439.989079 -361.938027) (xy 440.04137 -361.922667)
			(xy 440.095314 -361.914906) (xy 440.122564 -361.91444) (xy 440.149934 -361.914917) (xy 440.204113 -361.922731)
			(xy 440.256616 -361.938217) (xy 440.306363 -361.961056) (xy 440.35233 -361.990779) (xy 440.373262 -362.00842)
			(xy 440.380374 -362.014516) (xy 440.397138 -362.020866) (xy 440.48299 -362.020866) (xy 440.499754 -362.014516)
			(xy 440.506866 -362.00842) (xy 440.527799 -361.990779) (xy 440.573767 -361.961055) (xy 440.623513 -361.938209)
			(xy 440.676015 -361.922713) (xy 440.730193 -361.914884) (xy 440.784935 -361.914884) (xy 440.839113 -361.922713)
			(xy 440.891615 -361.938209) (xy 440.941361 -361.961055) (xy 440.987329 -361.990779) (xy 441.008262 -362.00842)
			(xy 441.015374 -362.014516) (xy 441.032138 -362.020866) (xy 441.11799 -362.020866) (xy 441.134754 -362.014516)
			(xy 441.141866 -362.00842) (xy 441.162799 -361.990779) (xy 441.208767 -361.961055) (xy 441.258513 -361.938209)
			(xy 441.311015 -361.922713) (xy 441.365193 -361.914884) (xy 441.419935 -361.914884) (xy 441.474113 -361.922713)
			(xy 441.526615 -361.938209) (xy 441.576361 -361.961055) (xy 441.622329 -361.990779) (xy 441.643262 -362.00842)
			(xy 441.650374 -362.014516) (xy 441.667138 -362.020866) (xy 441.752736 -362.020866) (xy 441.769754 -362.014516)
			(xy 441.776866 -362.00842) (xy 441.780676 -362.005118) (xy 441.78728 -361.99953) (xy 441.795662 -361.98556)
			(xy 441.79744 -361.976924) (xy 441.79871 -361.966256) (xy 441.79871 -361.88904) (xy 441.79744 -361.877356)
			(xy 441.795408 -361.869228) (xy 441.787026 -361.855512) (xy 441.780676 -361.850178) (xy 441.759946 -361.831987)
			(xy 441.723478 -361.790614) (xy 441.693349 -361.744419) (xy 441.670187 -361.694367) (xy 441.654474 -361.641501)
			(xy 441.646539 -361.586924) (xy 441.646056 -361.559348) (xy 441.646537 -361.531978) (xy 441.654349 -361.477799)
			(xy 441.669834 -361.425296) (xy 441.692673 -361.375548) (xy 441.722395 -361.329582) (xy 441.740036 -361.30865)
			(xy 441.746132 -361.301538) (xy 441.752482 -361.284774) (xy 441.752482 -361.198922) (xy 441.746132 -361.182158)
			(xy 441.740036 -361.175046) (xy 441.722442 -361.154075) (xy 441.692715 -361.108114) (xy 441.669866 -361.058374)
			(xy 441.654365 -361.005878) (xy 441.646532 -360.951705) (xy 441.646527 -360.896968) (xy 441.65435 -360.842793)
			(xy 441.66984 -360.790293) (xy 441.69268 -360.740549) (xy 441.722398 -360.694582) (xy 441.740036 -360.67365)
			(xy 441.746132 -360.666538) (xy 441.752482 -360.649774) (xy 441.752482 -360.563922) (xy 441.746132 -360.547158)
			(xy 441.740036 -360.540046) (xy 441.722442 -360.519075) (xy 441.692715 -360.473114) (xy 441.669866 -360.423374)
			(xy 441.654365 -360.370878) (xy 441.646532 -360.316705) (xy 441.646527 -360.261968) (xy 441.65435 -360.207793)
			(xy 441.66984 -360.155293) (xy 441.69268 -360.105549) (xy 441.722398 -360.059582) (xy 441.740036 -360.03865)
			(xy 441.746132 -360.031538) (xy 441.752482 -360.014774) (xy 441.752482 -359.928922) (xy 441.746132 -359.912158)
			(xy 441.740036 -359.905046) (xy 441.722411 -359.884103) (xy 441.692695 -359.838134) (xy 441.669856 -359.788389)
			(xy 441.654362 -359.735891) (xy 441.646531 -359.681717) (xy 441.646056 -359.654348) (xy 441.646535 -359.626774)
			(xy 441.654482 -359.572201) (xy 441.670203 -359.51934) (xy 441.693371 -359.469294) (xy 441.723502 -359.423104)
			(xy 441.759969 -359.381733) (xy 441.780676 -359.363518) (xy 441.787026 -359.358184) (xy 441.795408 -359.344468)
			(xy 441.79744 -359.33634) (xy 441.79871 -359.324656) (xy 441.79871 -359.24744) (xy 441.79744 -359.236772)
			(xy 441.795662 -359.228136) (xy 441.78728 -359.214166) (xy 441.780676 -359.208578) (xy 441.776866 -359.205276)
			(xy 441.769754 -359.19918) (xy 441.752736 -359.19283) (xy 441.667138 -359.19283) (xy 441.650374 -359.19918)
			(xy 441.643262 -359.205276) (xy 441.622329 -359.222917) (xy 441.576361 -359.252641) (xy 441.526615 -359.275487)
			(xy 441.474113 -359.290983) (xy 441.419935 -359.298812) (xy 441.365193 -359.298812) (xy 441.311015 -359.290983)
			(xy 441.258513 -359.275487) (xy 441.208767 -359.252641) (xy 441.162799 -359.222917) (xy 441.141866 -359.205276)
			(xy 441.134754 -359.19918) (xy 441.11799 -359.19283) (xy 441.032138 -359.19283) (xy 441.015374 -359.19918)
			(xy 441.008262 -359.205276) (xy 440.987329 -359.222917) (xy 440.941361 -359.252641) (xy 440.891615 -359.275487)
			(xy 440.839113 -359.290983) (xy 440.784935 -359.298812) (xy 440.730193 -359.298812) (xy 440.676015 -359.290983)
			(xy 440.623513 -359.275487) (xy 440.573767 -359.252641) (xy 440.527799 -359.222917) (xy 440.506866 -359.205276)
			(xy 440.499754 -359.19918) (xy 440.48299 -359.19283) (xy 440.397138 -359.19283) (xy 440.380374 -359.19918)
			(xy 440.373262 -359.205276) (xy 440.352314 -359.222896) (xy 440.306346 -359.252611) (xy 440.256603 -359.275451)
			(xy 440.204105 -359.290947) (xy 440.149932 -359.29878) (xy 440.122564 -359.299256) (xy 440.095314 -359.298756)
			(xy 440.041369 -359.290996) (xy 439.989078 -359.275638) (xy 439.939504 -359.252997) (xy 439.893656 -359.223531)
			(xy 439.852467 -359.187841) (xy 439.816776 -359.146654) (xy 439.787309 -359.100807) (xy 439.764666 -359.051233)
			(xy 439.749307 -358.998942) (xy 439.741545 -358.944998) (xy 439.741056 -358.917748) (xy 439.741537 -358.890378)
			(xy 439.749349 -358.836199) (xy 439.764834 -358.783696) (xy 439.787673 -358.733948) (xy 439.817395 -358.687982)
			(xy 439.835036 -358.66705) (xy 439.841132 -358.659938) (xy 439.847482 -358.643174) (xy 439.847482 -358.557322)
			(xy 439.841132 -358.540558) (xy 439.835036 -358.533446) (xy 439.817411 -358.512503) (xy 439.787695 -358.466534)
			(xy 439.764856 -358.416789) (xy 439.749362 -358.364291) (xy 439.741531 -358.310117) (xy 439.741056 -358.282748)
			(xy 439.7416 -358.255498) (xy 439.749349 -358.201552) (xy 439.764697 -358.149258) (xy 439.787332 -358.09968)
			(xy 439.816791 -358.053828) (xy 439.852477 -358.012636) (xy 439.893661 -357.976942) (xy 439.939506 -357.947472)
			(xy 439.989079 -357.924827) (xy 440.04137 -357.909467) (xy 440.095314 -357.901706) (xy 440.122564 -357.90124)
			(xy 440.149934 -357.901717) (xy 440.204113 -357.909531) (xy 440.256616 -357.925017) (xy 440.306363 -357.947856)
			(xy 440.35233 -357.977579) (xy 440.373262 -357.99522) (xy 440.380374 -358.001316) (xy 440.397138 -358.007666)
			(xy 440.48299 -358.007666) (xy 440.499754 -358.001316) (xy 440.506866 -357.99522) (xy 440.527799 -357.977579)
			(xy 440.573767 -357.947855) (xy 440.623513 -357.925009) (xy 440.676015 -357.909513) (xy 440.730193 -357.901684)
			(xy 440.784935 -357.901684) (xy 440.839113 -357.909513) (xy 440.891615 -357.925009) (xy 440.941361 -357.947855)
			(xy 440.987329 -357.977579) (xy 441.008262 -357.99522) (xy 441.015374 -358.001316) (xy 441.032138 -358.007666)
			(xy 441.11799 -358.007666) (xy 441.134754 -358.001316) (xy 441.141866 -357.99522) (xy 441.162799 -357.977579)
			(xy 441.208767 -357.947855) (xy 441.258513 -357.925009) (xy 441.311015 -357.909513) (xy 441.365193 -357.901684)
			(xy 441.419935 -357.901684) (xy 441.474113 -357.909513) (xy 441.526615 -357.925009) (xy 441.576361 -357.947855)
			(xy 441.622329 -357.977579) (xy 441.643262 -357.99522) (xy 441.650374 -358.001316) (xy 441.667138 -358.007666)
			(xy 441.75299 -358.007666) (xy 441.769754 -358.001316) (xy 441.776866 -357.99522) (xy 441.797799 -357.977579)
			(xy 441.843767 -357.947855) (xy 441.893513 -357.925009) (xy 441.946015 -357.909513) (xy 442.000193 -357.901684)
			(xy 442.054935 -357.901684) (xy 442.109113 -357.909513) (xy 442.161615 -357.925009) (xy 442.211361 -357.947855)
			(xy 442.257329 -357.977579) (xy 442.278262 -357.99522) (xy 442.285374 -358.001316) (xy 442.302138 -358.007666)
			(xy 442.38799 -358.007666) (xy 442.404754 -358.001316) (xy 442.411866 -357.99522) (xy 442.432803 -357.977586)
			(xy 442.478774 -357.947873) (xy 442.52852 -357.925036) (xy 442.58102 -357.909543) (xy 442.635195 -357.901714)
			(xy 442.662564 -357.90124) (xy 442.689818 -357.901689) (xy 442.743772 -357.909442) (xy 442.796073 -357.924796)
			(xy 442.845656 -357.947438) (xy 442.891512 -357.976907) (xy 442.932706 -358.012602) (xy 442.968401 -358.053798)
			(xy 442.997868 -358.099654) (xy 443.020508 -358.149238) (xy 443.03586 -358.20154) (xy 443.043612 -358.255494)
			(xy 443.044072 -358.282748) (xy 443.043582 -358.310117) (xy 443.035771 -358.364296) (xy 443.020288 -358.416799)
			(xy 442.997451 -358.466546) (xy 442.967731 -358.512514) (xy 442.950092 -358.533446) (xy 442.943996 -358.540558)
			(xy 442.937646 -358.557322) (xy 442.937646 -358.643174) (xy 442.943996 -358.659938) (xy 442.950092 -358.66705)
			(xy 442.96772 -358.687991) (xy 442.997434 -358.733961) (xy 443.020272 -358.783707) (xy 443.035766 -358.836205)
			(xy 443.043597 -358.890379) (xy 443.044072 -358.917748) (xy 443.04358 -358.945322) (xy 443.035634 -358.999894)
			(xy 443.019915 -359.052754) (xy 442.99675 -359.1028) (xy 442.966622 -359.14899) (xy 442.930158 -359.190362)
			(xy 442.909452 -359.208578) (xy 442.903102 -359.213912) (xy 442.89472 -359.227628) (xy 442.892688 -359.235756)
			(xy 442.891418 -359.24744) (xy 442.891418 -359.324656) (xy 442.892688 -359.33634) (xy 442.89472 -359.344468)
			(xy 442.903102 -359.358184) (xy 442.909452 -359.363518) (xy 442.930165 -359.381727) (xy 442.966638 -359.423095)
			(xy 442.996771 -359.469285) (xy 443.019936 -359.519334) (xy 443.035652 -359.572197) (xy 443.043589 -359.626773)
			(xy 443.044072 -359.654348) (xy 443.043582 -359.681717) (xy 443.035771 -359.735896) (xy 443.020288 -359.788399)
			(xy 442.997451 -359.838146) (xy 442.967731 -359.884114) (xy 442.950092 -359.905046) (xy 442.943996 -359.912158)
			(xy 442.937646 -359.928922) (xy 442.937646 -360.014774) (xy 442.943996 -360.031538) (xy 442.950092 -360.03865)
			(xy 442.967779 -360.059545) (xy 442.9975 -360.10552) (xy 443.020342 -360.155272) (xy 443.035833 -360.20778)
			(xy 443.043657 -360.261963) (xy 443.043652 -360.316709) (xy 443.035818 -360.370891) (xy 443.020316 -360.423395)
			(xy 442.997465 -360.473144) (xy 442.967735 -360.519113) (xy 442.950092 -360.540046) (xy 442.943996 -360.547158)
			(xy 442.937646 -360.563922) (xy 442.937646 -360.649774) (xy 442.943996 -360.666538) (xy 442.950092 -360.67365)
			(xy 442.967779 -360.694545) (xy 442.9975 -360.74052) (xy 443.020342 -360.790272) (xy 443.035833 -360.84278)
			(xy 443.043657 -360.896963) (xy 443.043652 -360.951709) (xy 443.035818 -361.005891) (xy 443.020316 -361.058395)
			(xy 442.997465 -361.108144) (xy 442.967735 -361.154113) (xy 442.950092 -361.175046) (xy 442.943996 -361.182158)
			(xy 442.937646 -361.198922) (xy 442.937646 -361.284774) (xy 442.943996 -361.301538) (xy 442.950092 -361.30865)
			(xy 442.96772 -361.329591) (xy 442.997434 -361.375561) (xy 443.020272 -361.425307) (xy 443.035766 -361.477805)
			(xy 443.043597 -361.531979) (xy 443.044072 -361.559348) (xy 443.043667 -361.586602) (xy 443.035903 -361.640555)
			(xy 443.02054 -361.692853) (xy 442.99789 -361.742433) (xy 442.968416 -361.788285) (xy 442.932716 -361.829475)
			(xy 442.891517 -361.865166) (xy 442.845659 -361.894631) (xy 442.796074 -361.917269) (xy 442.743772 -361.932621)
			(xy 442.689818 -361.940373) (xy 442.662564 -361.940856) (xy 442.635192 -361.940422) (xy 442.581012 -361.932598)
			(xy 442.528508 -361.917102) (xy 442.478761 -361.894253) (xy 442.432796 -361.864521) (xy 442.411866 -361.846876)
			(xy 442.404754 -361.84078) (xy 442.38799 -361.83443) (xy 442.302392 -361.83443) (xy 442.285374 -361.84078)
			(xy 442.278262 -361.846876) (xy 442.274452 -361.850178) (xy 442.267848 -361.855766) (xy 442.259466 -361.869736)
			(xy 442.257688 -361.878372) (xy 442.256418 -361.88904) (xy 442.256418 -361.966256) (xy 442.257688 -361.97794)
			(xy 442.25972 -361.986068) (xy 442.268102 -361.999784) (xy 442.274452 -362.005118) (xy 442.295165 -362.023327)
			(xy 442.331638 -362.064695) (xy 442.361771 -362.110885) (xy 442.384936 -362.160934) (xy 442.400652 -362.213797)
			(xy 442.408589 -362.268373) (xy 442.409072 -362.295948) (xy 442.408667 -362.323202) (xy 442.400903 -362.377155)
			(xy 442.38554 -362.429453) (xy 442.36289 -362.479033) (xy 442.333416 -362.524885) (xy 442.297716 -362.566075)
			(xy 442.256517 -362.601766) (xy 442.210659 -362.631231) (xy 442.161074 -362.653869) (xy 442.108772 -362.669221)
			(xy 442.054818 -362.676973) (xy 442.027564 -362.677456) (xy 441.998087 -362.676888) (xy 441.939835 -362.667827)
			(xy 441.88367 -362.649912) (xy 441.83093 -362.623569) (xy 441.782872 -362.589424) (xy 441.761372 -362.569252)
			(xy 441.75426 -362.56214) (xy 441.735972 -362.554774) (xy 441.70219 -362.554774) (xy 441.692185 -362.555279)
			(xy 441.673698 -362.562937) (xy 441.659546 -362.577085) (xy 441.651883 -362.595569) (xy 441.65139 -362.605574)
			(xy 441.65139 -362.639356) (xy 441.658756 -362.657644) (xy 441.665868 -362.664756) (xy 441.686023 -362.686272)
			(xy 441.72017 -362.734327) (xy 441.746519 -362.787062) (xy 441.764445 -362.843223) (xy 441.77352 -362.901472)
			(xy 441.774072 -362.930948) (xy 441.773667 -362.958202) (xy 441.765903 -363.012155) (xy 441.75054 -363.064453)
			(xy 441.72789 -363.114033) (xy 441.698416 -363.159885) (xy 441.662716 -363.201075) (xy 441.621517 -363.236766)
			(xy 441.575659 -363.266231) (xy 441.526074 -363.288869) (xy 441.473772 -363.304221) (xy 441.419818 -363.311973)
			(xy 441.392564 -363.312456) (xy 441.365192 -363.312022) (xy 441.311012 -363.304198) (xy 441.258508 -363.288702)
			(xy 441.208761 -363.265853) (xy 441.162796 -363.236121) (xy 441.141866 -363.218476) (xy 441.134754 -363.21238)
			(xy 441.11799 -363.20603) (xy 441.032138 -363.20603) (xy 441.015374 -363.21238) (xy 441.008262 -363.218476)
			(xy 440.987329 -363.236117) (xy 440.941361 -363.265841) (xy 440.891615 -363.288687) (xy 440.839113 -363.304183)
			(xy 440.784935 -363.312012) (xy 440.730193 -363.312012) (xy 440.676015 -363.304183) (xy 440.623513 -363.288687)
			(xy 440.573767 -363.265841) (xy 440.527799 -363.236117) (xy 440.506866 -363.218476) (xy 440.499754 -363.21238)
			(xy 440.48299 -363.20603) (xy 440.397138 -363.20603) (xy 440.380374 -363.21238) (xy 440.373262 -363.218476)
			(xy 440.352314 -363.236096) (xy 440.306346 -363.265811) (xy 440.256603 -363.288651) (xy 440.204105 -363.304147)
			(xy 440.149932 -363.31198) (xy 440.122564 -363.312456) (xy 440.095314 -363.311956) (xy 440.041369 -363.304196)
			(xy 439.989078 -363.288838) (xy 439.939504 -363.266197) (xy 439.893656 -363.236731) (xy 439.852467 -363.201041)
			(xy 439.816776 -363.159854) (xy 439.787309 -363.114007) (xy 439.764666 -363.064433) (xy 439.749307 -363.012142)
			(xy 439.741545 -362.958198) (xy 439.741056 -362.930948) (xy 422.838042 -362.930948) (xy 422.83622 -362.943621)
			(xy 422.820855 -362.995951) (xy 422.798198 -363.045561) (xy 422.768712 -363.091442) (xy 422.732997 -363.132659)
			(xy 422.69178 -363.168374) (xy 422.645899 -363.19786) (xy 422.596289 -363.220517) (xy 422.543959 -363.235882)
			(xy 422.489975 -363.243644) (xy 422.435437 -363.243644) (xy 422.381453 -363.235882) (xy 422.329123 -363.220517)
			(xy 422.279513 -363.19786) (xy 422.233632 -363.168374) (xy 422.192415 -363.132659) (xy 422.1567 -363.091442)
			(xy 422.127214 -363.045561) (xy 422.104557 -362.995951) (xy 422.089192 -362.943621) (xy 422.08143 -362.889637)
			(xy 422.080944 -362.862368) (xy 422.08138 -362.835333) (xy 422.089001 -362.781802) (xy 422.1041 -362.729883)
			(xy 422.126376 -362.680615) (xy 422.155382 -362.634983) (xy 422.190537 -362.593901) (xy 422.231138 -362.558192)
			(xy 422.276372 -362.52857) (xy 422.300654 -362.516674) (xy 422.309036 -362.51261) (xy 422.32199 -362.499402)
			(xy 422.351962 -362.429806) (xy 422.35372 -362.425364) (xy 422.355765 -362.416034) (xy 422.356026 -362.411264)
			(xy 422.35628 -362.40212) (xy 422.353486 -362.393738) (xy 422.344585 -362.364765) (xy 422.335017 -362.304916)
			(xy 422.334436 -362.274612) (xy 422.334533 -362.264431) (xy 422.335679 -362.2441) (xy 422.336722 -362.233972)
			(xy 422.336722 -362.23321) (xy 422.337299 -362.223146) (xy 422.331405 -362.203887) (xy 422.325292 -362.195872)
			(xy 422.27881 -362.139992) (xy 422.271901 -362.132432) (xy 422.253679 -362.123124) (xy 422.243504 -362.121958)
			(xy 422.215035 -362.119303) (xy 422.159283 -362.106625) (xy 422.106046 -362.085774) (xy 422.056513 -362.057218)
			(xy 422.011793 -362.021594) (xy 421.972885 -361.9797) (xy 421.940659 -361.932472) (xy 421.915837 -361.880966)
			(xy 421.898974 -361.826335) (xy 421.890446 -361.769799) (xy 421.889936 -361.741212) (xy 412.858712 -361.741212)
			(xy 412.091378 -362.508546) (xy 412.08453 -362.515943) (xy 412.0768 -362.534542) (xy 412.076392 -362.544614)
			(xy 412.076392 -362.804964) (xy 412.930846 -362.804964) (xy 412.934919 -362.749305) (xy 412.947054 -362.694832)
			(xy 412.96699 -362.642706) (xy 412.994304 -362.594038) (xy 413.028412 -362.549866) (xy 413.068589 -362.511131)
			(xy 413.113977 -362.478659) (xy 413.163609 -362.453141) (xy 413.216429 -362.435122) (xy 413.271308 -362.424985)
			(xy 413.327079 -362.422947) (xy 413.382553 -362.42905) (xy 413.436546 -362.443166) (xy 413.487909 -362.464993)
			(xy 413.535547 -362.494066) (xy 413.578443 -362.529765) (xy 413.615685 -362.571329) (xy 413.646479 -362.617873)
			(xy 413.670167 -362.668404) (xy 413.686245 -362.721846) (xy 413.694371 -362.77706) (xy 413.69488 -362.804964)
			(xy 413.694371 -362.832868) (xy 413.686245 -362.888082) (xy 413.670167 -362.941524) (xy 413.646479 -362.992055)
			(xy 413.615685 -363.038599) (xy 413.578443 -363.080163) (xy 413.535547 -363.115862) (xy 413.487909 -363.144935)
			(xy 413.436546 -363.166762) (xy 413.382553 -363.180878) (xy 413.327079 -363.186981) (xy 413.271308 -363.184943)
			(xy 413.216429 -363.174806) (xy 413.163609 -363.156787) (xy 413.113977 -363.131269) (xy 413.068589 -363.098797)
			(xy 413.028412 -363.060062) (xy 412.994304 -363.01589) (xy 412.96699 -362.967222) (xy 412.947054 -362.915096)
			(xy 412.934919 -362.860623) (xy 412.930846 -362.804964) (xy 412.076392 -362.804964) (xy 412.076392 -363.112812)
			(xy 412.076817 -363.122881) (xy 412.084533 -363.141484) (xy 412.091378 -363.14888) (xy 412.29915 -363.356652)
			(xy 415.064446 -363.356652) (xy 415.068519 -363.300993) (xy 415.080654 -363.24652) (xy 415.10059 -363.194394)
			(xy 415.127904 -363.145726) (xy 415.162012 -363.101554) (xy 415.202189 -363.062819) (xy 415.247577 -363.030347)
			(xy 415.297209 -363.004829) (xy 415.350029 -362.98681) (xy 415.404908 -362.976673) (xy 415.460679 -362.974635)
			(xy 415.516153 -362.980738) (xy 415.570146 -362.994854) (xy 415.621509 -363.016681) (xy 415.669147 -363.045754)
			(xy 415.712043 -363.081453) (xy 415.749285 -363.123017) (xy 415.780079 -363.169561) (xy 415.803767 -363.220092)
			(xy 415.819845 -363.273534) (xy 415.827971 -363.328748) (xy 415.82848 -363.356652) (xy 415.827971 -363.384556)
			(xy 415.819845 -363.43977) (xy 415.803767 -363.493212) (xy 415.780079 -363.543743) (xy 415.749285 -363.590287)
			(xy 415.712043 -363.631851) (xy 415.669147 -363.66755) (xy 415.621509 -363.696623) (xy 415.570146 -363.71845)
			(xy 415.516153 -363.732566) (xy 415.460679 -363.738669) (xy 415.404908 -363.736631) (xy 415.350029 -363.726494)
			(xy 415.297209 -363.708475) (xy 415.247577 -363.682957) (xy 415.202189 -363.650485) (xy 415.162012 -363.61175)
			(xy 415.127904 -363.567578) (xy 415.10059 -363.51891) (xy 415.080654 -363.466784) (xy 415.068519 -363.412311)
			(xy 415.064446 -363.356652) (xy 412.29915 -363.356652) (xy 412.648146 -363.705648) (xy 412.653324 -363.710462)
			(xy 412.665698 -363.717291) (xy 412.67253 -363.71911) (xy 412.679427 -363.720516) (xy 412.693481 -363.719882)
			(xy 412.700216 -363.71784) (xy 412.729887 -363.708472) (xy 412.791282 -363.698391) (xy 412.82239 -363.697774)
			(xy 412.849661 -363.698237) (xy 412.903647 -363.705998) (xy 412.955978 -363.721364) (xy 413.005591 -363.744021)
			(xy 413.051473 -363.773509) (xy 413.092691 -363.809227) (xy 413.128406 -363.850448) (xy 413.157891 -363.896332)
			(xy 413.180545 -363.945946) (xy 413.183002 -363.954314) (xy 425.230542 -363.954314) (xy 425.234615 -363.898655)
			(xy 425.24675 -363.844182) (xy 425.266686 -363.792056) (xy 425.294 -363.743388) (xy 425.328108 -363.699216)
			(xy 425.368285 -363.660481) (xy 425.413673 -363.628009) (xy 425.463305 -363.602491) (xy 425.516125 -363.584472)
			(xy 425.571004 -363.574335) (xy 425.626775 -363.572297) (xy 425.682249 -363.5784) (xy 425.736242 -363.592516)
			(xy 425.787605 -363.614343) (xy 425.835243 -363.643416) (xy 425.878139 -363.679115) (xy 425.915381 -363.720679)
			(xy 425.946175 -363.767223) (xy 425.969863 -363.817754) (xy 425.985941 -363.871196) (xy 425.994067 -363.92641)
			(xy 425.994576 -363.954314) (xy 425.994067 -363.982218) (xy 425.985941 -364.037432) (xy 425.969863 -364.090874)
			(xy 425.946175 -364.141405) (xy 425.915381 -364.187949) (xy 425.878139 -364.229513) (xy 425.835243 -364.265212)
			(xy 425.787605 -364.294285) (xy 425.736242 -364.316112) (xy 425.69097 -364.327948) (xy 431.047151 -364.327948)
			(xy 431.051154 -364.240086) (xy 431.06313 -364.152952) (xy 431.082981 -364.067268) (xy 431.11054 -363.983744)
			(xy 431.145581 -363.903072) (xy 431.187812 -363.825921) (xy 431.236884 -363.75293) (xy 431.292391 -363.684704)
			(xy 431.353871 -363.621808) (xy 431.420816 -363.564763) (xy 431.492671 -363.514042) (xy 431.568841 -363.470065)
			(xy 431.648694 -363.433197) (xy 431.731569 -363.403744) (xy 431.816779 -363.381948) (xy 431.903618 -363.367992)
			(xy 431.991366 -363.361989) (xy 432.079296 -363.363991) (xy 432.166681 -363.373981) (xy 432.252794 -363.391876)
			(xy 432.336924 -363.417527) (xy 432.418372 -363.450722) (xy 432.496465 -363.491186) (xy 432.570554 -363.538584)
			(xy 432.640026 -363.592523) (xy 432.704305 -363.652556) (xy 432.762859 -363.718185) (xy 432.815203 -363.788867)
			(xy 432.860902 -363.864016) (xy 432.899578 -363.943009) (xy 432.93091 -364.025192) (xy 432.95464 -364.109884)
			(xy 432.97057 -364.196383) (xy 432.978568 -364.283971) (xy 432.979068 -364.327948) (xy 432.978568 -364.371925)
			(xy 432.97057 -364.459513) (xy 432.95464 -364.546012) (xy 432.93091 -364.630704) (xy 432.899578 -364.712887)
			(xy 432.860902 -364.79188) (xy 432.815203 -364.867029) (xy 432.762859 -364.937711) (xy 432.704305 -365.00334)
			(xy 432.640026 -365.063373) (xy 432.570554 -365.117312) (xy 432.496465 -365.16471) (xy 432.418372 -365.205174)
			(xy 432.336924 -365.238369) (xy 432.252794 -365.26402) (xy 432.166681 -365.281915) (xy 432.079296 -365.291905)
			(xy 431.991366 -365.293907) (xy 431.903618 -365.287904) (xy 431.816779 -365.273948) (xy 431.731569 -365.252152)
			(xy 431.648694 -365.222699) (xy 431.568841 -365.185831) (xy 431.492671 -365.141854) (xy 431.420816 -365.091133)
			(xy 431.353871 -365.034088) (xy 431.292391 -364.971192) (xy 431.236884 -364.902966) (xy 431.187812 -364.829975)
			(xy 431.145581 -364.752824) (xy 431.11054 -364.672152) (xy 431.082981 -364.588628) (xy 431.06313 -364.502944)
			(xy 431.051154 -364.41581) (xy 431.047151 -364.327948) (xy 425.69097 -364.327948) (xy 425.682249 -364.330228)
			(xy 425.626775 -364.336331) (xy 425.571004 -364.334293) (xy 425.516125 -364.324156) (xy 425.463305 -364.306137)
			(xy 425.413673 -364.280619) (xy 425.368285 -364.248147) (xy 425.328108 -364.209412) (xy 425.294 -364.16524)
			(xy 425.266686 -364.116572) (xy 425.24675 -364.064446) (xy 425.234615 -364.009973) (xy 425.230542 -363.954314)
			(xy 413.183002 -363.954314) (xy 413.195908 -363.998279) (xy 413.203665 -364.052265) (xy 413.204152 -364.079536)
			(xy 413.203729 -364.105265) (xy 413.196811 -364.156257) (xy 413.183107 -364.205857) (xy 413.162863 -364.253166)
			(xy 413.136448 -364.297328) (xy 413.10434 -364.337541) (xy 413.086042 -364.355634) (xy 413.0842 -364.357412)
			(xy 416.135564 -364.357412) (xy 416.139637 -364.301753) (xy 416.151772 -364.24728) (xy 416.171708 -364.195154)
			(xy 416.199022 -364.146486) (xy 416.23313 -364.102314) (xy 416.273307 -364.063579) (xy 416.318695 -364.031107)
			(xy 416.368327 -364.005589) (xy 416.421147 -363.98757) (xy 416.476026 -363.977433) (xy 416.531797 -363.975395)
			(xy 416.587271 -363.981498) (xy 416.641264 -363.995614) (xy 416.692627 -364.017441) (xy 416.740265 -364.046514)
			(xy 416.783161 -364.082213) (xy 416.820403 -364.123777) (xy 416.851197 -364.170321) (xy 416.874885 -364.220852)
			(xy 416.890963 -364.274294) (xy 416.899089 -364.329508) (xy 416.899598 -364.357412) (xy 416.899089 -364.385316)
			(xy 416.890963 -364.44053) (xy 416.874885 -364.493972) (xy 416.868531 -364.507526) (xy 424.071794 -364.507526)
			(xy 424.075867 -364.451867) (xy 424.088002 -364.397394) (xy 424.107938 -364.345268) (xy 424.135252 -364.2966)
			(xy 424.16936 -364.252428) (xy 424.209537 -364.213693) (xy 424.254925 -364.181221) (xy 424.304557 -364.155703)
			(xy 424.357377 -364.137684) (xy 424.412256 -364.127547) (xy 424.468027 -364.125509) (xy 424.523501 -364.131612)
			(xy 424.577494 -364.145728) (xy 424.628857 -364.167555) (xy 424.676495 -364.196628) (xy 424.719391 -364.232327)
			(xy 424.756633 -364.273891) (xy 424.787427 -364.320435) (xy 424.811115 -364.370966) (xy 424.827193 -364.424408)
			(xy 424.835319 -364.479622) (xy 424.835828 -364.507526) (xy 424.835319 -364.53543) (xy 424.827193 -364.590644)
			(xy 424.811115 -364.644086) (xy 424.787427 -364.694617) (xy 424.756633 -364.741161) (xy 424.719391 -364.782725)
			(xy 424.676495 -364.818424) (xy 424.628857 -364.847497) (xy 424.577494 -364.869324) (xy 424.523501 -364.88344)
			(xy 424.468027 -364.889543) (xy 424.412256 -364.887505) (xy 424.357377 -364.877368) (xy 424.304557 -364.859349)
			(xy 424.254925 -364.833831) (xy 424.209537 -364.801359) (xy 424.16936 -364.762624) (xy 424.135252 -364.718452)
			(xy 424.107938 -364.669784) (xy 424.088002 -364.617658) (xy 424.075867 -364.563185) (xy 424.071794 -364.507526)
			(xy 416.868531 -364.507526) (xy 416.851197 -364.544503) (xy 416.820403 -364.591047) (xy 416.783161 -364.632611)
			(xy 416.740265 -364.66831) (xy 416.692627 -364.697383) (xy 416.641264 -364.71921) (xy 416.587271 -364.733326)
			(xy 416.531797 -364.739429) (xy 416.476026 -364.737391) (xy 416.421147 -364.727254) (xy 416.368327 -364.709235)
			(xy 416.318695 -364.683717) (xy 416.273307 -364.651245) (xy 416.23313 -364.61251) (xy 416.199022 -364.568338)
			(xy 416.171708 -364.51967) (xy 416.151772 -364.467544) (xy 416.139637 -364.413071) (xy 416.135564 -364.357412)
			(xy 413.0842 -364.357412) (xy 413.078676 -364.362746) (xy 413.066738 -364.389162) (xy 413.064687 -364.39412)
			(xy 413.062512 -364.404625) (xy 413.06242 -364.40999) (xy 413.06242 -364.878112) (xy 414.965386 -364.878112)
			(xy 414.969459 -364.822453) (xy 414.981594 -364.76798) (xy 415.00153 -364.715854) (xy 415.028844 -364.667186)
			(xy 415.062952 -364.623014) (xy 415.103129 -364.584279) (xy 415.148517 -364.551807) (xy 415.198149 -364.526289)
			(xy 415.250969 -364.50827) (xy 415.305848 -364.498133) (xy 415.361619 -364.496095) (xy 415.417093 -364.502198)
			(xy 415.471086 -364.516314) (xy 415.522449 -364.538141) (xy 415.570087 -364.567214) (xy 415.612983 -364.602913)
			(xy 415.650225 -364.644477) (xy 415.681019 -364.691021) (xy 415.704707 -364.741552) (xy 415.720785 -364.794994)
			(xy 415.728911 -364.850208) (xy 415.72942 -364.878112) (xy 415.728911 -364.906016) (xy 415.720785 -364.96123)
			(xy 415.704707 -365.014672) (xy 415.681019 -365.065203) (xy 415.650225 -365.111747) (xy 415.612983 -365.153311)
			(xy 415.570087 -365.18901) (xy 415.522449 -365.218083) (xy 415.472521 -365.2393) (xy 417.696394 -365.2393)
			(xy 417.700467 -365.183641) (xy 417.712602 -365.129168) (xy 417.732538 -365.077042) (xy 417.759852 -365.028374)
			(xy 417.79396 -364.984202) (xy 417.834137 -364.945467) (xy 417.879525 -364.912995) (xy 417.929157 -364.887477)
			(xy 417.981977 -364.869458) (xy 418.036856 -364.859321) (xy 418.092627 -364.857283) (xy 418.148101 -364.863386)
			(xy 418.202094 -364.877502) (xy 418.253457 -364.899329) (xy 418.301095 -364.928402) (xy 418.343991 -364.964101)
			(xy 418.381233 -365.005665) (xy 418.412027 -365.052209) (xy 418.435715 -365.10274) (xy 418.451793 -365.156182)
			(xy 418.459166 -365.20628) (xy 418.819328 -365.20628) (xy 418.823401 -365.150621) (xy 418.835536 -365.096148)
			(xy 418.855472 -365.044022) (xy 418.882786 -364.995354) (xy 418.916894 -364.951182) (xy 418.957071 -364.912447)
			(xy 419.002459 -364.879975) (xy 419.052091 -364.854457) (xy 419.104911 -364.836438) (xy 419.15979 -364.826301)
			(xy 419.215561 -364.824263) (xy 419.271035 -364.830366) (xy 419.325028 -364.844482) (xy 419.376391 -364.866309)
			(xy 419.424029 -364.895382) (xy 419.466925 -364.931081) (xy 419.504167 -364.972645) (xy 419.534961 -365.019189)
			(xy 419.558649 -365.06972) (xy 419.571001 -365.110776) (xy 420.772334 -365.110776) (xy 420.776407 -365.055117)
			(xy 420.788542 -365.000644) (xy 420.808478 -364.948518) (xy 420.835792 -364.89985) (xy 420.8699 -364.855678)
			(xy 420.910077 -364.816943) (xy 420.955465 -364.784471) (xy 421.005097 -364.758953) (xy 421.057917 -364.740934)
			(xy 421.112796 -364.730797) (xy 421.168567 -364.728759) (xy 421.224041 -364.734862) (xy 421.278034 -364.748978)
			(xy 421.329397 -364.770805) (xy 421.377035 -364.799878) (xy 421.419931 -364.835577) (xy 421.457173 -364.877141)
			(xy 421.487967 -364.923685) (xy 421.511655 -364.974216) (xy 421.527733 -365.027658) (xy 421.535859 -365.082872)
			(xy 421.536368 -365.110776) (xy 421.535859 -365.13868) (xy 421.527733 -365.193894) (xy 421.511655 -365.247336)
			(xy 421.487967 -365.297867) (xy 421.457173 -365.344411) (xy 421.419931 -365.385975) (xy 421.377035 -365.421674)
			(xy 421.329397 -365.450747) (xy 421.278034 -365.472574) (xy 421.224041 -365.48669) (xy 421.168567 -365.492793)
			(xy 421.112796 -365.490755) (xy 421.057917 -365.480618) (xy 421.005097 -365.462599) (xy 420.955465 -365.437081)
			(xy 420.910077 -365.404609) (xy 420.8699 -365.365874) (xy 420.835792 -365.321702) (xy 420.808478 -365.273034)
			(xy 420.788542 -365.220908) (xy 420.776407 -365.166435) (xy 420.772334 -365.110776) (xy 419.571001 -365.110776)
			(xy 419.574727 -365.123162) (xy 419.582853 -365.178376) (xy 419.583362 -365.20628) (xy 419.582853 -365.234184)
			(xy 419.574727 -365.289398) (xy 419.558649 -365.34284) (xy 419.534961 -365.393371) (xy 419.504167 -365.439915)
			(xy 419.466925 -365.481479) (xy 419.424029 -365.517178) (xy 419.376391 -365.546251) (xy 419.325028 -365.568078)
			(xy 419.271035 -365.582194) (xy 419.215561 -365.588297) (xy 419.15979 -365.586259) (xy 419.104911 -365.576122)
			(xy 419.052091 -365.558103) (xy 419.002459 -365.532585) (xy 418.957071 -365.500113) (xy 418.916894 -365.461378)
			(xy 418.882786 -365.417206) (xy 418.855472 -365.368538) (xy 418.835536 -365.316412) (xy 418.823401 -365.261939)
			(xy 418.819328 -365.20628) (xy 418.459166 -365.20628) (xy 418.459919 -365.211396) (xy 418.460428 -365.2393)
			(xy 418.459919 -365.267204) (xy 418.451793 -365.322418) (xy 418.435715 -365.37586) (xy 418.412027 -365.426391)
			(xy 418.381233 -365.472935) (xy 418.343991 -365.514499) (xy 418.301095 -365.550198) (xy 418.253457 -365.579271)
			(xy 418.202094 -365.601098) (xy 418.148101 -365.615214) (xy 418.092627 -365.621317) (xy 418.036856 -365.619279)
			(xy 417.981977 -365.609142) (xy 417.929157 -365.591123) (xy 417.879525 -365.565605) (xy 417.834137 -365.533133)
			(xy 417.79396 -365.494398) (xy 417.759852 -365.450226) (xy 417.732538 -365.401558) (xy 417.712602 -365.349432)
			(xy 417.700467 -365.294959) (xy 417.696394 -365.2393) (xy 415.472521 -365.2393) (xy 415.471086 -365.23991)
			(xy 415.417093 -365.254026) (xy 415.361619 -365.260129) (xy 415.305848 -365.258091) (xy 415.250969 -365.247954)
			(xy 415.198149 -365.229935) (xy 415.148517 -365.204417) (xy 415.103129 -365.171945) (xy 415.062952 -365.13321)
			(xy 415.028844 -365.089038) (xy 415.00153 -365.04037) (xy 414.981594 -364.988244) (xy 414.969459 -364.933771)
			(xy 414.965386 -364.878112) (xy 413.06242 -364.878112) (xy 413.06242 -365.299752) (xy 413.062886 -365.309626)
			(xy 413.070341 -365.327914) (xy 413.076898 -365.335312) (xy 413.418782 -365.677196) (xy 416.787328 -365.677196)
			(xy 416.791401 -365.621537) (xy 416.803536 -365.567064) (xy 416.823472 -365.514938) (xy 416.850786 -365.46627)
			(xy 416.884894 -365.422098) (xy 416.925071 -365.383363) (xy 416.970459 -365.350891) (xy 417.020091 -365.325373)
			(xy 417.072911 -365.307354) (xy 417.12779 -365.297217) (xy 417.183561 -365.295179) (xy 417.239035 -365.301282)
			(xy 417.293028 -365.315398) (xy 417.344391 -365.337225) (xy 417.392029 -365.366298) (xy 417.434925 -365.401997)
			(xy 417.472167 -365.443561) (xy 417.502961 -365.490105) (xy 417.526649 -365.540636) (xy 417.542727 -365.594078)
			(xy 417.550853 -365.649292) (xy 417.551362 -365.677196) (xy 417.550853 -365.7051) (xy 417.542727 -365.760314)
			(xy 417.526649 -365.813756) (xy 417.502961 -365.864287) (xy 417.472167 -365.910831) (xy 417.434925 -365.952395)
			(xy 417.392029 -365.988094) (xy 417.344391 -366.017167) (xy 417.293028 -366.038994) (xy 417.239035 -366.05311)
			(xy 417.183561 -366.059213) (xy 417.12779 -366.057175) (xy 417.072911 -366.047038) (xy 417.020091 -366.029019)
			(xy 416.970459 -366.003501) (xy 416.925071 -365.971029) (xy 416.884894 -365.932294) (xy 416.850786 -365.888122)
			(xy 416.823472 -365.839454) (xy 416.803536 -365.787328) (xy 416.791401 -365.732855) (xy 416.787328 -365.677196)
			(xy 413.418782 -365.677196) (xy 414.226502 -366.484916) (xy 414.232598 -366.491266) (xy 414.315656 -366.574324)
			(xy 414.322504 -366.581722) (xy 414.330236 -366.60032) (xy 414.330642 -366.610392) (xy 414.330642 -366.724946)
			(xy 414.330896 -366.73663) (xy 414.330896 -367.473484) (xy 415.204146 -367.473484) (xy 415.208219 -367.417825)
			(xy 415.220354 -367.363352) (xy 415.24029 -367.311226) (xy 415.267604 -367.262558) (xy 415.301712 -367.218386)
			(xy 415.341889 -367.179651) (xy 415.387277 -367.147179) (xy 415.436909 -367.121661) (xy 415.489729 -367.103642)
			(xy 415.544608 -367.093505) (xy 415.600379 -367.091467) (xy 415.655853 -367.09757) (xy 415.709846 -367.111686)
			(xy 415.761209 -367.133513) (xy 415.808847 -367.162586) (xy 415.851743 -367.198285) (xy 415.888985 -367.239849)
			(xy 415.919779 -367.286393) (xy 415.943467 -367.336924) (xy 415.959545 -367.390366) (xy 415.967671 -367.44558)
			(xy 415.96818 -367.473484) (xy 416.474146 -367.473484) (xy 416.478219 -367.417825) (xy 416.490354 -367.363352)
			(xy 416.51029 -367.311226) (xy 416.537604 -367.262558) (xy 416.571712 -367.218386) (xy 416.611889 -367.179651)
			(xy 416.657277 -367.147179) (xy 416.706909 -367.121661) (xy 416.759729 -367.103642) (xy 416.814608 -367.093505)
			(xy 416.870379 -367.091467) (xy 416.925853 -367.09757) (xy 416.979846 -367.111686) (xy 417.031209 -367.133513)
			(xy 417.078847 -367.162586) (xy 417.121743 -367.198285) (xy 417.158985 -367.239849) (xy 417.189779 -367.286393)
			(xy 417.213467 -367.336924) (xy 417.229545 -367.390366) (xy 417.237671 -367.44558) (xy 417.238027 -367.465102)
			(xy 418.560248 -367.465102) (xy 418.564321 -367.409443) (xy 418.576456 -367.35497) (xy 418.596392 -367.302844)
			(xy 418.623706 -367.254176) (xy 418.657814 -367.210004) (xy 418.697991 -367.171269) (xy 418.743379 -367.138797)
			(xy 418.793011 -367.113279) (xy 418.845831 -367.09526) (xy 418.90071 -367.085123) (xy 418.956481 -367.083085)
			(xy 419.011955 -367.089188) (xy 419.065948 -367.103304) (xy 419.117311 -367.125131) (xy 419.164949 -367.154204)
			(xy 419.207845 -367.189903) (xy 419.245087 -367.231467) (xy 419.275881 -367.278011) (xy 419.299569 -367.328542)
			(xy 419.315647 -367.381984) (xy 419.323773 -367.437198) (xy 419.324282 -367.465102) (xy 419.323773 -367.493006)
			(xy 419.315647 -367.54822) (xy 419.299569 -367.601662) (xy 419.275881 -367.652193) (xy 419.245087 -367.698737)
			(xy 419.207845 -367.740301) (xy 419.164949 -367.776) (xy 419.117311 -367.805073) (xy 419.065948 -367.8269)
			(xy 419.011955 -367.841016) (xy 418.956481 -367.847119) (xy 418.90071 -367.845081) (xy 418.845831 -367.834944)
			(xy 418.793011 -367.816925) (xy 418.743379 -367.791407) (xy 418.697991 -367.758935) (xy 418.657814 -367.7202)
			(xy 418.623706 -367.676028) (xy 418.596392 -367.62736) (xy 418.576456 -367.575234) (xy 418.564321 -367.520761)
			(xy 418.560248 -367.465102) (xy 417.238027 -367.465102) (xy 417.23818 -367.473484) (xy 417.237671 -367.501388)
			(xy 417.229545 -367.556602) (xy 417.213467 -367.610044) (xy 417.189779 -367.660575) (xy 417.158985 -367.707119)
			(xy 417.121743 -367.748683) (xy 417.078847 -367.784382) (xy 417.031209 -367.813455) (xy 416.979846 -367.835282)
			(xy 416.925853 -367.849398) (xy 416.870379 -367.855501) (xy 416.814608 -367.853463) (xy 416.759729 -367.843326)
			(xy 416.706909 -367.825307) (xy 416.657277 -367.799789) (xy 416.611889 -367.767317) (xy 416.571712 -367.728582)
			(xy 416.537604 -367.68441) (xy 416.51029 -367.635742) (xy 416.490354 -367.583616) (xy 416.478219 -367.529143)
			(xy 416.474146 -367.473484) (xy 415.96818 -367.473484) (xy 415.967671 -367.501388) (xy 415.959545 -367.556602)
			(xy 415.943467 -367.610044) (xy 415.919779 -367.660575) (xy 415.888985 -367.707119) (xy 415.851743 -367.748683)
			(xy 415.808847 -367.784382) (xy 415.761209 -367.813455) (xy 415.709846 -367.835282) (xy 415.655853 -367.849398)
			(xy 415.600379 -367.855501) (xy 415.544608 -367.853463) (xy 415.489729 -367.843326) (xy 415.436909 -367.825307)
			(xy 415.387277 -367.799789) (xy 415.341889 -367.767317) (xy 415.301712 -367.728582) (xy 415.267604 -367.68441)
			(xy 415.24029 -367.635742) (xy 415.220354 -367.583616) (xy 415.208219 -367.529143) (xy 415.204146 -367.473484)
			(xy 414.330896 -367.473484) (xy 414.330896 -369.599718) (xy 414.331356 -369.609595) (xy 414.338799 -369.627894)
			(xy 414.345374 -369.635278) (xy 414.644586 -369.93449) (xy 414.645094 -369.934998) (xy 414.652475 -369.94158)
			(xy 414.670775 -369.949024) (xy 414.680654 -369.949476) (xy 422.900856 -369.949476) (xy 422.910819 -369.948991)
			(xy 422.929243 -369.941403) (xy 422.93667 -369.934744) (xy 423.846498 -369.024916) (xy 423.853331 -369.017513)
			(xy 423.861035 -368.998915) (xy 423.861484 -368.988848) (xy 423.861484 -366.993424) (xy 423.858436 -366.985042)
			(xy 423.8478 -366.953586) (xy 423.836307 -366.888192) (xy 423.835576 -366.854994) (xy 423.836062 -366.827725)
			(xy 423.843824 -366.773741) (xy 423.859189 -366.721411) (xy 423.881846 -366.671801) (xy 423.911332 -366.62592)
			(xy 423.947047 -366.584703) (xy 423.988264 -366.548988) (xy 424.034145 -366.519502) (xy 424.083755 -366.496845)
			(xy 424.136085 -366.48148) (xy 424.190069 -366.473718) (xy 424.244607 -366.473718) (xy 424.298591 -366.48148)
			(xy 424.350921 -366.496845) (xy 424.400531 -366.519502) (xy 424.43406 -366.54105) (xy 427.287942 -366.54105)
			(xy 427.292015 -366.485391) (xy 427.30415 -366.430918) (xy 427.324086 -366.378792) (xy 427.3514 -366.330124)
			(xy 427.385508 -366.285952) (xy 427.425685 -366.247217) (xy 427.471073 -366.214745) (xy 427.520705 -366.189227)
			(xy 427.573525 -366.171208) (xy 427.628404 -366.161071) (xy 427.684175 -366.159033) (xy 427.739649 -366.165136)
			(xy 427.793642 -366.179252) (xy 427.845005 -366.201079) (xy 427.892643 -366.230152) (xy 427.935539 -366.265851)
			(xy 427.972781 -366.307415) (xy 428.003575 -366.353959) (xy 428.027263 -366.40449) (xy 428.043341 -366.457932)
			(xy 428.051467 -366.513146) (xy 428.051976 -366.54105) (xy 428.051467 -366.568954) (xy 428.043341 -366.624168)
			(xy 428.027263 -366.67761) (xy 428.003575 -366.728141) (xy 427.972781 -366.774685) (xy 427.935539 -366.816249)
			(xy 427.892643 -366.851948) (xy 427.845005 -366.881021) (xy 427.793642 -366.902848) (xy 427.739649 -366.916964)
			(xy 427.684175 -366.923067) (xy 427.628404 -366.921029) (xy 427.573525 -366.910892) (xy 427.520705 -366.892873)
			(xy 427.471073 -366.867355) (xy 427.425685 -366.834883) (xy 427.385508 -366.796148) (xy 427.3514 -366.751976)
			(xy 427.324086 -366.703308) (xy 427.30415 -366.651182) (xy 427.292015 -366.596709) (xy 427.287942 -366.54105)
			(xy 424.43406 -366.54105) (xy 424.446412 -366.548988) (xy 424.487629 -366.584703) (xy 424.523344 -366.62592)
			(xy 424.55283 -366.671801) (xy 424.575487 -366.721411) (xy 424.590852 -366.773741) (xy 424.598614 -366.827725)
			(xy 424.5991 -366.854994) (xy 424.59839 -366.888194) (xy 424.586899 -366.953592) (xy 424.57624 -366.985042)
			(xy 424.573192 -366.993424) (xy 424.573192 -368.249454) (xy 431.997102 -368.249454) (xy 432.001175 -368.193795)
			(xy 432.01331 -368.139322) (xy 432.033246 -368.087196) (xy 432.06056 -368.038528) (xy 432.094668 -367.994356)
			(xy 432.134845 -367.955621) (xy 432.180233 -367.923149) (xy 432.229865 -367.897631) (xy 432.282685 -367.879612)
			(xy 432.337564 -367.869475) (xy 432.393335 -367.867437) (xy 432.448809 -367.87354) (xy 432.502802 -367.887656)
			(xy 432.554165 -367.909483) (xy 432.601803 -367.938556) (xy 432.644699 -367.974255) (xy 432.681941 -368.015819)
			(xy 432.712735 -368.062363) (xy 432.736423 -368.112894) (xy 432.752501 -368.166336) (xy 432.760627 -368.22155)
			(xy 432.761136 -368.249454) (xy 432.760627 -368.277358) (xy 432.752501 -368.332572) (xy 432.736423 -368.386014)
			(xy 432.712735 -368.436545) (xy 432.681941 -368.483089) (xy 432.644699 -368.524653) (xy 432.601803 -368.560352)
			(xy 432.554165 -368.589425) (xy 432.502802 -368.611252) (xy 432.448809 -368.625368) (xy 432.393335 -368.631471)
			(xy 432.337564 -368.629433) (xy 432.282685 -368.619296) (xy 432.229865 -368.601277) (xy 432.180233 -368.575759)
			(xy 432.134845 -368.543287) (xy 432.094668 -368.504552) (xy 432.06056 -368.46038) (xy 432.033246 -368.411712)
			(xy 432.01331 -368.359586) (xy 432.001175 -368.305113) (xy 431.997102 -368.249454) (xy 424.573192 -368.249454)
			(xy 424.573192 -368.686588) (xy 426.72838 -368.686588) (xy 426.732453 -368.630929) (xy 426.744588 -368.576456)
			(xy 426.764524 -368.52433) (xy 426.791838 -368.475662) (xy 426.825946 -368.43149) (xy 426.866123 -368.392755)
			(xy 426.911511 -368.360283) (xy 426.961143 -368.334765) (xy 427.013963 -368.316746) (xy 427.068842 -368.306609)
			(xy 427.124613 -368.304571) (xy 427.180087 -368.310674) (xy 427.23408 -368.32479) (xy 427.285443 -368.346617)
			(xy 427.333081 -368.37569) (xy 427.375977 -368.411389) (xy 427.413219 -368.452953) (xy 427.444013 -368.499497)
			(xy 427.467701 -368.550028) (xy 427.483779 -368.60347) (xy 427.491905 -368.658684) (xy 427.492294 -368.679984)
			(xy 428.639476 -368.679984) (xy 428.643549 -368.624325) (xy 428.655684 -368.569852) (xy 428.67562 -368.517726)
			(xy 428.702934 -368.469058) (xy 428.737042 -368.424886) (xy 428.777219 -368.386151) (xy 428.822607 -368.353679)
			(xy 428.872239 -368.328161) (xy 428.925059 -368.310142) (xy 428.979938 -368.300005) (xy 429.035709 -368.297967)
			(xy 429.091183 -368.30407) (xy 429.145176 -368.318186) (xy 429.196539 -368.340013) (xy 429.244177 -368.369086)
			(xy 429.287073 -368.404785) (xy 429.324315 -368.446349) (xy 429.355109 -368.492893) (xy 429.378797 -368.543424)
			(xy 429.394875 -368.596866) (xy 429.403001 -368.65208) (xy 429.40351 -368.679984) (xy 429.403001 -368.707888)
			(xy 429.396716 -368.750596) (xy 432.71516 -368.750596) (xy 432.719233 -368.694937) (xy 432.731368 -368.640464)
			(xy 432.751304 -368.588338) (xy 432.778618 -368.53967) (xy 432.812726 -368.495498) (xy 432.852903 -368.456763)
			(xy 432.898291 -368.424291) (xy 432.947923 -368.398773) (xy 433.000743 -368.380754) (xy 433.055622 -368.370617)
			(xy 433.111393 -368.368579) (xy 433.166867 -368.374682) (xy 433.22086 -368.388798) (xy 433.272223 -368.410625)
			(xy 433.319861 -368.439698) (xy 433.362757 -368.475397) (xy 433.399999 -368.516961) (xy 433.430793 -368.563505)
			(xy 433.454481 -368.614036) (xy 433.470559 -368.667478) (xy 433.478685 -368.722692) (xy 433.479194 -368.750596)
			(xy 433.478685 -368.7785) (xy 433.470559 -368.833714) (xy 433.454481 -368.887156) (xy 433.430793 -368.937687)
			(xy 433.399999 -368.984231) (xy 433.362757 -369.025795) (xy 433.319861 -369.061494) (xy 433.272223 -369.090567)
			(xy 433.22086 -369.112394) (xy 433.166867 -369.12651) (xy 433.111393 -369.132613) (xy 433.055622 -369.130575)
			(xy 433.000743 -369.120438) (xy 432.947923 -369.102419) (xy 432.898291 -369.076901) (xy 432.852903 -369.044429)
			(xy 432.812726 -369.005694) (xy 432.778618 -368.961522) (xy 432.751304 -368.912854) (xy 432.731368 -368.860728)
			(xy 432.719233 -368.806255) (xy 432.71516 -368.750596) (xy 429.396716 -368.750596) (xy 429.394875 -368.763102)
			(xy 429.378797 -368.816544) (xy 429.355109 -368.867075) (xy 429.324315 -368.913619) (xy 429.287073 -368.955183)
			(xy 429.244177 -368.990882) (xy 429.196539 -369.019955) (xy 429.145176 -369.041782) (xy 429.091183 -369.055898)
			(xy 429.035709 -369.062001) (xy 428.979938 -369.059963) (xy 428.925059 -369.049826) (xy 428.872239 -369.031807)
			(xy 428.822607 -369.006289) (xy 428.777219 -368.973817) (xy 428.737042 -368.935082) (xy 428.702934 -368.89091)
			(xy 428.67562 -368.842242) (xy 428.655684 -368.790116) (xy 428.643549 -368.735643) (xy 428.639476 -368.679984)
			(xy 427.492294 -368.679984) (xy 427.492414 -368.686588) (xy 427.491905 -368.714492) (xy 427.483779 -368.769706)
			(xy 427.467701 -368.823148) (xy 427.444013 -368.873679) (xy 427.413219 -368.920223) (xy 427.375977 -368.961787)
			(xy 427.333081 -368.997486) (xy 427.285443 -369.026559) (xy 427.23408 -369.048386) (xy 427.180087 -369.062502)
			(xy 427.124613 -369.068605) (xy 427.068842 -369.066567) (xy 427.013963 -369.05643) (xy 426.961143 -369.038411)
			(xy 426.911511 -369.012893) (xy 426.866123 -368.980421) (xy 426.825946 -368.941686) (xy 426.791838 -368.897514)
			(xy 426.764524 -368.848846) (xy 426.744588 -368.79672) (xy 426.732453 -368.742247) (xy 426.72838 -368.686588)
			(xy 424.573192 -368.686588) (xy 424.573192 -369.283742) (xy 424.572761 -369.293809) (xy 424.565035 -369.312401)
			(xy 424.558206 -369.31981) (xy 424.479974 -369.398042) (xy 424.469306 -369.408964) (xy 423.320972 -370.557298)
			(xy 423.314622 -370.563394) (xy 423.231564 -370.646452) (xy 423.224166 -370.653298) (xy 423.205567 -370.661027)
			(xy 423.195496 -370.661438) (xy 423.080942 -370.661438) (xy 423.069258 -370.661692) (xy 414.512252 -370.661692)
			(xy 414.500568 -370.661438) (xy 414.386014 -370.661438) (xy 414.375952 -370.660998) (xy 414.357376 -370.653254)
			(xy 414.349946 -370.646452) (xy 414.266888 -370.563394) (xy 414.260538 -370.557298) (xy 413.723074 -370.019834)
			(xy 413.716978 -370.013484) (xy 413.63392 -369.930426) (xy 413.627083 -369.923024) (xy 413.619373 -369.904426)
			(xy 413.618934 -369.894358) (xy 413.618934 -369.779804) (xy 413.61868 -369.76812) (xy 413.61868 -366.905032)
			(xy 413.618244 -366.894968) (xy 413.61051 -366.876383) (xy 413.603694 -366.868964) (xy 412.712408 -365.977678)
			(xy 412.702293 -365.968209) (xy 412.678174 -365.954594) (xy 412.651285 -365.947961) (xy 412.623601 -365.948798)
			(xy 412.597161 -365.957043) (xy 412.57391 -365.97209) (xy 412.555557 -365.992832) (xy 412.543453 -366.017743)
			(xy 412.54045 -366.031272) (xy 412.535211 -366.057279) (xy 412.518497 -366.107628) (xy 412.494974 -366.155179)
			(xy 412.465095 -366.199015) (xy 412.429435 -366.238293) (xy 412.388681 -366.272257) (xy 412.343618 -366.300251)
			(xy 412.295113 -366.321738) (xy 412.244101 -366.336303) (xy 412.191563 -366.343666) (xy 412.165038 -366.3442)
			(xy 412.137763 -366.343739) (xy 412.083766 -366.33598) (xy 412.031424 -366.320616) (xy 411.981801 -366.297958)
			(xy 411.935908 -366.268469) (xy 411.894679 -366.232748) (xy 411.858954 -366.191523) (xy 411.82946 -366.145633)
			(xy 411.806797 -366.096012) (xy 411.791428 -366.043671) (xy 411.783664 -365.989675) (xy 411.783664 -365.935125)
			(xy 411.791428 -365.881129) (xy 411.806797 -365.828788) (xy 411.82946 -365.779167) (xy 411.858954 -365.733277)
			(xy 411.894679 -365.692052) (xy 411.935908 -365.656331) (xy 411.981801 -365.626842) (xy 412.031424 -365.604184)
			(xy 412.083766 -365.58882) (xy 412.137763 -365.581061) (xy 412.165038 -365.580676) (xy 412.181699 -365.580868)
			(xy 412.214894 -365.58379) (xy 412.231332 -365.586518) (xy 412.246001 -365.588581) (xy 412.275408 -365.585125)
			(xy 412.302591 -365.573386) (xy 412.325269 -365.554349) (xy 412.34154 -365.52961) (xy 412.350038 -365.501247)
			(xy 412.350458 -365.486442) (xy 412.350458 -365.479838) (xy 412.350204 -365.468154) (xy 412.350204 -364.435644)
			(xy 412.349771 -364.425578) (xy 412.342042 -364.406988) (xy 412.335218 -364.399576) (xy 412.272988 -364.337346)
			(xy 412.267146 -364.331504) (xy 411.46857 -363.532928) (xy 411.457902 -363.522006) (xy 411.37967 -363.443774)
			(xy 411.37282 -363.436377) (xy 411.365084 -363.417779) (xy 411.364684 -363.407706) (xy 411.364684 -362.24972)
			(xy 411.365121 -362.239656) (xy 411.372854 -362.221071) (xy 411.37967 -362.213652) (xy 411.457902 -362.13542)
			(xy 411.46857 -362.124498) (xy 412.931356 -360.661712) (xy 412.938036 -360.6543) (xy 412.945614 -360.635865)
			(xy 412.946088 -360.625898) (xy 412.946088 -358.147874) (xy 412.946342 -358.13619) (xy 412.946342 -358.021636)
			(xy 412.946778 -358.011572) (xy 412.954514 -357.992988) (xy 412.961328 -357.985568) (xy 413.044386 -357.90251)
			(xy 413.050482 -357.89616) (xy 416.487102 -354.45954) (xy 416.490912 -354.451412) (xy 416.502546 -354.427756)
			(xy 416.53136 -354.383611) (xy 416.565978 -354.343853) (xy 416.605739 -354.309239) (xy 416.649886 -354.280429)
			(xy 416.673538 -354.268786) (xy 416.681666 -354.264976) (xy 417.430966 -353.515676) (xy 417.437812 -353.508278)
			(xy 417.445544 -353.489679) (xy 417.445952 -353.479608) (xy 417.445952 -347.813376) (xy 417.445523 -347.803309)
			(xy 417.437797 -347.784715) (xy 417.430966 -347.777308) (xy 414.573212 -344.919554) (xy 414.565817 -344.9127)
			(xy 414.547218 -344.904952) (xy 414.537144 -344.904568) (xy 409.206192 -344.904568) (xy 409.196183 -344.905057)
			(xy 409.177688 -344.912717) (xy 409.16353 -344.926868) (xy 409.155862 -344.945359) (xy 409.155392 -344.955368)
			(xy 409.155392 -366.652048) (xy 409.768546 -366.652048) (xy 409.772619 -366.596389) (xy 409.784754 -366.541916)
			(xy 409.80469 -366.48979) (xy 409.832004 -366.441122) (xy 409.866112 -366.39695) (xy 409.906289 -366.358215)
			(xy 409.951677 -366.325743) (xy 410.001309 -366.300225) (xy 410.054129 -366.282206) (xy 410.109008 -366.272069)
			(xy 410.164779 -366.270031) (xy 410.220253 -366.276134) (xy 410.274246 -366.29025) (xy 410.325609 -366.312077)
			(xy 410.373247 -366.34115) (xy 410.416143 -366.376849) (xy 410.453385 -366.418413) (xy 410.484179 -366.464957)
			(xy 410.507867 -366.515488) (xy 410.523945 -366.56893) (xy 410.532071 -366.624144) (xy 410.53258 -366.652048)
			(xy 410.532071 -366.679952) (xy 410.523945 -366.735166) (xy 410.510437 -366.780064) (xy 412.410908 -366.780064)
			(xy 412.414981 -366.724405) (xy 412.427116 -366.669932) (xy 412.447052 -366.617806) (xy 412.474366 -366.569138)
			(xy 412.508474 -366.524966) (xy 412.548651 -366.486231) (xy 412.594039 -366.453759) (xy 412.643671 -366.428241)
			(xy 412.696491 -366.410222) (xy 412.75137 -366.400085) (xy 412.807141 -366.398047) (xy 412.862615 -366.40415)
			(xy 412.916608 -366.418266) (xy 412.967971 -366.440093) (xy 413.015609 -366.469166) (xy 413.058505 -366.504865)
			(xy 413.095747 -366.546429) (xy 413.126541 -366.592973) (xy 413.150229 -366.643504) (xy 413.166307 -366.696946)
			(xy 413.174433 -366.75216) (xy 413.174942 -366.780064) (xy 413.174433 -366.807968) (xy 413.166307 -366.863182)
			(xy 413.150229 -366.916624) (xy 413.126541 -366.967155) (xy 413.095747 -367.013699) (xy 413.058505 -367.055263)
			(xy 413.015609 -367.090962) (xy 412.967971 -367.120035) (xy 412.916608 -367.141862) (xy 412.862615 -367.155978)
			(xy 412.807141 -367.162081) (xy 412.75137 -367.160043) (xy 412.696491 -367.149906) (xy 412.643671 -367.131887)
			(xy 412.594039 -367.106369) (xy 412.548651 -367.073897) (xy 412.508474 -367.035162) (xy 412.474366 -366.99099)
			(xy 412.447052 -366.942322) (xy 412.427116 -366.890196) (xy 412.414981 -366.835723) (xy 412.410908 -366.780064)
			(xy 410.510437 -366.780064) (xy 410.507867 -366.788608) (xy 410.484179 -366.839139) (xy 410.453385 -366.885683)
			(xy 410.416143 -366.927247) (xy 410.373247 -366.962946) (xy 410.325609 -366.992019) (xy 410.274246 -367.013846)
			(xy 410.220253 -367.027962) (xy 410.164779 -367.034065) (xy 410.109008 -367.032027) (xy 410.054129 -367.02189)
			(xy 410.001309 -367.003871) (xy 409.951677 -366.978353) (xy 409.906289 -366.945881) (xy 409.866112 -366.907146)
			(xy 409.832004 -366.862974) (xy 409.80469 -366.814306) (xy 409.784754 -366.76218) (xy 409.772619 -366.707707)
			(xy 409.768546 -366.652048) (xy 409.155392 -366.652048) (xy 409.155392 -367.085118) (xy 409.155656 -367.092005)
			(xy 409.159388 -367.105268) (xy 409.162758 -367.11128) (xy 409.17876 -367.13795) (xy 409.187396 -367.146586)
			(xy 409.193238 -367.149888) (xy 409.217491 -367.164683) (xy 409.261729 -367.200323) (xy 409.300196 -367.242126)
			(xy 409.332041 -367.28917) (xy 409.356561 -367.340414) (xy 409.373215 -367.394727) (xy 409.381634 -367.450909)
			(xy 409.381632 -367.507717) (xy 409.373209 -367.563898) (xy 409.356552 -367.61821) (xy 409.332028 -367.669453)
			(xy 409.300179 -367.716494) (xy 409.26171 -367.758295) (xy 409.217469 -367.793932) (xy 409.193238 -367.808764)
			(xy 409.187396 -367.812066) (xy 409.17876 -367.820702) (xy 409.162758 -367.847372) (xy 409.159372 -367.853378)
			(xy 409.155639 -367.866644) (xy 409.155392 -367.873534) (xy 409.155392 -368.465862) (xy 409.15586 -368.475736)
			(xy 409.163313 -368.494024) (xy 409.16987 -368.501422) (xy 411.647386 -370.978938) (xy 431.486816 -370.978938)
			(xy 431.490889 -370.923279) (xy 431.503024 -370.868806) (xy 431.52296 -370.81668) (xy 431.550274 -370.768012)
			(xy 431.584382 -370.72384) (xy 431.624559 -370.685105) (xy 431.669947 -370.652633) (xy 431.719579 -370.627115)
			(xy 431.772399 -370.609096) (xy 431.827278 -370.598959) (xy 431.883049 -370.596921) (xy 431.938523 -370.603024)
			(xy 431.992516 -370.61714) (xy 432.043879 -370.638967) (xy 432.091517 -370.66804) (xy 432.134413 -370.703739)
			(xy 432.171655 -370.745303) (xy 432.202449 -370.791847) (xy 432.226137 -370.842378) (xy 432.242215 -370.89582)
			(xy 432.250341 -370.951034) (xy 432.25085 -370.978938) (xy 432.250341 -371.006842) (xy 432.242215 -371.062056)
			(xy 432.226137 -371.115498) (xy 432.202449 -371.166029) (xy 432.171655 -371.212573) (xy 432.134413 -371.254137)
			(xy 432.091517 -371.289836) (xy 432.043879 -371.318909) (xy 431.992516 -371.340736) (xy 431.938523 -371.354852)
			(xy 431.883049 -371.360955) (xy 431.827278 -371.358917) (xy 431.772399 -371.34878) (xy 431.719579 -371.330761)
			(xy 431.669947 -371.305243) (xy 431.624559 -371.272771) (xy 431.584382 -371.234036) (xy 431.550274 -371.189864)
			(xy 431.52296 -371.141196) (xy 431.503024 -371.08907) (xy 431.490889 -371.034597) (xy 431.486816 -370.978938)
			(xy 411.647386 -370.978938) (xy 412.775908 -372.10746) (xy 412.776416 -372.107968) (xy 412.783796 -372.114555)
			(xy 412.802095 -372.122016) (xy 412.811976 -372.122446) (xy 430.163986 -372.122446)
		)
		(stroke
			(width 0)
			(type solid)
		)
		(fill yes)
		(layer "In11.Cu")
		(net "GND")
	)
	(gr_poly
		(pts
			(xy 194.766184 -366.055402) (xy 194.77379 -366.05389) (xy 194.787627 -366.046906) (xy 194.793362 -366.041686)
			(xy 205.394052 -355.440996) (xy 205.400903 -355.4336) (xy 205.408644 -355.415001) (xy 205.409038 -355.404928)
			(xy 205.409038 -350.324928) (xy 205.416658 -350.306386) (xy 205.419452 -350.303592) (xy 205.419452 -349.903542)
			(xy 205.419887 -349.893478) (xy 205.427622 -349.874893) (xy 205.434438 -349.867474) (xy 206.616554 -348.685358)
			(xy 206.623399 -348.677959) (xy 206.631125 -348.659361) (xy 206.63154 -348.64929) (xy 206.63154 -344.63736)
			(xy 206.631021 -344.622401) (xy 206.622367 -344.593763) (xy 206.605785 -344.568861) (xy 206.582697 -344.549835)
			(xy 206.555086 -344.538316) (xy 206.525322 -344.535294) (xy 206.495959 -344.541027) (xy 206.469519 -344.555025)
			(xy 206.458566 -344.565224) (xy 206.436967 -344.585796) (xy 206.38857 -344.620655) (xy 206.335342 -344.647566)
			(xy 206.278577 -344.665875) (xy 206.219656 -344.675138) (xy 206.189834 -344.675714) (xy 206.162565 -344.675253)
			(xy 206.108581 -344.667496) (xy 206.056251 -344.652134) (xy 206.00664 -344.629482) (xy 205.960757 -344.599999)
			(xy 205.919539 -344.564286) (xy 205.883822 -344.52307) (xy 205.854335 -344.47719) (xy 205.831678 -344.427581)
			(xy 205.816312 -344.375252) (xy 205.808549 -344.321269) (xy 205.808549 -344.266731) (xy 205.816312 -344.212748)
			(xy 205.831678 -344.160419) (xy 205.854335 -344.11081) (xy 205.883822 -344.06493) (xy 205.919538 -344.023714)
			(xy 205.960757 -343.988001) (xy 206.00664 -343.958518) (xy 206.056251 -343.935866) (xy 206.108581 -343.920504)
			(xy 206.162565 -343.912747) (xy 206.189834 -343.91219) (xy 206.219655 -343.912765) (xy 206.278573 -343.922038)
			(xy 206.335335 -343.940351) (xy 206.388562 -343.967262) (xy 206.436961 -344.002116) (xy 206.458566 -344.02268)
			(xy 206.469568 -344.032815) (xy 206.496006 -344.046777) (xy 206.525353 -344.052491) (xy 206.555098 -344.049467)
			(xy 206.582695 -344.037964) (xy 206.605782 -344.018966) (xy 206.622383 -343.994099) (xy 206.631076 -343.965493)
			(xy 206.63154 -343.950544) (xy 206.63154 -332.874112) (xy 206.631117 -332.864042) (xy 206.623399 -332.84544)
			(xy 206.616554 -332.838044) (xy 205.530196 -331.751686) (xy 205.522801 -331.744831) (xy 205.504202 -331.737084)
			(xy 205.494128 -331.7367) (xy 197.838314 -331.7367) (xy 197.828251 -331.737139) (xy 197.809669 -331.744875)
			(xy 197.802246 -331.751686) (xy 197.104508 -332.449424) (xy 197.097665 -332.456824) (xy 197.089938 -332.475422)
			(xy 197.089522 -332.485492) (xy 197.089522 -338.879942) (xy 198.275192 -338.879942) (xy 198.279263 -338.82432)
			(xy 198.291389 -338.769883) (xy 198.311312 -338.717792) (xy 198.338608 -338.669157) (xy 198.372694 -338.625014)
			(xy 198.412843 -338.586305) (xy 198.458201 -338.553854) (xy 198.507801 -338.528353) (xy 198.560585 -338.510346)
			(xy 198.615428 -338.500216) (xy 198.671162 -338.498179) (xy 198.726599 -338.504279) (xy 198.780556 -338.518385)
			(xy 198.831885 -338.540197) (xy 198.879491 -338.569251) (xy 198.922359 -338.604926) (xy 198.959576 -338.646463)
			(xy 198.990349 -338.692976) (xy 199.014021 -338.743473) (xy 199.030089 -338.79688) (xy 199.038209 -338.852056)
			(xy 199.038718 -338.879942) (xy 199.038209 -338.907828) (xy 199.030089 -338.963004) (xy 199.014021 -339.016411)
			(xy 198.990349 -339.066908) (xy 198.959576 -339.113421) (xy 198.922359 -339.154958) (xy 198.879491 -339.190633)
			(xy 198.831885 -339.219687) (xy 198.780556 -339.241499) (xy 198.726599 -339.255605) (xy 198.671162 -339.261705)
			(xy 198.615428 -339.259668) (xy 198.560585 -339.249538) (xy 198.507801 -339.231531) (xy 198.458201 -339.20603)
			(xy 198.412843 -339.173579) (xy 198.372694 -339.13487) (xy 198.338608 -339.090727) (xy 198.311312 -339.042092)
			(xy 198.291389 -338.990001) (xy 198.279263 -338.935564) (xy 198.275192 -338.879942) (xy 197.089522 -338.879942)
			(xy 197.089522 -340.121748) (xy 203.227938 -340.121748) (xy 203.232009 -340.066126) (xy 203.244135 -340.011689)
			(xy 203.264058 -339.959598) (xy 203.291354 -339.910963) (xy 203.32544 -339.86682) (xy 203.365589 -339.828111)
			(xy 203.410947 -339.79566) (xy 203.460547 -339.770159) (xy 203.513331 -339.752152) (xy 203.568174 -339.742022)
			(xy 203.623908 -339.739985) (xy 203.679345 -339.746085) (xy 203.733302 -339.760191) (xy 203.784631 -339.782003)
			(xy 203.832237 -339.811057) (xy 203.875105 -339.846732) (xy 203.912322 -339.888269) (xy 203.943095 -339.934782)
			(xy 203.966767 -339.985279) (xy 203.982835 -340.038686) (xy 203.990955 -340.093862) (xy 203.991464 -340.121748)
			(xy 203.990955 -340.149634) (xy 203.982835 -340.20481) (xy 203.966767 -340.258217) (xy 203.943095 -340.308714)
			(xy 203.912322 -340.355227) (xy 203.875105 -340.396764) (xy 203.832237 -340.432439) (xy 203.784631 -340.461493)
			(xy 203.733302 -340.483305) (xy 203.679345 -340.497411) (xy 203.623908 -340.503511) (xy 203.568174 -340.501474)
			(xy 203.513331 -340.491344) (xy 203.460547 -340.473337) (xy 203.410947 -340.447836) (xy 203.365589 -340.415385)
			(xy 203.32544 -340.376676) (xy 203.291354 -340.332533) (xy 203.264058 -340.283898) (xy 203.244135 -340.231807)
			(xy 203.232009 -340.17737) (xy 203.227938 -340.121748) (xy 197.089522 -340.121748) (xy 197.089522 -342.001348)
			(xy 197.089091 -342.011415) (xy 197.081367 -342.030009) (xy 197.074536 -342.037416) (xy 196.689472 -342.42248)
			(xy 196.68871 -342.42248) (xy 196.675756 -342.424258) (xy 196.668644 -342.426544) (xy 196.662548 -342.4301)
			(xy 196.656543 -342.433491) (xy 196.643277 -342.437232) (xy 196.636386 -342.437466) (xy 153.13025 -342.437466)
			(xy 153.125372 -342.437562) (xy 153.115783 -342.439351) (xy 153.1112 -342.441022) (xy 153.102056 -342.444832)
			(xy 151.857202 -343.689686) (xy 159.75965 -343.689686) (xy 159.760211 -343.66077) (xy 159.768929 -343.6036)
			(xy 159.786177 -343.548402) (xy 159.81156 -343.496439) (xy 159.844498 -343.448905) (xy 159.884233 -343.406887)
			(xy 159.906716 -343.388696) (xy 159.915518 -343.381084) (xy 159.925704 -343.360187) (xy 159.926274 -343.348564)
			(xy 159.926274 -343.268808) (xy 159.925725 -343.257177) (xy 159.915544 -343.236267) (xy 159.906716 -343.228676)
			(xy 159.884224 -343.210494) (xy 159.844489 -343.168473) (xy 159.81155 -343.120937) (xy 159.786163 -343.068973)
			(xy 159.768909 -343.013774) (xy 159.760183 -342.956603) (xy 159.75965 -342.927686) (xy 159.760136 -342.900435)
			(xy 159.767892 -342.846487) (xy 159.783247 -342.794192) (xy 159.805889 -342.744615) (xy 159.835355 -342.698765)
			(xy 159.871046 -342.657574) (xy 159.912237 -342.621883) (xy 159.958087 -342.592417) (xy 160.007664 -342.569775)
			(xy 160.059959 -342.55442) (xy 160.113907 -342.546664) (xy 160.168409 -342.546664) (xy 160.222357 -342.55442)
			(xy 160.274652 -342.569775) (xy 160.324229 -342.592417) (xy 160.370079 -342.621883) (xy 160.41127 -342.657574)
			(xy 160.446961 -342.698765) (xy 160.476427 -342.744615) (xy 160.499069 -342.794192) (xy 160.514424 -342.846487)
			(xy 160.52218 -342.900435) (xy 160.522571 -342.922352) (xy 202.582016 -342.922352) (xy 202.586087 -342.86673)
			(xy 202.598213 -342.812293) (xy 202.618136 -342.760202) (xy 202.645432 -342.711567) (xy 202.679518 -342.667424)
			(xy 202.719667 -342.628715) (xy 202.765025 -342.596264) (xy 202.814625 -342.570763) (xy 202.867409 -342.552756)
			(xy 202.922252 -342.542626) (xy 202.977986 -342.540589) (xy 203.033423 -342.546689) (xy 203.08738 -342.560795)
			(xy 203.138709 -342.582607) (xy 203.186315 -342.611661) (xy 203.229183 -342.647336) (xy 203.2664 -342.688873)
			(xy 203.297173 -342.735386) (xy 203.320845 -342.785883) (xy 203.336913 -342.83929) (xy 203.345033 -342.894466)
			(xy 203.345542 -342.922352) (xy 203.345033 -342.950238) (xy 203.336913 -343.005414) (xy 203.320845 -343.058821)
			(xy 203.297173 -343.109318) (xy 203.2664 -343.155831) (xy 203.229183 -343.197368) (xy 203.186315 -343.233043)
			(xy 203.138709 -343.262097) (xy 203.08738 -343.283909) (xy 203.033423 -343.298015) (xy 202.977986 -343.304115)
			(xy 202.922252 -343.302078) (xy 202.867409 -343.291948) (xy 202.814625 -343.273941) (xy 202.765025 -343.24844)
			(xy 202.719667 -343.215989) (xy 202.679518 -343.17728) (xy 202.645432 -343.133137) (xy 202.618136 -343.084502)
			(xy 202.598213 -343.032411) (xy 202.586087 -342.977974) (xy 202.582016 -342.922352) (xy 160.522571 -342.922352)
			(xy 160.522666 -342.927686) (xy 160.52215 -342.956603) (xy 160.513423 -343.013775) (xy 160.496165 -343.068975)
			(xy 160.470773 -343.120936) (xy 160.437828 -343.16847) (xy 160.398086 -343.210486) (xy 160.3756 -343.228676)
			(xy 160.366814 -343.236303) (xy 160.356619 -343.257189) (xy 160.356042 -343.268808) (xy 160.356042 -343.348564)
			(xy 160.356544 -343.360201) (xy 160.366758 -343.381111) (xy 160.3756 -343.388696) (xy 160.398082 -343.406889)
			(xy 160.437817 -343.448909) (xy 160.470756 -343.496443) (xy 160.496145 -343.548404) (xy 160.513401 -343.603601)
			(xy 160.522131 -343.66077) (xy 160.522666 -343.689686) (xy 160.52218 -343.716937) (xy 160.514424 -343.770885)
			(xy 160.499069 -343.82318) (xy 160.486954 -343.849706) (xy 160.851086 -343.849706) (xy 160.855157 -343.794084)
			(xy 160.867283 -343.739647) (xy 160.887206 -343.687556) (xy 160.914502 -343.638921) (xy 160.948588 -343.594778)
			(xy 160.988737 -343.556069) (xy 161.034095 -343.523618) (xy 161.083695 -343.498117) (xy 161.136479 -343.48011)
			(xy 161.191322 -343.46998) (xy 161.247056 -343.467943) (xy 161.302493 -343.474043) (xy 161.35645 -343.488149)
			(xy 161.407779 -343.509961) (xy 161.455385 -343.539015) (xy 161.498253 -343.57469) (xy 161.53547 -343.616227)
			(xy 161.566243 -343.66274) (xy 161.589915 -343.713237) (xy 161.605983 -343.766644) (xy 161.614103 -343.82182)
			(xy 161.614612 -343.849706) (xy 161.614103 -343.877592) (xy 161.605983 -343.932768) (xy 161.589915 -343.986175)
			(xy 161.566243 -344.036672) (xy 161.53547 -344.083185) (xy 161.498253 -344.124722) (xy 161.455385 -344.160397)
			(xy 161.407779 -344.189451) (xy 161.35645 -344.211263) (xy 161.302493 -344.225369) (xy 161.247056 -344.231469)
			(xy 161.191322 -344.229432) (xy 161.136479 -344.219302) (xy 161.083695 -344.201295) (xy 161.034095 -344.175794)
			(xy 160.988737 -344.143343) (xy 160.948588 -344.104634) (xy 160.914502 -344.060491) (xy 160.887206 -344.011856)
			(xy 160.867283 -343.959765) (xy 160.855157 -343.905328) (xy 160.851086 -343.849706) (xy 160.486954 -343.849706)
			(xy 160.476427 -343.872757) (xy 160.446961 -343.918607) (xy 160.41127 -343.959798) (xy 160.370079 -343.995489)
			(xy 160.324229 -344.024955) (xy 160.274652 -344.047597) (xy 160.222357 -344.062952) (xy 160.168409 -344.070708)
			(xy 160.113907 -344.070708) (xy 160.059959 -344.062952) (xy 160.007664 -344.047597) (xy 159.958087 -344.024955)
			(xy 159.912237 -343.995489) (xy 159.871046 -343.959798) (xy 159.835355 -343.918607) (xy 159.805889 -343.872757)
			(xy 159.783247 -343.82318) (xy 159.767892 -343.770885) (xy 159.760136 -343.716937) (xy 159.75965 -343.689686)
			(xy 151.857202 -343.689686) (xy 150.706836 -344.840052) (xy 150.704128 -344.842901) (xy 150.699529 -344.849277)
			(xy 150.697692 -344.852752) (xy 150.69511 -344.858179) (xy 150.692289 -344.869859) (xy 150.692104 -344.875866)
			(xy 150.692104 -345.078304) (xy 160.503106 -345.078304) (xy 160.507177 -345.022682) (xy 160.519303 -344.968245)
			(xy 160.539226 -344.916154) (xy 160.566522 -344.867519) (xy 160.600608 -344.823376) (xy 160.640757 -344.784667)
			(xy 160.686115 -344.752216) (xy 160.735715 -344.726715) (xy 160.788499 -344.708708) (xy 160.843342 -344.698578)
			(xy 160.899076 -344.696541) (xy 160.954513 -344.702641) (xy 161.00847 -344.716747) (xy 161.059799 -344.738559)
			(xy 161.107405 -344.767613) (xy 161.150273 -344.803288) (xy 161.174565 -344.8304) (xy 201.363834 -344.8304)
			(xy 201.36434 -344.801482) (xy 201.373069 -344.74431) (xy 201.390329 -344.68911) (xy 201.415723 -344.637149)
			(xy 201.448669 -344.589615) (xy 201.488413 -344.547599) (xy 201.5109 -344.52941) (xy 201.519693 -344.521789)
			(xy 201.529884 -344.500899) (xy 201.530458 -344.489278) (xy 201.530458 -344.409522) (xy 201.529906 -344.397891)
			(xy 201.519728 -344.376981) (xy 201.5109 -344.36939) (xy 201.488412 -344.351205) (xy 201.448677 -344.309184)
			(xy 201.415738 -344.261648) (xy 201.390351 -344.209685) (xy 201.373096 -344.154487) (xy 201.364368 -344.097316)
			(xy 201.363834 -344.0684) (xy 201.36432 -344.041149) (xy 201.372076 -343.987201) (xy 201.387431 -343.934906)
			(xy 201.410073 -343.885329) (xy 201.439539 -343.839479) (xy 201.47523 -343.798288) (xy 201.516421 -343.762597)
			(xy 201.562271 -343.733131) (xy 201.611848 -343.710489) (xy 201.664143 -343.695134) (xy 201.718091 -343.687378)
			(xy 201.772593 -343.687378) (xy 201.826541 -343.695134) (xy 201.878836 -343.710489) (xy 201.928413 -343.733131)
			(xy 201.974263 -343.762597) (xy 202.015454 -343.798288) (xy 202.051145 -343.839479) (xy 202.080611 -343.885329)
			(xy 202.103253 -343.934906) (xy 202.118608 -343.987201) (xy 202.126364 -344.041149) (xy 202.12685 -344.0684)
			(xy 202.126351 -344.097318) (xy 202.11762 -344.154491) (xy 202.10036 -344.209691) (xy 202.074965 -344.261653)
			(xy 202.042017 -344.309186) (xy 202.002272 -344.351201) (xy 201.979784 -344.36939) (xy 201.970988 -344.377008)
			(xy 201.960799 -344.397901) (xy 201.960226 -344.409522) (xy 201.960226 -344.489278) (xy 201.960783 -344.500908)
			(xy 201.970958 -344.521818) (xy 201.979784 -344.52941) (xy 202.002269 -344.547599) (xy 202.042005 -344.589619)
			(xy 202.074944 -344.637154) (xy 202.100332 -344.689116) (xy 202.117588 -344.744314) (xy 202.126316 -344.801484)
			(xy 202.12685 -344.8304) (xy 202.126364 -344.857651) (xy 202.118608 -344.911599) (xy 202.103253 -344.963894)
			(xy 202.080611 -345.013471) (xy 202.051145 -345.059321) (xy 202.015454 -345.100512) (xy 201.974263 -345.136203)
			(xy 201.928413 -345.165669) (xy 201.878836 -345.188311) (xy 201.826541 -345.203666) (xy 201.772593 -345.211422)
			(xy 201.718091 -345.211422) (xy 201.664143 -345.203666) (xy 201.611848 -345.188311) (xy 201.562271 -345.165669)
			(xy 201.516421 -345.136203) (xy 201.47523 -345.100512) (xy 201.439539 -345.059321) (xy 201.410073 -345.013471)
			(xy 201.387431 -344.963894) (xy 201.372076 -344.911599) (xy 201.36432 -344.857651) (xy 201.363834 -344.8304)
			(xy 161.174565 -344.8304) (xy 161.18749 -344.844825) (xy 161.218263 -344.891338) (xy 161.241935 -344.941835)
			(xy 161.258003 -344.995242) (xy 161.266123 -345.050418) (xy 161.266632 -345.078304) (xy 161.266123 -345.10619)
			(xy 161.258003 -345.161366) (xy 161.241935 -345.214773) (xy 161.218263 -345.26527) (xy 161.18749 -345.311783)
			(xy 161.150273 -345.35332) (xy 161.107405 -345.388995) (xy 161.059799 -345.418049) (xy 161.00847 -345.439861)
			(xy 160.954513 -345.453967) (xy 160.899076 -345.460067) (xy 160.843342 -345.45803) (xy 160.788499 -345.4479)
			(xy 160.735715 -345.429893) (xy 160.686115 -345.404392) (xy 160.640757 -345.371941) (xy 160.600608 -345.333232)
			(xy 160.566522 -345.289089) (xy 160.539226 -345.240454) (xy 160.519303 -345.188363) (xy 160.507177 -345.133926)
			(xy 160.503106 -345.078304) (xy 150.692104 -345.078304) (xy 150.692104 -346.211652) (xy 165.219634 -346.211652)
			(xy 165.22012 -346.184401) (xy 165.227876 -346.130453) (xy 165.243231 -346.078158) (xy 165.265873 -346.028581)
			(xy 165.295339 -345.982731) (xy 165.33103 -345.94154) (xy 165.372221 -345.905849) (xy 165.418071 -345.876383)
			(xy 165.467648 -345.853741) (xy 165.519943 -345.838386) (xy 165.573891 -345.83063) (xy 165.628393 -345.83063)
			(xy 165.682341 -345.838386) (xy 165.734636 -345.853741) (xy 165.784213 -345.876383) (xy 165.830063 -345.905849)
			(xy 165.871254 -345.94154) (xy 165.906945 -345.982731) (xy 165.936411 -346.028581) (xy 165.959053 -346.078158)
			(xy 165.974408 -346.130453) (xy 165.982164 -346.184401) (xy 165.98265 -346.211652) (xy 165.98265 -346.211906)
			(xy 165.982064 -346.242274) (xy 165.972446 -346.302076) (xy 167.694608 -346.302076) (xy 167.698679 -346.246454)
			(xy 167.710805 -346.192017) (xy 167.730728 -346.139926) (xy 167.758024 -346.091291) (xy 167.79211 -346.047148)
			(xy 167.832259 -346.008439) (xy 167.877617 -345.975988) (xy 167.927217 -345.950487) (xy 167.980001 -345.93248)
			(xy 168.034844 -345.92235) (xy 168.090578 -345.920313) (xy 168.146015 -345.926413) (xy 168.199972 -345.940519)
			(xy 168.251301 -345.962331) (xy 168.298907 -345.991385) (xy 168.341775 -346.02706) (xy 168.378992 -346.068597)
			(xy 168.409765 -346.11511) (xy 168.433437 -346.165607) (xy 168.449505 -346.219014) (xy 168.457625 -346.27419)
			(xy 168.458134 -346.302076) (xy 168.457625 -346.329962) (xy 168.449505 -346.385138) (xy 168.433437 -346.438545)
			(xy 168.409765 -346.489042) (xy 168.378992 -346.535555) (xy 168.341775 -346.577092) (xy 168.334676 -346.583)
			(xy 201.363834 -346.583) (xy 201.36434 -346.554082) (xy 201.373069 -346.49691) (xy 201.390329 -346.44171)
			(xy 201.415723 -346.389749) (xy 201.448669 -346.342215) (xy 201.488413 -346.300199) (xy 201.5109 -346.28201)
			(xy 201.519693 -346.274389) (xy 201.529884 -346.253499) (xy 201.530458 -346.241878) (xy 201.530458 -346.162122)
			(xy 201.529906 -346.150491) (xy 201.519728 -346.129581) (xy 201.5109 -346.12199) (xy 201.488412 -346.103805)
			(xy 201.448677 -346.061784) (xy 201.415738 -346.014248) (xy 201.390351 -345.962285) (xy 201.373096 -345.907087)
			(xy 201.364368 -345.849916) (xy 201.363834 -345.821) (xy 201.36432 -345.793749) (xy 201.372076 -345.739801)
			(xy 201.387431 -345.687506) (xy 201.410073 -345.637929) (xy 201.439539 -345.592079) (xy 201.47523 -345.550888)
			(xy 201.516421 -345.515197) (xy 201.562271 -345.485731) (xy 201.611848 -345.463089) (xy 201.664143 -345.447734)
			(xy 201.718091 -345.439978) (xy 201.772593 -345.439978) (xy 201.826541 -345.447734) (xy 201.878836 -345.463089)
			(xy 201.928413 -345.485731) (xy 201.974263 -345.515197) (xy 202.015454 -345.550888) (xy 202.051145 -345.592079)
			(xy 202.080611 -345.637929) (xy 202.103253 -345.687506) (xy 202.118608 -345.739801) (xy 202.126364 -345.793749)
			(xy 202.12685 -345.821) (xy 202.126351 -345.849918) (xy 202.11762 -345.907091) (xy 202.10036 -345.962291)
			(xy 202.074965 -346.014253) (xy 202.042017 -346.061786) (xy 202.002272 -346.103801) (xy 201.979784 -346.12199)
			(xy 201.970988 -346.129608) (xy 201.960799 -346.150501) (xy 201.960226 -346.162122) (xy 201.960226 -346.241878)
			(xy 201.960783 -346.253508) (xy 201.970958 -346.274418) (xy 201.979784 -346.28201) (xy 202.002269 -346.300199)
			(xy 202.042005 -346.342219) (xy 202.074944 -346.389754) (xy 202.100332 -346.441716) (xy 202.117588 -346.496914)
			(xy 202.126316 -346.554084) (xy 202.12685 -346.583) (xy 202.126364 -346.610251) (xy 202.118608 -346.664199)
			(xy 202.103253 -346.716494) (xy 202.080611 -346.766071) (xy 202.051145 -346.811921) (xy 202.015454 -346.853112)
			(xy 201.974263 -346.888803) (xy 201.928413 -346.918269) (xy 201.878836 -346.940911) (xy 201.826541 -346.956266)
			(xy 201.772593 -346.964022) (xy 201.718091 -346.964022) (xy 201.664143 -346.956266) (xy 201.611848 -346.940911)
			(xy 201.562271 -346.918269) (xy 201.516421 -346.888803) (xy 201.47523 -346.853112) (xy 201.439539 -346.811921)
			(xy 201.410073 -346.766071) (xy 201.387431 -346.716494) (xy 201.372076 -346.664199) (xy 201.36432 -346.610251)
			(xy 201.363834 -346.583) (xy 168.334676 -346.583) (xy 168.298907 -346.612767) (xy 168.251301 -346.641821)
			(xy 168.199972 -346.663633) (xy 168.146015 -346.677739) (xy 168.090578 -346.683839) (xy 168.034844 -346.681802)
			(xy 167.980001 -346.671672) (xy 167.927217 -346.653665) (xy 167.877617 -346.628164) (xy 167.832259 -346.595713)
			(xy 167.79211 -346.557004) (xy 167.758024 -346.512861) (xy 167.730728 -346.464226) (xy 167.710805 -346.412135)
			(xy 167.698679 -346.357698) (xy 167.694608 -346.302076) (xy 165.972446 -346.302076) (xy 165.97242 -346.302239)
			(xy 165.953408 -346.359923) (xy 165.939978 -346.387166) (xy 165.93403 -346.39961) (xy 165.928387 -346.426599)
			(xy 165.930175 -346.454113) (xy 165.939261 -346.480145) (xy 165.954984 -346.502794) (xy 165.976196 -346.520409)
			(xy 166.001348 -346.531704) (xy 166.014908 -346.534232) (xy 166.041624 -346.538778) (xy 166.093505 -346.554432)
			(xy 166.142648 -346.577269) (xy 166.188066 -346.60683) (xy 166.228844 -346.642521) (xy 166.264161 -346.683623)
			(xy 166.293307 -346.729308) (xy 166.315695 -346.778659) (xy 166.330874 -346.83068) (xy 166.338539 -346.884326)
			(xy 166.339012 -346.911422) (xy 166.338526 -346.938673) (xy 166.33077 -346.992621) (xy 166.315415 -347.044916)
			(xy 166.292773 -347.094493) (xy 166.263307 -347.140343) (xy 166.227616 -347.181534) (xy 166.186425 -347.217225)
			(xy 166.140575 -347.246691) (xy 166.09206 -347.268848) (xy 203.547 -347.268848) (xy 203.547 -347.214352)
			(xy 203.554755 -347.160411) (xy 203.570108 -347.108122) (xy 203.592745 -347.05855) (xy 203.622206 -347.012704)
			(xy 203.657892 -346.971517) (xy 203.699075 -346.935828) (xy 203.744918 -346.906362) (xy 203.794488 -346.88372)
			(xy 203.846775 -346.868363) (xy 203.900716 -346.860603) (xy 203.927964 -346.860114) (xy 203.955334 -346.860598)
			(xy 204.009512 -346.868411) (xy 204.062015 -346.883896) (xy 204.111762 -346.906733) (xy 204.15773 -346.936454)
			(xy 204.178662 -346.954094) (xy 204.178916 -346.954348) (xy 204.18599 -346.959953) (xy 204.202917 -346.966188)
			(xy 204.211936 -346.96654) (xy 204.278992 -346.96654) (xy 204.28801 -346.966192) (xy 204.304928 -346.95994)
			(xy 204.312012 -346.954348) (xy 204.312012 -346.954094) (xy 204.312266 -346.954094) (xy 204.333199 -346.936456)
			(xy 204.379172 -346.906745) (xy 204.428919 -346.883908) (xy 204.481419 -346.868417) (xy 204.535595 -346.860588)
			(xy 204.562964 -346.860114) (xy 204.589876 -346.860595) (xy 204.643163 -346.868196) (xy 204.694856 -346.883196)
			(xy 204.743935 -346.905299) (xy 204.766926 -346.919296) (xy 204.76718 -346.919296) (xy 204.775203 -346.923891)
			(xy 204.793311 -346.927542) (xy 204.802486 -346.926408) (xy 204.869288 -346.915486) (xy 204.878413 -346.913542)
			(xy 204.894436 -346.904011) (xy 204.90053 -346.896944) (xy 204.91875 -346.875108) (xy 204.960565 -346.836565)
			(xy 205.007637 -346.804656) (xy 205.058924 -346.780086) (xy 205.11329 -346.763401) (xy 205.16953 -346.75497)
			(xy 205.197964 -346.75445) (xy 205.225212 -346.755012) (xy 205.279155 -346.762762) (xy 205.331446 -346.778111)
			(xy 205.38102 -346.800744) (xy 205.426869 -346.830203) (xy 205.468058 -346.865887) (xy 205.50375 -346.907069)
			(xy 205.533218 -346.952911) (xy 205.555862 -347.002481) (xy 205.571221 -347.054768) (xy 205.578983 -347.10871)
			(xy 205.579472 -347.135958) (xy 205.578988 -347.163328) (xy 205.571176 -347.217506) (xy 205.555691 -347.270009)
			(xy 205.532853 -347.319757) (xy 205.503132 -347.365724) (xy 205.485492 -347.386656) (xy 205.485238 -347.38691)
			(xy 205.479634 -347.393984) (xy 205.473399 -347.410911) (xy 205.473046 -347.41993) (xy 205.473046 -347.486986)
			(xy 205.4734 -347.496003) (xy 205.479649 -347.512921) (xy 205.485238 -347.520006) (xy 205.485492 -347.520006)
			(xy 205.485492 -347.52026) (xy 205.503125 -347.541197) (xy 205.532838 -347.587169) (xy 205.555675 -347.636915)
			(xy 205.571168 -347.689414) (xy 205.578997 -347.743589) (xy 205.579472 -347.770958) (xy 205.578986 -347.798209)
			(xy 205.57123 -347.852157) (xy 205.555875 -347.904452) (xy 205.533233 -347.954029) (xy 205.503767 -347.999879)
			(xy 205.468076 -348.04107) (xy 205.426885 -348.076761) (xy 205.381035 -348.106227) (xy 205.331458 -348.128869)
			(xy 205.279163 -348.144224) (xy 205.225215 -348.15198) (xy 205.170713 -348.15198) (xy 205.116765 -348.144224)
			(xy 205.06447 -348.128869) (xy 205.014893 -348.106227) (xy 204.969043 -348.076761) (xy 204.927852 -348.04107)
			(xy 204.892161 -347.999879) (xy 204.862695 -347.954029) (xy 204.840053 -347.904452) (xy 204.824698 -347.852157)
			(xy 204.816942 -347.798209) (xy 204.816456 -347.770958) (xy 204.816456 -347.770704) (xy 204.816596 -347.756361)
			(xy 204.818759 -347.727756) (xy 204.820774 -347.713554) (xy 204.822806 -347.700346) (xy 204.813408 -347.675708)
			(xy 204.736446 -347.611192) (xy 204.729468 -347.605905) (xy 204.713039 -347.599903) (xy 204.695548 -347.599767)
			(xy 204.68717 -347.602302) (xy 204.657048 -347.612043) (xy 204.594616 -347.62251) (xy 204.562964 -347.62313)
			(xy 204.535592 -347.622702) (xy 204.481411 -347.614878) (xy 204.428907 -347.599381) (xy 204.37916 -347.57653)
			(xy 204.333196 -347.546796) (xy 204.312266 -347.52915) (xy 204.312012 -347.528896) (xy 204.304927 -347.523308)
			(xy 204.288009 -347.517062) (xy 204.278992 -347.516704) (xy 204.211936 -347.516704) (xy 204.202921 -347.517077)
			(xy 204.186004 -347.523313) (xy 204.178916 -347.528896) (xy 204.178916 -347.52915) (xy 204.178662 -347.52915)
			(xy 204.157711 -347.546766) (xy 204.111744 -347.576483) (xy 204.062002 -347.599324) (xy 204.009505 -347.61482)
			(xy 203.955332 -347.622654) (xy 203.927964 -347.62313) (xy 203.900716 -347.622597) (xy 203.846775 -347.614837)
			(xy 203.794488 -347.59948) (xy 203.744918 -347.576838) (xy 203.699075 -347.547372) (xy 203.657892 -347.511683)
			(xy 203.622206 -347.470496) (xy 203.592745 -347.42465) (xy 203.570108 -347.375078) (xy 203.554755 -347.322789)
			(xy 203.547 -347.268848) (xy 166.09206 -347.268848) (xy 166.090998 -347.269333) (xy 166.038703 -347.284688)
			(xy 165.984755 -347.292444) (xy 165.930253 -347.292444) (xy 165.876305 -347.284688) (xy 165.82401 -347.269333)
			(xy 165.774433 -347.246691) (xy 165.728583 -347.217225) (xy 165.687392 -347.181534) (xy 165.651701 -347.140343)
			(xy 165.622235 -347.094493) (xy 165.599593 -347.044916) (xy 165.584238 -346.992621) (xy 165.576482 -346.938673)
			(xy 165.575996 -346.911422) (xy 165.575996 -346.911168) (xy 165.576616 -346.880802) (xy 165.586247 -346.820838)
			(xy 165.605245 -346.763153) (xy 165.618668 -346.735908) (xy 165.624614 -346.723465) (xy 165.630247 -346.696478)
			(xy 165.628455 -346.668967) (xy 165.619367 -346.642939) (xy 165.603648 -346.620292) (xy 165.582442 -346.602675)
			(xy 165.557295 -346.591375) (xy 165.543738 -346.588842) (xy 165.517029 -346.584266) (xy 165.465153 -346.56861)
			(xy 165.416014 -346.545772) (xy 165.3706 -346.516212) (xy 165.329825 -346.480524) (xy 165.294508 -346.439427)
			(xy 165.265362 -346.393747) (xy 165.24297 -346.344402) (xy 165.227785 -346.292386) (xy 165.220112 -346.238745)
			(xy 165.219634 -346.211652) (xy 150.692104 -346.211652) (xy 150.692104 -348.96806) (xy 154.087574 -348.96806)
			(xy 154.091645 -348.912438) (xy 154.103771 -348.858001) (xy 154.123694 -348.80591) (xy 154.15099 -348.757275)
			(xy 154.185076 -348.713132) (xy 154.225225 -348.674423) (xy 154.270583 -348.641972) (xy 154.320183 -348.616471)
			(xy 154.372967 -348.598464) (xy 154.42781 -348.588334) (xy 154.483544 -348.586297) (xy 154.538981 -348.592397)
			(xy 154.592938 -348.606503) (xy 154.644267 -348.628315) (xy 154.691873 -348.657369) (xy 154.734741 -348.693044)
			(xy 154.771958 -348.734581) (xy 154.802731 -348.781094) (xy 154.826403 -348.831591) (xy 154.842471 -348.884998)
			(xy 154.850591 -348.940174) (xy 154.8511 -348.96806) (xy 154.850591 -348.995946) (xy 154.842471 -349.051122)
			(xy 154.826403 -349.104529) (xy 154.802731 -349.155026) (xy 154.771958 -349.201539) (xy 154.734741 -349.243076)
			(xy 154.691873 -349.278751) (xy 154.644267 -349.307805) (xy 154.592938 -349.329617) (xy 154.538981 -349.343723)
			(xy 154.483544 -349.349823) (xy 154.42781 -349.347786) (xy 154.372967 -349.337656) (xy 154.320183 -349.319649)
			(xy 154.270583 -349.294148) (xy 154.225225 -349.261697) (xy 154.185076 -349.222988) (xy 154.15099 -349.178845)
			(xy 154.123694 -349.13021) (xy 154.103771 -349.078119) (xy 154.091645 -349.023682) (xy 154.087574 -348.96806)
			(xy 150.692104 -348.96806) (xy 150.692104 -354.568506) (xy 155.256992 -354.568506) (xy 155.256992 -352.988626)
			(xy 155.257588 -352.960686) (xy 155.266341 -352.905496) (xy 155.283607 -352.85235) (xy 155.30896 -352.802552)
			(xy 155.341778 -352.757325) (xy 155.361132 -352.737166) (xy 156.020262 -352.078036) (xy 156.026925 -352.070607)
			(xy 156.034526 -352.052181) (xy 156.034532 -352.03225) (xy 156.026942 -352.013819) (xy 156.020262 -352.006408)
			(xy 155.407614 -351.39376) (xy 155.388241 -351.37357) (xy 155.35534 -351.328316) (xy 155.329915 -351.278476)
			(xy 155.312591 -351.225275) (xy 155.303794 -351.170021) (xy 155.30322 -351.142046) (xy 155.30322 -347.995748)
			(xy 155.303772 -347.967768) (xy 155.312539 -347.912499) (xy 155.329848 -347.859284) (xy 155.355273 -347.809433)
			(xy 155.388186 -347.764176) (xy 155.407614 -347.744034) (xy 156.143198 -347.00845) (xy 156.160598 -346.991596)
			(xy 156.19917 -346.962292) (xy 156.241365 -346.938496) (xy 156.286399 -346.92065) (xy 156.309822 -346.91447)
			(xy 156.318204 -346.911676) (xy 156.342729 -346.901234) (xy 156.393962 -346.886519) (xy 156.446746 -346.879096)
			(xy 156.473398 -346.878656) (xy 156.500648 -346.87918) (xy 156.554592 -346.886935) (xy 156.606884 -346.902288)
			(xy 156.656459 -346.924926) (xy 156.702307 -346.954389) (xy 156.743497 -346.990076) (xy 156.779188 -347.031262)
			(xy 156.808656 -347.077108) (xy 156.831299 -347.12668) (xy 156.846657 -347.178971) (xy 156.854418 -347.232914)
			(xy 156.854906 -347.260164) (xy 156.854496 -347.287028) (xy 156.84695 -347.340223) (xy 156.832016 -347.391834)
			(xy 156.80999 -347.440839) (xy 156.781306 -347.48627) (xy 156.746533 -347.527228) (xy 156.706359 -347.562903)
			(xy 156.661577 -347.592589) (xy 156.613073 -347.615699) (xy 156.561807 -347.631777) (xy 156.535374 -347.636592)
			(xy 156.527754 -347.637862) (xy 156.51353 -347.644974) (xy 156.030422 -348.128336) (xy 156.023577 -348.135732)
			(xy 156.015859 -348.154334) (xy 156.015436 -348.164404) (xy 156.015436 -348.807278) (xy 158.315912 -348.807278)
			(xy 158.319983 -348.751656) (xy 158.332109 -348.697219) (xy 158.352032 -348.645128) (xy 158.379328 -348.596493)
			(xy 158.413414 -348.55235) (xy 158.453563 -348.513641) (xy 158.498921 -348.48119) (xy 158.548521 -348.455689)
			(xy 158.601305 -348.437682) (xy 158.656148 -348.427552) (xy 158.711882 -348.425515) (xy 158.767319 -348.431615)
			(xy 158.821276 -348.445721) (xy 158.872605 -348.467533) (xy 158.920211 -348.496587) (xy 158.963079 -348.532262)
			(xy 159.000296 -348.573799) (xy 159.031069 -348.620312) (xy 159.054741 -348.670809) (xy 159.070809 -348.724216)
			(xy 159.078929 -348.779392) (xy 159.079438 -348.807278) (xy 159.078929 -348.835164) (xy 159.070809 -348.89034)
			(xy 159.054741 -348.943747) (xy 159.031069 -348.994244) (xy 159.000296 -349.040757) (xy 158.963079 -349.082294)
			(xy 158.920211 -349.117969) (xy 158.872605 -349.147023) (xy 158.821276 -349.168835) (xy 158.767319 -349.182941)
			(xy 158.711882 -349.189041) (xy 158.656148 -349.187004) (xy 158.601305 -349.176874) (xy 158.548521 -349.158867)
			(xy 158.498921 -349.133366) (xy 158.453563 -349.100915) (xy 158.413414 -349.062206) (xy 158.379328 -349.018063)
			(xy 158.352032 -348.969428) (xy 158.332109 -348.917337) (xy 158.319983 -348.8629) (xy 158.315912 -348.807278)
			(xy 156.015436 -348.807278) (xy 156.015436 -349.270828) (xy 156.241748 -349.270828) (xy 156.245819 -349.215206)
			(xy 156.257945 -349.160769) (xy 156.277868 -349.108678) (xy 156.305164 -349.060043) (xy 156.33925 -349.0159)
			(xy 156.379399 -348.977191) (xy 156.424757 -348.94474) (xy 156.474357 -348.919239) (xy 156.527141 -348.901232)
			(xy 156.581984 -348.891102) (xy 156.637718 -348.889065) (xy 156.693155 -348.895165) (xy 156.747112 -348.909271)
			(xy 156.798441 -348.931083) (xy 156.846047 -348.960137) (xy 156.888915 -348.995812) (xy 156.926132 -349.037349)
			(xy 156.956905 -349.083862) (xy 156.980577 -349.134359) (xy 156.996645 -349.187766) (xy 157.004765 -349.242942)
			(xy 157.005274 -349.270828) (xy 157.004765 -349.298714) (xy 157.000421 -349.328232) (xy 165.391846 -349.328232)
			(xy 165.392346 -349.30034) (xy 165.400459 -349.245149) (xy 165.416529 -349.19173) (xy 165.440215 -349.141225)
			(xy 165.47101 -349.094712) (xy 165.508257 -349.053184) (xy 165.551158 -349.017529) (xy 165.574726 -349.002604)
			(xy 165.583715 -348.996529) (xy 165.595954 -348.978641) (xy 165.598348 -348.96806) (xy 165.611556 -348.892876)
			(xy 165.612903 -348.882232) (xy 165.60766 -348.861452) (xy 165.601396 -348.852744) (xy 165.601396 -348.85249)
			(xy 165.585731 -348.832176) (xy 165.55946 -348.788114) (xy 165.539321 -348.740933) (xy 165.525677 -348.691482)
			(xy 165.518773 -348.640649) (xy 165.518338 -348.615) (xy 165.518907 -348.586442) (xy 165.527415 -348.529964)
			(xy 165.544241 -348.475384) (xy 165.569009 -348.423918) (xy 165.601167 -348.376716) (xy 165.620192 -348.355412)
			(xy 165.62705 -348.348046) (xy 165.633908 -348.330012) (xy 165.632384 -348.239334) (xy 165.624764 -348.221554)
			(xy 165.617652 -348.214442) (xy 165.596896 -348.192852) (xy 165.561726 -348.14438) (xy 165.534565 -348.091007)
			(xy 165.516081 -348.034044) (xy 165.506728 -347.974892) (xy 165.506146 -347.944948) (xy 165.506632 -347.917697)
			(xy 165.514388 -347.863749) (xy 165.529743 -347.811454) (xy 165.552385 -347.761877) (xy 165.581851 -347.716027)
			(xy 165.617542 -347.674836) (xy 165.658733 -347.639145) (xy 165.704583 -347.609679) (xy 165.75416 -347.587037)
			(xy 165.806455 -347.571682) (xy 165.860403 -347.563926) (xy 165.914905 -347.563926) (xy 165.968853 -347.571682)
			(xy 166.021148 -347.587037) (xy 166.070725 -347.609679) (xy 166.116575 -347.639145) (xy 166.157766 -347.674836)
			(xy 166.193457 -347.716027) (xy 166.222923 -347.761877) (xy 166.245565 -347.811454) (xy 166.26092 -347.863749)
			(xy 166.268676 -347.917697) (xy 166.269162 -347.944948) (xy 166.268622 -347.973507) (xy 166.264541 -348.000574)
			(xy 167.718484 -348.000574) (xy 167.722555 -347.944952) (xy 167.734681 -347.890515) (xy 167.754604 -347.838424)
			(xy 167.7819 -347.789789) (xy 167.815986 -347.745646) (xy 167.856135 -347.706937) (xy 167.901493 -347.674486)
			(xy 167.951093 -347.648985) (xy 168.003877 -347.630978) (xy 168.05872 -347.620848) (xy 168.114454 -347.618811)
			(xy 168.169891 -347.624911) (xy 168.223848 -347.639017) (xy 168.275177 -347.660829) (xy 168.322783 -347.689883)
			(xy 168.365651 -347.725558) (xy 168.402868 -347.767095) (xy 168.433641 -347.813608) (xy 168.457313 -347.864105)
			(xy 168.473381 -347.917512) (xy 168.481501 -347.972688) (xy 168.48201 -348.000574) (xy 168.481501 -348.02846)
			(xy 168.473381 -348.083636) (xy 168.457313 -348.137043) (xy 168.433641 -348.18754) (xy 168.402868 -348.234053)
			(xy 168.365651 -348.27559) (xy 168.322783 -348.311265) (xy 168.275177 -348.340319) (xy 168.223848 -348.362131)
			(xy 168.169891 -348.376237) (xy 168.114454 -348.382337) (xy 168.05872 -348.3803) (xy 168.003877 -348.37017)
			(xy 167.951093 -348.352163) (xy 167.901493 -348.326662) (xy 167.856135 -348.294211) (xy 167.815986 -348.255502)
			(xy 167.7819 -348.211359) (xy 167.754604 -348.162724) (xy 167.734681 -348.110633) (xy 167.722555 -348.056196)
			(xy 167.718484 -348.000574) (xy 166.264541 -348.000574) (xy 166.260107 -348.029986) (xy 166.243274 -348.084567)
			(xy 166.2185 -348.136032) (xy 166.186336 -348.183232) (xy 166.167308 -348.204536) (xy 166.16045 -348.211902)
			(xy 166.153592 -348.229936) (xy 166.155116 -348.320614) (xy 166.162736 -348.338394) (xy 166.169848 -348.345506)
			(xy 166.190579 -348.367119) (xy 166.225752 -348.415585) (xy 166.252918 -348.468952) (xy 166.271408 -348.52591)
			(xy 166.280768 -348.585058) (xy 166.281354 -348.615) (xy 166.280879 -348.642893) (xy 166.272762 -348.698085)
			(xy 166.256687 -348.751504) (xy 166.232997 -348.80201) (xy 166.202198 -348.848523) (xy 166.164948 -348.89005)
			(xy 166.122043 -348.925703) (xy 166.098474 -348.940628) (xy 166.089474 -348.946689) (xy 166.077241 -348.964587)
			(xy 166.074852 -348.975172) (xy 166.061644 -349.050356) (xy 166.060279 -349.060999) (xy 166.065535 -349.081781)
			(xy 166.071804 -349.090488) (xy 166.071804 -349.090742) (xy 166.087438 -349.111079) (xy 166.113714 -349.155134)
			(xy 166.133859 -349.202309) (xy 166.14751 -349.251756) (xy 166.154423 -349.302584) (xy 166.154862 -349.328232)
			(xy 166.154275 -349.359057) (xy 166.144345 -349.419902) (xy 166.124751 -349.478355) (xy 166.096003 -349.532892)
			(xy 166.0779 -349.557848) (xy 166.072057 -349.566446) (xy 166.067217 -349.586646) (xy 166.068502 -349.596964)
			(xy 166.080948 -349.669862) (xy 166.083133 -349.680028) (xy 166.094427 -349.697465) (xy 166.102792 -349.703644)
			(xy 166.121171 -349.716344) (xy 168.5704 -349.716344) (xy 168.574471 -349.660722) (xy 168.586597 -349.606285)
			(xy 168.60652 -349.554194) (xy 168.633816 -349.505559) (xy 168.667902 -349.461416) (xy 168.708051 -349.422707)
			(xy 168.753409 -349.390256) (xy 168.803009 -349.364755) (xy 168.855793 -349.346748) (xy 168.910636 -349.336618)
			(xy 168.96637 -349.334581) (xy 169.021807 -349.340681) (xy 169.075764 -349.354787) (xy 169.127093 -349.376599)
			(xy 169.174699 -349.405653) (xy 169.217567 -349.441328) (xy 169.254784 -349.482865) (xy 169.285557 -349.529378)
			(xy 169.309229 -349.579875) (xy 169.325297 -349.633282) (xy 169.333417 -349.688458) (xy 169.333926 -349.716344)
			(xy 169.333417 -349.74423) (xy 169.325297 -349.799406) (xy 169.309229 -349.852813) (xy 169.285557 -349.90331)
			(xy 169.254784 -349.949823) (xy 169.217567 -349.99136) (xy 169.174699 -350.027035) (xy 169.127093 -350.056089)
			(xy 169.075764 -350.077901) (xy 169.021807 -350.092007) (xy 168.96637 -350.098107) (xy 168.910636 -350.09607)
			(xy 168.855793 -350.08594) (xy 168.803009 -350.067933) (xy 168.753409 -350.042432) (xy 168.708051 -350.009981)
			(xy 168.667902 -349.971272) (xy 168.633816 -349.927129) (xy 168.60652 -349.878494) (xy 168.586597 -349.826403)
			(xy 168.574471 -349.771966) (xy 168.5704 -349.716344) (xy 166.121171 -349.716344) (xy 166.124874 -349.718903)
			(xy 166.164991 -349.754562) (xy 166.199711 -349.795494) (xy 166.228348 -349.840891) (xy 166.250337 -349.889854)
			(xy 166.265242 -349.941417) (xy 166.272769 -349.994561) (xy 166.273226 -350.021398) (xy 166.27274 -350.048649)
			(xy 166.264984 -350.102597) (xy 166.249629 -350.154892) (xy 166.226987 -350.204469) (xy 166.197521 -350.250319)
			(xy 166.16183 -350.29151) (xy 166.120639 -350.327201) (xy 166.074789 -350.356667) (xy 166.025212 -350.379309)
			(xy 165.972917 -350.394664) (xy 165.918969 -350.40242) (xy 165.864467 -350.40242) (xy 165.810519 -350.394664)
			(xy 165.758224 -350.379309) (xy 165.708647 -350.356667) (xy 165.662797 -350.327201) (xy 165.621606 -350.29151)
			(xy 165.585915 -350.250319) (xy 165.556449 -350.204469) (xy 165.533807 -350.154892) (xy 165.518452 -350.102597)
			(xy 165.510696 -350.048649) (xy 165.51021 -350.021398) (xy 165.510819 -349.990574) (xy 165.520742 -349.92973)
			(xy 165.540331 -349.871277) (xy 165.569073 -349.81674) (xy 165.587172 -349.791782) (xy 165.592998 -349.783173)
			(xy 165.597849 -349.762982) (xy 165.59657 -349.752666) (xy 165.584124 -349.679768) (xy 165.581899 -349.669614)
			(xy 165.570631 -349.652173) (xy 165.56228 -349.645986) (xy 165.540159 -349.63078) (xy 165.500044 -349.595112)
			(xy 165.465328 -349.55417) (xy 165.436696 -349.508764) (xy 165.414714 -349.459792) (xy 165.399817 -349.408222)
			(xy 165.392299 -349.355072) (xy 165.391846 -349.328232) (xy 157.000421 -349.328232) (xy 156.996645 -349.35389)
			(xy 156.980577 -349.407297) (xy 156.956905 -349.457794) (xy 156.926132 -349.504307) (xy 156.888915 -349.545844)
			(xy 156.846047 -349.581519) (xy 156.798441 -349.610573) (xy 156.747112 -349.632385) (xy 156.693155 -349.646491)
			(xy 156.637718 -349.652591) (xy 156.581984 -349.650554) (xy 156.527141 -349.640424) (xy 156.474357 -349.622417)
			(xy 156.424757 -349.596916) (xy 156.379399 -349.564465) (xy 156.33925 -349.525756) (xy 156.305164 -349.481613)
			(xy 156.277868 -349.432978) (xy 156.257945 -349.380887) (xy 156.245819 -349.32645) (xy 156.241748 -349.270828)
			(xy 156.015436 -349.270828) (xy 156.015436 -350.091502) (xy 158.361886 -350.091502) (xy 158.365957 -350.03588)
			(xy 158.378083 -349.981443) (xy 158.398006 -349.929352) (xy 158.425302 -349.880717) (xy 158.459388 -349.836574)
			(xy 158.499537 -349.797865) (xy 158.544895 -349.765414) (xy 158.594495 -349.739913) (xy 158.647279 -349.721906)
			(xy 158.702122 -349.711776) (xy 158.757856 -349.709739) (xy 158.813293 -349.715839) (xy 158.86725 -349.729945)
			(xy 158.918579 -349.751757) (xy 158.966185 -349.780811) (xy 159.009053 -349.816486) (xy 159.04627 -349.858023)
			(xy 159.077043 -349.904536) (xy 159.100715 -349.955033) (xy 159.116783 -350.00844) (xy 159.124903 -350.063616)
			(xy 159.125412 -350.091502) (xy 159.124903 -350.119388) (xy 159.116783 -350.174564) (xy 159.100715 -350.227971)
			(xy 159.077043 -350.278468) (xy 159.04627 -350.324981) (xy 159.009053 -350.366518) (xy 158.966185 -350.402193)
			(xy 158.918579 -350.431247) (xy 158.86725 -350.453059) (xy 158.813293 -350.467165) (xy 158.757856 -350.473265)
			(xy 158.702122 -350.471228) (xy 158.647279 -350.461098) (xy 158.594495 -350.443091) (xy 158.544895 -350.41759)
			(xy 158.499537 -350.385139) (xy 158.459388 -350.34643) (xy 158.425302 -350.302287) (xy 158.398006 -350.253652)
			(xy 158.378083 -350.201561) (xy 158.365957 -350.147124) (xy 158.361886 -350.091502) (xy 156.015436 -350.091502)
			(xy 156.015436 -350.732344) (xy 168.5704 -350.732344) (xy 168.574471 -350.676722) (xy 168.586597 -350.622285)
			(xy 168.60652 -350.570194) (xy 168.633816 -350.521559) (xy 168.667902 -350.477416) (xy 168.708051 -350.438707)
			(xy 168.753409 -350.406256) (xy 168.803009 -350.380755) (xy 168.855793 -350.362748) (xy 168.910636 -350.352618)
			(xy 168.96637 -350.350581) (xy 169.021807 -350.356681) (xy 169.075764 -350.370787) (xy 169.127093 -350.392599)
			(xy 169.174699 -350.421653) (xy 169.217567 -350.457328) (xy 169.254784 -350.498865) (xy 169.285557 -350.545378)
			(xy 169.309229 -350.595875) (xy 169.325297 -350.649282) (xy 169.333417 -350.704458) (xy 169.333926 -350.732344)
			(xy 169.333417 -350.76023) (xy 169.325297 -350.815406) (xy 169.309229 -350.868813) (xy 169.285557 -350.91931)
			(xy 169.254784 -350.965823) (xy 169.217567 -351.00736) (xy 169.174699 -351.043035) (xy 169.127093 -351.072089)
			(xy 169.075764 -351.093901) (xy 169.021807 -351.108007) (xy 168.96637 -351.114107) (xy 168.910636 -351.11207)
			(xy 168.855793 -351.10194) (xy 168.803009 -351.083933) (xy 168.753409 -351.058432) (xy 168.708051 -351.025981)
			(xy 168.667902 -350.987272) (xy 168.633816 -350.943129) (xy 168.60652 -350.894494) (xy 168.586597 -350.842403)
			(xy 168.574471 -350.787966) (xy 168.5704 -350.732344) (xy 156.015436 -350.732344) (xy 156.015436 -350.97339)
			(xy 156.015857 -350.98346) (xy 156.02358 -351.002058) (xy 156.030422 -351.009458) (xy 156.418909 -351.398078)
			(xy 158.417512 -351.398078) (xy 158.421583 -351.342456) (xy 158.433709 -351.288019) (xy 158.453632 -351.235928)
			(xy 158.480928 -351.187293) (xy 158.515014 -351.14315) (xy 158.555163 -351.104441) (xy 158.600521 -351.07199)
			(xy 158.650121 -351.046489) (xy 158.702905 -351.028482) (xy 158.757748 -351.018352) (xy 158.813482 -351.016315)
			(xy 158.868919 -351.022415) (xy 158.922876 -351.036521) (xy 158.974205 -351.058333) (xy 159.021811 -351.087387)
			(xy 159.064679 -351.123062) (xy 159.101896 -351.164599) (xy 159.132669 -351.211112) (xy 159.156341 -351.261609)
			(xy 159.172409 -351.315016) (xy 159.180529 -351.370192) (xy 159.181038 -351.398078) (xy 159.180529 -351.425964)
			(xy 159.172409 -351.48114) (xy 159.156341 -351.534547) (xy 159.132669 -351.585044) (xy 159.12092 -351.602802)
			(xy 159.687512 -351.602802) (xy 159.691583 -351.54718) (xy 159.703709 -351.492743) (xy 159.723632 -351.440652)
			(xy 159.750928 -351.392017) (xy 159.785014 -351.347874) (xy 159.825163 -351.309165) (xy 159.870521 -351.276714)
			(xy 159.920121 -351.251213) (xy 159.972905 -351.233206) (xy 160.027748 -351.223076) (xy 160.083482 -351.221039)
			(xy 160.138919 -351.227139) (xy 160.192876 -351.241245) (xy 160.244205 -351.263057) (xy 160.291811 -351.292111)
			(xy 160.334679 -351.327786) (xy 160.371896 -351.369323) (xy 160.402669 -351.415836) (xy 160.426341 -351.466333)
			(xy 160.442409 -351.51974) (xy 160.450529 -351.574916) (xy 160.451038 -351.602802) (xy 160.450529 -351.630688)
			(xy 160.443367 -351.679356) (xy 160.907633 -351.679356) (xy 160.907633 -351.624844) (xy 160.915391 -351.570887)
			(xy 160.93075 -351.518584) (xy 160.953396 -351.468999) (xy 160.982868 -351.423142) (xy 161.018567 -351.381946)
			(xy 161.059766 -351.34625) (xy 161.105625 -351.316781) (xy 161.155212 -351.294139) (xy 161.207517 -351.278785)
			(xy 161.261474 -351.271031) (xy 161.28873 -351.27057) (xy 161.314483 -351.27099) (xy 161.36552 -351.277935)
			(xy 161.415158 -351.291681) (xy 161.462497 -351.311979) (xy 161.506676 -351.338459) (xy 161.546892 -351.37064)
			(xy 161.582414 -351.407938) (xy 161.597848 -351.428558) (xy 161.606183 -351.439287) (xy 161.627314 -351.456343)
			(xy 161.652198 -351.467214) (xy 161.679069 -351.471129) (xy 161.706021 -351.467811) (xy 161.73114 -351.457494)
			(xy 161.752644 -351.440912) (xy 161.76117 -351.430336) (xy 161.779334 -351.407289) (xy 161.8215 -351.366484)
			(xy 161.869419 -351.33262) (xy 161.921961 -351.306498) (xy 161.977885 -351.288733) (xy 162.035869 -351.279745)
			(xy 162.065208 -351.279206) (xy 162.065462 -351.279206) (xy 162.092718 -351.279638) (xy 162.146675 -351.287391)
			(xy 162.198979 -351.302744) (xy 162.248566 -351.325386) (xy 162.294426 -351.354854) (xy 162.335624 -351.390549)
			(xy 162.371323 -351.431744) (xy 162.400796 -351.477601) (xy 162.423442 -351.527185) (xy 162.437965 -351.57664)
			(xy 164.057836 -351.57664) (xy 164.061907 -351.521018) (xy 164.074033 -351.466581) (xy 164.093956 -351.41449)
			(xy 164.121252 -351.365855) (xy 164.155338 -351.321712) (xy 164.195487 -351.283003) (xy 164.240845 -351.250552)
			(xy 164.290445 -351.225051) (xy 164.343229 -351.207044) (xy 164.398072 -351.196914) (xy 164.453806 -351.194877)
			(xy 164.509243 -351.200977) (xy 164.5632 -351.215083) (xy 164.614529 -351.236895) (xy 164.662135 -351.265949)
			(xy 164.705003 -351.301624) (xy 164.74222 -351.343161) (xy 164.772993 -351.389674) (xy 164.796665 -351.440171)
			(xy 164.812733 -351.493578) (xy 164.820853 -351.548754) (xy 164.821362 -351.57664) (xy 164.820853 -351.604526)
			(xy 164.812733 -351.659702) (xy 164.796665 -351.713109) (xy 164.772993 -351.763606) (xy 164.74222 -351.810119)
			(xy 164.705003 -351.851656) (xy 164.662135 -351.887331) (xy 164.614529 -351.916385) (xy 164.5632 -351.938197)
			(xy 164.509243 -351.952303) (xy 164.453806 -351.958403) (xy 164.398072 -351.956366) (xy 164.343229 -351.946236)
			(xy 164.290445 -351.928229) (xy 164.240845 -351.902728) (xy 164.195487 -351.870277) (xy 164.155338 -351.831568)
			(xy 164.121252 -351.787425) (xy 164.093956 -351.73879) (xy 164.074033 -351.686699) (xy 164.061907 -351.632262)
			(xy 164.057836 -351.57664) (xy 162.437965 -351.57664) (xy 162.438801 -351.579488) (xy 162.446559 -351.633444)
			(xy 162.446559 -351.687956) (xy 162.438801 -351.741912) (xy 162.423442 -351.794215) (xy 162.400796 -351.843799)
			(xy 162.371323 -351.889656) (xy 162.335624 -351.930851) (xy 162.294426 -351.966546) (xy 162.248566 -351.996014)
			(xy 162.198979 -352.018656) (xy 162.146675 -352.034009) (xy 162.092718 -352.041762) (xy 162.065462 -352.042222)
			(xy 162.039708 -352.041811) (xy 161.988671 -352.034865) (xy 161.939033 -352.021117) (xy 161.891694 -352.000818)
			(xy 161.847515 -351.974337) (xy 161.807299 -351.942154) (xy 161.771778 -351.904855) (xy 161.756344 -351.884234)
			(xy 161.748018 -351.873497) (xy 161.726885 -351.856443) (xy 161.701999 -351.845574) (xy 161.675126 -351.84166)
			(xy 161.648173 -351.844979) (xy 161.623053 -351.855297) (xy 161.601548 -351.87188) (xy 161.593022 -351.882456)
			(xy 161.57486 -351.905505) (xy 161.532694 -351.94631) (xy 161.484774 -351.980174) (xy 161.432232 -352.006296)
			(xy 161.376308 -352.024061) (xy 161.318323 -352.033048) (xy 161.288984 -352.033586) (xy 161.28873 -352.033586)
			(xy 161.261474 -352.033169) (xy 161.207517 -352.025415) (xy 161.155212 -352.010061) (xy 161.105625 -351.987419)
			(xy 161.059766 -351.95795) (xy 161.018567 -351.922254) (xy 160.982868 -351.881058) (xy 160.953396 -351.835201)
			(xy 160.93075 -351.785616) (xy 160.915391 -351.733313) (xy 160.907633 -351.679356) (xy 160.443367 -351.679356)
			(xy 160.442409 -351.685864) (xy 160.426341 -351.739271) (xy 160.402669 -351.789768) (xy 160.371896 -351.836281)
			(xy 160.334679 -351.877818) (xy 160.291811 -351.913493) (xy 160.244205 -351.942547) (xy 160.192876 -351.964359)
			(xy 160.138919 -351.978465) (xy 160.083482 -351.984565) (xy 160.027748 -351.982528) (xy 159.972905 -351.972398)
			(xy 159.920121 -351.954391) (xy 159.870521 -351.92889) (xy 159.825163 -351.896439) (xy 159.785014 -351.85773)
			(xy 159.750928 -351.813587) (xy 159.723632 -351.764952) (xy 159.703709 -351.712861) (xy 159.691583 -351.658424)
			(xy 159.687512 -351.602802) (xy 159.12092 -351.602802) (xy 159.101896 -351.631557) (xy 159.064679 -351.673094)
			(xy 159.021811 -351.708769) (xy 158.974205 -351.737823) (xy 158.922876 -351.759635) (xy 158.868919 -351.773741)
			(xy 158.813482 -351.779841) (xy 158.757748 -351.777804) (xy 158.702905 -351.767674) (xy 158.650121 -351.749667)
			(xy 158.600521 -351.724166) (xy 158.555163 -351.691715) (xy 158.515014 -351.653006) (xy 158.480928 -351.608863)
			(xy 158.453632 -351.560228) (xy 158.433709 -351.508137) (xy 158.421583 -351.4537) (xy 158.417512 -351.398078)
			(xy 156.418909 -351.398078) (xy 156.774642 -351.753932) (xy 156.78277 -351.757742) (xy 156.806952 -351.769697)
			(xy 156.852025 -351.79933) (xy 156.892476 -351.835015) (xy 156.927499 -351.876041) (xy 156.956396 -351.92159)
			(xy 156.978591 -351.970754) (xy 156.993641 -352.022554) (xy 157.001247 -352.075957) (xy 157.001718 -352.102928)
			(xy 157.001187 -352.131928) (xy 156.992405 -352.189259) (xy 156.975045 -352.2446) (xy 156.94951 -352.296675)
			(xy 156.916387 -352.344286) (xy 156.876439 -352.386335) (xy 156.830587 -352.421854) (xy 156.779887 -352.450023)
			(xy 156.725508 -352.470193) (xy 156.668702 -352.481901) (xy 156.639768 -352.483928) (xy 156.630471 -352.484822)
			(xy 156.613409 -352.492382) (xy 156.606494 -352.49866) (xy 156.154882 -352.950272) (xy 178.85537 -352.950272)
			(xy 178.855851 -352.922361) (xy 178.863989 -352.867135) (xy 178.880088 -352.813684) (xy 178.903803 -352.763149)
			(xy 178.934629 -352.71661) (xy 178.952906 -352.69551) (xy 178.958799 -352.68833) (xy 178.965452 -352.671007)
			(xy 178.96586 -352.661728) (xy 178.96586 -352.584004) (xy 178.959256 -352.566732) (xy 178.952906 -352.55962)
			(xy 178.934617 -352.538529) (xy 178.903791 -352.491989) (xy 178.880078 -352.441452) (xy 178.863984 -352.387998)
			(xy 178.855853 -352.33277) (xy 178.85537 -352.304858) (xy 178.855856 -352.277607) (xy 178.863612 -352.223659)
			(xy 178.878967 -352.171364) (xy 178.901609 -352.121787) (xy 178.931075 -352.075937) (xy 178.966766 -352.034746)
			(xy 179.007957 -351.999055) (xy 179.053807 -351.969589) (xy 179.103384 -351.946947) (xy 179.155679 -351.931592)
			(xy 179.209627 -351.923836) (xy 179.264129 -351.923836) (xy 179.318077 -351.931592) (xy 179.370372 -351.946947)
			(xy 179.419949 -351.969589) (xy 179.465799 -351.999055) (xy 179.50699 -352.034746) (xy 179.542681 -352.075937)
			(xy 179.572147 -352.121787) (xy 179.594789 -352.171364) (xy 179.610144 -352.223659) (xy 179.6179 -352.277607)
			(xy 179.618386 -352.304858) (xy 179.617909 -352.332769) (xy 179.609768 -352.387995) (xy 179.593667 -352.441445)
			(xy 179.569952 -352.491979) (xy 179.539127 -352.538519) (xy 179.52085 -352.55962) (xy 179.514939 -352.566787)
			(xy 179.508298 -352.58412) (xy 179.507896 -352.593402) (xy 179.507896 -352.671126) (xy 179.5145 -352.688398)
			(xy 179.52085 -352.69551) (xy 179.539115 -352.71662) (xy 179.569943 -352.763156) (xy 179.593659 -352.813688)
			(xy 179.609759 -352.867137) (xy 179.617898 -352.922362) (xy 179.618386 -352.950272) (xy 179.6179 -352.977523)
			(xy 179.610144 -353.031471) (xy 179.594789 -353.083766) (xy 179.572147 -353.133343) (xy 179.542681 -353.179193)
			(xy 179.50699 -353.220384) (xy 179.465799 -353.256075) (xy 179.422658 -353.2838) (xy 183.237633 -353.2838)
			(xy 183.241801 -353.228186) (xy 183.25421 -353.173815) (xy 183.274583 -353.1219) (xy 183.302466 -353.073601)
			(xy 183.337236 -353.029997) (xy 183.378116 -352.992062) (xy 183.424192 -352.960642) (xy 183.474437 -352.936441)
			(xy 183.527727 -352.919998) (xy 183.582873 -352.91168) (xy 183.610758 -352.911156) (xy 183.63718 -352.91159)
			(xy 183.689497 -352.919048) (xy 183.740235 -352.933819) (xy 183.788379 -352.955607) (xy 183.832963 -352.983977)
			(xy 183.853328 -353.000818) (xy 183.860186 -353.00666) (xy 183.877204 -353.01301) (xy 183.961532 -353.01301)
			(xy 183.97855 -353.00666) (xy 183.985408 -353.000818) (xy 184.005774 -352.983979) (xy 184.05036 -352.955614)
			(xy 184.098504 -352.933827) (xy 184.149241 -352.919056) (xy 184.201556 -352.911596) (xy 184.2544 -352.911596)
			(xy 184.306715 -352.919056) (xy 184.357452 -352.933827) (xy 184.405596 -352.955614) (xy 184.450182 -352.983979)
			(xy 184.470548 -353.000818) (xy 184.477406 -353.00666) (xy 184.494424 -353.01301) (xy 184.578752 -353.01301)
			(xy 184.59577 -353.00666) (xy 184.602628 -353.000818) (xy 184.614414 -352.990981) (xy 184.639338 -352.973051)
			(xy 184.652412 -352.965004) (xy 184.652666 -352.96475) (xy 184.661833 -352.958508) (xy 184.674091 -352.94006)
			(xy 184.676288 -352.92919) (xy 184.690004 -352.840798) (xy 184.683654 -352.819208) (xy 184.676034 -352.810826)
			(xy 184.658169 -352.789823) (xy 184.62806 -352.743633) (xy 184.604911 -352.69359) (xy 184.589205 -352.640736)
			(xy 184.58127 -352.586173) (xy 184.580784 -352.558604) (xy 184.581258 -352.53103) (xy 184.58921 -352.476458)
			(xy 184.604933 -352.423598) (xy 184.628102 -352.373552) (xy 184.658233 -352.327362) (xy 184.694698 -352.28599)
			(xy 184.715404 -352.267774) (xy 184.723492 -352.26023) (xy 184.732839 -352.24021) (xy 184.733438 -352.229166)
			(xy 184.733438 -352.151442) (xy 184.732866 -352.140393) (xy 184.723506 -352.12037) (xy 184.715404 -352.112834)
			(xy 184.694707 -352.094608) (xy 184.658235 -352.053242) (xy 184.628101 -352.007055) (xy 184.604933 -351.95701)
			(xy 184.589214 -351.904151) (xy 184.581271 -351.849578) (xy 184.580784 -351.822004) (xy 184.58127 -351.794753)
			(xy 184.589026 -351.740805) (xy 184.604381 -351.68851) (xy 184.627023 -351.638933) (xy 184.656489 -351.593083)
			(xy 184.69218 -351.551892) (xy 184.733371 -351.516201) (xy 184.779221 -351.486735) (xy 184.828798 -351.464093)
			(xy 184.881093 -351.448738) (xy 184.935041 -351.440982) (xy 184.989543 -351.440982) (xy 185.043491 -351.448738)
			(xy 185.095786 -351.464093) (xy 185.145363 -351.486735) (xy 185.191213 -351.516201) (xy 185.232404 -351.551892)
			(xy 185.268095 -351.593083) (xy 185.297561 -351.638933) (xy 185.320203 -351.68851) (xy 185.335558 -351.740805)
			(xy 185.343314 -351.794753) (xy 185.3438 -351.822004) (xy 185.343337 -351.849579) (xy 185.335384 -351.904152)
			(xy 185.319658 -351.957012) (xy 185.296488 -352.007057) (xy 185.266355 -352.053247) (xy 185.229887 -352.094618)
			(xy 185.20918 -352.112834) (xy 185.201086 -352.120372) (xy 185.191743 -352.140397) (xy 185.191146 -352.151442)
			(xy 185.191146 -352.229166) (xy 185.191719 -352.240215) (xy 185.201079 -352.260237) (xy 185.20918 -352.267774)
			(xy 185.229878 -352.286) (xy 185.26635 -352.327365) (xy 185.296484 -352.373552) (xy 185.319653 -352.423597)
			(xy 185.335372 -352.476457) (xy 185.343314 -352.53103) (xy 185.3438 -352.558604) (xy 185.343259 -352.587026)
			(xy 185.334845 -352.643242) (xy 185.318173 -352.697584) (xy 185.293614 -352.748848) (xy 185.261712 -352.795894)
			(xy 185.223177 -352.83768) (xy 185.178861 -352.873278) (xy 185.15457 -352.888042) (xy 185.144664 -352.89363)
			(xy 185.131964 -352.912172) (xy 185.121245 -352.975672) (xy 187.181998 -352.975672) (xy 187.182472 -352.94776)
			(xy 187.190611 -352.892534) (xy 187.20671 -352.839083) (xy 187.230427 -352.788548) (xy 187.261255 -352.742009)
			(xy 187.279534 -352.72091) (xy 187.285431 -352.713733) (xy 187.292081 -352.696407) (xy 187.292488 -352.687128)
			(xy 187.292488 -352.609404) (xy 187.285884 -352.592132) (xy 187.279534 -352.58502) (xy 187.261234 -352.563939)
			(xy 187.230412 -352.517395) (xy 187.206702 -352.466855) (xy 187.19061 -352.4134) (xy 187.182481 -352.35817)
			(xy 187.181998 -352.330258) (xy 187.182484 -352.303007) (xy 187.19024 -352.249059) (xy 187.205595 -352.196764)
			(xy 187.228237 -352.147187) (xy 187.257703 -352.101337) (xy 187.293394 -352.060146) (xy 187.334585 -352.024455)
			(xy 187.380435 -351.994989) (xy 187.430012 -351.972347) (xy 187.482307 -351.956992) (xy 187.536255 -351.949236)
			(xy 187.590757 -351.949236) (xy 187.644705 -351.956992) (xy 187.697 -351.972347) (xy 187.746577 -351.994989)
			(xy 187.792427 -352.024455) (xy 187.833618 -352.060146) (xy 187.869309 -352.101337) (xy 187.898775 -352.147187)
			(xy 187.921417 -352.196764) (xy 187.936772 -352.249059) (xy 187.944528 -352.303007) (xy 187.945014 -352.330258)
			(xy 187.944555 -352.35817) (xy 187.936412 -352.413397) (xy 187.920309 -352.466848) (xy 187.896589 -352.517383)
			(xy 187.865758 -352.563921) (xy 187.847478 -352.58502) (xy 187.84157 -352.592189) (xy 187.834926 -352.609521)
			(xy 187.834524 -352.618802) (xy 187.834524 -352.696526) (xy 187.841128 -352.713798) (xy 187.847478 -352.72091)
			(xy 187.865731 -352.74203) (xy 187.896563 -352.788562) (xy 187.920284 -352.839092) (xy 187.936386 -352.892539)
			(xy 187.944526 -352.947762) (xy 187.945014 -352.975672) (xy 187.944528 -353.002923) (xy 187.936772 -353.056871)
			(xy 187.921417 -353.109166) (xy 187.898775 -353.158743) (xy 187.869309 -353.204593) (xy 187.833618 -353.245784)
			(xy 187.792427 -353.281475) (xy 187.749286 -353.3092) (xy 191.564233 -353.3092) (xy 191.568401 -353.253584)
			(xy 191.580811 -353.19921) (xy 191.601187 -353.147293) (xy 191.629072 -353.098992) (xy 191.663845 -353.055387)
			(xy 191.704728 -353.017452) (xy 191.750809 -352.986033) (xy 191.801057 -352.961833) (xy 191.854351 -352.945392)
			(xy 191.9095 -352.937078) (xy 191.937386 -352.936556) (xy 191.963807 -352.937032) (xy 192.016121 -352.944479)
			(xy 192.066859 -352.959241) (xy 192.115004 -352.98102) (xy 192.15959 -353.009381) (xy 192.179956 -353.026218)
			(xy 192.186814 -353.03206) (xy 192.203832 -353.03841) (xy 192.28816 -353.03841) (xy 192.305178 -353.03206)
			(xy 192.312036 -353.026218) (xy 192.332402 -353.009379) (xy 192.376988 -352.981014) (xy 192.425132 -352.959227)
			(xy 192.475869 -352.944456) (xy 192.528184 -352.936996) (xy 192.581028 -352.936996) (xy 192.633343 -352.944456)
			(xy 192.68408 -352.959227) (xy 192.732224 -352.981014) (xy 192.77681 -353.009379) (xy 192.797176 -353.026218)
			(xy 192.804034 -353.03206) (xy 192.821052 -353.03841) (xy 192.90538 -353.03841) (xy 192.922398 -353.03206)
			(xy 192.929256 -353.026218) (xy 192.943154 -353.014639) (xy 192.972794 -352.993899) (xy 192.988438 -352.984816)
			(xy 192.998264 -352.978642) (xy 193.011493 -352.959605) (xy 193.013838 -352.94824) (xy 193.0273 -352.857054)
			(xy 193.020442 -352.834956) (xy 193.012314 -352.82632) (xy 192.992734 -352.804937) (xy 192.959615 -352.757351)
			(xy 192.934083 -352.705299) (xy 192.916729 -352.649981) (xy 192.907952 -352.592672) (xy 192.907412 -352.563684)
			(xy 192.907931 -352.536111) (xy 192.915872 -352.481541) (xy 192.931586 -352.428682) (xy 192.954746 -352.378635)
			(xy 192.98487 -352.332444) (xy 193.021329 -352.291071) (xy 193.042032 -352.272854) (xy 193.050133 -352.265323)
			(xy 193.059472 -352.245293) (xy 193.060066 -352.234246) (xy 193.060066 -352.156522) (xy 193.059497 -352.145473)
			(xy 193.050133 -352.125451) (xy 193.042032 -352.117914) (xy 193.021331 -352.099692) (xy 192.984858 -352.058326)
			(xy 192.954724 -352.012139) (xy 192.931556 -351.962093) (xy 192.915838 -351.909232) (xy 192.907898 -351.854658)
			(xy 192.907412 -351.827084) (xy 192.907898 -351.799833) (xy 192.915654 -351.745885) (xy 192.931009 -351.69359)
			(xy 192.953651 -351.644013) (xy 192.983117 -351.598163) (xy 193.018808 -351.556972) (xy 193.059999 -351.521281)
			(xy 193.105849 -351.491815) (xy 193.155426 -351.469173) (xy 193.207721 -351.453818) (xy 193.261669 -351.446062)
			(xy 193.316171 -351.446062) (xy 193.370119 -351.453818) (xy 193.422414 -351.469173) (xy 193.471991 -351.491815)
			(xy 193.517841 -351.521281) (xy 193.559032 -351.556972) (xy 193.594723 -351.598163) (xy 193.624189 -351.644013)
			(xy 193.646831 -351.69359) (xy 193.662186 -351.745885) (xy 193.669942 -351.799833) (xy 193.670428 -351.827084)
			(xy 193.669942 -351.854658) (xy 193.661992 -351.909229) (xy 193.64627 -351.962088) (xy 193.623104 -352.012134)
			(xy 193.592976 -352.058324) (xy 193.556513 -352.099697) (xy 193.535808 -352.117914) (xy 193.527727 -352.125465)
			(xy 193.518376 -352.145479) (xy 193.517774 -352.156522) (xy 193.517774 -352.234246) (xy 193.518349 -352.245295)
			(xy 193.527707 -352.265318) (xy 193.535808 -352.272854) (xy 193.556502 -352.291084) (xy 193.592973 -352.332449)
			(xy 193.623107 -352.378635) (xy 193.646276 -352.428679) (xy 193.661996 -352.481538) (xy 193.66994 -352.53611)
			(xy 193.670428 -352.563684) (xy 193.669837 -352.592875) (xy 193.660932 -352.650574) (xy 193.643341 -352.706243)
			(xy 193.617476 -352.758583) (xy 193.583941 -352.806372) (xy 193.543517 -352.848496) (xy 193.497149 -352.88397)
			(xy 193.4718 -352.898456) (xy 193.461878 -352.904519) (xy 193.448379 -352.923421) (xy 193.445892 -352.934778)
			(xy 193.430906 -353.02571) (xy 193.437764 -353.047808) (xy 193.445638 -353.056444) (xy 193.464098 -353.077219)
			(xy 193.495309 -353.123201) (xy 193.519344 -353.173309) (xy 193.535671 -353.22643) (xy 193.543929 -353.281387)
			(xy 193.544444 -353.309174) (xy 193.543919 -353.335788) (xy 193.536348 -353.388476) (xy 193.521355 -353.43955)
			(xy 193.499246 -353.48797) (xy 193.470472 -353.53275) (xy 193.435617 -353.572981) (xy 193.395392 -353.607841)
			(xy 193.350615 -353.636621) (xy 193.302198 -353.658737) (xy 193.251127 -353.673737) (xy 193.19844 -353.681316)
			(xy 193.171826 -353.681792) (xy 193.145405 -353.681321) (xy 193.09309 -353.673875) (xy 193.042351 -353.659113)
			(xy 192.994207 -353.637332) (xy 192.949621 -353.608969) (xy 192.929256 -353.59213) (xy 192.922398 -353.586288)
			(xy 192.90538 -353.579938) (xy 192.821052 -353.579938) (xy 192.804034 -353.586288) (xy 192.797176 -353.59213)
			(xy 192.77681 -353.608969) (xy 192.732224 -353.637334) (xy 192.68408 -353.659121) (xy 192.633343 -353.673892)
			(xy 192.581028 -353.681352) (xy 192.528184 -353.681352) (xy 192.475869 -353.673892) (xy 192.425132 -353.659121)
			(xy 192.376988 -353.637334) (xy 192.332402 -353.608969) (xy 192.312036 -353.59213) (xy 192.305178 -353.586288)
			(xy 192.28816 -353.579938) (xy 192.203832 -353.579938) (xy 192.186814 -353.586288) (xy 192.179956 -353.59213)
			(xy 192.159598 -353.608978) (xy 192.115007 -353.637334) (xy 192.066861 -353.659112) (xy 192.016122 -353.673877)
			(xy 191.963808 -353.681334) (xy 191.937386 -353.681792) (xy 191.9095 -353.681322) (xy 191.854351 -353.673008)
			(xy 191.801057 -353.656567) (xy 191.750809 -353.632367) (xy 191.704728 -353.600948) (xy 191.663845 -353.563013)
			(xy 191.629072 -353.519408) (xy 191.601187 -353.471107) (xy 191.580811 -353.41919) (xy 191.568401 -353.364816)
			(xy 191.564233 -353.3092) (xy 187.749286 -353.3092) (xy 187.746577 -353.310941) (xy 187.697 -353.333583)
			(xy 187.644705 -353.348938) (xy 187.590757 -353.356694) (xy 187.536255 -353.356694) (xy 187.482307 -353.348938)
			(xy 187.430012 -353.333583) (xy 187.380435 -353.310941) (xy 187.334585 -353.281475) (xy 187.293394 -353.245784)
			(xy 187.257703 -353.204593) (xy 187.228237 -353.158743) (xy 187.205595 -353.109166) (xy 187.19024 -353.056871)
			(xy 187.182484 -353.002923) (xy 187.181998 -352.975672) (xy 185.121245 -352.975672) (xy 185.1152 -353.011486)
			(xy 185.121296 -353.033076) (xy 185.128662 -353.041712) (xy 185.145403 -353.062036) (xy 185.173607 -353.106501)
			(xy 185.195266 -353.154496) (xy 185.209948 -353.205062) (xy 185.217362 -353.257192) (xy 185.217816 -353.28352)
			(xy 185.217816 -353.283774) (xy 185.217342 -353.310391) (xy 185.209769 -353.363084) (xy 185.194774 -353.414163)
			(xy 185.172662 -353.462588) (xy 185.143883 -353.507373) (xy 185.109023 -353.547606) (xy 185.068792 -353.582469)
			(xy 185.024009 -353.61125) (xy 184.975586 -353.633366) (xy 184.924508 -353.648364) (xy 184.871815 -353.65594)
			(xy 184.845198 -353.656392) (xy 184.818776 -353.655937) (xy 184.76646 -353.648487) (xy 184.715722 -353.633721)
			(xy 184.667577 -353.611937) (xy 184.622993 -353.58357) (xy 184.602628 -353.56673) (xy 184.59577 -353.560888)
			(xy 184.578752 -353.554538) (xy 184.494424 -353.554538) (xy 184.477406 -353.560888) (xy 184.470548 -353.56673)
			(xy 184.450182 -353.583569) (xy 184.405596 -353.611934) (xy 184.357452 -353.633721) (xy 184.306715 -353.648492)
			(xy 184.2544 -353.655952) (xy 184.201556 -353.655952) (xy 184.149241 -353.648492) (xy 184.098504 -353.633721)
			(xy 184.05036 -353.611934) (xy 184.005774 -353.583569) (xy 183.985408 -353.56673) (xy 183.97855 -353.560888)
			(xy 183.961532 -353.554538) (xy 183.877204 -353.554538) (xy 183.860186 -353.560888) (xy 183.853328 -353.56673)
			(xy 183.832943 -353.583544) (xy 183.78836 -353.611905) (xy 183.74022 -353.63369) (xy 183.689487 -353.648463)
			(xy 183.637178 -353.655929) (xy 183.610758 -353.656392) (xy 183.582873 -353.65592) (xy 183.527727 -353.647602)
			(xy 183.474437 -353.631159) (xy 183.424192 -353.606958) (xy 183.378116 -353.575538) (xy 183.337236 -353.537603)
			(xy 183.302466 -353.493999) (xy 183.274583 -353.4457) (xy 183.25421 -353.393785) (xy 183.241801 -353.339414)
			(xy 183.237633 -353.2838) (xy 179.422658 -353.2838) (xy 179.419949 -353.285541) (xy 179.370372 -353.308183)
			(xy 179.318077 -353.323538) (xy 179.264129 -353.331294) (xy 179.209627 -353.331294) (xy 179.155679 -353.323538)
			(xy 179.103384 -353.308183) (xy 179.053807 -353.285541) (xy 179.007957 -353.256075) (xy 178.966766 -353.220384)
			(xy 178.931075 -353.179193) (xy 178.901609 -353.133343) (xy 178.878967 -353.083766) (xy 178.863612 -353.031471)
			(xy 178.855856 -352.977523) (xy 178.85537 -352.950272) (xy 156.154882 -352.950272) (xy 155.983686 -353.121468)
			(xy 155.976866 -353.128883) (xy 155.969135 -353.147471) (xy 155.9687 -353.157536) (xy 155.9687 -353.89439)
			(xy 157.69539 -353.89439) (xy 157.699461 -353.838768) (xy 157.711587 -353.784331) (xy 157.73151 -353.73224)
			(xy 157.758806 -353.683605) (xy 157.792892 -353.639462) (xy 157.833041 -353.600753) (xy 157.878399 -353.568302)
			(xy 157.927999 -353.542801) (xy 157.980783 -353.524794) (xy 158.035626 -353.514664) (xy 158.09136 -353.512627)
			(xy 158.146797 -353.518727) (xy 158.200754 -353.532833) (xy 158.252083 -353.554645) (xy 158.299689 -353.583699)
			(xy 158.342557 -353.619374) (xy 158.379774 -353.660911) (xy 158.410547 -353.707424) (xy 158.411153 -353.708716)
			(xy 159.770824 -353.708716) (xy 159.774895 -353.653094) (xy 159.787021 -353.598657) (xy 159.806944 -353.546566)
			(xy 159.83424 -353.497931) (xy 159.868326 -353.453788) (xy 159.908475 -353.415079) (xy 159.953833 -353.382628)
			(xy 160.003433 -353.357127) (xy 160.056217 -353.33912) (xy 160.11106 -353.32899) (xy 160.166794 -353.326953)
			(xy 160.222231 -353.333053) (xy 160.276188 -353.347159) (xy 160.327517 -353.368971) (xy 160.375123 -353.398025)
			(xy 160.417991 -353.4337) (xy 160.455208 -353.475237) (xy 160.485981 -353.52175) (xy 160.509653 -353.572247)
			(xy 160.525721 -353.625654) (xy 160.533841 -353.68083) (xy 160.53435 -353.708716) (xy 160.533841 -353.736602)
			(xy 160.525721 -353.791778) (xy 160.509653 -353.845185) (xy 160.485981 -353.895682) (xy 160.471544 -353.917504)
			(xy 161.123628 -353.917504) (xy 161.127699 -353.861882) (xy 161.139825 -353.807445) (xy 161.159748 -353.755354)
			(xy 161.187044 -353.706719) (xy 161.22113 -353.662576) (xy 161.261279 -353.623867) (xy 161.306637 -353.591416)
			(xy 161.356237 -353.565915) (xy 161.409021 -353.547908) (xy 161.463864 -353.537778) (xy 161.519598 -353.535741)
			(xy 161.575035 -353.541841) (xy 161.628992 -353.555947) (xy 161.680321 -353.577759) (xy 161.727927 -353.606813)
			(xy 161.770795 -353.642488) (xy 161.808012 -353.684025) (xy 161.838785 -353.730538) (xy 161.862457 -353.781035)
			(xy 161.878525 -353.834442) (xy 161.886645 -353.889618) (xy 161.887154 -353.917504) (xy 161.886645 -353.94539)
			(xy 161.878525 -354.000566) (xy 161.862457 -354.053973) (xy 161.838785 -354.10447) (xy 161.808012 -354.150983)
			(xy 161.770795 -354.19252) (xy 161.727927 -354.228195) (xy 161.680321 -354.257249) (xy 161.628992 -354.279061)
			(xy 161.575035 -354.293167) (xy 161.519598 -354.299267) (xy 161.463864 -354.29723) (xy 161.409021 -354.2871)
			(xy 161.356237 -354.269093) (xy 161.306637 -354.243592) (xy 161.261279 -354.211141) (xy 161.22113 -354.172432)
			(xy 161.187044 -354.128289) (xy 161.159748 -354.079654) (xy 161.139825 -354.027563) (xy 161.127699 -353.973126)
			(xy 161.123628 -353.917504) (xy 160.471544 -353.917504) (xy 160.455208 -353.942195) (xy 160.417991 -353.983732)
			(xy 160.375123 -354.019407) (xy 160.327517 -354.048461) (xy 160.276188 -354.070273) (xy 160.222231 -354.084379)
			(xy 160.166794 -354.090479) (xy 160.11106 -354.088442) (xy 160.056217 -354.078312) (xy 160.003433 -354.060305)
			(xy 159.953833 -354.034804) (xy 159.908475 -354.002353) (xy 159.868326 -353.963644) (xy 159.83424 -353.919501)
			(xy 159.806944 -353.870866) (xy 159.787021 -353.818775) (xy 159.774895 -353.764338) (xy 159.770824 -353.708716)
			(xy 158.411153 -353.708716) (xy 158.434219 -353.757921) (xy 158.450287 -353.811328) (xy 158.458407 -353.866504)
			(xy 158.458916 -353.89439) (xy 158.458407 -353.922276) (xy 158.450287 -353.977452) (xy 158.434219 -354.030859)
			(xy 158.410547 -354.081356) (xy 158.379774 -354.127869) (xy 158.342557 -354.169406) (xy 158.299689 -354.205081)
			(xy 158.252083 -354.234135) (xy 158.200754 -354.255947) (xy 158.146797 -354.270053) (xy 158.09136 -354.276153)
			(xy 158.035626 -354.274116) (xy 157.980783 -354.263986) (xy 157.927999 -354.245979) (xy 157.878399 -354.220478)
			(xy 157.833041 -354.188027) (xy 157.792892 -354.149318) (xy 157.758806 -354.105175) (xy 157.73151 -354.05654)
			(xy 157.711587 -354.004449) (xy 157.699461 -353.950012) (xy 157.69539 -353.89439) (xy 155.9687 -353.89439)
			(xy 155.9687 -354.399596) (xy 155.969101 -354.409669) (xy 155.976836 -354.428268) (xy 155.983686 -354.435664)
			(xy 156.349192 -354.80117) (xy 156.356604 -354.807995) (xy 156.375194 -354.815724) (xy 156.38526 -354.816156)
			(xy 164.43198 -354.816156) (xy 164.44205 -354.815732) (xy 164.460648 -354.808011) (xy 164.468048 -354.80117)
			(xy 165.205918 -354.0633) (xy 165.212753 -354.055896) (xy 165.220475 -354.0373) (xy 165.220904 -354.027232)
			(xy 165.220904 -353.47021) (xy 165.217856 -353.461828) (xy 165.207336 -353.430611) (xy 165.195965 -353.36573)
			(xy 165.19525 -353.332796) (xy 165.195736 -353.305545) (xy 165.203492 -353.251597) (xy 165.218847 -353.199302)
			(xy 165.241489 -353.149725) (xy 165.270955 -353.103875) (xy 165.306646 -353.062684) (xy 165.347837 -353.026993)
			(xy 165.393687 -352.997527) (xy 165.443264 -352.974885) (xy 165.495559 -352.95953) (xy 165.549507 -352.951774)
			(xy 165.604009 -352.951774) (xy 165.657957 -352.95953) (xy 165.710252 -352.974885) (xy 165.759829 -352.997527)
			(xy 165.805679 -353.026993) (xy 165.84687 -353.062684) (xy 165.882561 -353.103875) (xy 165.912027 -353.149725)
			(xy 165.934669 -353.199302) (xy 165.950024 -353.251597) (xy 165.95778 -353.305545) (xy 165.958266 -353.332796)
			(xy 165.957531 -353.365729) (xy 165.946167 -353.430608) (xy 165.93566 -353.461828) (xy 165.932612 -353.47021)
			(xy 165.932612 -354.181918) (xy 179.813202 -354.181918) (xy 179.817273 -354.126296) (xy 179.829399 -354.071859)
			(xy 179.849322 -354.019768) (xy 179.876618 -353.971133) (xy 179.910704 -353.92699) (xy 179.950853 -353.888281)
			(xy 179.996211 -353.85583) (xy 180.045811 -353.830329) (xy 180.098595 -353.812322) (xy 180.153438 -353.802192)
			(xy 180.209172 -353.800155) (xy 180.264609 -353.806255) (xy 180.318566 -353.820361) (xy 180.369895 -353.842173)
			(xy 180.417501 -353.871227) (xy 180.460369 -353.906902) (xy 180.497586 -353.948439) (xy 180.528359 -353.994952)
			(xy 180.552031 -354.045449) (xy 180.568099 -354.098856) (xy 180.576219 -354.154032) (xy 180.576728 -354.181918)
			(xy 180.576219 -354.209804) (xy 180.568099 -354.26498) (xy 180.552031 -354.318387) (xy 180.528359 -354.368884)
			(xy 180.497586 -354.415397) (xy 180.460369 -354.456934) (xy 180.417501 -354.492609) (xy 180.369895 -354.521663)
			(xy 180.318566 -354.543475) (xy 180.264609 -354.557581) (xy 180.209172 -354.563681) (xy 180.153438 -354.561644)
			(xy 180.098595 -354.551514) (xy 180.045811 -354.533507) (xy 179.996211 -354.508006) (xy 179.950853 -354.475555)
			(xy 179.910704 -354.436846) (xy 179.876618 -354.392703) (xy 179.849322 -354.344068) (xy 179.829399 -354.291977)
			(xy 179.817273 -354.23754) (xy 179.813202 -354.181918) (xy 165.932612 -354.181918) (xy 165.932612 -354.196142)
			(xy 165.932058 -354.224083) (xy 165.923294 -354.279276) (xy 165.906019 -354.332422) (xy 165.880657 -354.382219)
			(xy 165.84783 -354.427445) (xy 165.828472 -354.447602) (xy 164.85235 -355.423724) (xy 164.832235 -355.443133)
			(xy 164.787014 -355.475986) (xy 164.737209 -355.501357) (xy 164.684047 -355.518621) (xy 164.628838 -355.527352)
			(xy 164.60089 -355.527864) (xy 156.21635 -355.527864) (xy 156.188408 -355.527329) (xy 156.133214 -355.518562)
			(xy 156.080067 -355.501283) (xy 156.03027 -355.475917) (xy 155.985046 -355.443084) (xy 155.96489 -355.423724)
			(xy 155.361132 -354.819966) (xy 155.341723 -354.799852) (xy 155.308871 -354.75463) (xy 155.283501 -354.704824)
			(xy 155.266237 -354.651662) (xy 155.257505 -354.596454) (xy 155.256992 -354.568506) (xy 150.692104 -354.568506)
			(xy 150.692104 -360.273153) (xy 172.666349 -360.273153) (xy 172.666349 -360.218646) (xy 172.674107 -360.164693)
			(xy 172.689463 -360.112394) (xy 172.712107 -360.062813) (xy 172.741576 -360.016959) (xy 172.777271 -359.975765)
			(xy 172.818465 -359.940071) (xy 172.86432 -359.910603) (xy 172.913902 -359.887961) (xy 172.966201 -359.872605)
			(xy 173.020154 -359.864849) (xy 173.074661 -359.86485) (xy 173.128613 -359.872608) (xy 173.180912 -359.887966)
			(xy 173.230493 -359.91061) (xy 173.276347 -359.94008) (xy 173.317539 -359.975776) (xy 173.353233 -360.016971)
			(xy 173.3827 -360.062826) (xy 173.405342 -360.112408) (xy 173.420696 -360.164708) (xy 173.428452 -360.21866)
			(xy 173.428914 -360.245914) (xy 173.428704 -360.263673) (xy 173.425396 -360.299036) (xy 173.42231 -360.316526)
			(xy 173.420715 -360.328459) (xy 173.427489 -360.351528) (xy 173.435264 -360.360722) (xy 173.499526 -360.429556)
			(xy 173.52264 -360.437684) (xy 173.534578 -360.43616) (xy 173.546215 -360.434823) (xy 173.5696 -360.433428)
			(xy 173.581314 -360.433366) (xy 173.608564 -360.433865) (xy 173.66251 -360.441622) (xy 173.714803 -360.456978)
			(xy 173.764379 -360.479619) (xy 173.810228 -360.509084) (xy 173.851417 -360.544774) (xy 173.887109 -360.585963)
			(xy 173.916575 -360.631811) (xy 173.939218 -360.681385) (xy 173.954575 -360.733678) (xy 173.962334 -360.787624)
			(xy 173.962822 -360.814874) (xy 173.962822 -360.815382) (xy 173.962411 -360.840282) (xy 173.955895 -360.889655)
			(xy 173.943011 -360.93776) (xy 173.933866 -360.960924) (xy 173.928532 -360.973624) (xy 173.932342 -361.000802)
			(xy 173.995842 -361.08132) (xy 174.001647 -361.088146) (xy 174.016888 -361.097548) (xy 174.034436 -361.101118)
			(xy 174.04334 -361.100116) (xy 174.043594 -361.100116) (xy 174.058542 -361.097863) (xy 174.088676 -361.095448)
			(xy 174.103792 -361.09529) (xy 174.131046 -361.095747) (xy 174.184998 -361.103503) (xy 174.237298 -361.118858)
			(xy 174.286879 -361.1415) (xy 174.332734 -361.170968) (xy 174.373929 -361.206662) (xy 174.409624 -361.247856)
			(xy 174.439093 -361.293709) (xy 174.461737 -361.343291) (xy 174.477094 -361.39559) (xy 174.484852 -361.449542)
			(xy 174.484853 -361.504049) (xy 174.477096 -361.558001) (xy 174.461741 -361.610301) (xy 174.439098 -361.659882)
			(xy 174.40963 -361.705737) (xy 174.373935 -361.746931) (xy 174.332742 -361.782626) (xy 174.286888 -361.812095)
			(xy 174.237306 -361.834738) (xy 174.185007 -361.850095) (xy 174.131055 -361.857853) (xy 174.076548 -361.857853)
			(xy 174.022595 -361.850096) (xy 173.970296 -361.834739) (xy 173.920715 -361.812096) (xy 173.87486 -361.782628)
			(xy 173.833667 -361.746933) (xy 173.797972 -361.705739) (xy 173.768503 -361.659885) (xy 173.74586 -361.610303)
			(xy 173.730504 -361.558004) (xy 173.722747 -361.504052) (xy 173.722284 -361.476798) (xy 173.722284 -361.47629)
			(xy 173.722717 -361.451391) (xy 173.729224 -361.402018) (xy 173.7421 -361.353913) (xy 173.75124 -361.330748)
			(xy 173.756574 -361.318048) (xy 173.752764 -361.29087) (xy 173.689264 -361.210352) (xy 173.683461 -361.203525)
			(xy 173.668218 -361.194125) (xy 173.65067 -361.190554) (xy 173.641766 -361.191556) (xy 173.641512 -361.191556)
			(xy 173.626564 -361.193808) (xy 173.59643 -361.196224) (xy 173.581314 -361.196382) (xy 173.55406 -361.195932)
			(xy 173.500108 -361.188176) (xy 173.447808 -361.17282) (xy 173.398226 -361.150177) (xy 173.352372 -361.120709)
			(xy 173.311178 -361.085013) (xy 173.275484 -361.043819) (xy 173.246017 -360.997963) (xy 173.223376 -360.948381)
			(xy 173.208022 -360.896081) (xy 173.200268 -360.842128) (xy 173.199806 -360.814874) (xy 173.200014 -360.797115)
			(xy 173.203323 -360.761752) (xy 173.20641 -360.744262) (xy 173.208034 -360.73233) (xy 173.201243 -360.709255)
			(xy 173.193456 -360.700066) (xy 173.129194 -360.631232) (xy 173.10608 -360.623104) (xy 173.094142 -360.624628)
			(xy 173.082505 -360.625963) (xy 173.05912 -360.62736) (xy 173.047406 -360.627422) (xy 173.020152 -360.626951)
			(xy 172.9662 -360.619195) (xy 172.913901 -360.603839) (xy 172.864319 -360.581196) (xy 172.818464 -360.551728)
			(xy 172.77727 -360.516034) (xy 172.741575 -360.47484) (xy 172.712106 -360.428986) (xy 172.689463 -360.379404)
			(xy 172.674106 -360.327105) (xy 172.666349 -360.273153) (xy 150.692104 -360.273153) (xy 150.692104 -362.396278)
			(xy 165.733984 -362.396278) (xy 165.733984 -361.532678) (xy 165.73447 -361.505409) (xy 165.742232 -361.451425)
			(xy 165.757597 -361.399095) (xy 165.780254 -361.349485) (xy 165.80974 -361.303604) (xy 165.845455 -361.262387)
			(xy 165.886672 -361.226672) (xy 165.932553 -361.197186) (xy 165.982163 -361.174529) (xy 166.034493 -361.159164)
			(xy 166.088477 -361.151402) (xy 166.143015 -361.151402) (xy 166.196999 -361.159164) (xy 166.249329 -361.174529)
			(xy 166.298939 -361.197186) (xy 166.34482 -361.226672) (xy 166.386037 -361.262387) (xy 166.421752 -361.303604)
			(xy 166.451238 -361.349485) (xy 166.473895 -361.399095) (xy 166.48926 -361.451425) (xy 166.497022 -361.505409)
			(xy 166.497508 -361.532678) (xy 166.497508 -362.396278) (xy 166.497022 -362.423547) (xy 166.48926 -362.477531)
			(xy 166.473895 -362.529861) (xy 166.451238 -362.579471) (xy 166.421752 -362.625352) (xy 166.386037 -362.666569)
			(xy 166.34482 -362.702284) (xy 166.298939 -362.73177) (xy 166.249329 -362.754427) (xy 166.196999 -362.769792)
			(xy 166.143015 -362.777554) (xy 166.088477 -362.777554) (xy 166.034493 -362.769792) (xy 165.982163 -362.754427)
			(xy 165.932553 -362.73177) (xy 165.886672 -362.702284) (xy 165.845455 -362.666569) (xy 165.80974 -362.625352)
			(xy 165.780254 -362.579471) (xy 165.757597 -362.529861) (xy 165.742232 -362.477531) (xy 165.73447 -362.423547)
			(xy 165.733984 -362.396278) (xy 150.692104 -362.396278) (xy 150.692104 -363.708188) (xy 170.730926 -363.708188)
			(xy 170.731412 -363.680937) (xy 170.739168 -363.626989) (xy 170.754523 -363.574694) (xy 170.777165 -363.525117)
			(xy 170.806631 -363.479267) (xy 170.842322 -363.438076) (xy 170.883513 -363.402385) (xy 170.929363 -363.372919)
			(xy 170.97894 -363.350277) (xy 171.031235 -363.334922) (xy 171.085183 -363.327166) (xy 171.139685 -363.327166)
			(xy 171.193633 -363.334922) (xy 171.245928 -363.350277) (xy 171.295505 -363.372919) (xy 171.341355 -363.402385)
			(xy 171.382546 -363.438076) (xy 171.418237 -363.479267) (xy 171.447703 -363.525117) (xy 171.470345 -363.574694)
			(xy 171.4857 -363.626989) (xy 171.493456 -363.680937) (xy 171.493942 -363.708188) (xy 171.493571 -363.732446)
			(xy 171.487408 -363.780568) (xy 171.475193 -363.827521) (xy 171.46651 -363.850174) (xy 171.461783 -363.862923)
			(xy 171.458616 -363.889922) (xy 171.462692 -363.916798) (xy 171.473723 -363.941643) (xy 171.490924 -363.962692)
			(xy 171.513074 -363.97845) (xy 171.5386 -363.987798) (xy 171.552108 -363.989366) (xy 171.580275 -363.99237)
			(xy 171.635365 -364.005537) (xy 171.687901 -364.026709) (xy 171.736726 -364.055421) (xy 171.780768 -364.091039)
			(xy 171.819055 -364.13278) (xy 171.850746 -364.179727) (xy 171.875144 -364.230845) (xy 171.891711 -364.285009)
			(xy 171.900082 -364.341029) (xy 171.900596 -364.36935) (xy 171.90011 -364.396601) (xy 171.892354 -364.450549)
			(xy 171.876999 -364.502844) (xy 171.854357 -364.552421) (xy 171.824891 -364.598271) (xy 171.7892 -364.639462)
			(xy 171.748009 -364.675153) (xy 171.702159 -364.704619) (xy 171.652582 -364.727261) (xy 171.600287 -364.742616)
			(xy 171.546339 -364.750372) (xy 171.491837 -364.750372) (xy 171.437889 -364.742616) (xy 171.385594 -364.727261)
			(xy 171.336017 -364.704619) (xy 171.290167 -364.675153) (xy 171.248976 -364.639462) (xy 171.213285 -364.598271)
			(xy 171.183819 -364.552421) (xy 171.161177 -364.502844) (xy 171.145822 -364.450549) (xy 171.138066 -364.396601)
			(xy 171.13758 -364.36935) (xy 171.137961 -364.345093) (xy 171.14412 -364.296971) (xy 171.15633 -364.250018)
			(xy 171.165012 -364.227364) (xy 171.169676 -364.214594) (xy 171.172849 -364.187606) (xy 171.168781 -364.160738)
			(xy 171.15776 -364.135898) (xy 171.14057 -364.114852) (xy 171.118432 -364.099094) (xy 171.092917 -364.089743)
			(xy 171.079414 -364.088172) (xy 171.051232 -364.085294) (xy 170.996135 -364.072113) (xy 170.943595 -364.050926)
			(xy 170.894767 -364.0222) (xy 170.850725 -363.986568) (xy 170.812439 -363.944812) (xy 170.780752 -363.897852)
			(xy 170.756359 -363.846721) (xy 170.739799 -363.792544) (xy 170.731435 -363.736514) (xy 170.730926 -363.708188)
			(xy 150.692104 -363.708188) (xy 150.692104 -364.014004) (xy 150.692866 -364.022386) (xy 150.694377 -364.029993)
			(xy 150.701358 -364.043832) (xy 150.706582 -364.049564) (xy 152.683718 -366.0267) (xy 152.689467 -366.0319)
			(xy 152.703298 -366.038883) (xy 152.710896 -366.040416) (xy 152.719278 -366.041178) (xy 173.928024 -366.041178)
			(xy 173.938027 -366.040686) (xy 173.956507 -366.033021) (xy 173.970647 -366.018868) (xy 173.978295 -366.000381)
			(xy 173.978824 -365.990378) (xy 173.978824 -364.2614) (xy 173.979362 -364.251413) (xy 173.987078 -364.232983)
			(xy 173.99381 -364.225586) (xy 174.764192 -363.45495) (xy 174.771032 -363.447549) (xy 174.778749 -363.428951)
			(xy 174.779178 -363.418882) (xy 174.779178 -362.693458) (xy 174.777146 -362.686346) (xy 174.769592 -362.659543)
			(xy 174.761436 -362.60446) (xy 174.76089 -362.576618) (xy 174.761376 -362.549349) (xy 174.769138 -362.495365)
			(xy 174.784503 -362.443035) (xy 174.80716 -362.393425) (xy 174.836646 -362.347544) (xy 174.872361 -362.306327)
			(xy 174.913578 -362.270612) (xy 174.959459 -362.241126) (xy 175.009069 -362.218469) (xy 175.061399 -362.203104)
			(xy 175.115383 -362.195342) (xy 175.169921 -362.195342) (xy 175.223905 -362.203104) (xy 175.276235 -362.218469)
			(xy 175.325845 -362.241126) (xy 175.371726 -362.270612) (xy 175.412943 -362.306327) (xy 175.448658 -362.347544)
			(xy 175.478144 -362.393425) (xy 175.500801 -362.443035) (xy 175.516166 -362.495365) (xy 175.523928 -362.549349)
			(xy 175.524414 -362.576618) (xy 175.523144 -362.606844) (xy 175.522451 -362.621536) (xy 175.528528 -362.650301)
			(xy 175.542539 -362.676148) (xy 175.563324 -362.69694) (xy 175.589166 -362.71096) (xy 175.617929 -362.717047)
			(xy 175.632618 -362.716318) (xy 175.663098 -362.715048) (xy 175.690369 -362.715511) (xy 175.744355 -362.723273)
			(xy 175.796688 -362.73864) (xy 175.846301 -362.761297) (xy 175.892184 -362.790785) (xy 175.933403 -362.826502)
			(xy 175.96912 -362.867723) (xy 175.998607 -362.913607) (xy 176.021263 -362.96322) (xy 176.036628 -363.015552)
			(xy 176.044389 -363.069539) (xy 176.04486 -363.09681) (xy 176.04486 -363.097064) (xy 176.04441 -363.122649)
			(xy 176.037549 -363.173359) (xy 176.023997 -363.222703) (xy 176.01438 -363.246416) (xy 176.010316 -363.256068)
			(xy 176.010316 -363.487462) (xy 176.010855 -363.497412) (xy 176.018523 -363.515782) (xy 176.032576 -363.529882)
			(xy 176.041558 -363.534198) (xy 176.051001 -363.537735) (xy 176.07115 -363.537826) (xy 176.089761 -363.530104)
			(xy 176.097184 -363.523276) (xy 176.700434 -362.920026) (xy 176.707276 -362.912627) (xy 176.714994 -362.894028)
			(xy 176.71542 -362.883958) (xy 176.71542 -354.968302) (xy 176.715921 -354.936357) (xy 176.723929 -354.872971)
			(xy 176.739818 -354.811088) (xy 176.763337 -354.751684) (xy 176.794117 -354.695697) (xy 176.83167 -354.644008)
			(xy 176.875406 -354.597434) (xy 176.924634 -354.556709) (xy 176.978579 -354.522475) (xy 177.036388 -354.495272)
			(xy 177.097151 -354.475529) (xy 177.15991 -354.463557) (xy 177.223674 -354.459546) (xy 177.287438 -354.463557)
			(xy 177.350197 -354.475529) (xy 177.41096 -354.495272) (xy 177.468769 -354.522475) (xy 177.522714 -354.556709)
			(xy 177.571942 -354.597434) (xy 177.615678 -354.644008) (xy 177.653231 -354.695697) (xy 177.684011 -354.751684)
			(xy 177.70753 -354.811088) (xy 177.723419 -354.872971) (xy 177.731427 -354.936357) (xy 177.731928 -354.968302)
			(xy 177.731928 -354.987352) (xy 179.031136 -354.987352) (xy 179.035207 -354.93173) (xy 179.047333 -354.877293)
			(xy 179.067256 -354.825202) (xy 179.094552 -354.776567) (xy 179.128638 -354.732424) (xy 179.168787 -354.693715)
			(xy 179.214145 -354.661264) (xy 179.263745 -354.635763) (xy 179.316529 -354.617756) (xy 179.371372 -354.607626)
			(xy 179.427106 -354.605589) (xy 179.482543 -354.611689) (xy 179.5365 -354.625795) (xy 179.587829 -354.647607)
			(xy 179.635435 -354.676661) (xy 179.678303 -354.712336) (xy 179.71552 -354.753873) (xy 179.746293 -354.800386)
			(xy 179.769965 -354.850883) (xy 179.786033 -354.90429) (xy 179.794153 -354.959466) (xy 179.794662 -354.987352)
			(xy 179.794153 -355.015238) (xy 179.786033 -355.070414) (xy 179.769965 -355.123821) (xy 179.746293 -355.174318)
			(xy 179.71552 -355.220831) (xy 179.678303 -355.262368) (xy 179.635435 -355.298043) (xy 179.587829 -355.327097)
			(xy 179.5365 -355.348909) (xy 179.482543 -355.363015) (xy 179.427106 -355.369115) (xy 179.371372 -355.367078)
			(xy 179.316529 -355.356948) (xy 179.263745 -355.338941) (xy 179.214145 -355.31344) (xy 179.168787 -355.280989)
			(xy 179.128638 -355.24228) (xy 179.094552 -355.198137) (xy 179.067256 -355.149502) (xy 179.047333 -355.097411)
			(xy 179.035207 -355.042974) (xy 179.031136 -354.987352) (xy 177.731928 -354.987352) (xy 177.731928 -355.48443)
			(xy 177.846988 -355.48443) (xy 177.851059 -355.428808) (xy 177.863185 -355.374371) (xy 177.883108 -355.32228)
			(xy 177.910404 -355.273645) (xy 177.94449 -355.229502) (xy 177.984639 -355.190793) (xy 178.029997 -355.158342)
			(xy 178.079597 -355.132841) (xy 178.132381 -355.114834) (xy 178.187224 -355.104704) (xy 178.242958 -355.102667)
			(xy 178.298395 -355.108767) (xy 178.352352 -355.122873) (xy 178.403681 -355.144685) (xy 178.451287 -355.173739)
			(xy 178.494155 -355.209414) (xy 178.531372 -355.250951) (xy 178.562145 -355.297464) (xy 178.585817 -355.347961)
			(xy 178.601885 -355.401368) (xy 178.610005 -355.456544) (xy 178.610514 -355.48443) (xy 178.610005 -355.512316)
			(xy 178.601885 -355.567492) (xy 178.585817 -355.620899) (xy 178.562145 -355.671396) (xy 178.531372 -355.717909)
			(xy 178.500013 -355.752908) (xy 180.572918 -355.752908) (xy 180.573405 -355.725433) (xy 180.581296 -355.671054)
			(xy 180.596916 -355.618371) (xy 180.61994 -355.568478) (xy 180.649892 -355.52241) (xy 180.66766 -355.501448)
			(xy 180.667914 -355.501194) (xy 180.673511 -355.494114) (xy 180.679751 -355.477192) (xy 180.680106 -355.468174)
			(xy 180.680106 -355.40061) (xy 180.679743 -355.391594) (xy 180.673499 -355.374677) (xy 180.667914 -355.36759)
			(xy 180.667406 -355.367082) (xy 180.649669 -355.346139) (xy 180.619787 -355.300105) (xy 180.596821 -355.250259)
			(xy 180.581247 -355.197633) (xy 180.573388 -355.143317) (xy 180.572918 -355.115876) (xy 180.573404 -355.088625)
			(xy 180.58116 -355.034677) (xy 180.596515 -354.982382) (xy 180.619157 -354.932805) (xy 180.648623 -354.886955)
			(xy 180.684314 -354.845764) (xy 180.725505 -354.810073) (xy 180.771355 -354.780607) (xy 180.820932 -354.757965)
			(xy 180.873227 -354.74261) (xy 180.927175 -354.734854) (xy 180.981677 -354.734854) (xy 181.035625 -354.74261)
			(xy 181.08792 -354.757965) (xy 181.137497 -354.780607) (xy 181.183347 -354.810073) (xy 181.224538 -354.845764)
			(xy 181.260229 -354.886955) (xy 181.289695 -354.932805) (xy 181.312337 -354.982382) (xy 181.327692 -355.034677)
			(xy 181.335448 -355.088625) (xy 181.335934 -355.115876) (xy 181.335425 -355.14335) (xy 181.327537 -355.197728)
			(xy 181.311922 -355.25041) (xy 181.309272 -355.256154) (xy 181.577661 -355.256154) (xy 181.577661 -355.201646)
			(xy 181.585419 -355.147692) (xy 181.600777 -355.095392) (xy 181.623423 -355.045809) (xy 181.652894 -354.999955)
			(xy 181.688592 -354.958762) (xy 181.729789 -354.923069) (xy 181.775646 -354.893602) (xy 181.825231 -354.870963)
			(xy 181.877533 -354.85561) (xy 181.931488 -354.847858) (xy 181.958742 -354.847398) (xy 181.958996 -354.847398)
			(xy 181.9842 -354.847791) (xy 182.034168 -354.854432) (xy 182.082823 -354.86761) (xy 182.129312 -354.887095)
			(xy 182.151274 -354.899468) (xy 182.16118 -354.90531) (xy 182.183024 -354.907342) (xy 182.277766 -354.873814)
			(xy 182.293514 -354.85832) (xy 182.297578 -354.847906) (xy 182.308279 -354.821132) (xy 182.336565 -354.770889)
			(xy 182.372094 -354.725479) (xy 182.414055 -354.685936) (xy 182.461492 -354.653162) (xy 182.513322 -354.627904)
			(xy 182.568365 -354.610738) (xy 182.625365 -354.602055) (xy 182.654194 -354.601526) (xy 182.681448 -354.601961)
			(xy 182.735402 -354.609718) (xy 182.787702 -354.625075) (xy 182.837285 -354.647719) (xy 182.88314 -354.67719)
			(xy 182.924333 -354.712887) (xy 182.960027 -354.754083) (xy 182.989494 -354.79994) (xy 183.012135 -354.849524)
			(xy 183.024857 -354.892864) (xy 185.165746 -354.892864) (xy 185.16624 -354.86529) (xy 185.174184 -354.810718)
			(xy 185.189903 -354.757858) (xy 185.213067 -354.707811) (xy 185.243196 -354.661621) (xy 185.27966 -354.62025)
			(xy 185.300366 -354.602034) (xy 185.308437 -354.594475) (xy 185.317791 -354.574466) (xy 185.3184 -354.563426)
			(xy 185.3184 -354.485702) (xy 185.31783 -354.474653) (xy 185.308466 -354.454632) (xy 185.300366 -354.447094)
			(xy 185.279642 -354.428897) (xy 185.243174 -354.387524) (xy 185.213044 -354.341331) (xy 185.189881 -354.291281)
			(xy 185.174167 -354.238416) (xy 185.16623 -354.183839) (xy 185.165746 -354.156264) (xy 185.166244 -354.129014)
			(xy 185.174004 -354.075069) (xy 185.189362 -354.022777) (xy 185.212004 -353.973203) (xy 185.241469 -353.927355)
			(xy 185.277159 -353.886166) (xy 185.318347 -353.850476) (xy 185.364194 -353.821009) (xy 185.413768 -353.798365)
			(xy 185.466059 -353.783007) (xy 185.520004 -353.775245) (xy 185.547254 -353.774756) (xy 185.547762 -353.774756)
			(xy 185.581544 -353.77628) (xy 185.591704 -353.777296) (xy 185.611008 -353.7712) (xy 185.674 -353.718368)
			(xy 185.681282 -353.711637) (xy 185.690568 -353.694138) (xy 185.692034 -353.684332) (xy 185.692034 -353.68357)
			(xy 185.695048 -353.65543) (xy 185.708241 -353.600398) (xy 185.729422 -353.547919) (xy 185.758125 -353.499147)
			(xy 185.793721 -353.455152) (xy 185.835427 -353.4169) (xy 185.882328 -353.385232) (xy 185.933394 -353.360842)
			(xy 185.987504 -353.344266) (xy 186.043469 -353.335869) (xy 186.071764 -353.335336) (xy 186.072018 -353.335336)
			(xy 186.090037 -353.335559) (xy 186.125912 -353.338992) (xy 186.143646 -353.342194) (xy 186.153298 -353.343972)
			(xy 186.172348 -353.340416) (xy 186.247278 -353.29241) (xy 186.258708 -353.276662) (xy 186.260994 -353.267264)
			(xy 186.268418 -353.240228) (xy 186.290044 -353.188502) (xy 186.319005 -353.140498) (xy 186.354678 -353.097246)
			(xy 186.396293 -353.059678) (xy 186.442958 -353.028603) (xy 186.493666 -353.004689) (xy 186.547327 -352.98845)
			(xy 186.602786 -352.980236) (xy 186.630818 -352.979736) (xy 186.658073 -352.980138) (xy 186.712029 -352.987899)
			(xy 186.764331 -353.003259) (xy 186.813914 -353.025907) (xy 186.859769 -353.055381) (xy 186.900963 -353.091081)
			(xy 186.936656 -353.132281) (xy 186.966123 -353.178141) (xy 186.988762 -353.227728) (xy 187.004114 -353.280032)
			(xy 187.011866 -353.333989) (xy 187.012326 -353.361244) (xy 187.011813 -353.388817) (xy 187.003869 -353.443387)
			(xy 186.988152 -353.496246) (xy 186.964991 -353.546292) (xy 186.934868 -353.592482) (xy 186.898409 -353.633856)
			(xy 186.877706 -353.652074) (xy 186.869643 -353.65964) (xy 186.860282 -353.679643) (xy 186.859672 -353.690682)
			(xy 186.859672 -353.768406) (xy 186.86027 -353.779452) (xy 186.869612 -353.799475) (xy 186.877706 -353.807014)
			(xy 186.898428 -353.825213) (xy 186.934897 -353.866584) (xy 186.965028 -353.912777) (xy 186.988192 -353.962827)
			(xy 187.003906 -354.015692) (xy 187.011842 -354.070269) (xy 187.012326 -354.097844) (xy 187.011813 -354.125417)
			(xy 187.003869 -354.179987) (xy 186.995742 -354.207318) (xy 188.13983 -354.207318) (xy 188.143901 -354.151696)
			(xy 188.156027 -354.097259) (xy 188.17595 -354.045168) (xy 188.203246 -353.996533) (xy 188.237332 -353.95239)
			(xy 188.277481 -353.913681) (xy 188.322839 -353.88123) (xy 188.372439 -353.855729) (xy 188.425223 -353.837722)
			(xy 188.480066 -353.827592) (xy 188.5358 -353.825555) (xy 188.591237 -353.831655) (xy 188.645194 -353.845761)
			(xy 188.696523 -353.867573) (xy 188.744129 -353.896627) (xy 188.786997 -353.932302) (xy 188.824214 -353.973839)
			(xy 188.854987 -354.020352) (xy 188.878659 -354.070849) (xy 188.894727 -354.124256) (xy 188.902847 -354.179432)
			(xy 188.903356 -354.207318) (xy 188.902847 -354.235204) (xy 188.894727 -354.29038) (xy 188.878659 -354.343787)
			(xy 188.854987 -354.394284) (xy 188.824214 -354.440797) (xy 188.786997 -354.482334) (xy 188.744129 -354.518009)
			(xy 188.696523 -354.547063) (xy 188.645194 -354.568875) (xy 188.591237 -354.582981) (xy 188.5358 -354.589081)
			(xy 188.480066 -354.587044) (xy 188.425223 -354.576914) (xy 188.372439 -354.558907) (xy 188.322839 -354.533406)
			(xy 188.277481 -354.500955) (xy 188.237332 -354.462246) (xy 188.203246 -354.418103) (xy 188.17595 -354.369468)
			(xy 188.156027 -354.317377) (xy 188.143901 -354.26294) (xy 188.13983 -354.207318) (xy 186.995742 -354.207318)
			(xy 186.988152 -354.232846) (xy 186.964991 -354.282892) (xy 186.934868 -354.329082) (xy 186.898409 -354.370456)
			(xy 186.877706 -354.388674) (xy 186.869643 -354.39624) (xy 186.860282 -354.416243) (xy 186.859672 -354.427282)
			(xy 186.859672 -354.505006) (xy 186.86027 -354.516052) (xy 186.869612 -354.536075) (xy 186.877706 -354.543614)
			(xy 186.898428 -354.561813) (xy 186.934897 -354.603184) (xy 186.965028 -354.649377) (xy 186.988192 -354.699427)
			(xy 187.003906 -354.752292) (xy 187.011842 -354.806869) (xy 187.012326 -354.834444) (xy 187.011863 -354.861696)
			(xy 187.004101 -354.915643) (xy 186.988741 -354.967937) (xy 186.966096 -355.017513) (xy 186.936627 -355.063363)
			(xy 186.902567 -355.102668) (xy 187.56071 -355.102668) (xy 187.564781 -355.047046) (xy 187.576907 -354.992609)
			(xy 187.59683 -354.940518) (xy 187.624126 -354.891883) (xy 187.658212 -354.84774) (xy 187.698361 -354.809031)
			(xy 187.743719 -354.77658) (xy 187.793319 -354.751079) (xy 187.846103 -354.733072) (xy 187.900946 -354.722942)
			(xy 187.95668 -354.720905) (xy 188.012117 -354.727005) (xy 188.066074 -354.741111) (xy 188.117403 -354.762923)
			(xy 188.165009 -354.791977) (xy 188.207877 -354.827652) (xy 188.245094 -354.869189) (xy 188.275867 -354.915702)
			(xy 188.299539 -354.966199) (xy 188.315607 -355.019606) (xy 188.323727 -355.074782) (xy 188.324236 -355.102668)
			(xy 188.323727 -355.130554) (xy 188.315607 -355.18573) (xy 188.299539 -355.239137) (xy 188.275867 -355.289634)
			(xy 188.245094 -355.336147) (xy 188.207877 -355.377684) (xy 188.165009 -355.413359) (xy 188.117403 -355.442413)
			(xy 188.066074 -355.464225) (xy 188.012117 -355.478331) (xy 187.95668 -355.484431) (xy 187.900946 -355.482394)
			(xy 187.846103 -355.472264) (xy 187.793319 -355.454257) (xy 187.743719 -355.428756) (xy 187.698361 -355.396305)
			(xy 187.658212 -355.357596) (xy 187.624126 -355.313453) (xy 187.59683 -355.264818) (xy 187.576907 -355.212727)
			(xy 187.564781 -355.15829) (xy 187.56071 -355.102668) (xy 186.902567 -355.102668) (xy 186.900934 -355.104552)
			(xy 186.859742 -355.140243) (xy 186.813891 -355.169709) (xy 186.764313 -355.19235) (xy 186.712018 -355.207707)
			(xy 186.65807 -355.215465) (xy 186.630818 -355.215952) (xy 186.602962 -355.215448) (xy 186.547844 -355.207326)
			(xy 186.494491 -355.19128) (xy 186.444036 -355.167652) (xy 186.397551 -355.136943) (xy 186.356021 -355.099805)
			(xy 186.320329 -355.057026) (xy 186.291232 -355.009514) (xy 186.269348 -354.958279) (xy 186.261756 -354.931472)
			(xy 186.25947 -354.922582) (xy 186.248802 -354.907342) (xy 186.17692 -354.85959) (xy 186.158886 -354.855526)
			(xy 186.149742 -354.856796) (xy 186.136726 -354.858469) (xy 186.110541 -354.860246) (xy 186.097418 -354.860352)
			(xy 186.083269 -354.860256) (xy 186.055046 -354.858223) (xy 186.04103 -354.856288) (xy 186.031124 -354.854764)
			(xy 186.011312 -354.85959) (xy 185.93689 -354.91547) (xy 185.92673 -354.932996) (xy 185.92546 -354.943156)
			(xy 185.921339 -354.970304) (xy 185.906367 -355.023131) (xy 185.883977 -355.073266) (xy 185.854633 -355.119675)
			(xy 185.818939 -355.161398) (xy 185.777633 -355.197574) (xy 185.731569 -355.227457) (xy 185.681697 -355.250428)
			(xy 185.629048 -355.266013) (xy 185.574708 -355.273891) (xy 185.547254 -355.274372) (xy 185.52 -355.273965)
			(xy 185.466048 -355.266201) (xy 185.413749 -355.250838) (xy 185.364169 -355.228189) (xy 185.318317 -355.198715)
			(xy 185.277127 -355.163015) (xy 185.241436 -355.121817) (xy 185.211971 -355.075959) (xy 185.189333 -355.026374)
			(xy 185.173981 -354.974072) (xy 185.166229 -354.920118) (xy 185.165746 -354.892864) (xy 183.024857 -354.892864)
			(xy 183.027488 -354.901825) (xy 183.035241 -354.95578) (xy 183.035702 -354.983034) (xy 183.03504 -355.014597)
			(xy 183.024654 -355.076862) (xy 183.004169 -355.136571) (xy 182.989728 -355.164644) (xy 182.984902 -355.173534)
			(xy 182.98287 -355.193092) (xy 183.00573 -355.271578) (xy 183.008976 -355.280999) (xy 183.021387 -355.29656)
			(xy 183.02986 -355.301804) (xy 183.054938 -355.31639) (xy 183.100822 -355.351886) (xy 183.140799 -355.393923)
			(xy 183.173948 -355.44153) (xy 183.199503 -355.493609) (xy 183.216874 -355.548959) (xy 183.22566 -355.6063)
			(xy 183.226202 -355.635306) (xy 183.225716 -355.662557) (xy 183.21796 -355.716505) (xy 183.202605 -355.7688)
			(xy 183.198263 -355.778308) (xy 188.899546 -355.778308) (xy 188.900026 -355.750833) (xy 188.907918 -355.696453)
			(xy 188.923539 -355.64377) (xy 188.946565 -355.593877) (xy 188.976519 -355.547809) (xy 188.994288 -355.526848)
			(xy 188.994542 -355.526594) (xy 189.000142 -355.519517) (xy 189.00638 -355.502593) (xy 189.006734 -355.493574)
			(xy 189.006734 -355.42601) (xy 189.006365 -355.416995) (xy 189.000125 -355.400078) (xy 188.994542 -355.39299)
			(xy 188.994034 -355.392482) (xy 188.976301 -355.371535) (xy 188.946418 -355.325503) (xy 188.923451 -355.275658)
			(xy 188.907876 -355.223033) (xy 188.900016 -355.168717) (xy 188.899546 -355.141276) (xy 188.900032 -355.114025)
			(xy 188.907788 -355.060077) (xy 188.923143 -355.007782) (xy 188.945785 -354.958205) (xy 188.975251 -354.912355)
			(xy 189.010942 -354.871164) (xy 189.052133 -354.835473) (xy 189.097983 -354.806007) (xy 189.14756 -354.783365)
			(xy 189.199855 -354.76801) (xy 189.253803 -354.760254) (xy 189.308305 -354.760254) (xy 189.362253 -354.76801)
			(xy 189.414548 -354.783365) (xy 189.464125 -354.806007) (xy 189.509975 -354.835473) (xy 189.551166 -354.871164)
			(xy 189.586857 -354.912355) (xy 189.616323 -354.958205) (xy 189.638965 -355.007782) (xy 189.65432 -355.060077)
			(xy 189.662076 -355.114025) (xy 189.662562 -355.141276) (xy 189.662071 -355.168751) (xy 189.654182 -355.22313)
			(xy 189.638563 -355.275813) (xy 189.635916 -355.281549) (xy 189.904384 -355.281549) (xy 189.904384 -355.227051)
			(xy 189.912139 -355.173106) (xy 189.927493 -355.120815) (xy 189.950131 -355.07124) (xy 189.979594 -355.025392)
			(xy 190.015282 -354.984203) (xy 190.056468 -354.948512) (xy 190.102314 -354.919046) (xy 190.151887 -354.896403)
			(xy 190.204177 -354.881046) (xy 190.258121 -354.873286) (xy 190.28537 -354.872798) (xy 190.285624 -354.872798)
			(xy 190.310828 -354.873179) (xy 190.360797 -354.879823) (xy 190.409452 -354.893005) (xy 190.455941 -354.912493)
			(xy 190.477902 -354.924868) (xy 190.487808 -354.93071) (xy 190.509652 -354.932742) (xy 190.604394 -354.899214)
			(xy 190.620142 -354.88372) (xy 190.624206 -354.873306) (xy 190.634884 -354.846522) (xy 190.663173 -354.796278)
			(xy 190.698704 -354.750867) (xy 190.740669 -354.711325) (xy 190.788109 -354.678551) (xy 190.839943 -354.653295)
			(xy 190.894989 -354.636132) (xy 190.951992 -354.627453) (xy 190.980822 -354.626926) (xy 191.008077 -354.627335)
			(xy 191.062032 -354.635095) (xy 191.114333 -354.650456) (xy 191.163915 -354.673103) (xy 191.20977 -354.702577)
			(xy 191.250963 -354.738276) (xy 191.286657 -354.779475) (xy 191.316123 -354.825334) (xy 191.338764 -354.87492)
			(xy 191.351487 -354.918264) (xy 193.492374 -354.918264) (xy 193.492893 -354.890691) (xy 193.500836 -354.836121)
			(xy 193.516551 -354.783263) (xy 193.539711 -354.733217) (xy 193.569834 -354.687026) (xy 193.606292 -354.645652)
			(xy 193.626994 -354.627434) (xy 193.635054 -354.619864) (xy 193.644417 -354.599864) (xy 193.645028 -354.588826)
			(xy 193.645028 -354.511102) (xy 193.644481 -354.500049) (xy 193.635103 -354.480027) (xy 193.626994 -354.472494)
			(xy 193.606276 -354.454291) (xy 193.569806 -354.41292) (xy 193.539675 -354.366729) (xy 193.516511 -354.316679)
			(xy 193.500796 -354.263815) (xy 193.492858 -354.209239) (xy 193.492374 -354.181664) (xy 193.492844 -354.154413)
			(xy 193.500605 -354.100465) (xy 193.515964 -354.048171) (xy 193.538608 -353.998595) (xy 193.568076 -353.952746)
			(xy 193.603769 -353.911557) (xy 193.64496 -353.875866) (xy 193.690811 -353.846399) (xy 193.740388 -353.823758)
			(xy 193.792683 -353.808401) (xy 193.846631 -353.800643) (xy 193.873882 -353.800156) (xy 193.87439 -353.800156)
			(xy 193.908172 -353.80168) (xy 193.918332 -353.802696) (xy 193.937636 -353.7966) (xy 194.000628 -353.743768)
			(xy 194.007915 -353.737041) (xy 194.017198 -353.719539) (xy 194.018662 -353.709732) (xy 194.018662 -353.70897)
			(xy 194.021649 -353.680826) (xy 194.034843 -353.625792) (xy 194.056026 -353.573311) (xy 194.084732 -353.524538)
			(xy 194.120331 -353.480542) (xy 194.16204 -353.44229) (xy 194.208945 -353.410622) (xy 194.260014 -353.386234)
			(xy 194.314127 -353.369661) (xy 194.370095 -353.361267) (xy 194.398392 -353.360736) (xy 194.398646 -353.360736)
			(xy 194.416665 -353.360955) (xy 194.45254 -353.364391) (xy 194.470274 -353.367594) (xy 194.479926 -353.369372)
			(xy 194.498976 -353.365816) (xy 194.573906 -353.31781) (xy 194.585336 -353.302062) (xy 194.587622 -353.292664)
			(xy 194.59502 -353.26562) (xy 194.616649 -353.213893) (xy 194.645613 -353.165887) (xy 194.681288 -353.122635)
			(xy 194.722907 -353.085068) (xy 194.769575 -353.053993) (xy 194.820286 -353.030081) (xy 194.873951 -353.013845)
			(xy 194.929413 -353.005634) (xy 194.957446 -353.005136) (xy 194.9847 -353.005535) (xy 195.038654 -353.013299)
			(xy 195.090953 -353.028662) (xy 195.140533 -353.051312) (xy 195.186385 -353.080787) (xy 195.227576 -353.116488)
			(xy 195.263267 -353.157687) (xy 195.292731 -353.203546) (xy 195.315369 -353.253132) (xy 195.33072 -353.305435)
			(xy 195.338471 -353.35939) (xy 195.338954 -353.386644) (xy 195.338466 -353.414218) (xy 195.33052 -353.46879)
			(xy 195.314801 -353.521651) (xy 195.291635 -353.571697) (xy 195.261506 -353.617887) (xy 195.22504 -353.659258)
			(xy 195.204334 -353.677474) (xy 195.196259 -353.685029) (xy 195.186907 -353.705041) (xy 195.1863 -353.716082)
			(xy 195.1863 -353.793806) (xy 195.18692 -353.804849) (xy 195.196249 -353.824871) (xy 195.204334 -353.832414)
			(xy 195.225062 -353.850607) (xy 195.261529 -353.89198) (xy 195.291659 -353.938174) (xy 195.314821 -353.988226)
			(xy 195.330534 -354.041091) (xy 195.33847 -354.095668) (xy 195.338954 -354.123244) (xy 195.338466 -354.150818)
			(xy 195.33052 -354.20539) (xy 195.314801 -354.258251) (xy 195.291635 -354.308297) (xy 195.261506 -354.354487)
			(xy 195.22504 -354.395858) (xy 195.204334 -354.414074) (xy 195.196259 -354.421629) (xy 195.186907 -354.441641)
			(xy 195.1863 -354.452682) (xy 195.1863 -354.530406) (xy 195.18692 -354.541449) (xy 195.196249 -354.561471)
			(xy 195.204334 -354.569014) (xy 195.225062 -354.587207) (xy 195.261529 -354.62858) (xy 195.291659 -354.674774)
			(xy 195.314821 -354.724826) (xy 195.330534 -354.777691) (xy 195.33847 -354.832268) (xy 195.338954 -354.859844)
			(xy 195.338463 -354.887094) (xy 195.330702 -354.941039) (xy 195.315344 -354.993331) (xy 195.292701 -355.042906)
			(xy 195.263234 -355.088753) (xy 195.227543 -355.129942) (xy 195.186355 -355.165633) (xy 195.140507 -355.1951)
			(xy 195.090933 -355.217743) (xy 195.038641 -355.233102) (xy 194.984696 -355.240863) (xy 194.957446 -355.241352)
			(xy 194.92959 -355.240823) (xy 194.874473 -355.232705) (xy 194.821121 -355.216663) (xy 194.770667 -355.193038)
			(xy 194.724181 -355.162332) (xy 194.682651 -355.125197) (xy 194.646958 -355.082421) (xy 194.617861 -355.034911)
			(xy 194.595976 -354.983678) (xy 194.588384 -354.956872) (xy 194.586098 -354.947982) (xy 194.57543 -354.932742)
			(xy 194.503548 -354.88499) (xy 194.485514 -354.880926) (xy 194.47637 -354.882196) (xy 194.463354 -354.883866)
			(xy 194.437169 -354.885645) (xy 194.424046 -354.885752) (xy 194.409897 -354.885653) (xy 194.381674 -354.883622)
			(xy 194.367658 -354.881688) (xy 194.357752 -354.880164) (xy 194.33794 -354.88499) (xy 194.263518 -354.94087)
			(xy 194.253358 -354.958396) (xy 194.252088 -354.968556) (xy 194.248037 -354.995716) (xy 194.233061 -355.048548)
			(xy 194.210665 -355.098688) (xy 194.181314 -355.1451) (xy 194.145612 -355.186825) (xy 194.104298 -355.223001)
			(xy 194.058225 -355.252881) (xy 194.008344 -355.275848) (xy 193.955686 -355.291427) (xy 193.901339 -355.299296)
			(xy 193.873882 -355.299772) (xy 193.846627 -355.299362) (xy 193.792672 -355.291601) (xy 193.740371 -355.276241)
			(xy 193.690789 -355.253594) (xy 193.644934 -355.224121) (xy 193.60374 -355.188421) (xy 193.568047 -355.147223)
			(xy 193.53858 -355.101364) (xy 193.51594 -355.051778) (xy 193.500587 -354.999475) (xy 193.492834 -354.945519)
			(xy 193.492374 -354.918264) (xy 191.351487 -354.918264) (xy 191.354117 -354.927223) (xy 191.361869 -354.981179)
			(xy 191.36233 -355.008434) (xy 191.361665 -355.039996) (xy 191.351279 -355.102261) (xy 191.330796 -355.161971)
			(xy 191.316356 -355.190044) (xy 191.31153 -355.198934) (xy 191.309498 -355.218492) (xy 191.332358 -355.296978)
			(xy 191.335594 -355.306404) (xy 191.348012 -355.321963) (xy 191.356488 -355.327204) (xy 191.381573 -355.34178)
			(xy 191.427455 -355.377278) (xy 191.467431 -355.419317) (xy 191.500578 -355.466927) (xy 191.526132 -355.519007)
			(xy 191.543502 -355.574357) (xy 191.552288 -355.6317) (xy 191.55283 -355.660706) (xy 191.552344 -355.687957)
			(xy 191.544588 -355.741905) (xy 191.529233 -355.7942) (xy 191.506591 -355.843777) (xy 191.477125 -355.889627)
			(xy 191.441434 -355.930818) (xy 191.400243 -355.966509) (xy 191.354393 -355.995975) (xy 191.304816 -356.018617)
			(xy 191.252521 -356.033972) (xy 191.198573 -356.041728) (xy 191.144071 -356.041728) (xy 191.090123 -356.033972)
			(xy 191.037828 -356.018617) (xy 190.988251 -355.995975) (xy 190.942401 -355.966509) (xy 190.90121 -355.930818)
			(xy 190.865519 -355.889627) (xy 190.836053 -355.843777) (xy 190.813411 -355.7942) (xy 190.798056 -355.741905)
			(xy 190.7903 -355.687957) (xy 190.789814 -355.660706) (xy 190.79045 -355.629142) (xy 190.800847 -355.566876)
			(xy 190.821342 -355.507168) (xy 190.835788 -355.479096) (xy 190.840614 -355.470206) (xy 190.842646 -355.450648)
			(xy 190.819786 -355.372162) (xy 190.816558 -355.362734) (xy 190.804133 -355.347177) (xy 190.795656 -355.341936)
			(xy 190.78829 -355.337872) (xy 190.778384 -355.33203) (xy 190.75654 -355.329998) (xy 190.661798 -355.363526)
			(xy 190.64605 -355.37902) (xy 190.641986 -355.389434) (xy 190.631336 -355.41623) (xy 190.603042 -355.466472)
			(xy 190.567505 -355.511882) (xy 190.525536 -355.551423) (xy 190.478092 -355.584194) (xy 190.426255 -355.609449)
			(xy 190.371206 -355.62661) (xy 190.314201 -355.635287) (xy 190.28537 -355.635814) (xy 190.258121 -355.635314)
			(xy 190.204177 -355.627554) (xy 190.151887 -355.612197) (xy 190.102314 -355.589554) (xy 190.056468 -355.560088)
			(xy 190.015282 -355.524397) (xy 189.979594 -355.483208) (xy 189.950131 -355.43736) (xy 189.927493 -355.387785)
			(xy 189.912139 -355.335494) (xy 189.904384 -355.281549) (xy 189.635916 -355.281549) (xy 189.615539 -355.325706)
			(xy 189.585588 -355.371774) (xy 189.56782 -355.392736) (xy 189.567566 -355.39299) (xy 189.561974 -355.400072)
			(xy 189.555732 -355.416993) (xy 189.555374 -355.42601) (xy 189.555374 -355.493574) (xy 189.555749 -355.502589)
			(xy 189.561985 -355.519506) (xy 189.567566 -355.526594) (xy 189.568074 -355.527102) (xy 189.5858 -355.548054)
			(xy 189.615685 -355.594085) (xy 189.638653 -355.643928) (xy 189.654229 -355.696553) (xy 189.662091 -355.750867)
			(xy 189.662562 -355.778308) (xy 189.662076 -355.805559) (xy 189.65432 -355.859507) (xy 189.638965 -355.911802)
			(xy 189.616323 -355.961379) (xy 189.586857 -356.007229) (xy 189.551166 -356.04842) (xy 189.509975 -356.084111)
			(xy 189.464125 -356.113577) (xy 189.414548 -356.136219) (xy 189.362253 -356.151574) (xy 189.308305 -356.15933)
			(xy 189.253803 -356.15933) (xy 189.199855 -356.151574) (xy 189.14756 -356.136219) (xy 189.097983 -356.113577)
			(xy 189.052133 -356.084111) (xy 189.010942 -356.04842) (xy 188.975251 -356.007229) (xy 188.945785 -355.961379)
			(xy 188.923143 -355.911802) (xy 188.907788 -355.859507) (xy 188.900032 -355.805559) (xy 188.899546 -355.778308)
			(xy 183.198263 -355.778308) (xy 183.179963 -355.818377) (xy 183.150497 -355.864227) (xy 183.114806 -355.905418)
			(xy 183.073615 -355.941109) (xy 183.027765 -355.970575) (xy 182.978188 -355.993217) (xy 182.925893 -356.008572)
			(xy 182.871945 -356.016328) (xy 182.817443 -356.016328) (xy 182.763495 -356.008572) (xy 182.7112 -355.993217)
			(xy 182.661623 -355.970575) (xy 182.615773 -355.941109) (xy 182.574582 -355.905418) (xy 182.538891 -355.864227)
			(xy 182.509425 -355.818377) (xy 182.486783 -355.7688) (xy 182.471428 -355.716505) (xy 182.463672 -355.662557)
			(xy 182.463186 -355.635306) (xy 182.463826 -355.603742) (xy 182.474222 -355.541477) (xy 182.494715 -355.481768)
			(xy 182.50916 -355.453696) (xy 182.513986 -355.444806) (xy 182.516018 -355.425248) (xy 182.493158 -355.346762)
			(xy 182.48994 -355.337329) (xy 182.477508 -355.321774) (xy 182.469028 -355.316536) (xy 182.461662 -355.312472)
			(xy 182.451756 -355.30663) (xy 182.429912 -355.304598) (xy 182.33517 -355.338126) (xy 182.319422 -355.35362)
			(xy 182.315358 -355.364034) (xy 182.304648 -355.390804) (xy 182.276361 -355.441044) (xy 182.240832 -355.486452)
			(xy 182.198872 -355.525994) (xy 182.151437 -355.558768) (xy 182.099608 -355.584027) (xy 182.044568 -355.601196)
			(xy 181.98757 -355.609882) (xy 181.958742 -355.610414) (xy 181.931488 -355.609942) (xy 181.877533 -355.60219)
			(xy 181.825231 -355.586837) (xy 181.775646 -355.564198) (xy 181.729789 -355.534731) (xy 181.688592 -355.499038)
			(xy 181.652894 -355.457845) (xy 181.623423 -355.411991) (xy 181.600777 -355.362408) (xy 181.585419 -355.310108)
			(xy 181.577661 -355.256154) (xy 181.309272 -355.256154) (xy 181.288903 -355.300303) (xy 181.258957 -355.346373)
			(xy 181.241192 -355.367336) (xy 181.240938 -355.36759) (xy 181.235342 -355.37467) (xy 181.229103 -355.391592)
			(xy 181.228746 -355.40061) (xy 181.228746 -355.468174) (xy 181.229106 -355.477191) (xy 181.23535 -355.494108)
			(xy 181.240938 -355.501194) (xy 181.241446 -355.501702) (xy 181.259168 -355.522658) (xy 181.289054 -355.568687)
			(xy 181.312023 -355.61853) (xy 181.327601 -355.671153) (xy 181.335463 -355.725468) (xy 181.335934 -355.752908)
			(xy 181.335448 -355.780159) (xy 181.327692 -355.834107) (xy 181.312337 -355.886402) (xy 181.289695 -355.935979)
			(xy 181.260229 -355.981829) (xy 181.224538 -356.02302) (xy 181.183347 -356.058711) (xy 181.137497 -356.088177)
			(xy 181.08792 -356.110819) (xy 181.035625 -356.126174) (xy 180.981677 -356.13393) (xy 180.927175 -356.13393)
			(xy 180.873227 -356.126174) (xy 180.820932 -356.110819) (xy 180.771355 -356.088177) (xy 180.725505 -356.058711)
			(xy 180.684314 -356.02302) (xy 180.648623 -355.981829) (xy 180.619157 -355.935979) (xy 180.596515 -355.886402)
			(xy 180.58116 -355.834107) (xy 180.573404 -355.780159) (xy 180.572918 -355.752908) (xy 178.500013 -355.752908)
			(xy 178.494155 -355.759446) (xy 178.451287 -355.795121) (xy 178.403681 -355.824175) (xy 178.352352 -355.845987)
			(xy 178.298395 -355.860093) (xy 178.242958 -355.866193) (xy 178.187224 -355.864156) (xy 178.132381 -355.854026)
			(xy 178.079597 -355.836019) (xy 178.029997 -355.810518) (xy 177.984639 -355.778067) (xy 177.94449 -355.739358)
			(xy 177.910404 -355.695215) (xy 177.883108 -355.64658) (xy 177.863185 -355.594489) (xy 177.851059 -355.540052)
			(xy 177.846988 -355.48443) (xy 177.731928 -355.48443) (xy 177.731928 -363.115606) (xy 177.731384 -363.148884)
			(xy 177.722699 -363.214871) (xy 177.705477 -363.279161) (xy 177.680014 -363.340653) (xy 177.646745 -363.398298)
			(xy 177.606238 -363.451108) (xy 177.583084 -363.475016) (xy 177.133853 -363.924342) (xy 179.856638 -363.924342)
			(xy 179.857119 -363.896972) (xy 179.864932 -363.842793) (xy 179.880417 -363.79029) (xy 179.903256 -363.740543)
			(xy 179.932978 -363.694576) (xy 179.950618 -363.673644) (xy 179.950872 -363.67339) (xy 179.956477 -363.666317)
			(xy 179.962711 -363.649389) (xy 179.963064 -363.64037) (xy 179.963064 -363.573314) (xy 179.962708 -363.564297)
			(xy 179.95646 -363.54738) (xy 179.950872 -363.540294) (xy 179.950618 -363.540294) (xy 179.950618 -363.54004)
			(xy 179.932987 -363.519101) (xy 179.903273 -363.473131) (xy 179.880436 -363.423385) (xy 179.864943 -363.370886)
			(xy 179.857113 -363.316711) (xy 179.856638 -363.289342) (xy 179.857119 -363.261768) (xy 179.865067 -363.207195)
			(xy 179.880788 -363.154335) (xy 179.903955 -363.104289) (xy 179.934085 -363.058099) (xy 179.970551 -363.016728)
			(xy 179.991258 -362.998512) (xy 179.999337 -362.990961) (xy 180.008687 -362.970946) (xy 180.009292 -362.959904)
			(xy 180.009292 -362.88218) (xy 180.008682 -362.871136) (xy 179.999347 -362.851114) (xy 179.991258 -362.843572)
			(xy 179.970522 -362.825388) (xy 179.934055 -362.784013) (xy 179.903927 -362.737817) (xy 179.880766 -362.687764)
			(xy 179.865055 -362.634897) (xy 179.857121 -362.580318) (xy 179.856638 -362.552742) (xy 179.857119 -362.525372)
			(xy 179.864932 -362.471193) (xy 179.880417 -362.41869) (xy 179.903256 -362.368943) (xy 179.932978 -362.322976)
			(xy 179.950618 -362.302044) (xy 179.950872 -362.30179) (xy 179.956477 -362.294717) (xy 179.962711 -362.277789)
			(xy 179.963064 -362.26877) (xy 179.963064 -362.201714) (xy 179.962708 -362.192697) (xy 179.95646 -362.17578)
			(xy 179.950872 -362.168694) (xy 179.950618 -362.168694) (xy 179.950618 -362.16844) (xy 179.933019 -362.147474)
			(xy 179.903293 -362.101512) (xy 179.880446 -362.051771) (xy 179.864947 -361.999274) (xy 179.857114 -361.9451)
			(xy 179.85711 -361.890363) (xy 179.864933 -361.836188) (xy 179.880423 -361.783689) (xy 179.903263 -361.733944)
			(xy 179.932981 -361.687977) (xy 179.950618 -361.667044) (xy 179.950872 -361.66679) (xy 179.956477 -361.659717)
			(xy 179.962711 -361.642789) (xy 179.963064 -361.63377) (xy 179.963064 -361.566714) (xy 179.962708 -361.557697)
			(xy 179.95646 -361.54078) (xy 179.950872 -361.533694) (xy 179.950618 -361.533694) (xy 179.950618 -361.53344)
			(xy 179.933019 -361.512474) (xy 179.903293 -361.466512) (xy 179.880446 -361.416771) (xy 179.864947 -361.364274)
			(xy 179.857114 -361.3101) (xy 179.85711 -361.255363) (xy 179.864933 -361.201188) (xy 179.880423 -361.148689)
			(xy 179.903263 -361.098944) (xy 179.932981 -361.052977) (xy 179.950618 -361.032044) (xy 179.950872 -361.03179)
			(xy 179.956477 -361.024717) (xy 179.962711 -361.007789) (xy 179.963064 -360.99877) (xy 179.963064 -360.931714)
			(xy 179.962708 -360.922697) (xy 179.95646 -360.90578) (xy 179.950872 -360.898694) (xy 179.950618 -360.898694)
			(xy 179.950618 -360.89844) (xy 179.932987 -360.877501) (xy 179.903273 -360.831531) (xy 179.880436 -360.781785)
			(xy 179.864943 -360.729286) (xy 179.857113 -360.675111) (xy 179.856638 -360.647742) (xy 179.857119 -360.620168)
			(xy 179.865067 -360.565595) (xy 179.880788 -360.512735) (xy 179.903955 -360.462689) (xy 179.934085 -360.416499)
			(xy 179.970551 -360.375128) (xy 179.991258 -360.356912) (xy 179.999337 -360.349361) (xy 180.008687 -360.329346)
			(xy 180.009292 -360.318304) (xy 180.009292 -360.24058) (xy 180.008682 -360.229536) (xy 179.999347 -360.209514)
			(xy 179.991258 -360.201972) (xy 179.970522 -360.183788) (xy 179.934055 -360.142413) (xy 179.903927 -360.096217)
			(xy 179.880766 -360.046164) (xy 179.865055 -359.993297) (xy 179.857121 -359.938718) (xy 179.856638 -359.911142)
			(xy 179.857119 -359.883772) (xy 179.864932 -359.829593) (xy 179.880417 -359.77709) (xy 179.903256 -359.727343)
			(xy 179.932978 -359.681376) (xy 179.950618 -359.660444) (xy 179.950872 -359.66019) (xy 179.956477 -359.653117)
			(xy 179.962711 -359.636189) (xy 179.963064 -359.62717) (xy 179.963064 -359.560114) (xy 179.962708 -359.551097)
			(xy 179.95646 -359.53418) (xy 179.950872 -359.527094) (xy 179.950618 -359.527094) (xy 179.950618 -359.52684)
			(xy 179.932987 -359.505901) (xy 179.903273 -359.459931) (xy 179.880436 -359.410185) (xy 179.864943 -359.357686)
			(xy 179.857113 -359.303511) (xy 179.856638 -359.276142) (xy 179.857095 -359.248888) (xy 179.864847 -359.194935)
			(xy 179.8802 -359.142634) (xy 179.902841 -359.093051) (xy 179.932309 -359.047195) (xy 179.968004 -359.006001)
			(xy 180.009198 -358.970306) (xy 180.055054 -358.940839) (xy 180.104637 -358.918199) (xy 180.156938 -358.902846)
			(xy 180.210892 -358.895094) (xy 180.238146 -358.894634) (xy 180.265515 -358.895123) (xy 180.319694 -358.902934)
			(xy 180.372197 -358.918418) (xy 180.421944 -358.941254) (xy 180.467912 -358.970975) (xy 180.488844 -358.988614)
			(xy 180.489098 -358.988868) (xy 180.496175 -358.994468) (xy 180.513099 -359.000705) (xy 180.522118 -359.00106)
			(xy 180.589174 -359.00106) (xy 180.598191 -359.000699) (xy 180.615108 -358.994455) (xy 180.622194 -358.988868)
			(xy 180.622194 -358.988614) (xy 180.622448 -358.988614) (xy 180.643381 -358.970973) (xy 180.689349 -358.941249)
			(xy 180.739095 -358.918403) (xy 180.791597 -358.902907) (xy 180.845775 -358.895078) (xy 180.900517 -358.895078)
			(xy 180.954695 -358.902907) (xy 181.007197 -358.918403) (xy 181.056943 -358.941249) (xy 181.102911 -358.970973)
			(xy 181.123844 -358.988614) (xy 181.124098 -358.988868) (xy 181.131175 -358.994468) (xy 181.148099 -359.000705)
			(xy 181.157118 -359.00106) (xy 181.224174 -359.00106) (xy 181.233191 -359.000699) (xy 181.250108 -358.994455)
			(xy 181.257194 -358.988868) (xy 181.257194 -358.988614) (xy 181.257448 -358.988614) (xy 181.278381 -358.970973)
			(xy 181.324349 -358.941249) (xy 181.374095 -358.918403) (xy 181.426597 -358.902907) (xy 181.480775 -358.895078)
			(xy 181.535517 -358.895078) (xy 181.589695 -358.902907) (xy 181.642197 -358.918403) (xy 181.691943 -358.941249)
			(xy 181.737911 -358.970973) (xy 181.758844 -358.988614) (xy 181.759098 -358.988868) (xy 181.766175 -358.994468)
			(xy 181.783099 -359.000705) (xy 181.792118 -359.00106) (xy 181.859174 -359.00106) (xy 181.868191 -359.000699)
			(xy 181.885108 -358.994455) (xy 181.892194 -358.988868) (xy 181.892194 -358.988614) (xy 181.892448 -358.988614)
			(xy 181.913391 -358.970988) (xy 181.95936 -358.941274) (xy 182.009105 -358.918435) (xy 182.061604 -358.902941)
			(xy 182.115778 -358.89511) (xy 182.143146 -358.894634) (xy 182.1704 -358.895035) (xy 182.224353 -358.902799)
			(xy 182.276652 -358.918162) (xy 182.326232 -358.940812) (xy 182.372085 -358.970287) (xy 182.413275 -359.005987)
			(xy 182.448966 -359.047186) (xy 182.478431 -359.093045) (xy 182.501069 -359.14263) (xy 182.51642 -359.194933)
			(xy 182.524171 -359.248888) (xy 182.524654 -359.276142) (xy 182.524165 -359.303512) (xy 182.516355 -359.35769)
			(xy 182.500871 -359.410193) (xy 182.478034 -359.459941) (xy 182.448314 -359.505908) (xy 182.430674 -359.52684)
			(xy 182.43042 -359.527094) (xy 182.42482 -359.534171) (xy 182.418584 -359.551096) (xy 182.418228 -359.560114)
			(xy 182.418228 -359.62717) (xy 182.418593 -359.636186) (xy 182.424835 -359.653103) (xy 182.43042 -359.66019)
			(xy 182.430674 -359.66019) (xy 182.430674 -359.660444) (xy 182.448296 -359.68139) (xy 182.478012 -359.727358)
			(xy 182.500851 -359.777102) (xy 182.516346 -359.8296) (xy 182.524178 -359.883774) (xy 182.524654 -359.911142)
			(xy 182.524161 -359.938392) (xy 182.5164 -359.992337) (xy 182.501042 -360.044629) (xy 182.4784 -360.094203)
			(xy 182.448933 -360.140051) (xy 182.413243 -360.18124) (xy 182.372055 -360.216931) (xy 182.326207 -360.246398)
			(xy 182.276633 -360.269041) (xy 182.224341 -360.2844) (xy 182.170396 -360.292161) (xy 182.143146 -360.29265)
			(xy 182.115776 -360.292169) (xy 182.061597 -360.284357) (xy 182.009094 -360.268872) (xy 181.959347 -360.246033)
			(xy 181.91338 -360.216311) (xy 181.892448 -360.19867) (xy 181.892194 -360.198416) (xy 181.885112 -360.192823)
			(xy 181.868192 -360.186579) (xy 181.859174 -360.186224) (xy 181.792118 -360.186224) (xy 181.783101 -360.186585)
			(xy 181.766184 -360.192829) (xy 181.759098 -360.198416) (xy 181.759098 -360.19867) (xy 181.758844 -360.19867)
			(xy 181.737911 -360.216311) (xy 181.691943 -360.246035) (xy 181.642197 -360.268881) (xy 181.589695 -360.284377)
			(xy 181.535517 -360.292206) (xy 181.480775 -360.292206) (xy 181.426597 -360.284377) (xy 181.374095 -360.268881)
			(xy 181.324349 -360.246035) (xy 181.278381 -360.216311) (xy 181.257448 -360.19867) (xy 181.257194 -360.198416)
			(xy 181.250112 -360.192823) (xy 181.233192 -360.186579) (xy 181.224174 -360.186224) (xy 181.157118 -360.186224)
			(xy 181.148101 -360.186585) (xy 181.131184 -360.192829) (xy 181.124098 -360.198416) (xy 181.124098 -360.19867)
			(xy 181.123844 -360.19867) (xy 181.102911 -360.216311) (xy 181.056943 -360.246035) (xy 181.007197 -360.268881)
			(xy 180.954695 -360.284377) (xy 180.900517 -360.292206) (xy 180.845775 -360.292206) (xy 180.791597 -360.284377)
			(xy 180.739095 -360.268881) (xy 180.689349 -360.246035) (xy 180.643381 -360.216311) (xy 180.622448 -360.19867)
			(xy 180.622194 -360.198416) (xy 180.615112 -360.192823) (xy 180.598192 -360.186579) (xy 180.589174 -360.186224)
			(xy 180.522118 -360.186224) (xy 180.513101 -360.186585) (xy 180.496184 -360.192829) (xy 180.489098 -360.198416)
			(xy 180.488844 -360.19867) (xy 180.485034 -360.201972) (xy 180.476922 -360.20958) (xy 180.467567 -360.229728)
			(xy 180.467 -360.240834) (xy 180.467 -360.318304) (xy 180.467621 -360.329347) (xy 180.476949 -360.349368)
			(xy 180.485034 -360.356912) (xy 180.505761 -360.375106) (xy 180.542229 -360.416479) (xy 180.572358 -360.462673)
			(xy 180.595521 -360.512724) (xy 180.611234 -360.565589) (xy 180.61917 -360.620166) (xy 180.619654 -360.647742)
			(xy 180.619165 -360.675112) (xy 180.611355 -360.72929) (xy 180.595871 -360.781793) (xy 180.573034 -360.831541)
			(xy 180.543314 -360.877508) (xy 180.525674 -360.89844) (xy 180.52542 -360.898694) (xy 180.51982 -360.905771)
			(xy 180.513584 -360.922696) (xy 180.513228 -360.931714) (xy 180.513228 -360.99877) (xy 180.513593 -361.007786)
			(xy 180.519835 -361.024703) (xy 180.52542 -361.03179) (xy 180.525674 -361.03179) (xy 180.525674 -361.032044)
			(xy 180.543356 -361.052943) (xy 180.573079 -361.098917) (xy 180.595922 -361.148669) (xy 180.611415 -361.201176)
			(xy 180.619239 -361.255359) (xy 180.619235 -361.310104) (xy 180.611401 -361.364286) (xy 180.595899 -361.416791)
			(xy 180.573048 -361.466539) (xy 180.568874 -361.472993) (xy 185.652165 -361.472993) (xy 185.655896 -361.419741)
			(xy 185.667013 -361.367529) (xy 185.685299 -361.317376) (xy 185.710397 -361.270262) (xy 185.741818 -361.227107)
			(xy 185.778948 -361.188752) (xy 185.79973 -361.171998) (xy 185.808533 -361.164387) (xy 185.818718 -361.143489)
			(xy 185.819288 -361.131866) (xy 185.819288 -361.05211) (xy 185.818733 -361.04048) (xy 185.808556 -361.01957)
			(xy 185.79973 -361.011978) (xy 185.777242 -360.993792) (xy 185.737506 -360.951772) (xy 185.704567 -360.904236)
			(xy 185.679179 -360.852274) (xy 185.661924 -360.797075) (xy 185.653197 -360.739904) (xy 185.652664 -360.710988)
			(xy 185.653167 -360.683738) (xy 185.660924 -360.629792) (xy 185.676279 -360.577499) (xy 185.69892 -360.527924)
			(xy 185.728385 -360.482075) (xy 185.764074 -360.440886) (xy 185.805262 -360.405194) (xy 185.85111 -360.375727)
			(xy 185.900684 -360.353085) (xy 185.952976 -360.337727) (xy 186.006922 -360.329968) (xy 186.034172 -360.32948)
			(xy 186.06309 -360.329988) (xy 186.120263 -360.338715) (xy 186.175463 -360.355973) (xy 186.227425 -360.381366)
			(xy 186.274959 -360.414313) (xy 186.316974 -360.454058) (xy 186.335162 -360.476546) (xy 186.342788 -360.485334)
			(xy 186.363675 -360.495526) (xy 186.375294 -360.496104) (xy 186.45505 -360.496104) (xy 186.466683 -360.495578)
			(xy 186.487593 -360.48538) (xy 186.495182 -360.476546) (xy 186.51337 -360.45406) (xy 186.555392 -360.414327)
			(xy 186.602928 -360.38139) (xy 186.654889 -360.356003) (xy 186.710087 -360.338746) (xy 186.767256 -360.330016)
			(xy 186.796172 -360.32948) (xy 186.823424 -360.329981) (xy 186.877373 -360.337734) (xy 186.929669 -360.353086)
			(xy 186.979248 -360.375724) (xy 187.025101 -360.405188) (xy 187.066294 -360.440878) (xy 187.101988 -360.482067)
			(xy 187.131456 -360.527917) (xy 187.1541 -360.577494) (xy 187.169457 -360.629788) (xy 187.177216 -360.683736)
			(xy 187.17768 -360.710988) (xy 187.177161 -360.739905) (xy 187.168433 -360.797076) (xy 187.151176 -360.852276)
			(xy 187.125784 -360.904237) (xy 187.092841 -360.951771) (xy 187.0531 -360.993788) (xy 187.030614 -361.011978)
			(xy 187.021812 -361.01959) (xy 187.011629 -361.040488) (xy 187.011056 -361.05211) (xy 187.011056 -361.131866)
			(xy 187.011609 -361.143497) (xy 187.021786 -361.164408) (xy 187.030614 -361.171998) (xy 187.051386 -361.188765)
			(xy 187.088519 -361.227115) (xy 187.119942 -361.270268) (xy 187.145044 -361.31738) (xy 187.163332 -361.367531)
			(xy 187.17445 -361.419742) (xy 187.178181 -361.472993) (xy 187.174452 -361.526244) (xy 187.163336 -361.578455)
			(xy 187.14505 -361.628607) (xy 187.11995 -361.67572) (xy 187.088528 -361.718873) (xy 187.051397 -361.757225)
			(xy 187.030614 -361.773978) (xy 187.021812 -361.78159) (xy 187.011629 -361.802488) (xy 187.011056 -361.81411)
			(xy 187.011056 -361.893866) (xy 187.011609 -361.905497) (xy 187.021786 -361.926408) (xy 187.030614 -361.933998)
			(xy 187.053099 -361.952187) (xy 187.092834 -361.994207) (xy 187.125772 -362.041743) (xy 187.15116 -362.093704)
			(xy 187.168416 -362.148902) (xy 187.177145 -362.206072) (xy 187.17768 -362.234988) (xy 187.177233 -362.262242)
			(xy 187.169477 -362.316195) (xy 187.154121 -362.368495) (xy 187.131478 -362.418077) (xy 187.102009 -362.463931)
			(xy 187.094223 -362.472916) (xy 190.790826 -362.472916) (xy 190.790826 -362.38822) (xy 190.798877 -362.303906)
			(xy 190.814906 -362.22074) (xy 190.838767 -362.139473) (xy 190.870246 -362.060843) (xy 190.909057 -361.985562)
			(xy 190.954847 -361.91431) (xy 191.007203 -361.847734) (xy 191.065651 -361.786436) (xy 191.129661 -361.730971)
			(xy 191.198653 -361.681842) (xy 191.272003 -361.639493) (xy 191.349046 -361.604309) (xy 191.429085 -361.576607)
			(xy 191.511394 -361.556639) (xy 191.595229 -361.544586) (xy 191.67983 -361.540556) (xy 191.764431 -361.544586)
			(xy 191.848266 -361.556639) (xy 191.930575 -361.576607) (xy 192.010614 -361.604309) (xy 192.087657 -361.639493)
			(xy 192.161007 -361.681842) (xy 192.229999 -361.730971) (xy 192.294009 -361.786436) (xy 192.352457 -361.847734)
			(xy 192.404813 -361.91431) (xy 192.450603 -361.985562) (xy 192.489414 -362.060843) (xy 192.520893 -362.139473)
			(xy 192.544754 -362.22074) (xy 192.560783 -362.303906) (xy 192.568834 -362.38822) (xy 192.569338 -362.430568)
			(xy 192.568834 -362.472916) (xy 192.560783 -362.55723) (xy 192.544754 -362.640396) (xy 192.520893 -362.721663)
			(xy 192.489414 -362.800293) (xy 192.450603 -362.875574) (xy 192.404813 -362.946826) (xy 192.352457 -363.013402)
			(xy 192.294009 -363.0747) (xy 192.229999 -363.130165) (xy 192.161007 -363.179294) (xy 192.087657 -363.221643)
			(xy 192.010614 -363.256827) (xy 191.930575 -363.284529) (xy 191.848266 -363.304497) (xy 191.764431 -363.31655)
			(xy 191.67983 -363.320581) (xy 191.595229 -363.31655) (xy 191.511394 -363.304497) (xy 191.429085 -363.284529)
			(xy 191.349046 -363.256827) (xy 191.272003 -363.221643) (xy 191.198653 -363.179294) (xy 191.129661 -363.130165)
			(xy 191.065651 -363.0747) (xy 191.007203 -363.013402) (xy 190.954847 -362.946826) (xy 190.909057 -362.875574)
			(xy 190.870246 -362.800293) (xy 190.838767 -362.721663) (xy 190.814906 -362.640396) (xy 190.798877 -362.55723)
			(xy 190.790826 -362.472916) (xy 187.094223 -362.472916) (xy 187.066313 -362.505125) (xy 187.025118 -362.540819)
			(xy 186.979263 -362.570286) (xy 186.92968 -362.592927) (xy 186.877379 -362.608281) (xy 186.823426 -362.616035)
			(xy 186.796172 -362.616496) (xy 186.767257 -362.615928) (xy 186.710088 -362.607209) (xy 186.65489 -362.589961)
			(xy 186.602928 -362.564579) (xy 186.555393 -362.531644) (xy 186.513374 -362.491912) (xy 186.495182 -362.46943)
			(xy 186.487585 -362.460613) (xy 186.466676 -362.450438) (xy 186.45505 -362.449872) (xy 186.375294 -362.449872)
			(xy 186.36366 -362.450397) (xy 186.342749 -362.460593) (xy 186.335162 -362.46943) (xy 186.317 -362.491938)
			(xy 186.274973 -362.53167) (xy 186.227432 -362.564605) (xy 186.175465 -362.589989) (xy 186.120263 -362.607241)
			(xy 186.06309 -362.615964) (xy 186.034172 -362.616496) (xy 186.00692 -362.616048) (xy 185.95297 -362.608288)
			(xy 185.900674 -362.592928) (xy 185.851095 -362.570283) (xy 185.805245 -362.540813) (xy 185.764054 -362.505117)
			(xy 185.728363 -362.463923) (xy 185.698898 -362.418069) (xy 185.676258 -362.368489) (xy 185.660904 -362.316191)
			(xy 185.653149 -362.262241) (xy 185.652664 -362.234988) (xy 185.653221 -362.206072) (xy 185.661939 -362.148902)
			(xy 185.679187 -362.093703) (xy 185.704572 -362.04174) (xy 185.73751 -361.994206) (xy 185.777246 -361.952188)
			(xy 185.79973 -361.933998) (xy 185.808533 -361.926387) (xy 185.818718 -361.905489) (xy 185.819288 -361.893866)
			(xy 185.819288 -361.81411) (xy 185.818733 -361.80248) (xy 185.808556 -361.78157) (xy 185.79973 -361.773978)
			(xy 185.778937 -361.757238) (xy 185.741809 -361.718882) (xy 185.71039 -361.675725) (xy 185.685293 -361.62861)
			(xy 185.667009 -361.578457) (xy 185.655894 -361.526245) (xy 185.652165 -361.472993) (xy 180.568874 -361.472993)
			(xy 180.543318 -361.512507) (xy 180.525674 -361.53344) (xy 180.52542 -361.533694) (xy 180.51982 -361.540771)
			(xy 180.513584 -361.557696) (xy 180.513228 -361.566714) (xy 180.513228 -361.63377) (xy 180.513593 -361.642786)
			(xy 180.519835 -361.659703) (xy 180.52542 -361.66679) (xy 180.525674 -361.66679) (xy 180.525674 -361.667044)
			(xy 180.543356 -361.687943) (xy 180.573079 -361.733917) (xy 180.595922 -361.783669) (xy 180.611415 -361.836176)
			(xy 180.619239 -361.890359) (xy 180.619235 -361.945104) (xy 180.611401 -361.999286) (xy 180.595899 -362.051791)
			(xy 180.573048 -362.101539) (xy 180.543318 -362.147507) (xy 180.525674 -362.16844) (xy 180.52542 -362.168694)
			(xy 180.51982 -362.175771) (xy 180.513584 -362.192696) (xy 180.513228 -362.201714) (xy 180.513228 -362.26877)
			(xy 180.513593 -362.277786) (xy 180.519835 -362.294703) (xy 180.52542 -362.30179) (xy 180.525674 -362.30179)
			(xy 180.525674 -362.302044) (xy 180.543296 -362.32299) (xy 180.573012 -362.368958) (xy 180.595851 -362.418702)
			(xy 180.611346 -362.4712) (xy 180.619178 -362.525374) (xy 180.619654 -362.552742) (xy 180.619164 -362.580316)
			(xy 180.611219 -362.634888) (xy 180.5955 -362.687748) (xy 180.572334 -362.737795) (xy 180.542205 -362.783985)
			(xy 180.50574 -362.825356) (xy 180.485034 -362.843572) (xy 180.47696 -362.851128) (xy 180.467608 -362.871139)
			(xy 180.467 -362.88218) (xy 180.467 -362.95965) (xy 180.46758 -362.970758) (xy 180.47691 -362.990917)
			(xy 180.485034 -362.998512) (xy 180.488844 -363.001814) (xy 180.489098 -363.002068) (xy 180.496175 -363.007668)
			(xy 180.513099 -363.013905) (xy 180.522118 -363.01426) (xy 180.589174 -363.01426) (xy 180.598191 -363.013899)
			(xy 180.615108 -363.007655) (xy 180.622194 -363.002068) (xy 180.622194 -363.001814) (xy 180.622448 -363.001814)
			(xy 180.643381 -362.984173) (xy 180.689349 -362.954449) (xy 180.739095 -362.931603) (xy 180.791597 -362.916107)
			(xy 180.845775 -362.908278) (xy 180.900517 -362.908278) (xy 180.954695 -362.916107) (xy 181.007197 -362.931603)
			(xy 181.056943 -362.954449) (xy 181.102911 -362.984173) (xy 181.123844 -363.001814) (xy 181.124098 -363.002068)
			(xy 181.131175 -363.007668) (xy 181.148099 -363.013905) (xy 181.157118 -363.01426) (xy 181.224174 -363.01426)
			(xy 181.233191 -363.013899) (xy 181.250108 -363.007655) (xy 181.257194 -363.002068) (xy 181.257194 -363.001814)
			(xy 181.257448 -363.001814) (xy 181.278381 -362.984173) (xy 181.324349 -362.954449) (xy 181.374095 -362.931603)
			(xy 181.426597 -362.916107) (xy 181.480775 -362.908278) (xy 181.535517 -362.908278) (xy 181.589695 -362.916107)
			(xy 181.642197 -362.931603) (xy 181.691943 -362.954449) (xy 181.737911 -362.984173) (xy 181.758844 -363.001814)
			(xy 181.759098 -363.002068) (xy 181.766175 -363.007668) (xy 181.783099 -363.013905) (xy 181.792118 -363.01426)
			(xy 181.859174 -363.01426) (xy 181.868191 -363.013899) (xy 181.885108 -363.007655) (xy 181.892194 -363.002068)
			(xy 181.892194 -363.001814) (xy 181.892448 -363.001814) (xy 181.913391 -362.984188) (xy 181.95936 -362.954474)
			(xy 182.009105 -362.931635) (xy 182.061604 -362.916141) (xy 182.115778 -362.90831) (xy 182.143146 -362.907834)
			(xy 182.1704 -362.908235) (xy 182.224353 -362.915999) (xy 182.276652 -362.931362) (xy 182.326232 -362.954012)
			(xy 182.372085 -362.983487) (xy 182.413275 -363.019187) (xy 182.448966 -363.060386) (xy 182.478431 -363.106245)
			(xy 182.501069 -363.15583) (xy 182.51642 -363.208133) (xy 182.524171 -363.262088) (xy 182.524654 -363.289342)
			(xy 182.524165 -363.316712) (xy 182.516355 -363.37089) (xy 182.500871 -363.423393) (xy 182.478034 -363.473141)
			(xy 182.448314 -363.519108) (xy 182.430674 -363.54004) (xy 182.43042 -363.540294) (xy 182.42482 -363.547371)
			(xy 182.418584 -363.564296) (xy 182.418228 -363.573314) (xy 182.418228 -363.64037) (xy 182.418593 -363.649386)
			(xy 182.424835 -363.666303) (xy 182.43042 -363.67339) (xy 182.430674 -363.67339) (xy 182.430674 -363.673644)
			(xy 182.448296 -363.69459) (xy 182.478012 -363.740558) (xy 182.500851 -363.790302) (xy 182.516346 -363.8428)
			(xy 182.524178 -363.896974) (xy 182.524654 -363.924342) (xy 182.524161 -363.951592) (xy 182.5164 -364.005537)
			(xy 182.501042 -364.057829) (xy 182.4784 -364.107403) (xy 182.448933 -364.153251) (xy 182.413243 -364.19444)
			(xy 182.372055 -364.230131) (xy 182.326207 -364.259598) (xy 182.276633 -364.282241) (xy 182.224341 -364.2976)
			(xy 182.170396 -364.305361) (xy 182.143146 -364.30585) (xy 182.115776 -364.305369) (xy 182.061597 -364.297557)
			(xy 182.009094 -364.282072) (xy 181.959347 -364.259233) (xy 181.91338 -364.229511) (xy 181.892448 -364.21187)
			(xy 181.892194 -364.211616) (xy 181.885112 -364.206023) (xy 181.868192 -364.199779) (xy 181.859174 -364.199424)
			(xy 181.792118 -364.199424) (xy 181.783101 -364.199785) (xy 181.766184 -364.206029) (xy 181.759098 -364.211616)
			(xy 181.758844 -364.21187) (xy 181.737911 -364.229511) (xy 181.691943 -364.259235) (xy 181.642197 -364.282081)
			(xy 181.589695 -364.297577) (xy 181.535517 -364.305406) (xy 181.480775 -364.305406) (xy 181.426597 -364.297577)
			(xy 181.374095 -364.282081) (xy 181.324349 -364.259235) (xy 181.278381 -364.229511) (xy 181.257448 -364.21187)
			(xy 181.257194 -364.211616) (xy 181.250112 -364.206023) (xy 181.233192 -364.199779) (xy 181.224174 -364.199424)
			(xy 181.157118 -364.199424) (xy 181.148101 -364.199785) (xy 181.131184 -364.206029) (xy 181.124098 -364.211616)
			(xy 181.124098 -364.21187) (xy 181.123844 -364.21187) (xy 181.102911 -364.229511) (xy 181.056943 -364.259235)
			(xy 181.007197 -364.282081) (xy 180.954695 -364.297577) (xy 180.900517 -364.305406) (xy 180.845775 -364.305406)
			(xy 180.791597 -364.297577) (xy 180.739095 -364.282081) (xy 180.689349 -364.259235) (xy 180.643381 -364.229511)
			(xy 180.622448 -364.21187) (xy 180.622194 -364.211616) (xy 180.615112 -364.206023) (xy 180.598192 -364.199779)
			(xy 180.589174 -364.199424) (xy 180.522118 -364.199424) (xy 180.513101 -364.199785) (xy 180.496184 -364.206029)
			(xy 180.489098 -364.211616) (xy 180.489098 -364.21187) (xy 180.488844 -364.21187) (xy 180.467902 -364.229497)
			(xy 180.421933 -364.259212) (xy 180.372188 -364.282051) (xy 180.319689 -364.297544) (xy 180.265515 -364.305375)
			(xy 180.238146 -364.30585) (xy 180.210896 -364.305302) (xy 180.15695 -364.297552) (xy 180.104657 -364.282204)
			(xy 180.05508 -364.25957) (xy 180.009228 -364.230111) (xy 179.968036 -364.194426) (xy 179.932342 -364.153242)
			(xy 179.902872 -364.107398) (xy 179.880226 -364.057826) (xy 179.864866 -364.005536) (xy 179.857104 -363.951592)
			(xy 179.856638 -363.924342) (xy 177.133853 -363.924342) (xy 176.386998 -364.671356) (xy 176.380161 -364.678758)
			(xy 176.372447 -364.697356) (xy 176.372012 -364.707424) (xy 176.372012 -364.973038) (xy 190.790826 -364.973038)
			(xy 190.790826 -364.888342) (xy 190.798877 -364.804028) (xy 190.814906 -364.720862) (xy 190.838767 -364.639595)
			(xy 190.870246 -364.560965) (xy 190.909057 -364.485684) (xy 190.954847 -364.414432) (xy 191.007203 -364.347856)
			(xy 191.065651 -364.286558) (xy 191.129661 -364.231093) (xy 191.198653 -364.181964) (xy 191.272003 -364.139615)
			(xy 191.349046 -364.104431) (xy 191.429085 -364.076729) (xy 191.511394 -364.056761) (xy 191.595229 -364.044708)
			(xy 191.67983 -364.040678) (xy 191.764431 -364.044708) (xy 191.848266 -364.056761) (xy 191.930575 -364.076729)
			(xy 192.010614 -364.104431) (xy 192.087657 -364.139615) (xy 192.161007 -364.181964) (xy 192.229999 -364.231093)
			(xy 192.294009 -364.286558) (xy 192.352457 -364.347856) (xy 192.404813 -364.414432) (xy 192.450603 -364.485684)
			(xy 192.489414 -364.560965) (xy 192.520893 -364.639595) (xy 192.544754 -364.720862) (xy 192.560783 -364.804028)
			(xy 192.568834 -364.888342) (xy 192.569338 -364.93069) (xy 192.568834 -364.973038) (xy 192.560783 -365.057352)
			(xy 192.544754 -365.140518) (xy 192.520893 -365.221785) (xy 192.489414 -365.300415) (xy 192.450603 -365.375696)
			(xy 192.404813 -365.446948) (xy 192.352457 -365.513524) (xy 192.294009 -365.574822) (xy 192.229999 -365.630287)
			(xy 192.161007 -365.679416) (xy 192.087657 -365.721765) (xy 192.010614 -365.756949) (xy 191.930575 -365.784651)
			(xy 191.848266 -365.804619) (xy 191.764431 -365.816672) (xy 191.67983 -365.820703) (xy 191.595229 -365.816672)
			(xy 191.511394 -365.804619) (xy 191.429085 -365.784651) (xy 191.349046 -365.756949) (xy 191.272003 -365.721765)
			(xy 191.198653 -365.679416) (xy 191.129661 -365.630287) (xy 191.065651 -365.574822) (xy 191.007203 -365.513524)
			(xy 190.954847 -365.446948) (xy 190.909057 -365.375696) (xy 190.870246 -365.300415) (xy 190.838767 -365.221785)
			(xy 190.814906 -365.140518) (xy 190.798877 -365.057352) (xy 190.790826 -364.973038) (xy 176.372012 -364.973038)
			(xy 176.372012 -365.334804) (xy 176.371543 -365.366016) (xy 176.36391 -365.427973) (xy 176.348747 -365.488528)
			(xy 176.326283 -365.546771) (xy 176.296856 -365.601824) (xy 176.260908 -365.65286) (xy 176.218981 -365.699109)
			(xy 176.171706 -365.739875) (xy 176.119794 -365.774546) (xy 176.092104 -365.788956) (xy 176.081944 -365.794036)
			(xy 176.067974 -365.811816) (xy 176.045114 -365.910368) (xy 176.049686 -365.931958) (xy 176.052734 -365.936276)
			(xy 176.073308 -365.964216) (xy 176.073308 -365.964724) (xy 176.079465 -365.974268) (xy 176.090773 -365.993967)
			(xy 176.095914 -366.004094) (xy 176.095914 -366.004348) (xy 176.099724 -366.011968) (xy 176.114456 -366.0267)
			(xy 176.121835 -366.033287) (xy 176.140135 -366.040745) (xy 176.150016 -366.041178) (xy 176.153572 -366.041178)
			(xy 176.164527 -366.040657) (xy 176.184453 -366.031549) (xy 176.19878 -366.014975) (xy 176.20234 -366.004602)
			(xy 176.209974 -365.977895) (xy 176.231905 -365.926864) (xy 176.260999 -365.879549) (xy 176.296644 -365.836951)
			(xy 176.338085 -365.799968) (xy 176.384449 -365.769382) (xy 176.434757 -365.745838) (xy 176.487945 -365.729833)
			(xy 176.542892 -365.721706) (xy 176.598436 -365.721628) (xy 176.653405 -365.7296) (xy 176.706638 -365.745455)
			(xy 176.757011 -365.768858) (xy 176.803461 -365.799313) (xy 176.845007 -365.836179) (xy 176.880771 -365.878677)
			(xy 176.909999 -365.92591) (xy 176.932073 -365.976879) (xy 176.939702 -366.003586) (xy 176.939702 -366.00384)
			(xy 176.942177 -366.011782) (xy 176.951521 -366.025534) (xy 176.95799 -366.030764) (xy 176.964594 -366.035844)
			(xy 176.980088 -366.041178) (xy 181.37378 -366.041178) (xy 181.378735 -366.041295) (xy 181.388458 -366.043209)
			(xy 181.393084 -366.044988) (xy 181.410102 -366.0521) (xy 181.414841 -366.05397) (xy 181.424821 -366.056015)
			(xy 181.429914 -366.056164) (xy 194.757802 -366.056164)
		)
		(stroke
			(width 0)
			(type solid)
		)
		(fill yes)
		(layer "In11.Cu")
		(net "GND")
	)
	(gr_poly
		(pts
			(xy 293.195502 -151.239474) (xy 293.20538 -151.239016) (xy 293.22368 -151.231574) (xy 293.231062 -151.224996)
			(xy 294.461438 -149.99462) (xy 294.461946 -149.994112) (xy 294.468523 -149.986729) (xy 294.475962 -149.96843)
			(xy 294.476424 -149.958552) (xy 294.476424 -146.557746) (xy 294.475992 -146.54768) (xy 294.468266 -146.529087)
			(xy 294.461438 -146.521678) (xy 293.273734 -145.333974) (xy 293.266622 -145.326608) (xy 293.247826 -145.318988)
			(xy 287.359852 -145.318988) (xy 287.349786 -145.318556) (xy 287.331195 -145.310828) (xy 287.323784 -145.304002)
			(xy 278.527764 -136.507982) (xy 278.520652 -136.500616) (xy 278.501856 -136.492996) (xy 269.955772 -136.492996)
			(xy 269.945768 -136.492503) (xy 269.927287 -136.484838) (xy 269.913144 -136.470686) (xy 269.905491 -136.4522)
			(xy 269.904972 -136.442196) (xy 269.904972 -132.330698) (xy 269.882467 -132.343901) (xy 269.834617 -132.364709)
			(xy 269.784378 -132.378801) (xy 269.732687 -132.385913) (xy 269.706598 -132.386324) (xy 269.679331 -132.385838)
			(xy 269.625353 -132.378076) (xy 269.573029 -132.362712) (xy 269.523424 -132.340058) (xy 269.477548 -132.310575)
			(xy 269.436335 -132.274864) (xy 269.400623 -132.23365) (xy 269.371141 -132.187774) (xy 269.348487 -132.138169)
			(xy 269.333123 -132.085845) (xy 269.325362 -132.031867) (xy 269.325362 -131.977333) (xy 269.333123 -131.923355)
			(xy 269.348487 -131.871031) (xy 269.371141 -131.821426) (xy 269.400623 -131.77555) (xy 269.436335 -131.734336)
			(xy 269.477548 -131.698625) (xy 269.523424 -131.669142) (xy 269.573029 -131.646488) (xy 269.625353 -131.631124)
			(xy 269.679331 -131.623362) (xy 269.706598 -131.6228) (xy 269.732687 -131.623226) (xy 269.784377 -131.630334)
			(xy 269.834617 -131.644419) (xy 269.88247 -131.665218) (xy 269.904972 -131.678426) (xy 269.904972 -131.555744)
			(xy 269.904585 -131.546216) (xy 269.897641 -131.52847) (xy 269.884696 -131.514486) (xy 269.87627 -131.510024)
			(xy 269.79372 -131.470146) (xy 269.787188 -131.467296) (xy 269.773134 -131.464964) (xy 269.766034 -131.465574)
			(xy 269.751556 -131.467098) (xy 269.728534 -131.486048) (xy 269.678847 -131.519017) (xy 269.625646 -131.545952)
			(xy 269.569662 -131.566484) (xy 269.511662 -131.580331) (xy 269.452441 -131.587304) (xy 269.422626 -131.587748)
			(xy 269.391878 -131.587304) (xy 269.33083 -131.579894) (xy 269.27112 -131.565179) (xy 269.213619 -131.543374)
			(xy 269.159166 -131.514797) (xy 269.108554 -131.479864) (xy 269.062523 -131.439085) (xy 269.021743 -131.393055)
			(xy 268.986809 -131.342445) (xy 268.958231 -131.287992) (xy 268.936424 -131.230492) (xy 268.921708 -131.170782)
			(xy 268.914297 -131.109734) (xy 268.913864 -131.078986) (xy 268.913864 -131.078732) (xy 268.914343 -131.046761)
			(xy 268.922353 -130.983323) (xy 268.938251 -130.921389) (xy 268.961787 -130.861936) (xy 268.992588 -130.805902)
			(xy 269.030169 -130.75417) (xy 269.073938 -130.707556) (xy 269.098268 -130.68681) (xy 269.107158 -130.679698)
			(xy 269.11681 -130.659124) (xy 269.11681 -130.559048) (xy 269.107158 -130.538474) (xy 269.098268 -130.531362)
			(xy 269.073961 -130.510592) (xy 269.030204 -130.463976) (xy 268.992632 -130.412245) (xy 268.961838 -130.356214)
			(xy 268.938305 -130.296766) (xy 268.922406 -130.234839) (xy 268.914391 -130.171408) (xy 268.913864 -130.13944)
			(xy 268.913864 -130.139186) (xy 268.91431 -130.10844) (xy 268.921724 -130.047395) (xy 268.936442 -129.98769)
			(xy 268.95825 -129.930194) (xy 268.986829 -129.875746) (xy 269.021763 -129.82514) (xy 269.062542 -129.779113)
			(xy 269.108571 -129.738338) (xy 269.15918 -129.703408) (xy 269.213631 -129.674833) (xy 269.271128 -129.65303)
			(xy 269.330835 -129.638317) (xy 269.39188 -129.630908) (xy 269.422626 -129.630424) (xy 269.42288 -129.630424)
			(xy 269.457219 -129.630982) (xy 269.525272 -129.640213) (xy 269.591463 -129.658524) (xy 269.654586 -129.685581)
			(xy 269.71349 -129.720891) (xy 269.740634 -129.74193) (xy 269.766542 -129.752852) (xy 269.773146 -129.753614)
			(xy 269.787116 -129.751074) (xy 269.87627 -129.708148) (xy 269.884665 -129.703644) (xy 269.897593 -129.68967)
			(xy 269.904539 -129.671946) (xy 269.904972 -129.662428) (xy 269.904972 -125.035056) (xy 269.882366 -125.00737)
			(xy 269.864586 -125.00356) (xy 269.833835 -124.996583) (xy 269.77422 -124.976033) (xy 269.7176 -124.948274)
			(xy 269.664845 -124.913731) (xy 269.616763 -124.872934) (xy 269.57409 -124.826509) (xy 269.53748 -124.775166)
			(xy 269.507496 -124.719693) (xy 269.484596 -124.66094) (xy 269.469131 -124.599808) (xy 269.461339 -124.537233)
			(xy 269.461338 -124.474175) (xy 269.469129 -124.4116) (xy 269.484593 -124.350468) (xy 269.507492 -124.291715)
			(xy 269.537476 -124.236241) (xy 269.574084 -124.184898) (xy 269.616757 -124.138472) (xy 269.664839 -124.097674)
			(xy 269.717593 -124.06313) (xy 269.774212 -124.03537) (xy 269.833827 -124.014819) (xy 269.864586 -124.00788)
			(xy 269.882366 -124.00407) (xy 269.904972 -123.976384) (xy 269.904972 -123.71705) (xy 269.904545 -123.703842)
			(xy 269.897749 -123.678316) (xy 269.884627 -123.65539) (xy 269.866058 -123.636602) (xy 269.843288 -123.623212)
			(xy 269.817843 -123.616118) (xy 269.804642 -123.61545) (xy 269.771627 -123.614478) (xy 269.706253 -123.605047)
			(xy 269.64265 -123.587234) (xy 269.581888 -123.561339) (xy 269.524988 -123.527796) (xy 269.472908 -123.487172)
			(xy 269.426525 -123.440148) (xy 269.386617 -123.387517) (xy 269.353858 -123.330163) (xy 269.328798 -123.269051)
			(xy 269.311858 -123.20521) (xy 269.303323 -123.139713) (xy 269.302738 -123.106688) (xy 269.303203 -123.075942)
			(xy 269.310616 -123.014899) (xy 269.325333 -122.955194) (xy 269.34714 -122.897699) (xy 269.375717 -122.843251)
			(xy 269.410649 -122.792645) (xy 269.451426 -122.746618) (xy 269.497454 -122.705842) (xy 269.548061 -122.670911)
			(xy 269.60251 -122.642335) (xy 269.660006 -122.62053) (xy 269.719711 -122.605814) (xy 269.780754 -122.598402)
			(xy 269.8115 -122.597926) (xy 269.82674 -122.59818) (xy 269.837154 -122.598434) (xy 269.856204 -122.591068)
			(xy 269.863824 -122.583448) (xy 269.870555 -122.576083) (xy 269.878274 -122.557707) (xy 269.878409 -122.537776)
			(xy 269.870941 -122.519297) (xy 269.864332 -122.51182) (xy 269.83309 -122.48007) (xy 269.814802 -122.47245)
			(xy 269.804642 -122.472196) (xy 269.7723 -122.471254) (xy 269.708236 -122.46218) (xy 269.645841 -122.445052)
			(xy 269.586123 -122.420146) (xy 269.530048 -122.387865) (xy 269.478521 -122.34873) (xy 269.432376 -122.303375)
			(xy 269.392358 -122.252531) (xy 269.359113 -122.197022) (xy 269.33318 -122.137743) (xy 269.314977 -122.075653)
			(xy 269.304798 -122.011755) (xy 269.303246 -121.979436) (xy 269.301468 -121.967498) (xy 269.292918 -121.934372)
			(xy 269.28374 -121.866577) (xy 269.28318 -121.83237) (xy 269.283627 -121.801625) (xy 269.291043 -121.740583)
			(xy 269.305762 -121.68088) (xy 269.327571 -121.623386) (xy 269.356151 -121.568941) (xy 269.391085 -121.518337)
			(xy 269.431864 -121.472313) (xy 269.477894 -121.431541) (xy 269.528502 -121.396614) (xy 269.582952 -121.368041)
			(xy 269.640448 -121.346241) (xy 269.700153 -121.33153) (xy 269.761197 -121.324123) (xy 269.791942 -121.323608)
			(xy 269.824962 -121.324624) (xy 269.836392 -121.325386) (xy 269.856458 -121.317766) (xy 269.864586 -121.309638)
			(xy 269.871301 -121.302181) (xy 269.878776 -121.283575) (xy 269.878557 -121.263525) (xy 269.870677 -121.245087)
			(xy 269.863824 -121.237756) (xy 269.830804 -121.205244) (xy 269.8115 -121.197624) (xy 269.801594 -121.197878)
			(xy 269.791942 -121.197878) (xy 269.75998 -121.1974) (xy 269.696559 -121.189393) (xy 269.634642 -121.1735)
			(xy 269.575205 -121.149971) (xy 269.519186 -121.119179) (xy 269.467468 -121.081607) (xy 269.420868 -121.03785)
			(xy 269.380119 -120.988597) (xy 269.345865 -120.934625) (xy 269.318646 -120.876785) (xy 269.298891 -120.81599)
			(xy 269.286913 -120.753198) (xy 269.282898 -120.6894) (xy 269.286913 -120.625602) (xy 269.298891 -120.56281)
			(xy 269.318646 -120.502015) (xy 269.345865 -120.444175) (xy 269.380119 -120.390203) (xy 269.420868 -120.34095)
			(xy 269.467468 -120.297193) (xy 269.519186 -120.259621) (xy 269.575205 -120.228829) (xy 269.634642 -120.2053)
			(xy 269.696559 -120.189407) (xy 269.75998 -120.1814) (xy 269.791942 -120.180862) (xy 269.801594 -120.180862)
			(xy 269.8115 -120.181116) (xy 269.830804 -120.173496) (xy 269.889732 -120.115584) (xy 269.896672 -120.108155)
			(xy 269.904519 -120.08942) (xy 269.904972 -120.079262) (xy 269.904972 -116.856256) (xy 269.880334 -116.827554)
			(xy 269.861538 -116.82476) (xy 269.829044 -116.819409) (xy 269.765696 -116.801412) (xy 269.7052 -116.775393)
			(xy 269.648565 -116.741787) (xy 269.596739 -116.701156) (xy 269.550587 -116.654179) (xy 269.510881 -116.601641)
			(xy 269.478284 -116.544419) (xy 269.453341 -116.483471) (xy 269.436469 -116.419814) (xy 269.42795 -116.354513)
			(xy 269.427452 -116.321586) (xy 269.427917 -116.290847) (xy 269.435329 -116.229818) (xy 269.450043 -116.170126)
			(xy 269.471844 -116.112644) (xy 269.500415 -116.058209) (xy 269.53534 -116.007614) (xy 269.576108 -115.961598)
			(xy 269.622125 -115.920831) (xy 269.672721 -115.885908) (xy 269.69974 -115.871244) (xy 269.712032 -115.864255)
			(xy 269.73248 -115.844741) (xy 269.746798 -115.820371) (xy 269.753891 -115.793011) (xy 269.753215 -115.764754)
			(xy 269.744823 -115.737764) (xy 269.729357 -115.714106) (xy 269.708001 -115.695591) (xy 269.695422 -115.689126)
			(xy 269.666593 -115.675125) (xy 269.612393 -115.640923) (xy 269.56292 -115.600181) (xy 269.518958 -115.553545)
			(xy 269.481205 -115.501755) (xy 269.45026 -115.445631) (xy 269.426612 -115.386064) (xy 269.410636 -115.323997)
			(xy 269.402586 -115.260415) (xy 269.402052 -115.22837) (xy 269.402533 -115.197076) (xy 269.410216 -115.13496)
			(xy 269.425463 -115.074256) (xy 269.448043 -115.015883) (xy 269.477615 -114.96072) (xy 269.513732 -114.909603)
			(xy 269.555848 -114.863304) (xy 269.603327 -114.822522) (xy 269.655451 -114.787874) (xy 269.68323 -114.773456)
			(xy 269.696184 -114.767106) (xy 269.71117 -114.742722) (xy 269.711424 -114.637312) (xy 269.711048 -114.627883)
			(xy 269.704228 -114.610301) (xy 269.691507 -114.596379) (xy 269.68323 -114.591846) (xy 269.655493 -114.577412)
			(xy 269.603449 -114.542756) (xy 269.556047 -114.50198) (xy 269.514004 -114.455697) (xy 269.477954 -114.404608)
			(xy 269.448441 -114.349484) (xy 269.425912 -114.291157) (xy 269.410705 -114.230507) (xy 269.403051 -114.16845)
			(xy 269.40256 -114.137186) (xy 269.402814 -114.121184) (xy 269.402814 -114.116358) (xy 269.401798 -114.08537)
			(xy 269.402278 -114.054086) (xy 269.409954 -113.991992) (xy 269.425186 -113.931307) (xy 269.447744 -113.872947)
			(xy 269.477288 -113.817795) (xy 269.513372 -113.766681) (xy 269.555452 -113.720377) (xy 269.602891 -113.679583)
			(xy 269.654975 -113.644914) (xy 269.682722 -113.630456) (xy 269.695082 -113.623739) (xy 269.715809 -113.604733)
			(xy 269.730565 -113.580795) (xy 269.73823 -113.553739) (xy 269.738224 -113.525618) (xy 269.730547 -113.498565)
			(xy 269.715781 -113.474633) (xy 269.695046 -113.455636) (xy 269.682722 -113.448846) (xy 269.655004 -113.434396)
			(xy 269.602998 -113.399713) (xy 269.555634 -113.35892) (xy 269.513624 -113.312631) (xy 269.477602 -113.261544)
			(xy 269.448112 -113.206428) (xy 269.425596 -113.148113) (xy 269.410396 -113.08748) (xy 269.402738 -113.025441)
			(xy 269.402306 -112.994186) (xy 269.402782 -112.96304) (xy 269.410399 -112.901214) (xy 269.425503 -112.84078)
			(xy 269.44787 -112.782641) (xy 269.477165 -112.727666) (xy 269.51295 -112.676677) (xy 269.55469 -112.630436)
			(xy 269.601762 -112.589636) (xy 269.653461 -112.554884) (xy 269.709014 -112.526702) (xy 269.767592 -112.50551)
			(xy 269.828318 -112.491626) (xy 269.859252 -112.487964) (xy 269.879064 -112.485932) (xy 269.904972 -112.45723)
			(xy 269.904972 -103.695754) (xy 269.89278 -103.673402) (xy 269.881858 -103.66629) (xy 269.810992 -103.619808)
			(xy 269.800126 -103.613438) (xy 269.775073 -103.611174) (xy 269.76324 -103.61549) (xy 269.762732 -103.615744)
			(xy 269.762478 -103.615744) (xy 269.738311 -103.625849) (xy 269.6879 -103.640087) (xy 269.636015 -103.647289)
			(xy 269.609824 -103.647748) (xy 269.582567 -103.647287) (xy 269.528608 -103.639532) (xy 269.476302 -103.624176)
			(xy 269.426713 -103.601533) (xy 269.380852 -103.572062) (xy 269.339652 -103.536365) (xy 269.303952 -103.495167)
			(xy 269.274479 -103.449308) (xy 269.251832 -103.399721) (xy 269.236473 -103.347416) (xy 269.228715 -103.293457)
			(xy 269.228715 -103.238943) (xy 269.236473 -103.184984) (xy 269.251832 -103.132679) (xy 269.274479 -103.083092)
			(xy 269.303952 -103.037233) (xy 269.339652 -102.996035) (xy 269.380852 -102.960338) (xy 269.426713 -102.930867)
			(xy 269.476302 -102.908224) (xy 269.528608 -102.892868) (xy 269.582567 -102.885113) (xy 269.609824 -102.884732)
			(xy 269.636491 -102.885172) (xy 269.689307 -102.892595) (xy 269.740572 -102.907306) (xy 269.789287 -102.929018)
			(xy 269.834501 -102.957307) (xy 269.855188 -102.97414) (xy 269.856712 -102.97541) (xy 269.856966 -102.97541)
			(xy 269.864461 -102.980708) (xy 269.882001 -102.98607) (xy 269.900303 -102.984881) (xy 269.917002 -102.977296)
			(xy 269.923768 -102.971092) (xy 271.610328 -101.284532) (xy 271.617726 -101.277686) (xy 271.636325 -101.269957)
			(xy 271.646396 -101.269546) (xy 278.657304 -101.269546) (xy 278.667373 -101.269971) (xy 278.685972 -101.277692)
			(xy 278.693372 -101.284532) (xy 281.056588 -103.647748) (xy 281.057096 -103.648256) (xy 281.06448 -103.654831)
			(xy 281.082779 -103.662266) (xy 281.092656 -103.662734) (xy 285.206694 -103.662734) (xy 285.216566 -103.662261)
			(xy 285.234848 -103.654802) (xy 285.242254 -103.648256) (xy 285.993078 -102.897432) (xy 286.000698 -102.875334)
			(xy 285.999174 -102.863396) (xy 285.997764 -102.851636) (xy 285.996238 -102.827996) (xy 285.996126 -102.816152)
			(xy 285.996126 -102.815644) (xy 285.996491 -102.792113) (xy 286.002313 -102.745412) (xy 286.013837 -102.699782)
			(xy 286.022034 -102.677722) (xy 286.02559 -102.668832) (xy 286.02559 -100.073206) (xy 286.025168 -100.063136)
			(xy 286.017454 -100.04453) (xy 286.010604 -100.037138) (xy 284.06725 -98.093784) (xy 284.060138 -98.086418)
			(xy 284.041342 -98.078798) (xy 273.37893 -98.078798) (xy 273.36995 -98.079153) (xy 273.353102 -98.085376)
			(xy 273.339461 -98.09706) (xy 273.334734 -98.104706) (xy 273.284442 -98.194114) (xy 273.285204 -98.2218)
			(xy 273.292316 -98.233484) (xy 273.310199 -98.263661) (xy 273.338404 -98.327885) (xy 273.35751 -98.395378)
			(xy 273.367152 -98.464857) (xy 273.367754 -98.49993) (xy 273.367262 -98.531704) (xy 273.359339 -98.594756)
			(xy 273.343621 -98.656329) (xy 273.320352 -98.715464) (xy 273.289895 -98.771238) (xy 273.252726 -98.822782)
			(xy 273.209423 -98.869292) (xy 273.185382 -98.890074) (xy 273.167094 -98.928936) (xy 273.167348 -98.933)
			(xy 273.17446 -99.027234) (xy 273.18716 -99.048062) (xy 273.197574 -99.054666) (xy 273.225871 -99.072756)
			(xy 273.276203 -99.117213) (xy 273.29765 -99.143058) (xy 273.297904 -99.143312) (xy 273.298158 -99.14382)
			(xy 273.302131 -99.148327) (xy 273.311763 -99.155502) (xy 273.317208 -99.158044) (xy 273.317716 -99.158298)
			(xy 273.323518 -99.160633) (xy 273.335853 -99.162682) (xy 273.3421 -99.162362) (xy 273.439382 -99.15398)
			(xy 273.460718 -99.14001) (xy 273.466814 -99.128834) (xy 273.48166 -99.102379) (xy 273.516721 -99.052871)
			(xy 273.557426 -99.007888) (xy 273.603196 -98.968071) (xy 273.653381 -98.933986) (xy 273.707267 -98.906117)
			(xy 273.764087 -98.884861) (xy 273.823033 -98.87052) (xy 273.883267 -98.863298) (xy 273.9136 -98.862896)
			(xy 273.945561 -98.863398) (xy 274.008978 -98.871409) (xy 274.070892 -98.887306) (xy 274.130324 -98.910837)
			(xy 274.186339 -98.941632) (xy 274.238053 -98.979204) (xy 274.28465 -99.022961) (xy 274.325395 -99.072213)
			(xy 274.359646 -99.126184) (xy 274.386862 -99.184022) (xy 274.406615 -99.244815) (xy 274.418593 -99.307605)
			(xy 274.422607 -99.3714) (xy 274.418593 -99.435195) (xy 274.406615 -99.497985) (xy 274.386862 -99.558778)
			(xy 274.359646 -99.616616) (xy 274.325395 -99.670587) (xy 274.28465 -99.719839) (xy 274.238053 -99.763596)
			(xy 274.186339 -99.801168) (xy 274.130324 -99.831963) (xy 274.070892 -99.855494) (xy 274.008978 -99.871391)
			(xy 273.945561 -99.879402) (xy 273.9136 -99.879912) (xy 273.880116 -99.87938) (xy 273.813726 -99.870593)
			(xy 273.749064 -99.85317) (xy 273.687246 -99.827415) (xy 273.629343 -99.79377) (xy 273.576354 -99.752819)
			(xy 273.529197 -99.705269) (xy 273.488687 -99.651943) (xy 273.47164 -99.623118) (xy 273.46529 -99.611942)
			(xy 273.4437 -99.59848) (xy 273.333718 -99.591114) (xy 273.31035 -99.601528) (xy 273.30273 -99.611942)
			(xy 273.284554 -99.634842) (xy 273.242416 -99.675367) (xy 273.19459 -99.708991) (xy 273.142197 -99.734929)
			(xy 273.08646 -99.752574) (xy 273.028685 -99.761513) (xy 272.999454 -99.762056) (xy 272.9992 -99.762056)
			(xy 272.971948 -99.76157) (xy 272.917997 -99.753814) (xy 272.8657 -99.738459) (xy 272.816119 -99.715819)
			(xy 272.770266 -99.686353) (xy 272.729071 -99.650663) (xy 272.693375 -99.609473) (xy 272.663904 -99.563623)
			(xy 272.641257 -99.514045) (xy 272.625896 -99.46175) (xy 272.618133 -99.4078) (xy 272.617692 -99.380548)
			(xy 272.618159 -99.353519) (xy 272.625782 -99.300003) (xy 272.640884 -99.248098) (xy 272.663161 -99.198845)
			(xy 272.692168 -99.15323) (xy 272.709386 -99.13239) (xy 272.717514 -99.122992) (xy 272.723102 -99.099116)
			(xy 272.697702 -98.994976) (xy 272.6817 -98.976434) (xy 272.67027 -98.971862) (xy 272.639253 -98.95887)
			(xy 272.580653 -98.92588) (xy 272.526916 -98.885449) (xy 272.478981 -98.838285) (xy 272.437685 -98.78521)
			(xy 272.40375 -98.727153) (xy 272.377768 -98.665127) (xy 272.360194 -98.600216) (xy 272.351334 -98.533554)
			(xy 272.350738 -98.49993) (xy 272.351326 -98.464856) (xy 272.360968 -98.395375) (xy 272.380074 -98.32788)
			(xy 272.408279 -98.263653) (xy 272.426176 -98.233484) (xy 272.433288 -98.2218) (xy 272.43405 -98.194114)
			(xy 272.383758 -98.104706) (xy 272.379037 -98.097067) (xy 272.365368 -98.085436) (xy 272.348534 -98.079212)
			(xy 272.339562 -98.078798) (xy 268.595602 -98.078798) (xy 268.588934 -98.078992) (xy 268.576061 -98.082467)
			(xy 268.570202 -98.085656) (xy 268.543786 -98.100896) (xy 268.534896 -98.109278) (xy 268.531594 -98.114866)
			(xy 268.515719 -98.139405) (xy 268.477706 -98.183796) (xy 268.455902 -98.203258) (xy 268.455648 -98.203258)
			(xy 268.451229 -98.207375) (xy 268.444293 -98.217257) (xy 268.441932 -98.222816) (xy 268.439871 -98.228354)
			(xy 268.438072 -98.240029) (xy 268.438376 -98.24593) (xy 268.445234 -98.327972) (xy 268.44691 -98.339858)
			(xy 268.459488 -98.360267) (xy 268.469364 -98.367088) (xy 268.469618 -98.367342) (xy 268.497374 -98.38465)
			(xy 268.548619 -98.425305) (xy 268.594226 -98.472197) (xy 268.633443 -98.524551) (xy 268.665622 -98.581501)
			(xy 268.690231 -98.642109) (xy 268.706865 -98.705372) (xy 268.715247 -98.770245) (xy 268.715744 -98.802952)
			(xy 268.715242 -98.834913) (xy 268.707231 -98.898331) (xy 268.691334 -98.960245) (xy 268.678588 -98.992436)
			(xy 271.10004 -98.992436) (xy 271.104111 -98.936814) (xy 271.116237 -98.882377) (xy 271.13616 -98.830286)
			(xy 271.163456 -98.781651) (xy 271.197542 -98.737508) (xy 271.237691 -98.698799) (xy 271.283049 -98.666348)
			(xy 271.332649 -98.640847) (xy 271.385433 -98.62284) (xy 271.440276 -98.61271) (xy 271.49601 -98.610673)
			(xy 271.551447 -98.616773) (xy 271.605404 -98.630879) (xy 271.656733 -98.652691) (xy 271.704339 -98.681745)
			(xy 271.747207 -98.71742) (xy 271.784424 -98.758957) (xy 271.815197 -98.80547) (xy 271.838869 -98.855967)
			(xy 271.854937 -98.909374) (xy 271.863057 -98.96455) (xy 271.863566 -98.992436) (xy 271.863057 -99.020322)
			(xy 271.854937 -99.075498) (xy 271.838869 -99.128905) (xy 271.815197 -99.179402) (xy 271.784424 -99.225915)
			(xy 271.747207 -99.267452) (xy 271.704339 -99.303127) (xy 271.656733 -99.332181) (xy 271.605404 -99.353993)
			(xy 271.551447 -99.368099) (xy 271.49601 -99.374199) (xy 271.440276 -99.372162) (xy 271.385433 -99.362032)
			(xy 271.332649 -99.344025) (xy 271.283049 -99.318524) (xy 271.237691 -99.286073) (xy 271.197542 -99.247364)
			(xy 271.163456 -99.203221) (xy 271.13616 -99.154586) (xy 271.116237 -99.102495) (xy 271.104111 -99.048058)
			(xy 271.10004 -98.992436) (xy 268.678588 -98.992436) (xy 268.667802 -99.019678) (xy 268.637008 -99.075693)
			(xy 268.599435 -99.127408) (xy 268.555678 -99.174005) (xy 268.506425 -99.21475) (xy 268.452454 -99.249001)
			(xy 268.394615 -99.276218) (xy 268.333822 -99.295971) (xy 268.271032 -99.307949) (xy 268.207236 -99.311963)
			(xy 268.14344 -99.307949) (xy 268.08065 -99.295971) (xy 268.019857 -99.276218) (xy 267.962018 -99.249001)
			(xy 267.908047 -99.21475) (xy 267.858794 -99.174005) (xy 267.815037 -99.127408) (xy 267.777464 -99.075693)
			(xy 267.74667 -99.019678) (xy 267.723138 -98.960245) (xy 267.707241 -98.898331) (xy 267.69923 -98.834913)
			(xy 267.698728 -98.802952) (xy 267.699237 -98.770248) (xy 267.707629 -98.705379) (xy 267.724269 -98.642122)
			(xy 267.748882 -98.58152) (xy 267.781061 -98.524575) (xy 267.820275 -98.472224) (xy 267.865878 -98.425334)
			(xy 267.917116 -98.384677) (xy 267.944854 -98.367342) (xy 267.945108 -98.367088) (xy 267.955018 -98.360297)
			(xy 267.967608 -98.339876) (xy 267.969238 -98.327972) (xy 267.976096 -98.24593) (xy 267.976408 -98.240029)
			(xy 267.974605 -98.228353) (xy 267.97254 -98.222816) (xy 267.97017 -98.217263) (xy 267.963233 -98.207384)
			(xy 267.958824 -98.203258) (xy 267.95857 -98.203258) (xy 267.936763 -98.183799) (xy 267.898746 -98.13941)
			(xy 267.882878 -98.114866) (xy 267.879576 -98.109278) (xy 267.870686 -98.100896) (xy 267.84427 -98.085656)
			(xy 267.838393 -98.082511) (xy 267.825531 -98.079034) (xy 267.81887 -98.078798) (xy 267.364464 -98.078798)
			(xy 267.354397 -98.078368) (xy 267.335802 -98.070644) (xy 267.328396 -98.063812) (xy 267.253212 -97.988628)
			(xy 267.2458 -97.981944) (xy 267.227367 -97.974347) (xy 267.207429 -97.974347) (xy 267.188996 -97.981944)
			(xy 267.181584 -97.988628) (xy 266.056872 -99.11334) (xy 266.049506 -99.120452) (xy 266.041886 -99.139248)
			(xy 266.041886 -100.37953) (xy 274.848064 -100.37953) (xy 274.852135 -100.323908) (xy 274.864261 -100.269471)
			(xy 274.884184 -100.21738) (xy 274.91148 -100.168745) (xy 274.945566 -100.124602) (xy 274.985715 -100.085893)
			(xy 275.031073 -100.053442) (xy 275.080673 -100.027941) (xy 275.133457 -100.009934) (xy 275.1883 -99.999804)
			(xy 275.244034 -99.997767) (xy 275.299471 -100.003867) (xy 275.353428 -100.017973) (xy 275.404757 -100.039785)
			(xy 275.452363 -100.068839) (xy 275.495231 -100.104514) (xy 275.532448 -100.146051) (xy 275.563221 -100.192564)
			(xy 275.586893 -100.243061) (xy 275.602961 -100.296468) (xy 275.611081 -100.351644) (xy 275.61159 -100.37953)
			(xy 275.611081 -100.407416) (xy 275.60898 -100.421694) (xy 279.51125 -100.421694) (xy 279.515321 -100.366072)
			(xy 279.527447 -100.311635) (xy 279.54737 -100.259544) (xy 279.574666 -100.210909) (xy 279.608752 -100.166766)
			(xy 279.648901 -100.128057) (xy 279.694259 -100.095606) (xy 279.743859 -100.070105) (xy 279.796643 -100.052098)
			(xy 279.851486 -100.041968) (xy 279.90722 -100.039931) (xy 279.962657 -100.046031) (xy 280.016614 -100.060137)
			(xy 280.067943 -100.081949) (xy 280.115549 -100.111003) (xy 280.158417 -100.146678) (xy 280.195634 -100.188215)
			(xy 280.226407 -100.234728) (xy 280.250079 -100.285225) (xy 280.266147 -100.338632) (xy 280.274267 -100.393808)
			(xy 280.274776 -100.421694) (xy 280.274267 -100.44958) (xy 280.266147 -100.504756) (xy 280.250079 -100.558163)
			(xy 280.226407 -100.60866) (xy 280.195634 -100.655173) (xy 280.158417 -100.69671) (xy 280.115549 -100.732385)
			(xy 280.067943 -100.761439) (xy 280.016614 -100.783251) (xy 279.962657 -100.797357) (xy 279.90722 -100.803457)
			(xy 279.851486 -100.80142) (xy 279.796643 -100.79129) (xy 279.743859 -100.773283) (xy 279.694259 -100.747782)
			(xy 279.648901 -100.715331) (xy 279.608752 -100.676622) (xy 279.574666 -100.632479) (xy 279.54737 -100.583844)
			(xy 279.527447 -100.531753) (xy 279.515321 -100.477316) (xy 279.51125 -100.421694) (xy 275.60898 -100.421694)
			(xy 275.602961 -100.462592) (xy 275.586893 -100.515999) (xy 275.563221 -100.566496) (xy 275.532448 -100.613009)
			(xy 275.495231 -100.654546) (xy 275.452363 -100.690221) (xy 275.404757 -100.719275) (xy 275.353428 -100.741087)
			(xy 275.299471 -100.755193) (xy 275.244034 -100.761293) (xy 275.1883 -100.759256) (xy 275.133457 -100.749126)
			(xy 275.080673 -100.731119) (xy 275.031073 -100.705618) (xy 274.985715 -100.673167) (xy 274.945566 -100.634458)
			(xy 274.91148 -100.590315) (xy 274.884184 -100.54168) (xy 274.864261 -100.489589) (xy 274.852135 -100.435152)
			(xy 274.848064 -100.37953) (xy 266.041886 -100.37953) (xy 266.041886 -103.302265) (xy 266.828264 -103.302265)
			(xy 266.828264 -103.238343) (xy 266.836275 -103.174925) (xy 266.852172 -103.113011) (xy 266.875704 -103.053578)
			(xy 266.906498 -102.997563) (xy 266.944071 -102.945848) (xy 266.987828 -102.899251) (xy 267.037081 -102.858506)
			(xy 267.091052 -102.824255) (xy 267.148891 -102.797038) (xy 267.209684 -102.777285) (xy 267.272474 -102.765307)
			(xy 267.33627 -102.761294) (xy 267.400066 -102.765307) (xy 267.462856 -102.777285) (xy 267.523649 -102.797038)
			(xy 267.581488 -102.824255) (xy 267.635459 -102.858506) (xy 267.684712 -102.899251) (xy 267.728469 -102.945848)
			(xy 267.766042 -102.997563) (xy 267.796836 -103.053578) (xy 267.820368 -103.113011) (xy 267.836265 -103.174925)
			(xy 267.844276 -103.238343) (xy 267.844778 -103.270304) (xy 267.844276 -103.302265) (xy 267.836265 -103.365683)
			(xy 267.820368 -103.427597) (xy 267.796836 -103.48703) (xy 267.766042 -103.543045) (xy 267.728469 -103.59476)
			(xy 267.684712 -103.641357) (xy 267.635459 -103.682102) (xy 267.581488 -103.716353) (xy 267.523649 -103.74357)
			(xy 267.462856 -103.763323) (xy 267.400066 -103.775301) (xy 267.33627 -103.779315) (xy 267.272474 -103.775301)
			(xy 267.209684 -103.763323) (xy 267.148891 -103.74357) (xy 267.091052 -103.716353) (xy 267.037081 -103.682102)
			(xy 266.987828 -103.641357) (xy 266.944071 -103.59476) (xy 266.906498 -103.543045) (xy 266.875704 -103.48703)
			(xy 266.852172 -103.427597) (xy 266.836275 -103.365683) (xy 266.828264 -103.302265) (xy 266.041886 -103.302265)
			(xy 266.041886 -107.671616) (xy 266.04146 -107.681685) (xy 266.03374 -107.700284) (xy 266.0269 -107.707684)
			(xy 265.69924 -108.035344) (xy 265.697208 -108.03763) (xy 265.696954 -108.03763) (xy 265.6908 -108.045235)
			(xy 265.68428 -108.06366) (xy 265.684254 -108.073444) (xy 265.687556 -108.158534) (xy 265.6967 -108.17733)
			(xy 265.704828 -108.184442) (xy 265.725174 -108.202631) (xy 265.760967 -108.243827) (xy 265.790522 -108.289705)
			(xy 265.813233 -108.339329) (xy 265.828638 -108.391683) (xy 265.83642 -108.445699) (xy 265.836908 -108.472986)
			(xy 265.836446 -108.50024) (xy 265.82869 -108.554192) (xy 265.813335 -108.606491) (xy 265.790694 -108.656073)
			(xy 265.761226 -108.701928) (xy 265.725532 -108.743123) (xy 265.684339 -108.778818) (xy 265.638486 -108.808287)
			(xy 265.588905 -108.830931) (xy 265.536606 -108.846287) (xy 265.482653 -108.854045) (xy 265.4554 -108.854494)
			(xy 265.428112 -108.854027) (xy 265.374095 -108.846244) (xy 265.321739 -108.830837) (xy 265.272116 -108.808121)
			(xy 265.22624 -108.77856) (xy 265.185048 -108.742758) (xy 265.166856 -108.722414) (xy 265.159744 -108.714286)
			(xy 265.140948 -108.705142) (xy 265.055858 -108.70184) (xy 265.046081 -108.701892) (xy 265.027666 -108.708417)
			(xy 265.020044 -108.71454) (xy 264.611612 -109.122972) (xy 268.17193 -109.122972) (xy 268.172425 -109.091412)
			(xy 268.180235 -109.028778) (xy 268.195732 -108.96759) (xy 268.218678 -108.908789) (xy 268.24872 -108.853277)
			(xy 268.266672 -108.827316) (xy 268.272422 -108.818417) (xy 268.276826 -108.79772) (xy 268.272439 -108.777021)
			(xy 268.266672 -108.768134) (xy 268.24875 -108.742221) (xy 268.218775 -108.6868) (xy 268.195885 -108.628098)
			(xy 268.180431 -108.567015) (xy 268.172652 -108.50449) (xy 268.172184 -108.472986) (xy 268.172643 -108.442255)
			(xy 268.180053 -108.381241) (xy 268.194763 -108.321566) (xy 268.216559 -108.264098) (xy 268.245122 -108.209677)
			(xy 268.280037 -108.159095) (xy 268.320794 -108.11309) (xy 268.366799 -108.072333) (xy 268.417382 -108.037419)
			(xy 268.471804 -108.008856) (xy 268.529271 -107.987061) (xy 268.588947 -107.972352) (xy 268.649961 -107.964943)
			(xy 268.680692 -107.964478) (xy 268.711422 -107.964964) (xy 268.772435 -107.972371) (xy 268.83211 -107.987078)
			(xy 268.889577 -108.008871) (xy 268.943998 -108.037432) (xy 268.99458 -108.072345) (xy 269.040584 -108.1131)
			(xy 269.081341 -108.159103) (xy 269.116256 -108.209683) (xy 269.14482 -108.264103) (xy 269.166615 -108.321569)
			(xy 269.181325 -108.381243) (xy 269.188735 -108.442256) (xy 269.1892 -108.472986) (xy 269.188731 -108.504488)
			(xy 269.18092 -108.567005) (xy 269.165453 -108.628081) (xy 269.142567 -108.686781) (xy 269.112611 -108.742207)
			(xy 269.094712 -108.768134) (xy 269.088991 -108.777032) (xy 269.084674 -108.797721) (xy 269.089008 -108.818405)
			(xy 269.094712 -108.827316) (xy 269.112695 -108.853257) (xy 269.142741 -108.908772) (xy 269.165687 -108.967577)
			(xy 269.18118 -109.02877) (xy 269.188982 -109.09141) (xy 269.189454 -109.122972) (xy 269.188952 -109.154949)
			(xy 269.180937 -109.218399) (xy 269.165032 -109.280344) (xy 269.141489 -109.339806) (xy 269.110679 -109.39585)
			(xy 269.073087 -109.44759) (xy 269.029308 -109.49421) (xy 268.98003 -109.534976) (xy 268.926032 -109.569244)
			(xy 268.868165 -109.596475) (xy 268.807341 -109.616238) (xy 268.74452 -109.628221) (xy 268.680692 -109.632237)
			(xy 268.616864 -109.628221) (xy 268.554043 -109.616238) (xy 268.493219 -109.596475) (xy 268.435352 -109.569244)
			(xy 268.381354 -109.534976) (xy 268.332076 -109.49421) (xy 268.288297 -109.44759) (xy 268.250705 -109.39585)
			(xy 268.219895 -109.339806) (xy 268.196352 -109.280344) (xy 268.180447 -109.218399) (xy 268.172432 -109.154949)
			(xy 268.17193 -109.122972) (xy 264.611612 -109.122972) (xy 260.855984 -112.8786) (xy 262.35503 -112.8786)
			(xy 262.359047 -112.814768) (xy 262.371032 -112.751943) (xy 262.390797 -112.691115) (xy 262.418031 -112.633245)
			(xy 262.452303 -112.579244) (xy 262.493074 -112.529965) (xy 262.539699 -112.486185) (xy 262.591445 -112.448594)
			(xy 262.647494 -112.417785) (xy 262.706962 -112.394245) (xy 262.768912 -112.378343) (xy 262.832367 -112.370333)
			(xy 262.864346 -112.369854) (xy 262.897098 -112.370362) (xy 262.962058 -112.378781) (xy 263.025402 -112.395462)
			(xy 263.086084 -112.420129) (xy 263.143101 -112.452375) (xy 263.195512 -112.491666) (xy 263.242451 -112.537355)
			(xy 263.283143 -112.588687) (xy 263.300464 -112.616488) (xy 263.305245 -112.623802) (xy 263.318726 -112.634898)
			(xy 263.335167 -112.640776) (xy 263.343898 -112.641126) (xy 263.430258 -112.641126) (xy 263.438979 -112.640746)
			(xy 263.455391 -112.634832) (xy 263.468882 -112.623773) (xy 263.473692 -112.616488) (xy 263.491022 -112.588691)
			(xy 263.531702 -112.537347) (xy 263.578633 -112.491648) (xy 263.631042 -112.45235) (xy 263.68806 -112.420103)
			(xy 263.748745 -112.395439) (xy 263.812093 -112.378766) (xy 263.877057 -112.370361) (xy 263.90981 -112.369854)
			(xy 263.940066 -112.370288) (xy 264.000152 -112.377452) (xy 264.058966 -112.391688) (xy 264.115676 -112.412797)
			(xy 264.169485 -112.44048) (xy 264.219631 -112.474348) (xy 264.242804 -112.493806) (xy 264.249662 -112.499902)
			(xy 264.26668 -112.506252) (xy 264.31494 -112.506252) (xy 264.331958 -112.499902) (xy 264.338816 -112.493806)
			(xy 264.361981 -112.474335) (xy 264.41212 -112.440451) (xy 264.465927 -112.412757) (xy 264.522641 -112.391647)
			(xy 264.58146 -112.377418) (xy 264.641552 -112.370271) (xy 264.67181 -112.369854) (xy 264.704001 -112.370355)
			(xy 264.767868 -112.378475) (xy 264.830202 -112.394582) (xy 264.890007 -112.418422) (xy 264.946329 -112.449612)
			(xy 264.998269 -112.487655) (xy 265.044997 -112.531943) (xy 265.065764 -112.556544) (xy 265.07186 -112.564164)
			(xy 265.088878 -112.573562) (xy 265.178286 -112.584484) (xy 265.186922 -112.582198) (xy 265.191576 -112.580788)
			(xy 265.200271 -112.576436) (xy 265.204194 -112.573562) (xy 265.229166 -112.555504) (xy 265.283724 -112.526853)
			(xy 265.342173 -112.50733) (xy 265.402998 -112.497441) (xy 265.43381 -112.496854) (xy 265.459043 -112.497264)
			(xy 265.50907 -112.503909) (xy 265.557786 -112.517084) (xy 265.604343 -112.536558) (xy 265.626342 -112.548924)
			(xy 265.636705 -112.554335) (xy 265.659988 -112.55609) (xy 265.681637 -112.547343) (xy 265.689842 -112.539018)
			(xy 265.71055 -112.516563) (xy 265.75649 -112.476301) (xy 265.806918 -112.441826) (xy 265.861108 -112.413631)
			(xy 265.918282 -112.392124) (xy 265.97762 -112.377612) (xy 266.038267 -112.370304) (xy 266.06881 -112.369854)
			(xy 266.100788 -112.370325) (xy 266.164238 -112.378341) (xy 266.226184 -112.394247) (xy 266.285648 -112.417792)
			(xy 266.341692 -112.448603) (xy 266.393432 -112.486196) (xy 266.440053 -112.529977) (xy 266.480819 -112.579255)
			(xy 266.515088 -112.633255) (xy 266.542318 -112.691123) (xy 266.562081 -112.751949) (xy 266.574065 -112.814771)
			(xy 266.578081 -112.8786) (xy 266.574065 -112.942429) (xy 266.562081 -113.005251) (xy 266.542318 -113.066077)
			(xy 266.515088 -113.123945) (xy 266.480819 -113.177945) (xy 266.440053 -113.227223) (xy 266.393432 -113.271004)
			(xy 266.341692 -113.308597) (xy 266.285648 -113.339408) (xy 266.226184 -113.362953) (xy 266.164238 -113.378859)
			(xy 266.100788 -113.386875) (xy 266.06881 -113.387378) (xy 266.038267 -113.386915) (xy 265.97762 -113.379616)
			(xy 265.918283 -113.365108) (xy 265.86111 -113.343601) (xy 265.806922 -113.315404) (xy 265.7565 -113.280922)
			(xy 265.710568 -113.240652) (xy 265.689842 -113.218214) (xy 265.681599 -113.209938) (xy 265.659966 -113.201205)
			(xy 265.636699 -113.20291) (xy 265.626342 -113.208308) (xy 265.604341 -113.220671) (xy 265.557785 -113.240148)
			(xy 265.50907 -113.253325) (xy 265.459043 -113.259971) (xy 265.43381 -113.260378) (xy 265.408202 -113.25997)
			(xy 265.357442 -113.253165) (xy 265.30805 -113.239622) (xy 265.260918 -113.219586) (xy 265.216893 -113.193417)
			(xy 265.196574 -113.177828) (xy 265.187938 -113.175288) (xy 265.183142 -113.174113) (xy 265.173289 -113.173479)
			(xy 265.16838 -113.174018) (xy 265.088878 -113.18367) (xy 265.07186 -113.193068) (xy 265.065764 -113.200688)
			(xy 265.044985 -113.225279) (xy 264.998261 -113.269572) (xy 264.946325 -113.307618) (xy 264.890005 -113.338812)
			(xy 264.830201 -113.362653) (xy 264.767868 -113.378763) (xy 264.704001 -113.386883) (xy 264.67181 -113.387378)
			(xy 264.641555 -113.386924) (xy 264.581469 -113.379764) (xy 264.522657 -113.36553) (xy 264.465946 -113.344425)
			(xy 264.412137 -113.316746) (xy 264.36199 -113.282882) (xy 264.338816 -113.263426) (xy 264.331958 -113.25733)
			(xy 264.31494 -113.25098) (xy 264.26668 -113.25098) (xy 264.249662 -113.25733) (xy 264.242804 -113.263426)
			(xy 264.219623 -113.282877) (xy 264.169488 -113.316765) (xy 264.115685 -113.344463) (xy 264.058974 -113.365577)
			(xy 264.000157 -113.37981) (xy 263.940067 -113.386959) (xy 263.90981 -113.387378) (xy 263.877058 -113.38689)
			(xy 263.812097 -113.378466) (xy 263.748753 -113.361781) (xy 263.688072 -113.33711) (xy 263.631055 -113.304862)
			(xy 263.578644 -113.265568) (xy 263.531705 -113.219878) (xy 263.491013 -113.168546) (xy 263.473692 -113.140744)
			(xy 263.468928 -113.133417) (xy 263.455441 -113.12232) (xy 263.438992 -113.116449) (xy 263.430258 -113.116106)
			(xy 263.343898 -113.116106) (xy 263.335178 -113.116487) (xy 263.318769 -113.122406) (xy 263.305277 -113.133462)
			(xy 263.300464 -113.140744) (xy 263.283139 -113.168545) (xy 263.242462 -113.219892) (xy 263.195531 -113.265593)
			(xy 263.143122 -113.304892) (xy 263.086102 -113.33714) (xy 263.025415 -113.361803) (xy 262.962065 -113.378472)
			(xy 262.897099 -113.386873) (xy 262.864346 -113.387378) (xy 262.832367 -113.386867) (xy 262.768912 -113.378857)
			(xy 262.706962 -113.362955) (xy 262.647494 -113.339415) (xy 262.591445 -113.308606) (xy 262.539699 -113.271015)
			(xy 262.493074 -113.227235) (xy 262.452303 -113.177956) (xy 262.418031 -113.123955) (xy 262.390797 -113.066085)
			(xy 262.371032 -113.005257) (xy 262.359047 -112.942432) (xy 262.35503 -112.8786) (xy 260.855984 -112.8786)
			(xy 259.833872 -113.900712) (xy 259.827054 -113.90819) (xy 259.819426 -113.926918) (xy 259.819598 -113.947138)
			(xy 259.823204 -113.956592) (xy 259.860542 -114.043714) (xy 259.863825 -114.050522) (xy 259.873637 -114.06201)
			(xy 259.879846 -114.06632) (xy 259.892546 -114.074702) (xy 259.92328 -114.073686) (xy 259.950966 -114.074448)
			(xy 259.955804 -114.074638) (xy 259.9654 -114.073367) (xy 259.970016 -114.071908) (xy 259.978144 -114.069114)
			(xy 260.045962 -114.012726) (xy 260.055106 -113.996216) (xy 260.056122 -113.986564) (xy 260.06048 -113.956276)
			(xy 260.075517 -113.896961) (xy 260.097562 -113.839878) (xy 260.126297 -113.785852) (xy 260.161306 -113.735664)
			(xy 260.202084 -113.690039) (xy 260.248041 -113.649636) (xy 260.298513 -113.615039) (xy 260.352772 -113.586747)
			(xy 260.410034 -113.565169) (xy 260.469471 -113.550617) (xy 260.530224 -113.543302) (xy 260.56082 -113.542826)
			(xy 260.591566 -113.543291) (xy 260.652609 -113.550705) (xy 260.712313 -113.565423) (xy 260.769809 -113.58723)
			(xy 260.824256 -113.615807) (xy 260.874862 -113.650739) (xy 260.920889 -113.691516) (xy 260.961665 -113.737544)
			(xy 260.996597 -113.788151) (xy 261.025174 -113.842599) (xy 261.046979 -113.900094) (xy 261.061696 -113.959799)
			(xy 261.069109 -114.020842) (xy 261.069582 -114.051588) (xy 261.069582 -114.052096) (xy 261.069019 -114.085753)
			(xy 261.060103 -114.152476) (xy 261.042466 -114.21744) (xy 261.029958 -114.248692) (xy 261.025386 -114.259614)
			(xy 261.026656 -114.282728) (xy 261.076948 -114.372898) (xy 261.096252 -114.386106) (xy 261.107936 -114.387884)
			(xy 261.134698 -114.392402) (xy 261.186676 -114.408014) (xy 261.235919 -114.43083) (xy 261.281436 -114.460389)
			(xy 261.322307 -114.496095) (xy 261.35771 -114.53723) (xy 261.386931 -114.582965) (xy 261.409381 -114.632376)
			(xy 261.424608 -114.684468) (xy 261.432303 -114.738192) (xy 261.432802 -114.765328) (xy 261.432316 -114.792597)
			(xy 261.424554 -114.846581) (xy 261.409189 -114.898911) (xy 261.386532 -114.948521) (xy 261.357046 -114.994402)
			(xy 261.327988 -115.027937) (xy 264.509498 -115.027937) (xy 264.509498 -114.963983) (xy 264.517513 -114.900533)
			(xy 264.533418 -114.838588) (xy 264.556961 -114.779126) (xy 264.587771 -114.723082) (xy 264.625363 -114.671342)
			(xy 264.669142 -114.624722) (xy 264.71842 -114.583956) (xy 264.772418 -114.549688) (xy 264.830285 -114.522457)
			(xy 264.891109 -114.502694) (xy 264.95393 -114.490711) (xy 265.017758 -114.486695) (xy 265.081586 -114.490711)
			(xy 265.144407 -114.502694) (xy 265.205231 -114.522457) (xy 265.263098 -114.549688) (xy 265.317096 -114.583956)
			(xy 265.366374 -114.624722) (xy 265.410153 -114.671342) (xy 265.447745 -114.723082) (xy 265.478555 -114.779126)
			(xy 265.502098 -114.838588) (xy 265.518003 -114.900533) (xy 265.526018 -114.963983) (xy 265.52652 -114.99596)
			(xy 265.526018 -115.027937) (xy 265.518003 -115.091387) (xy 265.502098 -115.153332) (xy 265.478555 -115.212794)
			(xy 265.447745 -115.268838) (xy 265.410153 -115.320578) (xy 265.366374 -115.367198) (xy 265.317096 -115.407964)
			(xy 265.263098 -115.442232) (xy 265.205231 -115.469463) (xy 265.144407 -115.489226) (xy 265.081586 -115.501209)
			(xy 265.017758 -115.505225) (xy 264.95393 -115.501209) (xy 264.891109 -115.489226) (xy 264.830285 -115.469463)
			(xy 264.772418 -115.442232) (xy 264.71842 -115.407964) (xy 264.669142 -115.367198) (xy 264.625363 -115.320578)
			(xy 264.587771 -115.268838) (xy 264.556961 -115.212794) (xy 264.533418 -115.153332) (xy 264.517513 -115.091387)
			(xy 264.509498 -115.027937) (xy 261.327988 -115.027937) (xy 261.321331 -115.035619) (xy 261.280114 -115.071334)
			(xy 261.234233 -115.10082) (xy 261.184623 -115.123477) (xy 261.132293 -115.138842) (xy 261.078309 -115.146604)
			(xy 261.023771 -115.146604) (xy 260.969787 -115.138842) (xy 260.917457 -115.123477) (xy 260.867847 -115.10082)
			(xy 260.821966 -115.071334) (xy 260.780749 -115.035619) (xy 260.745034 -114.994402) (xy 260.715548 -114.948521)
			(xy 260.692891 -114.898911) (xy 260.677526 -114.846581) (xy 260.669764 -114.792597) (xy 260.669278 -114.765328)
			(xy 260.669278 -114.764566) (xy 260.669563 -114.744017) (xy 260.674018 -114.70316) (xy 260.678168 -114.683032)
			(xy 260.680962 -114.671348) (xy 260.675374 -114.648742) (xy 260.616954 -114.57813) (xy 260.613093 -114.573711)
			(xy 260.603729 -114.566643) (xy 260.598412 -114.56416) (xy 260.587998 -114.559588) (xy 260.56082 -114.56035)
			(xy 260.533134 -114.559588) (xy 260.528296 -114.559398) (xy 260.5187 -114.56067) (xy 260.514084 -114.562128)
			(xy 260.505956 -114.564922) (xy 260.438138 -114.62131) (xy 260.428994 -114.63782) (xy 260.427978 -114.647472)
			(xy 260.423881 -114.676106) (xy 260.410034 -114.732269) (xy 260.389906 -114.786499) (xy 260.363757 -114.838096)
			(xy 260.331924 -114.886394) (xy 260.313678 -114.908838) (xy 260.30428 -114.925348) (xy 260.301486 -114.933984)
			(xy 260.30682 -115.02263) (xy 260.314948 -115.040156) (xy 260.32206 -115.047014) (xy 260.346771 -115.071128)
			(xy 260.390114 -115.124875) (xy 260.425787 -115.183991) (xy 260.453135 -115.24739) (xy 260.471653 -115.313906)
			(xy 260.481003 -115.382315) (xy 260.481572 -115.416838) (xy 260.48107 -115.448815) (xy 260.473055 -115.512265)
			(xy 260.45715 -115.57421) (xy 260.433607 -115.633672) (xy 260.402797 -115.689716) (xy 260.365205 -115.741456)
			(xy 260.321426 -115.788076) (xy 260.272148 -115.828842) (xy 260.21815 -115.86311) (xy 260.160283 -115.890341)
			(xy 260.099459 -115.910104) (xy 260.036638 -115.922087) (xy 259.97281 -115.926103) (xy 259.908982 -115.922087)
			(xy 259.846161 -115.910104) (xy 259.785337 -115.890341) (xy 259.72747 -115.86311) (xy 259.673472 -115.828842)
			(xy 259.624194 -115.788076) (xy 259.580415 -115.741456) (xy 259.542823 -115.689716) (xy 259.512013 -115.633672)
			(xy 259.48847 -115.57421) (xy 259.472565 -115.512265) (xy 259.46455 -115.448815) (xy 259.464048 -115.416838)
			(xy 259.464048 -115.416584) (xy 259.46447 -115.38707) (xy 259.471298 -115.328438) (xy 259.484873 -115.270993)
			(xy 259.505011 -115.215506) (xy 259.531441 -115.162726) (xy 259.563807 -115.113364) (xy 259.582412 -115.090448)
			(xy 259.59181 -115.073938) (xy 259.594604 -115.065302) (xy 259.58927 -114.976656) (xy 259.581142 -114.95913)
			(xy 259.57403 -114.952272) (xy 259.54932 -114.928157) (xy 259.505979 -114.87441) (xy 259.470308 -114.815294)
			(xy 259.442963 -114.751895) (xy 259.424447 -114.685379) (xy 259.415099 -114.61697) (xy 259.414518 -114.582448)
			(xy 259.414772 -114.567716) (xy 259.41528 -114.551968) (xy 259.398516 -114.525552) (xy 259.297424 -114.482372)
			(xy 259.287964 -114.478787) (xy 259.267751 -114.478603) (xy 259.249036 -114.486239) (xy 259.241544 -114.49304)
			(xy 257.450109 -116.284475) (xy 258.36981 -116.284475) (xy 258.36981 -116.220521) (xy 258.377825 -116.157071)
			(xy 258.39373 -116.095126) (xy 258.417273 -116.035664) (xy 258.448083 -115.97962) (xy 258.485675 -115.92788)
			(xy 258.529454 -115.88126) (xy 258.578732 -115.840494) (xy 258.63273 -115.806226) (xy 258.690597 -115.778995)
			(xy 258.751421 -115.759232) (xy 258.814242 -115.747249) (xy 258.87807 -115.743233) (xy 258.941898 -115.747249)
			(xy 259.004719 -115.759232) (xy 259.065543 -115.778995) (xy 259.12341 -115.806226) (xy 259.177408 -115.840494)
			(xy 259.226686 -115.88126) (xy 259.270465 -115.92788) (xy 259.308057 -115.97962) (xy 259.338867 -116.035664)
			(xy 259.36241 -116.095126) (xy 259.378315 -116.157071) (xy 259.38633 -116.220521) (xy 259.386832 -116.252498)
			(xy 259.38633 -116.284475) (xy 259.378315 -116.347925) (xy 259.364085 -116.403347) (xy 268.039844 -116.403347)
			(xy 268.039844 -116.339393) (xy 268.047859 -116.275943) (xy 268.063764 -116.213998) (xy 268.087307 -116.154536)
			(xy 268.118117 -116.098492) (xy 268.155709 -116.046752) (xy 268.199488 -116.000132) (xy 268.248766 -115.959366)
			(xy 268.302764 -115.925098) (xy 268.360631 -115.897867) (xy 268.421455 -115.878104) (xy 268.484276 -115.866121)
			(xy 268.548104 -115.862105) (xy 268.611932 -115.866121) (xy 268.674753 -115.878104) (xy 268.735577 -115.897867)
			(xy 268.793444 -115.925098) (xy 268.847442 -115.959366) (xy 268.89672 -116.000132) (xy 268.940499 -116.046752)
			(xy 268.978091 -116.098492) (xy 269.008901 -116.154536) (xy 269.032444 -116.213998) (xy 269.048349 -116.275943)
			(xy 269.056364 -116.339393) (xy 269.056866 -116.37137) (xy 269.056364 -116.403347) (xy 269.048349 -116.466797)
			(xy 269.032444 -116.528742) (xy 269.008901 -116.588204) (xy 268.978091 -116.644248) (xy 268.940499 -116.695988)
			(xy 268.89672 -116.742608) (xy 268.847442 -116.783374) (xy 268.793444 -116.817642) (xy 268.735577 -116.844873)
			(xy 268.674753 -116.864636) (xy 268.611932 -116.876619) (xy 268.548104 -116.880635) (xy 268.484276 -116.876619)
			(xy 268.421455 -116.864636) (xy 268.360631 -116.844873) (xy 268.302764 -116.817642) (xy 268.248766 -116.783374)
			(xy 268.199488 -116.742608) (xy 268.155709 -116.695988) (xy 268.118117 -116.644248) (xy 268.087307 -116.588204)
			(xy 268.063764 -116.528742) (xy 268.047859 -116.466797) (xy 268.039844 -116.403347) (xy 259.364085 -116.403347)
			(xy 259.36241 -116.40987) (xy 259.338867 -116.469332) (xy 259.308057 -116.525376) (xy 259.270465 -116.577116)
			(xy 259.226686 -116.623736) (xy 259.177408 -116.664502) (xy 259.12341 -116.69877) (xy 259.065543 -116.726001)
			(xy 259.004719 -116.745764) (xy 258.941898 -116.757747) (xy 258.87807 -116.761763) (xy 258.814242 -116.757747)
			(xy 258.751421 -116.745764) (xy 258.690597 -116.726001) (xy 258.63273 -116.69877) (xy 258.578732 -116.664502)
			(xy 258.529454 -116.623736) (xy 258.485675 -116.577116) (xy 258.448083 -116.525376) (xy 258.417273 -116.469332)
			(xy 258.39373 -116.40987) (xy 258.377825 -116.347925) (xy 258.36981 -116.284475) (xy 257.450109 -116.284475)
			(xy 255.807237 -117.927347) (xy 257.86562 -117.927347) (xy 257.86562 -117.863393) (xy 257.873635 -117.799943)
			(xy 257.88954 -117.737998) (xy 257.913083 -117.678536) (xy 257.943893 -117.622492) (xy 257.981485 -117.570752)
			(xy 258.025264 -117.524132) (xy 258.074542 -117.483366) (xy 258.12854 -117.449098) (xy 258.186407 -117.421867)
			(xy 258.247231 -117.402104) (xy 258.310052 -117.390121) (xy 258.37388 -117.386105) (xy 258.437708 -117.390121)
			(xy 258.500529 -117.402104) (xy 258.561353 -117.421867) (xy 258.61922 -117.449098) (xy 258.673218 -117.483366)
			(xy 258.722496 -117.524132) (xy 258.766275 -117.570752) (xy 258.797632 -117.613911) (xy 259.44042 -117.613911)
			(xy 259.44042 -117.549957) (xy 259.448435 -117.486507) (xy 259.46434 -117.424562) (xy 259.487883 -117.3651)
			(xy 259.518693 -117.309056) (xy 259.556285 -117.257316) (xy 259.600064 -117.210696) (xy 259.649342 -117.16993)
			(xy 259.70334 -117.135662) (xy 259.761207 -117.108431) (xy 259.822031 -117.088668) (xy 259.884852 -117.076685)
			(xy 259.94868 -117.072669) (xy 260.012508 -117.076685) (xy 260.075329 -117.088668) (xy 260.136153 -117.108431)
			(xy 260.19402 -117.135662) (xy 260.248018 -117.16993) (xy 260.297296 -117.210696) (xy 260.341075 -117.257316)
			(xy 260.378667 -117.309056) (xy 260.409477 -117.3651) (xy 260.43302 -117.424562) (xy 260.448925 -117.486507)
			(xy 260.45694 -117.549957) (xy 260.457442 -117.581934) (xy 260.45694 -117.613911) (xy 260.448925 -117.677361)
			(xy 260.43302 -117.739306) (xy 260.409477 -117.798768) (xy 260.378667 -117.854812) (xy 260.341075 -117.906552)
			(xy 260.297296 -117.953172) (xy 260.248018 -117.993938) (xy 260.19402 -118.028206) (xy 260.136153 -118.055437)
			(xy 260.075329 -118.0752) (xy 260.012508 -118.087183) (xy 259.94868 -118.091199) (xy 259.884852 -118.087183)
			(xy 259.822031 -118.0752) (xy 259.761207 -118.055437) (xy 259.70334 -118.028206) (xy 259.649342 -117.993938)
			(xy 259.600064 -117.953172) (xy 259.556285 -117.906552) (xy 259.518693 -117.854812) (xy 259.487883 -117.798768)
			(xy 259.46434 -117.739306) (xy 259.448435 -117.677361) (xy 259.44042 -117.613911) (xy 258.797632 -117.613911)
			(xy 258.803867 -117.622492) (xy 258.834677 -117.678536) (xy 258.85822 -117.737998) (xy 258.874125 -117.799943)
			(xy 258.88214 -117.863393) (xy 258.882642 -117.89537) (xy 258.88214 -117.927347) (xy 258.874125 -117.990797)
			(xy 258.85822 -118.052742) (xy 258.834677 -118.112204) (xy 258.803867 -118.168248) (xy 258.766275 -118.219988)
			(xy 258.722496 -118.266608) (xy 258.673218 -118.307374) (xy 258.61922 -118.341642) (xy 258.561353 -118.368873)
			(xy 258.500529 -118.388636) (xy 258.437708 -118.400619) (xy 258.37388 -118.404635) (xy 258.310052 -118.400619)
			(xy 258.247231 -118.388636) (xy 258.186407 -118.368873) (xy 258.12854 -118.341642) (xy 258.074542 -118.307374)
			(xy 258.025264 -118.266608) (xy 257.981485 -118.219988) (xy 257.943893 -118.168248) (xy 257.913083 -118.112204)
			(xy 257.88954 -118.052742) (xy 257.873635 -117.990797) (xy 257.86562 -117.927347) (xy 255.807237 -117.927347)
			(xy 255.267206 -118.467378) (xy 255.25984 -118.47449) (xy 255.25222 -118.493286) (xy 255.25222 -118.913883)
			(xy 259.44042 -118.913883) (xy 259.44042 -118.849929) (xy 259.448435 -118.786479) (xy 259.46434 -118.724534)
			(xy 259.487883 -118.665072) (xy 259.518693 -118.609028) (xy 259.556285 -118.557288) (xy 259.600064 -118.510668)
			(xy 259.649342 -118.469902) (xy 259.70334 -118.435634) (xy 259.761207 -118.408403) (xy 259.822031 -118.38864)
			(xy 259.884852 -118.376657) (xy 259.94868 -118.372641) (xy 260.012508 -118.376657) (xy 260.075329 -118.38864)
			(xy 260.136153 -118.408403) (xy 260.19402 -118.435634) (xy 260.248018 -118.469902) (xy 260.297296 -118.510668)
			(xy 260.341075 -118.557288) (xy 260.378667 -118.609028) (xy 260.409477 -118.665072) (xy 260.43302 -118.724534)
			(xy 260.448925 -118.786479) (xy 260.45694 -118.849929) (xy 260.457442 -118.881906) (xy 260.45694 -118.913883)
			(xy 260.448925 -118.977333) (xy 260.43302 -119.039278) (xy 260.409477 -119.09874) (xy 260.378667 -119.154784)
			(xy 260.341075 -119.206524) (xy 260.297296 -119.253144) (xy 260.248018 -119.29391) (xy 260.19402 -119.328178)
			(xy 260.136153 -119.355409) (xy 260.075329 -119.375172) (xy 260.012508 -119.387155) (xy 259.94868 -119.391171)
			(xy 259.884852 -119.387155) (xy 259.822031 -119.375172) (xy 259.761207 -119.355409) (xy 259.70334 -119.328178)
			(xy 259.649342 -119.29391) (xy 259.600064 -119.253144) (xy 259.556285 -119.206524) (xy 259.518693 -119.154784)
			(xy 259.487883 -119.09874) (xy 259.46434 -119.039278) (xy 259.448435 -118.977333) (xy 259.44042 -118.913883)
			(xy 255.25222 -118.913883) (xy 255.25222 -119.959347) (xy 257.89864 -119.959347) (xy 257.89864 -119.895393)
			(xy 257.906655 -119.831943) (xy 257.92256 -119.769998) (xy 257.946103 -119.710536) (xy 257.976913 -119.654492)
			(xy 258.014505 -119.602752) (xy 258.058284 -119.556132) (xy 258.107562 -119.515366) (xy 258.16156 -119.481098)
			(xy 258.219427 -119.453867) (xy 258.280251 -119.434104) (xy 258.343072 -119.422121) (xy 258.4069 -119.418105)
			(xy 258.470728 -119.422121) (xy 258.533549 -119.434104) (xy 258.594373 -119.453867) (xy 258.65224 -119.481098)
			(xy 258.706238 -119.515366) (xy 258.755516 -119.556132) (xy 258.799295 -119.602752) (xy 258.836887 -119.654492)
			(xy 258.867697 -119.710536) (xy 258.89124 -119.769998) (xy 258.907145 -119.831943) (xy 258.91516 -119.895393)
			(xy 258.915662 -119.92737) (xy 258.91516 -119.959347) (xy 258.907145 -120.022797) (xy 258.89124 -120.084742)
			(xy 258.867697 -120.144204) (xy 258.836887 -120.200248) (xy 258.799295 -120.251988) (xy 258.755516 -120.298608)
			(xy 258.706238 -120.339374) (xy 258.65224 -120.373642) (xy 258.594373 -120.400873) (xy 258.533549 -120.420636)
			(xy 258.470728 -120.432619) (xy 258.4069 -120.436635) (xy 258.343072 -120.432619) (xy 258.280251 -120.420636)
			(xy 258.219427 -120.400873) (xy 258.16156 -120.373642) (xy 258.107562 -120.339374) (xy 258.058284 -120.298608)
			(xy 258.014505 -120.251988) (xy 257.976913 -120.200248) (xy 257.946103 -120.144204) (xy 257.92256 -120.084742)
			(xy 257.906655 -120.022797) (xy 257.89864 -119.959347) (xy 255.25222 -119.959347) (xy 255.25222 -120.566407)
			(xy 259.301736 -120.566407) (xy 259.301736 -120.502453) (xy 259.309751 -120.439003) (xy 259.325656 -120.377058)
			(xy 259.349199 -120.317596) (xy 259.380009 -120.261552) (xy 259.417601 -120.209812) (xy 259.46138 -120.163192)
			(xy 259.510658 -120.122426) (xy 259.564656 -120.088158) (xy 259.622523 -120.060927) (xy 259.683347 -120.041164)
			(xy 259.746168 -120.029181) (xy 259.809996 -120.025165) (xy 259.873824 -120.029181) (xy 259.936645 -120.041164)
			(xy 259.997469 -120.060927) (xy 260.055336 -120.088158) (xy 260.109334 -120.122426) (xy 260.158612 -120.163192)
			(xy 260.202391 -120.209812) (xy 260.239983 -120.261552) (xy 260.270793 -120.317596) (xy 260.294336 -120.377058)
			(xy 260.310241 -120.439003) (xy 260.318256 -120.502453) (xy 260.318758 -120.53443) (xy 260.318256 -120.566407)
			(xy 260.310241 -120.629857) (xy 260.294336 -120.691802) (xy 260.270793 -120.751264) (xy 260.239983 -120.807308)
			(xy 260.202391 -120.859048) (xy 260.158612 -120.905668) (xy 260.109334 -120.946434) (xy 260.055336 -120.980702)
			(xy 259.997469 -121.007933) (xy 259.936645 -121.027696) (xy 259.873824 -121.039679) (xy 259.809996 -121.043695)
			(xy 259.746168 -121.039679) (xy 259.683347 -121.027696) (xy 259.622523 -121.007933) (xy 259.564656 -120.980702)
			(xy 259.510658 -120.946434) (xy 259.46138 -120.905668) (xy 259.417601 -120.859048) (xy 259.380009 -120.807308)
			(xy 259.349199 -120.751264) (xy 259.325656 -120.691802) (xy 259.309751 -120.629857) (xy 259.301736 -120.566407)
			(xy 255.25222 -120.566407) (xy 255.25222 -121.991347) (xy 258.37108 -121.991347) (xy 258.37108 -121.927393)
			(xy 258.379095 -121.863943) (xy 258.395 -121.801998) (xy 258.418543 -121.742536) (xy 258.449353 -121.686492)
			(xy 258.486945 -121.634752) (xy 258.530724 -121.588132) (xy 258.580002 -121.547366) (xy 258.634 -121.513098)
			(xy 258.691867 -121.485867) (xy 258.752691 -121.466104) (xy 258.815512 -121.454121) (xy 258.87934 -121.450105)
			(xy 258.943168 -121.454121) (xy 259.005989 -121.466104) (xy 259.066813 -121.485867) (xy 259.12468 -121.513098)
			(xy 259.178678 -121.547366) (xy 259.227956 -121.588132) (xy 259.271735 -121.634752) (xy 259.309327 -121.686492)
			(xy 259.340137 -121.742536) (xy 259.36368 -121.801998) (xy 259.379585 -121.863943) (xy 259.3876 -121.927393)
			(xy 259.388102 -121.95937) (xy 259.3876 -121.991347) (xy 259.379585 -122.054797) (xy 259.36368 -122.116742)
			(xy 259.340137 -122.176204) (xy 259.309327 -122.232248) (xy 259.271735 -122.283988) (xy 259.227956 -122.330608)
			(xy 259.178678 -122.371374) (xy 259.12468 -122.405642) (xy 259.066813 -122.432873) (xy 259.005989 -122.452636)
			(xy 258.943168 -122.464619) (xy 258.87934 -122.468635) (xy 258.815512 -122.464619) (xy 258.752691 -122.452636)
			(xy 258.691867 -122.432873) (xy 258.634 -122.405642) (xy 258.580002 -122.371374) (xy 258.530724 -122.330608)
			(xy 258.486945 -122.283988) (xy 258.449353 -122.232248) (xy 258.418543 -122.176204) (xy 258.395 -122.116742)
			(xy 258.379095 -122.054797) (xy 258.37108 -121.991347) (xy 255.25222 -121.991347) (xy 255.25222 -122.526525)
			(xy 267.95958 -122.526525) (xy 267.95958 -122.462571) (xy 267.967595 -122.399121) (xy 267.9835 -122.337176)
			(xy 268.007043 -122.277714) (xy 268.037853 -122.22167) (xy 268.075445 -122.16993) (xy 268.119224 -122.12331)
			(xy 268.168502 -122.082544) (xy 268.2225 -122.048276) (xy 268.280367 -122.021045) (xy 268.341191 -122.001282)
			(xy 268.404012 -121.989299) (xy 268.46784 -121.985283) (xy 268.531668 -121.989299) (xy 268.594489 -122.001282)
			(xy 268.655313 -122.021045) (xy 268.71318 -122.048276) (xy 268.767178 -122.082544) (xy 268.816456 -122.12331)
			(xy 268.860235 -122.16993) (xy 268.897827 -122.22167) (xy 268.928637 -122.277714) (xy 268.95218 -122.337176)
			(xy 268.968085 -122.399121) (xy 268.9761 -122.462571) (xy 268.976602 -122.494548) (xy 268.9761 -122.526525)
			(xy 268.968085 -122.589975) (xy 268.95218 -122.65192) (xy 268.928637 -122.711382) (xy 268.897827 -122.767426)
			(xy 268.860235 -122.819166) (xy 268.816456 -122.865786) (xy 268.767178 -122.906552) (xy 268.71318 -122.94082)
			(xy 268.655313 -122.968051) (xy 268.594489 -122.987814) (xy 268.531668 -122.999797) (xy 268.46784 -123.003813)
			(xy 268.404012 -122.999797) (xy 268.341191 -122.987814) (xy 268.280367 -122.968051) (xy 268.2225 -122.94082)
			(xy 268.168502 -122.906552) (xy 268.119224 -122.865786) (xy 268.075445 -122.819166) (xy 268.037853 -122.767426)
			(xy 268.007043 -122.711382) (xy 267.9835 -122.65192) (xy 267.967595 -122.589975) (xy 267.95958 -122.526525)
			(xy 255.25222 -122.526525) (xy 255.25222 -122.755152) (xy 255.252668 -122.765294) (xy 255.260513 -122.784)
			(xy 255.274967 -122.798231) (xy 255.284224 -122.802396) (xy 255.372108 -122.837448) (xy 255.379263 -122.839956)
			(xy 255.394371 -122.841117) (xy 255.401826 -122.839734) (xy 255.416812 -122.836432) (xy 255.437556 -122.81375)
			(xy 255.483593 -122.773018) (xy 255.534198 -122.738126) (xy 255.588638 -122.709582) (xy 255.646118 -122.687801)
			(xy 255.705803 -122.6731) (xy 255.766824 -122.665693) (xy 255.797558 -122.665236) (xy 255.829538 -122.665715)
			(xy 255.892995 -122.673726) (xy 255.954947 -122.689628) (xy 256.014417 -122.71317) (xy 256.070467 -122.74398)
			(xy 256.122214 -122.781572) (xy 256.168841 -122.825354) (xy 256.209612 -122.874635) (xy 256.243886 -122.928637)
			(xy 256.27112 -122.986509) (xy 256.290886 -123.047339) (xy 256.302871 -123.110166) (xy 256.306888 -123.174)
			(xy 256.302871 -123.237834) (xy 256.290886 -123.300661) (xy 256.27112 -123.361491) (xy 256.260633 -123.383775)
			(xy 260.477756 -123.383775) (xy 260.477756 -123.319821) (xy 260.485771 -123.256371) (xy 260.501676 -123.194426)
			(xy 260.525219 -123.134964) (xy 260.556029 -123.07892) (xy 260.593621 -123.02718) (xy 260.6374 -122.98056)
			(xy 260.686678 -122.939794) (xy 260.740676 -122.905526) (xy 260.798543 -122.878295) (xy 260.859367 -122.858532)
			(xy 260.922188 -122.846549) (xy 260.986016 -122.842533) (xy 261.049844 -122.846549) (xy 261.112665 -122.858532)
			(xy 261.173489 -122.878295) (xy 261.231356 -122.905526) (xy 261.285354 -122.939794) (xy 261.334632 -122.98056)
			(xy 261.378411 -123.02718) (xy 261.416003 -123.07892) (xy 261.446813 -123.134964) (xy 261.470356 -123.194426)
			(xy 261.486261 -123.256371) (xy 261.494276 -123.319821) (xy 261.494778 -123.351798) (xy 261.494276 -123.383775)
			(xy 261.486261 -123.447225) (xy 261.480444 -123.469881) (xy 262.60018 -123.469881) (xy 262.60018 -123.405927)
			(xy 262.608195 -123.342477) (xy 262.6241 -123.280532) (xy 262.647643 -123.22107) (xy 262.678453 -123.165026)
			(xy 262.716045 -123.113286) (xy 262.759824 -123.066666) (xy 262.809102 -123.0259) (xy 262.8631 -122.991632)
			(xy 262.920967 -122.964401) (xy 262.981791 -122.944638) (xy 263.044612 -122.932655) (xy 263.10844 -122.928639)
			(xy 263.172268 -122.932655) (xy 263.235089 -122.944638) (xy 263.295913 -122.964401) (xy 263.35378 -122.991632)
			(xy 263.407778 -123.0259) (xy 263.457056 -123.066666) (xy 263.500835 -123.113286) (xy 263.538427 -123.165026)
			(xy 263.569237 -123.22107) (xy 263.59278 -123.280532) (xy 263.608685 -123.342477) (xy 263.6167 -123.405927)
			(xy 263.617202 -123.437904) (xy 263.6167 -123.469881) (xy 263.608685 -123.533331) (xy 263.59278 -123.595276)
			(xy 263.569237 -123.654738) (xy 263.538427 -123.710782) (xy 263.500835 -123.762522) (xy 263.457056 -123.809142)
			(xy 263.407778 -123.849908) (xy 263.35378 -123.884176) (xy 263.295913 -123.911407) (xy 263.235089 -123.93117)
			(xy 263.172268 -123.943153) (xy 263.10844 -123.947169) (xy 263.044612 -123.943153) (xy 262.981791 -123.93117)
			(xy 262.920967 -123.911407) (xy 262.8631 -123.884176) (xy 262.809102 -123.849908) (xy 262.759824 -123.809142)
			(xy 262.716045 -123.762522) (xy 262.678453 -123.710782) (xy 262.647643 -123.654738) (xy 262.6241 -123.595276)
			(xy 262.608195 -123.533331) (xy 262.60018 -123.469881) (xy 261.480444 -123.469881) (xy 261.470356 -123.50917)
			(xy 261.446813 -123.568632) (xy 261.416003 -123.624676) (xy 261.378411 -123.676416) (xy 261.334632 -123.723036)
			(xy 261.285354 -123.763802) (xy 261.231356 -123.79807) (xy 261.173489 -123.825301) (xy 261.112665 -123.845064)
			(xy 261.049844 -123.857047) (xy 260.986016 -123.861063) (xy 260.922188 -123.857047) (xy 260.859367 -123.845064)
			(xy 260.798543 -123.825301) (xy 260.740676 -123.79807) (xy 260.686678 -123.763802) (xy 260.6374 -123.723036)
			(xy 260.593621 -123.676416) (xy 260.556029 -123.624676) (xy 260.525219 -123.568632) (xy 260.501676 -123.50917)
			(xy 260.485771 -123.447225) (xy 260.477756 -123.383775) (xy 256.260633 -123.383775) (xy 256.243886 -123.419363)
			(xy 256.209612 -123.473365) (xy 256.168841 -123.522646) (xy 256.122214 -123.566428) (xy 256.070467 -123.60402)
			(xy 256.014417 -123.63483) (xy 255.954947 -123.658372) (xy 255.892995 -123.674274) (xy 255.829538 -123.682285)
			(xy 255.797558 -123.68276) (xy 255.762987 -123.682179) (xy 255.694481 -123.672816) (xy 255.627873 -123.654269)
			(xy 255.564387 -123.626879) (xy 255.505192 -123.59115) (xy 255.451376 -123.547738) (xy 255.427226 -123.522994)
			(xy 255.401064 -123.508008) (xy 255.394206 -123.506738) (xy 255.37922 -123.507754) (xy 255.284224 -123.5456)
			(xy 255.274958 -123.549757) (xy 255.260478 -123.563974) (xy 255.252653 -123.582697) (xy 255.25222 -123.592844)
			(xy 255.25222 -124.115068) (xy 255.850134 -124.115068) (xy 255.854207 -124.059409) (xy 255.866342 -124.004936)
			(xy 255.886278 -123.95281) (xy 255.913592 -123.904142) (xy 255.9477 -123.85997) (xy 255.987877 -123.821235)
			(xy 256.033265 -123.788763) (xy 256.082897 -123.763245) (xy 256.135717 -123.745226) (xy 256.190596 -123.735089)
			(xy 256.246367 -123.733051) (xy 256.301841 -123.739154) (xy 256.355834 -123.75327) (xy 256.407197 -123.775097)
			(xy 256.454835 -123.80417) (xy 256.497731 -123.839869) (xy 256.534973 -123.881433) (xy 256.565767 -123.927977)
			(xy 256.589455 -123.978508) (xy 256.605533 -124.03195) (xy 256.613659 -124.087164) (xy 256.614168 -124.115068)
			(xy 256.613659 -124.142972) (xy 256.605533 -124.198186) (xy 256.589455 -124.251628) (xy 256.565767 -124.302159)
			(xy 256.534973 -124.348703) (xy 256.497731 -124.390267) (xy 256.454835 -124.425966) (xy 256.407197 -124.455039)
			(xy 256.355834 -124.476866) (xy 256.301841 -124.490982) (xy 256.246367 -124.497085) (xy 256.190596 -124.495047)
			(xy 256.135717 -124.48491) (xy 256.082897 -124.466891) (xy 256.033265 -124.441373) (xy 255.987877 -124.408901)
			(xy 255.9477 -124.370166) (xy 255.913592 -124.325994) (xy 255.886278 -124.277326) (xy 255.866342 -124.2252)
			(xy 255.854207 -124.170727) (xy 255.850134 -124.115068) (xy 255.25222 -124.115068) (xy 255.25222 -125.38837)
			(xy 255.850134 -125.38837) (xy 255.854207 -125.332711) (xy 255.866342 -125.278238) (xy 255.886278 -125.226112)
			(xy 255.913592 -125.177444) (xy 255.9477 -125.133272) (xy 255.987877 -125.094537) (xy 256.033265 -125.062065)
			(xy 256.082897 -125.036547) (xy 256.135717 -125.018528) (xy 256.190596 -125.008391) (xy 256.246367 -125.006353)
			(xy 256.301841 -125.012456) (xy 256.355834 -125.026572) (xy 256.407197 -125.048399) (xy 256.454835 -125.077472)
			(xy 256.487192 -125.1044) (xy 267.690633 -125.1044) (xy 267.694648 -125.040574) (xy 267.706631 -124.977755)
			(xy 267.726393 -124.916933) (xy 267.753621 -124.859067) (xy 267.787887 -124.80507) (xy 267.82865 -124.755793)
			(xy 267.875268 -124.712014) (xy 267.927005 -124.674422) (xy 267.983045 -124.643611) (xy 268.042505 -124.620066)
			(xy 268.104447 -124.604158) (xy 268.167894 -124.59614) (xy 268.19987 -124.595636) (xy 268.233471 -124.596174)
			(xy 268.30009 -124.605014) (xy 268.364966 -124.622545) (xy 268.426971 -124.648461) (xy 268.485026 -124.682312)
			(xy 268.538121 -124.723508) (xy 268.585332 -124.771334) (xy 268.606016 -124.79782) (xy 268.612366 -124.806202)
			(xy 268.630654 -124.816616) (xy 268.724888 -124.82703) (xy 268.733778 -124.824236) (xy 268.738694 -124.822582)
			(xy 268.747788 -124.817601) (xy 268.751812 -124.81433) (xy 268.772637 -124.797093) (xy 268.818257 -124.768091)
			(xy 268.867514 -124.745818) (xy 268.919422 -124.730721) (xy 268.972941 -124.723101) (xy 268.99997 -124.722636)
			(xy 269.027242 -124.723101) (xy 269.081232 -124.73086) (xy 269.133568 -124.746224) (xy 269.183185 -124.768879)
			(xy 269.229072 -124.798366) (xy 269.270295 -124.834083) (xy 269.306016 -124.875304) (xy 269.335506 -124.921189)
			(xy 269.358166 -124.970804) (xy 269.373534 -125.023139) (xy 269.381296 -125.077128) (xy 269.381296 -125.131672)
			(xy 269.373534 -125.185661) (xy 269.358166 -125.237996) (xy 269.335506 -125.287611) (xy 269.306016 -125.333496)
			(xy 269.270295 -125.374717) (xy 269.229072 -125.410434) (xy 269.183185 -125.439921) (xy 269.133568 -125.462576)
			(xy 269.081232 -125.47794) (xy 269.027242 -125.485699) (xy 268.99997 -125.48616) (xy 268.97193 -125.485684)
			(xy 268.916454 -125.47747) (xy 268.862773 -125.461237) (xy 268.812042 -125.437333) (xy 268.765348 -125.406272)
			(xy 268.744192 -125.387862) (xy 268.735048 -125.384814) (xy 268.730031 -125.383417) (xy 268.719657 -125.38253)
			(xy 268.714474 -125.383036) (xy 268.630654 -125.39218) (xy 268.612366 -125.402594) (xy 268.606016 -125.410976)
			(xy 268.585358 -125.437483) (xy 268.538139 -125.485304) (xy 268.485039 -125.526496) (xy 268.42698 -125.560342)
			(xy 268.364972 -125.586255) (xy 268.300093 -125.603783) (xy 268.233472 -125.612622) (xy 268.19987 -125.61316)
			(xy 268.167894 -125.61266) (xy 268.104447 -125.604642) (xy 268.042505 -125.588734) (xy 267.983045 -125.565189)
			(xy 267.927005 -125.534378) (xy 267.875268 -125.496786) (xy 267.82865 -125.453007) (xy 267.787887 -125.40373)
			(xy 267.753621 -125.349733) (xy 267.726393 -125.291867) (xy 267.706631 -125.231045) (xy 267.694648 -125.168226)
			(xy 267.690633 -125.1044) (xy 256.487192 -125.1044) (xy 256.497731 -125.113171) (xy 256.534973 -125.154735)
			(xy 256.565767 -125.201279) (xy 256.589455 -125.25181) (xy 256.605533 -125.305252) (xy 256.613659 -125.360466)
			(xy 256.614168 -125.38837) (xy 256.613659 -125.416274) (xy 256.605533 -125.471488) (xy 256.589455 -125.52493)
			(xy 256.565767 -125.575461) (xy 256.534973 -125.622005) (xy 256.497731 -125.663569) (xy 256.454835 -125.699268)
			(xy 256.407197 -125.728341) (xy 256.355834 -125.750168) (xy 256.301841 -125.764284) (xy 256.246367 -125.770387)
			(xy 256.190596 -125.768349) (xy 256.135717 -125.758212) (xy 256.082897 -125.740193) (xy 256.033265 -125.714675)
			(xy 255.987877 -125.682203) (xy 255.9477 -125.643468) (xy 255.913592 -125.599296) (xy 255.886278 -125.550628)
			(xy 255.866342 -125.498502) (xy 255.854207 -125.444029) (xy 255.850134 -125.38837) (xy 255.25222 -125.38837)
			(xy 255.25222 -127.074649) (xy 259.717026 -127.074649) (xy 259.717026 -127.010695) (xy 259.725041 -126.947245)
			(xy 259.740946 -126.8853) (xy 259.764489 -126.825838) (xy 259.795299 -126.769794) (xy 259.832891 -126.718054)
			(xy 259.87667 -126.671434) (xy 259.925948 -126.630668) (xy 259.979946 -126.5964) (xy 260.037813 -126.569169)
			(xy 260.098637 -126.549406) (xy 260.161458 -126.537423) (xy 260.225286 -126.533407) (xy 260.289114 -126.537423)
			(xy 260.351935 -126.549406) (xy 260.412759 -126.569169) (xy 260.470626 -126.5964) (xy 260.524624 -126.630668)
			(xy 260.573902 -126.671434) (xy 260.617681 -126.718054) (xy 260.655273 -126.769794) (xy 260.686083 -126.825838)
			(xy 260.709626 -126.8853) (xy 260.725531 -126.947245) (xy 260.733546 -127.010695) (xy 260.734048 -127.042672)
			(xy 260.733546 -127.074649) (xy 260.725531 -127.138099) (xy 260.709626 -127.200044) (xy 260.686083 -127.259506)
			(xy 260.655273 -127.31555) (xy 260.617681 -127.36729) (xy 260.573902 -127.41391) (xy 260.524624 -127.454676)
			(xy 260.470626 -127.488944) (xy 260.412759 -127.516175) (xy 260.351935 -127.535938) (xy 260.289114 -127.547921)
			(xy 260.225286 -127.551937) (xy 260.161458 -127.547921) (xy 260.098637 -127.535938) (xy 260.037813 -127.516175)
			(xy 259.979946 -127.488944) (xy 259.925948 -127.454676) (xy 259.87667 -127.41391) (xy 259.832891 -127.36729)
			(xy 259.795299 -127.31555) (xy 259.764489 -127.259506) (xy 259.740946 -127.200044) (xy 259.725041 -127.138099)
			(xy 259.717026 -127.074649) (xy 255.25222 -127.074649) (xy 255.25222 -128.285494) (xy 255.251799 -128.295565)
			(xy 255.244088 -128.314173) (xy 255.237234 -128.321562) (xy 254.63754 -128.921256) (xy 254.630174 -128.928368)
			(xy 254.622554 -128.947164) (xy 254.622554 -129.617216) (xy 257.226052 -129.617216) (xy 257.230125 -129.561557)
			(xy 257.24226 -129.507084) (xy 257.262196 -129.454958) (xy 257.28951 -129.40629) (xy 257.323618 -129.362118)
			(xy 257.363795 -129.323383) (xy 257.409183 -129.290911) (xy 257.458815 -129.265393) (xy 257.511635 -129.247374)
			(xy 257.566514 -129.237237) (xy 257.622285 -129.235199) (xy 257.677759 -129.241302) (xy 257.731752 -129.255418)
			(xy 257.783115 -129.277245) (xy 257.830753 -129.306318) (xy 257.873649 -129.342017) (xy 257.910891 -129.383581)
			(xy 257.941685 -129.430125) (xy 257.965373 -129.480656) (xy 257.981451 -129.534098) (xy 257.989577 -129.589312)
			(xy 257.990086 -129.617216) (xy 257.989577 -129.64512) (xy 257.981451 -129.700334) (xy 257.965373 -129.753776)
			(xy 257.941685 -129.804307) (xy 257.910891 -129.850851) (xy 257.875371 -129.890493) (xy 259.726424 -129.890493)
			(xy 259.726424 -129.826539) (xy 259.734439 -129.763089) (xy 259.750344 -129.701144) (xy 259.773887 -129.641682)
			(xy 259.804697 -129.585638) (xy 259.842289 -129.533898) (xy 259.886068 -129.487278) (xy 259.935346 -129.446512)
			(xy 259.989344 -129.412244) (xy 260.047211 -129.385013) (xy 260.108035 -129.36525) (xy 260.170856 -129.353267)
			(xy 260.234684 -129.349251) (xy 260.298512 -129.353267) (xy 260.361333 -129.36525) (xy 260.422157 -129.385013)
			(xy 260.480024 -129.412244) (xy 260.534022 -129.446512) (xy 260.5833 -129.487278) (xy 260.627079 -129.533898)
			(xy 260.664671 -129.585638) (xy 260.695481 -129.641682) (xy 260.719024 -129.701144) (xy 260.734929 -129.763089)
			(xy 260.740359 -129.806076) (xy 263.070462 -129.806076) (xy 263.070462 -129.751524) (xy 263.078226 -129.697527)
			(xy 263.093596 -129.645185) (xy 263.11626 -129.595564) (xy 263.145755 -129.549673) (xy 263.181481 -129.508447)
			(xy 263.222711 -129.472726) (xy 263.268606 -129.443237) (xy 263.31823 -129.420579) (xy 263.370574 -129.405216)
			(xy 263.424572 -129.397458) (xy 263.451848 -129.396998) (xy 263.481128 -129.397578) (xy 263.539004 -129.406508)
			(xy 263.594838 -129.424168) (xy 263.647323 -129.450143) (xy 263.695228 -129.483825) (xy 263.737431 -129.524423)
			(xy 263.755632 -129.547366) (xy 263.758934 -129.55143) (xy 263.769918 -129.562264) (xy 263.796758 -129.577437)
			(xy 263.826904 -129.583904) (xy 263.857606 -129.581077) (xy 263.886064 -129.569212) (xy 263.909681 -129.549391)
			(xy 263.918446 -129.536698) (xy 263.920732 -129.532634) (xy 263.935384 -129.505452) (xy 263.970264 -129.454494)
			(xy 264.011055 -129.408133) (xy 264.057158 -129.367049) (xy 264.107894 -129.331848) (xy 264.162517 -129.303045)
			(xy 264.220225 -129.281066) (xy 264.280169 -129.266233) (xy 264.341468 -129.258765) (xy 264.372344 -129.258314)
			(xy 264.404318 -129.258867) (xy 264.46776 -129.266886) (xy 264.529698 -129.282794) (xy 264.589153 -129.306338)
			(xy 264.645189 -129.337149) (xy 264.696921 -129.374739) (xy 264.701932 -129.379445) (xy 268.08404 -129.379445)
			(xy 268.08404 -129.315491) (xy 268.092055 -129.252041) (xy 268.10796 -129.190096) (xy 268.131503 -129.130634)
			(xy 268.162313 -129.07459) (xy 268.199905 -129.02285) (xy 268.243684 -128.97623) (xy 268.292962 -128.935464)
			(xy 268.34696 -128.901196) (xy 268.404827 -128.873965) (xy 268.465651 -128.854202) (xy 268.528472 -128.842219)
			(xy 268.5923 -128.838203) (xy 268.656128 -128.842219) (xy 268.718949 -128.854202) (xy 268.779773 -128.873965)
			(xy 268.83764 -128.901196) (xy 268.891638 -128.935464) (xy 268.940916 -128.97623) (xy 268.984695 -129.02285)
			(xy 269.022287 -129.07459) (xy 269.053097 -129.130634) (xy 269.07664 -129.190096) (xy 269.092545 -129.252041)
			(xy 269.10056 -129.315491) (xy 269.101062 -129.347468) (xy 269.10056 -129.379445) (xy 269.092545 -129.442895)
			(xy 269.07664 -129.50484) (xy 269.053097 -129.564302) (xy 269.022287 -129.620346) (xy 268.984695 -129.672086)
			(xy 268.940916 -129.718706) (xy 268.891638 -129.759472) (xy 268.83764 -129.79374) (xy 268.779773 -129.820971)
			(xy 268.718949 -129.840734) (xy 268.656128 -129.852717) (xy 268.5923 -129.856733) (xy 268.528472 -129.852717)
			(xy 268.465651 -129.840734) (xy 268.404827 -129.820971) (xy 268.34696 -129.79374) (xy 268.292962 -129.759472)
			(xy 268.243684 -129.718706) (xy 268.199905 -129.672086) (xy 268.162313 -129.620346) (xy 268.131503 -129.564302)
			(xy 268.10796 -129.50484) (xy 268.092055 -129.442895) (xy 268.08404 -129.379445) (xy 264.701932 -129.379445)
			(xy 264.743535 -129.418516) (xy 264.784295 -129.46779) (xy 264.818558 -129.521784) (xy 264.845784 -129.579646)
			(xy 264.865544 -129.640464) (xy 264.877526 -129.703279) (xy 264.881541 -129.7671) (xy 264.877526 -129.830921)
			(xy 264.865544 -129.893736) (xy 264.845784 -129.954554) (xy 264.818558 -130.012416) (xy 264.784295 -130.06641)
			(xy 264.743535 -130.115684) (xy 264.696921 -130.159461) (xy 264.645189 -130.197051) (xy 264.589153 -130.227862)
			(xy 264.538557 -130.247898) (xy 267.973046 -130.247898) (xy 267.977119 -130.192239) (xy 267.989254 -130.137766)
			(xy 268.00919 -130.08564) (xy 268.036504 -130.036972) (xy 268.070612 -129.9928) (xy 268.110789 -129.954065)
			(xy 268.156177 -129.921593) (xy 268.205809 -129.896075) (xy 268.258629 -129.878056) (xy 268.313508 -129.867919)
			(xy 268.369279 -129.865881) (xy 268.424753 -129.871984) (xy 268.478746 -129.8861) (xy 268.530109 -129.907927)
			(xy 268.577747 -129.937) (xy 268.620643 -129.972699) (xy 268.657885 -130.014263) (xy 268.688679 -130.060807)
			(xy 268.712367 -130.111338) (xy 268.728445 -130.16478) (xy 268.736571 -130.219994) (xy 268.73708 -130.247898)
			(xy 268.736571 -130.275802) (xy 268.728445 -130.331016) (xy 268.712367 -130.384458) (xy 268.688679 -130.434989)
			(xy 268.657885 -130.481533) (xy 268.620643 -130.523097) (xy 268.577747 -130.558796) (xy 268.530109 -130.587869)
			(xy 268.478746 -130.609696) (xy 268.424753 -130.623812) (xy 268.369279 -130.629915) (xy 268.313508 -130.627877)
			(xy 268.258629 -130.61774) (xy 268.205809 -130.599721) (xy 268.156177 -130.574203) (xy 268.110789 -130.541731)
			(xy 268.070612 -130.502996) (xy 268.036504 -130.458824) (xy 268.00919 -130.410156) (xy 267.989254 -130.35803)
			(xy 267.977119 -130.303557) (xy 267.973046 -130.247898) (xy 264.538557 -130.247898) (xy 264.529698 -130.251406)
			(xy 264.46776 -130.267314) (xy 264.404318 -130.275333) (xy 264.372344 -130.275838) (xy 264.342191 -130.275342)
			(xy 264.282309 -130.26821) (xy 264.223688 -130.254054) (xy 264.167151 -130.233071) (xy 264.113488 -130.205555)
			(xy 264.063452 -130.171892) (xy 264.017744 -130.132553) (xy 263.977004 -130.088089) (xy 263.941802 -130.039124)
			(xy 263.926828 -130.012948) (xy 263.924542 -130.008884) (xy 263.91679 -129.998092) (xy 263.896719 -129.980689)
			(xy 263.872835 -129.969059) (xy 263.846758 -129.96399) (xy 263.820257 -129.965827) (xy 263.795128 -129.974444)
			(xy 263.773077 -129.989258) (xy 263.764014 -129.998978) (xy 263.760966 -130.002534) (xy 263.745545 -130.023166)
			(xy 263.71003 -130.060475) (xy 263.669815 -130.092663) (xy 263.625634 -130.119145) (xy 263.57829 -130.139439)
			(xy 263.528645 -130.153174) (xy 263.477603 -130.160101) (xy 263.451848 -130.160522) (xy 263.424572 -130.160142)
			(xy 263.370574 -130.152384) (xy 263.31823 -130.137021) (xy 263.268606 -130.114363) (xy 263.222711 -130.084874)
			(xy 263.181481 -130.049153) (xy 263.145755 -130.007927) (xy 263.11626 -129.962036) (xy 263.093596 -129.912415)
			(xy 263.078226 -129.860073) (xy 263.070462 -129.806076) (xy 260.740359 -129.806076) (xy 260.742944 -129.826539)
			(xy 260.743446 -129.858516) (xy 260.742944 -129.890493) (xy 260.734929 -129.953943) (xy 260.719024 -130.015888)
			(xy 260.695481 -130.07535) (xy 260.664671 -130.131394) (xy 260.627079 -130.183134) (xy 260.5833 -130.229754)
			(xy 260.534022 -130.27052) (xy 260.480024 -130.304788) (xy 260.422157 -130.332019) (xy 260.361333 -130.351782)
			(xy 260.298512 -130.363765) (xy 260.234684 -130.367781) (xy 260.170856 -130.363765) (xy 260.108035 -130.351782)
			(xy 260.047211 -130.332019) (xy 259.989344 -130.304788) (xy 259.935346 -130.27052) (xy 259.886068 -130.229754)
			(xy 259.842289 -130.183134) (xy 259.804697 -130.131394) (xy 259.773887 -130.07535) (xy 259.750344 -130.015888)
			(xy 259.734439 -129.953943) (xy 259.726424 -129.890493) (xy 257.875371 -129.890493) (xy 257.873649 -129.892415)
			(xy 257.830753 -129.928114) (xy 257.783115 -129.957187) (xy 257.731752 -129.979014) (xy 257.677759 -129.99313)
			(xy 257.622285 -129.999233) (xy 257.566514 -129.997195) (xy 257.511635 -129.987058) (xy 257.458815 -129.969039)
			(xy 257.409183 -129.943521) (xy 257.363795 -129.911049) (xy 257.323618 -129.872314) (xy 257.28951 -129.828142)
			(xy 257.262196 -129.779474) (xy 257.24226 -129.727348) (xy 257.230125 -129.672875) (xy 257.226052 -129.617216)
			(xy 254.622554 -129.617216) (xy 254.622554 -130.54584) (xy 254.643128 -130.573018) (xy 254.659638 -130.57759)
			(xy 254.689785 -130.586544) (xy 254.747774 -130.610881) (xy 254.802324 -130.642177) (xy 254.852602 -130.679955)
			(xy 254.897843 -130.72364) (xy 254.937357 -130.772566) (xy 254.962014 -130.812259) (xy 262.815572 -130.812259)
			(xy 262.815572 -130.748305) (xy 262.823587 -130.684855) (xy 262.839492 -130.62291) (xy 262.863035 -130.563448)
			(xy 262.893845 -130.507404) (xy 262.931437 -130.455664) (xy 262.975216 -130.409044) (xy 263.024494 -130.368278)
			(xy 263.078492 -130.33401) (xy 263.136359 -130.306779) (xy 263.197183 -130.287016) (xy 263.260004 -130.275033)
			(xy 263.323832 -130.271017) (xy 263.38766 -130.275033) (xy 263.450481 -130.287016) (xy 263.511305 -130.306779)
			(xy 263.569172 -130.33401) (xy 263.62317 -130.368278) (xy 263.672448 -130.409044) (xy 263.716227 -130.455664)
			(xy 263.753819 -130.507404) (xy 263.784629 -130.563448) (xy 263.808172 -130.62291) (xy 263.824077 -130.684855)
			(xy 263.832092 -130.748305) (xy 263.832594 -130.780282) (xy 263.832092 -130.812259) (xy 263.824077 -130.875709)
			(xy 263.808172 -130.937654) (xy 263.784629 -130.997116) (xy 263.753819 -131.05316) (xy 263.716227 -131.1049)
			(xy 263.672448 -131.15152) (xy 263.62317 -131.192286) (xy 263.569172 -131.226554) (xy 263.511305 -131.253785)
			(xy 263.450481 -131.273548) (xy 263.38766 -131.285531) (xy 263.323832 -131.289547) (xy 263.260004 -131.285531)
			(xy 263.197183 -131.273548) (xy 263.136359 -131.253785) (xy 263.078492 -131.226554) (xy 263.024494 -131.192286)
			(xy 262.975216 -131.15152) (xy 262.931437 -131.1049) (xy 262.893845 -131.05316) (xy 262.863035 -130.997116)
			(xy 262.839492 -130.937654) (xy 262.823587 -130.875709) (xy 262.815572 -130.812259) (xy 254.962014 -130.812259)
			(xy 254.970542 -130.825988) (xy 254.996892 -130.883091) (xy 255.016007 -130.943005) (xy 255.027593 -131.004818)
			(xy 255.031476 -131.067588) (xy 255.027596 -131.130358) (xy 255.016012 -131.192171) (xy 254.996901 -131.252087)
			(xy 254.970553 -131.309191) (xy 254.937371 -131.362614) (xy 254.897859 -131.411542) (xy 254.85262 -131.455229)
			(xy 254.802344 -131.49301) (xy 254.747796 -131.524308) (xy 254.689807 -131.548648) (xy 254.659638 -131.557522)
			(xy 254.643128 -131.562094) (xy 254.622554 -131.589272) (xy 254.622554 -131.641061) (xy 256.871464 -131.641061)
			(xy 256.871464 -131.577107) (xy 256.879479 -131.513657) (xy 256.895384 -131.451712) (xy 256.918927 -131.39225)
			(xy 256.949737 -131.336206) (xy 256.987329 -131.284466) (xy 257.031108 -131.237846) (xy 257.080386 -131.19708)
			(xy 257.134384 -131.162812) (xy 257.192251 -131.135581) (xy 257.253075 -131.115818) (xy 257.315896 -131.103835)
			(xy 257.379724 -131.099819) (xy 257.443552 -131.103835) (xy 257.506373 -131.115818) (xy 257.567197 -131.135581)
			(xy 257.625064 -131.162812) (xy 257.679062 -131.19708) (xy 257.72834 -131.237846) (xy 257.772119 -131.284466)
			(xy 257.809711 -131.336206) (xy 257.840521 -131.39225) (xy 257.864064 -131.451712) (xy 257.879969 -131.513657)
			(xy 257.887984 -131.577107) (xy 257.888486 -131.609084) (xy 257.887984 -131.641061) (xy 257.879969 -131.704511)
			(xy 257.864064 -131.766456) (xy 257.840521 -131.825918) (xy 257.809711 -131.881962) (xy 257.772119 -131.933702)
			(xy 257.72834 -131.980322) (xy 257.679062 -132.021088) (xy 257.625064 -132.055356) (xy 257.567197 -132.082587)
			(xy 257.506373 -132.10235) (xy 257.443552 -132.114333) (xy 257.379724 -132.118349) (xy 257.315896 -132.114333)
			(xy 257.253075 -132.10235) (xy 257.192251 -132.082587) (xy 257.134384 -132.055356) (xy 257.080386 -132.021088)
			(xy 257.031108 -131.980322) (xy 256.987329 -131.933702) (xy 256.949737 -131.881962) (xy 256.918927 -131.825918)
			(xy 256.895384 -131.766456) (xy 256.879479 -131.704511) (xy 256.871464 -131.641061) (xy 254.622554 -131.641061)
			(xy 254.622554 -131.81584) (xy 254.643128 -131.843018) (xy 254.659638 -131.84759) (xy 254.689785 -131.856544)
			(xy 254.747774 -131.880881) (xy 254.802324 -131.912177) (xy 254.852602 -131.949955) (xy 254.897843 -131.99364)
			(xy 254.937357 -132.042566) (xy 254.970542 -132.095988) (xy 254.996892 -132.153091) (xy 255.016007 -132.213005)
			(xy 255.027593 -132.274818) (xy 255.031476 -132.337588) (xy 255.029501 -132.369533) (xy 262.954256 -132.369533)
			(xy 262.954256 -132.305579) (xy 262.962271 -132.242129) (xy 262.978176 -132.180184) (xy 263.001719 -132.120722)
			(xy 263.032529 -132.064678) (xy 263.070121 -132.012938) (xy 263.1139 -131.966318) (xy 263.163178 -131.925552)
			(xy 263.217176 -131.891284) (xy 263.275043 -131.864053) (xy 263.335867 -131.84429) (xy 263.398688 -131.832307)
			(xy 263.462516 -131.828291) (xy 263.526344 -131.832307) (xy 263.589165 -131.84429) (xy 263.649989 -131.864053)
			(xy 263.707856 -131.891284) (xy 263.761854 -131.925552) (xy 263.811132 -131.966318) (xy 263.854911 -132.012938)
			(xy 263.892503 -132.064678) (xy 263.923313 -132.120722) (xy 263.946856 -132.180184) (xy 263.962761 -132.242129)
			(xy 263.970776 -132.305579) (xy 263.971278 -132.337556) (xy 263.971039 -132.352796) (xy 265.112244 -132.352796)
			(xy 265.116317 -132.297137) (xy 265.128452 -132.242664) (xy 265.148388 -132.190538) (xy 265.175702 -132.14187)
			(xy 265.20981 -132.097698) (xy 265.249987 -132.058963) (xy 265.295375 -132.026491) (xy 265.345007 -132.000973)
			(xy 265.397827 -131.982954) (xy 265.452706 -131.972817) (xy 265.508477 -131.970779) (xy 265.563951 -131.976882)
			(xy 265.617944 -131.990998) (xy 265.669307 -132.012825) (xy 265.716945 -132.041898) (xy 265.759841 -132.077597)
			(xy 265.797083 -132.119161) (xy 265.827877 -132.165705) (xy 265.851565 -132.216236) (xy 265.867643 -132.269678)
			(xy 265.875769 -132.324892) (xy 265.876278 -132.352796) (xy 265.875769 -132.3807) (xy 265.867643 -132.435914)
			(xy 265.851565 -132.489356) (xy 265.827877 -132.539887) (xy 265.797083 -132.586431) (xy 265.759841 -132.627995)
			(xy 265.716945 -132.663694) (xy 265.669307 -132.692767) (xy 265.617944 -132.714594) (xy 265.563951 -132.72871)
			(xy 265.508477 -132.734813) (xy 265.452706 -132.732775) (xy 265.397827 -132.722638) (xy 265.345007 -132.704619)
			(xy 265.295375 -132.679101) (xy 265.249987 -132.646629) (xy 265.20981 -132.607894) (xy 265.175702 -132.563722)
			(xy 265.148388 -132.515054) (xy 265.128452 -132.462928) (xy 265.116317 -132.408455) (xy 265.112244 -132.352796)
			(xy 263.971039 -132.352796) (xy 263.970776 -132.369533) (xy 263.962761 -132.432983) (xy 263.946856 -132.494928)
			(xy 263.923313 -132.55439) (xy 263.892503 -132.610434) (xy 263.854911 -132.662174) (xy 263.811132 -132.708794)
			(xy 263.761854 -132.74956) (xy 263.707856 -132.783828) (xy 263.649989 -132.811059) (xy 263.589165 -132.830822)
			(xy 263.526344 -132.842805) (xy 263.462516 -132.846821) (xy 263.398688 -132.842805) (xy 263.335867 -132.830822)
			(xy 263.275043 -132.811059) (xy 263.217176 -132.783828) (xy 263.163178 -132.74956) (xy 263.1139 -132.708794)
			(xy 263.070121 -132.662174) (xy 263.032529 -132.610434) (xy 263.001719 -132.55439) (xy 262.978176 -132.494928)
			(xy 262.962271 -132.432983) (xy 262.954256 -132.369533) (xy 255.029501 -132.369533) (xy 255.027596 -132.400358)
			(xy 255.016012 -132.462171) (xy 254.996901 -132.522087) (xy 254.970553 -132.579191) (xy 254.937371 -132.632614)
			(xy 254.897859 -132.681542) (xy 254.85262 -132.725229) (xy 254.802344 -132.76301) (xy 254.747796 -132.794308)
			(xy 254.689807 -132.818648) (xy 254.659638 -132.827522) (xy 254.643128 -132.832094) (xy 254.622554 -132.859272)
			(xy 254.622554 -133.063996) (xy 264.096244 -133.063996) (xy 264.100317 -133.008337) (xy 264.112452 -132.953864)
			(xy 264.132388 -132.901738) (xy 264.159702 -132.85307) (xy 264.19381 -132.808898) (xy 264.233987 -132.770163)
			(xy 264.279375 -132.737691) (xy 264.329007 -132.712173) (xy 264.381827 -132.694154) (xy 264.436706 -132.684017)
			(xy 264.492477 -132.681979) (xy 264.547951 -132.688082) (xy 264.601944 -132.702198) (xy 264.653307 -132.724025)
			(xy 264.700945 -132.753098) (xy 264.743841 -132.788797) (xy 264.781083 -132.830361) (xy 264.811877 -132.876905)
			(xy 264.835565 -132.927436) (xy 264.837669 -132.934429) (xy 268.282414 -132.934429) (xy 268.282414 -132.870475)
			(xy 268.290429 -132.807025) (xy 268.306334 -132.74508) (xy 268.329877 -132.685618) (xy 268.360687 -132.629574)
			(xy 268.398279 -132.577834) (xy 268.442058 -132.531214) (xy 268.491336 -132.490448) (xy 268.545334 -132.45618)
			(xy 268.603201 -132.428949) (xy 268.664025 -132.409186) (xy 268.726846 -132.397203) (xy 268.790674 -132.393187)
			(xy 268.854502 -132.397203) (xy 268.917323 -132.409186) (xy 268.978147 -132.428949) (xy 269.036014 -132.45618)
			(xy 269.090012 -132.490448) (xy 269.13929 -132.531214) (xy 269.183069 -132.577834) (xy 269.220661 -132.629574)
			(xy 269.251471 -132.685618) (xy 269.275014 -132.74508) (xy 269.290919 -132.807025) (xy 269.298934 -132.870475)
			(xy 269.299436 -132.902452) (xy 269.298934 -132.934429) (xy 269.290919 -132.997879) (xy 269.275014 -133.059824)
			(xy 269.251471 -133.119286) (xy 269.220661 -133.17533) (xy 269.183069 -133.22707) (xy 269.13929 -133.27369)
			(xy 269.090012 -133.314456) (xy 269.036014 -133.348724) (xy 268.978147 -133.375955) (xy 268.917323 -133.395718)
			(xy 268.854502 -133.407701) (xy 268.790674 -133.411717) (xy 268.726846 -133.407701) (xy 268.664025 -133.395718)
			(xy 268.603201 -133.375955) (xy 268.545334 -133.348724) (xy 268.491336 -133.314456) (xy 268.442058 -133.27369)
			(xy 268.398279 -133.22707) (xy 268.360687 -133.17533) (xy 268.329877 -133.119286) (xy 268.306334 -133.059824)
			(xy 268.290429 -132.997879) (xy 268.282414 -132.934429) (xy 264.837669 -132.934429) (xy 264.851643 -132.980878)
			(xy 264.859769 -133.036092) (xy 264.860278 -133.063996) (xy 264.859769 -133.0919) (xy 264.851643 -133.147114)
			(xy 264.835565 -133.200556) (xy 264.811877 -133.251087) (xy 264.781083 -133.297631) (xy 264.743841 -133.339195)
			(xy 264.700945 -133.374894) (xy 264.653307 -133.403967) (xy 264.601944 -133.425794) (xy 264.547951 -133.43991)
			(xy 264.492477 -133.446013) (xy 264.436706 -133.443975) (xy 264.381827 -133.433838) (xy 264.329007 -133.415819)
			(xy 264.279375 -133.390301) (xy 264.233987 -133.357829) (xy 264.19381 -133.319094) (xy 264.159702 -133.274922)
			(xy 264.132388 -133.226254) (xy 264.112452 -133.174128) (xy 264.100317 -133.119655) (xy 264.096244 -133.063996)
			(xy 254.622554 -133.063996) (xy 254.622554 -133.10108) (xy 254.643128 -133.128258) (xy 254.659638 -133.13283)
			(xy 254.689782 -133.141784) (xy 254.747767 -133.16612) (xy 254.802312 -133.197415) (xy 254.852586 -133.235192)
			(xy 254.897822 -133.278874) (xy 254.937332 -133.327797) (xy 254.970513 -133.381216) (xy 254.99686 -133.438315)
			(xy 255.015972 -133.498225) (xy 255.027557 -133.560034) (xy 255.031438 -133.622799) (xy 255.027557 -133.685564)
			(xy 255.015972 -133.747373) (xy 254.996861 -133.807283) (xy 254.970514 -133.864382) (xy 254.937333 -133.917801)
			(xy 254.897823 -133.966724) (xy 254.852587 -134.010407) (xy 254.802314 -134.048184) (xy 254.747769 -134.079479)
			(xy 254.689784 -134.103815) (xy 254.659638 -134.112762) (xy 254.643128 -134.117334) (xy 254.622554 -134.144512)
			(xy 254.622554 -134.37108) (xy 254.643128 -134.398258) (xy 254.659638 -134.40283) (xy 254.689782 -134.411784)
			(xy 254.747767 -134.43612) (xy 254.802312 -134.467415) (xy 254.852586 -134.505192) (xy 254.897822 -134.548874)
			(xy 254.937332 -134.597797) (xy 254.970513 -134.651216) (xy 254.99686 -134.708315) (xy 255.015972 -134.768225)
			(xy 255.027557 -134.830034) (xy 255.031438 -134.892799) (xy 255.027557 -134.955564) (xy 255.015972 -135.017373)
			(xy 254.996861 -135.077283) (xy 254.970514 -135.134382) (xy 254.937333 -135.187801) (xy 254.897823 -135.236724)
			(xy 254.878634 -135.255254) (xy 256.870962 -135.255254) (xy 256.871507 -135.221899) (xy 256.88023 -135.155761)
			(xy 256.897522 -135.091331) (xy 256.923085 -135.029713) (xy 256.956482 -134.971964) (xy 256.997138 -134.919074)
			(xy 257.044358 -134.871951) (xy 257.097331 -134.831403) (xy 257.125978 -134.81431) (xy 257.137154 -134.80796)
			(xy 257.150362 -134.786878) (xy 257.158998 -134.67842) (xy 257.154426 -134.667752) (xy 257.151836 -134.662127)
			(xy 257.144379 -134.652244) (xy 257.139694 -134.648194) (xy 257.117986 -134.629937) (xy 257.079639 -134.588146)
			(xy 257.047898 -134.541142) (xy 257.02346 -134.489958) (xy 257.006865 -134.435722) (xy 256.998478 -134.379627)
			(xy 256.997962 -134.351268) (xy 256.998382 -134.324971) (xy 257.005624 -134.272877) (xy 257.019951 -134.222272)
			(xy 257.041094 -134.174114) (xy 257.06865 -134.129316) (xy 257.102097 -134.088727) (xy 257.121152 -134.070598)
			(xy 257.128502 -134.063062) (xy 257.136889 -134.043775) (xy 257.137408 -134.03326) (xy 257.137408 -133.959092)
			(xy 257.136936 -133.948568) (xy 257.128528 -133.929277) (xy 257.121152 -133.921754) (xy 257.102097 -133.90363)
			(xy 257.068672 -133.863027) (xy 257.041134 -133.818224) (xy 257.02 -133.770067) (xy 257.005672 -133.719466)
			(xy 256.99842 -133.667379) (xy 256.997962 -133.641084) (xy 256.998448 -133.613815) (xy 257.00621 -133.559831)
			(xy 257.021575 -133.507501) (xy 257.044232 -133.457891) (xy 257.073718 -133.41201) (xy 257.109433 -133.370793)
			(xy 257.15065 -133.335078) (xy 257.196531 -133.305592) (xy 257.246141 -133.282935) (xy 257.298471 -133.26757)
			(xy 257.352455 -133.259808) (xy 257.406993 -133.259808) (xy 257.460977 -133.26757) (xy 257.513307 -133.282935)
			(xy 257.562917 -133.305592) (xy 257.608798 -133.335078) (xy 257.650015 -133.370793) (xy 257.68573 -133.41201)
			(xy 257.715216 -133.457891) (xy 257.737873 -133.507501) (xy 257.753238 -133.559831) (xy 257.761 -133.613815)
			(xy 257.761486 -133.641084) (xy 257.761259 -133.654773) (xy 262.954256 -133.654773) (xy 262.954256 -133.590819)
			(xy 262.962271 -133.527369) (xy 262.978176 -133.465424) (xy 263.001719 -133.405962) (xy 263.032529 -133.349918)
			(xy 263.070121 -133.298178) (xy 263.1139 -133.251558) (xy 263.163178 -133.210792) (xy 263.217176 -133.176524)
			(xy 263.275043 -133.149293) (xy 263.335867 -133.12953) (xy 263.398688 -133.117547) (xy 263.462516 -133.113531)
			(xy 263.526344 -133.117547) (xy 263.589165 -133.12953) (xy 263.649989 -133.149293) (xy 263.707856 -133.176524)
			(xy 263.761854 -133.210792) (xy 263.811132 -133.251558) (xy 263.854911 -133.298178) (xy 263.892503 -133.349918)
			(xy 263.923313 -133.405962) (xy 263.946856 -133.465424) (xy 263.962761 -133.527369) (xy 263.970776 -133.590819)
			(xy 263.971278 -133.622796) (xy 263.970776 -133.654773) (xy 263.962761 -133.718223) (xy 263.946856 -133.780168)
			(xy 263.923313 -133.83963) (xy 263.892503 -133.895674) (xy 263.854911 -133.947414) (xy 263.811132 -133.994034)
			(xy 263.761854 -134.0348) (xy 263.707856 -134.069068) (xy 263.649989 -134.096299) (xy 263.589165 -134.116062)
			(xy 263.526344 -134.128045) (xy 263.462516 -134.132061) (xy 263.398688 -134.128045) (xy 263.335867 -134.116062)
			(xy 263.275043 -134.096299) (xy 263.217176 -134.069068) (xy 263.163178 -134.0348) (xy 263.1139 -133.994034)
			(xy 263.070121 -133.947414) (xy 263.032529 -133.895674) (xy 263.001719 -133.83963) (xy 262.978176 -133.780168)
			(xy 262.962271 -133.718223) (xy 262.954256 -133.654773) (xy 257.761259 -133.654773) (xy 257.76105 -133.667381)
			(xy 257.753814 -133.719474) (xy 257.739491 -133.77008) (xy 257.718352 -133.818239) (xy 257.690797 -133.863037)
			(xy 257.657351 -133.903625) (xy 257.638296 -133.921754) (xy 257.630974 -133.929314) (xy 257.62257 -133.948582)
			(xy 257.62204 -133.959092) (xy 257.62204 -134.03326) (xy 257.622524 -134.043783) (xy 257.630923 -134.063075)
			(xy 257.638296 -134.070598) (xy 257.657337 -134.088736) (xy 257.690761 -134.129337) (xy 257.7183 -134.174137)
			(xy 257.739436 -134.222291) (xy 257.753768 -134.272889) (xy 257.761025 -134.324974) (xy 257.761486 -134.351268)
			(xy 257.760939 -134.380656) (xy 257.75194 -134.43874) (xy 257.73415 -134.49476) (xy 257.734015 -134.495032)
			(xy 263.802366 -134.495032) (xy 263.806439 -134.439373) (xy 263.818574 -134.3849) (xy 263.83851 -134.332774)
			(xy 263.865824 -134.284106) (xy 263.899932 -134.239934) (xy 263.940109 -134.201199) (xy 263.985497 -134.168727)
			(xy 264.035129 -134.143209) (xy 264.087949 -134.12519) (xy 264.142828 -134.115053) (xy 264.198599 -134.113015)
			(xy 264.254073 -134.119118) (xy 264.308066 -134.133234) (xy 264.359429 -134.155061) (xy 264.407067 -134.184134)
			(xy 264.449963 -134.219833) (xy 264.487205 -134.261397) (xy 264.517999 -134.307941) (xy 264.541687 -134.358472)
			(xy 264.557765 -134.411914) (xy 264.565891 -134.467128) (xy 264.5664 -134.495032) (xy 264.565891 -134.522936)
			(xy 264.557765 -134.57815) (xy 264.541687 -134.631592) (xy 264.517999 -134.682123) (xy 264.487205 -134.728667)
			(xy 264.449963 -134.770231) (xy 264.407067 -134.80593) (xy 264.359429 -134.835003) (xy 264.308066 -134.85683)
			(xy 264.254073 -134.870946) (xy 264.198599 -134.877049) (xy 264.142828 -134.875011) (xy 264.087949 -134.864874)
			(xy 264.035129 -134.846855) (xy 263.985497 -134.821337) (xy 263.940109 -134.788865) (xy 263.899932 -134.75013)
			(xy 263.865824 -134.705958) (xy 263.83851 -134.65729) (xy 263.818574 -134.605164) (xy 263.806439 -134.550691)
			(xy 263.802366 -134.495032) (xy 257.734015 -134.495032) (xy 257.707989 -134.547394) (xy 257.674073 -134.595399)
			(xy 257.633205 -134.637642) (xy 257.610102 -134.655814) (xy 257.605276 -134.66699) (xy 257.603075 -134.672692)
			(xy 257.601156 -134.684761) (xy 257.601466 -134.690866) (xy 257.609086 -134.786878) (xy 257.622294 -134.80796)
			(xy 257.63347 -134.81431) (xy 257.662136 -134.831376) (xy 257.715118 -134.871921) (xy 257.762344 -134.919044)
			(xy 257.803005 -134.971937) (xy 257.836403 -135.029691) (xy 257.861964 -135.091315) (xy 257.879251 -135.155752)
			(xy 257.887965 -135.221896) (xy 257.888486 -135.255254) (xy 257.887984 -135.287231) (xy 257.879969 -135.350681)
			(xy 257.864064 -135.412626) (xy 257.840521 -135.472088) (xy 257.809711 -135.528132) (xy 257.772119 -135.579872)
			(xy 257.72834 -135.626492) (xy 257.679062 -135.667258) (xy 257.625064 -135.701526) (xy 257.567197 -135.728757)
			(xy 257.506373 -135.74852) (xy 257.443552 -135.760503) (xy 257.379724 -135.764519) (xy 257.315896 -135.760503)
			(xy 257.253075 -135.74852) (xy 257.192251 -135.728757) (xy 257.134384 -135.701526) (xy 257.080386 -135.667258)
			(xy 257.031108 -135.626492) (xy 256.987329 -135.579872) (xy 256.949737 -135.528132) (xy 256.918927 -135.472088)
			(xy 256.895384 -135.412626) (xy 256.879479 -135.350681) (xy 256.871464 -135.287231) (xy 256.870962 -135.255254)
			(xy 254.878634 -135.255254) (xy 254.852587 -135.280407) (xy 254.802314 -135.318184) (xy 254.747769 -135.349479)
			(xy 254.689784 -135.373815) (xy 254.659638 -135.382762) (xy 254.643128 -135.387334) (xy 254.622554 -135.414512)
			(xy 254.622554 -135.919437) (xy 262.641074 -135.919437) (xy 262.641074 -135.855483) (xy 262.649089 -135.792033)
			(xy 262.664994 -135.730088) (xy 262.688537 -135.670626) (xy 262.719347 -135.614582) (xy 262.756939 -135.562842)
			(xy 262.800718 -135.516222) (xy 262.849996 -135.475456) (xy 262.903994 -135.441188) (xy 262.961861 -135.413957)
			(xy 263.022685 -135.394194) (xy 263.085506 -135.382211) (xy 263.149334 -135.378195) (xy 263.213162 -135.382211)
			(xy 263.275983 -135.394194) (xy 263.336807 -135.413957) (xy 263.394674 -135.441188) (xy 263.448672 -135.475456)
			(xy 263.49795 -135.516222) (xy 263.541729 -135.562842) (xy 263.579321 -135.614582) (xy 263.610131 -135.670626)
			(xy 263.633674 -135.730088) (xy 263.649579 -135.792033) (xy 263.657594 -135.855483) (xy 263.658096 -135.88746)
			(xy 263.657594 -135.919437) (xy 263.649579 -135.982887) (xy 263.633674 -136.044832) (xy 263.610131 -136.104294)
			(xy 263.579321 -136.160338) (xy 263.541729 -136.212078) (xy 263.49795 -136.258698) (xy 263.448672 -136.299464)
			(xy 263.394674 -136.333732) (xy 263.336807 -136.360963) (xy 263.275983 -136.380726) (xy 263.213162 -136.392709)
			(xy 263.149334 -136.396725) (xy 263.085506 -136.392709) (xy 263.022685 -136.380726) (xy 262.961861 -136.360963)
			(xy 262.903994 -136.333732) (xy 262.849996 -136.299464) (xy 262.800718 -136.258698) (xy 262.756939 -136.212078)
			(xy 262.719347 -136.160338) (xy 262.688537 -136.104294) (xy 262.664994 -136.044832) (xy 262.649089 -135.982887)
			(xy 262.641074 -135.919437) (xy 254.622554 -135.919437) (xy 254.622554 -136.730376) (xy 259.380856 -136.730376)
			(xy 259.380856 -136.675824) (xy 259.38862 -136.621826) (xy 259.40399 -136.569484) (xy 259.426654 -136.519862)
			(xy 259.456149 -136.473971) (xy 259.491876 -136.432744) (xy 259.533106 -136.397023) (xy 259.579001 -136.367533)
			(xy 259.628625 -136.344875) (xy 259.68097 -136.329511) (xy 259.734968 -136.321753) (xy 259.762244 -136.321292)
			(xy 259.789895 -136.321683) (xy 259.844622 -136.329642) (xy 259.897628 -136.345415) (xy 259.947802 -136.368672)
			(xy 259.994095 -136.398927) (xy 260.035537 -136.435545) (xy 260.07126 -136.477761) (xy 260.100518 -136.524691)
			(xy 260.122696 -136.575351) (xy 260.137332 -136.628682) (xy 260.141212 -136.656064) (xy 260.141974 -136.660636)
			(xy 260.14559 -136.674836) (xy 260.159752 -136.700475) (xy 260.180598 -136.72105) (xy 260.206421 -136.734875)
			(xy 260.235102 -136.740817) (xy 260.264292 -136.738388) (xy 260.278118 -136.733534) (xy 260.282436 -136.731502)
			(xy 260.309046 -136.718675) (xy 260.364574 -136.698518) (xy 260.422062 -136.684925) (xy 260.480737 -136.678082)
			(xy 260.510274 -136.677654) (xy 260.541833 -136.678086) (xy 260.604465 -136.68589) (xy 260.665652 -136.701381)
			(xy 260.66994 -136.703054) (xy 261.835644 -136.703054) (xy 261.839717 -136.647395) (xy 261.851852 -136.592922)
			(xy 261.871788 -136.540796) (xy 261.899102 -136.492128) (xy 261.93321 -136.447956) (xy 261.973387 -136.409221)
			(xy 262.018775 -136.376749) (xy 262.068407 -136.351231) (xy 262.121227 -136.333212) (xy 262.176106 -136.323075)
			(xy 262.231877 -136.321037) (xy 262.287351 -136.32714) (xy 262.341344 -136.341256) (xy 262.392707 -136.363083)
			(xy 262.440345 -136.392156) (xy 262.483241 -136.427855) (xy 262.520483 -136.469419) (xy 262.551277 -136.515963)
			(xy 262.574965 -136.566494) (xy 262.591043 -136.619936) (xy 262.599169 -136.67515) (xy 262.599678 -136.703054)
			(xy 262.599169 -136.730958) (xy 262.591043 -136.786172) (xy 262.574965 -136.839614) (xy 262.551277 -136.890145)
			(xy 262.520483 -136.936689) (xy 262.483241 -136.978253) (xy 262.440345 -137.013952) (xy 262.392707 -137.043025)
			(xy 262.341344 -137.064852) (xy 262.287351 -137.078968) (xy 262.231877 -137.085071) (xy 262.176106 -137.083033)
			(xy 262.121227 -137.072896) (xy 262.068407 -137.054877) (xy 262.018775 -137.029359) (xy 261.973387 -136.996887)
			(xy 261.93321 -136.958152) (xy 261.899102 -136.91398) (xy 261.871788 -136.865312) (xy 261.851852 -136.813186)
			(xy 261.839717 -136.758713) (xy 261.835644 -136.703054) (xy 260.66994 -136.703054) (xy 260.724452 -136.724322)
			(xy 260.779964 -136.75436) (xy 260.831333 -136.791033) (xy 260.877772 -136.833779) (xy 260.918567 -136.881941)
			(xy 260.953091 -136.934778) (xy 260.980815 -136.991481) (xy 261.001311 -137.051177) (xy 261.014267 -137.112951)
			(xy 261.019482 -137.175852) (xy 261.016876 -137.238915) (xy 261.00649 -137.301172) (xy 260.988483 -137.361666)
			(xy 260.963132 -137.419468) (xy 260.950515 -137.440643) (xy 264.665454 -137.440643) (xy 264.665454 -137.376689)
			(xy 264.673469 -137.313239) (xy 264.689374 -137.251294) (xy 264.712917 -137.191832) (xy 264.743727 -137.135788)
			(xy 264.781319 -137.084048) (xy 264.825098 -137.037428) (xy 264.874376 -136.996662) (xy 264.928374 -136.962394)
			(xy 264.986241 -136.935163) (xy 265.047065 -136.9154) (xy 265.109886 -136.903417) (xy 265.173714 -136.899401)
			(xy 265.237542 -136.903417) (xy 265.300363 -136.9154) (xy 265.361187 -136.935163) (xy 265.419054 -136.962394)
			(xy 265.473052 -136.996662) (xy 265.52233 -137.037428) (xy 265.566109 -137.084048) (xy 265.603701 -137.135788)
			(xy 265.634511 -137.191832) (xy 265.658054 -137.251294) (xy 265.673959 -137.313239) (xy 265.681974 -137.376689)
			(xy 265.682476 -137.408666) (xy 265.681974 -137.440643) (xy 265.673959 -137.504093) (xy 265.658054 -137.566038)
			(xy 265.634511 -137.6255) (xy 265.603701 -137.681544) (xy 265.566109 -137.733284) (xy 265.52233 -137.779904)
			(xy 265.473052 -137.82067) (xy 265.419054 -137.854938) (xy 265.361187 -137.882169) (xy 265.300363 -137.901932)
			(xy 265.237542 -137.913915) (xy 265.173714 -137.917931) (xy 265.109886 -137.913915) (xy 265.047065 -137.901932)
			(xy 264.986241 -137.882169) (xy 264.928374 -137.854938) (xy 264.874376 -137.82067) (xy 264.825098 -137.779904)
			(xy 264.781319 -137.733284) (xy 264.743727 -137.681544) (xy 264.712917 -137.6255) (xy 264.689374 -137.566038)
			(xy 264.673469 -137.504093) (xy 264.665454 -137.440643) (xy 260.950515 -137.440643) (xy 260.930825 -137.47369)
			(xy 260.89206 -137.5235) (xy 260.847432 -137.568132) (xy 260.797625 -137.606902) (xy 260.743405 -137.639213)
			(xy 260.685605 -137.664569) (xy 260.625113 -137.682581) (xy 260.562857 -137.692972) (xy 260.499794 -137.695583)
			(xy 260.436892 -137.690373) (xy 260.375118 -137.677423) (xy 260.31542 -137.656931) (xy 260.258715 -137.629212)
			(xy 260.205874 -137.594692) (xy 260.157709 -137.553901) (xy 260.11496 -137.507466) (xy 260.078282 -137.456099)
			(xy 260.04824 -137.40059) (xy 260.025294 -137.341792) (xy 260.009798 -137.280607) (xy 260.001989 -137.217975)
			(xy 260.001512 -137.186416) (xy 260.00202 -137.16508) (xy 260.00202 -137.160254) (xy 260.000715 -137.145845)
			(xy 259.991067 -137.118582) (xy 259.974156 -137.095123) (xy 259.951341 -137.077353) (xy 259.924456 -137.066699)
			(xy 259.895662 -137.064019) (xy 259.88137 -137.066274) (xy 259.875782 -137.067544) (xy 259.848092 -137.075606)
			(xy 259.791079 -137.084286) (xy 259.762244 -137.084816) (xy 259.734968 -137.084447) (xy 259.68097 -137.076689)
			(xy 259.628625 -137.061325) (xy 259.579001 -137.038667) (xy 259.533106 -137.009177) (xy 259.491876 -136.973456)
			(xy 259.456149 -136.932229) (xy 259.426654 -136.886338) (xy 259.40399 -136.836716) (xy 259.38862 -136.784374)
			(xy 259.380856 -136.730376) (xy 254.622554 -136.730376) (xy 254.622554 -137.211816) (xy 254.6228 -137.218765)
			(xy 254.626548 -137.23215) (xy 254.62992 -137.238232) (xy 254.634273 -137.244883) (xy 254.646313 -137.255247)
			(xy 254.653542 -137.258552) (xy 254.739902 -137.294874) (xy 254.746934 -137.297599) (xy 254.761927 -137.299159)
			(xy 254.769366 -137.297922) (xy 254.784098 -137.295128) (xy 254.808133 -137.271031) (xy 254.861528 -137.228828)
			(xy 254.920077 -137.194127) (xy 254.982732 -137.167549) (xy 255.048374 -137.149569) (xy 255.115828 -137.140508)
			(xy 255.149858 -137.139934) (xy 255.181838 -137.140413) (xy 255.245295 -137.148424) (xy 255.307247 -137.164327)
			(xy 255.366718 -137.187868) (xy 255.422768 -137.218678) (xy 255.474515 -137.256271) (xy 255.521142 -137.300053)
			(xy 255.561914 -137.349334) (xy 255.596187 -137.403336) (xy 255.623422 -137.461209) (xy 255.643188 -137.522038)
			(xy 255.655173 -137.584866) (xy 255.65919 -137.6487) (xy 255.655173 -137.712534) (xy 255.643188 -137.775362)
			(xy 255.623422 -137.836191) (xy 255.596187 -137.894064) (xy 255.561914 -137.948066) (xy 255.521142 -137.997347)
			(xy 255.474515 -138.041129) (xy 255.422768 -138.078722) (xy 255.366718 -138.109532) (xy 255.307247 -138.133073)
			(xy 255.245295 -138.148976) (xy 255.181838 -138.156987) (xy 255.149858 -138.157458) (xy 255.117057 -138.156949)
			(xy 255.051998 -138.148519) (xy 254.988564 -138.131791) (xy 254.927808 -138.107044) (xy 254.87074 -138.074688)
			(xy 254.818307 -138.03526) (xy 254.794512 -138.012678) (xy 254.788996 -138.007717) (xy 254.775833 -138.000886)
			(xy 254.768604 -137.999216) (xy 254.761746 -137.997946) (xy 254.74676 -137.99947) (xy 254.653542 -138.03884)
			(xy 254.646365 -138.042224) (xy 254.634353 -138.052578) (xy 254.62992 -138.05916) (xy 254.622554 -138.071352)
			(xy 254.622554 -139.70828) (xy 255.93204 -139.70828) (xy 255.937251 -139.645382) (xy 255.950202 -139.583611)
			(xy 255.970695 -139.523916) (xy 255.998414 -139.467215) (xy 256.032933 -139.414378) (xy 256.073723 -139.366216)
			(xy 256.120157 -139.323469) (xy 256.171522 -139.286795) (xy 256.227029 -139.256755) (xy 256.285825 -139.233812)
			(xy 256.347008 -139.218318) (xy 256.409637 -139.21051) (xy 256.441194 -139.210034) (xy 256.468778 -139.210397)
			(xy 256.523623 -139.216365) (xy 256.5775 -139.228232) (xy 256.603754 -139.236704) (xy 256.615946 -139.234418)
			(xy 256.62213 -139.232956) (xy 256.633569 -139.227438) (xy 256.638552 -139.223496) (xy 256.713736 -139.161266)
			(xy 256.723388 -139.137644) (xy 256.722118 -139.124944) (xy 256.721053 -139.11469) (xy 256.719912 -139.094105)
			(xy 256.719832 -139.083796) (xy 256.71992 -139.073488) (xy 256.721064 -139.052903) (xy 256.722118 -139.042648)
			(xy 256.723388 -139.029948) (xy 256.713736 -139.006326) (xy 256.628646 -138.935714) (xy 256.616708 -138.933428)
			(xy 256.610491 -138.932361) (xy 256.597896 -138.933013) (xy 256.591816 -138.934698) (xy 256.555076 -138.945359)
			(xy 256.479443 -138.956845) (xy 256.441194 -138.957558) (xy 256.409638 -138.95708) (xy 256.34701 -138.949273)
			(xy 256.285829 -138.933779) (xy 256.227034 -138.910836) (xy 256.171528 -138.880797) (xy 256.120164 -138.844124)
			(xy 256.073731 -138.801378) (xy 256.032942 -138.753218) (xy 255.998423 -138.700382) (xy 255.970705 -138.643682)
			(xy 255.950212 -138.583989) (xy 255.937261 -138.522219) (xy 255.93205 -138.459322) (xy 255.934658 -138.396263)
			(xy 255.945046 -138.334012) (xy 255.963055 -138.273523) (xy 255.988407 -138.215726) (xy 256.020714 -138.161509)
			(xy 256.059478 -138.111704) (xy 256.104106 -138.067077) (xy 256.153911 -138.028313) (xy 256.208128 -137.996006)
			(xy 256.265925 -137.970654) (xy 256.326414 -137.952646) (xy 256.388665 -137.942258) (xy 256.451724 -137.93965)
			(xy 256.514621 -137.944861) (xy 256.576391 -137.957813) (xy 256.636084 -137.978305) (xy 256.692783 -138.006024)
			(xy 256.745619 -138.040543) (xy 256.79378 -138.081333) (xy 256.836525 -138.127766) (xy 256.873199 -138.17913)
			(xy 256.903237 -138.234636) (xy 256.926179 -138.293431) (xy 256.941673 -138.354612) (xy 256.94948 -138.41724)
			(xy 256.949956 -138.448796) (xy 256.949295 -138.485253) (xy 256.938845 -138.557416) (xy 256.929128 -138.59256)
			(xy 256.932176 -138.604752) (xy 256.933845 -138.6107) (xy 256.939633 -138.621611) (xy 256.943606 -138.626342)
			(xy 257.004566 -138.694922) (xy 257.01498 -138.702034) (xy 257.02006 -138.703812) (xy 257.026075 -138.705783)
			(xy 257.038664 -138.707073) (xy 257.044952 -138.706352) (xy 257.059026 -138.704342) (xy 257.087377 -138.70218)
			(xy 257.101594 -138.702034) (xy 257.128572 -138.702475) (xy 257.181992 -138.710067) (xy 257.233812 -138.7251)
			(xy 257.283 -138.747276) (xy 257.328579 -138.776153) (xy 257.36964 -138.811157) (xy 257.387852 -138.831066)
			(xy 257.395371 -138.838888) (xy 257.415113 -138.847839) (xy 257.425952 -138.848338) (xy 257.501136 -138.848338)
			(xy 257.511965 -138.84779) (xy 257.531698 -138.838858) (xy 257.539236 -138.831066) (xy 257.557449 -138.81116)
			(xy 257.598514 -138.776164) (xy 257.644093 -138.747293) (xy 257.693282 -138.725121) (xy 257.7451 -138.71009)
			(xy 257.798517 -138.702499) (xy 257.825494 -138.702034) (xy 257.859783 -138.702764) (xy 257.927256 -138.715027)
			(xy 257.959606 -138.726418) (xy 257.973322 -138.72337) (xy 257.980069 -138.721578) (xy 257.992312 -138.714884)
			(xy 257.997452 -138.710162) (xy 258.067302 -138.64209) (xy 258.07416 -138.630152) (xy 258.075684 -138.624056)
			(xy 258.077255 -138.617205) (xy 258.076999 -138.603158) (xy 258.075176 -138.59637) (xy 258.064965 -138.560334)
			(xy 258.053999 -138.486244) (xy 258.053332 -138.448796) (xy 258.053808 -138.415996) (xy 258.062236 -138.350939)
			(xy 258.078953 -138.287505) (xy 258.103681 -138.226744) (xy 258.13601 -138.169663) (xy 258.175405 -138.117209)
			(xy 258.221212 -138.070251) (xy 258.246626 -138.049508) (xy 258.251452 -138.03884) (xy 258.253679 -138.033273)
			(xy 258.25574 -138.021464) (xy 258.255516 -138.015472) (xy 258.249674 -137.921492) (xy 258.237482 -137.900918)
			(xy 258.227068 -137.89406) (xy 258.200426 -137.876474) (xy 258.151288 -137.835724) (xy 258.107636 -137.789144)
			(xy 258.070157 -137.737468) (xy 258.039439 -137.681507) (xy 258.015967 -137.622142) (xy 258.000108 -137.560307)
			(xy 257.992112 -137.496972) (xy 257.99161 -137.465054) (xy 257.992112 -137.433077) (xy 258.000127 -137.369627)
			(xy 258.016032 -137.307682) (xy 258.039575 -137.24822) (xy 258.070385 -137.192176) (xy 258.107977 -137.140436)
			(xy 258.151756 -137.093816) (xy 258.201034 -137.05305) (xy 258.255032 -137.018782) (xy 258.312899 -136.991551)
			(xy 258.373723 -136.971788) (xy 258.436544 -136.959805) (xy 258.500372 -136.955789) (xy 258.5642 -136.959805)
			(xy 258.627021 -136.971788) (xy 258.687845 -136.991551) (xy 258.745712 -137.018782) (xy 258.79971 -137.05305)
			(xy 258.848988 -137.093816) (xy 258.892767 -137.140436) (xy 258.930359 -137.192176) (xy 258.961169 -137.24822)
			(xy 258.984712 -137.307682) (xy 259.000617 -137.369627) (xy 259.008632 -137.433077) (xy 259.009134 -137.465054)
			(xy 259.008635 -137.497854) (xy 259.000212 -137.56291) (xy 258.9835 -137.626344) (xy 258.958777 -137.687105)
			(xy 258.926451 -137.744187) (xy 258.887058 -137.796641) (xy 258.841253 -137.843599) (xy 258.81584 -137.864342)
			(xy 258.811014 -137.87501) (xy 258.808768 -137.880571) (xy 258.80672 -137.892385) (xy 258.80695 -137.898378)
			(xy 258.812792 -137.992358) (xy 258.824984 -138.012932) (xy 258.835398 -138.01979) (xy 258.862055 -138.037354)
			(xy 258.911195 -138.078107) (xy 258.954847 -138.124689) (xy 258.992326 -138.176368) (xy 259.023042 -138.232332)
			(xy 259.046512 -138.291701) (xy 259.062366 -138.353539) (xy 259.070357 -138.416876) (xy 259.070856 -138.448796)
			(xy 259.070413 -138.479544) (xy 259.063001 -138.540591) (xy 259.048284 -138.600299) (xy 259.026478 -138.657798)
			(xy 258.9979 -138.712249) (xy 258.962966 -138.762859) (xy 258.922187 -138.808889) (xy 258.876157 -138.849668)
			(xy 258.825548 -138.884601) (xy 258.771096 -138.913179) (xy 258.713597 -138.934985) (xy 258.653889 -138.949701)
			(xy 258.592842 -138.957113) (xy 258.562094 -138.957558) (xy 258.533972 -138.957219) (xy 258.478069 -138.951053)
			(xy 258.423187 -138.938754) (xy 258.37 -138.92047) (xy 258.344416 -138.90879) (xy 258.331462 -138.90244)
			(xy 258.303522 -138.905488) (xy 258.209288 -138.977116) (xy 258.198874 -139.003532) (xy 258.201414 -139.017756)
			(xy 258.204132 -139.034131) (xy 258.207056 -139.067198) (xy 258.207256 -139.083796) (xy 258.207061 -139.100394)
			(xy 258.204133 -139.133461) (xy 258.201414 -139.149836) (xy 258.198874 -139.16406) (xy 258.209288 -139.190476)
			(xy 258.303522 -139.262104) (xy 258.331462 -139.265152) (xy 258.344416 -139.258802) (xy 258.370002 -139.247131)
			(xy 258.423194 -139.228866) (xy 258.478074 -139.216572) (xy 258.533974 -139.210398) (xy 258.562094 -139.210034)
			(xy 258.593651 -139.210507) (xy 258.656281 -139.218313) (xy 258.717465 -139.233806) (xy 258.776262 -139.256749)
			(xy 258.83177 -139.286787) (xy 258.883136 -139.323461) (xy 258.929571 -139.366207) (xy 258.970363 -139.414369)
			(xy 259.004884 -139.467206) (xy 259.014385 -139.48664) (xy 263.384792 -139.48664) (xy 263.385305 -139.453242)
			(xy 263.394053 -139.387023) (xy 263.41139 -139.322517) (xy 263.437018 -139.260834) (xy 263.470496 -139.203034)
			(xy 263.490456 -139.176252) (xy 263.495673 -139.168974) (xy 263.501136 -139.151933) (xy 263.501124 -139.142978)
			(xy 263.500616 -139.121642) (xy 263.501123 -139.090896) (xy 263.50853 -139.029853) (xy 263.523241 -138.970147)
			(xy 263.545042 -138.91265) (xy 263.573615 -138.8582) (xy 263.608543 -138.807591) (xy 263.649316 -138.761561)
			(xy 263.695341 -138.720782) (xy 263.745945 -138.685848) (xy 263.800391 -138.657269) (xy 263.857886 -138.63546)
			(xy 263.91759 -138.620742) (xy 263.978632 -138.613327) (xy 264.009378 -138.61288) (xy 264.041469 -138.613386)
			(xy 264.105141 -138.621451) (xy 264.167294 -138.637458) (xy 264.226942 -138.66115) (xy 264.283138 -138.692153)
			(xy 264.309352 -138.71067) (xy 264.317212 -138.715857) (xy 264.335367 -138.72078) (xy 264.354078 -138.718834)
			(xy 264.370831 -138.71028) (xy 264.377424 -138.703558) (xy 264.395609 -138.683776) (xy 264.436555 -138.648982)
			(xy 264.481981 -138.62028) (xy 264.530986 -138.59824) (xy 264.582599 -138.583298) (xy 264.6358 -138.57575)
			(xy 264.662666 -138.575288) (xy 264.693308 -138.575905) (xy 264.7538 -138.585733) (xy 264.783062 -138.594846)
			(xy 264.791912 -138.597331) (xy 264.810266 -138.596543) (xy 264.818876 -138.593322) (xy 264.842511 -138.583757)
			(xy 264.891692 -138.570304) (xy 264.942226 -138.563519) (xy 264.96772 -138.563096) (xy 264.994985 -138.563668)
			(xy 265.048961 -138.571431) (xy 265.101282 -138.586796) (xy 265.150885 -138.609451) (xy 265.196758 -138.638934)
			(xy 265.237969 -138.674646) (xy 265.273678 -138.715858) (xy 265.303159 -138.761733) (xy 265.325811 -138.811336)
			(xy 265.341173 -138.863659) (xy 265.348934 -138.917635) (xy 265.348934 -138.972165) (xy 265.341173 -139.026141)
			(xy 265.325811 -139.078464) (xy 265.303159 -139.128067) (xy 265.273678 -139.173942) (xy 265.237969 -139.215154)
			(xy 265.196758 -139.250866) (xy 265.150885 -139.280349) (xy 265.101282 -139.303004) (xy 265.048961 -139.318369)
			(xy 264.994985 -139.326132) (xy 264.96772 -139.32662) (xy 264.936948 -139.326062) (xy 264.876195 -139.316233)
			(xy 264.846816 -139.307062) (xy 264.837988 -139.304495) (xy 264.819627 -139.305148) (xy 264.811002 -139.308332)
			(xy 264.787436 -139.317818) (xy 264.738418 -139.331153) (xy 264.688066 -139.337885) (xy 264.662666 -139.338304)
			(xy 264.662412 -139.338304) (xy 264.629415 -139.337595) (xy 264.564407 -139.326224) (xy 264.533126 -139.315698)
			(xy 264.529824 -139.314428) (xy 264.520975 -139.311993) (xy 264.502657 -139.312929) (xy 264.485832 -139.320235)
			(xy 264.472641 -139.332981) (xy 264.468356 -139.341098) (xy 264.456415 -139.365281) (xy 264.428164 -139.411226)
			(xy 264.411968 -139.432792) (xy 264.406848 -139.44005) (xy 264.40138 -139.456932) (xy 264.4013 -139.465812)
			(xy 264.401808 -139.48664) (xy 264.401382 -139.517372) (xy 264.393969 -139.578387) (xy 264.379256 -139.638064)
			(xy 264.357457 -139.695532) (xy 264.32889 -139.749954) (xy 264.293972 -139.800536) (xy 264.253212 -139.846541)
			(xy 264.207205 -139.887297) (xy 264.15662 -139.922211) (xy 264.102196 -139.950773) (xy 264.044726 -139.972568)
			(xy 263.985048 -139.987276) (xy 263.924032 -139.994684) (xy 263.8933 -139.995148) (xy 263.862571 -139.994644)
			(xy 263.80156 -139.987236) (xy 263.741886 -139.972529) (xy 263.684421 -139.950736) (xy 263.630001 -139.922176)
			(xy 263.57942 -139.887265) (xy 263.533416 -139.846512) (xy 263.49266 -139.800511) (xy 263.457744 -139.749933)
			(xy 263.42918 -139.695516) (xy 263.407383 -139.638052) (xy 263.392671 -139.57838) (xy 263.385258 -139.517369)
			(xy 263.384792 -139.48664) (xy 259.014385 -139.48664) (xy 259.032604 -139.523907) (xy 259.053097 -139.583602)
			(xy 259.06605 -139.645373) (xy 259.071262 -139.708272) (xy 259.068654 -139.771333) (xy 259.058266 -139.833587)
			(xy 259.040258 -139.894078) (xy 259.014905 -139.951876) (xy 258.982598 -140.006095) (xy 258.943832 -140.055902)
			(xy 258.899203 -140.100531) (xy 258.849397 -140.139297) (xy 258.795178 -140.171604) (xy 258.73738 -140.196957)
			(xy 258.676889 -140.214966) (xy 258.614635 -140.225354) (xy 258.551574 -140.227962) (xy 258.488675 -140.22275)
			(xy 258.426904 -140.209798) (xy 258.367209 -140.189304) (xy 258.310508 -140.161585) (xy 258.25767 -140.127064)
			(xy 258.209509 -140.086273) (xy 258.166762 -140.039838) (xy 258.130088 -139.988472) (xy 258.100049 -139.932964)
			(xy 258.077107 -139.874167) (xy 258.061614 -139.812983) (xy 258.053807 -139.750353) (xy 258.053332 -139.718796)
			(xy 258.053704 -139.69148) (xy 258.059556 -139.637163) (xy 258.071192 -139.583786) (xy 258.079494 -139.55776)
			(xy 258.075938 -139.544298) (xy 258.073975 -139.537654) (xy 258.06701 -139.525684) (xy 258.062222 -139.520676)
			(xy 257.992372 -139.452604) (xy 257.980434 -139.446) (xy 257.974084 -139.444476) (xy 257.967247 -139.443125)
			(xy 257.953332 -139.443762) (xy 257.946652 -139.445746) (xy 257.917218 -139.454986) (xy 257.856338 -139.464944)
			(xy 257.825494 -139.465558) (xy 257.798515 -139.465128) (xy 257.745095 -139.457534) (xy 257.693275 -139.442499)
			(xy 257.644086 -139.420321) (xy 257.598508 -139.391442) (xy 257.557447 -139.356436) (xy 257.539236 -139.336526)
			(xy 257.531722 -139.328697) (xy 257.511976 -139.319751) (xy 257.501136 -139.319254) (xy 257.425952 -139.319254)
			(xy 257.415123 -139.319798) (xy 257.39539 -139.328733) (xy 257.387852 -139.336526) (xy 257.369643 -139.356436)
			(xy 257.328578 -139.391433) (xy 257.282997 -139.420303) (xy 257.233808 -139.442474) (xy 257.181989 -139.457504)
			(xy 257.128571 -139.465094) (xy 257.101594 -139.465558) (xy 257.084222 -139.465345) (xy 257.049625 -139.462168)
			(xy 257.032506 -139.459208) (xy 257.021076 -139.463526) (xy 257.015147 -139.465801) (xy 257.004605 -139.472876)
			(xy 257.000248 -139.477496) (xy 256.935224 -139.550648) (xy 256.93243 -139.562078) (xy 256.931108 -139.568303)
			(xy 256.931247 -139.581024) (xy 256.932684 -139.587224) (xy 256.940794 -139.619509) (xy 256.949456 -139.685511)
			(xy 256.949956 -139.718796) (xy 256.949491 -139.750353) (xy 256.941684 -139.812982) (xy 256.926191 -139.874165)
			(xy 256.903249 -139.932962) (xy 256.873211 -139.988469) (xy 256.836537 -140.039835) (xy 256.793791 -140.08627)
			(xy 256.74563 -140.127061) (xy 256.692794 -140.161582) (xy 256.636093 -140.189301) (xy 256.576399 -140.209795)
			(xy 256.514628 -140.222748) (xy 256.45173 -140.22796) (xy 256.38867 -140.225353) (xy 256.326416 -140.214965)
			(xy 256.265926 -140.196957) (xy 256.208127 -140.171605) (xy 256.153909 -140.139298) (xy 256.104102 -140.100533)
			(xy 256.059474 -140.055905) (xy 256.020708 -140.0061) (xy 255.9884 -139.951882) (xy 255.963047 -139.894084)
			(xy 255.945037 -139.833594) (xy 255.934649 -139.77134) (xy 255.93204 -139.70828) (xy 254.622554 -139.70828)
			(xy 254.622554 -140.082016) (xy 254.6228 -140.088965) (xy 254.626548 -140.10235) (xy 254.62992 -140.108432)
			(xy 254.634273 -140.115083) (xy 254.646313 -140.125447) (xy 254.653542 -140.128752) (xy 254.739902 -140.165074)
			(xy 254.746934 -140.167799) (xy 254.761927 -140.169359) (xy 254.769366 -140.168122) (xy 254.784098 -140.165328)
			(xy 254.808133 -140.141231) (xy 254.861528 -140.099028) (xy 254.920077 -140.064327) (xy 254.982732 -140.037749)
			(xy 255.048374 -140.019769) (xy 255.115828 -140.010708) (xy 255.149858 -140.010134) (xy 255.181838 -140.010613)
			(xy 255.245295 -140.018624) (xy 255.307247 -140.034527) (xy 255.366718 -140.058068) (xy 255.422768 -140.088878)
			(xy 255.474515 -140.126471) (xy 255.521142 -140.170253) (xy 255.561914 -140.219534) (xy 255.596187 -140.273536)
			(xy 255.623422 -140.331409) (xy 255.643077 -140.391896) (xy 260.608318 -140.391896) (xy 260.608821 -140.364627)
			(xy 260.616582 -140.310645) (xy 260.631947 -140.258317) (xy 260.654602 -140.208709) (xy 260.684087 -140.162829)
			(xy 260.7198 -140.121612) (xy 260.761016 -140.085896) (xy 260.806895 -140.05641) (xy 260.856502 -140.033753)
			(xy 260.90883 -140.018386) (xy 260.962811 -140.010622) (xy 260.99008 -140.010134) (xy 261.018767 -140.010713)
			(xy 261.075493 -140.01931) (xy 261.130294 -140.036297) (xy 261.181937 -140.061293) (xy 261.229258 -140.093734)
			(xy 261.271192 -140.13289) (xy 261.306796 -140.177881) (xy 261.335268 -140.227691) (xy 261.355965 -140.281202)
			(xy 261.362698 -140.309092) (xy 261.364984 -140.318744) (xy 261.375906 -140.334746) (xy 261.418324 -140.363194)
			(xy 261.441692 -140.366242) (xy 261.453122 -140.362432) (xy 261.48003 -140.353511) (xy 261.535318 -140.340975)
			(xy 261.591655 -140.334646) (xy 261.62 -140.334238) (xy 261.650746 -140.334702) (xy 261.711791 -140.342114)
			(xy 261.771497 -140.35683) (xy 261.828993 -140.378636) (xy 261.883442 -140.407213) (xy 261.93405 -140.442145)
			(xy 261.980078 -140.482922) (xy 262.020855 -140.52895) (xy 262.055787 -140.579558) (xy 262.084364 -140.634007)
			(xy 262.10617 -140.691503) (xy 262.120886 -140.751209) (xy 262.128298 -140.812254) (xy 262.128762 -140.843)
			(xy 262.128307 -140.874359) (xy 262.120597 -140.936601) (xy 262.105296 -140.997424) (xy 262.082634 -141.055905)
			(xy 262.052956 -141.111157) (xy 262.016712 -141.162341) (xy 261.97445 -141.208683) (xy 261.926813 -141.249478)
			(xy 261.900924 -141.26718) (xy 261.89559 -141.271244) (xy 261.872369 -141.291009) (xy 261.82202 -141.325414)
			(xy 261.767916 -141.353549) (xy 261.710836 -141.37501) (xy 261.651599 -141.38949) (xy 261.591055 -141.39678)
			(xy 261.560564 -141.397228) (xy 261.529833 -141.396778) (xy 261.468819 -141.389366) (xy 261.409144 -141.374654)
			(xy 261.351677 -141.352857) (xy 261.297256 -141.324292) (xy 261.246675 -141.289376) (xy 261.200671 -141.248618)
			(xy 261.159914 -141.202613) (xy 261.125 -141.15203) (xy 261.096437 -141.097608) (xy 261.074641 -141.040141)
			(xy 261.059931 -140.980465) (xy 261.052521 -140.919451) (xy 261.052056 -140.88872) (xy 261.05231 -140.876528)
			(xy 261.052564 -140.866622) (xy 261.04596 -140.848334) (xy 260.98627 -140.781786) (xy 260.968998 -140.77315)
			(xy 260.959092 -140.772388) (xy 260.930779 -140.769587) (xy 260.875388 -140.756602) (xy 260.822536 -140.735541)
			(xy 260.773396 -140.70687) (xy 260.729054 -140.671224) (xy 260.690493 -140.629392) (xy 260.658567 -140.582301)
			(xy 260.633983 -140.530994) (xy 260.617284 -140.476606) (xy 260.608842 -140.420343) (xy 260.608318 -140.391896)
			(xy 255.643077 -140.391896) (xy 255.643188 -140.392238) (xy 255.655173 -140.455066) (xy 255.65919 -140.5189)
			(xy 255.655173 -140.582734) (xy 255.643188 -140.645562) (xy 255.623422 -140.706391) (xy 255.596187 -140.764264)
			(xy 255.561914 -140.818266) (xy 255.533205 -140.852967) (xy 257.672852 -140.852967) (xy 257.672852 -140.798433)
			(xy 257.680613 -140.744454) (xy 257.695977 -140.692129) (xy 257.718631 -140.642522) (xy 257.748114 -140.596645)
			(xy 257.783826 -140.555431) (xy 257.82504 -140.519718) (xy 257.870917 -140.490234) (xy 257.920523 -140.467579)
			(xy 257.972848 -140.452215) (xy 258.026827 -140.444453) (xy 258.054094 -140.443966) (xy 258.080664 -140.444414)
			(xy 258.133291 -140.451783) (xy 258.184387 -140.466381) (xy 258.232964 -140.487924) (xy 258.278084 -140.515997)
			(xy 258.318874 -140.550056) (xy 258.33705 -140.569442) (xy 258.346979 -140.5796) (xy 258.371105 -140.594562)
			(xy 258.398419 -140.602298) (xy 258.426807 -140.60221) (xy 258.454073 -140.594305) (xy 258.478106 -140.579194)
			(xy 258.487926 -140.568934) (xy 258.508636 -140.546468) (xy 258.554548 -140.506146) (xy 258.604961 -140.471616)
			(xy 258.659147 -140.443375) (xy 258.716328 -140.42183) (xy 258.775678 -140.407291) (xy 258.836342 -140.399969)
			(xy 258.866894 -140.399516) (xy 258.898871 -140.400041) (xy 258.962321 -140.408056) (xy 259.024267 -140.42396)
			(xy 259.08373 -140.447503) (xy 259.139774 -140.478313) (xy 259.191514 -140.515904) (xy 259.238135 -140.559683)
			(xy 259.278901 -140.60896) (xy 259.31317 -140.662959) (xy 259.340401 -140.720826) (xy 259.360164 -140.78165)
			(xy 259.372148 -140.844472) (xy 259.376164 -140.9083) (xy 259.374153 -140.940255) (xy 259.628634 -140.940255)
			(xy 259.628634 -140.876301) (xy 259.636649 -140.812851) (xy 259.652554 -140.750906) (xy 259.676097 -140.691444)
			(xy 259.706907 -140.6354) (xy 259.744499 -140.58366) (xy 259.788278 -140.53704) (xy 259.837556 -140.496274)
			(xy 259.891554 -140.462006) (xy 259.949421 -140.434775) (xy 260.010245 -140.415012) (xy 260.073066 -140.403029)
			(xy 260.136894 -140.399013) (xy 260.200722 -140.403029) (xy 260.263543 -140.415012) (xy 260.324367 -140.434775)
			(xy 260.382234 -140.462006) (xy 260.436232 -140.496274) (xy 260.48551 -140.53704) (xy 260.529289 -140.58366)
			(xy 260.566881 -140.6354) (xy 260.597691 -140.691444) (xy 260.621234 -140.750906) (xy 260.637139 -140.812851)
			(xy 260.645154 -140.876301) (xy 260.645656 -140.908278) (xy 260.645154 -140.940255) (xy 260.637139 -141.003705)
			(xy 260.621234 -141.06565) (xy 260.597691 -141.125112) (xy 260.566881 -141.181156) (xy 260.529289 -141.232896)
			(xy 260.48551 -141.279516) (xy 260.436232 -141.320282) (xy 260.382234 -141.35455) (xy 260.324367 -141.381781)
			(xy 260.263543 -141.401544) (xy 260.200722 -141.413527) (xy 260.136894 -141.417543) (xy 260.073066 -141.413527)
			(xy 260.010245 -141.401544) (xy 259.949421 -141.381781) (xy 259.891554 -141.35455) (xy 259.837556 -141.320282)
			(xy 259.788278 -141.279516) (xy 259.744499 -141.232896) (xy 259.706907 -141.181156) (xy 259.676097 -141.125112)
			(xy 259.652554 -141.06565) (xy 259.636649 -141.003705) (xy 259.628634 -140.940255) (xy 259.374153 -140.940255)
			(xy 259.372148 -140.972128) (xy 259.360164 -141.03495) (xy 259.340401 -141.095774) (xy 259.31317 -141.153641)
			(xy 259.278901 -141.20764) (xy 259.238135 -141.256917) (xy 259.191514 -141.300696) (xy 259.139774 -141.338287)
			(xy 259.08373 -141.369097) (xy 259.024267 -141.39264) (xy 258.962321 -141.408544) (xy 258.898871 -141.416559)
			(xy 258.866894 -141.41704) (xy 258.833724 -141.416493) (xy 258.767944 -141.407887) (xy 258.703842 -141.390798)
			(xy 258.642509 -141.365514) (xy 258.584986 -141.332466) (xy 258.532251 -141.292216) (xy 258.485201 -141.245448)
			(xy 258.444634 -141.192956) (xy 258.427474 -141.164564) (xy 258.41995 -141.152488) (xy 258.399424 -141.132799)
			(xy 258.374258 -141.119546) (xy 258.34641 -141.113761) (xy 258.318048 -141.115894) (xy 258.291378 -141.125779)
			(xy 258.279646 -141.13383) (xy 258.254951 -141.15118) (xy 258.201236 -141.17869) (xy 258.143868 -141.197423)
			(xy 258.084269 -141.206914) (xy 258.054094 -141.20749) (xy 258.026827 -141.206947) (xy 257.972848 -141.199185)
			(xy 257.920523 -141.183821) (xy 257.870917 -141.161166) (xy 257.82504 -141.131682) (xy 257.783826 -141.095969)
			(xy 257.748114 -141.054755) (xy 257.718631 -141.008878) (xy 257.695977 -140.959271) (xy 257.680613 -140.906946)
			(xy 257.672852 -140.852967) (xy 255.533205 -140.852967) (xy 255.521142 -140.867547) (xy 255.474515 -140.911329)
			(xy 255.422768 -140.948922) (xy 255.366718 -140.979732) (xy 255.307247 -141.003273) (xy 255.245295 -141.019176)
			(xy 255.181838 -141.027187) (xy 255.149858 -141.027658) (xy 255.117057 -141.027149) (xy 255.051998 -141.018719)
			(xy 254.988564 -141.001991) (xy 254.927808 -140.977244) (xy 254.87074 -140.944888) (xy 254.818307 -140.90546)
			(xy 254.794512 -140.882878) (xy 254.788996 -140.877917) (xy 254.775833 -140.871086) (xy 254.768604 -140.869416)
			(xy 254.761746 -140.868146) (xy 254.74676 -140.86967) (xy 254.653542 -140.90904) (xy 254.646365 -140.912424)
			(xy 254.634353 -140.922778) (xy 254.62992 -140.92936) (xy 254.622554 -140.941552) (xy 254.622554 -141.763977)
			(xy 256.77469 -141.763977) (xy 256.77469 -141.700023) (xy 256.782705 -141.636573) (xy 256.79861 -141.574628)
			(xy 256.822153 -141.515166) (xy 256.852963 -141.459122) (xy 256.890555 -141.407382) (xy 256.934334 -141.360762)
			(xy 256.983612 -141.319996) (xy 257.03761 -141.285728) (xy 257.095477 -141.258497) (xy 257.156301 -141.238734)
			(xy 257.219122 -141.226751) (xy 257.28295 -141.222735) (xy 257.346778 -141.226751) (xy 257.409599 -141.238734)
			(xy 257.470423 -141.258497) (xy 257.52829 -141.285728) (xy 257.582288 -141.319996) (xy 257.631566 -141.360762)
			(xy 257.675345 -141.407382) (xy 257.712937 -141.459122) (xy 257.719251 -141.470607) (xy 264.319252 -141.470607)
			(xy 264.319252 -141.406653) (xy 264.327267 -141.343203) (xy 264.343172 -141.281258) (xy 264.366715 -141.221796)
			(xy 264.397525 -141.165752) (xy 264.435117 -141.114012) (xy 264.478896 -141.067392) (xy 264.528174 -141.026626)
			(xy 264.582172 -140.992358) (xy 264.640039 -140.965127) (xy 264.700863 -140.945364) (xy 264.763684 -140.933381)
			(xy 264.827512 -140.929365) (xy 264.89134 -140.933381) (xy 264.954161 -140.945364) (xy 265.014985 -140.965127)
			(xy 265.072852 -140.992358) (xy 265.12685 -141.026626) (xy 265.176128 -141.067392) (xy 265.219907 -141.114012)
			(xy 265.257499 -141.165752) (xy 265.288309 -141.221796) (xy 265.311852 -141.281258) (xy 265.327757 -141.343203)
			(xy 265.335772 -141.406653) (xy 265.336274 -141.43863) (xy 265.335772 -141.470607) (xy 265.327757 -141.534057)
			(xy 265.311852 -141.596002) (xy 265.288309 -141.655464) (xy 265.257499 -141.711508) (xy 265.219907 -141.763248)
			(xy 265.176128 -141.809868) (xy 265.12685 -141.850634) (xy 265.072852 -141.884902) (xy 265.014985 -141.912133)
			(xy 264.954161 -141.931896) (xy 264.89134 -141.943879) (xy 264.827512 -141.947895) (xy 264.763684 -141.943879)
			(xy 264.700863 -141.931896) (xy 264.640039 -141.912133) (xy 264.582172 -141.884902) (xy 264.528174 -141.850634)
			(xy 264.478896 -141.809868) (xy 264.435117 -141.763248) (xy 264.397525 -141.711508) (xy 264.366715 -141.655464)
			(xy 264.343172 -141.596002) (xy 264.327267 -141.534057) (xy 264.319252 -141.470607) (xy 257.719251 -141.470607)
			(xy 257.743747 -141.515166) (xy 257.76729 -141.574628) (xy 257.783195 -141.636573) (xy 257.79121 -141.700023)
			(xy 257.791712 -141.732) (xy 257.79121 -141.763977) (xy 257.783195 -141.827427) (xy 257.76729 -141.889372)
			(xy 257.743747 -141.948834) (xy 257.73281 -141.968728) (xy 258.053076 -141.968728) (xy 258.057147 -141.913106)
			(xy 258.069273 -141.858669) (xy 258.089196 -141.806578) (xy 258.116492 -141.757943) (xy 258.150578 -141.7138)
			(xy 258.190727 -141.675091) (xy 258.236085 -141.64264) (xy 258.285685 -141.617139) (xy 258.338469 -141.599132)
			(xy 258.393312 -141.589002) (xy 258.449046 -141.586965) (xy 258.504483 -141.593065) (xy 258.55844 -141.607171)
			(xy 258.609769 -141.628983) (xy 258.657375 -141.658037) (xy 258.700243 -141.693712) (xy 258.73746 -141.735249)
			(xy 258.768233 -141.781762) (xy 258.791905 -141.832259) (xy 258.807973 -141.885666) (xy 258.816093 -141.940842)
			(xy 258.816602 -141.968728) (xy 259.322822 -141.968728) (xy 259.326895 -141.913069) (xy 259.33903 -141.858596)
			(xy 259.358966 -141.80647) (xy 259.38628 -141.757802) (xy 259.420388 -141.71363) (xy 259.460565 -141.674895)
			(xy 259.505953 -141.642423) (xy 259.555585 -141.616905) (xy 259.608405 -141.598886) (xy 259.663284 -141.588749)
			(xy 259.719055 -141.586711) (xy 259.774529 -141.592814) (xy 259.828522 -141.60693) (xy 259.879885 -141.628757)
			(xy 259.927523 -141.65783) (xy 259.970419 -141.693529) (xy 260.007661 -141.735093) (xy 260.038455 -141.781637)
			(xy 260.062143 -141.832168) (xy 260.078221 -141.88561) (xy 260.086347 -141.940824) (xy 260.086856 -141.968728)
			(xy 260.622794 -141.968728) (xy 260.626867 -141.913069) (xy 260.639002 -141.858596) (xy 260.658938 -141.80647)
			(xy 260.686252 -141.757802) (xy 260.72036 -141.71363) (xy 260.760537 -141.674895) (xy 260.805925 -141.642423)
			(xy 260.855557 -141.616905) (xy 260.908377 -141.598886) (xy 260.963256 -141.588749) (xy 261.019027 -141.586711)
			(xy 261.074501 -141.592814) (xy 261.128494 -141.60693) (xy 261.179857 -141.628757) (xy 261.227495 -141.65783)
			(xy 261.270391 -141.693529) (xy 261.307633 -141.735093) (xy 261.338427 -141.781637) (xy 261.362115 -141.832168)
			(xy 261.378193 -141.88561) (xy 261.386319 -141.940824) (xy 261.386828 -141.968728) (xy 261.386319 -141.996632)
			(xy 261.378193 -142.051846) (xy 261.362115 -142.105288) (xy 261.338427 -142.155819) (xy 261.307633 -142.202363)
			(xy 261.28893 -142.223236) (xy 261.892794 -142.223236) (xy 261.896867 -142.167577) (xy 261.909002 -142.113104)
			(xy 261.928938 -142.060978) (xy 261.956252 -142.01231) (xy 261.99036 -141.968138) (xy 262.030537 -141.929403)
			(xy 262.075925 -141.896931) (xy 262.125557 -141.871413) (xy 262.178377 -141.853394) (xy 262.233256 -141.843257)
			(xy 262.289027 -141.841219) (xy 262.344501 -141.847322) (xy 262.398494 -141.861438) (xy 262.449857 -141.883265)
			(xy 262.497495 -141.912338) (xy 262.540391 -141.948037) (xy 262.577633 -141.989601) (xy 262.608427 -142.036145)
			(xy 262.632115 -142.086676) (xy 262.648193 -142.140118) (xy 262.656319 -142.195332) (xy 262.656828 -142.223236)
			(xy 262.656319 -142.25114) (xy 262.648193 -142.306354) (xy 262.632115 -142.359796) (xy 262.608427 -142.410327)
			(xy 262.577633 -142.456871) (xy 262.540391 -142.498435) (xy 262.497495 -142.534134) (xy 262.449857 -142.563207)
			(xy 262.398494 -142.585034) (xy 262.344501 -142.59915) (xy 262.289027 -142.605253) (xy 262.233256 -142.603215)
			(xy 262.178377 -142.593078) (xy 262.125557 -142.575059) (xy 262.075925 -142.549541) (xy 262.030537 -142.517069)
			(xy 261.99036 -142.478334) (xy 261.956252 -142.434162) (xy 261.928938 -142.385494) (xy 261.909002 -142.333368)
			(xy 261.896867 -142.278895) (xy 261.892794 -142.223236) (xy 261.28893 -142.223236) (xy 261.270391 -142.243927)
			(xy 261.227495 -142.279626) (xy 261.179857 -142.308699) (xy 261.128494 -142.330526) (xy 261.074501 -142.344642)
			(xy 261.019027 -142.350745) (xy 260.963256 -142.348707) (xy 260.908377 -142.33857) (xy 260.855557 -142.320551)
			(xy 260.805925 -142.295033) (xy 260.760537 -142.262561) (xy 260.72036 -142.223826) (xy 260.686252 -142.179654)
			(xy 260.658938 -142.130986) (xy 260.639002 -142.07886) (xy 260.626867 -142.024387) (xy 260.622794 -141.968728)
			(xy 260.086856 -141.968728) (xy 260.086347 -141.996632) (xy 260.078221 -142.051846) (xy 260.062143 -142.105288)
			(xy 260.038455 -142.155819) (xy 260.007661 -142.202363) (xy 259.970419 -142.243927) (xy 259.927523 -142.279626)
			(xy 259.879885 -142.308699) (xy 259.828522 -142.330526) (xy 259.774529 -142.344642) (xy 259.719055 -142.350745)
			(xy 259.663284 -142.348707) (xy 259.608405 -142.33857) (xy 259.555585 -142.320551) (xy 259.505953 -142.295033)
			(xy 259.460565 -142.262561) (xy 259.420388 -142.223826) (xy 259.38628 -142.179654) (xy 259.358966 -142.130986)
			(xy 259.33903 -142.07886) (xy 259.326895 -142.024387) (xy 259.322822 -141.968728) (xy 258.816602 -141.968728)
			(xy 258.816093 -141.996614) (xy 258.807973 -142.05179) (xy 258.791905 -142.105197) (xy 258.768233 -142.155694)
			(xy 258.73746 -142.202207) (xy 258.700243 -142.243744) (xy 258.657375 -142.279419) (xy 258.609769 -142.308473)
			(xy 258.55844 -142.330285) (xy 258.504483 -142.344391) (xy 258.449046 -142.350491) (xy 258.393312 -142.348454)
			(xy 258.338469 -142.338324) (xy 258.285685 -142.320317) (xy 258.236085 -142.294816) (xy 258.190727 -142.262365)
			(xy 258.150578 -142.223656) (xy 258.116492 -142.179513) (xy 258.089196 -142.130878) (xy 258.069273 -142.078787)
			(xy 258.057147 -142.02435) (xy 258.053076 -141.968728) (xy 257.73281 -141.968728) (xy 257.712937 -142.004878)
			(xy 257.675345 -142.056618) (xy 257.631566 -142.103238) (xy 257.582288 -142.144004) (xy 257.52829 -142.178272)
			(xy 257.470423 -142.205503) (xy 257.409599 -142.225266) (xy 257.346778 -142.237249) (xy 257.28295 -142.241265)
			(xy 257.219122 -142.237249) (xy 257.156301 -142.225266) (xy 257.095477 -142.205503) (xy 257.03761 -142.178272)
			(xy 256.983612 -142.144004) (xy 256.934334 -142.103238) (xy 256.890555 -142.056618) (xy 256.852963 -142.004878)
			(xy 256.822153 -141.948834) (xy 256.79861 -141.889372) (xy 256.782705 -141.827427) (xy 256.77469 -141.763977)
			(xy 254.622554 -141.763977) (xy 254.622554 -142.076678) (xy 254.622115 -142.086741) (xy 254.614376 -142.10532)
			(xy 254.607568 -142.112746) (xy 254.522986 -142.197328) (xy 254.516135 -142.204724) (xy 254.508397 -142.223323)
			(xy 254.508 -142.233396) (xy 254.508 -143.061155) (xy 257.55574 -143.061155) (xy 257.55574 -142.997201)
			(xy 257.563755 -142.933751) (xy 257.57966 -142.871806) (xy 257.603203 -142.812344) (xy 257.634013 -142.7563)
			(xy 257.671605 -142.70456) (xy 257.715384 -142.65794) (xy 257.764662 -142.617174) (xy 257.81866 -142.582906)
			(xy 257.876527 -142.555675) (xy 257.937351 -142.535912) (xy 258.000172 -142.523929) (xy 258.064 -142.519913)
			(xy 258.127828 -142.523929) (xy 258.190649 -142.535912) (xy 258.251473 -142.555675) (xy 258.30934 -142.582906)
			(xy 258.363338 -142.617174) (xy 258.412616 -142.65794) (xy 258.456395 -142.70456) (xy 258.493987 -142.7563)
			(xy 258.524797 -142.812344) (xy 258.54834 -142.871806) (xy 258.564245 -142.933751) (xy 258.57226 -142.997201)
			(xy 258.572762 -143.029178) (xy 258.572687 -143.033977) (xy 259.58774 -143.033977) (xy 259.58774 -142.970023)
			(xy 259.595755 -142.906573) (xy 259.61166 -142.844628) (xy 259.635203 -142.785166) (xy 259.666013 -142.729122)
			(xy 259.703605 -142.677382) (xy 259.747384 -142.630762) (xy 259.796662 -142.589996) (xy 259.85066 -142.555728)
			(xy 259.908527 -142.528497) (xy 259.969351 -142.508734) (xy 260.032172 -142.496751) (xy 260.096 -142.492735)
			(xy 260.159828 -142.496751) (xy 260.222649 -142.508734) (xy 260.283473 -142.528497) (xy 260.34134 -142.555728)
			(xy 260.395338 -142.589996) (xy 260.444616 -142.630762) (xy 260.488395 -142.677382) (xy 260.525987 -142.729122)
			(xy 260.556797 -142.785166) (xy 260.58034 -142.844628) (xy 260.596245 -142.906573) (xy 260.60426 -142.970023)
			(xy 260.604762 -143.002) (xy 260.60426 -143.033977) (xy 260.73074 -143.033977) (xy 260.73074 -142.970023)
			(xy 260.738755 -142.906573) (xy 260.75466 -142.844628) (xy 260.778203 -142.785166) (xy 260.809013 -142.729122)
			(xy 260.846605 -142.677382) (xy 260.890384 -142.630762) (xy 260.939662 -142.589996) (xy 260.99366 -142.555728)
			(xy 261.051527 -142.528497) (xy 261.112351 -142.508734) (xy 261.175172 -142.496751) (xy 261.239 -142.492735)
			(xy 261.302828 -142.496751) (xy 261.365649 -142.508734) (xy 261.426473 -142.528497) (xy 261.48434 -142.555728)
			(xy 261.538338 -142.589996) (xy 261.587616 -142.630762) (xy 261.631395 -142.677382) (xy 261.668987 -142.729122)
			(xy 261.699797 -142.785166) (xy 261.72334 -142.844628) (xy 261.739245 -142.906573) (xy 261.74726 -142.970023)
			(xy 261.747762 -143.002) (xy 261.74726 -143.033977) (xy 261.739245 -143.097427) (xy 261.738058 -143.102049)
			(xy 263.580112 -143.102049) (xy 263.580112 -143.038095) (xy 263.588127 -142.974645) (xy 263.604032 -142.9127)
			(xy 263.627575 -142.853238) (xy 263.658385 -142.797194) (xy 263.695977 -142.745454) (xy 263.739756 -142.698834)
			(xy 263.789034 -142.658068) (xy 263.843032 -142.6238) (xy 263.900899 -142.596569) (xy 263.961723 -142.576806)
			(xy 264.024544 -142.564823) (xy 264.088372 -142.560807) (xy 264.1522 -142.564823) (xy 264.215021 -142.576806)
			(xy 264.275845 -142.596569) (xy 264.333712 -142.6238) (xy 264.38771 -142.658068) (xy 264.436988 -142.698834)
			(xy 264.480767 -142.745454) (xy 264.518359 -142.797194) (xy 264.549169 -142.853238) (xy 264.572712 -142.9127)
			(xy 264.588617 -142.974645) (xy 264.596632 -143.038095) (xy 264.597134 -143.070072) (xy 264.596632 -143.102049)
			(xy 264.588617 -143.165499) (xy 264.572712 -143.227444) (xy 264.549169 -143.286906) (xy 264.518359 -143.34295)
			(xy 264.480767 -143.39469) (xy 264.436988 -143.44131) (xy 264.38771 -143.482076) (xy 264.333712 -143.516344)
			(xy 264.275845 -143.543575) (xy 264.215021 -143.563338) (xy 264.1522 -143.575321) (xy 264.088372 -143.579337)
			(xy 264.024544 -143.575321) (xy 263.961723 -143.563338) (xy 263.900899 -143.543575) (xy 263.843032 -143.516344)
			(xy 263.789034 -143.482076) (xy 263.739756 -143.44131) (xy 263.695977 -143.39469) (xy 263.658385 -143.34295)
			(xy 263.627575 -143.286906) (xy 263.604032 -143.227444) (xy 263.588127 -143.165499) (xy 263.580112 -143.102049)
			(xy 261.738058 -143.102049) (xy 261.72334 -143.159372) (xy 261.699797 -143.218834) (xy 261.668987 -143.274878)
			(xy 261.631395 -143.326618) (xy 261.587616 -143.373238) (xy 261.538338 -143.414004) (xy 261.48434 -143.448272)
			(xy 261.426473 -143.475503) (xy 261.365649 -143.495266) (xy 261.302828 -143.507249) (xy 261.239 -143.511265)
			(xy 261.175172 -143.507249) (xy 261.112351 -143.495266) (xy 261.051527 -143.475503) (xy 260.99366 -143.448272)
			(xy 260.939662 -143.414004) (xy 260.890384 -143.373238) (xy 260.846605 -143.326618) (xy 260.809013 -143.274878)
			(xy 260.778203 -143.218834) (xy 260.75466 -143.159372) (xy 260.738755 -143.097427) (xy 260.73074 -143.033977)
			(xy 260.60426 -143.033977) (xy 260.596245 -143.097427) (xy 260.58034 -143.159372) (xy 260.556797 -143.218834)
			(xy 260.525987 -143.274878) (xy 260.488395 -143.326618) (xy 260.444616 -143.373238) (xy 260.395338 -143.414004)
			(xy 260.34134 -143.448272) (xy 260.283473 -143.475503) (xy 260.222649 -143.495266) (xy 260.159828 -143.507249)
			(xy 260.096 -143.511265) (xy 260.032172 -143.507249) (xy 259.969351 -143.495266) (xy 259.908527 -143.475503)
			(xy 259.85066 -143.448272) (xy 259.796662 -143.414004) (xy 259.747384 -143.373238) (xy 259.703605 -143.326618)
			(xy 259.666013 -143.274878) (xy 259.635203 -143.218834) (xy 259.61166 -143.159372) (xy 259.595755 -143.097427)
			(xy 259.58774 -143.033977) (xy 258.572687 -143.033977) (xy 258.57226 -143.061155) (xy 258.564245 -143.124605)
			(xy 258.54834 -143.18655) (xy 258.524797 -143.246012) (xy 258.493987 -143.302056) (xy 258.456395 -143.353796)
			(xy 258.412616 -143.400416) (xy 258.363338 -143.441182) (xy 258.30934 -143.47545) (xy 258.251473 -143.502681)
			(xy 258.190649 -143.522444) (xy 258.127828 -143.534427) (xy 258.064 -143.538443) (xy 258.000172 -143.534427)
			(xy 257.937351 -143.522444) (xy 257.876527 -143.502681) (xy 257.81866 -143.47545) (xy 257.764662 -143.441182)
			(xy 257.715384 -143.400416) (xy 257.671605 -143.353796) (xy 257.634013 -143.302056) (xy 257.603203 -143.246012)
			(xy 257.57966 -143.18655) (xy 257.563755 -143.124605) (xy 257.55574 -143.061155) (xy 254.508 -143.061155)
			(xy 254.508 -143.234918) (xy 254.508427 -143.244987) (xy 254.516146 -143.263586) (xy 254.522986 -143.270986)
			(xy 255.676119 -144.424119) (xy 256.438648 -144.424119) (xy 256.438648 -144.360165) (xy 256.446663 -144.296715)
			(xy 256.462568 -144.23477) (xy 256.486111 -144.175308) (xy 256.516921 -144.119264) (xy 256.554513 -144.067524)
			(xy 256.598292 -144.020904) (xy 256.64757 -143.980138) (xy 256.701568 -143.94587) (xy 256.759435 -143.918639)
			(xy 256.820259 -143.898876) (xy 256.88308 -143.886893) (xy 256.946908 -143.882877) (xy 257.010736 -143.886893)
			(xy 257.073557 -143.898876) (xy 257.134381 -143.918639) (xy 257.192248 -143.94587) (xy 257.246246 -143.980138)
			(xy 257.295524 -144.020904) (xy 257.339303 -144.067524) (xy 257.376895 -144.119264) (xy 257.407705 -144.175308)
			(xy 257.431248 -144.23477) (xy 257.447153 -144.296715) (xy 257.455168 -144.360165) (xy 257.45567 -144.392142)
			(xy 257.455168 -144.424119) (xy 257.447153 -144.487569) (xy 257.431248 -144.549514) (xy 257.407705 -144.608976)
			(xy 257.376895 -144.66502) (xy 257.339303 -144.71676) (xy 257.295524 -144.76338) (xy 257.246246 -144.804146)
			(xy 257.192248 -144.838414) (xy 257.134381 -144.865645) (xy 257.073557 -144.885408) (xy 257.010736 -144.897391)
			(xy 256.946908 -144.901407) (xy 256.88308 -144.897391) (xy 256.820259 -144.885408) (xy 256.759435 -144.865645)
			(xy 256.701568 -144.838414) (xy 256.64757 -144.804146) (xy 256.598292 -144.76338) (xy 256.554513 -144.71676)
			(xy 256.516921 -144.66502) (xy 256.486111 -144.608976) (xy 256.462568 -144.549514) (xy 256.446663 -144.487569)
			(xy 256.438648 -144.424119) (xy 255.676119 -144.424119) (xy 256.398014 -145.146014) (xy 256.405409 -145.152868)
			(xy 256.424008 -145.16061) (xy 256.434082 -145.161) (xy 258.353814 -145.161) (xy 258.383278 -145.13179)
			(xy 258.383532 -145.110708) (xy 258.384344 -145.079564) (xy 258.392629 -145.017815) (xy 258.40839 -144.95754)
			(xy 258.431392 -144.899639) (xy 258.46129 -144.84498) (xy 258.497637 -144.794379) (xy 258.53989 -144.748595)
			(xy 258.587416 -144.708311) (xy 258.639505 -144.67413) (xy 258.695377 -144.646564) (xy 258.754196 -144.626025)
			(xy 258.815083 -144.61282) (xy 258.846066 -144.609566) (xy 258.859639 -144.60789) (xy 258.88523 -144.598275)
			(xy 258.907347 -144.582207) (xy 258.924399 -144.560839) (xy 258.93516 -144.535708) (xy 258.938858 -144.508622)
			(xy 258.937506 -144.495012) (xy 258.935461 -144.478324) (xy 258.933297 -144.444769) (xy 258.933188 -144.427956)
			(xy 258.93369 -144.395979) (xy 258.941705 -144.332529) (xy 258.95761 -144.270584) (xy 258.981153 -144.211122)
			(xy 259.011963 -144.155078) (xy 259.049555 -144.103338) (xy 259.093334 -144.056718) (xy 259.142612 -144.015952)
			(xy 259.19661 -143.981684) (xy 259.254477 -143.954453) (xy 259.315301 -143.93469) (xy 259.378122 -143.922707)
			(xy 259.44195 -143.918691) (xy 259.505778 -143.922707) (xy 259.568599 -143.93469) (xy 259.629423 -143.954453)
			(xy 259.68729 -143.981684) (xy 259.741288 -144.015952) (xy 259.790566 -144.056718) (xy 259.834345 -144.103338)
			(xy 259.871937 -144.155078) (xy 259.872247 -144.155641) (xy 262.232388 -144.155641) (xy 262.232388 -144.091687)
			(xy 262.240403 -144.028237) (xy 262.256308 -143.966292) (xy 262.279851 -143.90683) (xy 262.310661 -143.850786)
			(xy 262.348253 -143.799046) (xy 262.392032 -143.752426) (xy 262.44131 -143.71166) (xy 262.495308 -143.677392)
			(xy 262.553175 -143.650161) (xy 262.613999 -143.630398) (xy 262.67682 -143.618415) (xy 262.740648 -143.614399)
			(xy 262.804476 -143.618415) (xy 262.867297 -143.630398) (xy 262.928121 -143.650161) (xy 262.985988 -143.677392)
			(xy 263.039986 -143.71166) (xy 263.089264 -143.752426) (xy 263.133043 -143.799046) (xy 263.170635 -143.850786)
			(xy 263.201445 -143.90683) (xy 263.224988 -143.966292) (xy 263.240893 -144.028237) (xy 263.248908 -144.091687)
			(xy 263.24941 -144.123664) (xy 263.248908 -144.155641) (xy 263.240893 -144.219091) (xy 263.224988 -144.281036)
			(xy 263.201445 -144.340498) (xy 263.170635 -144.396542) (xy 263.133043 -144.448282) (xy 263.089264 -144.494902)
			(xy 263.039986 -144.535668) (xy 262.985988 -144.569936) (xy 262.928121 -144.597167) (xy 262.867297 -144.61693)
			(xy 262.804476 -144.628913) (xy 262.740648 -144.632929) (xy 262.67682 -144.628913) (xy 262.613999 -144.61693)
			(xy 262.553175 -144.597167) (xy 262.495308 -144.569936) (xy 262.44131 -144.535668) (xy 262.392032 -144.494902)
			(xy 262.348253 -144.448282) (xy 262.310661 -144.396542) (xy 262.279851 -144.340498) (xy 262.256308 -144.281036)
			(xy 262.240403 -144.219091) (xy 262.232388 -144.155641) (xy 259.872247 -144.155641) (xy 259.902747 -144.211122)
			(xy 259.92629 -144.270584) (xy 259.942195 -144.332529) (xy 259.95021 -144.395979) (xy 259.950712 -144.427956)
			(xy 259.950244 -144.459338) (xy 259.942519 -144.521624) (xy 259.927193 -144.582488) (xy 259.904498 -144.641005)
			(xy 259.87478 -144.696287) (xy 259.838489 -144.747495) (xy 259.796177 -144.793852) (xy 259.748485 -144.834653)
			(xy 259.696137 -144.86928) (xy 259.639929 -144.897207) (xy 259.580712 -144.918009) (xy 259.519388 -144.931372)
			(xy 259.488178 -144.934686) (xy 259.474604 -144.936358) (xy 259.44901 -144.945967) (xy 259.426891 -144.962035)
			(xy 259.40984 -144.983405) (xy 259.399084 -145.008539) (xy 259.395398 -145.035628) (xy 259.396738 -145.04924)
			(xy 259.398632 -145.064539) (xy 259.400791 -145.095294) (xy 259.401056 -145.110708) (xy 259.40131 -145.13179)
			(xy 259.430774 -145.161) (xy 280.48331 -145.161) (xy 280.493379 -145.161425) (xy 280.511981 -145.169142)
			(xy 280.519378 -145.175986) (xy 286.56788 -151.224488) (xy 286.568388 -151.224996) (xy 286.575773 -151.231568)
			(xy 286.594072 -151.239) (xy 286.603948 -151.239474)
		)
		(stroke
			(width 0)
			(type solid)
		)
		(fill yes)
		(layer "In11.Cu")
		(net "PVDD18_S5_P0")
	)
	(gr_poly
		(pts
			(xy 336.259678 -159.27324) (xy 336.269741 -159.272801) (xy 336.288319 -159.26506) (xy 336.295746 -159.258254)
			(xy 343.924382 -151.629618) (xy 343.931217 -151.622216) (xy 343.938925 -151.603617) (xy 343.939368 -151.59355)
			(xy 343.939368 -146.51482) (xy 343.939874 -146.504769) (xy 343.947594 -146.486208) (xy 343.954354 -146.478752)
			(xy 346.3671 -144.066006) (xy 346.374498 -144.059159) (xy 346.393096 -144.051423) (xy 346.403168 -144.05102)
			(xy 355.245416 -144.05102) (xy 355.253798 -144.050258) (xy 355.261404 -144.048746) (xy 355.275244 -144.041765)
			(xy 355.280976 -144.036542) (xy 363.27715 -136.040368) (xy 363.284478 -136.032297) (xy 363.292101 -136.011898)
			(xy 363.291882 -136.000998) (xy 363.28604 -135.913622) (xy 363.27588 -135.894572) (xy 363.26699 -135.887714)
			(xy 363.240783 -135.867037) (xy 363.193487 -135.819927) (xy 363.152761 -135.767035) (xy 363.119303 -135.70927)
			(xy 363.09369 -135.647624) (xy 363.076362 -135.583157) (xy 363.067616 -135.516977) (xy 363.067092 -135.4836)
			(xy 363.067556 -135.452869) (xy 363.074965 -135.391855) (xy 363.089673 -135.332179) (xy 363.111468 -135.274711)
			(xy 363.140031 -135.220289) (xy 363.174945 -135.169707) (xy 363.215702 -135.123702) (xy 363.261707 -135.082945)
			(xy 363.312289 -135.048031) (xy 363.366711 -135.019468) (xy 363.424179 -134.997673) (xy 363.483855 -134.982965)
			(xy 363.544869 -134.975556) (xy 363.5756 -134.975092) (xy 363.606827 -134.975567) (xy 363.66881 -134.983213)
			(xy 363.729392 -134.998389) (xy 363.78766 -135.020867) (xy 363.842737 -135.05031) (xy 363.893797 -135.086274)
			(xy 363.91723 -135.106918) (xy 363.924342 -135.113268) (xy 363.941614 -135.119872) (xy 364.013496 -135.119872)
			(xy 364.025631 -135.119248) (xy 364.04725 -135.108234) (xy 364.054898 -135.09879) (xy 364.11027 -135.021828)
			(xy 364.113826 -134.997698) (xy 364.109762 -134.986014) (xy 364.101277 -134.95972) (xy 364.0894 -134.905759)
			(xy 364.083448 -134.850827) (xy 364.083092 -134.8232) (xy 364.083556 -134.792469) (xy 364.090965 -134.731455)
			(xy 364.105673 -134.671779) (xy 364.127468 -134.614311) (xy 364.156031 -134.559889) (xy 364.190945 -134.509307)
			(xy 364.231702 -134.463302) (xy 364.277707 -134.422545) (xy 364.328289 -134.387631) (xy 364.382711 -134.359068)
			(xy 364.440179 -134.337273) (xy 364.499855 -134.322565) (xy 364.560869 -134.315156) (xy 364.5916 -134.314692)
			(xy 364.620579 -134.315106) (xy 364.678162 -134.321697) (xy 364.734625 -134.334782) (xy 364.789237 -134.354193)
			(xy 364.841292 -134.379677) (xy 364.86592 -134.394956) (xy 364.88116 -134.404862) (xy 364.916466 -134.401052)
			(xy 368.658394 -130.659124) (xy 368.665791 -130.652274) (xy 368.684389 -130.644534) (xy 368.694462 -130.644138)
			(xy 397.368268 -130.644138) (xy 397.37665 -130.643376) (xy 397.384258 -130.641867) (xy 397.398099 -130.634888)
			(xy 397.403828 -130.62966) (xy 397.426942 -130.606546) (xy 397.434341 -130.599701) (xy 397.452939 -130.591975)
			(xy 397.46301 -130.59156) (xy 398.311624 -130.59156) (xy 398.320006 -130.590798) (xy 398.32761 -130.589282)
			(xy 398.341443 -130.582294) (xy 398.347184 -130.577082) (xy 400.414744 -128.509522) (xy 400.421427 -128.502112)
			(xy 400.42901 -128.483676) (xy 400.429476 -128.473708) (xy 400.429476 -60.46343) (xy 400.42961 -60.453941)
			(xy 400.430879 -60.435005) (xy 400.432016 -60.425584) (xy 400.433741 -60.412579) (xy 400.439081 -60.386891)
			(xy 400.442684 -60.374276) (xy 400.444716 -60.367164) (xy 400.444716 -60.329826) (xy 400.445153 -60.319762)
			(xy 400.452888 -60.301179) (xy 400.459702 -60.293758) (xy 406.367234 -54.386226) (xy 406.374633 -54.379382)
			(xy 406.393231 -54.371656) (xy 406.403302 -54.37124) (xy 412.535878 -54.37124) (xy 412.54426 -54.370478)
			(xy 412.551867 -54.368968) (xy 412.565707 -54.361987) (xy 412.571438 -54.356762) (xy 422.275254 -44.652946)
			(xy 422.282097 -44.645547) (xy 422.289819 -44.626948) (xy 422.29024 -44.616878) (xy 422.29024 -36.068762)
			(xy 422.290671 -36.058696) (xy 422.2984 -36.040105) (xy 422.305226 -36.032694) (xy 424.121834 -34.216086)
			(xy 424.12923 -34.209235) (xy 424.147829 -34.2015) (xy 424.157902 -34.2011) (xy 425.759118 -34.2011)
			(xy 425.769187 -34.201527) (xy 425.787786 -34.209246) (xy 425.795186 -34.216086) (xy 426.348609 -34.769509)
			(xy 427.462944 -34.769509) (xy 427.462944 -34.705587) (xy 427.470955 -34.642169) (xy 427.486852 -34.580255)
			(xy 427.510384 -34.520822) (xy 427.541178 -34.464807) (xy 427.578751 -34.413092) (xy 427.622508 -34.366495)
			(xy 427.671761 -34.32575) (xy 427.725732 -34.291499) (xy 427.783571 -34.264282) (xy 427.844364 -34.244529)
			(xy 427.907154 -34.232551) (xy 427.97095 -34.228538) (xy 428.034746 -34.232551) (xy 428.097536 -34.244529)
			(xy 428.158329 -34.264282) (xy 428.216168 -34.291499) (xy 428.270139 -34.32575) (xy 428.319392 -34.366495)
			(xy 428.363149 -34.413092) (xy 428.400722 -34.464807) (xy 428.431516 -34.520822) (xy 428.455048 -34.580255)
			(xy 428.470945 -34.642169) (xy 428.478956 -34.705587) (xy 428.479458 -34.737548) (xy 428.478956 -34.769509)
			(xy 428.470945 -34.832927) (xy 428.455048 -34.894841) (xy 428.431516 -34.954274) (xy 428.400722 -35.010289)
			(xy 428.363149 -35.062004) (xy 428.319392 -35.108601) (xy 428.270139 -35.149346) (xy 428.216168 -35.183597)
			(xy 428.158329 -35.210814) (xy 428.097536 -35.230567) (xy 428.034746 -35.242545) (xy 427.97095 -35.246559)
			(xy 427.907154 -35.242545) (xy 427.844364 -35.230567) (xy 427.783571 -35.210814) (xy 427.725732 -35.183597)
			(xy 427.671761 -35.149346) (xy 427.622508 -35.108601) (xy 427.578751 -35.062004) (xy 427.541178 -35.010289)
			(xy 427.510384 -34.954274) (xy 427.486852 -34.894841) (xy 427.470955 -34.832927) (xy 427.462944 -34.769509)
			(xy 426.348609 -34.769509) (xy 426.402754 -34.823654) (xy 426.409597 -34.831053) (xy 426.417319 -34.849652)
			(xy 426.41774 -34.859722) (xy 426.41774 -36.039509) (xy 427.462944 -36.039509) (xy 427.462944 -35.975587)
			(xy 427.470955 -35.912169) (xy 427.486852 -35.850255) (xy 427.510384 -35.790822) (xy 427.541178 -35.734807)
			(xy 427.578751 -35.683092) (xy 427.622508 -35.636495) (xy 427.671761 -35.59575) (xy 427.725732 -35.561499)
			(xy 427.783571 -35.534282) (xy 427.844364 -35.514529) (xy 427.907154 -35.502551) (xy 427.97095 -35.498538)
			(xy 428.034746 -35.502551) (xy 428.097536 -35.514529) (xy 428.158329 -35.534282) (xy 428.216168 -35.561499)
			(xy 428.270139 -35.59575) (xy 428.319392 -35.636495) (xy 428.363149 -35.683092) (xy 428.400722 -35.734807)
			(xy 428.431516 -35.790822) (xy 428.455048 -35.850255) (xy 428.470945 -35.912169) (xy 428.478956 -35.975587)
			(xy 428.479458 -36.007548) (xy 428.478956 -36.039509) (xy 428.470945 -36.102927) (xy 428.455048 -36.164841)
			(xy 428.431516 -36.224274) (xy 428.400722 -36.280289) (xy 428.363149 -36.332004) (xy 428.319392 -36.378601)
			(xy 428.270139 -36.419346) (xy 428.216168 -36.453597) (xy 428.158329 -36.480814) (xy 428.097536 -36.500567)
			(xy 428.034746 -36.512545) (xy 427.97095 -36.516559) (xy 427.907154 -36.512545) (xy 427.844364 -36.500567)
			(xy 427.783571 -36.480814) (xy 427.725732 -36.453597) (xy 427.671761 -36.419346) (xy 427.622508 -36.378601)
			(xy 427.578751 -36.332004) (xy 427.541178 -36.280289) (xy 427.510384 -36.224274) (xy 427.486852 -36.164841)
			(xy 427.470955 -36.102927) (xy 427.462944 -36.039509) (xy 426.41774 -36.039509) (xy 426.41774 -36.829238)
			(xy 426.418171 -36.839304) (xy 426.4259 -36.857895) (xy 426.432726 -36.865306) (xy 426.941234 -37.373814)
			(xy 426.94863 -37.380665) (xy 426.967229 -37.3884) (xy 426.977302 -37.3888) (xy 429.183038 -37.3888)
			(xy 429.19142 -37.388038) (xy 429.199024 -37.386522) (xy 429.212858 -37.379535) (xy 429.218598 -37.374322)
			(xy 429.491394 -37.101526) (xy 429.498229 -37.094124) (xy 429.505938 -37.075525) (xy 429.50638 -37.065458)
			(xy 429.50638 -29.815282) (xy 429.49876 -29.796486) (xy 429.491394 -29.789374) (xy 428.378366 -28.676346)
			(xy 428.370968 -28.6695) (xy 428.352369 -28.661771) (xy 428.342298 -28.66136) (xy 424.617642 -28.66136)
			(xy 424.598846 -28.66898) (xy 424.591734 -28.676346) (xy 422.308571 -30.959509) (xy 424.459394 -30.959509)
			(xy 424.459394 -30.895587) (xy 424.467405 -30.832169) (xy 424.483302 -30.770255) (xy 424.506834 -30.710822)
			(xy 424.537628 -30.654807) (xy 424.575201 -30.603092) (xy 424.618958 -30.556495) (xy 424.668211 -30.51575)
			(xy 424.722182 -30.481499) (xy 424.780021 -30.454282) (xy 424.840814 -30.434529) (xy 424.903604 -30.422551)
			(xy 424.9674 -30.418538) (xy 425.031196 -30.422551) (xy 425.093986 -30.434529) (xy 425.154779 -30.454282)
			(xy 425.212618 -30.481499) (xy 425.266589 -30.51575) (xy 425.315842 -30.556495) (xy 425.359599 -30.603092)
			(xy 425.397172 -30.654807) (xy 425.407475 -30.673548) (xy 427.043342 -30.673548) (xy 427.043883 -30.641381)
			(xy 427.052004 -30.577561) (xy 427.06811 -30.515275) (xy 427.091944 -30.455519) (xy 427.123124 -30.399245)
			(xy 427.161154 -30.347354) (xy 427.205424 -30.300674) (xy 427.255229 -30.259951) (xy 427.309773 -30.225835)
			(xy 427.368184 -30.198871) (xy 427.42953 -30.17949) (xy 427.49283 -30.168001) (xy 427.524926 -30.165802)
			(xy 427.533621 -30.16494) (xy 427.549727 -30.158206) (xy 427.556422 -30.152594) (xy 427.57852 -30.132782)
			(xy 427.584633 -30.126772) (xy 427.592815 -30.111719) (xy 427.594522 -30.103318) (xy 427.59939 -30.076909)
			(xy 427.615496 -30.025682) (xy 427.638625 -29.97722) (xy 427.668321 -29.932479) (xy 427.703996 -29.892343)
			(xy 427.744946 -29.857606) (xy 427.790362 -29.828954) (xy 427.839347 -29.806953) (xy 427.890933 -29.792037)
			(xy 427.944101 -29.784501) (xy 427.97095 -29.78404) (xy 427.998204 -29.784502) (xy 428.052157 -29.792253)
			(xy 428.104458 -29.807605) (xy 428.154041 -29.830246) (xy 428.199897 -29.859713) (xy 428.241091 -29.895407)
			(xy 428.276786 -29.936601) (xy 428.306253 -29.982457) (xy 428.328894 -30.03204) (xy 428.344246 -30.084341)
			(xy 428.351998 -30.138294) (xy 428.352458 -30.165548) (xy 428.351924 -30.194552) (xy 428.343157 -30.251893)
			(xy 428.325803 -30.307243) (xy 428.300262 -30.359325) (xy 428.267125 -30.406935) (xy 428.227156 -30.448975)
			(xy 428.181278 -30.484472) (xy 428.130552 -30.512609) (xy 428.103538 -30.52318) (xy 428.095679 -30.526495)
			(xy 428.082566 -30.537387) (xy 428.077884 -30.544516) (xy 428.06239 -30.57017) (xy 428.058213 -30.577788)
			(xy 428.054709 -30.594795) (xy 428.055532 -30.603444) (xy 428.057799 -30.620881) (xy 428.060216 -30.655965)
			(xy 428.060358 -30.673548) (xy 428.059856 -30.705509) (xy 428.051845 -30.768927) (xy 428.035948 -30.830841)
			(xy 428.012416 -30.890274) (xy 427.981622 -30.946289) (xy 427.944049 -30.998004) (xy 427.900292 -31.044601)
			(xy 427.851039 -31.085346) (xy 427.797068 -31.119597) (xy 427.739229 -31.146814) (xy 427.678436 -31.166567)
			(xy 427.615646 -31.178545) (xy 427.55185 -31.182559) (xy 427.488054 -31.178545) (xy 427.425264 -31.166567)
			(xy 427.364471 -31.146814) (xy 427.306632 -31.119597) (xy 427.252661 -31.085346) (xy 427.203408 -31.044601)
			(xy 427.159651 -30.998004) (xy 427.122078 -30.946289) (xy 427.091284 -30.890274) (xy 427.067752 -30.830841)
			(xy 427.051855 -30.768927) (xy 427.043844 -30.705509) (xy 427.043342 -30.673548) (xy 425.407475 -30.673548)
			(xy 425.427966 -30.710822) (xy 425.451498 -30.770255) (xy 425.467395 -30.832169) (xy 425.475406 -30.895587)
			(xy 425.475908 -30.927548) (xy 425.475406 -30.959509) (xy 425.467395 -31.022927) (xy 425.451498 -31.084841)
			(xy 425.427966 -31.144274) (xy 425.397172 -31.200289) (xy 425.359599 -31.252004) (xy 425.315842 -31.298601)
			(xy 425.266589 -31.339346) (xy 425.212618 -31.373597) (xy 425.154779 -31.400814) (xy 425.093986 -31.420567)
			(xy 425.031196 -31.432545) (xy 424.9674 -31.436559) (xy 424.903604 -31.432545) (xy 424.840814 -31.420567)
			(xy 424.780021 -31.400814) (xy 424.722182 -31.373597) (xy 424.668211 -31.339346) (xy 424.618958 -31.298601)
			(xy 424.575201 -31.252004) (xy 424.537628 -31.200289) (xy 424.506834 -31.144274) (xy 424.483302 -31.084841)
			(xy 424.467405 -31.022927) (xy 424.459394 -30.959509) (xy 422.308571 -30.959509) (xy 421.070532 -32.197548)
			(xy 424.585382 -32.197548) (xy 424.589453 -32.141926) (xy 424.601579 -32.087489) (xy 424.621502 -32.035398)
			(xy 424.648798 -31.986763) (xy 424.682884 -31.94262) (xy 424.723033 -31.903911) (xy 424.768391 -31.87146)
			(xy 424.817991 -31.845959) (xy 424.870775 -31.827952) (xy 424.925618 -31.817822) (xy 424.981352 -31.815785)
			(xy 425.036789 -31.821885) (xy 425.090746 -31.835991) (xy 425.142075 -31.857803) (xy 425.189681 -31.886857)
			(xy 425.232549 -31.922532) (xy 425.269766 -31.964069) (xy 425.300539 -32.010582) (xy 425.324211 -32.061079)
			(xy 425.340279 -32.114486) (xy 425.348399 -32.169662) (xy 425.348908 -32.197548) (xy 425.348399 -32.225434)
			(xy 425.347799 -32.229509) (xy 427.462944 -32.229509) (xy 427.462944 -32.165587) (xy 427.470955 -32.102169)
			(xy 427.486852 -32.040255) (xy 427.510384 -31.980822) (xy 427.541178 -31.924807) (xy 427.578751 -31.873092)
			(xy 427.622508 -31.826495) (xy 427.671761 -31.78575) (xy 427.725732 -31.751499) (xy 427.783571 -31.724282)
			(xy 427.844364 -31.704529) (xy 427.907154 -31.692551) (xy 427.97095 -31.688538) (xy 428.034746 -31.692551)
			(xy 428.097536 -31.704529) (xy 428.158329 -31.724282) (xy 428.216168 -31.751499) (xy 428.270139 -31.78575)
			(xy 428.319392 -31.826495) (xy 428.363149 -31.873092) (xy 428.400722 -31.924807) (xy 428.431516 -31.980822)
			(xy 428.455048 -32.040255) (xy 428.470945 -32.102169) (xy 428.478956 -32.165587) (xy 428.479458 -32.197548)
			(xy 428.478956 -32.229509) (xy 428.470945 -32.292927) (xy 428.455048 -32.354841) (xy 428.431516 -32.414274)
			(xy 428.400722 -32.470289) (xy 428.363149 -32.522004) (xy 428.319392 -32.568601) (xy 428.270139 -32.609346)
			(xy 428.216168 -32.643597) (xy 428.158329 -32.670814) (xy 428.097536 -32.690567) (xy 428.034746 -32.702545)
			(xy 427.97095 -32.706559) (xy 427.907154 -32.702545) (xy 427.844364 -32.690567) (xy 427.783571 -32.670814)
			(xy 427.725732 -32.643597) (xy 427.671761 -32.609346) (xy 427.622508 -32.568601) (xy 427.578751 -32.522004)
			(xy 427.541178 -32.470289) (xy 427.510384 -32.414274) (xy 427.486852 -32.354841) (xy 427.470955 -32.292927)
			(xy 427.462944 -32.229509) (xy 425.347799 -32.229509) (xy 425.340279 -32.28061) (xy 425.324211 -32.334017)
			(xy 425.300539 -32.384514) (xy 425.269766 -32.431027) (xy 425.232549 -32.472564) (xy 425.189681 -32.508239)
			(xy 425.142075 -32.537293) (xy 425.090746 -32.559105) (xy 425.036789 -32.573211) (xy 424.981352 -32.579311)
			(xy 424.925618 -32.577274) (xy 424.870775 -32.567144) (xy 424.817991 -32.549137) (xy 424.768391 -32.523636)
			(xy 424.723033 -32.491185) (xy 424.682884 -32.452476) (xy 424.648798 -32.408333) (xy 424.621502 -32.359698)
			(xy 424.601579 -32.307607) (xy 424.589453 -32.25317) (xy 424.585382 -32.197548) (xy 421.070532 -32.197548)
			(xy 420.612316 -32.655764) (xy 420.610792 -32.657034) (xy 419.862947 -33.499509) (xy 424.459394 -33.499509)
			(xy 424.459394 -33.435587) (xy 424.467405 -33.372169) (xy 424.483302 -33.310255) (xy 424.506834 -33.250822)
			(xy 424.537628 -33.194807) (xy 424.575201 -33.143092) (xy 424.618958 -33.096495) (xy 424.668211 -33.05575)
			(xy 424.722182 -33.021499) (xy 424.780021 -32.994282) (xy 424.840814 -32.974529) (xy 424.903604 -32.962551)
			(xy 424.9674 -32.958538) (xy 425.031196 -32.962551) (xy 425.093986 -32.974529) (xy 425.154779 -32.994282)
			(xy 425.212618 -33.021499) (xy 425.266589 -33.05575) (xy 425.315842 -33.096495) (xy 425.359599 -33.143092)
			(xy 425.397172 -33.194807) (xy 425.427966 -33.250822) (xy 425.451498 -33.310255) (xy 425.467395 -33.372169)
			(xy 425.475406 -33.435587) (xy 425.475908 -33.467548) (xy 425.475406 -33.499509) (xy 427.462944 -33.499509)
			(xy 427.462944 -33.435587) (xy 427.470955 -33.372169) (xy 427.486852 -33.310255) (xy 427.510384 -33.250822)
			(xy 427.541178 -33.194807) (xy 427.578751 -33.143092) (xy 427.622508 -33.096495) (xy 427.671761 -33.05575)
			(xy 427.725732 -33.021499) (xy 427.783571 -32.994282) (xy 427.844364 -32.974529) (xy 427.907154 -32.962551)
			(xy 427.97095 -32.958538) (xy 428.034746 -32.962551) (xy 428.097536 -32.974529) (xy 428.158329 -32.994282)
			(xy 428.216168 -33.021499) (xy 428.270139 -33.05575) (xy 428.319392 -33.096495) (xy 428.363149 -33.143092)
			(xy 428.400722 -33.194807) (xy 428.431516 -33.250822) (xy 428.455048 -33.310255) (xy 428.470945 -33.372169)
			(xy 428.478956 -33.435587) (xy 428.479458 -33.467548) (xy 428.478956 -33.499509) (xy 428.470945 -33.562927)
			(xy 428.455048 -33.624841) (xy 428.431516 -33.684274) (xy 428.400722 -33.740289) (xy 428.363149 -33.792004)
			(xy 428.319392 -33.838601) (xy 428.270139 -33.879346) (xy 428.216168 -33.913597) (xy 428.158329 -33.940814)
			(xy 428.097536 -33.960567) (xy 428.034746 -33.972545) (xy 427.97095 -33.976559) (xy 427.907154 -33.972545)
			(xy 427.844364 -33.960567) (xy 427.783571 -33.940814) (xy 427.725732 -33.913597) (xy 427.671761 -33.879346)
			(xy 427.622508 -33.838601) (xy 427.578751 -33.792004) (xy 427.541178 -33.740289) (xy 427.510384 -33.684274)
			(xy 427.486852 -33.624841) (xy 427.470955 -33.562927) (xy 427.462944 -33.499509) (xy 425.475406 -33.499509)
			(xy 425.467395 -33.562927) (xy 425.451498 -33.624841) (xy 425.427966 -33.684274) (xy 425.397172 -33.740289)
			(xy 425.359599 -33.792004) (xy 425.315842 -33.838601) (xy 425.266589 -33.879346) (xy 425.212618 -33.913597)
			(xy 425.154779 -33.940814) (xy 425.093986 -33.960567) (xy 425.031196 -33.972545) (xy 424.9674 -33.976559)
			(xy 424.903604 -33.972545) (xy 424.840814 -33.960567) (xy 424.780021 -33.940814) (xy 424.722182 -33.913597)
			(xy 424.668211 -33.879346) (xy 424.618958 -33.838601) (xy 424.575201 -33.792004) (xy 424.537628 -33.740289)
			(xy 424.506834 -33.684274) (xy 424.483302 -33.624841) (xy 424.467405 -33.562927) (xy 424.459394 -33.499509)
			(xy 419.862947 -33.499509) (xy 417.636621 -36.007548) (xy 419.359332 -36.007548) (xy 419.363403 -35.951926)
			(xy 419.375529 -35.897489) (xy 419.395452 -35.845398) (xy 419.422748 -35.796763) (xy 419.456834 -35.75262)
			(xy 419.496983 -35.713911) (xy 419.542341 -35.68146) (xy 419.591941 -35.655959) (xy 419.644725 -35.637952)
			(xy 419.699568 -35.627822) (xy 419.755302 -35.625785) (xy 419.810739 -35.631885) (xy 419.864696 -35.645991)
			(xy 419.916025 -35.667803) (xy 419.963631 -35.696857) (xy 420.006499 -35.732532) (xy 420.043716 -35.774069)
			(xy 420.074489 -35.820582) (xy 420.098161 -35.871079) (xy 420.114229 -35.924486) (xy 420.122349 -35.979662)
			(xy 420.122858 -36.007548) (xy 420.122349 -36.035434) (xy 420.114229 -36.09061) (xy 420.098161 -36.144017)
			(xy 420.074489 -36.194514) (xy 420.043716 -36.241027) (xy 420.006499 -36.282564) (xy 419.963631 -36.318239)
			(xy 419.916025 -36.347293) (xy 419.864696 -36.369105) (xy 419.810739 -36.383211) (xy 419.755302 -36.389311)
			(xy 419.699568 -36.387274) (xy 419.644725 -36.377144) (xy 419.591941 -36.359137) (xy 419.542341 -36.333636)
			(xy 419.496983 -36.301185) (xy 419.456834 -36.262476) (xy 419.422748 -36.218333) (xy 419.395452 -36.169698)
			(xy 419.375529 -36.117607) (xy 419.363403 -36.06317) (xy 419.359332 -36.007548) (xy 417.636621 -36.007548)
			(xy 416.480902 -37.309509) (xy 419.233344 -37.309509) (xy 419.233344 -37.245587) (xy 419.241355 -37.182169)
			(xy 419.257252 -37.120255) (xy 419.280784 -37.060822) (xy 419.311578 -37.004807) (xy 419.349151 -36.953092)
			(xy 419.392908 -36.906495) (xy 419.442161 -36.86575) (xy 419.496132 -36.831499) (xy 419.553971 -36.804282)
			(xy 419.614764 -36.784529) (xy 419.677554 -36.772551) (xy 419.74135 -36.768538) (xy 419.805146 -36.772551)
			(xy 419.867936 -36.784529) (xy 419.928729 -36.804282) (xy 419.986568 -36.831499) (xy 420.040539 -36.86575)
			(xy 420.089792 -36.906495) (xy 420.133549 -36.953092) (xy 420.171122 -37.004807) (xy 420.201916 -37.060822)
			(xy 420.225448 -37.120255) (xy 420.241345 -37.182169) (xy 420.249356 -37.245587) (xy 420.249858 -37.277548)
			(xy 420.249356 -37.309509) (xy 420.241345 -37.372927) (xy 420.225448 -37.434841) (xy 420.201916 -37.494274)
			(xy 420.171122 -37.550289) (xy 420.133549 -37.602004) (xy 420.089792 -37.648601) (xy 420.040539 -37.689346)
			(xy 419.986568 -37.723597) (xy 419.928729 -37.750814) (xy 419.867936 -37.770567) (xy 419.805146 -37.782545)
			(xy 419.74135 -37.786559) (xy 419.677554 -37.782545) (xy 419.614764 -37.770567) (xy 419.553971 -37.750814)
			(xy 419.496132 -37.723597) (xy 419.442161 -37.689346) (xy 419.392908 -37.648601) (xy 419.349151 -37.602004)
			(xy 419.311578 -37.550289) (xy 419.280784 -37.494274) (xy 419.257252 -37.434841) (xy 419.241355 -37.372927)
			(xy 419.233344 -37.309509) (xy 416.480902 -37.309509) (xy 415.353554 -38.579509) (xy 419.233344 -38.579509)
			(xy 419.233344 -38.515587) (xy 419.241355 -38.452169) (xy 419.257252 -38.390255) (xy 419.280784 -38.330822)
			(xy 419.311578 -38.274807) (xy 419.349151 -38.223092) (xy 419.392908 -38.176495) (xy 419.442161 -38.13575)
			(xy 419.496132 -38.101499) (xy 419.553971 -38.074282) (xy 419.614764 -38.054529) (xy 419.677554 -38.042551)
			(xy 419.74135 -38.038538) (xy 419.805146 -38.042551) (xy 419.867936 -38.054529) (xy 419.928729 -38.074282)
			(xy 419.986568 -38.101499) (xy 420.040539 -38.13575) (xy 420.089792 -38.176495) (xy 420.133549 -38.223092)
			(xy 420.171122 -38.274807) (xy 420.201916 -38.330822) (xy 420.225448 -38.390255) (xy 420.241345 -38.452169)
			(xy 420.249356 -38.515587) (xy 420.249858 -38.547548) (xy 420.249356 -38.579509) (xy 420.241345 -38.642927)
			(xy 420.225448 -38.704841) (xy 420.201916 -38.764274) (xy 420.171122 -38.820289) (xy 420.133549 -38.872004)
			(xy 420.089792 -38.918601) (xy 420.040539 -38.959346) (xy 419.986568 -38.993597) (xy 419.928729 -39.020814)
			(xy 419.867936 -39.040567) (xy 419.805146 -39.052545) (xy 419.74135 -39.056559) (xy 419.677554 -39.052545)
			(xy 419.614764 -39.040567) (xy 419.553971 -39.020814) (xy 419.496132 -38.993597) (xy 419.442161 -38.959346)
			(xy 419.392908 -38.918601) (xy 419.349151 -38.872004) (xy 419.311578 -38.820289) (xy 419.280784 -38.764274)
			(xy 419.257252 -38.704841) (xy 419.241355 -38.642927) (xy 419.233344 -38.579509) (xy 415.353554 -38.579509)
			(xy 413.098857 -41.119509) (xy 419.233344 -41.119509) (xy 419.233344 -41.055587) (xy 419.241355 -40.992169)
			(xy 419.257252 -40.930255) (xy 419.280784 -40.870822) (xy 419.311578 -40.814807) (xy 419.349151 -40.763092)
			(xy 419.392908 -40.716495) (xy 419.442161 -40.67575) (xy 419.496132 -40.641499) (xy 419.553971 -40.614282)
			(xy 419.614764 -40.594529) (xy 419.677554 -40.582551) (xy 419.74135 -40.578538) (xy 419.805146 -40.582551)
			(xy 419.867936 -40.594529) (xy 419.928729 -40.614282) (xy 419.986568 -40.641499) (xy 420.040539 -40.67575)
			(xy 420.089792 -40.716495) (xy 420.133549 -40.763092) (xy 420.171122 -40.814807) (xy 420.201916 -40.870822)
			(xy 420.225448 -40.930255) (xy 420.241345 -40.992169) (xy 420.249356 -41.055587) (xy 420.249858 -41.087548)
			(xy 420.249356 -41.119509) (xy 420.241345 -41.182927) (xy 420.225448 -41.244841) (xy 420.201916 -41.304274)
			(xy 420.171122 -41.360289) (xy 420.133549 -41.412004) (xy 420.089792 -41.458601) (xy 420.040539 -41.499346)
			(xy 419.986568 -41.533597) (xy 419.928729 -41.560814) (xy 419.867936 -41.580567) (xy 419.805146 -41.592545)
			(xy 419.74135 -41.596559) (xy 419.677554 -41.592545) (xy 419.614764 -41.580567) (xy 419.553971 -41.560814)
			(xy 419.496132 -41.533597) (xy 419.442161 -41.499346) (xy 419.392908 -41.458601) (xy 419.349151 -41.412004)
			(xy 419.311578 -41.360289) (xy 419.280784 -41.304274) (xy 419.257252 -41.244841) (xy 419.241355 -41.182927)
			(xy 419.233344 -41.119509) (xy 413.098857 -41.119509) (xy 412.597825 -41.68394) (xy 413.816292 -41.68394)
			(xy 413.816794 -41.651979) (xy 413.824805 -41.588561) (xy 413.840702 -41.526647) (xy 413.864234 -41.467214)
			(xy 413.895028 -41.411199) (xy 413.932601 -41.359484) (xy 413.976358 -41.312887) (xy 414.025611 -41.272142)
			(xy 414.079582 -41.237891) (xy 414.137421 -41.210674) (xy 414.198214 -41.190921) (xy 414.261004 -41.178943)
			(xy 414.3248 -41.17493) (xy 414.388596 -41.178943) (xy 414.451386 -41.190921) (xy 414.512179 -41.210674)
			(xy 414.570018 -41.237891) (xy 414.623989 -41.272142) (xy 414.673242 -41.312887) (xy 414.716999 -41.359484)
			(xy 414.754572 -41.411199) (xy 414.785366 -41.467214) (xy 414.808898 -41.526647) (xy 414.824795 -41.588561)
			(xy 414.832806 -41.651979) (xy 414.833308 -41.68394) (xy 414.832879 -41.71431) (xy 414.825625 -41.774615)
			(xy 414.811239 -41.833627) (xy 414.789923 -41.890504) (xy 414.761984 -41.944436) (xy 414.727817 -41.994656)
			(xy 414.68791 -42.040447) (xy 414.665668 -42.06113) (xy 414.657032 -42.069004) (xy 414.648396 -42.090594)
			(xy 414.655254 -42.193718) (xy 414.666938 -42.213784) (xy 414.67659 -42.220388) (xy 414.701838 -42.23817)
			(xy 414.748212 -42.278954) (xy 414.789309 -42.325051) (xy 414.824521 -42.375786) (xy 414.853333 -42.43041)
			(xy 414.875319 -42.48812) (xy 414.890157 -42.548068) (xy 414.897627 -42.609372) (xy 414.898078 -42.64025)
			(xy 414.897576 -42.672211) (xy 414.889565 -42.735629) (xy 414.873668 -42.797543) (xy 414.850136 -42.856976)
			(xy 414.819342 -42.912991) (xy 414.781769 -42.964706) (xy 414.738012 -43.011303) (xy 414.688759 -43.052048)
			(xy 414.634788 -43.086299) (xy 414.576949 -43.113516) (xy 414.516156 -43.133269) (xy 414.453366 -43.145247)
			(xy 414.38957 -43.149261) (xy 414.325774 -43.145247) (xy 414.262984 -43.133269) (xy 414.202191 -43.113516)
			(xy 414.144352 -43.086299) (xy 414.090381 -43.052048) (xy 414.041128 -43.011303) (xy 413.997371 -42.964706)
			(xy 413.959798 -42.912991) (xy 413.929004 -42.856976) (xy 413.905472 -42.797543) (xy 413.889575 -42.735629)
			(xy 413.881564 -42.672211) (xy 413.881062 -42.64025) (xy 413.881494 -42.60988) (xy 413.888748 -42.549575)
			(xy 413.903135 -42.490564) (xy 413.92445 -42.433688) (xy 413.952389 -42.379755) (xy 413.986555 -42.329536)
			(xy 414.02646 -42.283744) (xy 414.048702 -42.26306) (xy 414.057338 -42.255186) (xy 414.065974 -42.233596)
			(xy 414.059116 -42.130472) (xy 414.047432 -42.110406) (xy 414.03778 -42.103802) (xy 414.012544 -42.086004)
			(xy 413.966166 -42.045225) (xy 413.925067 -41.999131) (xy 413.889852 -41.948399) (xy 413.861039 -41.893777)
			(xy 413.839051 -41.836068) (xy 413.824213 -41.776121) (xy 413.816743 -41.714818) (xy 413.816292 -41.68394)
			(xy 412.597825 -41.68394) (xy 411.513316 -42.90568) (xy 412.7881 -42.90568) (xy 412.788602 -42.873719)
			(xy 412.796613 -42.810301) (xy 412.81251 -42.748387) (xy 412.836042 -42.688954) (xy 412.866836 -42.632939)
			(xy 412.904409 -42.581224) (xy 412.948166 -42.534627) (xy 412.997419 -42.493882) (xy 413.05139 -42.459631)
			(xy 413.109229 -42.432414) (xy 413.170022 -42.412661) (xy 413.232812 -42.400683) (xy 413.296608 -42.39667)
			(xy 413.360404 -42.400683) (xy 413.423194 -42.412661) (xy 413.483987 -42.432414) (xy 413.541826 -42.459631)
			(xy 413.595797 -42.493882) (xy 413.64505 -42.534627) (xy 413.688807 -42.581224) (xy 413.72638 -42.632939)
			(xy 413.757174 -42.688954) (xy 413.780706 -42.748387) (xy 413.796603 -42.810301) (xy 413.804614 -42.873719)
			(xy 413.805116 -42.90568) (xy 413.804653 -42.935718) (xy 413.797587 -42.995377) (xy 413.783538 -43.053787)
			(xy 413.762703 -43.110134) (xy 413.735373 -43.163633) (xy 413.701927 -43.213538) (xy 413.662833 -43.259153)
			(xy 413.641032 -43.279822) (xy 413.633158 -43.286934) (xy 413.62503 -43.305222) (xy 413.622236 -43.398694)
			(xy 413.629348 -43.41749) (xy 413.636714 -43.42511) (xy 413.656655 -43.446581) (xy 413.690404 -43.49448)
			(xy 413.716438 -43.546974) (xy 413.734145 -43.602829) (xy 413.743109 -43.660735) (xy 413.743648 -43.690032)
			(xy 413.743162 -43.717283) (xy 413.735406 -43.771231) (xy 413.720051 -43.823526) (xy 413.697409 -43.873103)
			(xy 413.667943 -43.918953) (xy 413.632252 -43.960144) (xy 413.591061 -43.995835) (xy 413.545211 -44.025301)
			(xy 413.495634 -44.047943) (xy 413.443339 -44.063298) (xy 413.389391 -44.071054) (xy 413.334889 -44.071054)
			(xy 413.280941 -44.063298) (xy 413.228646 -44.047943) (xy 413.179069 -44.025301) (xy 413.133219 -43.995835)
			(xy 413.092028 -43.960144) (xy 413.056337 -43.918953) (xy 413.026871 -43.873103) (xy 413.004229 -43.823526)
			(xy 412.988874 -43.771231) (xy 412.981118 -43.717283) (xy 412.980632 -43.690032) (xy 412.981131 -43.661368)
			(xy 412.989717 -43.604686) (xy 413.006686 -43.549927) (xy 413.031655 -43.498322) (xy 413.047434 -43.474386)
			(xy 413.053276 -43.46575) (xy 413.05734 -43.445938) (xy 413.039052 -43.354244) (xy 413.027876 -43.33748)
			(xy 413.018986 -43.331892) (xy 412.99281 -43.314207) (xy 412.944574 -43.273414) (xy 412.901758 -43.226964)
			(xy 412.86502 -43.175572) (xy 412.834926 -43.120028) (xy 412.811939 -43.061186) (xy 412.796411 -42.999952)
			(xy 412.788582 -42.937266) (xy 412.7881 -42.90568) (xy 411.513316 -42.90568) (xy 408.299059 -46.526661)
			(xy 409.707074 -46.526661) (xy 409.707074 -46.462739) (xy 409.715085 -46.399321) (xy 409.730982 -46.337407)
			(xy 409.754514 -46.277974) (xy 409.785308 -46.221959) (xy 409.822881 -46.170244) (xy 409.866638 -46.123647)
			(xy 409.915891 -46.082902) (xy 409.969862 -46.048651) (xy 410.027701 -46.021434) (xy 410.088494 -46.001681)
			(xy 410.151284 -45.989703) (xy 410.21508 -45.98569) (xy 410.278876 -45.989703) (xy 410.341666 -46.001681)
			(xy 410.402459 -46.021434) (xy 410.460298 -46.048651) (xy 410.514269 -46.082902) (xy 410.563522 -46.123647)
			(xy 410.607279 -46.170244) (xy 410.644852 -46.221959) (xy 410.675646 -46.277974) (xy 410.699178 -46.337407)
			(xy 410.715075 -46.399321) (xy 410.723086 -46.462739) (xy 410.723588 -46.4947) (xy 410.723086 -46.526661)
			(xy 410.715075 -46.590079) (xy 410.699178 -46.651993) (xy 410.675646 -46.711426) (xy 410.644852 -46.767441)
			(xy 410.607279 -46.819156) (xy 410.563522 -46.865753) (xy 410.514269 -46.906498) (xy 410.460298 -46.940749)
			(xy 410.402459 -46.967966) (xy 410.341666 -46.987719) (xy 410.278876 -46.999697) (xy 410.21508 -47.003711)
			(xy 410.151284 -46.999697) (xy 410.088494 -46.987719) (xy 410.027701 -46.967966) (xy 409.969862 -46.940749)
			(xy 409.915891 -46.906498) (xy 409.866638 -46.865753) (xy 409.822881 -46.819156) (xy 409.785308 -46.767441)
			(xy 409.754514 -46.711426) (xy 409.730982 -46.651993) (xy 409.715085 -46.590079) (xy 409.707074 -46.526661)
			(xy 408.299059 -46.526661) (xy 397.645128 -58.528712) (xy 397.643604 -58.530236) (xy 393.741402 -63.692786)
			(xy 393.740386 -63.694056) (xy 393.73937 -63.695326) (xy 393.618591 -63.828676) (xy 399.552666 -63.828676)
			(xy 399.556737 -63.773054) (xy 399.568863 -63.718617) (xy 399.588786 -63.666526) (xy 399.616082 -63.617891)
			(xy 399.650168 -63.573748) (xy 399.690317 -63.535039) (xy 399.735675 -63.502588) (xy 399.785275 -63.477087)
			(xy 399.838059 -63.45908) (xy 399.892902 -63.44895) (xy 399.948636 -63.446913) (xy 400.004073 -63.453013)
			(xy 400.05803 -63.467119) (xy 400.109359 -63.488931) (xy 400.156965 -63.517985) (xy 400.199833 -63.55366)
			(xy 400.23705 -63.595197) (xy 400.267823 -63.64171) (xy 400.291495 -63.692207) (xy 400.307563 -63.745614)
			(xy 400.315683 -63.80079) (xy 400.316192 -63.828676) (xy 400.315683 -63.856562) (xy 400.307563 -63.911738)
			(xy 400.291495 -63.965145) (xy 400.267823 -64.015642) (xy 400.23705 -64.062155) (xy 400.199833 -64.103692)
			(xy 400.156965 -64.139367) (xy 400.109359 -64.168421) (xy 400.05803 -64.190233) (xy 400.004073 -64.204339)
			(xy 399.948636 -64.210439) (xy 399.892902 -64.208402) (xy 399.838059 -64.198272) (xy 399.785275 -64.180265)
			(xy 399.735675 -64.154764) (xy 399.690317 -64.122313) (xy 399.650168 -64.083604) (xy 399.616082 -64.039461)
			(xy 399.588786 -63.990826) (xy 399.568863 -63.938735) (xy 399.556737 -63.884298) (xy 399.552666 -63.828676)
			(xy 393.618591 -63.828676) (xy 384.98643 -73.3593) (xy 391.791132 -73.3593) (xy 391.795147 -73.295496)
			(xy 391.807126 -73.232699) (xy 391.826882 -73.171898) (xy 391.854102 -73.114053) (xy 391.888357 -73.060076)
			(xy 391.929108 -73.010817) (xy 391.975711 -72.967055) (xy 392.027431 -72.929478) (xy 392.083454 -72.89868)
			(xy 392.142894 -72.875147) (xy 392.204815 -72.859248) (xy 392.268241 -72.851237) (xy 392.300206 -72.850756)
			(xy 392.318494 -72.85101) (xy 392.327061 -72.850977) (xy 392.343418 -72.845926) (xy 392.350498 -72.841104)
			(xy 392.374374 -72.823578) (xy 392.381027 -72.818203) (xy 392.390628 -72.804059) (xy 392.39317 -72.795892)
			(xy 392.402258 -72.763854) (xy 392.427753 -72.702329) (xy 392.461059 -72.644658) (xy 392.501607 -72.591827)
			(xy 392.548703 -72.54474) (xy 392.601542 -72.504202) (xy 392.65922 -72.470908) (xy 392.72075 -72.445425)
			(xy 392.785079 -72.428191) (xy 392.851107 -72.4195) (xy 392.884406 -72.418956) (xy 392.916365 -72.41953)
			(xy 392.979778 -72.427542) (xy 393.041686 -72.443438) (xy 393.101115 -72.466968) (xy 393.157125 -72.497761)
			(xy 393.208835 -72.535331) (xy 393.255428 -72.579085) (xy 393.29617 -72.628334) (xy 393.330419 -72.682301)
			(xy 393.357633 -72.740135) (xy 393.377384 -72.800924) (xy 393.389361 -72.863709) (xy 393.393375 -72.9275)
			(xy 393.389361 -72.991291) (xy 393.387106 -73.003113) (xy 393.674594 -73.003113) (xy 393.674594 -72.939191)
			(xy 393.682605 -72.875773) (xy 393.698502 -72.813859) (xy 393.722034 -72.754426) (xy 393.752828 -72.698411)
			(xy 393.790401 -72.646696) (xy 393.834158 -72.600099) (xy 393.883411 -72.559354) (xy 393.937382 -72.525103)
			(xy 393.995221 -72.497886) (xy 394.056014 -72.478133) (xy 394.118804 -72.466155) (xy 394.1826 -72.462142)
			(xy 394.246396 -72.466155) (xy 394.309186 -72.478133) (xy 394.369979 -72.497886) (xy 394.427818 -72.525103)
			(xy 394.481789 -72.559354) (xy 394.531042 -72.600099) (xy 394.574799 -72.646696) (xy 394.612372 -72.698411)
			(xy 394.643166 -72.754426) (xy 394.666698 -72.813859) (xy 394.682595 -72.875773) (xy 394.690606 -72.939191)
			(xy 394.691108 -72.971152) (xy 394.690606 -73.003113) (xy 394.68451 -73.051373) (xy 394.959834 -73.051373)
			(xy 394.959834 -72.987451) (xy 394.967845 -72.924033) (xy 394.983742 -72.862119) (xy 395.007274 -72.802686)
			(xy 395.038068 -72.746671) (xy 395.075641 -72.694956) (xy 395.119398 -72.648359) (xy 395.168651 -72.607614)
			(xy 395.222622 -72.573363) (xy 395.280461 -72.546146) (xy 395.341254 -72.526393) (xy 395.404044 -72.514415)
			(xy 395.46784 -72.510402) (xy 395.531636 -72.514415) (xy 395.594426 -72.526393) (xy 395.655219 -72.546146)
			(xy 395.713058 -72.573363) (xy 395.767029 -72.607614) (xy 395.816282 -72.648359) (xy 395.860039 -72.694956)
			(xy 395.897612 -72.746671) (xy 395.928406 -72.802686) (xy 395.951938 -72.862119) (xy 395.967835 -72.924033)
			(xy 395.975846 -72.987451) (xy 395.976348 -73.019412) (xy 395.975846 -73.051373) (xy 395.967835 -73.114791)
			(xy 395.951938 -73.176705) (xy 395.928406 -73.236138) (xy 395.897612 -73.292153) (xy 395.860039 -73.343868)
			(xy 395.816282 -73.390465) (xy 395.767029 -73.43121) (xy 395.713058 -73.465461) (xy 395.655219 -73.492678)
			(xy 395.594426 -73.512431) (xy 395.531636 -73.524409) (xy 395.46784 -73.528423) (xy 395.404044 -73.524409)
			(xy 395.341254 -73.512431) (xy 395.280461 -73.492678) (xy 395.222622 -73.465461) (xy 395.168651 -73.43121)
			(xy 395.119398 -73.390465) (xy 395.075641 -73.343868) (xy 395.038068 -73.292153) (xy 395.007274 -73.236138)
			(xy 394.983742 -73.176705) (xy 394.967845 -73.114791) (xy 394.959834 -73.051373) (xy 394.68451 -73.051373)
			(xy 394.682595 -73.066531) (xy 394.666698 -73.128445) (xy 394.643166 -73.187878) (xy 394.612372 -73.243893)
			(xy 394.574799 -73.295608) (xy 394.531042 -73.342205) (xy 394.481789 -73.38295) (xy 394.427818 -73.417201)
			(xy 394.369979 -73.444418) (xy 394.309186 -73.464171) (xy 394.246396 -73.476149) (xy 394.1826 -73.480163)
			(xy 394.118804 -73.476149) (xy 394.056014 -73.464171) (xy 393.995221 -73.444418) (xy 393.937382 -73.417201)
			(xy 393.883411 -73.38295) (xy 393.834158 -73.342205) (xy 393.790401 -73.295608) (xy 393.752828 -73.243893)
			(xy 393.722034 -73.187878) (xy 393.698502 -73.128445) (xy 393.682605 -73.066531) (xy 393.674594 -73.003113)
			(xy 393.387106 -73.003113) (xy 393.377384 -73.054076) (xy 393.357633 -73.114865) (xy 393.330419 -73.172699)
			(xy 393.29617 -73.226666) (xy 393.255428 -73.275915) (xy 393.208835 -73.319669) (xy 393.157125 -73.357239)
			(xy 393.101115 -73.388032) (xy 393.041686 -73.411562) (xy 392.979778 -73.427458) (xy 392.916365 -73.43547)
			(xy 392.884406 -73.435972) (xy 392.866118 -73.435718) (xy 392.85755 -73.435723) (xy 392.841193 -73.440795)
			(xy 392.834114 -73.445624) (xy 392.810238 -73.46315) (xy 392.803608 -73.46855) (xy 392.793994 -73.482676)
			(xy 392.791442 -73.490836) (xy 392.782296 -73.522857) (xy 392.756811 -73.584382) (xy 392.723513 -73.642054)
			(xy 392.682973 -73.694887) (xy 392.635883 -73.741976) (xy 392.58305 -73.782516) (xy 392.525378 -73.815813)
			(xy 392.463853 -73.841298) (xy 392.399528 -73.858534) (xy 392.333503 -73.867227) (xy 392.300206 -73.867772)
			(xy 392.268241 -73.867363) (xy 392.204815 -73.859352) (xy 392.142894 -73.843453) (xy 392.083454 -73.81992)
			(xy 392.027431 -73.789122) (xy 391.975711 -73.751545) (xy 391.929108 -73.707783) (xy 391.888357 -73.658524)
			(xy 391.854102 -73.604547) (xy 391.826882 -73.546702) (xy 391.807126 -73.485901) (xy 391.795147 -73.423104)
			(xy 391.791132 -73.3593) (xy 384.98643 -73.3593) (xy 384.066242 -74.375264) (xy 389.74268 -74.375264)
			(xy 389.743182 -74.343303) (xy 389.751193 -74.279885) (xy 389.76709 -74.217971) (xy 389.790622 -74.158538)
			(xy 389.821416 -74.102523) (xy 389.858989 -74.050808) (xy 389.902746 -74.004211) (xy 389.951999 -73.963466)
			(xy 390.00597 -73.929215) (xy 390.063809 -73.901998) (xy 390.124602 -73.882245) (xy 390.187392 -73.870267)
			(xy 390.251188 -73.866254) (xy 390.314984 -73.870267) (xy 390.377774 -73.882245) (xy 390.438567 -73.901998)
			(xy 390.496406 -73.929215) (xy 390.550377 -73.963466) (xy 390.59963 -74.004211) (xy 390.643387 -74.050808)
			(xy 390.68096 -74.102523) (xy 390.711754 -74.158538) (xy 390.719707 -74.178625) (xy 392.880082 -74.178625)
			(xy 392.880082 -74.114703) (xy 392.888093 -74.051285) (xy 392.90399 -73.989371) (xy 392.927522 -73.929938)
			(xy 392.958316 -73.873923) (xy 392.995889 -73.822208) (xy 393.039646 -73.775611) (xy 393.088899 -73.734866)
			(xy 393.14287 -73.700615) (xy 393.200709 -73.673398) (xy 393.261502 -73.653645) (xy 393.324292 -73.641667)
			(xy 393.388088 -73.637654) (xy 393.451884 -73.641667) (xy 393.514674 -73.653645) (xy 393.575467 -73.673398)
			(xy 393.633306 -73.700615) (xy 393.687277 -73.734866) (xy 393.73653 -73.775611) (xy 393.780287 -73.822208)
			(xy 393.81786 -73.873923) (xy 393.848654 -73.929938) (xy 393.872186 -73.989371) (xy 393.888083 -74.051285)
			(xy 393.896094 -74.114703) (xy 393.896596 -74.146664) (xy 393.896094 -74.178625) (xy 393.888083 -74.242043)
			(xy 393.872186 -74.303957) (xy 393.848654 -74.36339) (xy 393.81786 -74.419405) (xy 393.780287 -74.47112)
			(xy 393.73653 -74.517717) (xy 393.687277 -74.558462) (xy 393.633306 -74.592713) (xy 393.575467 -74.61993)
			(xy 393.514674 -74.639683) (xy 393.451884 -74.651661) (xy 393.388088 -74.655675) (xy 393.324292 -74.651661)
			(xy 393.261502 -74.639683) (xy 393.200709 -74.61993) (xy 393.14287 -74.592713) (xy 393.088899 -74.558462)
			(xy 393.039646 -74.517717) (xy 392.995889 -74.47112) (xy 392.958316 -74.419405) (xy 392.927522 -74.36339)
			(xy 392.90399 -74.303957) (xy 392.888093 -74.242043) (xy 392.880082 -74.178625) (xy 390.719707 -74.178625)
			(xy 390.735286 -74.217971) (xy 390.751183 -74.279885) (xy 390.759194 -74.343303) (xy 390.759696 -74.375264)
			(xy 390.759242 -74.405672) (xy 390.751992 -74.466055) (xy 390.737592 -74.525141) (xy 390.716246 -74.582088)
			(xy 390.68826 -74.636083) (xy 390.654034 -74.686354) (xy 390.614055 -74.732183) (xy 390.568896 -74.772917)
			(xy 390.544304 -74.790808) (xy 390.532813 -74.79942) (xy 390.514834 -74.821797) (xy 390.503797 -74.848296)
			(xy 390.500576 -74.87682) (xy 390.501686 -74.8833) (xy 397.367253 -74.8833) (xy 397.371267 -74.819502)
			(xy 397.383245 -74.75671) (xy 397.402998 -74.695915) (xy 397.430214 -74.638074) (xy 397.464465 -74.5841)
			(xy 397.505211 -74.534845) (xy 397.551808 -74.491084) (xy 397.603522 -74.453509) (xy 397.659538 -74.422711)
			(xy 397.718972 -74.399176) (xy 397.780887 -74.383275) (xy 397.844306 -74.37526) (xy 397.876268 -74.374756)
			(xy 397.909827 -74.375272) (xy 397.976358 -74.384121) (xy 398.041148 -74.401643) (xy 398.103071 -74.427533)
			(xy 398.161052 -74.461341) (xy 398.214082 -74.502481) (xy 398.261242 -74.550238) (xy 398.281906 -74.576686)
			(xy 398.28851 -74.585322) (xy 398.30629 -74.595482) (xy 398.401286 -74.605896) (xy 398.420844 -74.5998)
			(xy 398.428972 -74.592942) (xy 398.449747 -74.575791) (xy 398.495248 -74.54695) (xy 398.544357 -74.524803)
			(xy 398.596095 -74.509792) (xy 398.649432 -74.502216) (xy 398.676368 -74.501756) (xy 398.70362 -74.502289)
			(xy 398.757569 -74.510042) (xy 398.809866 -74.525393) (xy 398.859445 -74.548032) (xy 398.905298 -74.577496)
			(xy 398.946491 -74.613187) (xy 398.982184 -74.654376) (xy 399.011653 -74.700227) (xy 399.034295 -74.749804)
			(xy 399.049652 -74.8021) (xy 399.057409 -74.856048) (xy 399.057409 -74.910552) (xy 399.049652 -74.9645)
			(xy 399.034295 -75.016796) (xy 399.011653 -75.066373) (xy 398.982184 -75.112224) (xy 398.946491 -75.153413)
			(xy 398.905298 -75.189104) (xy 398.859445 -75.218568) (xy 398.809866 -75.241207) (xy 398.757569 -75.256558)
			(xy 398.70362 -75.264311) (xy 398.676368 -75.264772) (xy 398.649435 -75.264285) (xy 398.596104 -75.2567)
			(xy 398.544372 -75.241686) (xy 398.495268 -75.219542) (xy 398.449768 -75.190708) (xy 398.428972 -75.173586)
			(xy 398.420844 -75.166728) (xy 398.401286 -75.160632) (xy 398.30629 -75.171046) (xy 398.28851 -75.181206)
			(xy 398.281906 -75.189842) (xy 398.261234 -75.216284) (xy 398.214085 -75.264052) (xy 398.16106 -75.3052)
			(xy 398.10308 -75.339011) (xy 398.041155 -75.364896) (xy 397.976361 -75.382406) (xy 397.909827 -75.391235)
			(xy 397.876268 -75.391772) (xy 397.844306 -75.39134) (xy 397.780887 -75.383325) (xy 397.718972 -75.367424)
			(xy 397.659538 -75.343889) (xy 397.603522 -75.313091) (xy 397.551808 -75.275516) (xy 397.505211 -75.231755)
			(xy 397.464465 -75.1825) (xy 397.430214 -75.128526) (xy 397.402998 -75.070685) (xy 397.383245 -75.00989)
			(xy 397.371267 -74.947098) (xy 397.367253 -74.8833) (xy 390.501686 -74.8833) (xy 390.505424 -74.905113)
			(xy 390.517958 -74.930937) (xy 390.537187 -74.95225) (xy 390.54913 -74.960226) (xy 390.576261 -74.977675)
			(xy 390.626304 -75.018383) (xy 390.670794 -75.065094) (xy 390.709017 -75.117059) (xy 390.740359 -75.173442)
			(xy 390.764317 -75.233337) (xy 390.780504 -75.295781) (xy 390.788662 -75.359772) (xy 390.78916 -75.392026)
			(xy 390.788658 -75.423987) (xy 390.780647 -75.487405) (xy 390.76475 -75.549319) (xy 390.741218 -75.608752)
			(xy 390.710424 -75.664767) (xy 390.672851 -75.716482) (xy 390.667457 -75.722226) (xy 394.311884 -75.722226)
			(xy 394.315955 -75.666604) (xy 394.328081 -75.612167) (xy 394.348004 -75.560076) (xy 394.3753 -75.511441)
			(xy 394.409386 -75.467298) (xy 394.449535 -75.428589) (xy 394.494893 -75.396138) (xy 394.544493 -75.370637)
			(xy 394.597277 -75.35263) (xy 394.65212 -75.3425) (xy 394.707854 -75.340463) (xy 394.763291 -75.346563)
			(xy 394.817248 -75.360669) (xy 394.868577 -75.382481) (xy 394.916183 -75.411535) (xy 394.959051 -75.44721)
			(xy 394.996268 -75.488747) (xy 395.027041 -75.53526) (xy 395.050713 -75.585757) (xy 395.066781 -75.639164)
			(xy 395.074901 -75.69434) (xy 395.07541 -75.722226) (xy 395.074901 -75.750112) (xy 395.066781 -75.805288)
			(xy 395.050713 -75.858695) (xy 395.027041 -75.909192) (xy 394.996268 -75.955705) (xy 394.959051 -75.997242)
			(xy 394.916183 -76.032917) (xy 394.878806 -76.055728) (xy 397.0053 -76.055728) (xy 397.009371 -76.000106)
			(xy 397.021497 -75.945669) (xy 397.04142 -75.893578) (xy 397.068716 -75.844943) (xy 397.102802 -75.8008)
			(xy 397.142951 -75.762091) (xy 397.188309 -75.72964) (xy 397.237909 -75.704139) (xy 397.290693 -75.686132)
			(xy 397.345536 -75.676002) (xy 397.40127 -75.673965) (xy 397.456707 -75.680065) (xy 397.510664 -75.694171)
			(xy 397.561993 -75.715983) (xy 397.609599 -75.745037) (xy 397.652467 -75.780712) (xy 397.689684 -75.822249)
			(xy 397.720457 -75.868762) (xy 397.744129 -75.919259) (xy 397.760197 -75.972666) (xy 397.768317 -76.027842)
			(xy 397.768826 -76.055728) (xy 397.768317 -76.083614) (xy 397.760197 -76.13879) (xy 397.744129 -76.192197)
			(xy 397.720457 -76.242694) (xy 397.689684 -76.289207) (xy 397.652467 -76.330744) (xy 397.609599 -76.366419)
			(xy 397.561993 -76.395473) (xy 397.510664 -76.417285) (xy 397.456707 -76.431391) (xy 397.40127 -76.437491)
			(xy 397.345536 -76.435454) (xy 397.290693 -76.425324) (xy 397.237909 -76.407317) (xy 397.188309 -76.381816)
			(xy 397.142951 -76.349365) (xy 397.102802 -76.310656) (xy 397.068716 -76.266513) (xy 397.04142 -76.217878)
			(xy 397.021497 -76.165787) (xy 397.009371 -76.11135) (xy 397.0053 -76.055728) (xy 394.878806 -76.055728)
			(xy 394.868577 -76.061971) (xy 394.817248 -76.083783) (xy 394.763291 -76.097889) (xy 394.707854 -76.103989)
			(xy 394.65212 -76.101952) (xy 394.597277 -76.091822) (xy 394.544493 -76.073815) (xy 394.494893 -76.048314)
			(xy 394.449535 -76.015863) (xy 394.409386 -75.977154) (xy 394.3753 -75.933011) (xy 394.348004 -75.884376)
			(xy 394.328081 -75.832285) (xy 394.315955 -75.777848) (xy 394.311884 -75.722226) (xy 390.667457 -75.722226)
			(xy 390.629094 -75.763079) (xy 390.579841 -75.803824) (xy 390.52587 -75.838075) (xy 390.468031 -75.865292)
			(xy 390.407238 -75.885045) (xy 390.344448 -75.897023) (xy 390.280652 -75.901037) (xy 390.216856 -75.897023)
			(xy 390.154066 -75.885045) (xy 390.093273 -75.865292) (xy 390.035434 -75.838075) (xy 389.981463 -75.803824)
			(xy 389.93221 -75.763079) (xy 389.888453 -75.716482) (xy 389.85088 -75.664767) (xy 389.820086 -75.608752)
			(xy 389.796554 -75.549319) (xy 389.780657 -75.487405) (xy 389.772646 -75.423987) (xy 389.772144 -75.392026)
			(xy 389.772573 -75.361617) (xy 389.779825 -75.301233) (xy 389.794228 -75.242145) (xy 389.815577 -75.185197)
			(xy 389.843566 -75.131202) (xy 389.877796 -75.080932) (xy 389.917779 -75.035104) (xy 389.962942 -74.994372)
			(xy 389.987536 -74.976482) (xy 389.999032 -74.967879) (xy 390.017004 -74.945497) (xy 390.028035 -74.918997)
			(xy 390.031254 -74.890474) (xy 390.026406 -74.862182) (xy 390.013874 -74.836358) (xy 389.99465 -74.815043)
			(xy 389.98271 -74.807064) (xy 389.955583 -74.789607) (xy 389.905539 -74.748902) (xy 389.861047 -74.702193)
			(xy 389.822823 -74.650229) (xy 389.79148 -74.593847) (xy 389.767522 -74.533953) (xy 389.751335 -74.471509)
			(xy 389.743177 -74.407518) (xy 389.74268 -74.375264) (xy 384.066242 -74.375264) (xy 382.225111 -76.408026)
			(xy 389.89965 -76.408026) (xy 389.903721 -76.352404) (xy 389.915847 -76.297967) (xy 389.93577 -76.245876)
			(xy 389.963066 -76.197241) (xy 389.997152 -76.153098) (xy 390.037301 -76.114389) (xy 390.082659 -76.081938)
			(xy 390.132259 -76.056437) (xy 390.185043 -76.03843) (xy 390.239886 -76.0283) (xy 390.29562 -76.026263)
			(xy 390.351057 -76.032363) (xy 390.405014 -76.046469) (xy 390.456343 -76.068281) (xy 390.503949 -76.097335)
			(xy 390.546817 -76.13301) (xy 390.584034 -76.174547) (xy 390.614807 -76.22106) (xy 390.638479 -76.271557)
			(xy 390.654547 -76.324964) (xy 390.662667 -76.38014) (xy 390.663176 -76.408026) (xy 390.662667 -76.435912)
			(xy 390.654547 -76.491088) (xy 390.638479 -76.544495) (xy 390.614807 -76.594992) (xy 390.584034 -76.641505)
			(xy 390.546817 -76.683042) (xy 390.503949 -76.718717) (xy 390.456343 -76.747771) (xy 390.405014 -76.769583)
			(xy 390.351057 -76.783689) (xy 390.29562 -76.789789) (xy 390.239886 -76.787752) (xy 390.185043 -76.777622)
			(xy 390.132259 -76.759615) (xy 390.082659 -76.734114) (xy 390.037301 -76.701663) (xy 389.997152 -76.662954)
			(xy 389.963066 -76.618811) (xy 389.93577 -76.570176) (xy 389.915847 -76.518085) (xy 389.903721 -76.463648)
			(xy 389.89965 -76.408026) (xy 382.225111 -76.408026) (xy 381.797438 -76.880212) (xy 395.471902 -76.880212)
			(xy 395.475973 -76.82459) (xy 395.488099 -76.770153) (xy 395.508022 -76.718062) (xy 395.535318 -76.669427)
			(xy 395.569404 -76.625284) (xy 395.609553 -76.586575) (xy 395.654911 -76.554124) (xy 395.704511 -76.528623)
			(xy 395.757295 -76.510616) (xy 395.812138 -76.500486) (xy 395.867872 -76.498449) (xy 395.923309 -76.504549)
			(xy 395.977266 -76.518655) (xy 396.028595 -76.540467) (xy 396.076201 -76.569521) (xy 396.119069 -76.605196)
			(xy 396.156286 -76.646733) (xy 396.1659 -76.661264) (xy 398.977864 -76.661264) (xy 398.981935 -76.605642)
			(xy 398.994061 -76.551205) (xy 399.013984 -76.499114) (xy 399.04128 -76.450479) (xy 399.075366 -76.406336)
			(xy 399.115515 -76.367627) (xy 399.160873 -76.335176) (xy 399.210473 -76.309675) (xy 399.263257 -76.291668)
			(xy 399.3181 -76.281538) (xy 399.373834 -76.279501) (xy 399.429271 -76.285601) (xy 399.483228 -76.299707)
			(xy 399.534557 -76.321519) (xy 399.582163 -76.350573) (xy 399.625031 -76.386248) (xy 399.662248 -76.427785)
			(xy 399.693021 -76.474298) (xy 399.716693 -76.524795) (xy 399.732761 -76.578202) (xy 399.740881 -76.633378)
			(xy 399.74139 -76.661264) (xy 399.740881 -76.68915) (xy 399.732761 -76.744326) (xy 399.716693 -76.797733)
			(xy 399.693021 -76.84823) (xy 399.662248 -76.894743) (xy 399.625031 -76.93628) (xy 399.582163 -76.971955)
			(xy 399.534557 -77.001009) (xy 399.483228 -77.022821) (xy 399.429271 -77.036927) (xy 399.373834 -77.043027)
			(xy 399.3181 -77.04099) (xy 399.263257 -77.03086) (xy 399.210473 -77.012853) (xy 399.160873 -76.987352)
			(xy 399.115515 -76.954901) (xy 399.075366 -76.916192) (xy 399.04128 -76.872049) (xy 399.013984 -76.823414)
			(xy 398.994061 -76.771323) (xy 398.981935 -76.716886) (xy 398.977864 -76.661264) (xy 396.1659 -76.661264)
			(xy 396.187059 -76.693246) (xy 396.210731 -76.743743) (xy 396.226799 -76.79715) (xy 396.234919 -76.852326)
			(xy 396.235428 -76.880212) (xy 396.234919 -76.908098) (xy 396.226799 -76.963274) (xy 396.210731 -77.016681)
			(xy 396.187059 -77.067178) (xy 396.156286 -77.113691) (xy 396.119069 -77.155228) (xy 396.076201 -77.190903)
			(xy 396.028595 -77.219957) (xy 395.977266 -77.241769) (xy 395.923309 -77.255875) (xy 395.867872 -77.261975)
			(xy 395.812138 -77.259938) (xy 395.757295 -77.249808) (xy 395.704511 -77.231801) (xy 395.654911 -77.2063)
			(xy 395.609553 -77.173849) (xy 395.569404 -77.13514) (xy 395.535318 -77.090997) (xy 395.508022 -77.042362)
			(xy 395.488099 -76.990271) (xy 395.475973 -76.935834) (xy 395.471902 -76.880212) (xy 381.797438 -76.880212)
			(xy 381.30489 -77.424026) (xy 389.89965 -77.424026) (xy 389.903721 -77.368404) (xy 389.915847 -77.313967)
			(xy 389.93577 -77.261876) (xy 389.963066 -77.213241) (xy 389.997152 -77.169098) (xy 390.037301 -77.130389)
			(xy 390.082659 -77.097938) (xy 390.132259 -77.072437) (xy 390.185043 -77.05443) (xy 390.239886 -77.0443)
			(xy 390.29562 -77.042263) (xy 390.351057 -77.048363) (xy 390.405014 -77.062469) (xy 390.456343 -77.084281)
			(xy 390.503949 -77.113335) (xy 390.546817 -77.14901) (xy 390.584034 -77.190547) (xy 390.614807 -77.23706)
			(xy 390.638479 -77.287557) (xy 390.654547 -77.340964) (xy 390.662667 -77.39614) (xy 390.663176 -77.424026)
			(xy 390.662667 -77.451912) (xy 390.654547 -77.507088) (xy 390.638479 -77.560495) (xy 390.614807 -77.610992)
			(xy 390.584034 -77.657505) (xy 390.546817 -77.699042) (xy 390.503949 -77.734717) (xy 390.456343 -77.763771)
			(xy 390.405014 -77.785583) (xy 390.351057 -77.799689) (xy 390.29562 -77.805789) (xy 390.239886 -77.803752)
			(xy 390.185043 -77.793622) (xy 390.132259 -77.775615) (xy 390.082659 -77.750114) (xy 390.037301 -77.717663)
			(xy 389.997152 -77.678954) (xy 389.963066 -77.634811) (xy 389.93577 -77.586176) (xy 389.915847 -77.534085)
			(xy 389.903721 -77.479648) (xy 389.89965 -77.424026) (xy 381.30489 -77.424026) (xy 380.355722 -78.471987)
			(xy 389.773662 -78.471987) (xy 389.773662 -78.408065) (xy 389.781673 -78.344647) (xy 389.79757 -78.282733)
			(xy 389.821102 -78.2233) (xy 389.851896 -78.167285) (xy 389.889469 -78.11557) (xy 389.933226 -78.068973)
			(xy 389.982479 -78.028228) (xy 390.03645 -77.993977) (xy 390.094289 -77.96676) (xy 390.155082 -77.947007)
			(xy 390.217872 -77.935029) (xy 390.281668 -77.931016) (xy 390.345464 -77.935029) (xy 390.408254 -77.947007)
			(xy 390.469047 -77.96676) (xy 390.526886 -77.993977) (xy 390.580857 -78.028228) (xy 390.63011 -78.068973)
			(xy 390.673867 -78.11557) (xy 390.71144 -78.167285) (xy 390.742234 -78.2233) (xy 390.765766 -78.282733)
			(xy 390.781663 -78.344647) (xy 390.789674 -78.408065) (xy 390.790176 -78.440026) (xy 390.789674 -78.471987)
			(xy 390.781663 -78.535405) (xy 390.765766 -78.597319) (xy 390.742234 -78.656752) (xy 390.71144 -78.712767)
			(xy 390.673867 -78.764482) (xy 390.63011 -78.811079) (xy 390.580857 -78.851824) (xy 390.526886 -78.886075)
			(xy 390.469047 -78.913292) (xy 390.408254 -78.933045) (xy 390.345464 -78.945023) (xy 390.281668 -78.949037)
			(xy 390.217872 -78.945023) (xy 390.155082 -78.933045) (xy 390.094289 -78.913292) (xy 390.03645 -78.886075)
			(xy 389.982479 -78.851824) (xy 389.933226 -78.811079) (xy 389.889469 -78.764482) (xy 389.851896 -78.712767)
			(xy 389.821102 -78.656752) (xy 389.79757 -78.597319) (xy 389.781673 -78.535405) (xy 389.773662 -78.471987)
			(xy 380.355722 -78.471987) (xy 379.253949 -79.688436) (xy 396.876016 -79.688436) (xy 396.87655 -79.655096)
			(xy 396.885254 -79.588988) (xy 396.902532 -79.524587) (xy 396.928086 -79.462998) (xy 396.961476 -79.405282)
			(xy 397.00213 -79.35243) (xy 397.025368 -79.328518) (xy 397.03248 -79.321406) (xy 397.0401 -79.30261)
			(xy 397.0401 -79.210662) (xy 397.03248 -79.191866) (xy 397.025368 -79.184754) (xy 397.002128 -79.160845)
			(xy 396.961486 -79.107985) (xy 396.928101 -79.050266) (xy 396.902547 -78.988679) (xy 396.885262 -78.924281)
			(xy 396.876542 -78.858175) (xy 396.876016 -78.824836) (xy 396.876518 -78.792875) (xy 396.884529 -78.729457)
			(xy 396.900426 -78.667543) (xy 396.923958 -78.60811) (xy 396.954752 -78.552095) (xy 396.992325 -78.50038)
			(xy 397.036082 -78.453783) (xy 397.085335 -78.413038) (xy 397.139306 -78.378787) (xy 397.197145 -78.35157)
			(xy 397.257938 -78.331817) (xy 397.320728 -78.319839) (xy 397.384524 -78.315826) (xy 397.44832 -78.319839)
			(xy 397.51111 -78.331817) (xy 397.571903 -78.35157) (xy 397.629742 -78.378787) (xy 397.683713 -78.413038)
			(xy 397.732966 -78.453783) (xy 397.776723 -78.50038) (xy 397.814296 -78.552095) (xy 397.84509 -78.60811)
			(xy 397.868622 -78.667543) (xy 397.884519 -78.729457) (xy 397.89253 -78.792875) (xy 397.893032 -78.824836)
			(xy 397.892531 -78.858176) (xy 397.883817 -78.924286) (xy 397.866532 -78.988687) (xy 397.840973 -79.050275)
			(xy 397.807577 -79.10799) (xy 397.76692 -79.160842) (xy 397.74368 -79.184754) (xy 397.736568 -79.191866)
			(xy 397.728948 -79.210662) (xy 397.728948 -79.30261) (xy 397.736568 -79.321406) (xy 397.74368 -79.328518)
			(xy 397.766898 -79.352448) (xy 397.807544 -79.405303) (xy 397.840932 -79.463017) (xy 397.866491 -79.5246)
			(xy 397.88378 -79.588995) (xy 397.892504 -79.655098) (xy 397.893032 -79.688436) (xy 397.89253 -79.720397)
			(xy 397.884519 -79.783815) (xy 397.868622 -79.845729) (xy 397.84509 -79.905162) (xy 397.814296 -79.961177)
			(xy 397.776723 -80.012892) (xy 397.732966 -80.059489) (xy 397.683713 -80.100234) (xy 397.629742 -80.134485)
			(xy 397.571903 -80.161702) (xy 397.51111 -80.181455) (xy 397.44832 -80.193433) (xy 397.384524 -80.197447)
			(xy 397.320728 -80.193433) (xy 397.257938 -80.181455) (xy 397.197145 -80.161702) (xy 397.139306 -80.134485)
			(xy 397.085335 -80.100234) (xy 397.036082 -80.059489) (xy 396.992325 -80.012892) (xy 396.954752 -79.961177)
			(xy 396.923958 -79.905162) (xy 396.900426 -79.845729) (xy 396.884529 -79.783815) (xy 396.876518 -79.720397)
			(xy 396.876016 -79.688436) (xy 379.253949 -79.688436) (xy 377.981347 -81.093494) (xy 398.27606 -81.093494)
			(xy 398.27606 -81.008798) (xy 398.284111 -80.924484) (xy 398.30014 -80.841318) (xy 398.324001 -80.760051)
			(xy 398.35548 -80.681421) (xy 398.394291 -80.60614) (xy 398.440081 -80.534888) (xy 398.492437 -80.468312)
			(xy 398.550885 -80.407014) (xy 398.614895 -80.351549) (xy 398.683887 -80.30242) (xy 398.757237 -80.260071)
			(xy 398.83428 -80.224887) (xy 398.914319 -80.197185) (xy 398.996628 -80.177217) (xy 399.080463 -80.165164)
			(xy 399.165064 -80.161134) (xy 399.249665 -80.165164) (xy 399.3335 -80.177217) (xy 399.415809 -80.197185)
			(xy 399.495848 -80.224887) (xy 399.572891 -80.260071) (xy 399.646241 -80.30242) (xy 399.715233 -80.351549)
			(xy 399.779243 -80.407014) (xy 399.837691 -80.468312) (xy 399.890047 -80.534888) (xy 399.935837 -80.60614)
			(xy 399.974648 -80.681421) (xy 400.006127 -80.760051) (xy 400.029988 -80.841318) (xy 400.046017 -80.924484)
			(xy 400.054068 -81.008798) (xy 400.054572 -81.051146) (xy 400.054068 -81.093494) (xy 400.046017 -81.177808)
			(xy 400.029988 -81.260974) (xy 400.006127 -81.342241) (xy 399.974648 -81.420871) (xy 399.935837 -81.496152)
			(xy 399.890047 -81.567404) (xy 399.837691 -81.63398) (xy 399.779243 -81.695278) (xy 399.715233 -81.750743)
			(xy 399.646241 -81.799872) (xy 399.572891 -81.842221) (xy 399.495848 -81.877405) (xy 399.415809 -81.905107)
			(xy 399.3335 -81.925075) (xy 399.249665 -81.937128) (xy 399.165064 -81.941159) (xy 399.080463 -81.937128)
			(xy 398.996628 -81.925075) (xy 398.914319 -81.905107) (xy 398.83428 -81.877405) (xy 398.757237 -81.842221)
			(xy 398.683887 -81.799872) (xy 398.614895 -81.750743) (xy 398.550885 -81.695278) (xy 398.492437 -81.63398)
			(xy 398.440081 -81.567404) (xy 398.394291 -81.496152) (xy 398.35548 -81.420871) (xy 398.324001 -81.342241)
			(xy 398.30014 -81.260974) (xy 398.284111 -81.177808) (xy 398.27606 -81.093494) (xy 377.981347 -81.093494)
			(xy 350.783746 -111.121909) (xy 369.565422 -111.121909) (xy 369.565422 -111.057987) (xy 369.573433 -110.994569)
			(xy 369.58933 -110.932655) (xy 369.612862 -110.873222) (xy 369.643656 -110.817207) (xy 369.681229 -110.765492)
			(xy 369.724986 -110.718895) (xy 369.774239 -110.67815) (xy 369.82821 -110.643899) (xy 369.886049 -110.616682)
			(xy 369.946842 -110.596929) (xy 370.009632 -110.584951) (xy 370.073428 -110.580938) (xy 370.137224 -110.584951)
			(xy 370.200014 -110.596929) (xy 370.260807 -110.616682) (xy 370.318646 -110.643899) (xy 370.372617 -110.67815)
			(xy 370.42187 -110.718895) (xy 370.465627 -110.765492) (xy 370.5032 -110.817207) (xy 370.533994 -110.873222)
			(xy 370.557526 -110.932655) (xy 370.573423 -110.994569) (xy 370.581434 -111.057987) (xy 370.581936 -111.089948)
			(xy 370.581434 -111.121909) (xy 370.573423 -111.185327) (xy 370.557526 -111.247241) (xy 370.533994 -111.306674)
			(xy 370.5032 -111.362689) (xy 370.465627 -111.414404) (xy 370.42187 -111.461001) (xy 370.372617 -111.501746)
			(xy 370.318646 -111.535997) (xy 370.260807 -111.563214) (xy 370.200014 -111.582967) (xy 370.137224 -111.594945)
			(xy 370.073428 -111.598959) (xy 370.009632 -111.594945) (xy 369.946842 -111.582967) (xy 369.886049 -111.563214)
			(xy 369.82821 -111.535997) (xy 369.774239 -111.501746) (xy 369.724986 -111.461001) (xy 369.681229 -111.414404)
			(xy 369.643656 -111.362689) (xy 369.612862 -111.306674) (xy 369.58933 -111.247241) (xy 369.573433 -111.185327)
			(xy 369.565422 -111.121909) (xy 350.783746 -111.121909) (xy 347.794981 -114.421755) (xy 370.378143 -114.421755)
			(xy 370.378143 -114.367245) (xy 370.385901 -114.31329) (xy 370.401259 -114.260988) (xy 370.423904 -114.211404)
			(xy 370.453376 -114.165548) (xy 370.489074 -114.124354) (xy 370.530271 -114.088659) (xy 370.576129 -114.059191)
			(xy 370.625714 -114.036549) (xy 370.678017 -114.021195) (xy 370.731973 -114.013441) (xy 370.759228 -114.01298)
			(xy 370.789921 -114.01359) (xy 370.850516 -114.023415) (xy 370.908758 -114.042809) (xy 370.963147 -114.071272)
			(xy 370.988082 -114.08918) (xy 370.99621 -114.095276) (xy 371.014752 -114.100356) (xy 371.104414 -114.089434)
			(xy 371.121432 -114.080036) (xy 371.127782 -114.072416) (xy 371.148527 -114.047851) (xy 371.195198 -114.003626)
			(xy 371.247071 -113.965637) (xy 371.30332 -113.934489) (xy 371.363046 -113.910681) (xy 371.425297 -113.894591)
			(xy 371.48908 -113.886477) (xy 371.521228 -113.88598) (xy 371.553187 -113.886508) (xy 371.616601 -113.894522)
			(xy 371.678511 -113.910421) (xy 371.737939 -113.933953) (xy 371.79395 -113.964748) (xy 371.84566 -114.00232)
			(xy 371.892253 -114.046076) (xy 371.932995 -114.095327) (xy 371.967243 -114.149296) (xy 371.994457 -114.207131)
			(xy 372.014208 -114.267922) (xy 372.026185 -114.330708) (xy 372.030199 -114.3945) (xy 372.026185 -114.458292)
			(xy 372.014208 -114.521078) (xy 371.994457 -114.581869) (xy 371.967243 -114.639704) (xy 371.932995 -114.693673)
			(xy 371.892253 -114.742924) (xy 371.84566 -114.78668) (xy 371.79395 -114.824252) (xy 371.737939 -114.855047)
			(xy 371.678511 -114.878579) (xy 371.616601 -114.894478) (xy 371.553187 -114.902492) (xy 371.521228 -114.902996)
			(xy 371.489078 -114.902513) (xy 371.425289 -114.894416) (xy 371.363031 -114.878336) (xy 371.3033 -114.854529)
			(xy 371.247049 -114.823377) (xy 371.195179 -114.785376) (xy 371.148518 -114.741135) (xy 371.127782 -114.71656)
			(xy 371.121432 -114.70894) (xy 371.104414 -114.699542) (xy 371.014752 -114.68862) (xy 370.99621 -114.6937)
			(xy 370.988082 -114.699796) (xy 370.963142 -114.717697) (xy 370.908755 -114.74616) (xy 370.850514 -114.765555)
			(xy 370.789921 -114.775381) (xy 370.759228 -114.775996) (xy 370.731973 -114.775559) (xy 370.678017 -114.767805)
			(xy 370.625714 -114.752451) (xy 370.576129 -114.729809) (xy 370.530271 -114.700341) (xy 370.489074 -114.664646)
			(xy 370.453376 -114.623452) (xy 370.423904 -114.577596) (xy 370.401259 -114.528012) (xy 370.385901 -114.47571)
			(xy 370.378143 -114.421755) (xy 347.794981 -114.421755) (xy 345.978048 -116.4278) (xy 355.217948 -116.4278)
			(xy 355.221962 -116.363999) (xy 355.23394 -116.301204) (xy 355.253695 -116.240405) (xy 355.280914 -116.182562)
			(xy 355.315168 -116.128586) (xy 355.355917 -116.07933) (xy 355.402518 -116.035568) (xy 355.454236 -115.997993)
			(xy 355.510256 -115.967196) (xy 355.569694 -115.943662) (xy 355.631613 -115.927764) (xy 355.695036 -115.919752)
			(xy 355.727 -115.91925) (xy 355.759152 -115.919697) (xy 355.822943 -115.927798) (xy 355.885202 -115.943883)
			(xy 355.944934 -115.967695) (xy 356.001184 -115.998853) (xy 356.053053 -116.03686) (xy 356.099712 -116.081108)
			(xy 356.120446 -116.105686) (xy 356.126796 -116.113306) (xy 356.143814 -116.122704) (xy 356.233476 -116.133626)
			(xy 356.252018 -116.128546) (xy 356.260146 -116.12245) (xy 356.285081 -116.104543) (xy 356.33947 -116.076079)
			(xy 356.397712 -116.056686) (xy 356.458307 -116.046863) (xy 356.489 -116.04625) (xy 356.519462 -116.046842)
			(xy 356.579612 -116.056531) (xy 356.637455 -116.075663) (xy 356.691519 -116.103749) (xy 356.71633 -116.121434)
			(xy 356.724458 -116.127276) (xy 356.743254 -116.132356) (xy 356.832662 -116.120926) (xy 356.84968 -116.111528)
			(xy 356.85603 -116.103908) (xy 356.876763 -116.079103) (xy 356.923501 -116.034434) (xy 356.975521 -115.996046)
			(xy 357.031985 -115.964558) (xy 357.091984 -115.940477) (xy 357.15455 -115.924191) (xy 357.218675 -115.915962)
			(xy 357.251 -115.91544) (xy 357.282964 -115.915846) (xy 357.346388 -115.923858) (xy 357.408308 -115.939756)
			(xy 357.467747 -115.96329) (xy 357.523767 -115.994087) (xy 357.575486 -116.031663) (xy 357.622088 -116.075425)
			(xy 357.650658 -116.109961) (xy 369.442994 -116.109961) (xy 369.442994 -116.046039) (xy 369.451005 -115.982621)
			(xy 369.466902 -115.920707) (xy 369.490434 -115.861274) (xy 369.521228 -115.805259) (xy 369.558801 -115.753544)
			(xy 369.602558 -115.706947) (xy 369.651811 -115.666202) (xy 369.705782 -115.631951) (xy 369.763621 -115.604734)
			(xy 369.824414 -115.584981) (xy 369.887204 -115.573003) (xy 369.951 -115.56899) (xy 370.014796 -115.573003)
			(xy 370.077586 -115.584981) (xy 370.138379 -115.604734) (xy 370.196218 -115.631951) (xy 370.250189 -115.666202)
			(xy 370.299442 -115.706947) (xy 370.343199 -115.753544) (xy 370.380772 -115.805259) (xy 370.411566 -115.861274)
			(xy 370.435098 -115.920707) (xy 370.450995 -115.982621) (xy 370.459006 -116.046039) (xy 370.459508 -116.078)
			(xy 370.459006 -116.109961) (xy 370.450995 -116.173379) (xy 370.435098 -116.235293) (xy 370.411566 -116.294726)
			(xy 370.380772 -116.350741) (xy 370.343199 -116.402456) (xy 370.299442 -116.449053) (xy 370.250189 -116.489798)
			(xy 370.20513 -116.518393) (xy 372.01068 -116.518393) (xy 372.01068 -116.454471) (xy 372.018691 -116.391053)
			(xy 372.034588 -116.329139) (xy 372.05812 -116.269706) (xy 372.088914 -116.213691) (xy 372.126487 -116.161976)
			(xy 372.170244 -116.115379) (xy 372.219497 -116.074634) (xy 372.273468 -116.040383) (xy 372.331307 -116.013166)
			(xy 372.3921 -115.993413) (xy 372.45489 -115.981435) (xy 372.518686 -115.977422) (xy 372.582482 -115.981435)
			(xy 372.645272 -115.993413) (xy 372.706065 -116.013166) (xy 372.763904 -116.040383) (xy 372.817875 -116.074634)
			(xy 372.867128 -116.115379) (xy 372.910885 -116.161976) (xy 372.948458 -116.213691) (xy 372.979252 -116.269706)
			(xy 373.002784 -116.329139) (xy 373.018681 -116.391053) (xy 373.026692 -116.454471) (xy 373.027194 -116.486432)
			(xy 373.026692 -116.518393) (xy 373.018681 -116.581811) (xy 373.002784 -116.643725) (xy 372.979252 -116.703158)
			(xy 372.948458 -116.759173) (xy 372.910885 -116.810888) (xy 372.867128 -116.857485) (xy 372.817875 -116.89823)
			(xy 372.763904 -116.932481) (xy 372.706065 -116.959698) (xy 372.645272 -116.979451) (xy 372.582482 -116.991429)
			(xy 372.518686 -116.995443) (xy 372.45489 -116.991429) (xy 372.3921 -116.979451) (xy 372.331307 -116.959698)
			(xy 372.273468 -116.932481) (xy 372.219497 -116.89823) (xy 372.170244 -116.857485) (xy 372.126487 -116.810888)
			(xy 372.088914 -116.759173) (xy 372.05812 -116.703158) (xy 372.034588 -116.643725) (xy 372.018691 -116.581811)
			(xy 372.01068 -116.518393) (xy 370.20513 -116.518393) (xy 370.196218 -116.524049) (xy 370.138379 -116.551266)
			(xy 370.077586 -116.571019) (xy 370.014796 -116.582997) (xy 369.951 -116.587011) (xy 369.887204 -116.582997)
			(xy 369.824414 -116.571019) (xy 369.763621 -116.551266) (xy 369.705782 -116.524049) (xy 369.651811 -116.489798)
			(xy 369.602558 -116.449053) (xy 369.558801 -116.402456) (xy 369.521228 -116.350741) (xy 369.490434 -116.294726)
			(xy 369.466902 -116.235293) (xy 369.451005 -116.173379) (xy 369.442994 -116.109961) (xy 357.650658 -116.109961)
			(xy 357.662837 -116.124683) (xy 357.697092 -116.178659) (xy 357.724311 -116.236503) (xy 357.744066 -116.297302)
			(xy 357.756045 -116.360098) (xy 357.760059 -116.4239) (xy 357.756045 -116.487702) (xy 357.744066 -116.550498)
			(xy 357.724311 -116.611297) (xy 357.697092 -116.669141) (xy 357.662837 -116.723117) (xy 357.622088 -116.772375)
			(xy 357.575486 -116.816137) (xy 357.523767 -116.853713) (xy 357.467747 -116.88451) (xy 357.408308 -116.908044)
			(xy 357.346388 -116.923942) (xy 357.283391 -116.9319) (xy 357.885038 -116.9319) (xy 357.889051 -116.86811)
			(xy 357.901027 -116.805326) (xy 357.920779 -116.744538) (xy 357.947993 -116.686705) (xy 357.982241 -116.632739)
			(xy 358.022982 -116.583491) (xy 358.069575 -116.539738) (xy 358.121284 -116.502169) (xy 358.177294 -116.471377)
			(xy 358.236722 -116.447848) (xy 358.29863 -116.431953) (xy 358.362042 -116.423942) (xy 358.394 -116.42344)
			(xy 358.426152 -116.42389) (xy 358.489942 -116.431991) (xy 358.552201 -116.448076) (xy 358.611933 -116.471888)
			(xy 358.668183 -116.503045) (xy 358.720052 -116.541052) (xy 358.766712 -116.585299) (xy 358.787446 -116.609876)
			(xy 358.793796 -116.617496) (xy 358.810814 -116.626894) (xy 358.900476 -116.637816) (xy 358.919018 -116.632736)
			(xy 358.927146 -116.62664) (xy 358.94926 -116.610657) (xy 358.997143 -116.5845) (xy 359.048263 -116.565426)
			(xy 359.101577 -116.553823) (xy 359.156 -116.549929) (xy 359.210423 -116.553823) (xy 359.263737 -116.565426)
			(xy 359.314857 -116.5845) (xy 359.36274 -116.610657) (xy 359.384854 -116.62664) (xy 359.392982 -116.632736)
			(xy 359.411524 -116.637816) (xy 359.501186 -116.626894) (xy 359.518204 -116.617496) (xy 359.524554 -116.609876)
			(xy 359.545329 -116.585337) (xy 359.591993 -116.541108) (xy 359.64386 -116.503115) (xy 359.700104 -116.471963)
			(xy 359.759826 -116.448151) (xy 359.822073 -116.432057) (xy 359.885853 -116.423939) (xy 359.918 -116.42344)
			(xy 359.949964 -116.423846) (xy 360.013388 -116.431858) (xy 360.075308 -116.447756) (xy 360.134747 -116.47129)
			(xy 360.190767 -116.502087) (xy 360.242486 -116.539663) (xy 360.289088 -116.583425) (xy 360.329837 -116.632683)
			(xy 360.364092 -116.686659) (xy 360.391311 -116.744503) (xy 360.411066 -116.805302) (xy 360.423045 -116.868098)
			(xy 360.427059 -116.9319) (xy 360.423045 -116.995702) (xy 360.411066 -117.058498) (xy 360.391311 -117.119297)
			(xy 360.364092 -117.177141) (xy 360.329837 -117.231117) (xy 360.289088 -117.280375) (xy 360.242486 -117.324137)
			(xy 360.190767 -117.361713) (xy 360.134747 -117.39251) (xy 360.075308 -117.416044) (xy 360.013388 -117.431942)
			(xy 359.949964 -117.439954) (xy 359.918 -117.440456) (xy 359.885848 -117.440007) (xy 359.822057 -117.431906)
			(xy 359.759799 -117.415821) (xy 359.700067 -117.392009) (xy 359.643817 -117.360851) (xy 359.591947 -117.322845)
			(xy 359.545288 -117.278598) (xy 359.524554 -117.25402) (xy 359.518204 -117.2464) (xy 359.501186 -117.237002)
			(xy 359.411524 -117.22608) (xy 359.392982 -117.23116) (xy 359.384854 -117.237256) (xy 359.36274 -117.253239)
			(xy 359.314857 -117.279396) (xy 359.263737 -117.29847) (xy 359.210423 -117.310073) (xy 359.156 -117.313967)
			(xy 359.101577 -117.310073) (xy 359.048263 -117.29847) (xy 358.997143 -117.279396) (xy 358.94926 -117.253239)
			(xy 358.927146 -117.237256) (xy 358.919018 -117.23116) (xy 358.900476 -117.22608) (xy 358.810814 -117.237002)
			(xy 358.793796 -117.2464) (xy 358.787446 -117.25402) (xy 358.76667 -117.278558) (xy 358.720007 -117.322787)
			(xy 358.668139 -117.360781) (xy 358.611896 -117.391933) (xy 358.552174 -117.415745) (xy 358.489927 -117.431839)
			(xy 358.426147 -117.439957) (xy 358.394 -117.440456) (xy 358.362042 -117.439858) (xy 358.29863 -117.431847)
			(xy 358.236722 -117.415952) (xy 358.177294 -117.392423) (xy 358.121284 -117.361631) (xy 358.069575 -117.324062)
			(xy 358.022982 -117.280309) (xy 357.982241 -117.231061) (xy 357.947993 -117.177095) (xy 357.920779 -117.119262)
			(xy 357.901027 -117.058474) (xy 357.889051 -116.99569) (xy 357.885038 -116.9319) (xy 357.283391 -116.9319)
			(xy 357.282964 -116.931954) (xy 357.251 -116.932456) (xy 357.219031 -116.931964) (xy 357.155599 -116.923942)
			(xy 357.093671 -116.908036) (xy 357.034224 -116.884498) (xy 356.978193 -116.853698) (xy 356.926463 -116.816122)
			(xy 356.879847 -116.77236) (xy 356.859078 -116.748052) (xy 356.852728 -116.740178) (xy 356.83571 -116.731034)
			(xy 356.746048 -116.72062) (xy 356.727506 -116.7257) (xy 356.719378 -116.731796) (xy 356.694359 -116.750009)
			(xy 356.639662 -116.778947) (xy 356.581009 -116.798671) (xy 356.51994 -116.808664) (xy 356.489 -116.809266)
			(xy 356.458307 -116.808652) (xy 356.397712 -116.79883) (xy 356.339469 -116.779437) (xy 356.28508 -116.750975)
			(xy 356.260146 -116.733066) (xy 356.252018 -116.72697) (xy 356.233476 -116.72189) (xy 356.143814 -116.732812)
			(xy 356.126796 -116.74221) (xy 356.120446 -116.74983) (xy 356.099673 -116.77437) (xy 356.053008 -116.818599)
			(xy 356.00114 -116.856592) (xy 355.944897 -116.887743) (xy 355.885175 -116.911556) (xy 355.822927 -116.927649)
			(xy 355.759147 -116.935767) (xy 355.727 -116.936266) (xy 355.695036 -116.935848) (xy 355.631613 -116.927836)
			(xy 355.569694 -116.911938) (xy 355.510256 -116.888404) (xy 355.454236 -116.857607) (xy 355.402518 -116.820032)
			(xy 355.355917 -116.77627) (xy 355.315168 -116.727014) (xy 355.280914 -116.673038) (xy 355.253695 -116.615195)
			(xy 355.23394 -116.554396) (xy 355.221962 -116.491601) (xy 355.217948 -116.4278) (xy 345.978048 -116.4278)
			(xy 344.430084 -118.136881) (xy 379.828038 -118.136881) (xy 379.828038 -118.072959) (xy 379.836049 -118.009541)
			(xy 379.851946 -117.947627) (xy 379.875478 -117.888194) (xy 379.906272 -117.832179) (xy 379.943845 -117.780464)
			(xy 379.987602 -117.733867) (xy 380.036855 -117.693122) (xy 380.090826 -117.658871) (xy 380.148665 -117.631654)
			(xy 380.209458 -117.611901) (xy 380.272248 -117.599923) (xy 380.336044 -117.59591) (xy 380.39984 -117.599923)
			(xy 380.46263 -117.611901) (xy 380.523423 -117.631654) (xy 380.581262 -117.658871) (xy 380.635233 -117.693122)
			(xy 380.684486 -117.733867) (xy 380.728243 -117.780464) (xy 380.765816 -117.832179) (xy 380.79661 -117.888194)
			(xy 380.820142 -117.947627) (xy 380.836039 -118.009541) (xy 380.84405 -118.072959) (xy 380.844396 -118.094971)
			(xy 381.453384 -118.094971) (xy 381.453384 -118.031049) (xy 381.461395 -117.967631) (xy 381.477292 -117.905717)
			(xy 381.500824 -117.846284) (xy 381.531618 -117.790269) (xy 381.569191 -117.738554) (xy 381.612948 -117.691957)
			(xy 381.662201 -117.651212) (xy 381.716172 -117.616961) (xy 381.774011 -117.589744) (xy 381.834804 -117.569991)
			(xy 381.897594 -117.558013) (xy 381.96139 -117.554) (xy 382.025186 -117.558013) (xy 382.087976 -117.569991)
			(xy 382.148769 -117.589744) (xy 382.206608 -117.616961) (xy 382.260579 -117.651212) (xy 382.309832 -117.691957)
			(xy 382.353589 -117.738554) (xy 382.391162 -117.790269) (xy 382.421956 -117.846284) (xy 382.445488 -117.905717)
			(xy 382.461385 -117.967631) (xy 382.469396 -118.031049) (xy 382.469898 -118.06301) (xy 382.469396 -118.094971)
			(xy 382.461385 -118.158389) (xy 382.445488 -118.220303) (xy 382.421956 -118.279736) (xy 382.391162 -118.335751)
			(xy 382.353589 -118.387466) (xy 382.309832 -118.434063) (xy 382.260579 -118.474808) (xy 382.206608 -118.509059)
			(xy 382.148769 -118.536276) (xy 382.087976 -118.556029) (xy 382.025186 -118.568007) (xy 381.96139 -118.572021)
			(xy 381.897594 -118.568007) (xy 381.834804 -118.556029) (xy 381.774011 -118.536276) (xy 381.716172 -118.509059)
			(xy 381.662201 -118.474808) (xy 381.612948 -118.434063) (xy 381.569191 -118.387466) (xy 381.531618 -118.335751)
			(xy 381.500824 -118.279736) (xy 381.477292 -118.220303) (xy 381.461395 -118.158389) (xy 381.453384 -118.094971)
			(xy 380.844396 -118.094971) (xy 380.844552 -118.10492) (xy 380.84405 -118.136881) (xy 380.836039 -118.200299)
			(xy 380.820142 -118.262213) (xy 380.79661 -118.321646) (xy 380.765816 -118.377661) (xy 380.728243 -118.429376)
			(xy 380.684486 -118.475973) (xy 380.635233 -118.516718) (xy 380.581262 -118.550969) (xy 380.523423 -118.578186)
			(xy 380.46263 -118.597939) (xy 380.39984 -118.609917) (xy 380.336044 -118.613931) (xy 380.272248 -118.609917)
			(xy 380.209458 -118.597939) (xy 380.148665 -118.578186) (xy 380.090826 -118.550969) (xy 380.036855 -118.516718)
			(xy 379.987602 -118.475973) (xy 379.943845 -118.429376) (xy 379.906272 -118.377661) (xy 379.875478 -118.321646)
			(xy 379.851946 -118.262213) (xy 379.836049 -118.200299) (xy 379.828038 -118.136881) (xy 344.430084 -118.136881)
			(xy 343.949959 -118.666979) (xy 389.27633 -118.666979) (xy 389.27633 -118.603057) (xy 389.284341 -118.539639)
			(xy 389.300238 -118.477725) (xy 389.32377 -118.418292) (xy 389.354564 -118.362277) (xy 389.392137 -118.310562)
			(xy 389.435894 -118.263965) (xy 389.485147 -118.22322) (xy 389.539118 -118.188969) (xy 389.596957 -118.161752)
			(xy 389.65775 -118.141999) (xy 389.72054 -118.130021) (xy 389.784336 -118.126008) (xy 389.848132 -118.130021)
			(xy 389.910922 -118.141999) (xy 389.971715 -118.161752) (xy 390.029554 -118.188969) (xy 390.083525 -118.22322)
			(xy 390.132778 -118.263965) (xy 390.176535 -118.310562) (xy 390.214108 -118.362277) (xy 390.244902 -118.418292)
			(xy 390.268434 -118.477725) (xy 390.284331 -118.539639) (xy 390.292342 -118.603057) (xy 390.292844 -118.635018)
			(xy 390.292342 -118.666979) (xy 390.284331 -118.730397) (xy 390.268434 -118.792311) (xy 390.244902 -118.851744)
			(xy 390.214108 -118.907759) (xy 390.176535 -118.959474) (xy 390.132778 -119.006071) (xy 390.083525 -119.046816)
			(xy 390.029554 -119.081067) (xy 389.971715 -119.108284) (xy 389.910922 -119.128037) (xy 389.848132 -119.140015)
			(xy 389.784336 -119.144029) (xy 389.72054 -119.140015) (xy 389.65775 -119.128037) (xy 389.596957 -119.108284)
			(xy 389.539118 -119.081067) (xy 389.485147 -119.046816) (xy 389.435894 -119.006071) (xy 389.392137 -118.959474)
			(xy 389.354564 -118.907759) (xy 389.32377 -118.851744) (xy 389.300238 -118.792311) (xy 389.284341 -118.730397)
			(xy 389.27633 -118.666979) (xy 343.949959 -118.666979) (xy 343.128892 -119.573505) (xy 382.00939 -119.573505)
			(xy 382.00939 -119.509583) (xy 382.017401 -119.446165) (xy 382.033298 -119.384251) (xy 382.05683 -119.324818)
			(xy 382.087624 -119.268803) (xy 382.125197 -119.217088) (xy 382.168954 -119.170491) (xy 382.218207 -119.129746)
			(xy 382.272178 -119.095495) (xy 382.330017 -119.068278) (xy 382.39081 -119.048525) (xy 382.4536 -119.036547)
			(xy 382.517396 -119.032534) (xy 382.581192 -119.036547) (xy 382.643982 -119.048525) (xy 382.704775 -119.068278)
			(xy 382.762614 -119.095495) (xy 382.816585 -119.129746) (xy 382.865838 -119.170491) (xy 382.909595 -119.217088)
			(xy 382.947168 -119.268803) (xy 382.977962 -119.324818) (xy 383.001494 -119.384251) (xy 383.017391 -119.446165)
			(xy 383.025402 -119.509583) (xy 383.025904 -119.541544) (xy 383.025402 -119.573505) (xy 383.017391 -119.636923)
			(xy 383.001494 -119.698837) (xy 382.977962 -119.75827) (xy 382.947168 -119.814285) (xy 382.909595 -119.866)
			(xy 382.865838 -119.912597) (xy 382.816585 -119.953342) (xy 382.762614 -119.987593) (xy 382.704775 -120.01481)
			(xy 382.643982 -120.034563) (xy 382.581192 -120.046541) (xy 382.517396 -120.050555) (xy 382.4536 -120.046541)
			(xy 382.39081 -120.034563) (xy 382.330017 -120.01481) (xy 382.272178 -119.987593) (xy 382.218207 -119.953342)
			(xy 382.168954 -119.912597) (xy 382.125197 -119.866) (xy 382.087624 -119.814285) (xy 382.05683 -119.75827)
			(xy 382.033298 -119.698837) (xy 382.017401 -119.636923) (xy 382.00939 -119.573505) (xy 343.128892 -119.573505)
			(xy 342.515565 -120.250669) (xy 379.395222 -120.250669) (xy 379.395222 -120.186747) (xy 379.403233 -120.123329)
			(xy 379.41913 -120.061415) (xy 379.442662 -120.001982) (xy 379.473456 -119.945967) (xy 379.511029 -119.894252)
			(xy 379.554786 -119.847655) (xy 379.604039 -119.80691) (xy 379.65801 -119.772659) (xy 379.715849 -119.745442)
			(xy 379.776642 -119.725689) (xy 379.839432 -119.713711) (xy 379.903228 -119.709698) (xy 379.967024 -119.713711)
			(xy 380.029814 -119.725689) (xy 380.090607 -119.745442) (xy 380.148446 -119.772659) (xy 380.202417 -119.80691)
			(xy 380.25167 -119.847655) (xy 380.295427 -119.894252) (xy 380.333 -119.945967) (xy 380.363794 -120.001982)
			(xy 380.387326 -120.061415) (xy 380.403223 -120.123329) (xy 380.411234 -120.186747) (xy 380.411736 -120.218708)
			(xy 380.411234 -120.250669) (xy 380.403223 -120.314087) (xy 380.387326 -120.376001) (xy 380.363794 -120.435434)
			(xy 380.333 -120.491449) (xy 380.295427 -120.543164) (xy 380.25167 -120.589761) (xy 380.202417 -120.630506)
			(xy 380.148446 -120.664757) (xy 380.090607 -120.691974) (xy 380.029814 -120.711727) (xy 379.967024 -120.723705)
			(xy 379.903228 -120.727719) (xy 379.839432 -120.723705) (xy 379.776642 -120.711727) (xy 379.715849 -120.691974)
			(xy 379.65801 -120.664757) (xy 379.604039 -120.630506) (xy 379.554786 -120.589761) (xy 379.511029 -120.543164)
			(xy 379.473456 -120.491449) (xy 379.442662 -120.435434) (xy 379.41913 -120.376001) (xy 379.403233 -120.314087)
			(xy 379.395222 -120.250669) (xy 342.515565 -120.250669) (xy 341.155249 -121.752571) (xy 385.348474 -121.752571)
			(xy 385.348474 -121.688649) (xy 385.356485 -121.625231) (xy 385.372382 -121.563317) (xy 385.395914 -121.503884)
			(xy 385.426708 -121.447869) (xy 385.464281 -121.396154) (xy 385.508038 -121.349557) (xy 385.557291 -121.308812)
			(xy 385.611262 -121.274561) (xy 385.669101 -121.247344) (xy 385.729894 -121.227591) (xy 385.792684 -121.215613)
			(xy 385.85648 -121.2116) (xy 385.920276 -121.215613) (xy 385.983066 -121.227591) (xy 386.043859 -121.247344)
			(xy 386.101698 -121.274561) (xy 386.155669 -121.308812) (xy 386.204922 -121.349557) (xy 386.248679 -121.396154)
			(xy 386.286252 -121.447869) (xy 386.317046 -121.503884) (xy 386.340578 -121.563317) (xy 386.356475 -121.625231)
			(xy 386.364486 -121.688649) (xy 386.364884 -121.713963) (xy 393.99311 -121.713963) (xy 393.99311 -121.650041)
			(xy 394.001121 -121.586623) (xy 394.017018 -121.524709) (xy 394.04055 -121.465276) (xy 394.071344 -121.409261)
			(xy 394.108917 -121.357546) (xy 394.152674 -121.310949) (xy 394.201927 -121.270204) (xy 394.255898 -121.235953)
			(xy 394.313737 -121.208736) (xy 394.37453 -121.188983) (xy 394.43732 -121.177005) (xy 394.501116 -121.172992)
			(xy 394.564912 -121.177005) (xy 394.627702 -121.188983) (xy 394.688495 -121.208736) (xy 394.746334 -121.235953)
			(xy 394.800305 -121.270204) (xy 394.849558 -121.310949) (xy 394.893315 -121.357546) (xy 394.930888 -121.409261)
			(xy 394.961682 -121.465276) (xy 394.985214 -121.524709) (xy 395.001111 -121.586623) (xy 395.009122 -121.650041)
			(xy 395.009624 -121.682002) (xy 395.009122 -121.713963) (xy 395.001111 -121.777381) (xy 394.985214 -121.839295)
			(xy 394.961682 -121.898728) (xy 394.930888 -121.954743) (xy 394.893315 -122.006458) (xy 394.849558 -122.053055)
			(xy 394.800305 -122.0938) (xy 394.746334 -122.128051) (xy 394.688495 -122.155268) (xy 394.627702 -122.175021)
			(xy 394.564912 -122.186999) (xy 394.501116 -122.191013) (xy 394.43732 -122.186999) (xy 394.37453 -122.175021)
			(xy 394.313737 -122.155268) (xy 394.255898 -122.128051) (xy 394.201927 -122.0938) (xy 394.152674 -122.053055)
			(xy 394.108917 -122.006458) (xy 394.071344 -121.954743) (xy 394.04055 -121.898728) (xy 394.017018 -121.839295)
			(xy 394.001121 -121.777381) (xy 393.99311 -121.713963) (xy 386.364884 -121.713963) (xy 386.364988 -121.72061)
			(xy 386.364486 -121.752571) (xy 386.356475 -121.815989) (xy 386.340578 -121.877903) (xy 386.317046 -121.937336)
			(xy 386.286252 -121.993351) (xy 386.248679 -122.045066) (xy 386.204922 -122.091663) (xy 386.155669 -122.132408)
			(xy 386.101698 -122.166659) (xy 386.043859 -122.193876) (xy 385.983066 -122.213629) (xy 385.920276 -122.225607)
			(xy 385.85648 -122.229621) (xy 385.792684 -122.225607) (xy 385.729894 -122.213629) (xy 385.669101 -122.193876)
			(xy 385.611262 -122.166659) (xy 385.557291 -122.132408) (xy 385.508038 -122.091663) (xy 385.464281 -122.045066)
			(xy 385.426708 -121.993351) (xy 385.395914 -121.937336) (xy 385.372382 -121.877903) (xy 385.356485 -121.815989)
			(xy 385.348474 -121.752571) (xy 341.155249 -121.752571) (xy 339.69739 -123.362169) (xy 348.452942 -123.362169)
			(xy 348.452942 -123.298247) (xy 348.460953 -123.234829) (xy 348.47685 -123.172915) (xy 348.500382 -123.113482)
			(xy 348.531176 -123.057467) (xy 348.568749 -123.005752) (xy 348.612506 -122.959155) (xy 348.661759 -122.91841)
			(xy 348.71573 -122.884159) (xy 348.773569 -122.856942) (xy 348.834362 -122.837189) (xy 348.897152 -122.825211)
			(xy 348.960948 -122.821198) (xy 349.024744 -122.825211) (xy 349.087534 -122.837189) (xy 349.148327 -122.856942)
			(xy 349.206166 -122.884159) (xy 349.260137 -122.91841) (xy 349.30939 -122.959155) (xy 349.353147 -123.005752)
			(xy 349.39072 -123.057467) (xy 349.421514 -123.113482) (xy 349.445046 -123.172915) (xy 349.460943 -123.234829)
			(xy 349.468954 -123.298247) (xy 349.469456 -123.330208) (xy 349.469028 -123.357454) (xy 349.595863 -123.357454)
			(xy 349.595863 -123.302946) (xy 349.603622 -123.248992) (xy 349.61898 -123.196691) (xy 349.641625 -123.147109)
			(xy 349.671097 -123.101254) (xy 349.706795 -123.060061) (xy 349.747993 -123.024368) (xy 349.793851 -122.994902)
			(xy 349.843436 -122.972263) (xy 349.895738 -122.956911) (xy 349.949693 -122.94916) (xy 349.976948 -122.9487)
			(xy 350.00579 -122.949224) (xy 350.062816 -122.957908) (xy 350.117886 -122.975072) (xy 350.169748 -123.000325)
			(xy 350.217222 -123.033092) (xy 350.259226 -123.072627) (xy 350.27743 -123.095004) (xy 350.28671 -123.105886)
			(xy 350.30991 -123.122577) (xy 350.336825 -123.13219) (xy 350.36535 -123.133974) (xy 350.393252 -123.127787)
			(xy 350.41835 -123.114115) (xy 350.43868 -123.094027) (xy 350.446086 -123.081796) (xy 350.463041 -123.052608)
			(xy 350.503456 -122.998542) (xy 350.550668 -122.950299) (xy 350.603848 -122.908726) (xy 350.662061 -122.874554)
			(xy 350.724283 -122.848385) (xy 350.78942 -122.830678) (xy 350.856327 -122.821744) (xy 350.890078 -122.821192)
			(xy 350.922041 -122.821672) (xy 350.985464 -122.829681) (xy 351.047383 -122.845577) (xy 351.106821 -122.869108)
			(xy 351.162841 -122.899903) (xy 351.169857 -122.905) (xy 383.51788 -122.905) (xy 383.521894 -122.841202)
			(xy 383.533873 -122.778409) (xy 383.553627 -122.717613) (xy 383.580846 -122.659773) (xy 383.615099 -122.6058)
			(xy 383.655847 -122.556546) (xy 383.702447 -122.512787) (xy 383.754163 -122.475214) (xy 383.810182 -122.44442)
			(xy 383.869618 -122.420889) (xy 383.931535 -122.404994) (xy 383.994956 -122.396984) (xy 384.026918 -122.396504)
			(xy 384.059041 -122.396986) (xy 384.122777 -122.405063) (xy 384.184987 -122.421109) (xy 384.244677 -122.44487)
			(xy 384.300896 -122.475965) (xy 384.352746 -122.5139) (xy 384.399401 -122.558069) (xy 384.440115 -122.607767)
			(xy 384.47424 -122.6622) (xy 384.488182 -122.691144) (xy 384.494714 -122.704256) (xy 384.514021 -122.726275)
			(xy 384.53878 -122.741913) (xy 384.566959 -122.749886) (xy 384.596241 -122.749539) (xy 384.624223 -122.740899)
			(xy 384.648604 -122.724677) (xy 384.658362 -122.71375) (xy 384.679074 -122.689751) (xy 384.725545 -122.646629)
			(xy 384.777017 -122.609621) (xy 384.832693 -122.579302) (xy 384.891706 -122.556143) (xy 384.953142 -122.540502)
			(xy 385.016046 -122.532623) (xy 385.047744 -122.53214) (xy 385.079706 -122.532548) (xy 385.143126 -122.540565)
			(xy 385.205041 -122.556467) (xy 385.264475 -122.580003) (xy 385.320491 -122.610802) (xy 385.372205 -122.648379)
			(xy 385.418803 -122.692141) (xy 385.459548 -122.741397) (xy 385.493799 -122.795371) (xy 385.521015 -122.853213)
			(xy 385.540768 -122.914009) (xy 385.552745 -122.976801) (xy 385.556759 -123.0406) (xy 385.552745 -123.104399)
			(xy 385.540768 -123.167191) (xy 385.521015 -123.227987) (xy 385.493799 -123.285829) (xy 385.459548 -123.339803)
			(xy 385.418803 -123.389059) (xy 385.372205 -123.432821) (xy 385.320491 -123.470398) (xy 385.264475 -123.501197)
			(xy 385.205041 -123.524733) (xy 385.143126 -123.540635) (xy 385.079706 -123.548652) (xy 385.047744 -123.549156)
			(xy 385.015619 -123.548729) (xy 384.95188 -123.540647) (xy 384.889668 -123.524595) (xy 384.829976 -123.500828)
			(xy 384.773756 -123.469725) (xy 384.721906 -123.431783) (xy 384.675253 -123.387608) (xy 384.634541 -123.337903)
			(xy 384.60042 -123.283463) (xy 384.58648 -123.254516) (xy 384.579864 -123.241453) (xy 384.56057 -123.219447)
			(xy 384.535827 -123.203815) (xy 384.507668 -123.19584) (xy 384.478403 -123.196177) (xy 384.450435 -123.204798)
			(xy 384.426059 -123.220996) (xy 384.4163 -123.23191) (xy 384.395545 -123.25587) (xy 384.349083 -123.298996)
			(xy 384.297619 -123.336009) (xy 384.241951 -123.366333) (xy 384.182943 -123.389499) (xy 384.121513 -123.405147)
			(xy 384.058614 -123.413033) (xy 384.026918 -123.41352) (xy 383.994956 -123.413016) (xy 383.931535 -123.405006)
			(xy 383.869618 -123.389111) (xy 383.810182 -123.36558) (xy 383.754163 -123.334786) (xy 383.702447 -123.297213)
			(xy 383.655847 -123.253454) (xy 383.615099 -123.2042) (xy 383.580846 -123.150227) (xy 383.553627 -123.092387)
			(xy 383.533873 -123.031591) (xy 383.521894 -122.968798) (xy 383.51788 -122.905) (xy 351.169857 -122.905)
			(xy 351.214559 -122.937477) (xy 351.261161 -122.981236) (xy 351.30191 -123.030492) (xy 351.336164 -123.084466)
			(xy 351.363384 -123.142308) (xy 351.383138 -123.203106) (xy 351.395117 -123.2659) (xy 351.399132 -123.3297)
			(xy 351.395117 -123.3935) (xy 351.383138 -123.456294) (xy 351.363384 -123.517092) (xy 351.336164 -123.574934)
			(xy 351.30191 -123.628908) (xy 351.261161 -123.678164) (xy 351.214559 -123.721923) (xy 351.162841 -123.759497)
			(xy 351.106821 -123.790292) (xy 351.047383 -123.813823) (xy 350.985464 -123.829719) (xy 350.922041 -123.837728)
			(xy 350.890078 -123.838208) (xy 350.85636 -123.837678) (xy 350.789514 -123.828773) (xy 350.724432 -123.81111)
			(xy 350.662257 -123.784998) (xy 350.604079 -123.750895) (xy 350.55092 -123.709401) (xy 350.503713 -123.661243)
			(xy 350.463287 -123.607267) (xy 350.44634 -123.578112) (xy 350.438925 -123.565871) (xy 350.41858 -123.545761)
			(xy 350.393454 -123.532086) (xy 350.365521 -123.52592) (xy 350.336973 -123.527746) (xy 350.310053 -123.537422)
			(xy 350.286874 -123.554188) (xy 350.277684 -123.565158) (xy 350.25947 -123.587566) (xy 350.217445 -123.627168)
			(xy 350.169937 -123.659991) (xy 350.118029 -123.685288) (xy 350.062905 -123.702483) (xy 350.00582 -123.711183)
			(xy 349.976948 -123.711716) (xy 349.949693 -123.71124) (xy 349.895738 -123.703489) (xy 349.843436 -123.688137)
			(xy 349.793851 -123.665498) (xy 349.747993 -123.636032) (xy 349.706795 -123.600339) (xy 349.671097 -123.559146)
			(xy 349.641625 -123.513291) (xy 349.61898 -123.463709) (xy 349.603622 -123.411408) (xy 349.595863 -123.357454)
			(xy 349.469028 -123.357454) (xy 349.468954 -123.362169) (xy 349.460943 -123.425587) (xy 349.445046 -123.487501)
			(xy 349.421514 -123.546934) (xy 349.39072 -123.602949) (xy 349.353147 -123.654664) (xy 349.30939 -123.701261)
			(xy 349.260137 -123.742006) (xy 349.206166 -123.776257) (xy 349.148327 -123.803474) (xy 349.087534 -123.823227)
			(xy 349.024744 -123.835205) (xy 348.960948 -123.839219) (xy 348.897152 -123.835205) (xy 348.834362 -123.823227)
			(xy 348.773569 -123.803474) (xy 348.71573 -123.776257) (xy 348.661759 -123.742006) (xy 348.612506 -123.701261)
			(xy 348.568749 -123.654664) (xy 348.531176 -123.602949) (xy 348.500382 -123.546934) (xy 348.47685 -123.487501)
			(xy 348.460953 -123.425587) (xy 348.452942 -123.362169) (xy 339.69739 -123.362169) (xy 339.259351 -123.8458)
			(xy 371.701296 -123.8458) (xy 371.70531 -123.782003) (xy 371.717289 -123.719211) (xy 371.737043 -123.658417)
			(xy 371.764261 -123.600577) (xy 371.798515 -123.546606) (xy 371.839262 -123.497353) (xy 371.885862 -123.453595)
			(xy 371.937579 -123.416024) (xy 371.993596 -123.385231) (xy 372.053032 -123.361701) (xy 372.114948 -123.345807)
			(xy 372.178368 -123.337799) (xy 372.21033 -123.33732) (xy 372.24248 -123.337827) (xy 372.306268 -123.345919)
			(xy 372.368525 -123.361995) (xy 372.428257 -123.385797) (xy 372.484507 -123.416946) (xy 372.536378 -123.454944)
			(xy 372.58304 -123.499182) (xy 372.603776 -123.523756) (xy 372.610126 -123.531376) (xy 372.627144 -123.540774)
			(xy 372.716806 -123.551696) (xy 372.735348 -123.546616) (xy 372.743476 -123.54052) (xy 372.76559 -123.524537)
			(xy 372.813473 -123.49838) (xy 372.864593 -123.479306) (xy 372.917907 -123.467703) (xy 372.97233 -123.463809)
			(xy 373.026753 -123.467703) (xy 373.080067 -123.479306) (xy 373.131187 -123.49838) (xy 373.17907 -123.524537)
			(xy 373.201184 -123.54052) (xy 373.209312 -123.546616) (xy 373.227854 -123.551696) (xy 373.317516 -123.540774)
			(xy 373.334534 -123.531376) (xy 373.340884 -123.523756) (xy 373.361637 -123.499199) (xy 373.408306 -123.454971)
			(xy 373.460177 -123.41698) (xy 373.516424 -123.385831) (xy 373.57615 -123.362022) (xy 373.6384 -123.345931)
			(xy 373.702182 -123.337817) (xy 373.73433 -123.33732) (xy 373.766292 -123.337768) (xy 373.82971 -123.345783)
			(xy 373.891624 -123.361683) (xy 373.951058 -123.385217) (xy 374.007073 -123.416015) (xy 374.058786 -123.45359)
			(xy 374.105383 -123.49735) (xy 374.146128 -123.546604) (xy 374.180378 -123.600577) (xy 374.207595 -123.658417)
			(xy 374.227347 -123.719212) (xy 374.239325 -123.782003) (xy 374.243339 -123.8458) (xy 374.241326 -123.877789)
			(xy 376.528324 -123.877789) (xy 376.528324 -123.813867) (xy 376.536335 -123.750449) (xy 376.552232 -123.688535)
			(xy 376.575764 -123.629102) (xy 376.606558 -123.573087) (xy 376.644131 -123.521372) (xy 376.687888 -123.474775)
			(xy 376.737141 -123.43403) (xy 376.791112 -123.399779) (xy 376.848951 -123.372562) (xy 376.909744 -123.352809)
			(xy 376.972534 -123.340831) (xy 377.03633 -123.336818) (xy 377.100126 -123.340831) (xy 377.162916 -123.352809)
			(xy 377.223709 -123.372562) (xy 377.281548 -123.399779) (xy 377.335519 -123.43403) (xy 377.384772 -123.474775)
			(xy 377.428529 -123.521372) (xy 377.466102 -123.573087) (xy 377.496896 -123.629102) (xy 377.520428 -123.688535)
			(xy 377.536325 -123.750449) (xy 377.544336 -123.813867) (xy 377.544838 -123.845828) (xy 377.544336 -123.877789)
			(xy 377.536325 -123.941207) (xy 377.520428 -124.003121) (xy 377.496896 -124.062554) (xy 377.480897 -124.091657)
			(xy 380.429002 -124.091657) (xy 380.429002 -124.027735) (xy 380.437013 -123.964317) (xy 380.45291 -123.902403)
			(xy 380.476442 -123.84297) (xy 380.507236 -123.786955) (xy 380.544809 -123.73524) (xy 380.588566 -123.688643)
			(xy 380.637819 -123.647898) (xy 380.69179 -123.613647) (xy 380.749629 -123.58643) (xy 380.810422 -123.566677)
			(xy 380.873212 -123.554699) (xy 380.937008 -123.550686) (xy 381.000804 -123.554699) (xy 381.063594 -123.566677)
			(xy 381.124387 -123.58643) (xy 381.182226 -123.613647) (xy 381.236197 -123.647898) (xy 381.271225 -123.676875)
			(xy 395.274286 -123.676875) (xy 395.274286 -123.612953) (xy 395.282297 -123.549535) (xy 395.298194 -123.487621)
			(xy 395.321726 -123.428188) (xy 395.35252 -123.372173) (xy 395.390093 -123.320458) (xy 395.43385 -123.273861)
			(xy 395.483103 -123.233116) (xy 395.537074 -123.198865) (xy 395.594913 -123.171648) (xy 395.655706 -123.151895)
			(xy 395.718496 -123.139917) (xy 395.782292 -123.135904) (xy 395.846088 -123.139917) (xy 395.908878 -123.151895)
			(xy 395.969671 -123.171648) (xy 396.02751 -123.198865) (xy 396.081481 -123.233116) (xy 396.130734 -123.273861)
			(xy 396.174491 -123.320458) (xy 396.212064 -123.372173) (xy 396.242858 -123.428188) (xy 396.26639 -123.487621)
			(xy 396.282287 -123.549535) (xy 396.290298 -123.612953) (xy 396.2908 -123.644914) (xy 396.290298 -123.676875)
			(xy 396.282287 -123.740293) (xy 396.26639 -123.802207) (xy 396.242858 -123.86164) (xy 396.212064 -123.917655)
			(xy 396.174491 -123.96937) (xy 396.130734 -124.015967) (xy 396.081481 -124.056712) (xy 396.02751 -124.090963)
			(xy 395.969671 -124.11818) (xy 395.908878 -124.137933) (xy 395.846088 -124.149911) (xy 395.782292 -124.153925)
			(xy 395.718496 -124.149911) (xy 395.655706 -124.137933) (xy 395.594913 -124.11818) (xy 395.537074 -124.090963)
			(xy 395.483103 -124.056712) (xy 395.43385 -124.015967) (xy 395.390093 -123.96937) (xy 395.35252 -123.917655)
			(xy 395.321726 -123.86164) (xy 395.298194 -123.802207) (xy 395.282297 -123.740293) (xy 395.274286 -123.676875)
			(xy 381.271225 -123.676875) (xy 381.28545 -123.688643) (xy 381.329207 -123.73524) (xy 381.36678 -123.786955)
			(xy 381.397574 -123.84297) (xy 381.421106 -123.902403) (xy 381.437003 -123.964317) (xy 381.445014 -124.027735)
			(xy 381.445516 -124.059696) (xy 381.445014 -124.091657) (xy 381.437003 -124.155075) (xy 381.421106 -124.216989)
			(xy 381.397574 -124.276422) (xy 381.36678 -124.332437) (xy 381.329207 -124.384152) (xy 381.28545 -124.430749)
			(xy 381.236197 -124.471494) (xy 381.182226 -124.505745) (xy 381.124387 -124.532962) (xy 381.063594 -124.552715)
			(xy 381.000804 -124.564693) (xy 380.937008 -124.568707) (xy 380.873212 -124.564693) (xy 380.810422 -124.552715)
			(xy 380.749629 -124.532962) (xy 380.69179 -124.505745) (xy 380.637819 -124.471494) (xy 380.588566 -124.430749)
			(xy 380.544809 -124.384152) (xy 380.507236 -124.332437) (xy 380.476442 -124.276422) (xy 380.45291 -124.216989)
			(xy 380.437013 -124.155075) (xy 380.429002 -124.091657) (xy 377.480897 -124.091657) (xy 377.466102 -124.118569)
			(xy 377.428529 -124.170284) (xy 377.384772 -124.216881) (xy 377.335519 -124.257626) (xy 377.281548 -124.291877)
			(xy 377.223709 -124.319094) (xy 377.162916 -124.338847) (xy 377.100126 -124.350825) (xy 377.03633 -124.354839)
			(xy 376.972534 -124.350825) (xy 376.909744 -124.338847) (xy 376.848951 -124.319094) (xy 376.791112 -124.291877)
			(xy 376.737141 -124.257626) (xy 376.687888 -124.216881) (xy 376.644131 -124.170284) (xy 376.606558 -124.118569)
			(xy 376.575764 -124.062554) (xy 376.552232 -124.003121) (xy 376.536335 -123.941207) (xy 376.528324 -123.877789)
			(xy 374.241326 -123.877789) (xy 374.239325 -123.909597) (xy 374.227347 -123.972388) (xy 374.207595 -124.033183)
			(xy 374.180378 -124.091023) (xy 374.146128 -124.144996) (xy 374.105383 -124.19425) (xy 374.058786 -124.23801)
			(xy 374.007073 -124.275585) (xy 373.951058 -124.306383) (xy 373.891624 -124.329917) (xy 373.82971 -124.345817)
			(xy 373.766292 -124.353832) (xy 373.73433 -124.354336) (xy 373.702179 -124.353873) (xy 373.638388 -124.345776)
			(xy 373.576129 -124.329694) (xy 373.516397 -124.305884) (xy 373.460147 -124.274728) (xy 373.408278 -124.236723)
			(xy 373.361618 -124.192477) (xy 373.340884 -124.1679) (xy 373.334534 -124.16028) (xy 373.317516 -124.150882)
			(xy 373.227854 -124.13996) (xy 373.209312 -124.14504) (xy 373.201184 -124.151136) (xy 373.17907 -124.167119)
			(xy 373.131187 -124.193276) (xy 373.080067 -124.21235) (xy 373.026753 -124.223953) (xy 372.97233 -124.227847)
			(xy 372.917907 -124.223953) (xy 372.864593 -124.21235) (xy 372.813473 -124.193276) (xy 372.76559 -124.167119)
			(xy 372.743476 -124.151136) (xy 372.735348 -124.14504) (xy 372.716806 -124.13996) (xy 372.627144 -124.150882)
			(xy 372.610126 -124.16028) (xy 372.603776 -124.1679) (xy 372.583034 -124.192468) (xy 372.536365 -124.236696)
			(xy 372.484492 -124.274687) (xy 372.428243 -124.305836) (xy 372.368515 -124.329643) (xy 372.306263 -124.345731)
			(xy 372.242479 -124.353841) (xy 372.21033 -124.354336) (xy 372.178368 -124.353801) (xy 372.114948 -124.345793)
			(xy 372.053032 -124.329899) (xy 371.993596 -124.306369) (xy 371.937579 -124.275576) (xy 371.885862 -124.238005)
			(xy 371.839262 -124.194247) (xy 371.798515 -124.144994) (xy 371.764261 -124.091023) (xy 371.737043 -124.033183)
			(xy 371.717289 -123.972389) (xy 371.70531 -123.909597) (xy 371.701296 -123.8458) (xy 339.259351 -123.8458)
			(xy 338.175115 -125.042887) (xy 373.874532 -125.042887) (xy 373.874532 -124.978965) (xy 373.882543 -124.915547)
			(xy 373.89844 -124.853633) (xy 373.921972 -124.7942) (xy 373.952766 -124.738185) (xy 373.990339 -124.68647)
			(xy 374.034096 -124.639873) (xy 374.083349 -124.599128) (xy 374.13732 -124.564877) (xy 374.195159 -124.53766)
			(xy 374.255952 -124.517907) (xy 374.318742 -124.505929) (xy 374.382538 -124.501916) (xy 374.446334 -124.505929)
			(xy 374.509124 -124.517907) (xy 374.569917 -124.53766) (xy 374.627756 -124.564877) (xy 374.681727 -124.599128)
			(xy 374.73098 -124.639873) (xy 374.774737 -124.68647) (xy 374.81231 -124.738185) (xy 374.843104 -124.7942)
			(xy 374.866636 -124.853633) (xy 374.882533 -124.915547) (xy 374.890544 -124.978965) (xy 374.891046 -125.010926)
			(xy 374.890544 -125.042887) (xy 374.882533 -125.106305) (xy 374.866636 -125.168219) (xy 374.843104 -125.227652)
			(xy 374.81231 -125.283667) (xy 374.774737 -125.335382) (xy 374.73098 -125.381979) (xy 374.681727 -125.422724)
			(xy 374.627756 -125.456975) (xy 374.569917 -125.484192) (xy 374.509124 -125.503945) (xy 374.446334 -125.515923)
			(xy 374.382538 -125.519937) (xy 374.318742 -125.515923) (xy 374.255952 -125.503945) (xy 374.195159 -125.484192)
			(xy 374.13732 -125.456975) (xy 374.083349 -125.422724) (xy 374.034096 -125.381979) (xy 373.990339 -125.335382)
			(xy 373.952766 -125.283667) (xy 373.921972 -125.227652) (xy 373.89844 -125.168219) (xy 373.882543 -125.106305)
			(xy 373.874532 -125.042887) (xy 338.175115 -125.042887) (xy 333.830984 -129.839169) (xy 348.452942 -129.839169)
			(xy 348.452942 -129.775247) (xy 348.460953 -129.711829) (xy 348.47685 -129.649915) (xy 348.500382 -129.590482)
			(xy 348.531176 -129.534467) (xy 348.568749 -129.482752) (xy 348.612506 -129.436155) (xy 348.661759 -129.39541)
			(xy 348.71573 -129.361159) (xy 348.773569 -129.333942) (xy 348.834362 -129.314189) (xy 348.897152 -129.302211)
			(xy 348.960948 -129.298198) (xy 349.024744 -129.302211) (xy 349.087534 -129.314189) (xy 349.148327 -129.333942)
			(xy 349.206166 -129.361159) (xy 349.260137 -129.39541) (xy 349.30939 -129.436155) (xy 349.353147 -129.482752)
			(xy 349.39072 -129.534467) (xy 349.421514 -129.590482) (xy 349.445046 -129.649915) (xy 349.460943 -129.711829)
			(xy 349.468954 -129.775247) (xy 349.469456 -129.807208) (xy 349.469028 -129.834454) (xy 349.595863 -129.834454)
			(xy 349.595863 -129.779946) (xy 349.603622 -129.725992) (xy 349.61898 -129.673691) (xy 349.641625 -129.624109)
			(xy 349.671097 -129.578254) (xy 349.706795 -129.537061) (xy 349.747993 -129.501368) (xy 349.793851 -129.471902)
			(xy 349.843436 -129.449263) (xy 349.895738 -129.433911) (xy 349.949693 -129.42616) (xy 349.976948 -129.4257)
			(xy 350.00579 -129.426224) (xy 350.062816 -129.434908) (xy 350.117886 -129.452072) (xy 350.169748 -129.477325)
			(xy 350.217222 -129.510092) (xy 350.259226 -129.549627) (xy 350.27743 -129.572004) (xy 350.28671 -129.582886)
			(xy 350.30991 -129.599577) (xy 350.336825 -129.60919) (xy 350.36535 -129.610974) (xy 350.393252 -129.604787)
			(xy 350.41835 -129.591115) (xy 350.43868 -129.571027) (xy 350.446086 -129.558796) (xy 350.463041 -129.529608)
			(xy 350.503456 -129.475542) (xy 350.550668 -129.427299) (xy 350.603848 -129.385726) (xy 350.662061 -129.351554)
			(xy 350.724283 -129.325385) (xy 350.78942 -129.307678) (xy 350.856327 -129.298744) (xy 350.890078 -129.298192)
			(xy 350.922041 -129.298672) (xy 350.985464 -129.306681) (xy 351.047383 -129.322577) (xy 351.106821 -129.346108)
			(xy 351.162841 -129.376903) (xy 351.214559 -129.414477) (xy 351.261161 -129.458236) (xy 351.30191 -129.507492)
			(xy 351.336164 -129.561466) (xy 351.363384 -129.619308) (xy 351.383138 -129.680106) (xy 351.395117 -129.7429)
			(xy 351.399132 -129.8067) (xy 351.395117 -129.8705) (xy 351.383138 -129.933294) (xy 351.363384 -129.994092)
			(xy 351.336164 -130.051934) (xy 351.30191 -130.105908) (xy 351.261161 -130.155164) (xy 351.214559 -130.198923)
			(xy 351.162841 -130.236497) (xy 351.106821 -130.267292) (xy 351.047383 -130.290823) (xy 350.985464 -130.306719)
			(xy 350.922041 -130.314728) (xy 350.890078 -130.315208) (xy 350.85636 -130.314678) (xy 350.789514 -130.305773)
			(xy 350.724432 -130.28811) (xy 350.662257 -130.261998) (xy 350.604079 -130.227895) (xy 350.55092 -130.186401)
			(xy 350.503713 -130.138243) (xy 350.463287 -130.084267) (xy 350.44634 -130.055112) (xy 350.438925 -130.042871)
			(xy 350.41858 -130.022761) (xy 350.393454 -130.009086) (xy 350.365521 -130.00292) (xy 350.336973 -130.004746)
			(xy 350.310053 -130.014422) (xy 350.286874 -130.031188) (xy 350.277684 -130.042158) (xy 350.25947 -130.064566)
			(xy 350.217445 -130.104168) (xy 350.169937 -130.136991) (xy 350.118029 -130.162288) (xy 350.062905 -130.179483)
			(xy 350.00582 -130.188183) (xy 349.976948 -130.188716) (xy 349.949693 -130.18824) (xy 349.895738 -130.180489)
			(xy 349.843436 -130.165137) (xy 349.793851 -130.142498) (xy 349.747993 -130.113032) (xy 349.706795 -130.077339)
			(xy 349.671097 -130.036146) (xy 349.641625 -129.990291) (xy 349.61898 -129.940709) (xy 349.603622 -129.888408)
			(xy 349.595863 -129.834454) (xy 349.469028 -129.834454) (xy 349.468954 -129.839169) (xy 349.460943 -129.902587)
			(xy 349.445046 -129.964501) (xy 349.421514 -130.023934) (xy 349.39072 -130.079949) (xy 349.353147 -130.131664)
			(xy 349.30939 -130.178261) (xy 349.260137 -130.219006) (xy 349.206166 -130.253257) (xy 349.148327 -130.280474)
			(xy 349.087534 -130.300227) (xy 349.024744 -130.312205) (xy 348.960948 -130.316219) (xy 348.897152 -130.312205)
			(xy 348.834362 -130.300227) (xy 348.773569 -130.280474) (xy 348.71573 -130.253257) (xy 348.661759 -130.219006)
			(xy 348.612506 -130.178261) (xy 348.568749 -130.131664) (xy 348.531176 -130.079949) (xy 348.500382 -130.023934)
			(xy 348.47685 -129.964501) (xy 348.460953 -129.902587) (xy 348.452942 -129.839169) (xy 333.830984 -129.839169)
			(xy 332.491334 -131.318254) (xy 332.487016 -131.323588) (xy 332.269429 -131.63931) (xy 337.646262 -131.63931)
			(xy 337.650333 -131.583688) (xy 337.662459 -131.529251) (xy 337.682382 -131.47716) (xy 337.709678 -131.428525)
			(xy 337.743764 -131.384382) (xy 337.783913 -131.345673) (xy 337.829271 -131.313222) (xy 337.878871 -131.287721)
			(xy 337.931655 -131.269714) (xy 337.986498 -131.259584) (xy 338.042232 -131.257547) (xy 338.097669 -131.263647)
			(xy 338.151626 -131.277753) (xy 338.202955 -131.299565) (xy 338.250561 -131.328619) (xy 338.293429 -131.364294)
			(xy 338.330646 -131.405831) (xy 338.361419 -131.452344) (xy 338.385091 -131.502841) (xy 338.401159 -131.556248)
			(xy 338.409279 -131.611424) (xy 338.409788 -131.63931) (xy 338.409279 -131.667196) (xy 338.401159 -131.722372)
			(xy 338.385091 -131.775779) (xy 338.361419 -131.826276) (xy 338.330646 -131.872789) (xy 338.293429 -131.914326)
			(xy 338.250561 -131.950001) (xy 338.202955 -131.979055) (xy 338.151626 -132.000867) (xy 338.097669 -132.014973)
			(xy 338.042232 -132.021073) (xy 337.986498 -132.019036) (xy 337.931655 -132.008906) (xy 337.878871 -131.990899)
			(xy 337.829271 -131.965398) (xy 337.783913 -131.932947) (xy 337.743764 -131.894238) (xy 337.709678 -131.850095)
			(xy 337.682382 -131.80146) (xy 337.662459 -131.749369) (xy 337.650333 -131.694932) (xy 337.646262 -131.63931)
			(xy 332.269429 -131.63931) (xy 332.173326 -131.778756) (xy 332.167094 -131.788771) (xy 332.163637 -131.812076)
			(xy 332.166722 -131.82346) (xy 332.195678 -131.911598) (xy 332.212188 -131.928362) (xy 332.223364 -131.932426)
			(xy 332.264757 -131.947398) (xy 332.344628 -131.984406) (xy 332.420451 -132.029126) (xy 332.491482 -132.081122)
			(xy 332.557025 -132.139884) (xy 332.61644 -132.204837) (xy 332.643226 -132.239766) (xy 332.648874 -132.246558)
			(xy 332.663679 -132.256168) (xy 332.672182 -132.258562) (xy 332.713451 -132.268841) (xy 332.793969 -132.296244)
			(xy 332.871504 -132.331208) (xy 332.945347 -132.373414) (xy 333.014824 -132.422477) (xy 333.0793 -132.477947)
			(xy 333.123724 -132.524246) (xy 337.630514 -132.524246) (xy 337.634585 -132.468624) (xy 337.646711 -132.414187)
			(xy 337.666634 -132.362096) (xy 337.69393 -132.313461) (xy 337.728016 -132.269318) (xy 337.768165 -132.230609)
			(xy 337.813523 -132.198158) (xy 337.863123 -132.172657) (xy 337.915907 -132.15465) (xy 337.97075 -132.14452)
			(xy 338.026484 -132.142483) (xy 338.081921 -132.148583) (xy 338.135878 -132.162689) (xy 338.187207 -132.184501)
			(xy 338.234813 -132.213555) (xy 338.277681 -132.24923) (xy 338.314898 -132.290767) (xy 338.345671 -132.33728)
			(xy 338.369343 -132.387777) (xy 338.385411 -132.441184) (xy 338.393531 -132.49636) (xy 338.39404 -132.524246)
			(xy 338.393531 -132.552132) (xy 338.385411 -132.607308) (xy 338.369343 -132.660715) (xy 338.345671 -132.711212)
			(xy 338.314898 -132.757725) (xy 338.277681 -132.799262) (xy 338.234813 -132.834937) (xy 338.187207 -132.863991)
			(xy 338.135878 -132.885803) (xy 338.081921 -132.899909) (xy 338.026484 -132.906009) (xy 337.97075 -132.903972)
			(xy 337.915907 -132.893842) (xy 337.863123 -132.875835) (xy 337.813523 -132.850334) (xy 337.768165 -132.817883)
			(xy 337.728016 -132.779174) (xy 337.69393 -132.735031) (xy 337.666634 -132.686396) (xy 337.646711 -132.634305)
			(xy 337.634585 -132.579868) (xy 337.630514 -132.524246) (xy 333.123724 -132.524246) (xy 333.138187 -132.539319)
			(xy 333.190946 -132.606032) (xy 333.237096 -132.677477) (xy 333.276215 -132.753) (xy 333.307946 -132.831914)
			(xy 333.331999 -132.913495) (xy 333.348154 -132.997001) (xy 333.356264 -133.081667) (xy 333.356712 -133.124194)
			(xy 333.356204 -133.166535) (xy 333.348146 -133.250832) (xy 333.332113 -133.333982) (xy 333.315098 -133.39191)
			(xy 337.646262 -133.39191) (xy 337.650333 -133.336288) (xy 337.662459 -133.281851) (xy 337.682382 -133.22976)
			(xy 337.709678 -133.181125) (xy 337.743764 -133.136982) (xy 337.783913 -133.098273) (xy 337.829271 -133.065822)
			(xy 337.878871 -133.040321) (xy 337.931655 -133.022314) (xy 337.986498 -133.012184) (xy 338.042232 -133.010147)
			(xy 338.097669 -133.016247) (xy 338.151626 -133.030353) (xy 338.202955 -133.052165) (xy 338.250561 -133.081219)
			(xy 338.293429 -133.116894) (xy 338.330646 -133.158431) (xy 338.361419 -133.204944) (xy 338.385091 -133.255441)
			(xy 338.401159 -133.308848) (xy 338.409279 -133.364024) (xy 338.409788 -133.39191) (xy 338.409279 -133.419796)
			(xy 338.401159 -133.474972) (xy 338.385091 -133.528379) (xy 338.361419 -133.578876) (xy 338.330646 -133.625389)
			(xy 338.293429 -133.666926) (xy 338.250561 -133.702601) (xy 338.202955 -133.731655) (xy 338.151626 -133.753467)
			(xy 338.097669 -133.767573) (xy 338.042232 -133.773673) (xy 337.986498 -133.771636) (xy 337.931655 -133.761506)
			(xy 337.878871 -133.743499) (xy 337.829271 -133.717998) (xy 337.783913 -133.685547) (xy 337.743764 -133.646838)
			(xy 337.709678 -133.602695) (xy 337.682382 -133.55406) (xy 337.662459 -133.501969) (xy 337.650333 -133.447532)
			(xy 337.646262 -133.39191) (xy 333.315098 -133.39191) (xy 333.308248 -133.415232) (xy 333.276769 -133.493845)
			(xy 333.23796 -133.56911) (xy 333.192173 -133.640346) (xy 333.139823 -133.706908) (xy 333.081382 -133.768192)
			(xy 333.017382 -133.823644) (xy 332.9484 -133.872761) (xy 332.875063 -133.9151) (xy 332.836774 -133.933184)
			(xy 332.828759 -133.937227) (xy 332.816012 -133.949851) (xy 332.811882 -133.957822) (xy 332.793571 -133.995473)
			(xy 332.750861 -134.067491) (xy 332.701569 -134.135173) (xy 332.646132 -134.197922) (xy 332.585042 -134.255181)
			(xy 332.557062 -134.276846) (xy 337.631024 -134.276846) (xy 337.63151 -134.249595) (xy 337.639266 -134.195647)
			(xy 337.654621 -134.143352) (xy 337.677263 -134.093775) (xy 337.706729 -134.047925) (xy 337.74242 -134.006734)
			(xy 337.783611 -133.971043) (xy 337.829461 -133.941577) (xy 337.879038 -133.918935) (xy 337.931333 -133.90358)
			(xy 337.985281 -133.895824) (xy 338.039783 -133.895824) (xy 338.093731 -133.90358) (xy 338.146026 -133.918935)
			(xy 338.195603 -133.941577) (xy 338.241453 -133.971043) (xy 338.282644 -134.006734) (xy 338.318335 -134.047925)
			(xy 338.347801 -134.093775) (xy 338.370443 -134.143352) (xy 338.385798 -134.195647) (xy 338.393554 -134.249595)
			(xy 338.39404 -134.276846) (xy 338.393592 -134.30303) (xy 338.386417 -134.354903) (xy 338.372223 -134.40531)
			(xy 338.351275 -134.453305) (xy 338.323966 -134.497989) (xy 338.290809 -134.538522) (xy 338.252424 -134.574145)
			(xy 338.231226 -134.58952) (xy 338.219997 -134.597927) (xy 338.202262 -134.619646) (xy 338.19111 -134.645372)
			(xy 338.187383 -134.673163) (xy 338.191362 -134.700919) (xy 338.202748 -134.726543) (xy 338.220679 -134.7481)
			(xy 338.231988 -134.756398) (xy 338.253541 -134.771728) (xy 338.292627 -134.807361) (xy 338.326415 -134.848052)
			(xy 338.354257 -134.893021) (xy 338.375619 -134.941405) (xy 338.390093 -134.992276) (xy 338.397399 -135.044659)
			(xy 338.39785 -135.071104) (xy 338.397364 -135.098355) (xy 338.389608 -135.152303) (xy 338.374253 -135.204598)
			(xy 338.351611 -135.254175) (xy 338.322145 -135.300025) (xy 338.286454 -135.341216) (xy 338.245263 -135.376907)
			(xy 338.199413 -135.406373) (xy 338.149836 -135.429015) (xy 338.097541 -135.44437) (xy 338.043593 -135.452126)
			(xy 337.989091 -135.452126) (xy 337.935143 -135.44437) (xy 337.882848 -135.429015) (xy 337.833271 -135.406373)
			(xy 337.787421 -135.376907) (xy 337.74623 -135.341216) (xy 337.710539 -135.300025) (xy 337.681073 -135.254175)
			(xy 337.658431 -135.204598) (xy 337.643076 -135.152303) (xy 337.63532 -135.098355) (xy 337.634834 -135.071104)
			(xy 337.635256 -135.04492) (xy 337.642436 -134.993045) (xy 337.656636 -134.942638) (xy 337.677589 -134.894643)
			(xy 337.704901 -134.849961) (xy 337.738062 -134.809428) (xy 337.776449 -134.773805) (xy 337.797648 -134.75843)
			(xy 337.808919 -134.750079) (xy 337.826642 -134.728344) (xy 337.837783 -134.702606) (xy 337.841501 -134.674808)
			(xy 337.837515 -134.647047) (xy 337.826127 -134.621418) (xy 337.808195 -134.599855) (xy 337.796886 -134.591552)
			(xy 337.775303 -134.576262) (xy 337.73622 -134.540621) (xy 337.702435 -134.499923) (xy 337.674597 -134.454948)
			(xy 337.653239 -134.406557) (xy 337.638771 -134.355681) (xy 337.631471 -134.303293) (xy 337.631024 -134.276846)
			(xy 332.557062 -134.276846) (xy 332.518839 -134.306443) (xy 332.448109 -134.351254) (xy 332.37348 -134.389216)
			(xy 332.295612 -134.419994) (xy 332.215196 -134.443315) (xy 332.132943 -134.458973) (xy 332.049583 -134.466828)
			(xy 332.007718 -134.467346) (xy 331.961807 -134.466769) (xy 331.870474 -134.457314) (xy 331.780598 -134.438511)
			(xy 331.693133 -134.410561) (xy 331.650848 -134.39267) (xy 331.642506 -134.389494) (xy 331.6247 -134.38844)
			(xy 331.61605 -134.390638) (xy 331.577136 -134.401869) (xy 331.497763 -134.418025) (xy 331.457554 -134.422896)
			(xy 331.445362 -134.424166) (xy 331.425042 -134.437628) (xy 331.372464 -134.530592) (xy 331.371448 -134.554976)
			(xy 331.376528 -134.566152) (xy 331.387469 -134.591169) (xy 331.402878 -134.643553) (xy 331.41064 -134.6976)
			(xy 331.411072 -134.724902) (xy 331.410559 -134.753537) (xy 331.401998 -134.810162) (xy 331.385068 -134.864872)
			(xy 331.360151 -134.916436) (xy 331.327805 -134.963696) (xy 331.288758 -135.00559) (xy 331.243888 -135.041176)
			(xy 331.219302 -135.055864) (xy 331.211747 -135.060634) (xy 331.200294 -135.074335) (xy 331.194229 -135.09113)
			(xy 331.193902 -135.10006) (xy 331.193902 -135.187944) (xy 331.194206 -135.196875) (xy 331.200274 -135.213671)
			(xy 331.211756 -135.227348) (xy 331.219302 -135.23214) (xy 331.243885 -135.246829) (xy 331.288744 -135.282421)
			(xy 331.327781 -135.324319) (xy 331.360117 -135.371579) (xy 331.385028 -135.423142) (xy 331.401952 -135.477848)
			(xy 331.41051 -135.53447) (xy 331.411072 -135.563102) (xy 331.410586 -135.590353) (xy 331.40283 -135.644301)
			(xy 331.387475 -135.696596) (xy 331.364833 -135.746173) (xy 331.335367 -135.792023) (xy 331.299676 -135.833214)
			(xy 331.258485 -135.868905) (xy 331.212635 -135.898371) (xy 331.163058 -135.921013) (xy 331.110763 -135.936368)
			(xy 331.056815 -135.944124) (xy 331.002313 -135.944124) (xy 330.948365 -135.936368) (xy 330.89607 -135.921013)
			(xy 330.846493 -135.898371) (xy 330.800643 -135.868905) (xy 330.759452 -135.833214) (xy 330.723761 -135.792023)
			(xy 330.694295 -135.746173) (xy 330.671653 -135.696596) (xy 330.656298 -135.644301) (xy 330.648542 -135.590353)
			(xy 330.648056 -135.563102) (xy 330.648569 -135.534468) (xy 330.65713 -135.477843) (xy 330.67406 -135.423134)
			(xy 330.698978 -135.37157) (xy 330.731325 -135.324312) (xy 330.770373 -135.28242) (xy 330.815245 -135.246836)
			(xy 330.839826 -135.23214) (xy 330.847379 -135.227368) (xy 330.858826 -135.213666) (xy 330.864889 -135.196872)
			(xy 330.865226 -135.187944) (xy 330.865226 -135.10006) (xy 330.864923 -135.091128) (xy 330.858859 -135.074328)
			(xy 330.847379 -135.060644) (xy 330.839826 -135.055864) (xy 330.815242 -135.041176) (xy 330.770379 -135.005585)
			(xy 330.731339 -134.963689) (xy 330.698999 -134.916429) (xy 330.674087 -134.864865) (xy 330.65716 -134.810158)
			(xy 330.648601 -134.753535) (xy 330.648056 -134.724902) (xy 330.648512 -134.698392) (xy 330.655854 -134.645882)
			(xy 330.670399 -134.594895) (xy 330.691864 -134.546414) (xy 330.719838 -134.501374) (xy 330.753779 -134.460641)
			(xy 330.793035 -134.425001) (xy 330.81468 -134.409688) (xy 330.82484 -134.40283) (xy 330.836524 -134.38124)
			(xy 330.839318 -134.27456) (xy 330.828904 -134.252462) (xy 330.819252 -134.245096) (xy 330.799186 -134.229348)
			(xy 330.791997 -134.224028) (xy 330.775106 -134.218192) (xy 330.766166 -134.217918) (xy 330.74864 -134.218172)
			(xy 330.697503 -134.217471) (xy 330.595903 -134.205756) (xy 330.545948 -134.194804) (xy 330.530454 -134.191248)
			(xy 330.501498 -134.202424) (xy 330.32319 -134.460742) (xy 330.320142 -134.484872) (xy 330.324206 -134.496556)
			(xy 330.334729 -134.527838) (xy 330.346095 -134.592845) (xy 330.346812 -134.625842) (xy 330.346345 -134.652794)
			(xy 330.338753 -134.706161) (xy 330.323727 -134.757929) (xy 330.301566 -134.807067) (xy 330.27271 -134.852598)
			(xy 330.237735 -134.893615) (xy 330.197335 -134.929302) (xy 330.152315 -134.958948) (xy 330.103572 -134.981965)
			(xy 330.052074 -134.997893) (xy 329.998848 -135.006415) (xy 329.971908 -135.00735) (xy 329.959716 -135.007604)
			(xy 329.938126 -135.019034) (xy 328.916792 -136.499854) (xy 328.912975 -136.505907) (xy 330.109062 -136.505907)
			(xy 330.109062 -136.441985) (xy 330.117073 -136.378567) (xy 330.13297 -136.316653) (xy 330.156502 -136.25722)
			(xy 330.187296 -136.201205) (xy 330.224869 -136.14949) (xy 330.268626 -136.102893) (xy 330.317879 -136.062148)
			(xy 330.37185 -136.027897) (xy 330.429689 -136.00068) (xy 330.490482 -135.980927) (xy 330.553272 -135.968949)
			(xy 330.617068 -135.964936) (xy 330.680864 -135.968949) (xy 330.743654 -135.980927) (xy 330.804447 -136.00068)
			(xy 330.862286 -136.027897) (xy 330.916257 -136.062148) (xy 330.96551 -136.102893) (xy 331.009267 -136.14949)
			(xy 331.04684 -136.201205) (xy 331.077634 -136.25722) (xy 331.101166 -136.316653) (xy 331.117063 -136.378567)
			(xy 331.125074 -136.441985) (xy 331.125576 -136.473946) (xy 331.125074 -136.505907) (xy 331.117063 -136.569325)
			(xy 331.101166 -136.631239) (xy 331.077634 -136.690672) (xy 331.04684 -136.746687) (xy 331.009267 -136.798402)
			(xy 330.968095 -136.842246) (xy 337.605624 -136.842246) (xy 337.606163 -136.812753) (xy 337.615222 -136.754468)
			(xy 337.633147 -136.698272) (xy 337.65951 -136.645507) (xy 337.693684 -136.597429) (xy 337.734852 -136.555186)
			(xy 337.782032 -136.519785) (xy 337.807808 -136.505442) (xy 337.821085 -136.497829) (xy 337.84263 -136.476106)
			(xy 337.85678 -136.44898) (xy 337.862269 -136.418881) (xy 337.858604 -136.388507) (xy 337.846114 -136.360577)
			(xy 337.825918 -136.337596) (xy 337.813142 -136.329166) (xy 337.789698 -136.314175) (xy 337.746975 -136.278524)
			(xy 337.709889 -136.237041) (xy 337.679226 -136.190608) (xy 337.655639 -136.14021) (xy 337.639627 -136.08692)
			(xy 337.631532 -136.031868) (xy 337.631024 -136.004046) (xy 337.63151 -135.976795) (xy 337.639266 -135.922847)
			(xy 337.654621 -135.870552) (xy 337.677263 -135.820975) (xy 337.706729 -135.775125) (xy 337.74242 -135.733934)
			(xy 337.783611 -135.698243) (xy 337.829461 -135.668777) (xy 337.879038 -135.646135) (xy 337.931333 -135.63078)
			(xy 337.985281 -135.623024) (xy 338.039783 -135.623024) (xy 338.093731 -135.63078) (xy 338.146026 -135.646135)
			(xy 338.170458 -135.657293) (xy 360.003084 -135.657293) (xy 360.003084 -135.593371) (xy 360.011095 -135.529953)
			(xy 360.026992 -135.468039) (xy 360.050524 -135.408606) (xy 360.081318 -135.352591) (xy 360.118891 -135.300876)
			(xy 360.162648 -135.254279) (xy 360.211901 -135.213534) (xy 360.265872 -135.179283) (xy 360.323711 -135.152066)
			(xy 360.384504 -135.132313) (xy 360.447294 -135.120335) (xy 360.51109 -135.116322) (xy 360.574886 -135.120335)
			(xy 360.637676 -135.132313) (xy 360.698469 -135.152066) (xy 360.756308 -135.179283) (xy 360.810279 -135.213534)
			(xy 360.859532 -135.254279) (xy 360.903289 -135.300876) (xy 360.940862 -135.352591) (xy 360.971656 -135.408606)
			(xy 360.995188 -135.468039) (xy 361.011085 -135.529953) (xy 361.019096 -135.593371) (xy 361.019598 -135.625332)
			(xy 361.019096 -135.657293) (xy 361.011085 -135.720711) (xy 360.995188 -135.782625) (xy 360.971656 -135.842058)
			(xy 360.940862 -135.898073) (xy 360.903289 -135.949788) (xy 360.859532 -135.996385) (xy 360.810279 -136.03713)
			(xy 360.756308 -136.071381) (xy 360.698469 -136.098598) (xy 360.637676 -136.118351) (xy 360.574886 -136.130329)
			(xy 360.51109 -136.134343) (xy 360.447294 -136.130329) (xy 360.384504 -136.118351) (xy 360.323711 -136.098598)
			(xy 360.265872 -136.071381) (xy 360.211901 -136.03713) (xy 360.162648 -135.996385) (xy 360.118891 -135.949788)
			(xy 360.081318 -135.898073) (xy 360.050524 -135.842058) (xy 360.026992 -135.782625) (xy 360.011095 -135.720711)
			(xy 360.003084 -135.657293) (xy 338.170458 -135.657293) (xy 338.195603 -135.668777) (xy 338.241453 -135.698243)
			(xy 338.282644 -135.733934) (xy 338.318335 -135.775125) (xy 338.347801 -135.820975) (xy 338.370443 -135.870552)
			(xy 338.385798 -135.922847) (xy 338.393554 -135.976795) (xy 338.39404 -136.004046) (xy 338.393514 -136.03354)
			(xy 338.384455 -136.091826) (xy 338.366529 -136.148023) (xy 338.340164 -136.20079) (xy 338.305988 -136.248867)
			(xy 338.264817 -136.291109) (xy 338.217633 -136.326508) (xy 338.191856 -136.34085) (xy 338.178589 -136.348476)
			(xy 338.157052 -136.370199) (xy 338.142907 -136.397321) (xy 338.13742 -136.427415) (xy 338.141081 -136.457784)
			(xy 338.153564 -136.485711) (xy 338.173751 -136.508694) (xy 338.186522 -136.517126) (xy 338.209954 -136.532135)
			(xy 338.252679 -136.567782) (xy 338.289767 -136.609261) (xy 338.320432 -136.655691) (xy 338.344021 -136.706086)
			(xy 338.360034 -136.759375) (xy 338.368131 -136.814425) (xy 338.36864 -136.842246) (xy 338.368154 -136.869497)
			(xy 338.360398 -136.923445) (xy 338.345043 -136.97574) (xy 338.322401 -137.025317) (xy 338.292935 -137.071167)
			(xy 338.257244 -137.112358) (xy 338.216053 -137.148049) (xy 338.170203 -137.177515) (xy 338.120626 -137.200157)
			(xy 338.068331 -137.215512) (xy 338.014383 -137.223268) (xy 337.959881 -137.223268) (xy 337.905933 -137.215512)
			(xy 337.853638 -137.200157) (xy 337.804061 -137.177515) (xy 337.758211 -137.148049) (xy 337.71702 -137.112358)
			(xy 337.681329 -137.071167) (xy 337.651863 -137.025317) (xy 337.629221 -136.97574) (xy 337.613866 -136.923445)
			(xy 337.60611 -136.869497) (xy 337.605624 -136.842246) (xy 330.968095 -136.842246) (xy 330.96551 -136.844999)
			(xy 330.916257 -136.885744) (xy 330.862286 -136.919995) (xy 330.804447 -136.947212) (xy 330.743654 -136.966965)
			(xy 330.680864 -136.978943) (xy 330.617068 -136.982957) (xy 330.553272 -136.978943) (xy 330.490482 -136.966965)
			(xy 330.429689 -136.947212) (xy 330.37185 -136.919995) (xy 330.317879 -136.885744) (xy 330.268626 -136.844999)
			(xy 330.224869 -136.798402) (xy 330.187296 -136.746687) (xy 330.156502 -136.690672) (xy 330.13297 -136.631239)
			(xy 330.117073 -136.569325) (xy 330.109062 -136.505907) (xy 328.912975 -136.505907) (xy 328.911554 -136.50816)
			(xy 328.907243 -136.527298) (xy 328.910493 -136.546645) (xy 328.915268 -136.555226) (xy 328.97191 -136.647428)
			(xy 328.998834 -136.660382) (xy 329.014074 -136.65835) (xy 329.026774 -136.656703) (xy 329.052323 -136.654922)
			(xy 329.065128 -136.654794) (xy 329.092378 -136.655282) (xy 329.146322 -136.663041) (xy 329.198614 -136.678399)
			(xy 329.248187 -136.701042) (xy 329.294034 -136.730509) (xy 329.335221 -136.7662) (xy 329.370909 -136.80739)
			(xy 329.400373 -136.853239) (xy 329.423011 -136.902814) (xy 329.438365 -136.955107) (xy 329.44612 -137.009052)
			(xy 329.446636 -137.036302) (xy 329.446169 -137.06327) (xy 329.438569 -137.116667) (xy 329.423521 -137.168461)
			(xy 329.401325 -137.217618) (xy 329.372424 -137.263157) (xy 329.337394 -137.304169) (xy 329.296935 -137.339836)
			(xy 329.274678 -137.355072) (xy 329.26655 -137.360406) (xy 329.255628 -137.3759) (xy 329.234038 -137.46099)
			(xy 329.236324 -137.479786) (xy 329.240896 -137.488168) (xy 329.258373 -137.521566) (xy 329.287405 -137.591136)
			(xy 329.309421 -137.663233) (xy 329.324208 -137.737153) (xy 329.331619 -137.812172) (xy 329.332082 -137.849864)
			(xy 329.33161 -137.888205) (xy 329.323916 -137.964501) (xy 329.308603 -138.039638) (xy 329.285825 -138.11286)
			(xy 329.255813 -138.183425) (xy 329.218868 -138.25062) (xy 329.175366 -138.313769) (xy 329.125744 -138.372231)
			(xy 329.070505 -138.425418) (xy 329.059383 -138.434156) (xy 336.593841 -138.434156) (xy 336.593841 -138.379644)
			(xy 336.601599 -138.325688) (xy 336.616958 -138.273384) (xy 336.639605 -138.2238) (xy 336.669078 -138.177943)
			(xy 336.704777 -138.136747) (xy 336.745976 -138.101052) (xy 336.791836 -138.071584) (xy 336.841424 -138.048943)
			(xy 336.893729 -138.03359) (xy 336.947686 -138.025838) (xy 336.974942 -138.025378) (xy 337.002577 -138.025943)
			(xy 337.057266 -138.033932) (xy 337.110233 -138.049721) (xy 337.16037 -138.072982) (xy 337.206629 -138.103228)
			(xy 337.248045 -138.139827) (xy 337.283752 -138.182015) (xy 337.313003 -138.22891) (xy 337.335188 -138.279532)
			(xy 337.342988 -138.306048) (xy 337.34629 -138.318494) (xy 337.363562 -138.336782) (xy 337.46821 -138.37158)
			(xy 337.492848 -138.367262) (xy 337.503008 -138.359388) (xy 337.521912 -138.345189) (xy 337.562582 -138.32108)
			(xy 337.605916 -138.302173) (xy 337.628484 -138.295126) (xy 337.640676 -138.29157) (xy 337.658456 -138.274298)
			(xy 337.692746 -138.171428) (xy 337.688682 -138.147044) (xy 337.681316 -138.136884) (xy 337.663538 -138.112037)
			(xy 337.635283 -138.057872) (xy 337.616021 -137.999896) (xy 337.606246 -137.939592) (xy 337.605624 -137.909046)
			(xy 337.60611 -137.881795) (xy 337.613866 -137.827847) (xy 337.629221 -137.775552) (xy 337.651863 -137.725975)
			(xy 337.681329 -137.680125) (xy 337.71702 -137.638934) (xy 337.758211 -137.603243) (xy 337.804061 -137.573777)
			(xy 337.853638 -137.551135) (xy 337.905933 -137.53578) (xy 337.959881 -137.528024) (xy 338.014383 -137.528024)
			(xy 338.068331 -137.53578) (xy 338.120626 -137.551135) (xy 338.170203 -137.573777) (xy 338.216053 -137.603243)
			(xy 338.257244 -137.638934) (xy 338.292935 -137.680125) (xy 338.322401 -137.725975) (xy 338.345043 -137.775552)
			(xy 338.360398 -137.827847) (xy 338.368154 -137.881795) (xy 338.36864 -137.909046) (xy 338.368184 -137.937299)
			(xy 338.359857 -137.993187) (xy 338.343378 -138.047236) (xy 338.319106 -138.098262) (xy 338.287573 -138.14515)
			(xy 338.249469 -138.186875) (xy 338.205627 -138.222522) (xy 338.157007 -138.251313) (xy 338.104672 -138.272616)
			(xy 338.049767 -138.285968) (xy 338.021676 -138.28903) (xy 338.011884 -138.29033) (xy 337.994328 -138.299348)
			(xy 337.981479 -138.314329) (xy 337.975239 -138.333053) (xy 337.976534 -138.352747) (xy 337.98517 -138.370493)
			(xy 337.992212 -138.377422) (xy 338.004573 -138.388776) (xy 338.027464 -138.413325) (xy 338.037932 -138.426444)
			(xy 338.045477 -138.435223) (xy 338.066249 -138.445395) (xy 338.07781 -138.446002) (xy 338.158074 -138.446002)
			(xy 338.16964 -138.445416) (xy 338.190411 -138.435232) (xy 338.197952 -138.426444) (xy 338.216181 -138.403993)
			(xy 338.258192 -138.364253) (xy 338.305718 -138.331309) (xy 338.357672 -138.305915) (xy 338.412864 -138.288652)
			(xy 338.470028 -138.279916) (xy 338.498942 -138.279378) (xy 338.526194 -138.279839) (xy 338.580142 -138.287601)
			(xy 338.632436 -138.30296) (xy 338.682012 -138.325605) (xy 338.727862 -138.355075) (xy 338.769051 -138.390769)
			(xy 338.804742 -138.431961) (xy 338.834208 -138.477812) (xy 338.856849 -138.52739) (xy 338.872205 -138.579686)
			(xy 338.879963 -138.633634) (xy 338.88045 -138.660886) (xy 338.880022 -138.687266) (xy 338.872759 -138.739523)
			(xy 338.858369 -138.790282) (xy 338.837127 -138.838576) (xy 338.809437 -138.883485) (xy 338.775827 -138.924153)
			(xy 338.736937 -138.959806) (xy 338.693508 -138.989764) (xy 338.670138 -139.002008) (xy 338.65693 -139.008358)
			(xy 338.641944 -139.032742) (xy 338.641944 -139.15263) (xy 338.65693 -139.177014) (xy 338.670138 -139.183364)
			(xy 338.693511 -139.1956) (xy 338.736934 -139.225564) (xy 338.775818 -139.261221) (xy 338.809423 -139.301892)
			(xy 338.837109 -139.346801) (xy 338.85835 -139.395094) (xy 338.872739 -139.445852) (xy 338.880004 -139.498107)
			(xy 338.88045 -139.524486) (xy 338.879961 -139.551743) (xy 338.872196 -139.605702) (xy 338.856836 -139.658008)
			(xy 338.834193 -139.707598) (xy 338.804727 -139.753464) (xy 338.769038 -139.794673) (xy 338.727851 -139.830387)
			(xy 338.70519 -139.845542) (xy 338.698195 -139.850359) (xy 338.687676 -139.863683) (xy 338.682126 -139.879726)
			(xy 338.681822 -139.888214) (xy 338.681822 -139.973558) (xy 338.68218 -139.982034) (xy 338.687751 -139.998048)
			(xy 338.698233 -140.011375) (xy 338.70519 -140.01623) (xy 338.727839 -140.031402) (xy 338.769027 -140.067112)
			(xy 338.804716 -140.108318) (xy 338.834179 -140.154182) (xy 338.856818 -140.203772) (xy 338.872172 -140.256078)
			(xy 338.879929 -140.310036) (xy 338.87993 -140.364549) (xy 338.872175 -140.418507) (xy 338.856824 -140.470814)
			(xy 338.834187 -140.520404) (xy 338.804725 -140.56627) (xy 338.769038 -140.607478) (xy 338.727851 -140.643189)
			(xy 338.70519 -140.658342) (xy 338.698195 -140.663159) (xy 338.687676 -140.676483) (xy 338.682126 -140.692526)
			(xy 338.681822 -140.701014) (xy 338.681822 -140.786358) (xy 338.68218 -140.794834) (xy 338.687751 -140.810848)
			(xy 338.698233 -140.824175) (xy 338.70519 -140.82903) (xy 338.727837 -140.844206) (xy 338.769034 -140.87991)
			(xy 338.80473 -140.921112) (xy 338.834201 -140.966974) (xy 338.856846 -141.016563) (xy 338.872204 -141.068869)
			(xy 338.879963 -141.122829) (xy 338.88045 -141.150086) (xy 338.879909 -141.177335) (xy 338.872155 -141.231278)
			(xy 338.856804 -141.28357) (xy 338.834168 -141.333144) (xy 338.804707 -141.378992) (xy 338.769021 -141.420182)
			(xy 338.727837 -141.455873) (xy 338.681993 -141.485341) (xy 338.632422 -141.507985) (xy 338.580133 -141.523343)
			(xy 338.526191 -141.531105) (xy 338.498942 -141.531594) (xy 338.470026 -141.531048) (xy 338.412856 -141.522325)
			(xy 338.357658 -141.505073) (xy 338.305696 -141.479686) (xy 338.258161 -141.446748) (xy 338.216143 -141.407011)
			(xy 338.197952 -141.384528) (xy 338.190419 -141.375737) (xy 338.169638 -141.365572) (xy 338.158074 -141.36497)
			(xy 338.07781 -141.36497) (xy 338.066239 -141.365522) (xy 338.045467 -141.375727) (xy 338.037932 -141.384528)
			(xy 338.023158 -141.402931) (xy 337.989785 -141.436299) (xy 337.971384 -141.451076) (xy 337.962634 -141.45865)
			(xy 337.952445 -141.4794) (xy 337.951826 -141.490954) (xy 337.951826 -141.571218) (xy 337.952377 -141.582789)
			(xy 337.962584 -141.60356) (xy 337.971384 -141.611096) (xy 337.993862 -141.629293) (xy 338.033598 -141.671311)
			(xy 338.066539 -141.718845) (xy 338.091928 -141.770805) (xy 338.109185 -141.826001) (xy 338.117915 -141.88317)
			(xy 338.11845 -141.912086) (xy 338.117976 -141.939281) (xy 338.110297 -141.993125) (xy 338.095035 -142.045328)
			(xy 338.072502 -142.09483) (xy 338.043155 -142.140622) (xy 338.02574 -142.161514) (xy 338.018882 -142.169388)
			(xy 338.012532 -142.188438) (xy 338.020406 -142.28191) (xy 338.029804 -142.29969) (xy 338.037932 -142.306294)
			(xy 338.062353 -142.32703) (xy 338.106295 -142.373654) (xy 338.14403 -142.42543) (xy 338.174962 -142.481536)
			(xy 338.198599 -142.541084) (xy 338.214567 -142.60313) (xy 338.222614 -142.66669) (xy 338.223098 -142.698724)
			(xy 338.222596 -142.730685) (xy 338.214585 -142.794103) (xy 338.198688 -142.856017) (xy 338.175156 -142.91545)
			(xy 338.144362 -142.971465) (xy 338.106789 -143.02318) (xy 338.063032 -143.069777) (xy 338.013779 -143.110522)
			(xy 337.959808 -143.144773) (xy 337.901969 -143.17199) (xy 337.841176 -143.191743) (xy 337.778386 -143.203721)
			(xy 337.71459 -143.207735) (xy 337.650794 -143.203721) (xy 337.588004 -143.191743) (xy 337.527211 -143.17199)
			(xy 337.469372 -143.144773) (xy 337.415401 -143.110522) (xy 337.366148 -143.069777) (xy 337.322391 -143.02318)
			(xy 337.284818 -142.971465) (xy 337.254024 -142.91545) (xy 337.230492 -142.856017) (xy 337.214595 -142.794103)
			(xy 337.206584 -142.730685) (xy 337.206082 -142.698724) (xy 337.206639 -142.66462) (xy 337.215765 -142.597025)
			(xy 337.233843 -142.531256) (xy 337.260549 -142.468493) (xy 337.295403 -142.409862) (xy 337.337781 -142.356416)
			(xy 337.386922 -142.309113) (xy 337.414108 -142.288514) (xy 337.42249 -142.282418) (xy 337.432904 -142.265146)
			(xy 337.446112 -142.172436) (xy 337.440778 -142.152878) (xy 337.434428 -142.14475) (xy 337.419479 -142.124674)
			(xy 337.394429 -142.081337) (xy 337.375265 -142.035096) (xy 337.362318 -141.986744) (xy 337.355808 -141.937114)
			(xy 337.355434 -141.912086) (xy 337.356001 -141.883171) (xy 337.364718 -141.826001) (xy 337.381966 -141.770803)
			(xy 337.407348 -141.718841) (xy 337.440284 -141.671306) (xy 337.480018 -141.629287) (xy 337.5025 -141.611096)
			(xy 337.511259 -141.603531) (xy 337.521444 -141.582775) (xy 337.522058 -141.571218) (xy 337.522058 -141.490954)
			(xy 337.521471 -141.479388) (xy 337.51129 -141.458616) (xy 337.5025 -141.451076) (xy 337.480005 -141.432899)
			(xy 337.440271 -141.390876) (xy 337.407333 -141.343338) (xy 337.381946 -141.291374) (xy 337.364693 -141.236174)
			(xy 337.355967 -141.179003) (xy 337.355434 -141.150086) (xy 337.355908 -141.122828) (xy 337.363677 -141.068869)
			(xy 337.37904 -141.016563) (xy 337.401686 -140.966973) (xy 337.431154 -140.921108) (xy 337.466844 -140.879899)
			(xy 337.508032 -140.844185) (xy 337.530694 -140.82903) (xy 337.537652 -140.824166) (xy 337.548179 -140.810864)
			(xy 337.553746 -140.79484) (xy 337.554062 -140.786358) (xy 337.554062 -140.701014) (xy 337.553686 -140.69254)
			(xy 337.548117 -140.676531) (xy 337.537644 -140.663202) (xy 337.530694 -140.658342) (xy 337.508019 -140.643207)
			(xy 337.466832 -140.607493) (xy 337.431144 -140.566282) (xy 337.401682 -140.520414) (xy 337.379044 -140.470821)
			(xy 337.363693 -140.418511) (xy 337.355938 -140.36455) (xy 337.355939 -140.310035) (xy 337.363696 -140.256074)
			(xy 337.37905 -140.203765) (xy 337.401689 -140.154173) (xy 337.431153 -140.108306) (xy 337.466843 -140.067096)
			(xy 337.508031 -140.031384) (xy 337.530694 -140.01623) (xy 337.537652 -140.011366) (xy 337.548179 -139.998064)
			(xy 337.553746 -139.98204) (xy 337.554062 -139.973558) (xy 337.554062 -139.888214) (xy 337.553686 -139.87974)
			(xy 337.548117 -139.863731) (xy 337.537644 -139.850402) (xy 337.530694 -139.845542) (xy 337.50803 -139.830389)
			(xy 337.466835 -139.794682) (xy 337.43114 -139.753475) (xy 337.401671 -139.707609) (xy 337.379029 -139.658017)
			(xy 337.363674 -139.605707) (xy 337.355919 -139.551744) (xy 337.355434 -139.524486) (xy 337.355875 -139.498106)
			(xy 337.36313 -139.445848) (xy 337.377514 -139.395087) (xy 337.398753 -139.346791) (xy 337.426441 -139.301881)
			(xy 337.460052 -139.261212) (xy 337.498943 -139.225561) (xy 337.542374 -139.195606) (xy 337.565746 -139.183364)
			(xy 337.578954 -139.177014) (xy 337.59394 -139.15263) (xy 337.59394 -139.032742) (xy 337.578954 -139.008358)
			(xy 337.565746 -139.002008) (xy 337.542124 -138.989623) (xy 337.498264 -138.959273) (xy 337.459052 -138.923116)
			(xy 337.425252 -138.881856) (xy 337.39752 -138.836296) (xy 337.376397 -138.78732) (xy 337.368896 -138.761724)
			(xy 337.365594 -138.749278) (xy 337.348322 -138.73099) (xy 337.243674 -138.696192) (xy 337.219036 -138.70051)
			(xy 337.208876 -138.708384) (xy 337.188733 -138.723514) (xy 337.145208 -138.748886) (xy 337.09872 -138.768301)
			(xy 337.050078 -138.781419) (xy 337.000132 -138.788011) (xy 336.974942 -138.788394) (xy 336.947686 -138.787962)
			(xy 336.893729 -138.78021) (xy 336.841424 -138.764857) (xy 336.791836 -138.742216) (xy 336.745976 -138.712748)
			(xy 336.704777 -138.677053) (xy 336.669078 -138.635857) (xy 336.639605 -138.59) (xy 336.616958 -138.540416)
			(xy 336.601599 -138.488112) (xy 336.593841 -138.434156) (xy 329.059383 -138.434156) (xy 329.010206 -138.472791)
			(xy 328.945456 -138.513872) (xy 328.87691 -138.548246) (xy 328.805259 -138.575566) (xy 328.731228 -138.595556)
			(xy 328.655565 -138.608014) (xy 328.617326 -138.610848) (xy 328.607942 -138.611837) (xy 328.590844 -138.619791)
			(xy 328.584052 -138.626342) (xy 328.563224 -138.647932) (xy 328.556779 -138.65523) (xy 328.549465 -138.673258)
			(xy 328.549 -138.682984) (xy 328.549 -140.408152) (xy 331.943966 -140.408152) (xy 331.94801 -140.329698)
			(xy 331.960099 -140.252076) (xy 331.980106 -140.176108) (xy 332.007817 -140.1026) (xy 332.04294 -140.032331)
			(xy 332.085102 -139.966046) (xy 332.133856 -139.904447) (xy 332.188685 -139.848187) (xy 332.249008 -139.797863)
			(xy 332.314186 -139.754009) (xy 332.383527 -139.717088) (xy 332.456298 -139.687493) (xy 332.531725 -139.665538)
			(xy 332.60901 -139.651454) (xy 332.687334 -139.645391) (xy 332.765866 -139.647414) (xy 332.843774 -139.6575)
			(xy 332.920231 -139.675544) (xy 332.994429 -139.701354) (xy 333.065579 -139.734656) (xy 333.132928 -139.775097)
			(xy 333.195762 -139.822248) (xy 333.253414 -139.875611) (xy 333.305274 -139.934618) (xy 333.350793 -139.998645)
			(xy 333.389486 -140.067013) (xy 333.420945 -140.138997) (xy 333.444836 -140.213834) (xy 333.460905 -140.290731)
			(xy 333.468982 -140.368873) (xy 333.469488 -140.408152) (xy 333.468982 -140.447431) (xy 333.460905 -140.525573)
			(xy 333.444836 -140.60247) (xy 333.420945 -140.677307) (xy 333.389486 -140.749291) (xy 333.350793 -140.817659)
			(xy 333.305274 -140.881686) (xy 333.253414 -140.940693) (xy 333.195762 -140.994056) (xy 333.132928 -141.041207)
			(xy 333.065579 -141.081648) (xy 332.994429 -141.11495) (xy 332.920231 -141.14076) (xy 332.843774 -141.158804)
			(xy 332.765866 -141.16889) (xy 332.687334 -141.170913) (xy 332.60901 -141.16485) (xy 332.531725 -141.150766)
			(xy 332.456298 -141.128811) (xy 332.383527 -141.099216) (xy 332.314186 -141.062295) (xy 332.249008 -141.018441)
			(xy 332.188685 -140.968117) (xy 332.133856 -140.911857) (xy 332.085102 -140.850258) (xy 332.04294 -140.783973)
			(xy 332.007817 -140.713704) (xy 331.980106 -140.640196) (xy 331.960099 -140.564228) (xy 331.94801 -140.486606)
			(xy 331.943966 -140.408152) (xy 328.549 -140.408152) (xy 328.549 -141.074902) (xy 330.241146 -141.074902)
			(xy 330.245217 -141.01928) (xy 330.257343 -140.964843) (xy 330.277266 -140.912752) (xy 330.304562 -140.864117)
			(xy 330.338648 -140.819974) (xy 330.378797 -140.781265) (xy 330.424155 -140.748814) (xy 330.473755 -140.723313)
			(xy 330.526539 -140.705306) (xy 330.581382 -140.695176) (xy 330.637116 -140.693139) (xy 330.692553 -140.699239)
			(xy 330.74651 -140.713345) (xy 330.797839 -140.735157) (xy 330.845445 -140.764211) (xy 330.888313 -140.799886)
			(xy 330.92553 -140.841423) (xy 330.956303 -140.887936) (xy 330.979975 -140.938433) (xy 330.996043 -140.99184)
			(xy 331.004163 -141.047016) (xy 331.004672 -141.074902) (xy 331.004163 -141.102788) (xy 330.996043 -141.157964)
			(xy 330.979975 -141.211371) (xy 330.956303 -141.261868) (xy 330.92553 -141.308381) (xy 330.888313 -141.349918)
			(xy 330.845445 -141.385593) (xy 330.797839 -141.414647) (xy 330.74651 -141.436459) (xy 330.692553 -141.450565)
			(xy 330.637116 -141.456665) (xy 330.581382 -141.454628) (xy 330.526539 -141.444498) (xy 330.473755 -141.426491)
			(xy 330.424155 -141.40099) (xy 330.378797 -141.368539) (xy 330.338648 -141.32983) (xy 330.304562 -141.285687)
			(xy 330.277266 -141.237052) (xy 330.257343 -141.184961) (xy 330.245217 -141.130524) (xy 330.241146 -141.074902)
			(xy 328.549 -141.074902) (xy 328.549 -141.755114) (xy 328.549668 -141.767141) (xy 328.560529 -141.788606)
			(xy 328.569828 -141.796262) (xy 328.646028 -141.851888) (xy 328.669904 -141.855698) (xy 328.681588 -141.851888)
			(xy 328.719273 -141.84033) (xy 328.796426 -141.824153) (xy 328.874837 -141.816039) (xy 328.914252 -141.815566)
			(xy 328.952901 -141.816037) (xy 329.029803 -141.823853) (xy 329.105519 -141.839408) (xy 329.179273 -141.862545)
			(xy 329.250308 -141.893024) (xy 329.317894 -141.930534) (xy 329.381339 -141.974689) (xy 329.439991 -142.025037)
			(xy 329.493249 -142.08106) (xy 329.540565 -142.142184) (xy 329.581454 -142.207782) (xy 329.615497 -142.277179)
			(xy 329.642344 -142.349665) (xy 329.661719 -142.424495) (xy 329.673425 -142.500901) (xy 329.67734 -142.5781)
			(xy 329.673425 -142.655299) (xy 329.661719 -142.731705) (xy 329.642344 -142.806535) (xy 329.615497 -142.879021)
			(xy 329.581454 -142.948418) (xy 329.545997 -143.005302) (xy 331.791056 -143.005302) (xy 331.791438 -142.978254)
			(xy 331.79908 -142.924699) (xy 331.814209 -142.872761) (xy 331.836522 -142.82348) (xy 331.865573 -142.777846)
			(xy 331.900779 -142.736772) (xy 331.941434 -142.701084) (xy 331.986721 -142.671495) (xy 332.035735 -142.6486)
			(xy 332.087491 -142.632858) (xy 332.140951 -142.624585) (xy 332.167992 -142.623794) (xy 332.181479 -142.623246)
			(xy 332.207438 -142.615872) (xy 332.230558 -142.601954) (xy 332.249224 -142.582466) (xy 332.262134 -142.558769)
			(xy 332.268384 -142.532517) (xy 332.267539 -142.505545) (xy 332.259658 -142.479736) (xy 332.252828 -142.468092)
			(xy 332.234277 -142.437531) (xy 332.205031 -142.372296) (xy 332.185209 -142.303607) (xy 332.175201 -142.23282)
			(xy 332.174596 -142.197074) (xy 332.175095 -142.165535) (xy 332.182901 -142.102942) (xy 332.198388 -142.041795)
			(xy 332.22132 -141.983033) (xy 332.251345 -141.927559) (xy 332.288 -141.876224) (xy 332.330724 -141.829818)
			(xy 332.378859 -141.789053) (xy 332.431667 -141.754554) (xy 332.488337 -141.726853) (xy 332.547998 -141.706373)
			(xy 332.609734 -141.693431) (xy 332.672597 -141.688224) (xy 332.735621 -141.690833) (xy 332.797839 -141.701217)
			(xy 332.858294 -141.719217) (xy 332.916058 -141.744556) (xy 332.970245 -141.776847) (xy 333.020022 -141.815591)
			(xy 333.064624 -141.860195) (xy 333.103366 -141.909973) (xy 333.135654 -141.964161) (xy 333.160991 -142.021927)
			(xy 333.178988 -142.082383) (xy 333.18937 -142.144601) (xy 333.191976 -142.207625) (xy 333.186766 -142.270488)
			(xy 333.173821 -142.332223) (xy 333.153339 -142.391883) (xy 333.125635 -142.448552) (xy 333.091134 -142.501358)
			(xy 333.050367 -142.549492) (xy 333.003959 -142.592214) (xy 332.952623 -142.628867) (xy 332.897147 -142.658889)
			(xy 332.838384 -142.681818) (xy 332.777237 -142.697303) (xy 332.714643 -142.705106) (xy 332.683104 -142.705582)
			(xy 332.668082 -142.705465) (xy 332.638091 -142.703685) (xy 332.62316 -142.702026) (xy 332.609709 -142.700871)
			(xy 332.583014 -142.70483) (xy 332.55829 -142.715649) (xy 332.537267 -142.732571) (xy 332.521416 -142.754413)
			(xy 332.511845 -142.779646) (xy 332.509224 -142.806506) (xy 332.513735 -142.833113) (xy 332.51902 -142.845536)
			(xy 332.530101 -142.870695) (xy 332.545708 -142.923408) (xy 332.553593 -142.977815) (xy 332.554072 -143.005302)
			(xy 332.553586 -143.032553) (xy 332.54583 -143.086501) (xy 332.530475 -143.138796) (xy 332.507833 -143.188373)
			(xy 332.478367 -143.234223) (xy 332.442676 -143.275414) (xy 332.401485 -143.311105) (xy 332.355635 -143.340571)
			(xy 332.306058 -143.363213) (xy 332.253763 -143.378568) (xy 332.199815 -143.386324) (xy 332.145313 -143.386324)
			(xy 332.091365 -143.378568) (xy 332.03907 -143.363213) (xy 331.989493 -143.340571) (xy 331.943643 -143.311105)
			(xy 331.902452 -143.275414) (xy 331.866761 -143.234223) (xy 331.837295 -143.188373) (xy 331.814653 -143.138796)
			(xy 331.799298 -143.086501) (xy 331.791542 -143.032553) (xy 331.791056 -143.005302) (xy 329.545997 -143.005302)
			(xy 329.540565 -143.014016) (xy 329.493249 -143.07514) (xy 329.439991 -143.131163) (xy 329.381339 -143.181511)
			(xy 329.317894 -143.225666) (xy 329.250308 -143.263176) (xy 329.179273 -143.293655) (xy 329.105519 -143.316792)
			(xy 329.029803 -143.332347) (xy 328.952901 -143.340163) (xy 328.914252 -143.340582) (xy 328.874839 -143.340082)
			(xy 328.796432 -143.331953) (xy 328.719279 -143.315794) (xy 328.681588 -143.30426) (xy 328.669904 -143.30045)
			(xy 328.646028 -143.30426) (xy 328.569828 -143.359886) (xy 328.560479 -143.367504) (xy 328.550835 -143.386556)
			(xy 333.949546 -143.386556) (xy 333.953617 -143.330934) (xy 333.965743 -143.276497) (xy 333.985666 -143.224406)
			(xy 334.012962 -143.175771) (xy 334.047048 -143.131628) (xy 334.087197 -143.092919) (xy 334.132555 -143.060468)
			(xy 334.182155 -143.034967) (xy 334.234939 -143.01696) (xy 334.289782 -143.00683) (xy 334.345516 -143.004793)
			(xy 334.400953 -143.010893) (xy 334.45491 -143.024999) (xy 334.506239 -143.046811) (xy 334.553845 -143.075865)
			(xy 334.596713 -143.11154) (xy 334.63393 -143.153077) (xy 334.664703 -143.19959) (xy 334.688375 -143.250087)
			(xy 334.704443 -143.303494) (xy 334.712563 -143.35867) (xy 334.713072 -143.386556) (xy 334.712563 -143.414442)
			(xy 334.704443 -143.469618) (xy 334.688375 -143.523025) (xy 334.664703 -143.573522) (xy 334.63393 -143.620035)
			(xy 334.596713 -143.661572) (xy 334.553845 -143.697247) (xy 334.506239 -143.726301) (xy 334.45491 -143.748113)
			(xy 334.400953 -143.762219) (xy 334.345516 -143.768319) (xy 334.289782 -143.766282) (xy 334.234939 -143.756152)
			(xy 334.182155 -143.738145) (xy 334.132555 -143.712644) (xy 334.087197 -143.680193) (xy 334.047048 -143.641484)
			(xy 334.012962 -143.597341) (xy 333.985666 -143.548706) (xy 333.965743 -143.496615) (xy 333.953617 -143.442178)
			(xy 333.949546 -143.386556) (xy 328.550835 -143.386556) (xy 328.549603 -143.388989) (xy 328.549 -143.401034)
			(xy 328.549 -145.031206) (xy 328.549254 -145.036794) (xy 329.065636 -149.747224) (xy 329.067237 -149.7574)
			(xy 329.077329 -149.775336) (xy 329.093634 -149.787894) (xy 329.103482 -149.790912) (xy 329.211178 -149.818598)
			(xy 329.240388 -149.807676) (xy 329.249786 -149.794468) (xy 329.265161 -149.773381) (xy 329.300751 -149.735211)
			(xy 329.341212 -149.70225) (xy 329.38579 -149.675113) (xy 329.433651 -149.654308) (xy 329.483902 -149.640222)
			(xy 329.535604 -149.63312) (xy 329.561698 -149.63267) (xy 329.59192 -149.633223) (xy 329.651615 -149.642711)
			(xy 329.709066 -149.661498) (xy 329.762833 -149.689112) (xy 329.811571 -149.724862) (xy 329.833224 -149.745954)
			(xy 329.840336 -149.75332) (xy 329.858878 -149.761194) (xy 329.952096 -149.76094) (xy 329.970638 -149.753066)
			(xy 329.978004 -149.7457) (xy 329.996014 -149.727871) (xy 330.035926 -149.696644) (xy 330.079621 -149.670976)
			(xy 330.12633 -149.651318) (xy 330.175231 -149.638018) (xy 330.225462 -149.631309) (xy 330.2508 -149.630892)
			(xy 330.278051 -149.631378) (xy 330.331999 -149.639134) (xy 330.384294 -149.654489) (xy 330.433871 -149.677131)
			(xy 330.479721 -149.706597) (xy 330.520912 -149.742288) (xy 330.556603 -149.783479) (xy 330.586069 -149.829329)
			(xy 330.608711 -149.878906) (xy 330.624066 -149.931201) (xy 330.624785 -149.9362) (xy 332.028292 -149.9362)
			(xy 332.02876 -149.90883) (xy 332.036578 -149.854651) (xy 332.052066 -149.802148) (xy 332.074908 -149.752401)
			(xy 332.104631 -149.706434) (xy 332.122272 -149.685502) (xy 332.128368 -149.67839) (xy 332.134718 -149.661372)
			(xy 332.134718 -149.576028) (xy 332.128368 -149.55901) (xy 332.122272 -149.551898) (xy 332.104614 -149.530981)
			(xy 332.074906 -149.485004) (xy 332.052074 -149.435252) (xy 332.036587 -149.382748) (xy 332.028764 -149.32857)
			(xy 332.028292 -149.3012) (xy 332.028778 -149.273949) (xy 332.036534 -149.220001) (xy 332.051889 -149.167706)
			(xy 332.074531 -149.118129) (xy 332.103997 -149.072279) (xy 332.139688 -149.031088) (xy 332.180879 -148.995397)
			(xy 332.226729 -148.965931) (xy 332.276306 -148.943289) (xy 332.328601 -148.927934) (xy 332.382549 -148.920178)
			(xy 332.437051 -148.920178) (xy 332.490999 -148.927934) (xy 332.543294 -148.943289) (xy 332.592871 -148.965931)
			(xy 332.638721 -148.995397) (xy 332.679912 -149.031088) (xy 332.715603 -149.072279) (xy 332.745069 -149.118129)
			(xy 332.767711 -149.167706) (xy 332.783066 -149.220001) (xy 332.790822 -149.273949) (xy 332.791308 -149.3012)
			(xy 332.79084 -149.32857) (xy 332.783022 -149.382749) (xy 332.767534 -149.435252) (xy 332.744692 -149.484999)
			(xy 332.714969 -149.530966) (xy 332.697328 -149.551898) (xy 332.691232 -149.55901) (xy 332.684882 -149.576028)
			(xy 332.684882 -149.661372) (xy 332.691232 -149.67839) (xy 332.697328 -149.685502) (xy 332.714986 -149.706419)
			(xy 332.744694 -149.752396) (xy 332.767526 -149.802148) (xy 332.783013 -149.854652) (xy 332.790836 -149.90883)
			(xy 332.791308 -149.9362) (xy 332.790822 -149.963451) (xy 332.783066 -150.017399) (xy 332.767711 -150.069694)
			(xy 332.745069 -150.119271) (xy 332.715603 -150.165121) (xy 332.679912 -150.206312) (xy 332.638721 -150.242003)
			(xy 332.592871 -150.271469) (xy 332.543294 -150.294111) (xy 332.490999 -150.309466) (xy 332.437051 -150.317222)
			(xy 332.382549 -150.317222) (xy 332.328601 -150.309466) (xy 332.276306 -150.294111) (xy 332.226729 -150.271469)
			(xy 332.180879 -150.242003) (xy 332.139688 -150.206312) (xy 332.103997 -150.165121) (xy 332.074531 -150.119271)
			(xy 332.051889 -150.069694) (xy 332.036534 -150.017399) (xy 332.028778 -149.963451) (xy 332.028292 -149.9362)
			(xy 330.624785 -149.9362) (xy 330.631822 -149.985149) (xy 330.631822 -150.039651) (xy 330.624066 -150.093599)
			(xy 330.608711 -150.145894) (xy 330.586069 -150.195471) (xy 330.556603 -150.241321) (xy 330.520912 -150.282512)
			(xy 330.479721 -150.318203) (xy 330.433871 -150.347669) (xy 330.384294 -150.370311) (xy 330.331999 -150.385666)
			(xy 330.278051 -150.393422) (xy 330.2508 -150.393908) (xy 330.220577 -150.393355) (xy 330.160881 -150.383868)
			(xy 330.103428 -150.365084) (xy 330.049658 -150.337474) (xy 330.000915 -150.301728) (xy 329.979274 -150.280624)
			(xy 329.972162 -150.273258) (xy 329.95362 -150.265384) (xy 329.860402 -150.265638) (xy 329.84186 -150.273512)
			(xy 329.834494 -150.280878) (xy 329.816485 -150.298707) (xy 329.776573 -150.329936) (xy 329.732878 -150.355606)
			(xy 329.686169 -150.375264) (xy 329.637268 -150.388565) (xy 329.587037 -150.395274) (xy 329.561698 -150.395686)
			(xy 329.53348 -150.395178) (xy 329.47766 -150.386867) (xy 329.423671 -150.370428) (xy 329.372692 -150.346218)
			(xy 329.325834 -150.314766) (xy 329.30465 -150.296118) (xy 329.292966 -150.28545) (xy 329.261724 -150.281132)
			(xy 329.162664 -150.331424) (xy 329.153729 -150.336522) (xy 329.14055 -150.352292) (xy 329.134579 -150.371959)
			(xy 329.135232 -150.382224) (xy 329.148208 -150.500588) (xy 334.204056 -150.500588) (xy 334.204616 -150.471672)
			(xy 334.213334 -150.414502) (xy 334.230582 -150.359303) (xy 334.255966 -150.307341) (xy 334.288903 -150.259806)
			(xy 334.328639 -150.217789) (xy 334.351122 -150.199598) (xy 334.359884 -150.192037) (xy 334.370067 -150.171277)
			(xy 334.37068 -150.15972) (xy 334.37068 -150.079456) (xy 334.370084 -150.067891) (xy 334.359908 -150.047119)
			(xy 334.351122 -150.039578) (xy 334.328633 -150.021394) (xy 334.288897 -149.979373) (xy 334.255958 -149.931837)
			(xy 334.23057 -149.879874) (xy 334.213316 -149.824675) (xy 334.204589 -149.767505) (xy 334.204056 -149.738588)
			(xy 334.204542 -149.711337) (xy 334.212298 -149.657389) (xy 334.227653 -149.605094) (xy 334.250295 -149.555517)
			(xy 334.279761 -149.509667) (xy 334.315452 -149.468476) (xy 334.356643 -149.432785) (xy 334.402493 -149.403319)
			(xy 334.45207 -149.380677) (xy 334.504365 -149.365322) (xy 334.558313 -149.357566) (xy 334.612815 -149.357566)
			(xy 334.666763 -149.365322) (xy 334.719058 -149.380677) (xy 334.768635 -149.403319) (xy 334.814485 -149.432785)
			(xy 334.855676 -149.468476) (xy 334.891367 -149.509667) (xy 334.920833 -149.555517) (xy 334.943475 -149.605094)
			(xy 334.95883 -149.657389) (xy 334.966586 -149.711337) (xy 334.967072 -149.738588) (xy 334.966556 -149.767505)
			(xy 334.957828 -149.824677) (xy 334.94057 -149.879876) (xy 334.915178 -149.931838) (xy 334.882234 -149.979372)
			(xy 334.842492 -150.021388) (xy 334.820006 -150.039578) (xy 334.811259 -150.047155) (xy 334.801067 -150.067902)
			(xy 334.800448 -150.079456) (xy 334.800448 -150.15972) (xy 334.801048 -150.171285) (xy 334.81122 -150.192057)
			(xy 334.820006 -150.199598) (xy 334.84249 -150.217789) (xy 334.882225 -150.259809) (xy 334.915163 -150.307344)
			(xy 334.940552 -150.359305) (xy 334.957808 -150.414503) (xy 334.966537 -150.471672) (xy 334.967072 -150.500588)
			(xy 336.261456 -150.500588) (xy 336.262016 -150.471672) (xy 336.270734 -150.414502) (xy 336.287982 -150.359303)
			(xy 336.313366 -150.307341) (xy 336.346303 -150.259806) (xy 336.386039 -150.217789) (xy 336.408522 -150.199598)
			(xy 336.417284 -150.192037) (xy 336.427467 -150.171277) (xy 336.42808 -150.15972) (xy 336.42808 -150.079456)
			(xy 336.427484 -150.067891) (xy 336.417308 -150.047119) (xy 336.408522 -150.039578) (xy 336.386033 -150.021394)
			(xy 336.346297 -149.979373) (xy 336.313358 -149.931837) (xy 336.28797 -149.879874) (xy 336.270716 -149.824675)
			(xy 336.261989 -149.767505) (xy 336.261456 -149.738588) (xy 336.261942 -149.711337) (xy 336.269698 -149.657389)
			(xy 336.285053 -149.605094) (xy 336.307695 -149.555517) (xy 336.337161 -149.509667) (xy 336.372852 -149.468476)
			(xy 336.414043 -149.432785) (xy 336.459893 -149.403319) (xy 336.50947 -149.380677) (xy 336.561765 -149.365322)
			(xy 336.615713 -149.357566) (xy 336.670215 -149.357566) (xy 336.724163 -149.365322) (xy 336.776458 -149.380677)
			(xy 336.826035 -149.403319) (xy 336.871885 -149.432785) (xy 336.913076 -149.468476) (xy 336.948767 -149.509667)
			(xy 336.978233 -149.555517) (xy 337.000875 -149.605094) (xy 337.01623 -149.657389) (xy 337.023986 -149.711337)
			(xy 337.024472 -149.738588) (xy 337.023956 -149.767505) (xy 337.015228 -149.824677) (xy 336.99797 -149.879876)
			(xy 336.972578 -149.931838) (xy 336.939634 -149.979372) (xy 336.899892 -150.021388) (xy 336.877406 -150.039578)
			(xy 336.868659 -150.047155) (xy 336.858467 -150.067902) (xy 336.857848 -150.079456) (xy 336.857848 -150.15972)
			(xy 336.858448 -150.171285) (xy 336.86862 -150.192057) (xy 336.877406 -150.199598) (xy 336.89989 -150.217789)
			(xy 336.939625 -150.259809) (xy 336.972563 -150.307344) (xy 336.997952 -150.359305) (xy 337.015208 -150.414503)
			(xy 337.023937 -150.471672) (xy 337.024472 -150.500588) (xy 337.023986 -150.527839) (xy 337.01623 -150.581787)
			(xy 337.000875 -150.634082) (xy 336.978233 -150.683659) (xy 336.948767 -150.729509) (xy 336.913076 -150.7707)
			(xy 336.871885 -150.806391) (xy 336.826035 -150.835857) (xy 336.776458 -150.858499) (xy 336.724163 -150.873854)
			(xy 336.670215 -150.88161) (xy 336.615713 -150.88161) (xy 336.561765 -150.873854) (xy 336.50947 -150.858499)
			(xy 336.459893 -150.835857) (xy 336.414043 -150.806391) (xy 336.372852 -150.7707) (xy 336.337161 -150.729509)
			(xy 336.307695 -150.683659) (xy 336.285053 -150.634082) (xy 336.269698 -150.581787) (xy 336.261942 -150.527839)
			(xy 336.261456 -150.500588) (xy 334.967072 -150.500588) (xy 334.966586 -150.527839) (xy 334.95883 -150.581787)
			(xy 334.943475 -150.634082) (xy 334.920833 -150.683659) (xy 334.891367 -150.729509) (xy 334.855676 -150.7707)
			(xy 334.814485 -150.806391) (xy 334.768635 -150.835857) (xy 334.719058 -150.858499) (xy 334.666763 -150.873854)
			(xy 334.612815 -150.88161) (xy 334.558313 -150.88161) (xy 334.504365 -150.873854) (xy 334.45207 -150.858499)
			(xy 334.402493 -150.835857) (xy 334.356643 -150.806391) (xy 334.315452 -150.7707) (xy 334.279761 -150.729509)
			(xy 334.250295 -150.683659) (xy 334.227653 -150.634082) (xy 334.212298 -150.581787) (xy 334.204542 -150.527839)
			(xy 334.204056 -150.500588) (xy 329.148208 -150.500588) (xy 329.713844 -155.660344) (xy 329.715137 -155.668908)
			(xy 329.72267 -155.68449) (xy 329.728576 -155.690824) (xy 329.809348 -155.77185) (xy 329.809348 -155.781502)
			(xy 329.812904 -155.790646) (xy 330.261722 -156.934662) (xy 330.264008 -156.939742) (xy 330.730606 -157.828742)
			(xy 330.801472 -157.96387) (xy 330.805028 -157.970728) (xy 332.092554 -159.258254) (xy 332.099953 -159.265097)
			(xy 332.118552 -159.272819) (xy 332.128622 -159.27324)
		)
		(stroke
			(width 0)
			(type solid)
		)
		(fill yes)
		(layer "In11.Cu")
		(net "PVDD18_S5_P0")
	)
	(gr_poly
		(pts
			(xy 239.24641 -231.422448) (xy 239.256478 -231.422022) (xy 239.275075 -231.414299) (xy 239.282478 -231.407462)
			(xy 240.328196 -230.361744) (xy 240.335034 -230.354343) (xy 240.342749 -230.335744) (xy 240.343182 -230.325676)
			(xy 240.343182 -227.447856) (xy 240.34275 -227.43779) (xy 240.335023 -227.419199) (xy 240.328196 -227.411788)
			(xy 239.80648 -226.890072) (xy 239.796066 -226.881944) (xy 239.767164 -226.864739) (xy 239.713742 -226.823868)
			(xy 239.666177 -226.776309) (xy 239.625299 -226.722893) (xy 239.608106 -226.693984) (xy 239.599978 -226.68357)
			(xy 236.561122 -223.644714) (xy 236.553773 -223.637914) (xy 236.53531 -223.630208) (xy 236.525308 -223.629728)
			(xy 236.495082 -223.629474) (xy 236.48566 -223.629913) (xy 236.468074 -223.636687) (xy 236.460792 -223.642682)
			(xy 236.437343 -223.66331) (xy 236.386293 -223.699288) (xy 236.331221 -223.728742) (xy 236.272955 -223.751229)
			(xy 236.212374 -223.766409) (xy 236.150389 -223.774054) (xy 236.119162 -223.774508) (xy 236.088433 -223.774042)
			(xy 236.027422 -223.766629) (xy 235.96775 -223.751918) (xy 235.910286 -223.730121) (xy 235.855868 -223.701556)
			(xy 235.80529 -223.666641) (xy 235.759289 -223.625884) (xy 235.718535 -223.57988) (xy 235.683624 -223.529299)
			(xy 235.655064 -223.474879) (xy 235.633271 -223.417414) (xy 235.618564 -223.357741) (xy 235.611156 -223.29673)
			(xy 235.610654 -223.266) (xy 235.611035 -223.238593) (xy 235.616959 -223.184099) (xy 235.628706 -223.130558)
			(xy 235.63707 -223.104456) (xy 235.64088 -223.092772) (xy 235.637324 -223.068642) (xy 235.581952 -222.99168)
			(xy 235.574286 -222.982266) (xy 235.552674 -222.971282) (xy 235.54055 -222.970598) (xy 220.848428 -222.970598)
			(xy 220.838364 -222.970162) (xy 220.819778 -222.962429) (xy 220.81236 -222.955612) (xy 212.58276 -214.726012)
			(xy 212.575905 -214.718617) (xy 212.568157 -214.700018) (xy 212.567774 -214.689944) (xy 212.567774 -195.984622)
			(xy 212.567336 -195.974559) (xy 212.559599 -195.955977) (xy 212.552788 -195.948554) (xy 209.617056 -193.012822)
			(xy 209.60969 -193.005998) (xy 209.591179 -192.998256) (xy 209.571114 -192.998198) (xy 209.561684 -193.001646)
			(xy 209.460592 -193.043556) (xy 209.443574 -193.068702) (xy 209.443574 -193.08445) (xy 209.443008 -193.116588)
			(xy 209.434754 -193.180335) (xy 209.418525 -193.242531) (xy 209.394578 -193.302182) (xy 209.363298 -193.358336)
			(xy 209.325183 -193.410095) (xy 209.303366 -193.4337) (xy 209.296254 -193.440812) (xy 209.289142 -193.459354)
			(xy 209.290412 -193.55054) (xy 209.298032 -193.568574) (xy 209.305144 -193.575686) (xy 209.329457 -193.600611)
			(xy 209.371731 -193.655938) (xy 209.406057 -193.716518) (xy 209.419444 -193.74866) (xy 209.424264 -193.759318)
			(xy 209.441531 -193.77506) (xy 209.463967 -193.781584) (xy 209.475578 -193.780156) (xy 209.497864 -193.776366)
			(xy 209.54289 -193.772296) (xy 209.565494 -193.772028) (xy 209.596226 -193.772473) (xy 209.657241 -193.779882)
			(xy 209.716918 -193.794591) (xy 209.774386 -193.816386) (xy 209.828809 -193.84495) (xy 209.879391 -193.879866)
			(xy 209.925396 -193.920625) (xy 209.966152 -193.966632) (xy 210.001065 -194.017217) (xy 210.029626 -194.071641)
			(xy 210.051418 -194.129111) (xy 210.066124 -194.188789) (xy 210.073529 -194.249804) (xy 210.074002 -194.280536)
			(xy 210.07351 -194.312737) (xy 210.065383 -194.376623) (xy 210.049251 -194.438972) (xy 210.025373 -194.498783)
			(xy 209.994132 -194.555099) (xy 209.956027 -194.607018) (xy 209.911669 -194.653707) (xy 209.861769 -194.69442)
			(xy 209.807126 -194.728503) (xy 209.748615 -194.755411) (xy 209.687174 -194.774713) (xy 209.623787 -194.786099)
			(xy 209.591656 -194.788282) (xy 209.581242 -194.78879) (xy 209.5627 -194.797934) (xy 209.501232 -194.869308)
			(xy 209.494882 -194.88912) (xy 209.495898 -194.899534) (xy 209.496975 -194.91157) (xy 209.498118 -194.93571)
			(xy 209.498184 -194.947794) (xy 209.497676 -194.972178) (xy 209.497168 -194.9831) (xy 209.505042 -195.00342)
			(xy 209.575908 -195.071746) (xy 209.596482 -195.079112) (xy 209.607404 -195.07835) (xy 209.64906 -195.076572)
			(xy 209.681025 -195.077051) (xy 209.744452 -195.085059) (xy 209.806375 -195.100953) (xy 209.865818 -195.124484)
			(xy 209.921842 -195.15528) (xy 209.973564 -195.192855) (xy 210.020169 -195.236616) (xy 210.060922 -195.285874)
			(xy 210.095179 -195.339851) (xy 210.122401 -195.397697) (xy 210.142157 -195.458498) (xy 210.154137 -195.521296)
			(xy 210.158152 -195.5851) (xy 210.154137 -195.648904) (xy 210.142157 -195.711702) (xy 210.122401 -195.772503)
			(xy 210.095179 -195.830349) (xy 210.060922 -195.884326) (xy 210.020169 -195.933584) (xy 209.973564 -195.977345)
			(xy 209.921842 -196.01492) (xy 209.865817 -196.045716) (xy 209.806375 -196.069247) (xy 209.744452 -196.085141)
			(xy 209.681025 -196.093149) (xy 209.64906 -196.093588) (xy 209.607658 -196.09181) (xy 209.596736 -196.091048)
			(xy 209.576162 -196.098414) (xy 209.50555 -196.166232) (xy 209.497422 -196.186298) (xy 209.497676 -196.19722)
			(xy 209.498184 -196.217794) (xy 209.497706 -196.248489) (xy 209.490286 -196.30943) (xy 209.47559 -196.369036)
			(xy 209.453831 -196.426442) (xy 209.425324 -196.480814) (xy 209.408268 -196.506338) (xy 209.402798 -196.515091)
			(xy 209.398669 -196.535295) (xy 209.402794 -196.5555) (xy 209.408268 -196.56425) (xy 209.425321 -196.589778)
			(xy 209.453845 -196.644141) (xy 209.47561 -196.701545) (xy 209.490299 -196.761154) (xy 209.497697 -196.822098)
			(xy 209.498184 -196.852794) (xy 209.497706 -196.883489) (xy 209.490286 -196.94443) (xy 209.47559 -197.004036)
			(xy 209.453831 -197.061442) (xy 209.425324 -197.115814) (xy 209.408268 -197.141338) (xy 209.402798 -197.150091)
			(xy 209.398669 -197.170295) (xy 209.402794 -197.1905) (xy 209.408268 -197.19925) (xy 209.425321 -197.224778)
			(xy 209.453845 -197.279141) (xy 209.47561 -197.336545) (xy 209.490299 -197.396154) (xy 209.497697 -197.457098)
			(xy 209.498184 -197.487794) (xy 209.49763 -197.521608) (xy 209.488674 -197.588641) (xy 209.470917 -197.653897)
			(xy 209.444673 -197.716226) (xy 209.410404 -197.77453) (xy 209.38998 -197.801484) (xy 209.383169 -197.811189)
			(xy 209.378448 -197.834393) (xy 209.384593 -197.857262) (xy 209.392012 -197.866508) (xy 209.412193 -197.889851)
			(xy 209.447353 -197.940562) (xy 209.476121 -197.995154) (xy 209.498073 -198.052824) (xy 209.512889 -198.112727)
			(xy 209.520349 -198.173982) (xy 209.52079 -198.204836) (xy 209.520342 -198.234435) (xy 209.513436 -198.293229)
			(xy 209.499759 -198.350825) (xy 209.479493 -198.406446) (xy 209.452912 -198.459341) (xy 209.420376 -198.508796)
			(xy 209.401664 -198.531734) (xy 209.396196 -198.538727) (xy 209.390072 -198.555377) (xy 209.389726 -198.564246)
			(xy 209.389726 -198.594218) (xy 209.389962 -198.603046) (xy 209.395818 -198.619695) (xy 209.401156 -198.62673)
			(xy 209.422775 -198.654084) (xy 209.459114 -198.713589) (xy 209.486984 -198.777499) (xy 209.505862 -198.844618)
			(xy 209.515393 -198.913687) (xy 209.515964 -198.948548) (xy 209.515425 -198.981817) (xy 209.506754 -199.047788)
			(xy 209.489553 -199.112065) (xy 209.464117 -199.17355) (xy 209.430879 -199.231192) (xy 209.411062 -199.25792)
			(xy 209.405008 -199.266678) (xy 209.399974 -199.287339) (xy 209.403742 -199.308267) (xy 209.409284 -199.317356)
			(xy 209.425961 -199.342691) (xy 209.453832 -199.396564) (xy 209.475097 -199.45337) (xy 209.489453 -199.512303)
			(xy 209.496697 -199.572524) (xy 209.497168 -199.602852) (xy 209.496705 -199.634229) (xy 209.488985 -199.696506)
			(xy 209.473657 -199.75736) (xy 209.450954 -199.815863) (xy 209.421222 -199.871126) (xy 209.403442 -199.896984)
			(xy 209.397883 -199.905739) (xy 209.393633 -199.926016) (xy 209.397738 -199.946324) (xy 209.403188 -199.95515)
			(xy 209.420154 -199.980655) (xy 209.448526 -200.034947) (xy 209.470176 -200.092253) (xy 209.48479 -200.151743)
			(xy 209.492157 -200.212557) (xy 209.492596 -200.243186) (xy 209.492118 -200.274192) (xy 209.484547 -200.335741)
			(xy 209.469554 -200.395914) (xy 209.44736 -200.453818) (xy 209.418295 -200.508597) (xy 209.400902 -200.53427)
			(xy 209.396257 -200.541607) (xy 209.391721 -200.558357) (xy 209.392012 -200.567036) (xy 209.394044 -200.596754)
			(xy 209.395034 -200.605369) (xy 209.402055 -200.62121) (xy 209.40776 -200.627742) (xy 209.429343 -200.651382)
			(xy 209.467016 -200.703136) (xy 209.497895 -200.75921) (xy 209.521491 -200.818717) (xy 209.537431 -200.880715)
			(xy 209.545462 -200.944223) (xy 209.545936 -200.97623) (xy 209.545498 -201.006501) (xy 209.538306 -201.066614)
			(xy 209.524028 -201.125448) (xy 209.502865 -201.182171) (xy 209.475117 -201.235979) (xy 209.441177 -201.286113)
			(xy 209.401524 -201.331862) (xy 209.35672 -201.372579) (xy 209.332322 -201.390504) (xy 209.32267 -201.397362)
			(xy 209.311494 -201.417682) (xy 209.306414 -201.520806) (xy 209.315558 -201.542142) (xy 209.324194 -201.549762)
			(xy 209.347234 -201.570494) (xy 209.388619 -201.616637) (xy 209.424086 -201.667469) (xy 209.453111 -201.722236)
			(xy 209.475262 -201.780125) (xy 209.49021 -201.840278) (xy 209.497735 -201.901803) (xy 209.498184 -201.932794)
			(xy 209.497706 -201.963489) (xy 209.490286 -202.02443) (xy 209.47559 -202.084036) (xy 209.453831 -202.141442)
			(xy 209.425324 -202.195814) (xy 209.408268 -202.221338) (xy 209.402798 -202.230091) (xy 209.398669 -202.250295)
			(xy 209.402794 -202.2705) (xy 209.408268 -202.27925) (xy 209.425321 -202.304778) (xy 209.453845 -202.359141)
			(xy 209.47561 -202.416545) (xy 209.490299 -202.476154) (xy 209.497697 -202.537098) (xy 209.498184 -202.567794)
			(xy 209.497706 -202.598489) (xy 209.490286 -202.65943) (xy 209.47559 -202.719036) (xy 209.453831 -202.776442)
			(xy 209.425324 -202.830814) (xy 209.408268 -202.856338) (xy 209.402798 -202.865091) (xy 209.398669 -202.885295)
			(xy 209.402794 -202.9055) (xy 209.408268 -202.91425) (xy 209.425321 -202.939778) (xy 209.453845 -202.994141)
			(xy 209.47561 -203.051545) (xy 209.490299 -203.111154) (xy 209.497697 -203.172098) (xy 209.498184 -203.202794)
			(xy 209.497625 -203.236672) (xy 209.488627 -203.303829) (xy 209.47079 -203.369196) (xy 209.44443 -203.431614)
			(xy 209.410013 -203.489979) (xy 209.36815 -203.543256) (xy 209.34426 -203.567284) (xy 209.338145 -203.573725)
			(xy 209.330454 -203.589724) (xy 209.329274 -203.598526) (xy 209.326226 -203.628244) (xy 209.325672 -203.63714)
			(xy 209.329946 -203.65443) (xy 209.334608 -203.662026) (xy 209.35121 -203.687332) (xy 209.378945 -203.741129)
			(xy 209.4001 -203.797837) (xy 209.414375 -203.856655) (xy 209.421569 -203.916751) (xy 209.421984 -203.947014)
			(xy 209.421482 -203.978975) (xy 209.413471 -204.042393) (xy 209.397574 -204.104307) (xy 209.374042 -204.16374)
			(xy 209.343248 -204.219755) (xy 209.305675 -204.27147) (xy 209.261918 -204.318067) (xy 209.212665 -204.358812)
			(xy 209.158694 -204.393063) (xy 209.100855 -204.42028) (xy 209.040062 -204.440033) (xy 208.977272 -204.452011)
			(xy 208.913476 -204.456025) (xy 208.84968 -204.452011) (xy 208.78689 -204.440033) (xy 208.726097 -204.42028)
			(xy 208.668258 -204.393063) (xy 208.614287 -204.358812) (xy 208.565034 -204.318067) (xy 208.521277 -204.27147)
			(xy 208.483704 -204.219755) (xy 208.45291 -204.16374) (xy 208.429378 -204.104307) (xy 208.413481 -204.042393)
			(xy 208.40547 -203.978975) (xy 208.404968 -203.947014) (xy 208.405527 -203.913135) (xy 208.414523 -203.845977)
			(xy 208.432358 -203.780609) (xy 208.458716 -203.718188) (xy 208.493129 -203.65982) (xy 208.534989 -203.606539)
			(xy 208.558892 -203.582524) (xy 208.56499 -203.576075) (xy 208.572643 -203.560073) (xy 208.573878 -203.551282)
			(xy 208.576926 -203.521564) (xy 208.577464 -203.512673) (xy 208.57316 -203.495402) (xy 208.568544 -203.487782)
			(xy 208.551943 -203.462475) (xy 208.524209 -203.408678) (xy 208.503056 -203.35197) (xy 208.488781 -203.293153)
			(xy 208.481587 -203.233056) (xy 208.481168 -203.202794) (xy 208.481647 -203.172099) (xy 208.489069 -203.111159)
			(xy 208.503767 -203.051554) (xy 208.52553 -202.994151) (xy 208.554039 -202.939782) (xy 208.571084 -202.91425)
			(xy 208.576556 -202.905499) (xy 208.580684 -202.885295) (xy 208.576552 -202.865092) (xy 208.571084 -202.856338)
			(xy 208.554028 -202.830811) (xy 208.525498 -202.776449) (xy 208.503725 -202.719045) (xy 208.489027 -202.659436)
			(xy 208.481618 -202.598491) (xy 208.481168 -202.567794) (xy 208.481647 -202.537099) (xy 208.489069 -202.476159)
			(xy 208.503767 -202.416554) (xy 208.52553 -202.359151) (xy 208.554039 -202.304782) (xy 208.571084 -202.27925)
			(xy 208.576556 -202.270499) (xy 208.580684 -202.250295) (xy 208.576552 -202.230092) (xy 208.571084 -202.221338)
			(xy 208.554028 -202.195811) (xy 208.525498 -202.141449) (xy 208.503725 -202.084045) (xy 208.489027 -202.024436)
			(xy 208.481618 -201.963491) (xy 208.481168 -201.932794) (xy 208.481605 -201.902522) (xy 208.488794 -201.842408)
			(xy 208.50307 -201.783572) (xy 208.524231 -201.726847) (xy 208.551978 -201.673037) (xy 208.585918 -201.622901)
			(xy 208.62557 -201.57715) (xy 208.670374 -201.536431) (xy 208.694782 -201.51852) (xy 208.704434 -201.511662)
			(xy 208.71561 -201.491342) (xy 208.72069 -201.388218) (xy 208.711546 -201.366882) (xy 208.70291 -201.359262)
			(xy 208.679869 -201.33853) (xy 208.638482 -201.292388) (xy 208.603011 -201.241557) (xy 208.573984 -201.18679)
			(xy 208.55183 -201.1289) (xy 208.536879 -201.068747) (xy 208.529351 -201.007222) (xy 208.52892 -200.97623)
			(xy 208.529398 -200.945224) (xy 208.536966 -200.883674) (xy 208.551958 -200.823501) (xy 208.574151 -200.765595)
			(xy 208.603216 -200.710815) (xy 208.620614 -200.685146) (xy 208.62526 -200.67781) (xy 208.6298 -200.661059)
			(xy 208.629504 -200.65238) (xy 208.627472 -200.622662) (xy 208.626484 -200.614046) (xy 208.619469 -200.598199)
			(xy 208.613756 -200.591674) (xy 208.592171 -200.568035) (xy 208.554495 -200.516281) (xy 208.523614 -200.460207)
			(xy 208.500016 -200.400701) (xy 208.484073 -200.338702) (xy 208.47604 -200.275194) (xy 208.47558 -200.243186)
			(xy 208.476047 -200.21181) (xy 208.483773 -200.149535) (xy 208.499106 -200.088685) (xy 208.521812 -200.030185)
			(xy 208.551547 -199.974925) (xy 208.569306 -199.949054) (xy 208.574868 -199.940297) (xy 208.579129 -199.920015)
			(xy 208.575038 -199.899698) (xy 208.56956 -199.890888) (xy 208.552599 -199.865381) (xy 208.524236 -199.811087)
			(xy 208.502595 -199.753781) (xy 208.48799 -199.694292) (xy 208.480631 -199.63348) (xy 208.480152 -199.602852)
			(xy 208.480691 -199.569583) (xy 208.489363 -199.503612) (xy 208.506564 -199.439336) (xy 208.532001 -199.377851)
			(xy 208.565239 -199.32021) (xy 208.585054 -199.29348) (xy 208.591107 -199.284722) (xy 208.596139 -199.264061)
			(xy 208.592372 -199.243133) (xy 208.586832 -199.234044) (xy 208.570155 -199.208709) (xy 208.542283 -199.154836)
			(xy 208.521018 -199.09803) (xy 208.506661 -199.039098) (xy 208.499416 -198.978876) (xy 208.498948 -198.948548)
			(xy 208.499397 -198.91895) (xy 208.506305 -198.860157) (xy 208.519985 -198.802562) (xy 208.540253 -198.746943)
			(xy 208.566836 -198.69405) (xy 208.599375 -198.644598) (xy 208.618074 -198.62165) (xy 208.623537 -198.614656)
			(xy 208.629651 -198.598006) (xy 208.630012 -198.589138) (xy 208.630012 -198.559166) (xy 208.629772 -198.55034)
			(xy 208.623906 -198.533699) (xy 208.618582 -198.526654) (xy 208.596966 -198.499298) (xy 208.560633 -198.439792)
			(xy 208.532769 -198.375881) (xy 208.513896 -198.308763) (xy 208.504368 -198.239696) (xy 208.503774 -198.204836)
			(xy 208.504332 -198.171024) (xy 208.513298 -198.103995) (xy 208.531064 -198.038746) (xy 208.557317 -197.976424)
			(xy 208.591594 -197.918129) (xy 208.611978 -197.891146) (xy 208.618766 -197.88144) (xy 208.623453 -197.858254)
			(xy 208.617296 -197.835413) (xy 208.609946 -197.826122) (xy 208.589767 -197.802778) (xy 208.55461 -197.752067)
			(xy 208.525846 -197.697475) (xy 208.503899 -197.639804) (xy 208.48909 -197.579901) (xy 208.481637 -197.518647)
			(xy 208.481168 -197.487794) (xy 208.481647 -197.457099) (xy 208.489069 -197.396159) (xy 208.503767 -197.336554)
			(xy 208.52553 -197.279151) (xy 208.554039 -197.224782) (xy 208.571084 -197.19925) (xy 208.576556 -197.190499)
			(xy 208.580684 -197.170295) (xy 208.576552 -197.150092) (xy 208.571084 -197.141338) (xy 208.554028 -197.115811)
			(xy 208.525498 -197.061449) (xy 208.503725 -197.004045) (xy 208.489027 -196.944436) (xy 208.481618 -196.883491)
			(xy 208.481168 -196.852794) (xy 208.481647 -196.822099) (xy 208.489069 -196.761159) (xy 208.503767 -196.701554)
			(xy 208.52553 -196.644151) (xy 208.554039 -196.589782) (xy 208.571084 -196.56425) (xy 208.576556 -196.555499)
			(xy 208.580684 -196.535295) (xy 208.576552 -196.515092) (xy 208.571084 -196.506338) (xy 208.554028 -196.480811)
			(xy 208.525498 -196.426449) (xy 208.503725 -196.369045) (xy 208.489027 -196.309436) (xy 208.481618 -196.248491)
			(xy 208.481168 -196.217794) (xy 208.481632 -196.187063) (xy 208.489041 -196.126048) (xy 208.50375 -196.066372)
			(xy 208.525545 -196.008903) (xy 208.554108 -195.954481) (xy 208.589022 -195.903898) (xy 208.629779 -195.857891)
			(xy 208.675783 -195.817133) (xy 208.726365 -195.782217) (xy 208.780787 -195.753653) (xy 208.838255 -195.731856)
			(xy 208.897931 -195.717145) (xy 208.958945 -195.709734) (xy 208.989676 -195.709286) (xy 209.031078 -195.711064)
			(xy 209.042 -195.711826) (xy 209.062574 -195.70446) (xy 209.133186 -195.636642) (xy 209.141314 -195.616576)
			(xy 209.14106 -195.605654) (xy 209.140552 -195.58508) (xy 209.14106 -195.560696) (xy 209.141568 -195.549774)
			(xy 209.133694 -195.529454) (xy 209.062828 -195.461128) (xy 209.042254 -195.453762) (xy 209.031332 -195.454524)
			(xy 208.989676 -195.456302) (xy 208.958946 -195.455837) (xy 208.897935 -195.448426) (xy 208.838261 -195.433715)
			(xy 208.780796 -195.411919) (xy 208.726377 -195.383355) (xy 208.675798 -195.34844) (xy 208.629796 -195.307683)
			(xy 208.589042 -195.261679) (xy 208.55413 -195.211097) (xy 208.525569 -195.156676) (xy 208.503776 -195.09921)
			(xy 208.489069 -195.039536) (xy 208.481662 -194.978524) (xy 208.481168 -194.947794) (xy 208.481712 -194.913781)
			(xy 208.490786 -194.846363) (xy 208.508769 -194.780757) (xy 208.535342 -194.718135) (xy 208.570029 -194.659617)
			(xy 208.61221 -194.606247) (xy 208.661133 -194.558981) (xy 208.688178 -194.538346) (xy 208.698592 -194.530726)
			(xy 208.70926 -194.50812) (xy 208.704688 -194.398138) (xy 208.691988 -194.376548) (xy 208.681066 -194.369944)
			(xy 208.653659 -194.352544) (xy 208.603077 -194.31185) (xy 208.558087 -194.265048) (xy 208.519418 -194.212901)
			(xy 208.487702 -194.156256) (xy 208.463453 -194.096035) (xy 208.447066 -194.033218) (xy 208.438808 -193.968826)
			(xy 208.438242 -193.936366) (xy 208.43872 -193.904099) (xy 208.446846 -193.84008) (xy 208.463013 -193.777605)
			(xy 208.486962 -193.717681) (xy 208.518306 -193.661271) (xy 208.556541 -193.609285) (xy 208.57845 -193.585592)
			(xy 208.585562 -193.57848) (xy 208.592674 -193.559938) (xy 208.591404 -193.468752) (xy 208.583784 -193.450718)
			(xy 208.576672 -193.443606) (xy 208.553319 -193.419678) (xy 208.512452 -193.366758) (xy 208.47888 -193.308935)
			(xy 208.453182 -193.247208) (xy 208.435803 -193.182643) (xy 208.427043 -193.116357) (xy 208.426558 -193.082926)
			(xy 208.42703 -193.051423) (xy 208.434817 -192.9889) (xy 208.450273 -192.927819) (xy 208.473163 -192.869118)
			(xy 208.503134 -192.813697) (xy 208.521046 -192.787778) (xy 208.526634 -192.779904) (xy 208.531206 -192.762124)
			(xy 208.5213 -192.675764) (xy 208.512918 -192.659254) (xy 208.505806 -192.652904) (xy 208.484744 -192.633695)
			(xy 208.446583 -192.591344) (xy 208.413387 -192.544999) (xy 208.399126 -192.520316) (xy 208.39176 -192.507108)
			(xy 208.365852 -192.493138) (xy 208.243678 -192.503044) (xy 208.220056 -192.520824) (xy 208.214976 -192.535048)
			(xy 208.200443 -192.573618) (xy 208.165118 -192.648094) (xy 208.122959 -192.718926) (xy 208.074338 -192.785488)
			(xy 208.019684 -192.847193) (xy 207.959481 -192.903497) (xy 207.894259 -192.953901) (xy 207.824594 -192.997962)
			(xy 207.751102 -193.03529) (xy 207.67443 -193.065556) (xy 207.595256 -193.088492) (xy 207.51428 -193.103896)
			(xy 207.432214 -193.111632) (xy 207.391 -193.112136) (xy 207.349497 -193.111656) (xy 207.266861 -193.10382)
			(xy 207.185335 -193.088211) (xy 207.10565 -193.064966) (xy 207.028518 -193.034295) (xy 206.95463 -192.996471)
			(xy 206.884647 -192.951834) (xy 206.819196 -192.900783) (xy 206.758862 -192.843775) (xy 206.704186 -192.78132)
			(xy 206.655658 -192.713977) (xy 206.61371 -192.64235) (xy 206.57872 -192.567078) (xy 206.551 -192.488837)
			(xy 206.530798 -192.408327) (xy 206.518296 -192.326267) (xy 206.515462 -192.284858) (xy 206.514446 -192.264538)
			(xy 206.485236 -192.236852) (xy 205.487524 -192.236852) (xy 205.459076 -192.260982) (xy 205.456028 -192.27927)
			(xy 205.451049 -192.306107) (xy 205.434227 -192.35803) (xy 205.409935 -192.406907) (xy 205.378703 -192.451669)
			(xy 205.341215 -192.491339) (xy 205.298289 -192.525049) (xy 205.250863 -192.552064) (xy 205.199974 -192.571794)
			(xy 205.146731 -192.583806) (xy 205.0923 -192.58784) (xy 205.037869 -192.583806) (xy 204.984626 -192.571794)
			(xy 204.933737 -192.552064) (xy 204.886311 -192.525049) (xy 204.843385 -192.491339) (xy 204.805897 -192.451669)
			(xy 204.774665 -192.406907) (xy 204.750373 -192.35803) (xy 204.733551 -192.306107) (xy 204.728572 -192.27927)
			(xy 204.725524 -192.260982) (xy 204.697076 -192.236852) (xy 203.698856 -192.236852) (xy 203.670408 -192.260982)
			(xy 203.66736 -192.27927) (xy 203.662381 -192.306107) (xy 203.645559 -192.35803) (xy 203.621267 -192.406907)
			(xy 203.590035 -192.451669) (xy 203.552547 -192.491339) (xy 203.509621 -192.525049) (xy 203.462195 -192.552064)
			(xy 203.411306 -192.571794) (xy 203.358063 -192.583806) (xy 203.303632 -192.58784) (xy 203.249201 -192.583806)
			(xy 203.195958 -192.571794) (xy 203.145069 -192.552064) (xy 203.097643 -192.525049) (xy 203.054717 -192.491339)
			(xy 203.017229 -192.451669) (xy 202.985997 -192.406907) (xy 202.961705 -192.35803) (xy 202.944883 -192.306107)
			(xy 202.939904 -192.27927) (xy 202.936856 -192.260982) (xy 202.908408 -192.236852) (xy 201.910696 -192.236852)
			(xy 201.881486 -192.264538) (xy 201.88047 -192.284858) (xy 201.877228 -192.330714) (xy 201.862382 -192.421442)
			(xy 201.838135 -192.510121) (xy 201.804755 -192.59578) (xy 201.784204 -192.636902) (xy 201.779215 -192.648066)
			(xy 201.779202 -192.672482) (xy 201.784204 -192.683638) (xy 201.802884 -192.720951) (xy 201.833907 -192.79842)
			(xy 201.857435 -192.878484) (xy 201.873255 -192.96042) (xy 201.881224 -193.043488) (xy 201.88174 -193.085212)
			(xy 201.881227 -193.127598) (xy 201.873045 -193.211975) (xy 201.856757 -193.295168) (xy 201.832517 -193.376401)
			(xy 201.800549 -193.454915) (xy 201.761154 -193.529978) (xy 201.714698 -193.600888) (xy 201.661615 -193.666984)
			(xy 201.602402 -193.727648) (xy 201.53761 -193.782314) (xy 201.503026 -193.806826) (xy 201.495382 -193.812582)
			(xy 201.484702 -193.828442) (xy 201.480563 -193.847109) (xy 201.48169 -193.85661) (xy 201.484642 -193.876162)
			(xy 201.487819 -193.915578) (xy 201.48804 -193.93535) (xy 201.487547 -193.967182) (xy 201.483784 -193.99631)
			(xy 202.808078 -193.99631) (xy 202.808546 -193.963511) (xy 202.817185 -193.898484) (xy 202.834325 -193.835164)
			(xy 202.859667 -193.774659) (xy 202.892769 -193.718025) (xy 202.933052 -193.666252) (xy 202.979812 -193.620245)
			(xy 203.032232 -193.580808) (xy 203.060554 -193.564256) (xy 203.07173 -193.557906) (xy 203.085446 -193.536824)
			(xy 203.094082 -193.42735) (xy 203.084176 -193.404236) (xy 203.074016 -193.396108) (xy 203.052705 -193.378513)
			(xy 203.015075 -193.338042) (xy 202.983905 -193.292409) (xy 202.959893 -193.242636) (xy 202.943577 -193.189837)
			(xy 202.935321 -193.135195) (xy 202.934824 -193.107564) (xy 202.93534 -193.079964) (xy 202.943567 -193.025381)
			(xy 202.959837 -192.972634) (xy 202.983787 -192.922902) (xy 203.014882 -192.877294) (xy 203.052427 -192.83683)
			(xy 203.095584 -192.802413) (xy 203.143388 -192.774814) (xy 203.194772 -192.754647) (xy 203.248587 -192.742364)
			(xy 203.303632 -192.738239) (xy 203.358677 -192.742364) (xy 203.412492 -192.754647) (xy 203.463876 -192.774814)
			(xy 203.51168 -192.802413) (xy 203.554837 -192.83683) (xy 203.592382 -192.877294) (xy 203.623477 -192.922902)
			(xy 203.647427 -192.972634) (xy 203.663697 -193.025381) (xy 203.671924 -193.079964) (xy 203.67244 -193.107564)
			(xy 203.671974 -193.135199) (xy 203.663737 -193.189851) (xy 203.647427 -193.242659) (xy 203.623411 -193.292437)
			(xy 203.592228 -193.338069) (xy 203.554577 -193.37853) (xy 203.533248 -193.396108) (xy 203.523342 -193.403982)
			(xy 203.513436 -193.427096) (xy 203.522072 -193.53657) (xy 203.535788 -193.557906) (xy 203.546964 -193.564002)
			(xy 203.575327 -193.580524) (xy 203.627775 -193.619995) (xy 203.674561 -193.666037) (xy 203.714868 -193.717846)
			(xy 203.747991 -193.774517) (xy 203.773353 -193.835061) (xy 203.790511 -193.898421) (xy 203.799165 -193.963489)
			(xy 203.799694 -193.99631) (xy 203.799152 -194.029152) (xy 203.790485 -194.094261) (xy 203.773292 -194.157654)
			(xy 203.747873 -194.21822) (xy 203.714675 -194.274896) (xy 203.67428 -194.32669) (xy 203.627395 -194.372691)
			(xy 203.574844 -194.412095) (xy 203.546456 -194.428618) (xy 203.53528 -194.434968) (xy 203.521818 -194.45605)
			(xy 203.512928 -194.565778) (xy 203.523088 -194.588892) (xy 203.532994 -194.596766) (xy 203.554324 -194.614386)
			(xy 203.592029 -194.65487) (xy 203.623262 -194.700533) (xy 203.647323 -194.75035) (xy 203.663672 -194.803201)
			(xy 203.671942 -194.857903) (xy 203.67244 -194.885564) (xy 203.671924 -194.913164) (xy 203.663697 -194.967747)
			(xy 203.647427 -195.020494) (xy 203.623477 -195.070227) (xy 203.592382 -195.115834) (xy 203.554837 -195.156298)
			(xy 203.51168 -195.190715) (xy 203.463876 -195.218314) (xy 203.412492 -195.238481) (xy 203.358677 -195.250764)
			(xy 203.303632 -195.254889) (xy 203.248587 -195.250764) (xy 203.194772 -195.238481) (xy 203.143388 -195.218314)
			(xy 203.095584 -195.190715) (xy 203.052427 -195.156298) (xy 203.014882 -195.115834) (xy 202.983787 -195.070227)
			(xy 202.959837 -195.020494) (xy 202.943567 -194.967747) (xy 202.93534 -194.913164) (xy 202.934824 -194.885564)
			(xy 202.935329 -194.857902) (xy 202.943597 -194.803199) (xy 202.959941 -194.750344) (xy 202.983996 -194.700523)
			(xy 203.015221 -194.654853) (xy 203.052917 -194.614358) (xy 203.07427 -194.596766) (xy 203.08443 -194.588638)
			(xy 203.094336 -194.565778) (xy 203.0857 -194.45605) (xy 203.072238 -194.434714) (xy 203.061062 -194.428618)
			(xy 203.032691 -194.412089) (xy 202.980194 -194.37265) (xy 202.933361 -194.326627) (xy 202.893011 -194.274827)
			(xy 202.859849 -194.218154) (xy 202.834456 -194.157602) (xy 202.817277 -194.094228) (xy 202.80861 -194.029141)
			(xy 202.808078 -193.99631) (xy 201.483784 -193.99631) (xy 201.47939 -194.030323) (xy 201.463217 -194.091899)
			(xy 201.439293 -194.150899) (xy 201.408014 -194.20635) (xy 201.369892 -194.25734) (xy 201.348086 -194.280536)
			(xy 201.340974 -194.287902) (xy 201.333608 -194.30619) (xy 201.334624 -194.398138) (xy 201.342498 -194.416426)
			(xy 201.34961 -194.423538) (xy 201.373094 -194.447501) (xy 201.414204 -194.500527) (xy 201.447987 -194.558497)
			(xy 201.473856 -194.620405) (xy 201.491364 -194.685176) (xy 201.500205 -194.751686) (xy 201.50074 -194.785234)
			(xy 201.500238 -194.817195) (xy 201.492227 -194.880613) (xy 201.47633 -194.942527) (xy 201.452798 -195.00196)
			(xy 201.422004 -195.057975) (xy 201.384431 -195.10969) (xy 201.340674 -195.156287) (xy 201.291421 -195.197032)
			(xy 201.23745 -195.231283) (xy 201.179611 -195.2585) (xy 201.118818 -195.278253) (xy 201.056028 -195.290231)
			(xy 200.992232 -195.294245) (xy 200.928436 -195.290231) (xy 200.865646 -195.278253) (xy 200.804853 -195.2585)
			(xy 200.747014 -195.231283) (xy 200.693043 -195.197032) (xy 200.64379 -195.156287) (xy 200.600033 -195.10969)
			(xy 200.56246 -195.057975) (xy 200.531666 -195.00196) (xy 200.508134 -194.942527) (xy 200.492237 -194.880613)
			(xy 200.484226 -194.817195) (xy 200.483724 -194.785234) (xy 200.48426 -194.751685) (xy 200.493084 -194.685171)
			(xy 200.510583 -194.620395) (xy 200.536452 -194.558485) (xy 200.570243 -194.500518) (xy 200.611367 -194.4475)
			(xy 200.634854 -194.423538) (xy 200.641966 -194.416426) (xy 200.64984 -194.398138) (xy 200.650856 -194.30619)
			(xy 200.64349 -194.287902) (xy 200.636378 -194.280536) (xy 200.614557 -194.257353) (xy 200.576429 -194.206365)
			(xy 200.545147 -194.150913) (xy 200.521229 -194.09191) (xy 200.505067 -194.030328) (xy 200.496929 -193.967184)
			(xy 200.496424 -193.93535) (xy 200.496709 -193.9119) (xy 200.50116 -193.865213) (xy 200.505314 -193.842132)
			(xy 200.506734 -193.832647) (xy 200.503197 -193.813812) (xy 200.492974 -193.797601) (xy 200.485502 -193.791586)
			(xy 200.462702 -193.774547) (xy 200.419106 -193.737943) (xy 200.39838 -193.718434) (xy 200.391058 -193.712041)
			(xy 200.373031 -193.704816) (xy 200.35361 -193.704808) (xy 200.335577 -193.712018) (xy 200.321515 -193.725414)
			(xy 200.313438 -193.743076) (xy 200.312503 -193.762474) (xy 200.315322 -193.771774) (xy 200.324109 -193.798139)
			(xy 200.336434 -193.852332) (xy 200.342628 -193.907562) (xy 200.343008 -193.93535) (xy 200.342503 -193.967453)
			(xy 200.334216 -194.031121) (xy 200.317775 -194.093185) (xy 200.293456 -194.152606) (xy 200.261665 -194.208388)
			(xy 200.222935 -194.259597) (xy 200.200768 -194.282822) (xy 200.193656 -194.290188) (xy 200.18629 -194.308984)
			(xy 200.18756 -194.401694) (xy 200.195688 -194.420236) (xy 200.203054 -194.427348) (xy 200.226742 -194.450807)
			(xy 200.26825 -194.502976) (xy 200.302392 -194.560238) (xy 200.328551 -194.621559) (xy 200.346256 -194.685833)
			(xy 200.355186 -194.7519) (xy 200.355708 -194.785234) (xy 200.355183 -194.817954) (xy 200.346576 -194.882825)
			(xy 200.329518 -194.946002) (xy 200.304303 -195.006388) (xy 200.27137 -195.062936) (xy 200.231289 -195.114665)
			(xy 200.208388 -195.13804) (xy 200.201022 -195.145152) (xy 200.193148 -195.163948) (xy 200.193148 -195.256658)
			(xy 200.201022 -195.275454) (xy 200.208388 -195.282566) (xy 200.231289 -195.305941) (xy 200.271374 -195.357667)
			(xy 200.304308 -195.414214) (xy 200.329521 -195.474601) (xy 200.346573 -195.53778) (xy 200.355169 -195.602652)
			(xy 200.355708 -195.635372) (xy 200.355219 -195.666535) (xy 200.347407 -195.728369) (xy 200.331907 -195.788737)
			(xy 200.308964 -195.846685) (xy 200.278938 -195.901302) (xy 200.242304 -195.951724) (xy 200.199639 -195.997158)
			(xy 200.151617 -196.036886) (xy 200.098993 -196.070281) (xy 200.042599 -196.096818) (xy 199.983324 -196.116078)
			(xy 199.922103 -196.127757) (xy 199.8599 -196.13167) (xy 199.797697 -196.127757) (xy 199.736476 -196.116078)
			(xy 199.677201 -196.096818) (xy 199.620807 -196.070281) (xy 199.568183 -196.036886) (xy 199.520161 -195.997158)
			(xy 199.477496 -195.951724) (xy 199.440862 -195.901302) (xy 199.410836 -195.846685) (xy 199.387893 -195.788737)
			(xy 199.372393 -195.728369) (xy 199.364581 -195.666535) (xy 199.364092 -195.635372) (xy 199.364617 -195.602652)
			(xy 199.373223 -195.537781) (xy 199.39028 -195.474603) (xy 199.415495 -195.414216) (xy 199.448428 -195.357668)
			(xy 199.488508 -195.305938) (xy 199.511412 -195.282566) (xy 199.518778 -195.275454) (xy 199.526652 -195.256658)
			(xy 199.526652 -195.163948) (xy 199.518778 -195.145152) (xy 199.511412 -195.13804) (xy 199.488511 -195.114665)
			(xy 199.448425 -195.06294) (xy 199.41549 -195.006392) (xy 199.390277 -194.946005) (xy 199.373224 -194.882826)
			(xy 199.364627 -194.817954) (xy 199.364092 -194.785234) (xy 199.364598 -194.753132) (xy 199.372887 -194.689465)
			(xy 199.389329 -194.627401) (xy 199.41365 -194.567982) (xy 199.445442 -194.512201) (xy 199.484172 -194.460994)
			(xy 199.506332 -194.437762) (xy 199.513444 -194.430396) (xy 199.52081 -194.4116) (xy 199.51954 -194.31889)
			(xy 199.511412 -194.300348) (xy 199.504046 -194.293236) (xy 199.480359 -194.269777) (xy 199.438852 -194.217607)
			(xy 199.404712 -194.160345) (xy 199.378555 -194.099024) (xy 199.360853 -194.03475) (xy 199.351924 -193.968684)
			(xy 199.351392 -193.93535) (xy 199.351926 -193.90289) (xy 199.360406 -193.838526) (xy 199.377213 -193.775819)
			(xy 199.402062 -193.715843) (xy 199.434526 -193.659622) (xy 199.47405 -193.60812) (xy 199.519958 -193.562217)
			(xy 199.571464 -193.522698) (xy 199.627688 -193.49024) (xy 199.687667 -193.465397) (xy 199.750375 -193.448596)
			(xy 199.81474 -193.440123) (xy 199.8472 -193.439542) (xy 199.879201 -193.440028) (xy 199.942674 -193.448231)
			(xy 200.004567 -193.464526) (xy 200.034398 -193.476118) (xy 200.048368 -193.48196) (xy 200.076816 -193.476626)
			(xy 200.166478 -193.393822) (xy 200.174098 -193.365628) (xy 200.169526 -193.351404) (xy 200.157027 -193.310523)
			(xy 200.139088 -193.226935) (xy 200.133712 -193.184526) (xy 200.132442 -193.173858) (xy 200.122028 -193.15557)
			(xy 200.044558 -193.098674) (xy 200.024238 -193.094102) (xy 200.01357 -193.096134) (xy 199.972381 -193.103592)
			(xy 199.889055 -193.111604) (xy 199.8472 -193.112136) (xy 199.805697 -193.111656) (xy 199.723061 -193.10382)
			(xy 199.641535 -193.088211) (xy 199.56185 -193.064966) (xy 199.484718 -193.034295) (xy 199.41083 -192.996471)
			(xy 199.340847 -192.951834) (xy 199.275396 -192.900783) (xy 199.215062 -192.843775) (xy 199.160386 -192.78132)
			(xy 199.111858 -192.713977) (xy 199.06991 -192.64235) (xy 199.03492 -192.567078) (xy 199.0072 -192.488837)
			(xy 198.986998 -192.408327) (xy 198.974496 -192.326267) (xy 198.971662 -192.284858) (xy 198.970646 -192.264538)
			(xy 198.941436 -192.236852) (xy 197.981824 -192.236852) (xy 197.953376 -192.260982) (xy 197.950328 -192.27927)
			(xy 197.945349 -192.306107) (xy 197.928527 -192.35803) (xy 197.904235 -192.406907) (xy 197.873003 -192.451669)
			(xy 197.835515 -192.491339) (xy 197.792589 -192.525049) (xy 197.745163 -192.552064) (xy 197.694274 -192.571794)
			(xy 197.641031 -192.583806) (xy 197.5866 -192.58784) (xy 197.532169 -192.583806) (xy 197.478926 -192.571794)
			(xy 197.428037 -192.552064) (xy 197.380611 -192.525049) (xy 197.337685 -192.491339) (xy 197.300197 -192.451669)
			(xy 197.268965 -192.406907) (xy 197.244673 -192.35803) (xy 197.227851 -192.306107) (xy 197.222872 -192.27927)
			(xy 197.219824 -192.260982) (xy 197.191376 -192.236852) (xy 196.155056 -192.236852) (xy 196.126608 -192.260982)
			(xy 196.12356 -192.27927) (xy 196.118581 -192.306107) (xy 196.101759 -192.35803) (xy 196.077467 -192.406907)
			(xy 196.046235 -192.451669) (xy 196.008747 -192.491339) (xy 195.965821 -192.525049) (xy 195.918395 -192.552064)
			(xy 195.867506 -192.571794) (xy 195.814263 -192.583806) (xy 195.759832 -192.58784) (xy 195.705401 -192.583806)
			(xy 195.652158 -192.571794) (xy 195.601269 -192.552064) (xy 195.553843 -192.525049) (xy 195.510917 -192.491339)
			(xy 195.473429 -192.451669) (xy 195.442197 -192.406907) (xy 195.417905 -192.35803) (xy 195.401083 -192.306107)
			(xy 195.396104 -192.27927) (xy 195.393056 -192.260982) (xy 195.364608 -192.236852) (xy 194.366896 -192.236852)
			(xy 194.337686 -192.264538) (xy 194.33667 -192.284858) (xy 194.333428 -192.330714) (xy 194.318582 -192.421442)
			(xy 194.294335 -192.510121) (xy 194.260955 -192.59578) (xy 194.240404 -192.636902) (xy 194.235415 -192.648066)
			(xy 194.235402 -192.672482) (xy 194.240404 -192.683638) (xy 194.259084 -192.720951) (xy 194.290107 -192.79842)
			(xy 194.313635 -192.878484) (xy 194.329455 -192.96042) (xy 194.337424 -193.043488) (xy 194.33794 -193.085212)
			(xy 194.337427 -193.127598) (xy 194.329245 -193.211975) (xy 194.312957 -193.295168) (xy 194.288717 -193.376401)
			(xy 194.256749 -193.454915) (xy 194.217354 -193.529978) (xy 194.170898 -193.600888) (xy 194.117815 -193.666984)
			(xy 194.058602 -193.727648) (xy 193.99381 -193.782314) (xy 193.959226 -193.806826) (xy 193.951582 -193.812582)
			(xy 193.940902 -193.828442) (xy 193.936763 -193.847109) (xy 193.93789 -193.85661) (xy 193.940842 -193.876162)
			(xy 193.944019 -193.915578) (xy 193.94424 -193.93535) (xy 193.943747 -193.967182) (xy 193.939949 -193.996582)
			(xy 195.263458 -193.996582) (xy 195.267308 -193.934899) (xy 195.278794 -193.874173) (xy 195.297737 -193.815345)
			(xy 195.323845 -193.759327) (xy 195.356711 -193.706988) (xy 195.395828 -193.65914) (xy 195.440587 -193.616523)
			(xy 195.490296 -193.579799) (xy 195.517008 -193.564256) (xy 195.528184 -193.55816) (xy 195.541646 -193.536824)
			(xy 195.550282 -193.42735) (xy 195.540376 -193.404236) (xy 195.530216 -193.396362) (xy 195.508861 -193.378784)
			(xy 195.4712 -193.338277) (xy 195.440014 -193.292598) (xy 195.416004 -193.242771) (xy 195.399708 -193.189916)
			(xy 195.391494 -193.135219) (xy 195.391024 -193.107564) (xy 195.39154 -193.079964) (xy 195.399767 -193.025381)
			(xy 195.416037 -192.972634) (xy 195.439987 -192.922902) (xy 195.471082 -192.877294) (xy 195.508627 -192.83683)
			(xy 195.551784 -192.802413) (xy 195.599588 -192.774814) (xy 195.650972 -192.754647) (xy 195.704787 -192.742364)
			(xy 195.759832 -192.738239) (xy 195.814877 -192.742364) (xy 195.868692 -192.754647) (xy 195.920076 -192.774814)
			(xy 195.96788 -192.802413) (xy 196.011037 -192.83683) (xy 196.048582 -192.877294) (xy 196.079677 -192.922902)
			(xy 196.103627 -192.972634) (xy 196.119897 -193.025381) (xy 196.128124 -193.079964) (xy 196.12864 -193.107564)
			(xy 196.12811 -193.135214) (xy 196.119878 -193.189897) (xy 196.103578 -193.24274) (xy 196.079575 -193.292558)
			(xy 196.048407 -193.338237) (xy 196.010771 -193.378753) (xy 195.989448 -193.396362) (xy 195.979288 -193.404236)
			(xy 195.969382 -193.42735) (xy 195.978018 -193.536824) (xy 195.99148 -193.55816) (xy 196.002656 -193.564256)
			(xy 196.029331 -193.579854) (xy 196.079028 -193.616577) (xy 196.123776 -193.65919) (xy 196.162882 -193.707033)
			(xy 196.19574 -193.759365) (xy 196.221841 -193.815375) (xy 196.240779 -193.874194) (xy 196.252262 -193.93491)
			(xy 196.256111 -193.996582) (xy 196.252266 -194.058255) (xy 196.240788 -194.118972) (xy 196.221854 -194.177792)
			(xy 196.195757 -194.233804) (xy 196.162903 -194.286138) (xy 196.1238 -194.333984) (xy 196.079055 -194.376601)
			(xy 196.029361 -194.413327) (xy 196.002656 -194.428872) (xy 195.99148 -194.434968) (xy 195.978018 -194.456304)
			(xy 195.969382 -194.565778) (xy 195.979288 -194.588892) (xy 195.989448 -194.596766) (xy 196.010809 -194.614337)
			(xy 196.048472 -194.654844) (xy 196.079658 -194.700525) (xy 196.103667 -194.750353) (xy 196.119961 -194.80321)
			(xy 196.128172 -194.857908) (xy 196.12864 -194.885564) (xy 196.128124 -194.913164) (xy 196.119897 -194.967747)
			(xy 196.103627 -195.020494) (xy 196.079677 -195.070227) (xy 196.048582 -195.115834) (xy 196.011037 -195.156298)
			(xy 195.96788 -195.190715) (xy 195.920076 -195.218314) (xy 195.868692 -195.238481) (xy 195.814877 -195.250764)
			(xy 195.759832 -195.254889) (xy 195.704787 -195.250764) (xy 195.650972 -195.238481) (xy 195.599588 -195.218314)
			(xy 195.551784 -195.190715) (xy 195.508627 -195.156298) (xy 195.471082 -195.115834) (xy 195.439987 -195.070227)
			(xy 195.416037 -195.020494) (xy 195.399767 -194.967747) (xy 195.39154 -194.913164) (xy 195.391024 -194.885564)
			(xy 195.391479 -194.857911) (xy 195.399723 -194.803223) (xy 195.416036 -194.750378) (xy 195.440053 -194.70056)
			(xy 195.471236 -194.654883) (xy 195.508886 -194.614371) (xy 195.530216 -194.596766) (xy 195.540376 -194.588892)
			(xy 195.550282 -194.565778) (xy 195.541646 -194.456304) (xy 195.528184 -194.434968) (xy 195.517008 -194.428872)
			(xy 195.490266 -194.413382) (xy 195.44056 -194.376654) (xy 195.395804 -194.334035) (xy 195.356691 -194.286183)
			(xy 195.323828 -194.233842) (xy 195.297724 -194.177822) (xy 195.278785 -194.118993) (xy 195.267303 -194.058265)
			(xy 195.263458 -193.996582) (xy 193.939949 -193.996582) (xy 193.93559 -194.030323) (xy 193.919417 -194.091899)
			(xy 193.895493 -194.150899) (xy 193.864214 -194.20635) (xy 193.826092 -194.25734) (xy 193.804286 -194.280536)
			(xy 193.797174 -194.287902) (xy 193.789808 -194.30619) (xy 193.790824 -194.398138) (xy 193.798698 -194.416426)
			(xy 193.80581 -194.423538) (xy 193.829294 -194.447501) (xy 193.870404 -194.500527) (xy 193.904187 -194.558497)
			(xy 193.930056 -194.620405) (xy 193.947564 -194.685176) (xy 193.956405 -194.751686) (xy 193.95694 -194.785234)
			(xy 193.956438 -194.817195) (xy 193.948427 -194.880613) (xy 193.93253 -194.942527) (xy 193.908998 -195.00196)
			(xy 193.878204 -195.057975) (xy 193.840631 -195.10969) (xy 193.796874 -195.156287) (xy 193.747621 -195.197032)
			(xy 193.69365 -195.231283) (xy 193.635811 -195.2585) (xy 193.575018 -195.278253) (xy 193.512228 -195.290231)
			(xy 193.448432 -195.294245) (xy 193.384636 -195.290231) (xy 193.321846 -195.278253) (xy 193.261053 -195.2585)
			(xy 193.203214 -195.231283) (xy 193.149243 -195.197032) (xy 193.09999 -195.156287) (xy 193.056233 -195.10969)
			(xy 193.01866 -195.057975) (xy 192.987866 -195.00196) (xy 192.964334 -194.942527) (xy 192.948437 -194.880613)
			(xy 192.940426 -194.817195) (xy 192.939924 -194.785234) (xy 192.94046 -194.751685) (xy 192.949284 -194.685171)
			(xy 192.966783 -194.620395) (xy 192.992652 -194.558485) (xy 193.026443 -194.500518) (xy 193.067567 -194.4475)
			(xy 193.091054 -194.423538) (xy 193.098166 -194.416426) (xy 193.10604 -194.398138) (xy 193.107056 -194.30619)
			(xy 193.09969 -194.287902) (xy 193.092578 -194.280536) (xy 193.070757 -194.257353) (xy 193.032629 -194.206365)
			(xy 193.001347 -194.150913) (xy 192.977429 -194.09191) (xy 192.961267 -194.030328) (xy 192.953129 -193.967184)
			(xy 192.952624 -193.93535) (xy 192.952909 -193.9119) (xy 192.95736 -193.865213) (xy 192.961514 -193.842132)
			(xy 192.962934 -193.832647) (xy 192.959397 -193.813812) (xy 192.949174 -193.797601) (xy 192.941702 -193.791586)
			(xy 192.918757 -193.774441) (xy 192.874905 -193.737583) (xy 192.854072 -193.717926) (xy 192.846726 -193.711534)
			(xy 192.828654 -193.704327) (xy 192.809197 -193.704356) (xy 192.791146 -193.711616) (xy 192.777088 -193.725067)
			(xy 192.769038 -193.74278) (xy 192.76815 -193.762216) (xy 192.771014 -193.77152) (xy 192.779871 -193.797915)
			(xy 192.792293 -193.852188) (xy 192.798558 -193.907512) (xy 192.798954 -193.93535) (xy 192.798449 -193.967453)
			(xy 192.790163 -194.031122) (xy 192.773723 -194.093187) (xy 192.749406 -194.152609) (xy 192.717617 -194.208393)
			(xy 192.678889 -194.259604) (xy 192.656714 -194.282822) (xy 192.649602 -194.290188) (xy 192.642236 -194.308984)
			(xy 192.643506 -194.401694) (xy 192.651634 -194.420236) (xy 192.659 -194.427348) (xy 192.682686 -194.450808)
			(xy 192.724191 -194.502979) (xy 192.758329 -194.560241) (xy 192.784486 -194.621562) (xy 192.802189 -194.685835)
			(xy 192.811118 -194.751901) (xy 192.811654 -194.785234) (xy 192.811128 -194.817953) (xy 192.802521 -194.882823)
			(xy 192.785461 -194.945999) (xy 192.760244 -195.006384) (xy 192.727308 -195.06293) (xy 192.687225 -195.114655)
			(xy 192.664334 -195.13804) (xy 192.656968 -195.145152) (xy 192.649094 -195.163948) (xy 192.649094 -195.256658)
			(xy 192.656968 -195.275454) (xy 192.664334 -195.282566) (xy 192.687237 -195.30594) (xy 192.727326 -195.357664)
			(xy 192.760264 -195.414211) (xy 192.78548 -195.474599) (xy 192.802534 -195.537778) (xy 192.811131 -195.602652)
			(xy 192.811654 -195.635372) (xy 192.811165 -195.666535) (xy 192.803353 -195.728369) (xy 192.787853 -195.788737)
			(xy 192.76491 -195.846685) (xy 192.734884 -195.901302) (xy 192.69825 -195.951724) (xy 192.655585 -195.997158)
			(xy 192.607563 -196.036886) (xy 192.554939 -196.070281) (xy 192.498545 -196.096818) (xy 192.43927 -196.116078)
			(xy 192.378049 -196.127757) (xy 192.315846 -196.13167) (xy 192.253643 -196.127757) (xy 192.192422 -196.116078)
			(xy 192.133147 -196.096818) (xy 192.076753 -196.070281) (xy 192.024129 -196.036886) (xy 191.976107 -195.997158)
			(xy 191.933442 -195.951724) (xy 191.896808 -195.901302) (xy 191.866782 -195.846685) (xy 191.843839 -195.788737)
			(xy 191.828339 -195.728369) (xy 191.820527 -195.666535) (xy 191.820038 -195.635372) (xy 191.820564 -195.602653)
			(xy 191.82917 -195.537782) (xy 191.846229 -195.474606) (xy 191.871445 -195.41422) (xy 191.90438 -195.357673)
			(xy 191.944463 -195.305947) (xy 191.967358 -195.282566) (xy 191.974724 -195.275454) (xy 191.982598 -195.256658)
			(xy 191.982598 -195.163948) (xy 191.974724 -195.145152) (xy 191.967358 -195.13804) (xy 191.944455 -195.114666)
			(xy 191.904366 -195.062942) (xy 191.871428 -195.006395) (xy 191.846212 -194.946007) (xy 191.829157 -194.882828)
			(xy 191.82056 -194.817954) (xy 191.820038 -194.785234) (xy 191.820544 -194.753132) (xy 191.828833 -194.689466)
			(xy 191.845277 -194.627403) (xy 191.8696 -194.567985) (xy 191.901394 -194.512206) (xy 191.940127 -194.461002)
			(xy 191.962278 -194.437762) (xy 191.96939 -194.430396) (xy 191.976756 -194.4116) (xy 191.975486 -194.31889)
			(xy 191.967358 -194.300348) (xy 191.959992 -194.293236) (xy 191.936307 -194.269776) (xy 191.894805 -194.217604)
			(xy 191.860669 -194.160341) (xy 191.834514 -194.099021) (xy 191.816814 -194.034748) (xy 191.807887 -193.968683)
			(xy 191.807338 -193.93535) (xy 191.807872 -193.902891) (xy 191.816352 -193.838529) (xy 191.83316 -193.775825)
			(xy 191.858009 -193.715851) (xy 191.890474 -193.659633) (xy 191.929998 -193.608134) (xy 191.975907 -193.562235)
			(xy 192.027413 -193.52272) (xy 192.083637 -193.490267) (xy 192.143616 -193.465429) (xy 192.206323 -193.448633)
			(xy 192.270687 -193.440166) (xy 192.303146 -193.439542) (xy 192.335198 -193.440045) (xy 192.398767 -193.448313)
			(xy 192.460736 -193.464716) (xy 192.490598 -193.476372) (xy 192.504314 -193.48196) (xy 192.53327 -193.476626)
			(xy 192.622678 -193.394076) (xy 192.630298 -193.365628) (xy 192.625726 -193.351404) (xy 192.613227 -193.310523)
			(xy 192.595288 -193.226935) (xy 192.589912 -193.184526) (xy 192.588642 -193.173604) (xy 192.578228 -193.15557)
			(xy 192.500758 -193.098674) (xy 192.480184 -193.094102) (xy 192.46977 -193.096134) (xy 192.428521 -193.103617)
			(xy 192.345065 -193.11163) (xy 192.303146 -193.112136) (xy 192.261644 -193.111653) (xy 192.179012 -193.103813)
			(xy 192.097491 -193.0882) (xy 192.017809 -193.064952) (xy 191.940682 -193.034278) (xy 191.866798 -192.996453)
			(xy 191.79682 -192.951815) (xy 191.731373 -192.900763) (xy 191.671044 -192.843755) (xy 191.616372 -192.781301)
			(xy 191.567846 -192.71396) (xy 191.525902 -192.642334) (xy 191.490915 -192.567065) (xy 191.463197 -192.488827)
			(xy 191.442997 -192.408319) (xy 191.430495 -192.326263) (xy 191.427608 -192.284858) (xy 191.426592 -192.264538)
			(xy 191.397382 -192.236852) (xy 190.39967 -192.236852) (xy 190.371222 -192.260982) (xy 190.368174 -192.27927)
			(xy 190.363195 -192.306107) (xy 190.346373 -192.35803) (xy 190.322081 -192.406907) (xy 190.290849 -192.451669)
			(xy 190.253361 -192.491339) (xy 190.210435 -192.525049) (xy 190.163009 -192.552064) (xy 190.11212 -192.571794)
			(xy 190.058877 -192.583806) (xy 190.004446 -192.58784) (xy 189.950015 -192.583806) (xy 189.896772 -192.571794)
			(xy 189.845883 -192.552064) (xy 189.798457 -192.525049) (xy 189.755531 -192.491339) (xy 189.718043 -192.451669)
			(xy 189.686811 -192.406907) (xy 189.662519 -192.35803) (xy 189.645697 -192.306107) (xy 189.640718 -192.27927)
			(xy 189.63767 -192.260982) (xy 189.609222 -192.236852) (xy 188.611002 -192.236852) (xy 188.582554 -192.260982)
			(xy 188.579506 -192.27927) (xy 188.574527 -192.306107) (xy 188.557705 -192.35803) (xy 188.533413 -192.406907)
			(xy 188.502181 -192.451669) (xy 188.464693 -192.491339) (xy 188.421767 -192.525049) (xy 188.374341 -192.552064)
			(xy 188.323452 -192.571794) (xy 188.270209 -192.583806) (xy 188.215778 -192.58784) (xy 188.161347 -192.583806)
			(xy 188.108104 -192.571794) (xy 188.057215 -192.552064) (xy 188.009789 -192.525049) (xy 187.966863 -192.491339)
			(xy 187.929375 -192.451669) (xy 187.898143 -192.406907) (xy 187.873851 -192.35803) (xy 187.857029 -192.306107)
			(xy 187.85205 -192.27927) (xy 187.849002 -192.260982) (xy 187.820554 -192.236852) (xy 186.822842 -192.236852)
			(xy 186.793632 -192.264538) (xy 186.792616 -192.284858) (xy 186.789374 -192.330714) (xy 186.774527 -192.421441)
			(xy 186.750279 -192.51012) (xy 186.716896 -192.595778) (xy 186.69635 -192.636902) (xy 186.691364 -192.648067)
			(xy 186.691351 -192.672481) (xy 186.69635 -192.683638) (xy 186.715031 -192.720951) (xy 186.746056 -192.798419)
			(xy 186.769585 -192.878483) (xy 186.785406 -192.960419) (xy 186.793376 -193.043487) (xy 186.793886 -193.085212)
			(xy 186.793373 -193.127599) (xy 186.785191 -193.211976) (xy 186.768904 -193.29517) (xy 186.744664 -193.376404)
			(xy 186.712698 -193.454919) (xy 186.673304 -193.529983) (xy 186.62685 -193.600895) (xy 186.573769 -193.666993)
			(xy 186.514557 -193.72766) (xy 186.449766 -193.782329) (xy 186.415172 -193.806826) (xy 186.407522 -193.812579)
			(xy 186.396832 -193.828438) (xy 186.392689 -193.84711) (xy 186.393836 -193.85661) (xy 186.396788 -193.876162)
			(xy 186.399964 -193.915578) (xy 186.400186 -193.93535) (xy 186.399643 -193.968393) (xy 186.395868 -193.996582)
			(xy 187.719431 -193.996582) (xy 187.723281 -193.934902) (xy 187.734765 -193.874177) (xy 187.753706 -193.815351)
			(xy 187.779811 -193.759334) (xy 187.812674 -193.706995) (xy 187.851786 -193.659146) (xy 187.89654 -193.616528)
			(xy 187.946244 -193.579801) (xy 187.972954 -193.564256) (xy 187.98413 -193.55816) (xy 187.997592 -193.536824)
			(xy 188.006228 -193.42735) (xy 187.996322 -193.404236) (xy 187.986162 -193.396362) (xy 187.964816 -193.378773)
			(xy 187.927152 -193.33827) (xy 187.895964 -193.292593) (xy 187.871952 -193.242768) (xy 187.855655 -193.189914)
			(xy 187.84744 -193.135219) (xy 187.84697 -193.107564) (xy 187.847486 -193.079964) (xy 187.855713 -193.025381)
			(xy 187.871983 -192.972634) (xy 187.895933 -192.922902) (xy 187.927028 -192.877294) (xy 187.964573 -192.83683)
			(xy 188.00773 -192.802413) (xy 188.055534 -192.774814) (xy 188.106918 -192.754647) (xy 188.160733 -192.742364)
			(xy 188.215778 -192.738239) (xy 188.270823 -192.742364) (xy 188.324638 -192.754647) (xy 188.376022 -192.774814)
			(xy 188.423826 -192.802413) (xy 188.466983 -192.83683) (xy 188.504528 -192.877294) (xy 188.535623 -192.922902)
			(xy 188.559573 -192.972634) (xy 188.575843 -193.025381) (xy 188.58407 -193.079964) (xy 188.584586 -193.107564)
			(xy 188.584077 -193.135215) (xy 188.575843 -193.1899) (xy 188.559541 -193.242744) (xy 188.535534 -193.292563)
			(xy 188.504361 -193.338241) (xy 188.46672 -193.378755) (xy 188.445394 -193.396362) (xy 188.435234 -193.404236)
			(xy 188.425328 -193.42735) (xy 188.433964 -193.536824) (xy 188.447426 -193.55816) (xy 188.458602 -193.564256)
			(xy 188.48528 -193.579852) (xy 188.534981 -193.616572) (xy 188.579734 -193.659183) (xy 188.618845 -193.707026)
			(xy 188.651707 -193.759359) (xy 188.67781 -193.815369) (xy 188.696751 -193.87419) (xy 188.708235 -193.934908)
			(xy 188.712084 -193.996582) (xy 188.708239 -194.058257) (xy 188.69676 -194.118976) (xy 188.677823 -194.177798)
			(xy 188.651723 -194.23381) (xy 188.618865 -194.286145) (xy 188.579758 -194.333991) (xy 188.535008 -194.376605)
			(xy 188.485309 -194.413329) (xy 188.458602 -194.428872) (xy 188.447426 -194.434968) (xy 188.433964 -194.456304)
			(xy 188.425328 -194.565778) (xy 188.435234 -194.588892) (xy 188.445394 -194.596766) (xy 188.466765 -194.614325)
			(xy 188.504425 -194.654837) (xy 188.535608 -194.70052) (xy 188.559615 -194.75035) (xy 188.575907 -194.803209)
			(xy 188.584118 -194.857908) (xy 188.584586 -194.885564) (xy 188.58407 -194.913164) (xy 188.575843 -194.967747)
			(xy 188.559573 -195.020494) (xy 188.535623 -195.070227) (xy 188.504528 -195.115834) (xy 188.466983 -195.156298)
			(xy 188.423826 -195.190715) (xy 188.376022 -195.218314) (xy 188.324638 -195.238481) (xy 188.270823 -195.250764)
			(xy 188.215778 -195.254889) (xy 188.160733 -195.250764) (xy 188.106918 -195.238481) (xy 188.055534 -195.218314)
			(xy 188.00773 -195.190715) (xy 187.964573 -195.156298) (xy 187.927028 -195.115834) (xy 187.895933 -195.070227)
			(xy 187.871983 -195.020494) (xy 187.855713 -194.967747) (xy 187.847486 -194.913164) (xy 187.84697 -194.885564)
			(xy 187.847445 -194.857912) (xy 187.855688 -194.803226) (xy 187.871998 -194.750382) (xy 187.896012 -194.700564)
			(xy 187.92719 -194.654887) (xy 187.964835 -194.614373) (xy 187.986162 -194.596766) (xy 187.996322 -194.588892)
			(xy 188.006228 -194.565778) (xy 187.997592 -194.456304) (xy 187.98413 -194.434968) (xy 187.972954 -194.428872)
			(xy 187.946215 -194.41338) (xy 187.896513 -194.37665) (xy 187.851762 -194.334028) (xy 187.812653 -194.286176)
			(xy 187.779794 -194.233835) (xy 187.753693 -194.177816) (xy 187.734757 -194.118988) (xy 187.723277 -194.058263)
			(xy 187.719431 -193.996582) (xy 186.395868 -193.996582) (xy 186.390872 -194.033896) (xy 186.373478 -194.097652)
			(xy 186.347769 -194.158533) (xy 186.314202 -194.215461) (xy 186.273371 -194.267425) (xy 186.225999 -194.313505)
			(xy 186.19978 -194.333622) (xy 186.191398 -194.339718) (xy 186.180984 -194.357498) (xy 186.168792 -194.450208)
			(xy 186.174126 -194.47002) (xy 186.180476 -194.478148) (xy 186.200607 -194.504475) (xy 186.234399 -194.561488)
			(xy 186.260288 -194.622498) (xy 186.277811 -194.686414) (xy 186.286656 -194.752097) (xy 186.287156 -194.785234)
			(xy 186.286623 -194.817696) (xy 186.278145 -194.882064) (xy 186.261339 -194.944775) (xy 186.236492 -195.004756)
			(xy 186.20403 -195.060981) (xy 186.164507 -195.112489) (xy 186.118599 -195.158397) (xy 186.067093 -195.197922)
			(xy 186.010868 -195.230386) (xy 185.950888 -195.255235) (xy 185.888178 -195.272043) (xy 185.82381 -195.280522)
			(xy 185.791348 -195.281042) (xy 185.760393 -195.280569) (xy 185.698965 -195.272866) (xy 185.638973 -195.257574)
			(xy 185.581353 -195.234932) (xy 185.527001 -195.20529) (xy 185.476762 -195.169112) (xy 185.431419 -195.12696)
			(xy 185.391677 -195.07949) (xy 185.374534 -195.053712) (xy 185.367422 -195.042536) (xy 185.344562 -195.030344)
			(xy 185.232548 -195.031106) (xy 185.209942 -195.043552) (xy 185.20283 -195.054728) (xy 185.186825 -195.079606)
			(xy 185.149897 -195.125824) (xy 185.12917 -195.14693) (xy 185.121804 -195.154296) (xy 185.114184 -195.17233)
			(xy 185.113168 -195.264278) (xy 185.120534 -195.28282) (xy 185.127646 -195.290186) (xy 185.14947 -195.313368)
			(xy 185.187605 -195.364354) (xy 185.218893 -195.419806) (xy 185.24282 -195.478809) (xy 185.25899 -195.540391)
			(xy 185.267138 -195.603537) (xy 185.2676 -195.635372) (xy 185.267111 -195.666535) (xy 185.259299 -195.728369)
			(xy 185.243799 -195.788737) (xy 185.220856 -195.846685) (xy 185.19083 -195.901302) (xy 185.154196 -195.951724)
			(xy 185.111531 -195.997158) (xy 185.063509 -196.036886) (xy 185.010885 -196.070281) (xy 184.954491 -196.096818)
			(xy 184.895216 -196.116078) (xy 184.833995 -196.127757) (xy 184.771792 -196.13167) (xy 184.709589 -196.127757)
			(xy 184.648368 -196.116078) (xy 184.589093 -196.096818) (xy 184.532699 -196.070281) (xy 184.480075 -196.036886)
			(xy 184.432053 -195.997158) (xy 184.389388 -195.951724) (xy 184.352754 -195.901302) (xy 184.322728 -195.846685)
			(xy 184.299785 -195.788737) (xy 184.284285 -195.728369) (xy 184.276473 -195.666535) (xy 184.275984 -195.635372)
			(xy 184.276476 -195.603539) (xy 184.284631 -195.540398) (xy 184.300802 -195.47882) (xy 184.324724 -195.419819)
			(xy 184.356004 -195.364367) (xy 184.394125 -195.313376) (xy 184.415938 -195.290186) (xy 184.42305 -195.28282)
			(xy 184.430416 -195.264278) (xy 184.4294 -195.17233) (xy 184.42178 -195.154296) (xy 184.414414 -195.14693)
			(xy 184.39093 -195.122967) (xy 184.349822 -195.069941) (xy 184.316041 -195.01197) (xy 184.290174 -194.950062)
			(xy 184.27267 -194.885291) (xy 184.263833 -194.818781) (xy 184.263284 -194.785234) (xy 184.263802 -194.752314)
			(xy 184.272299 -194.687026) (xy 184.289153 -194.623381) (xy 184.314085 -194.562445) (xy 184.346675 -194.505238)
			(xy 184.386379 -194.452718) (xy 184.40908 -194.428872) (xy 184.416192 -194.421506) (xy 184.423558 -194.403218)
			(xy 184.423304 -194.31127) (xy 184.415684 -194.292982) (xy 184.408318 -194.28587) (xy 184.385765 -194.262534)
			(xy 184.34629 -194.211023) (xy 184.31387 -194.154803) (xy 184.289059 -194.094835) (xy 184.272282 -194.032143)
			(xy 184.263825 -193.967799) (xy 184.263284 -193.93535) (xy 184.263818 -193.90289) (xy 184.272298 -193.838525)
			(xy 184.289105 -193.775818) (xy 184.313954 -193.715841) (xy 184.346417 -193.65962) (xy 184.385941 -193.608117)
			(xy 184.431849 -193.562214) (xy 184.483355 -193.522694) (xy 184.539579 -193.490235) (xy 184.599558 -193.465392)
			(xy 184.662267 -193.448589) (xy 184.726632 -193.440115) (xy 184.759092 -193.439542) (xy 184.791145 -193.440042)
			(xy 184.854715 -193.448302) (xy 184.916688 -193.4647) (xy 184.946544 -193.476372) (xy 184.96026 -193.48196)
			(xy 184.989216 -193.476626) (xy 185.078624 -193.394076) (xy 185.086244 -193.365628) (xy 185.081672 -193.351404)
			(xy 185.069173 -193.310523) (xy 185.051232 -193.226936) (xy 185.045858 -193.184526) (xy 185.044588 -193.173604)
			(xy 185.034174 -193.15557) (xy 184.956704 -193.098674) (xy 184.93613 -193.094102) (xy 184.925716 -193.096134)
			(xy 184.884467 -193.10362) (xy 184.801012 -193.111637) (xy 184.759092 -193.112136) (xy 184.717589 -193.111655)
			(xy 184.634954 -193.103819) (xy 184.553429 -193.088209) (xy 184.473744 -193.064964) (xy 184.396613 -193.034292)
			(xy 184.322725 -192.996468) (xy 184.252743 -192.951831) (xy 184.187292 -192.90078) (xy 184.12696 -192.843772)
			(xy 184.072284 -192.781317) (xy 184.023756 -192.713975) (xy 183.981809 -192.642347) (xy 183.946819 -192.567077)
			(xy 183.9191 -192.488836) (xy 183.898898 -192.408326) (xy 183.886396 -192.326267) (xy 183.883554 -192.284858)
			(xy 183.882538 -192.264538) (xy 183.853328 -192.236852) (xy 182.855616 -192.236852) (xy 182.827168 -192.260982)
			(xy 182.82412 -192.27927) (xy 182.819141 -192.306107) (xy 182.802319 -192.35803) (xy 182.778027 -192.406907)
			(xy 182.746795 -192.451669) (xy 182.709307 -192.491339) (xy 182.666381 -192.525049) (xy 182.618955 -192.552064)
			(xy 182.568066 -192.571794) (xy 182.514823 -192.583806) (xy 182.460392 -192.58784) (xy 182.405961 -192.583806)
			(xy 182.352718 -192.571794) (xy 182.301829 -192.552064) (xy 182.254403 -192.525049) (xy 182.211477 -192.491339)
			(xy 182.173989 -192.451669) (xy 182.142757 -192.406907) (xy 182.118465 -192.35803) (xy 182.101643 -192.306107)
			(xy 182.096664 -192.27927) (xy 182.093616 -192.260982) (xy 182.065168 -192.236852) (xy 181.066948 -192.236852)
			(xy 181.0385 -192.260982) (xy 181.035452 -192.27927) (xy 181.030473 -192.306107) (xy 181.013651 -192.35803)
			(xy 180.989359 -192.406907) (xy 180.958127 -192.451669) (xy 180.920639 -192.491339) (xy 180.877713 -192.525049)
			(xy 180.830287 -192.552064) (xy 180.779398 -192.571794) (xy 180.726155 -192.583806) (xy 180.671724 -192.58784)
			(xy 180.617293 -192.583806) (xy 180.56405 -192.571794) (xy 180.513161 -192.552064) (xy 180.465735 -192.525049)
			(xy 180.422809 -192.491339) (xy 180.385321 -192.451669) (xy 180.354089 -192.406907) (xy 180.329797 -192.35803)
			(xy 180.312975 -192.306107) (xy 180.307996 -192.27927) (xy 180.304948 -192.260982) (xy 180.2765 -192.236852)
			(xy 179.278788 -192.236852) (xy 179.249578 -192.264538) (xy 179.248562 -192.284858) (xy 179.24532 -192.330714)
			(xy 179.230474 -192.421442) (xy 179.206227 -192.510121) (xy 179.172846 -192.59578) (xy 179.152296 -192.636902)
			(xy 179.147307 -192.648066) (xy 179.147295 -192.672481) (xy 179.152296 -192.683638) (xy 179.170976 -192.720951)
			(xy 179.201999 -192.798419) (xy 179.225527 -192.878483) (xy 179.241347 -192.96042) (xy 179.249317 -193.043488)
			(xy 179.249832 -193.085212) (xy 179.24932 -193.127599) (xy 179.241138 -193.211977) (xy 179.224851 -193.295172)
			(xy 179.200612 -193.376407) (xy 179.168647 -193.454923) (xy 179.129254 -193.529989) (xy 179.082801 -193.600902)
			(xy 179.029722 -193.667002) (xy 178.970512 -193.727671) (xy 178.905723 -193.782343) (xy 178.871118 -193.806826)
			(xy 178.863475 -193.812582) (xy 178.852796 -193.828442) (xy 178.848658 -193.847109) (xy 178.849782 -193.85661)
			(xy 178.852734 -193.876162) (xy 178.855911 -193.915578) (xy 178.856132 -193.93535) (xy 178.855639 -193.967182)
			(xy 178.851843 -193.996564) (xy 180.17617 -193.996564) (xy 180.176638 -193.9665) (xy 180.18392 -193.906814)
			(xy 180.198361 -193.848446) (xy 180.21975 -193.79225) (xy 180.247772 -193.73905) (xy 180.282018 -193.689627)
			(xy 180.321985 -193.644704) (xy 180.367087 -193.60494) (xy 180.416664 -193.570917) (xy 180.443124 -193.556636)
			(xy 180.455062 -193.55054) (xy 180.46954 -193.528696) (xy 180.477668 -193.415666) (xy 180.466746 -193.392044)
			(xy 180.455824 -193.38417) (xy 180.432558 -193.366731) (xy 180.391336 -193.325726) (xy 180.357063 -193.278757)
			(xy 180.330589 -193.22699) (xy 180.312571 -193.171709) (xy 180.303456 -193.114284) (xy 180.302916 -193.085212)
			(xy 180.303432 -193.057612) (xy 180.311659 -193.003029) (xy 180.327929 -192.950282) (xy 180.351879 -192.90055)
			(xy 180.382974 -192.854942) (xy 180.420519 -192.814478) (xy 180.463676 -192.780061) (xy 180.51148 -192.752462)
			(xy 180.562864 -192.732295) (xy 180.616679 -192.720012) (xy 180.671724 -192.715887) (xy 180.726769 -192.720012)
			(xy 180.780584 -192.732295) (xy 180.831968 -192.752462) (xy 180.879772 -192.780061) (xy 180.922929 -192.814478)
			(xy 180.960474 -192.854942) (xy 180.991569 -192.90055) (xy 181.015519 -192.950282) (xy 181.031789 -193.003029)
			(xy 181.040016 -193.057612) (xy 181.040532 -193.085212) (xy 181.040012 -193.11427) (xy 181.030901 -193.171668)
			(xy 181.012907 -193.226929) (xy 180.986475 -193.278686) (xy 180.952257 -193.325661) (xy 180.911099 -193.366693)
			(xy 180.887878 -193.38417) (xy 180.876956 -193.39179) (xy 180.866034 -193.415666) (xy 180.874162 -193.528442)
			(xy 180.88864 -193.550286) (xy 180.900578 -193.556636) (xy 180.927076 -193.570873) (xy 180.976712 -193.604858)
			(xy 181.021869 -193.644601) (xy 181.061886 -193.689516) (xy 181.096172 -193.738944) (xy 181.124224 -193.792159)
			(xy 181.145631 -193.848376) (xy 181.160076 -193.906772) (xy 181.167348 -193.966486) (xy 181.167786 -193.996564)
			(xy 181.167315 -194.029397) (xy 181.158651 -194.09449) (xy 181.141468 -194.157869) (xy 181.116068 -194.218424)
			(xy 181.082897 -194.275096) (xy 181.042533 -194.326893) (xy 180.995684 -194.372907) (xy 180.943171 -194.412334)
			(xy 180.914802 -194.428872) (xy 180.903626 -194.435222) (xy 180.890164 -194.456304) (xy 180.881274 -194.565778)
			(xy 180.89118 -194.588892) (xy 180.90134 -194.59702) (xy 180.922655 -194.61461) (xy 180.960287 -194.655081)
			(xy 180.991458 -194.700714) (xy 181.015469 -194.750489) (xy 181.031784 -194.803289) (xy 181.040037 -194.857932)
			(xy 181.040532 -194.885564) (xy 181.040016 -194.913164) (xy 181.031789 -194.967747) (xy 181.015519 -195.020494)
			(xy 180.991569 -195.070227) (xy 180.960474 -195.115834) (xy 180.922929 -195.156298) (xy 180.879772 -195.190715)
			(xy 180.831968 -195.218314) (xy 180.780584 -195.238481) (xy 180.726769 -195.250764) (xy 180.671724 -195.254889)
			(xy 180.616679 -195.250764) (xy 180.562864 -195.238481) (xy 180.51148 -195.218314) (xy 180.463676 -195.190715)
			(xy 180.420519 -195.156298) (xy 180.382974 -195.115834) (xy 180.351879 -195.070227) (xy 180.327929 -195.020494)
			(xy 180.311659 -194.967747) (xy 180.303432 -194.913164) (xy 180.302916 -194.885564) (xy 180.303424 -194.857902)
			(xy 180.311692 -194.803199) (xy 180.328036 -194.750345) (xy 180.35209 -194.700524) (xy 180.383315 -194.654853)
			(xy 180.42101 -194.614359) (xy 180.442362 -194.596766) (xy 180.452268 -194.588892) (xy 180.462428 -194.565778)
			(xy 180.453538 -194.45605) (xy 180.440076 -194.434968) (xy 180.4289 -194.428618) (xy 180.400579 -194.412052)
			(xy 180.348133 -194.37263) (xy 180.301346 -194.326634) (xy 180.261035 -194.274868) (xy 180.227905 -194.218236)
			(xy 180.202535 -194.15773) (xy 180.185368 -194.094405) (xy 180.176705 -194.029369) (xy 180.17617 -193.996564)
			(xy 178.851843 -193.996564) (xy 178.847482 -194.030323) (xy 178.831308 -194.091899) (xy 178.807385 -194.150898)
			(xy 178.776105 -194.206349) (xy 178.737983 -194.257339) (xy 178.716178 -194.280536) (xy 178.709066 -194.287902)
			(xy 178.7017 -194.30619) (xy 178.702716 -194.398138) (xy 178.71059 -194.416426) (xy 178.717702 -194.423538)
			(xy 178.741187 -194.447501) (xy 178.782297 -194.500527) (xy 178.81608 -194.558497) (xy 178.84195 -194.620405)
			(xy 178.859458 -194.685176) (xy 178.868299 -194.751686) (xy 178.868832 -194.785234) (xy 178.86833 -194.817195)
			(xy 178.860319 -194.880613) (xy 178.844422 -194.942527) (xy 178.82089 -195.00196) (xy 178.790096 -195.057975)
			(xy 178.752523 -195.10969) (xy 178.708766 -195.156287) (xy 178.659513 -195.197032) (xy 178.605542 -195.231283)
			(xy 178.547703 -195.2585) (xy 178.48691 -195.278253) (xy 178.42412 -195.290231) (xy 178.360324 -195.294245)
			(xy 178.296528 -195.290231) (xy 178.233738 -195.278253) (xy 178.172945 -195.2585) (xy 178.115106 -195.231283)
			(xy 178.061135 -195.197032) (xy 178.011882 -195.156287) (xy 177.968125 -195.10969) (xy 177.930552 -195.057975)
			(xy 177.899758 -195.00196) (xy 177.876226 -194.942527) (xy 177.860329 -194.880613) (xy 177.852318 -194.817195)
			(xy 177.851816 -194.785234) (xy 177.852352 -194.751685) (xy 177.861176 -194.68517) (xy 177.878674 -194.620395)
			(xy 177.904544 -194.558485) (xy 177.938334 -194.500517) (xy 177.979457 -194.447498) (xy 178.002946 -194.423538)
			(xy 178.010058 -194.416426) (xy 178.017932 -194.398138) (xy 178.018948 -194.30619) (xy 178.011582 -194.287902)
			(xy 178.00447 -194.280536) (xy 177.982649 -194.257353) (xy 177.944522 -194.206365) (xy 177.913241 -194.150913)
			(xy 177.889322 -194.09191) (xy 177.873161 -194.030328) (xy 177.865023 -193.967184) (xy 177.864516 -193.93535)
			(xy 177.864801 -193.9119) (xy 177.869252 -193.865212) (xy 177.873406 -193.842132) (xy 177.874826 -193.832647)
			(xy 177.871289 -193.813812) (xy 177.861065 -193.797603) (xy 177.853594 -193.791586) (xy 177.830649 -193.77444)
			(xy 177.786798 -193.737582) (xy 177.765964 -193.717926) (xy 177.758619 -193.711535) (xy 177.740549 -193.704332)
			(xy 177.721095 -193.704362) (xy 177.703047 -193.711621) (xy 177.688992 -193.72507) (xy 177.680943 -193.74278)
			(xy 177.680055 -193.762213) (xy 177.682906 -193.77152) (xy 177.691763 -193.797915) (xy 177.704186 -193.852188)
			(xy 177.71045 -193.907512) (xy 177.710846 -193.93535) (xy 177.710341 -193.967453) (xy 177.702055 -194.031122)
			(xy 177.685615 -194.093187) (xy 177.661297 -194.152609) (xy 177.629508 -194.208392) (xy 177.59078 -194.259603)
			(xy 177.568606 -194.282822) (xy 177.561494 -194.290188) (xy 177.554128 -194.308984) (xy 177.555398 -194.401694)
			(xy 177.563526 -194.420236) (xy 177.570892 -194.427348) (xy 177.594578 -194.450808) (xy 177.636084 -194.502978)
			(xy 177.670223 -194.560241) (xy 177.69638 -194.621561) (xy 177.714083 -194.685835) (xy 177.723013 -194.751901)
			(xy 177.723546 -194.785234) (xy 177.72302 -194.817953) (xy 177.714413 -194.882823) (xy 177.697353 -194.945999)
			(xy 177.672136 -195.006383) (xy 177.639199 -195.062929) (xy 177.599115 -195.114654) (xy 177.576226 -195.13804)
			(xy 177.56886 -195.145152) (xy 177.560986 -195.163948) (xy 177.560986 -195.256658) (xy 177.56886 -195.275454)
			(xy 177.576226 -195.282566) (xy 177.599129 -195.30594) (xy 177.639219 -195.357664) (xy 177.672158 -195.41421)
			(xy 177.697373 -195.474598) (xy 177.714428 -195.537778) (xy 177.723025 -195.602651) (xy 177.723546 -195.635372)
			(xy 177.723057 -195.666535) (xy 177.715245 -195.728369) (xy 177.699745 -195.788737) (xy 177.676802 -195.846685)
			(xy 177.646776 -195.901302) (xy 177.610142 -195.951724) (xy 177.567477 -195.997158) (xy 177.519455 -196.036886)
			(xy 177.466831 -196.070281) (xy 177.410437 -196.096818) (xy 177.351162 -196.116078) (xy 177.289941 -196.127757)
			(xy 177.227738 -196.13167) (xy 177.165535 -196.127757) (xy 177.104314 -196.116078) (xy 177.045039 -196.096818)
			(xy 176.988645 -196.070281) (xy 176.936021 -196.036886) (xy 176.887999 -195.997158) (xy 176.845334 -195.951724)
			(xy 176.8087 -195.901302) (xy 176.778674 -195.846685) (xy 176.755731 -195.788737) (xy 176.740231 -195.728369)
			(xy 176.732419 -195.666535) (xy 176.73193 -195.635372) (xy 176.732456 -195.602652) (xy 176.741062 -195.537782)
			(xy 176.75812 -195.474605) (xy 176.783336 -195.414219) (xy 176.816271 -195.357672) (xy 176.856354 -195.305945)
			(xy 176.87925 -195.282566) (xy 176.886616 -195.275454) (xy 176.89449 -195.256658) (xy 176.89449 -195.163948)
			(xy 176.886616 -195.145152) (xy 176.87925 -195.13804) (xy 176.856347 -195.114666) (xy 176.816259 -195.062942)
			(xy 176.783321 -195.006394) (xy 176.758106 -194.946007) (xy 176.741051 -194.882828) (xy 176.732454 -194.817954)
			(xy 176.73193 -194.785234) (xy 176.732436 -194.753132) (xy 176.740725 -194.689465) (xy 176.757169 -194.627403)
			(xy 176.781491 -194.567984) (xy 176.813285 -194.512206) (xy 176.852017 -194.461001) (xy 176.87417 -194.437762)
			(xy 176.881282 -194.430396) (xy 176.888648 -194.4116) (xy 176.887378 -194.31889) (xy 176.87925 -194.300348)
			(xy 176.871884 -194.293236) (xy 176.848199 -194.269775) (xy 176.806698 -194.217604) (xy 176.772562 -194.160341)
			(xy 176.746408 -194.09902) (xy 176.728708 -194.034748) (xy 176.719781 -193.968683) (xy 176.71923 -193.93535)
			(xy 176.719764 -193.902891) (xy 176.728244 -193.838529) (xy 176.745052 -193.775824) (xy 176.769901 -193.715849)
			(xy 176.802365 -193.659632) (xy 176.84189 -193.608132) (xy 176.887798 -193.562232) (xy 176.939305 -193.522716)
			(xy 176.995528 -193.490262) (xy 177.055507 -193.465424) (xy 177.118215 -193.448627) (xy 177.182579 -193.440158)
			(xy 177.215038 -193.439542) (xy 177.24709 -193.440045) (xy 177.310659 -193.448311) (xy 177.372629 -193.464714)
			(xy 177.40249 -193.476372) (xy 177.416206 -193.48196) (xy 177.445162 -193.476626) (xy 177.53457 -193.394076)
			(xy 177.54219 -193.365628) (xy 177.537618 -193.351404) (xy 177.525119 -193.310523) (xy 177.50718 -193.226935)
			(xy 177.501804 -193.184526) (xy 177.500534 -193.173604) (xy 177.49012 -193.15557) (xy 177.41265 -193.098674)
			(xy 177.392076 -193.094102) (xy 177.381662 -193.096134) (xy 177.340413 -193.103617) (xy 177.256957 -193.111629)
			(xy 177.215038 -193.112136) (xy 177.173537 -193.111653) (xy 177.090905 -193.103812) (xy 177.009384 -193.088198)
			(xy 176.929703 -193.06495) (xy 176.852576 -193.034276) (xy 176.778693 -192.99645) (xy 176.708716 -192.951812)
			(xy 176.64327 -192.90076) (xy 176.582941 -192.843752) (xy 176.528269 -192.781298) (xy 176.479745 -192.713957)
			(xy 176.437801 -192.642332) (xy 176.402814 -192.567063) (xy 176.375096 -192.488825) (xy 176.354897 -192.408318)
			(xy 176.342395 -192.326262) (xy 176.3395 -192.284858) (xy 176.338484 -192.264538) (xy 176.309274 -192.236852)
			(xy 175.311562 -192.236852) (xy 175.283114 -192.260982) (xy 175.280066 -192.27927) (xy 175.275087 -192.306107)
			(xy 175.258265 -192.35803) (xy 175.233973 -192.406907) (xy 175.202741 -192.451669) (xy 175.165253 -192.491339)
			(xy 175.122327 -192.525049) (xy 175.074901 -192.552064) (xy 175.024012 -192.571794) (xy 174.970769 -192.583806)
			(xy 174.916338 -192.58784) (xy 174.861907 -192.583806) (xy 174.808664 -192.571794) (xy 174.757775 -192.552064)
			(xy 174.710349 -192.525049) (xy 174.667423 -192.491339) (xy 174.629935 -192.451669) (xy 174.598703 -192.406907)
			(xy 174.574411 -192.35803) (xy 174.557589 -192.306107) (xy 174.55261 -192.27927) (xy 174.549562 -192.260982)
			(xy 174.521114 -192.236852) (xy 173.522894 -192.236852) (xy 173.494446 -192.260982) (xy 173.491398 -192.27927)
			(xy 173.486419 -192.306107) (xy 173.469597 -192.35803) (xy 173.445305 -192.406907) (xy 173.414073 -192.451669)
			(xy 173.376585 -192.491339) (xy 173.333659 -192.525049) (xy 173.286233 -192.552064) (xy 173.235344 -192.571794)
			(xy 173.182101 -192.583806) (xy 173.12767 -192.58784) (xy 173.073239 -192.583806) (xy 173.019996 -192.571794)
			(xy 172.969107 -192.552064) (xy 172.921681 -192.525049) (xy 172.878755 -192.491339) (xy 172.841267 -192.451669)
			(xy 172.810035 -192.406907) (xy 172.785743 -192.35803) (xy 172.768921 -192.306107) (xy 172.763942 -192.27927)
			(xy 172.760894 -192.260982) (xy 172.732446 -192.236852) (xy 171.734734 -192.236852) (xy 171.705524 -192.264538)
			(xy 171.704508 -192.284858) (xy 171.701266 -192.330714) (xy 171.686419 -192.421441) (xy 171.662171 -192.51012)
			(xy 171.628788 -192.595778) (xy 171.608242 -192.636902) (xy 171.603257 -192.648067) (xy 171.603244 -192.672481)
			(xy 171.608242 -192.683638) (xy 171.626923 -192.720951) (xy 171.657948 -192.798419) (xy 171.681478 -192.878483)
			(xy 171.697299 -192.960419) (xy 171.705269 -193.043487) (xy 171.705778 -193.085212) (xy 171.705265 -193.127599)
			(xy 171.697083 -193.211976) (xy 171.680796 -193.29517) (xy 171.656556 -193.376403) (xy 171.62459 -193.454919)
			(xy 171.585195 -193.529982) (xy 171.538741 -193.600894) (xy 171.485659 -193.666991) (xy 171.426447 -193.727657)
			(xy 171.361656 -193.782326) (xy 171.327064 -193.806826) (xy 171.319415 -193.812579) (xy 171.308727 -193.828439)
			(xy 171.304584 -193.84711) (xy 171.305728 -193.85661) (xy 171.30868 -193.876162) (xy 171.311856 -193.915578)
			(xy 171.312078 -193.93535) (xy 171.311585 -193.967183) (xy 171.307789 -193.996564) (xy 172.632116 -193.996564)
			(xy 172.632561 -193.965981) (xy 172.640072 -193.905278) (xy 172.654998 -193.845962) (xy 172.677114 -193.788935)
			(xy 172.706082 -193.735064) (xy 172.741462 -193.685169) (xy 172.782716 -193.64001) (xy 172.829216 -193.600274)
			(xy 172.880254 -193.566564) (xy 172.907452 -193.552572) (xy 172.91939 -193.546476) (xy 172.934122 -193.524886)
			(xy 172.944536 -193.41211) (xy 172.933868 -193.388234) (xy 172.9232 -193.38036) (xy 172.900692 -193.362827)
			(xy 172.860858 -193.321983) (xy 172.82779 -193.275492) (xy 172.802276 -193.224462) (xy 172.784926 -193.170112)
			(xy 172.776152 -193.113738) (xy 172.775626 -193.085212) (xy 172.776142 -193.057612) (xy 172.784369 -193.003029)
			(xy 172.800639 -192.950282) (xy 172.824589 -192.90055) (xy 172.855684 -192.854942) (xy 172.893229 -192.814478)
			(xy 172.936386 -192.780061) (xy 172.98419 -192.752462) (xy 173.035574 -192.732295) (xy 173.089389 -192.720012)
			(xy 173.144434 -192.715887) (xy 173.199479 -192.720012) (xy 173.253294 -192.732295) (xy 173.304678 -192.752462)
			(xy 173.352482 -192.780061) (xy 173.395639 -192.814478) (xy 173.433184 -192.854942) (xy 173.464279 -192.90055)
			(xy 173.488229 -192.950282) (xy 173.504499 -193.003029) (xy 173.512726 -193.057612) (xy 173.513242 -193.085212)
			(xy 173.512796 -193.110593) (xy 173.505833 -193.160876) (xy 173.49204 -193.209728) (xy 173.471677 -193.256228)
			(xy 173.44513 -193.299495) (xy 173.412899 -193.338713) (xy 173.375595 -193.37314) (xy 173.355 -193.38798)
			(xy 173.343824 -193.3956) (xy 173.332394 -193.419222) (xy 173.338744 -193.532252) (xy 173.352714 -193.55435)
			(xy 173.364398 -193.5607) (xy 173.393397 -193.577053) (xy 173.447137 -193.616352) (xy 173.495134 -193.662489)
			(xy 173.536527 -193.714634) (xy 173.570569 -193.771848) (xy 173.596649 -193.833103) (xy 173.614298 -193.897297)
			(xy 173.623198 -193.963276) (xy 173.623732 -193.996564) (xy 173.623238 -194.029396) (xy 173.614574 -194.094487)
			(xy 173.597393 -194.157864) (xy 173.571996 -194.218418) (xy 173.538828 -194.27509) (xy 173.498468 -194.326887)
			(xy 173.451624 -194.372903) (xy 173.399115 -194.412332) (xy 173.370748 -194.428872) (xy 173.359572 -194.435222)
			(xy 173.34611 -194.456304) (xy 173.33722 -194.565778) (xy 173.347126 -194.588892) (xy 173.357286 -194.59702)
			(xy 173.378611 -194.614599) (xy 173.41624 -194.655073) (xy 173.447408 -194.70071) (xy 173.471418 -194.750486)
			(xy 173.487731 -194.803287) (xy 173.495983 -194.857932) (xy 173.496478 -194.885564) (xy 173.495962 -194.913164)
			(xy 173.487735 -194.967747) (xy 173.471465 -195.020494) (xy 173.447515 -195.070227) (xy 173.41642 -195.115834)
			(xy 173.378875 -195.156298) (xy 173.335718 -195.190715) (xy 173.287914 -195.218314) (xy 173.23653 -195.238481)
			(xy 173.182715 -195.250764) (xy 173.12767 -195.254889) (xy 173.072625 -195.250764) (xy 173.01881 -195.238481)
			(xy 172.967426 -195.218314) (xy 172.919622 -195.190715) (xy 172.876465 -195.156298) (xy 172.83892 -195.115834)
			(xy 172.807825 -195.070227) (xy 172.783875 -195.020494) (xy 172.767605 -194.967747) (xy 172.759378 -194.913164)
			(xy 172.758862 -194.885564) (xy 172.759354 -194.857901) (xy 172.767622 -194.803197) (xy 172.783968 -194.750341)
			(xy 172.808026 -194.70052) (xy 172.839254 -194.654851) (xy 172.876954 -194.614358) (xy 172.898308 -194.596766)
			(xy 172.908214 -194.588892) (xy 172.918374 -194.565778) (xy 172.909484 -194.45605) (xy 172.896022 -194.434968)
			(xy 172.884846 -194.428618) (xy 172.856513 -194.412073) (xy 172.804069 -194.372646) (xy 172.757284 -194.326646)
			(xy 172.716975 -194.274876) (xy 172.683847 -194.218242) (xy 172.658479 -194.157733) (xy 172.641313 -194.094407)
			(xy 172.632651 -194.02937) (xy 172.632116 -193.996564) (xy 171.307789 -193.996564) (xy 171.303428 -194.030324)
			(xy 171.287256 -194.091901) (xy 171.263334 -194.150901) (xy 171.232056 -194.206354) (xy 171.193937 -194.257346)
			(xy 171.172124 -194.280536) (xy 171.165012 -194.287902) (xy 171.157646 -194.30619) (xy 171.158662 -194.398138)
			(xy 171.166536 -194.416426) (xy 171.173648 -194.423538) (xy 171.197135 -194.447499) (xy 171.238249 -194.500524)
			(xy 171.272036 -194.558494) (xy 171.297909 -194.620402) (xy 171.315419 -194.685174) (xy 171.324261 -194.751686)
			(xy 171.324778 -194.785234) (xy 171.324276 -194.817195) (xy 171.316265 -194.880613) (xy 171.300368 -194.942527)
			(xy 171.276836 -195.00196) (xy 171.246042 -195.057975) (xy 171.208469 -195.10969) (xy 171.164712 -195.156287)
			(xy 171.115459 -195.197032) (xy 171.061488 -195.231283) (xy 171.003649 -195.2585) (xy 170.942856 -195.278253)
			(xy 170.880066 -195.290231) (xy 170.81627 -195.294245) (xy 170.752474 -195.290231) (xy 170.689684 -195.278253)
			(xy 170.628891 -195.2585) (xy 170.571052 -195.231283) (xy 170.517081 -195.197032) (xy 170.467828 -195.156287)
			(xy 170.424071 -195.10969) (xy 170.386498 -195.057975) (xy 170.355704 -195.00196) (xy 170.332172 -194.942527)
			(xy 170.316275 -194.880613) (xy 170.308264 -194.817195) (xy 170.307762 -194.785234) (xy 170.308298 -194.751686)
			(xy 170.317123 -194.685172) (xy 170.334623 -194.620397) (xy 170.360494 -194.558488) (xy 170.394286 -194.500522)
			(xy 170.435412 -194.447507) (xy 170.458892 -194.423538) (xy 170.466004 -194.416426) (xy 170.473878 -194.398138)
			(xy 170.474894 -194.30619) (xy 170.467528 -194.287902) (xy 170.460416 -194.280536) (xy 170.438594 -194.257354)
			(xy 170.400462 -194.206367) (xy 170.369179 -194.150915) (xy 170.345258 -194.091912) (xy 170.329095 -194.03033)
			(xy 170.320956 -193.967184) (xy 170.320462 -193.93535) (xy 170.320747 -193.9119) (xy 170.325198 -193.865213)
			(xy 170.329352 -193.842132) (xy 170.330772 -193.832646) (xy 170.327237 -193.813809) (xy 170.317019 -193.797594)
			(xy 170.30954 -193.791586) (xy 170.286596 -193.774439) (xy 170.242747 -193.737579) (xy 170.22191 -193.717926)
			(xy 170.214569 -193.711548) (xy 170.196515 -193.704363) (xy 170.177084 -193.704402) (xy 170.159059 -193.711659)
			(xy 170.145021 -193.725094) (xy 170.136981 -193.742784) (xy 170.13609 -193.762194) (xy 170.138852 -193.77152)
			(xy 170.14771 -193.797915) (xy 170.160134 -193.852188) (xy 170.166399 -193.907512) (xy 170.166792 -193.93535)
			(xy 170.166287 -193.967453) (xy 170.158 -194.03112) (xy 170.141559 -194.093185) (xy 170.117239 -194.152605)
			(xy 170.085447 -194.208386) (xy 170.046716 -194.259594) (xy 170.024552 -194.282822) (xy 170.01744 -194.290188)
			(xy 170.010074 -194.308984) (xy 170.011344 -194.401694) (xy 170.019472 -194.420236) (xy 170.026838 -194.427348)
			(xy 170.050522 -194.450809) (xy 170.092024 -194.502981) (xy 170.12616 -194.560243) (xy 170.152314 -194.621564)
			(xy 170.170016 -194.685836) (xy 170.178945 -194.751901) (xy 170.179492 -194.785234) (xy 170.178967 -194.817954)
			(xy 170.17036 -194.882824) (xy 170.153301 -194.946001) (xy 170.128086 -195.006387) (xy 170.095152 -195.062934)
			(xy 170.05507 -195.114662) (xy 170.032172 -195.13804) (xy 170.024806 -195.145152) (xy 170.016932 -195.163948)
			(xy 170.016932 -195.256658) (xy 170.024806 -195.275454) (xy 170.032172 -195.282566) (xy 170.055073 -195.305941)
			(xy 170.09516 -195.357666) (xy 170.128095 -195.414213) (xy 170.153308 -195.474601) (xy 170.170361 -195.537779)
			(xy 170.178958 -195.602652) (xy 170.179492 -195.635372) (xy 170.179003 -195.666535) (xy 170.171191 -195.728369)
			(xy 170.155691 -195.788737) (xy 170.132748 -195.846685) (xy 170.102722 -195.901302) (xy 170.066088 -195.951724)
			(xy 170.023423 -195.997158) (xy 169.975401 -196.036886) (xy 169.922777 -196.070281) (xy 169.866383 -196.096818)
			(xy 169.807108 -196.116078) (xy 169.745887 -196.127757) (xy 169.683684 -196.13167) (xy 169.621481 -196.127757)
			(xy 169.56026 -196.116078) (xy 169.500985 -196.096818) (xy 169.444591 -196.070281) (xy 169.391967 -196.036886)
			(xy 169.343945 -195.997158) (xy 169.30128 -195.951724) (xy 169.264646 -195.901302) (xy 169.23462 -195.846685)
			(xy 169.211677 -195.788737) (xy 169.196177 -195.728369) (xy 169.188365 -195.666535) (xy 169.187876 -195.635372)
			(xy 169.188402 -195.602653) (xy 169.197008 -195.537783) (xy 169.214068 -195.474607) (xy 169.239286 -195.414223)
			(xy 169.272223 -195.357678) (xy 169.312308 -195.305954) (xy 169.335196 -195.282566) (xy 169.342562 -195.275454)
			(xy 169.350436 -195.256658) (xy 169.350436 -195.163948) (xy 169.342562 -195.145152) (xy 169.335196 -195.13804)
			(xy 169.312296 -195.114664) (xy 169.272211 -195.062939) (xy 169.239277 -195.006391) (xy 169.214065 -194.946004)
			(xy 169.197012 -194.882826) (xy 169.188416 -194.817954) (xy 169.187876 -194.785234) (xy 169.188382 -194.753132)
			(xy 169.19667 -194.689464) (xy 169.213112 -194.627401) (xy 169.237433 -194.567981) (xy 169.269224 -194.5122)
			(xy 169.307954 -194.460992) (xy 169.330116 -194.437762) (xy 169.337228 -194.430396) (xy 169.344594 -194.4116)
			(xy 169.343324 -194.31889) (xy 169.335196 -194.300348) (xy 169.32783 -194.293236) (xy 169.304143 -194.269777)
			(xy 169.262638 -194.217606) (xy 169.228499 -194.160344) (xy 169.202343 -194.099023) (xy 169.184641 -194.034749)
			(xy 169.175713 -193.968683) (xy 169.175176 -193.93535) (xy 169.17571 -193.90289) (xy 169.184189 -193.838525)
			(xy 169.200997 -193.775817) (xy 169.225845 -193.71584) (xy 169.258309 -193.659618) (xy 169.297833 -193.608115)
			(xy 169.34374 -193.56221) (xy 169.395247 -193.52269) (xy 169.45147 -193.49023) (xy 169.511449 -193.465386)
			(xy 169.574158 -193.448583) (xy 169.638524 -193.440108) (xy 169.670984 -193.439542) (xy 169.703037 -193.440041)
			(xy 169.766608 -193.448301) (xy 169.828581 -193.464698) (xy 169.858436 -193.476372) (xy 169.872152 -193.48196)
			(xy 169.901108 -193.476626) (xy 169.990516 -193.394076) (xy 169.998136 -193.365628) (xy 169.993564 -193.351404)
			(xy 169.981065 -193.310523) (xy 169.963125 -193.226936) (xy 169.95775 -193.184526) (xy 169.95648 -193.173604)
			(xy 169.946066 -193.15557) (xy 169.868596 -193.098674) (xy 169.848022 -193.094102) (xy 169.837608 -193.096134)
			(xy 169.796359 -193.103619) (xy 169.712904 -193.111636) (xy 169.670984 -193.112136) (xy 169.629481 -193.111655)
			(xy 169.546846 -193.103818) (xy 169.465322 -193.088207) (xy 169.385638 -193.064962) (xy 169.308507 -193.03429)
			(xy 169.23462 -192.996466) (xy 169.164639 -192.951828) (xy 169.099189 -192.900777) (xy 169.038857 -192.843769)
			(xy 168.984182 -192.781314) (xy 168.935654 -192.713972) (xy 168.893708 -192.642345) (xy 168.858718 -192.567075)
			(xy 168.830999 -192.488834) (xy 168.810798 -192.408324) (xy 168.798296 -192.326266) (xy 168.795446 -192.284858)
			(xy 168.79443 -192.264538) (xy 168.76522 -192.236852) (xy 167.767508 -192.236852) (xy 167.73906 -192.260982)
			(xy 167.736012 -192.27927) (xy 167.731033 -192.306107) (xy 167.714211 -192.35803) (xy 167.689919 -192.406907)
			(xy 167.658687 -192.451669) (xy 167.621199 -192.491339) (xy 167.578273 -192.525049) (xy 167.530847 -192.552064)
			(xy 167.479958 -192.571794) (xy 167.426715 -192.583806) (xy 167.372284 -192.58784) (xy 167.317853 -192.583806)
			(xy 167.26461 -192.571794) (xy 167.213721 -192.552064) (xy 167.166295 -192.525049) (xy 167.123369 -192.491339)
			(xy 167.085881 -192.451669) (xy 167.054649 -192.406907) (xy 167.030357 -192.35803) (xy 167.013535 -192.306107)
			(xy 167.008556 -192.27927) (xy 167.005508 -192.260982) (xy 166.97706 -192.236852) (xy 165.97884 -192.236852)
			(xy 165.950392 -192.260982) (xy 165.947344 -192.27927) (xy 165.942365 -192.306107) (xy 165.925543 -192.35803)
			(xy 165.901251 -192.406907) (xy 165.870019 -192.451669) (xy 165.832531 -192.491339) (xy 165.789605 -192.525049)
			(xy 165.742179 -192.552064) (xy 165.69129 -192.571794) (xy 165.638047 -192.583806) (xy 165.583616 -192.58784)
			(xy 165.529185 -192.583806) (xy 165.475942 -192.571794) (xy 165.425053 -192.552064) (xy 165.377627 -192.525049)
			(xy 165.334701 -192.491339) (xy 165.297213 -192.451669) (xy 165.265981 -192.406907) (xy 165.241689 -192.35803)
			(xy 165.224867 -192.306107) (xy 165.219888 -192.27927) (xy 165.21684 -192.260982) (xy 165.188392 -192.236852)
			(xy 164.19068 -192.236852) (xy 164.16147 -192.264538) (xy 164.160454 -192.284858) (xy 164.157212 -192.330714)
			(xy 164.142365 -192.421442) (xy 164.118119 -192.51012) (xy 164.084737 -192.59578) (xy 164.064188 -192.636902)
			(xy 164.0592 -192.648066) (xy 164.059187 -192.672481) (xy 164.064188 -192.683638) (xy 164.082868 -192.720951)
			(xy 164.113892 -192.798419) (xy 164.13742 -192.878483) (xy 164.15324 -192.960419) (xy 164.16121 -193.043488)
			(xy 164.161724 -193.085212) (xy 164.161212 -193.127599) (xy 164.153029 -193.211977) (xy 164.136743 -193.295172)
			(xy 164.112504 -193.376406) (xy 164.080539 -193.454923) (xy 164.041146 -193.529988) (xy 163.994692 -193.600901)
			(xy 163.941613 -193.667001) (xy 163.882402 -193.727669) (xy 163.817613 -193.782341) (xy 163.78301 -193.806826)
			(xy 163.775368 -193.812583) (xy 163.764691 -193.828443) (xy 163.760553 -193.847109) (xy 163.761674 -193.85661)
			(xy 163.764626 -193.876162) (xy 163.767803 -193.915578) (xy 163.768024 -193.93535) (xy 163.767531 -193.967182)
			(xy 163.763733 -193.996582) (xy 165.087472 -193.996582) (xy 165.091318 -193.934942) (xy 165.102793 -193.874258)
			(xy 165.121718 -193.815469) (xy 165.147801 -193.759487) (xy 165.180637 -193.707179) (xy 165.219718 -193.659356)
			(xy 165.264437 -193.61676) (xy 165.314102 -193.580049) (xy 165.340792 -193.56451) (xy 165.351968 -193.55816)
			(xy 165.36543 -193.537078) (xy 165.37432 -193.42735) (xy 165.36416 -193.404236) (xy 165.354254 -193.396362)
			(xy 165.332878 -193.378795) (xy 165.295179 -193.338298) (xy 165.263953 -193.292624) (xy 165.2399 -193.242797)
			(xy 165.22356 -193.189937) (xy 165.2153 -193.135228) (xy 165.214808 -193.107564) (xy 165.215324 -193.079964)
			(xy 165.223551 -193.025381) (xy 165.239821 -192.972634) (xy 165.263771 -192.922902) (xy 165.294866 -192.877294)
			(xy 165.332411 -192.83683) (xy 165.375568 -192.802413) (xy 165.423372 -192.774814) (xy 165.474756 -192.754647)
			(xy 165.528571 -192.742364) (xy 165.583616 -192.738239) (xy 165.638661 -192.742364) (xy 165.692476 -192.754647)
			(xy 165.74386 -192.774814) (xy 165.791664 -192.802413) (xy 165.834821 -192.83683) (xy 165.872366 -192.877294)
			(xy 165.903461 -192.922902) (xy 165.927411 -192.972634) (xy 165.943681 -193.025381) (xy 165.951908 -193.079964)
			(xy 165.952424 -193.107564) (xy 165.951927 -193.135197) (xy 165.943692 -193.189846) (xy 165.927386 -193.242652)
			(xy 165.903376 -193.29243) (xy 165.8722 -193.338063) (xy 165.834557 -193.378527) (xy 165.813232 -193.396108)
			(xy 165.803072 -193.404236) (xy 165.793166 -193.42735) (xy 165.802056 -193.536824) (xy 165.815518 -193.557906)
			(xy 165.826694 -193.564256) (xy 165.853372 -193.579852) (xy 165.903074 -193.616571) (xy 165.947828 -193.659182)
			(xy 165.986939 -193.707025) (xy 166.019802 -193.759358) (xy 166.045906 -193.815368) (xy 166.064847 -193.874189)
			(xy 166.076331 -193.934907) (xy 166.08018 -193.996582) (xy 166.076335 -194.058258) (xy 166.064855 -194.118977)
			(xy 166.045919 -194.177799) (xy 166.019818 -194.233811) (xy 165.98696 -194.286146) (xy 165.947852 -194.333992)
			(xy 165.903101 -194.376606) (xy 165.853402 -194.413329) (xy 165.826694 -194.428872) (xy 165.815518 -194.435222)
			(xy 165.802056 -194.456304) (xy 165.793166 -194.565778) (xy 165.803072 -194.588892) (xy 165.813232 -194.59702)
			(xy 165.834566 -194.614588) (xy 165.872193 -194.655066) (xy 165.903358 -194.700705) (xy 165.927366 -194.750483)
			(xy 165.943678 -194.803286) (xy 165.951929 -194.857932) (xy 165.952424 -194.885564) (xy 165.951908 -194.913164)
			(xy 165.943681 -194.967747) (xy 165.927411 -195.020494) (xy 165.903461 -195.070227) (xy 165.872366 -195.115834)
			(xy 165.834821 -195.156298) (xy 165.791664 -195.190715) (xy 165.74386 -195.218314) (xy 165.692476 -195.238481)
			(xy 165.638661 -195.250764) (xy 165.583616 -195.254889) (xy 165.528571 -195.250764) (xy 165.474756 -195.238481)
			(xy 165.423372 -195.218314) (xy 165.375568 -195.190715) (xy 165.332411 -195.156298) (xy 165.294866 -195.115834)
			(xy 165.263771 -195.070227) (xy 165.239821 -195.020494) (xy 165.223551 -194.967747) (xy 165.215324 -194.913164)
			(xy 165.214808 -194.885564) (xy 165.215319 -194.857902) (xy 165.223587 -194.8032) (xy 165.23993 -194.750345)
			(xy 165.263984 -194.700524) (xy 165.295208 -194.654854) (xy 165.332902 -194.614359) (xy 165.354254 -194.596766)
			(xy 165.36416 -194.588892) (xy 165.37432 -194.565778) (xy 165.36543 -194.45605) (xy 165.351968 -194.434968)
			(xy 165.340792 -194.428618) (xy 165.314073 -194.413132) (xy 165.26441 -194.376417) (xy 165.219694 -194.333818)
			(xy 165.180617 -194.285992) (xy 165.147784 -194.233682) (xy 165.121705 -194.177698) (xy 165.102784 -194.118908)
			(xy 165.091313 -194.058223) (xy 165.087472 -193.996582) (xy 163.763733 -193.996582) (xy 163.759374 -194.030323)
			(xy 163.7432 -194.091899) (xy 163.719276 -194.150898) (xy 163.687996 -194.206348) (xy 163.649874 -194.257338)
			(xy 163.62807 -194.280536) (xy 163.620958 -194.287902) (xy 163.613592 -194.30619) (xy 163.614608 -194.398138)
			(xy 163.622482 -194.416426) (xy 163.629594 -194.423538) (xy 163.653079 -194.4475) (xy 163.69419 -194.500526)
			(xy 163.727974 -194.558496) (xy 163.753844 -194.620404) (xy 163.771352 -194.685175) (xy 163.780194 -194.751686)
			(xy 163.780724 -194.785234) (xy 163.780222 -194.817195) (xy 163.772211 -194.880613) (xy 163.756314 -194.942527)
			(xy 163.732782 -195.00196) (xy 163.701988 -195.057975) (xy 163.664415 -195.10969) (xy 163.620658 -195.156287)
			(xy 163.571405 -195.197032) (xy 163.517434 -195.231283) (xy 163.459595 -195.2585) (xy 163.398802 -195.278253)
			(xy 163.336012 -195.290231) (xy 163.272216 -195.294245) (xy 163.20842 -195.290231) (xy 163.14563 -195.278253)
			(xy 163.084837 -195.2585) (xy 163.026998 -195.231283) (xy 162.973027 -195.197032) (xy 162.923774 -195.156287)
			(xy 162.880017 -195.10969) (xy 162.842444 -195.057975) (xy 162.81165 -195.00196) (xy 162.788118 -194.942527)
			(xy 162.772221 -194.880613) (xy 162.76421 -194.817195) (xy 162.763708 -194.785234) (xy 162.764329 -194.748569)
			(xy 162.774831 -194.675996) (xy 162.795664 -194.605688) (xy 162.810444 -194.572128) (xy 162.81654 -194.559428)
			(xy 162.813492 -194.531488) (xy 162.743134 -194.437508) (xy 162.717226 -194.42684) (xy 162.70351 -194.428872)
			(xy 162.68495 -194.431475) (xy 162.647574 -194.434274) (xy 162.628834 -194.43446) (xy 162.595967 -194.433939)
			(xy 162.530781 -194.425463) (xy 162.46723 -194.408659) (xy 162.406374 -194.383809) (xy 162.349226 -194.351326)
			(xy 162.296738 -194.311752) (xy 162.249786 -194.265746) (xy 162.209152 -194.214074) (xy 162.175513 -194.157599)
			(xy 162.14943 -194.097261) (xy 162.131337 -194.034065) (xy 162.125914 -194.001644) (xy 162.123882 -193.987928)
			(xy 162.106864 -193.966846) (xy 162.011614 -193.930016) (xy 162.003115 -193.927113) (xy 161.98517 -193.926814)
			(xy 161.968218 -193.932711) (xy 161.961068 -193.938144) (xy 161.762948 -194.100704) (xy 161.729761 -194.127143)
			(xy 161.658687 -194.1735) (xy 161.583022 -194.211908) (xy 161.50365 -194.241915) (xy 161.46272 -194.253104)
			(xy 161.452157 -194.256382) (xy 161.435028 -194.270337) (xy 161.4297 -194.280028) (xy 161.417882 -194.30391)
			(xy 161.391441 -194.350176) (xy 161.376868 -194.372484) (xy 161.372376 -194.379937) (xy 161.368209 -194.396819)
			(xy 161.36874 -194.405504) (xy 161.371534 -194.434968) (xy 161.372768 -194.443324) (xy 161.379897 -194.458623)
			(xy 161.385504 -194.46494) (xy 161.399716 -194.48032) (xy 161.425047 -194.51367) (xy 161.43605 -194.531488)
			(xy 161.440722 -194.53863) (xy 161.453824 -194.54955) (xy 161.461704 -194.552824) (xy 161.489644 -194.563492)
			(xy 161.497922 -194.566207) (xy 161.515328 -194.566475) (xy 161.52368 -194.564) (xy 161.549589 -194.555771)
			(xy 161.602717 -194.544243) (xy 161.656772 -194.538443) (xy 161.683954 -194.538092) (xy 161.714688 -194.538535)
			(xy 161.775708 -194.545939) (xy 161.835391 -194.560645) (xy 161.892866 -194.582437) (xy 161.947295 -194.610999)
			(xy 161.997883 -194.645914) (xy 162.043895 -194.686673) (xy 162.084657 -194.73268) (xy 162.119577 -194.783266)
			(xy 162.148144 -194.837692) (xy 162.169942 -194.895165) (xy 162.184653 -194.954847) (xy 162.192062 -195.015866)
			(xy 162.192462 -195.0466) (xy 162.192013 -195.077399) (xy 162.184576 -195.138545) (xy 162.169811 -195.198347)
			(xy 162.147934 -195.255928) (xy 162.119264 -195.310447) (xy 162.084222 -195.361105) (xy 162.04332 -195.407162)
			(xy 162.020504 -195.427854) (xy 162.013138 -195.434204) (xy 162.004248 -195.451476) (xy 161.99612 -195.540376)
			(xy 162.001454 -195.558918) (xy 162.00755 -195.566538) (xy 162.027869 -195.593455) (xy 162.061982 -195.651634)
			(xy 162.088106 -195.713811) (xy 162.105783 -195.778895) (xy 162.114702 -195.845745) (xy 162.115246 -195.879466)
			(xy 162.114744 -195.911427) (xy 162.106733 -195.974845) (xy 162.090836 -196.036759) (xy 162.067304 -196.096192)
			(xy 162.03651 -196.152207) (xy 161.998937 -196.203922) (xy 161.95518 -196.250519) (xy 161.905927 -196.291264)
			(xy 161.851956 -196.325515) (xy 161.794117 -196.352732) (xy 161.733324 -196.372485) (xy 161.670534 -196.384463)
			(xy 161.606738 -196.388477) (xy 161.542942 -196.384463) (xy 161.480152 -196.372485) (xy 161.419359 -196.352732)
			(xy 161.36152 -196.325515) (xy 161.307549 -196.291264) (xy 161.258296 -196.250519) (xy 161.214539 -196.203922)
			(xy 161.176966 -196.152207) (xy 161.146172 -196.096192) (xy 161.12264 -196.036759) (xy 161.106743 -195.974845)
			(xy 161.098732 -195.911427) (xy 161.09823 -195.879466) (xy 161.098681 -195.848668) (xy 161.106121 -195.787523)
			(xy 161.12089 -195.727724) (xy 161.14277 -195.670146) (xy 161.171441 -195.61563) (xy 161.206485 -195.564974)
			(xy 161.247387 -195.51892) (xy 161.270188 -195.498212) (xy 161.277554 -195.491862) (xy 161.286444 -195.47459)
			(xy 161.294572 -195.38569) (xy 161.289238 -195.367148) (xy 161.283142 -195.359528) (xy 161.261438 -195.330757)
			(xy 161.225511 -195.268283) (xy 161.198778 -195.201357) (xy 161.18967 -195.166488) (xy 161.187282 -195.158137)
			(xy 161.177803 -195.143597) (xy 161.171128 -195.13804) (xy 161.147506 -195.120006) (xy 161.140515 -195.115099)
			(xy 161.124295 -195.109775) (xy 161.115756 -195.109592) (xy 161.109152 -195.109592) (xy 161.083397 -195.109171)
			(xy 161.032356 -195.102244) (xy 160.982712 -195.088508) (xy 160.935369 -195.068213) (xy 160.891189 -195.04173)
			(xy 160.850977 -195.00954) (xy 160.815464 -194.972229) (xy 160.800034 -194.951604) (xy 160.794747 -194.9449)
			(xy 160.780728 -194.935174) (xy 160.772602 -194.932554) (xy 160.744154 -194.924426) (xy 160.73559 -194.922357)
			(xy 160.71803 -194.923658) (xy 160.709864 -194.926966) (xy 160.680784 -194.939404) (xy 160.621021 -194.960128)
			(xy 160.590484 -194.968368) (xy 160.579923 -194.971649) (xy 160.562797 -194.985605) (xy 160.557464 -194.995292)
			(xy 160.541716 -195.02628) (xy 160.536128 -195.03644) (xy 160.535112 -195.0593) (xy 160.574736 -195.153788)
			(xy 160.591754 -195.169028) (xy 160.60293 -195.172076) (xy 160.634333 -195.181649) (xy 160.694562 -195.207777)
			(xy 160.750927 -195.241439) (xy 160.80249 -195.282076) (xy 160.848394 -195.329012) (xy 160.887875 -195.381466)
			(xy 160.920275 -195.438566) (xy 160.945057 -195.49936) (xy 160.961808 -195.562839) (xy 160.970249 -195.627946)
			(xy 160.970722 -195.660772) (xy 160.970191 -195.69414) (xy 160.961451 -195.7603) (xy 160.94413 -195.824748)
			(xy 160.918526 -195.886377) (xy 160.885079 -195.944125) (xy 160.844364 -195.997002) (xy 160.821116 -196.020944)
			(xy 160.814872 -196.027806) (xy 160.80731 -196.044733) (xy 160.806384 -196.053964) (xy 160.804352 -196.084444)
			(xy 160.80419 -196.093748) (xy 160.809781 -196.111479) (xy 160.815274 -196.118988) (xy 160.83577 -196.145974)
			(xy 160.870196 -196.204344) (xy 160.896567 -196.266768) (xy 160.914417 -196.33214) (xy 160.923429 -196.399303)
			(xy 160.923986 -196.433186) (xy 160.923484 -196.465147) (xy 160.915473 -196.528565) (xy 160.899576 -196.590479)
			(xy 160.876044 -196.649912) (xy 160.84525 -196.705927) (xy 160.807677 -196.757642) (xy 160.76392 -196.804239)
			(xy 160.714667 -196.844984) (xy 160.660696 -196.879235) (xy 160.602857 -196.906452) (xy 160.542064 -196.926205)
			(xy 160.479274 -196.938183) (xy 160.415478 -196.942197) (xy 160.351682 -196.938183) (xy 160.288892 -196.926205)
			(xy 160.228099 -196.906452) (xy 160.17026 -196.879235) (xy 160.116289 -196.844984) (xy 160.067036 -196.804239)
			(xy 160.023279 -196.757642) (xy 159.985706 -196.705927) (xy 159.954912 -196.649912) (xy 159.93138 -196.590479)
			(xy 159.915483 -196.528565) (xy 159.907472 -196.465147) (xy 159.90697 -196.433186) (xy 159.907497 -196.399817)
			(xy 159.91623 -196.333653) (xy 159.933545 -196.2692) (xy 159.959144 -196.207566) (xy 159.992587 -196.149811)
			(xy 160.033298 -196.096929) (xy 160.056576 -196.073014) (xy 160.062816 -196.06615) (xy 160.070364 -196.049222)
			(xy 160.071308 -196.039994) (xy 160.07334 -196.009514) (xy 160.073494 -196.000213) (xy 160.067891 -195.982492)
			(xy 160.062418 -195.97497) (xy 160.042052 -195.948175) (xy 160.007815 -195.890229) (xy 159.981534 -195.828267)
			(xy 159.963669 -195.763377) (xy 159.958532 -195.730114) (xy 159.956754 -195.718176) (xy 159.9438 -195.698872)
			(xy 159.85363 -195.647056) (xy 159.830262 -195.645278) (xy 159.81934 -195.64985) (xy 159.794592 -195.659793)
			(xy 159.744001 -195.676696) (xy 159.718248 -195.683632) (xy 159.707696 -195.686923) (xy 159.690596 -195.700891)
			(xy 159.685228 -195.710556) (xy 159.666247 -195.748571) (xy 159.621221 -195.820635) (xy 159.568658 -195.887402)
			(xy 159.509177 -195.948085) (xy 159.476694 -195.975478) (xy 159.155638 -196.238622) (xy 159.147764 -196.245226)
			(xy 159.114455 -196.271911) (xy 159.043055 -196.318675) (xy 158.966998 -196.357407) (xy 158.887183 -196.387649)
			(xy 158.846012 -196.398896) (xy 158.835449 -196.402175) (xy 158.818321 -196.41613) (xy 158.812992 -196.42582)
			(xy 158.794013 -196.463837) (xy 158.748992 -196.535906) (xy 158.696434 -196.602678) (xy 158.636957 -196.663368)
			(xy 158.604458 -196.690742) (xy 158.274258 -196.961506) (xy 158.24107 -196.988017) (xy 158.16995 -197.034472)
			(xy 158.094216 -197.07295) (xy 158.014761 -197.102999) (xy 157.973776 -197.11416) (xy 157.963215 -197.117442)
			(xy 157.94609 -197.131397) (xy 157.940756 -197.141084) (xy 157.921778 -197.179102) (xy 157.876758 -197.251172)
			(xy 157.8242 -197.317944) (xy 157.764723 -197.378635) (xy 157.732222 -197.406006) (xy 157.402022 -197.67677)
			(xy 157.368832 -197.703278) (xy 157.297709 -197.749727) (xy 157.221975 -197.788198) (xy 157.142518 -197.81824)
			(xy 157.10154 -197.829424) (xy 157.090988 -197.832716) (xy 157.07389 -197.846684) (xy 157.06852 -197.856348)
			(xy 157.052317 -197.888953) (xy 157.014704 -197.951299) (xy 156.971459 -198.009879) (xy 156.922954 -198.064185)
			(xy 156.896562 -198.089266) (xy 156.890415 -198.095402) (xy 156.882335 -198.110762) (xy 156.879893 -198.127945)
			(xy 156.881322 -198.13651) (xy 156.884898 -198.155292) (xy 156.888713 -198.193338) (xy 156.888942 -198.212456)
			(xy 156.888482 -198.239712) (xy 156.88073 -198.293669) (xy 156.865379 -198.345975) (xy 156.842739 -198.395562)
			(xy 156.813273 -198.441424) (xy 156.77758 -198.482624) (xy 156.736386 -198.518326) (xy 156.690531 -198.547802)
			(xy 156.640948 -198.570451) (xy 156.588646 -198.585814) (xy 156.53469 -198.593577) (xy 156.507434 -198.593964)
			(xy 156.481418 -198.593524) (xy 156.42987 -198.586451) (xy 156.379763 -198.572431) (xy 156.332029 -198.551726)
			(xy 156.309568 -198.538592) (xy 156.300017 -198.533372) (xy 156.278434 -198.53073) (xy 156.267912 -198.533512)
			(xy 156.229304 -198.544688) (xy 156.218742 -198.547967) (xy 156.201614 -198.561922) (xy 156.196284 -198.571612)
			(xy 156.177305 -198.609629) (xy 156.132285 -198.681699) (xy 156.079727 -198.748471) (xy 156.02025 -198.809161)
			(xy 155.98775 -198.836534) (xy 155.713049 -199.061789) (xy 156.627824 -199.061789) (xy 156.627824 -198.997867)
			(xy 156.635835 -198.934449) (xy 156.651732 -198.872535) (xy 156.675264 -198.813102) (xy 156.706058 -198.757087)
			(xy 156.743631 -198.705372) (xy 156.787388 -198.658775) (xy 156.836641 -198.61803) (xy 156.890612 -198.583779)
			(xy 156.948451 -198.556562) (xy 157.009244 -198.536809) (xy 157.072034 -198.524831) (xy 157.13583 -198.520818)
			(xy 157.199626 -198.524831) (xy 157.262416 -198.536809) (xy 157.323209 -198.556562) (xy 157.381048 -198.583779)
			(xy 157.435019 -198.61803) (xy 157.484272 -198.658775) (xy 157.528029 -198.705372) (xy 157.565602 -198.757087)
			(xy 157.596396 -198.813102) (xy 157.619928 -198.872535) (xy 157.635825 -198.934449) (xy 157.643836 -198.997867)
			(xy 157.644338 -199.029828) (xy 157.643836 -199.061789) (xy 157.635825 -199.125207) (xy 157.619928 -199.187121)
			(xy 157.596396 -199.246554) (xy 157.565602 -199.302569) (xy 157.528029 -199.354284) (xy 157.484272 -199.400881)
			(xy 157.435019 -199.441626) (xy 157.381048 -199.475877) (xy 157.323209 -199.503094) (xy 157.262416 -199.522847)
			(xy 157.199626 -199.534825) (xy 157.13583 -199.538839) (xy 157.072034 -199.534825) (xy 157.009244 -199.522847)
			(xy 156.948451 -199.503094) (xy 156.890612 -199.475877) (xy 156.836641 -199.441626) (xy 156.787388 -199.400881)
			(xy 156.743631 -199.354284) (xy 156.706058 -199.302569) (xy 156.675264 -199.246554) (xy 156.651732 -199.187121)
			(xy 156.635835 -199.125207) (xy 156.627824 -199.061789) (xy 155.713049 -199.061789) (xy 155.65755 -199.107298)
			(xy 155.627878 -199.131044) (xy 155.564713 -199.17331) (xy 155.49775 -199.209258) (xy 155.427618 -199.238548)
			(xy 155.354979 -199.260905) (xy 155.280515 -199.276119) (xy 155.242768 -199.280526) (xy 155.235148 -199.281288)
			(xy 155.221686 -199.286876) (xy 153.989532 -200.297034) (xy 153.985722 -200.30059) (xy 153.52776 -200.758552)
			(xy 153.527077 -200.766172) (xy 155.513276 -200.766172) (xy 155.517347 -200.71055) (xy 155.529473 -200.656113)
			(xy 155.549396 -200.604022) (xy 155.576692 -200.555387) (xy 155.610778 -200.511244) (xy 155.650927 -200.472535)
			(xy 155.696285 -200.440084) (xy 155.745885 -200.414583) (xy 155.798669 -200.396576) (xy 155.853512 -200.386446)
			(xy 155.909246 -200.384409) (xy 155.964683 -200.390509) (xy 156.01864 -200.404615) (xy 156.069969 -200.426427)
			(xy 156.117575 -200.455481) (xy 156.160443 -200.491156) (xy 156.19766 -200.532693) (xy 156.228433 -200.579206)
			(xy 156.252105 -200.629703) (xy 156.268173 -200.68311) (xy 156.276293 -200.738286) (xy 156.276802 -200.766172)
			(xy 156.276293 -200.794058) (xy 156.268173 -200.849234) (xy 156.252105 -200.902641) (xy 156.228433 -200.953138)
			(xy 156.19766 -200.999651) (xy 156.160443 -201.041188) (xy 156.117575 -201.076863) (xy 156.069969 -201.105917)
			(xy 156.01864 -201.127729) (xy 155.964683 -201.141835) (xy 155.909246 -201.147935) (xy 155.853512 -201.145898)
			(xy 155.798669 -201.135768) (xy 155.745885 -201.117761) (xy 155.696285 -201.09226) (xy 155.650927 -201.059809)
			(xy 155.610778 -201.0211) (xy 155.576692 -200.976957) (xy 155.549396 -200.928322) (xy 155.529473 -200.876231)
			(xy 155.517347 -200.821794) (xy 155.513276 -200.766172) (xy 153.527077 -200.766172) (xy 153.524458 -200.795382)
			(xy 153.53538 -200.810622) (xy 153.552971 -200.836415) (xy 153.582404 -200.891476) (xy 153.604864 -200.94973)
			(xy 153.620013 -201.010298) (xy 153.627621 -201.072267) (xy 153.62809 -201.103484) (xy 153.62762 -201.134884)
			(xy 153.619889 -201.197206) (xy 153.604553 -201.258104) (xy 153.581846 -201.316655) (xy 153.567384 -201.34453)
			(xy 153.562558 -201.35342) (xy 153.560526 -201.372978) (xy 153.585164 -201.4601) (xy 153.597102 -201.475594)
			(xy 153.605738 -201.480674) (xy 153.633317 -201.49723) (xy 153.684454 -201.536254) (xy 153.730255 -201.58142)
			(xy 153.769988 -201.632008) (xy 153.803018 -201.687206) (xy 153.828815 -201.746133) (xy 153.838402 -201.776838)
			(xy 153.84145 -201.786744) (xy 153.853642 -201.801984) (xy 153.933906 -201.846434) (xy 153.953464 -201.84872)
			(xy 153.96337 -201.845926) (xy 153.988517 -201.839379) (xy 154.040004 -201.832374) (xy 154.065986 -201.831956)
			(xy 154.093242 -201.832418) (xy 154.1472 -201.840174) (xy 154.199504 -201.85553) (xy 154.249091 -201.878174)
			(xy 154.29495 -201.907645) (xy 154.336148 -201.943342) (xy 154.371847 -201.984539) (xy 154.401319 -202.030397)
			(xy 154.423965 -202.079983) (xy 154.439323 -202.132287) (xy 154.447081 -202.186244) (xy 154.447081 -202.240756)
			(xy 154.439323 -202.294713) (xy 154.423965 -202.347017) (xy 154.401319 -202.396603) (xy 154.371847 -202.442461)
			(xy 154.336148 -202.483658) (xy 154.29495 -202.519355) (xy 154.249091 -202.548826) (xy 154.199504 -202.57147)
			(xy 154.1472 -202.586826) (xy 154.093242 -202.594582) (xy 154.065986 -202.594972) (xy 154.037365 -202.594459)
			(xy 153.980765 -202.585909) (xy 153.926077 -202.569002) (xy 153.874527 -202.544118) (xy 153.827271 -202.511814)
			(xy 153.785369 -202.472816) (xy 153.749761 -202.427998) (xy 153.735024 -202.403456) (xy 153.729944 -202.394566)
			(xy 153.71445 -202.382374) (xy 153.626058 -202.35799) (xy 153.6065 -202.360276) (xy 153.59761 -202.365102)
			(xy 153.569184 -202.380312) (xy 153.509317 -202.404234) (xy 153.446908 -202.420407) (xy 153.382957 -202.428573)
			(xy 153.350722 -202.42911) (xy 153.319989 -202.428666) (xy 153.258971 -202.421259) (xy 153.19929 -202.406552)
			(xy 153.141818 -202.384757) (xy 153.087392 -202.356194) (xy 153.036805 -202.321279) (xy 152.990796 -202.280521)
			(xy 152.950036 -202.234514) (xy 152.915118 -202.183929) (xy 152.886552 -202.129504) (xy 152.864756 -202.072033)
			(xy 152.850045 -202.012353) (xy 152.842636 -201.951335) (xy 152.842214 -201.920602) (xy 152.842684 -201.889202)
			(xy 152.850418 -201.826881) (xy 152.865755 -201.765983) (xy 152.888463 -201.707434) (xy 152.90292 -201.679556)
			(xy 152.907746 -201.670666) (xy 152.909778 -201.651108) (xy 152.88514 -201.563986) (xy 152.873202 -201.548492)
			(xy 152.864566 -201.543412) (xy 152.82672 -201.519282) (xy 152.81148 -201.50836) (xy 152.77465 -201.511662)
			(xy 151.78405 -202.502262) (xy 151.775676 -202.511452) (xy 151.768229 -202.535144) (xy 151.769826 -202.547474)
			(xy 151.787098 -202.641962) (xy 151.802338 -202.66152) (xy 151.813768 -202.6666) (xy 151.838433 -202.678328)
			(xy 151.884422 -202.707789) (xy 151.925744 -202.743501) (xy 151.961556 -202.784737) (xy 151.991128 -202.830653)
			(xy 152.013857 -202.880315) (xy 152.029278 -202.932708) (xy 152.037077 -202.986764) (xy 152.037542 -203.014072)
			(xy 152.037058 -203.041325) (xy 152.029305 -203.095278) (xy 152.013953 -203.147578) (xy 151.991314 -203.197161)
			(xy 151.961849 -203.243017) (xy 151.926158 -203.284214) (xy 151.884967 -203.319911) (xy 151.839115 -203.349384)
			(xy 151.789536 -203.372031) (xy 151.737239 -203.387392) (xy 151.683287 -203.395154) (xy 151.656034 -203.39558)
			(xy 151.628725 -203.395116) (xy 151.574664 -203.387333) (xy 151.522265 -203.371922) (xy 151.472598 -203.349197)
			(xy 151.42668 -203.319623) (xy 151.385447 -203.283804) (xy 151.349742 -203.242471) (xy 151.320295 -203.196471)
			(xy 151.308562 -203.171806) (xy 151.303482 -203.160376) (xy 151.283924 -203.145136) (xy 151.189436 -203.127864)
			(xy 151.177106 -203.126239) (xy 151.153413 -203.133706) (xy 151.144224 -203.142088) (xy 150.439628 -203.846684)
			(xy 150.433194 -203.853723) (xy 150.425626 -203.871212) (xy 150.424896 -203.88072) (xy 150.42388 -203.910692)
			(xy 150.423976 -203.919779) (xy 150.42984 -203.936963) (xy 150.43531 -203.94422) (xy 150.456702 -203.971533)
			(xy 150.492671 -204.030857) (xy 150.520238 -204.094521) (xy 150.538894 -204.161342) (xy 150.548291 -204.230079)
			(xy 150.548848 -204.264768) (xy 150.548848 -204.274166) (xy 150.549033 -204.282943) (xy 150.554612 -204.299575)
			(xy 150.55977 -204.306678) (xy 150.578312 -204.3303) (xy 150.583955 -204.336886) (xy 150.598634 -204.346098)
			(xy 150.607014 -204.348334) (xy 150.635371 -204.355249) (xy 150.689717 -204.376533) (xy 150.740177 -204.405862)
			(xy 150.763224 -204.423772) (xy 150.771098 -204.430122) (xy 150.78964 -204.43571) (xy 150.87981 -204.427836)
			(xy 150.897082 -204.418946) (xy 150.903686 -204.411326) (xy 150.924431 -204.38823) (xy 150.970616 -204.346741)
			(xy 151.021505 -204.31118) (xy 151.076344 -204.282076) (xy 151.134317 -204.259862) (xy 151.194562 -204.244868)
			(xy 151.256184 -204.237316) (xy 151.287226 -204.236828) (xy 151.319184 -204.237331) (xy 151.382595 -204.245345)
			(xy 151.444502 -204.261243) (xy 151.503928 -204.284774) (xy 151.559936 -204.315568) (xy 151.611644 -204.353138)
			(xy 151.658235 -204.396892) (xy 151.698975 -204.446141) (xy 151.733222 -204.500107) (xy 151.760435 -204.55794)
			(xy 151.780185 -204.618727) (xy 151.792161 -204.681511) (xy 151.796175 -204.7453) (xy 151.792161 -204.809089)
			(xy 151.780185 -204.871873) (xy 151.760435 -204.93266) (xy 151.733222 -204.990493) (xy 151.698975 -205.044459)
			(xy 151.658235 -205.093708) (xy 151.611644 -205.137462) (xy 151.559936 -205.175032) (xy 151.503928 -205.205826)
			(xy 151.444502 -205.229357) (xy 151.382595 -205.245255) (xy 151.319184 -205.253269) (xy 151.287226 -205.253844)
			(xy 151.253821 -205.253318) (xy 151.187585 -205.244572) (xy 151.123064 -205.227229) (xy 151.061371 -205.201586)
			(xy 151.003566 -205.168086) (xy 150.950646 -205.127304) (xy 150.903522 -205.079944) (xy 150.882858 -205.053692)
			(xy 150.876762 -205.045564) (xy 150.859998 -205.035658) (xy 150.770336 -205.021942) (xy 150.75154 -205.02626)
			(xy 150.743412 -205.032102) (xy 150.719149 -205.048578) (xy 150.666627 -205.074673) (xy 150.610728 -205.092417)
			(xy 150.552772 -205.101391) (xy 150.523448 -205.101952) (xy 150.496059 -205.101476) (xy 150.441846 -205.093637)
			(xy 150.38931 -205.078129) (xy 150.339531 -205.055268) (xy 150.293532 -205.025526) (xy 150.252257 -204.989513)
			(xy 150.216555 -204.947969) (xy 150.187159 -204.901747) (xy 150.164673 -204.851798) (xy 150.156672 -204.8256)
			(xy 150.153981 -204.817409) (xy 150.143985 -204.803375) (xy 150.137114 -204.798168) (xy 150.112476 -204.780896)
			(xy 150.105104 -204.776151) (xy 150.088219 -204.771482) (xy 150.079456 -204.771752) (xy 150.04034 -204.773276)
			(xy 150.00988 -204.772825) (xy 149.949398 -204.765541) (xy 149.890219 -204.751083) (xy 149.833191 -204.729659)
			(xy 149.779131 -204.701577) (xy 149.728812 -204.667237) (xy 149.705568 -204.647546) (xy 149.690582 -204.634338)
			(xy 149.65045 -204.635862) (xy 149.12975 -205.156562) (xy 149.127718 -205.19517) (xy 149.140164 -205.21041)
			(xy 149.156224 -205.230905) (xy 149.183234 -205.275419) (xy 149.203946 -205.32319) (xy 149.217979 -205.373332)
			(xy 149.225072 -205.424914) (xy 149.225508 -205.450948) (xy 149.225019 -205.478197) (xy 149.217257 -205.53214)
			(xy 149.201898 -205.584429) (xy 149.179254 -205.634) (xy 149.149786 -205.679844) (xy 149.114095 -205.721029)
			(xy 149.072906 -205.756715) (xy 149.027058 -205.786177) (xy 148.977484 -205.808814) (xy 148.925193 -205.824167)
			(xy 148.871249 -205.831922) (xy 148.844 -205.832456) (xy 148.823973 -205.8322) (xy 148.784139 -205.828)
			(xy 148.764498 -205.824074) (xy 148.753322 -205.821788) (xy 148.73097 -205.827122) (xy 148.660612 -205.884018)
			(xy 148.652217 -205.891636) (xy 148.642463 -205.91207) (xy 148.641816 -205.923388) (xy 148.641816 -206.315056)
			(xy 148.64225 -206.325121) (xy 148.64998 -206.34371) (xy 148.656802 -206.351124) (xy 149.164548 -206.85887)
			(xy 149.171948 -206.865712) (xy 149.190546 -206.873434) (xy 149.200616 -206.873856) (xy 152.270206 -206.873856)
			(xy 152.280275 -206.87343) (xy 152.298873 -206.86571) (xy 152.306274 -206.85887) (xy 162.85083 -196.314314)
			(xy 162.85823 -196.307471) (xy 162.876828 -196.299745) (xy 162.886898 -196.299328) (xy 166.864792 -196.299328)
			(xy 166.87399 -196.298927) (xy 166.891205 -196.292439) (xy 166.905047 -196.28032) (xy 166.90975 -196.272404)
			(xy 166.958518 -196.180964) (xy 166.957248 -196.153278) (xy 166.949374 -196.14134) (xy 166.93315 -196.116226)
			(xy 166.906051 -196.062929) (xy 166.885395 -196.00682) (xy 166.871467 -195.948674) (xy 166.864461 -195.889295)
			(xy 166.86403 -195.8594) (xy 166.864565 -195.826241) (xy 166.873181 -195.760486) (xy 166.890269 -195.696408)
			(xy 166.915537 -195.635093) (xy 166.948558 -195.577582) (xy 166.988772 -195.524848) (xy 167.035496 -195.477786)
			(xy 167.061388 -195.457064) (xy 167.070255 -195.449481) (xy 167.080577 -195.428582) (xy 167.0812 -195.416932)
			(xy 167.0812 -195.336668) (xy 167.080619 -195.325008) (xy 167.070278 -195.304108) (xy 167.061388 -195.296536)
			(xy 167.035493 -195.275817) (xy 166.988768 -195.228755) (xy 166.948554 -195.176021) (xy 166.915533 -195.118509)
			(xy 166.890264 -195.057193) (xy 166.873177 -194.993115) (xy 166.86456 -194.927359) (xy 166.86403 -194.8942)
			(xy 166.864582 -194.860438) (xy 166.873523 -194.793508) (xy 166.891248 -194.728351) (xy 166.917444 -194.666114)
			(xy 166.95165 -194.607895) (xy 166.993264 -194.554717) (xy 167.041553 -194.507518) (xy 167.095666 -194.467128)
			(xy 167.124888 -194.450208) (xy 167.13581 -194.443858) (xy 167.149526 -194.422776) (xy 167.159178 -194.31381)
			(xy 167.149272 -194.290696) (xy 167.139366 -194.282568) (xy 167.118516 -194.264958) (xy 167.081736 -194.224638)
			(xy 167.051302 -194.179336) (xy 167.027881 -194.130042) (xy 167.011983 -194.077834) (xy 167.003956 -194.023852)
			(xy 167.003476 -193.996564) (xy 167.003992 -193.968964) (xy 167.012219 -193.914381) (xy 167.028489 -193.861634)
			(xy 167.052439 -193.811902) (xy 167.083534 -193.766294) (xy 167.121079 -193.72583) (xy 167.164236 -193.691413)
			(xy 167.21204 -193.663814) (xy 167.263424 -193.643647) (xy 167.317239 -193.631364) (xy 167.372284 -193.627239)
			(xy 167.427329 -193.631364) (xy 167.481144 -193.643647) (xy 167.532528 -193.663814) (xy 167.580332 -193.691413)
			(xy 167.623489 -193.72583) (xy 167.661034 -193.766294) (xy 167.692129 -193.811902) (xy 167.716079 -193.861634)
			(xy 167.732349 -193.914381) (xy 167.740576 -193.968964) (xy 167.741092 -193.996564) (xy 167.740596 -194.023849)
			(xy 167.73255 -194.077822) (xy 167.716642 -194.130021) (xy 167.69322 -194.179309) (xy 167.662795 -194.224609)
			(xy 167.626029 -194.264935) (xy 167.605202 -194.282568) (xy 167.595296 -194.290442) (xy 167.585644 -194.313556)
			(xy 167.595296 -194.422776) (xy 167.609012 -194.443858) (xy 167.619934 -194.449954) (xy 167.649184 -194.466875)
			(xy 167.703348 -194.507279) (xy 167.751686 -194.5545) (xy 167.793344 -194.607705) (xy 167.82759 -194.665959)
			(xy 167.853819 -194.728235) (xy 167.871572 -194.793436) (xy 167.880533 -194.860413) (xy 167.881046 -194.8942)
			(xy 167.880512 -194.927359) (xy 167.871896 -194.993116) (xy 167.85481 -195.057196) (xy 167.829544 -195.118513)
			(xy 167.796527 -195.176028) (xy 167.756317 -195.228766) (xy 167.709596 -195.275834) (xy 167.683688 -195.296536)
			(xy 167.674824 -195.304121) (xy 167.664507 -195.325019) (xy 167.663876 -195.336668) (xy 167.663876 -195.416932)
			(xy 167.664456 -195.428593) (xy 167.674794 -195.449497) (xy 167.683688 -195.457064) (xy 167.709584 -195.477782)
			(xy 167.756311 -195.524843) (xy 167.796527 -195.577577) (xy 167.82955 -195.635089) (xy 167.85482 -195.696405)
			(xy 167.871908 -195.760484) (xy 167.880525 -195.826241) (xy 167.881046 -195.8594) (xy 167.880615 -195.889295)
			(xy 167.873602 -195.948673) (xy 167.859673 -196.006818) (xy 167.839021 -196.062929) (xy 167.81193 -196.116229)
			(xy 167.795702 -196.14134) (xy 167.787828 -196.153278) (xy 167.786558 -196.180964) (xy 167.835326 -196.272404)
			(xy 167.839984 -196.28036) (xy 167.853817 -196.292524) (xy 167.871071 -196.298976) (xy 167.880284 -196.299328)
			(xy 168.181528 -196.299328) (xy 168.193943 -196.298705) (xy 168.215907 -196.287121) (xy 168.223438 -196.27723)
			(xy 168.239416 -196.25475) (xy 168.276958 -196.214349) (xy 168.320097 -196.179989) (xy 168.367872 -196.152437)
			(xy 168.419217 -196.132305) (xy 168.472987 -196.120044) (xy 168.527984 -196.115926) (xy 168.582981 -196.120044)
			(xy 168.636751 -196.132305) (xy 168.688096 -196.152437) (xy 168.735871 -196.179989) (xy 168.77901 -196.214349)
			(xy 168.816552 -196.25475) (xy 168.83253 -196.27723) (xy 168.840054 -196.287132) (xy 168.86202 -196.298731)
			(xy 168.87444 -196.299328) (xy 174.408846 -196.299328) (xy 174.418039 -196.298919) (xy 174.43524 -196.292418)
			(xy 174.449066 -196.280296) (xy 174.453804 -196.272404) (xy 174.502572 -196.180964) (xy 174.501302 -196.153278)
			(xy 174.493428 -196.14134) (xy 174.477202 -196.116227) (xy 174.4501 -196.062931) (xy 174.429442 -196.006821)
			(xy 174.415513 -195.948675) (xy 174.408506 -195.889296) (xy 174.408084 -195.8594) (xy 174.408618 -195.826241)
			(xy 174.417235 -195.760485) (xy 174.434321 -195.696406) (xy 174.459588 -195.635089) (xy 174.492607 -195.577576)
			(xy 174.532818 -195.524839) (xy 174.579541 -195.477774) (xy 174.605442 -195.457064) (xy 174.614315 -195.449484)
			(xy 174.624647 -195.428585) (xy 174.625254 -195.416932) (xy 174.625254 -195.336668) (xy 174.624675 -195.325006)
			(xy 174.614341 -195.304098) (xy 174.605442 -195.296536) (xy 174.579545 -195.275819) (xy 174.532815 -195.228759)
			(xy 174.492597 -195.176026) (xy 174.459572 -195.118513) (xy 174.4343 -195.057197) (xy 174.417211 -194.993117)
			(xy 174.408593 -194.92736) (xy 174.408084 -194.8942) (xy 174.408636 -194.860437) (xy 174.417577 -194.793506)
			(xy 174.4353 -194.728347) (xy 174.461495 -194.666109) (xy 174.495699 -194.607887) (xy 174.537311 -194.554707)
			(xy 174.585598 -194.507504) (xy 174.639709 -194.46711) (xy 174.668942 -194.450208) (xy 174.679864 -194.443858)
			(xy 174.69358 -194.422776) (xy 174.703232 -194.31381) (xy 174.693326 -194.290696) (xy 174.68342 -194.282568)
			(xy 174.662572 -194.264956) (xy 174.625796 -194.224635) (xy 174.595367 -194.179332) (xy 174.571948 -194.130039)
			(xy 174.556053 -194.077831) (xy 174.548027 -194.023851) (xy 174.54753 -193.996564) (xy 174.548046 -193.968964)
			(xy 174.556273 -193.914381) (xy 174.572543 -193.861634) (xy 174.596493 -193.811902) (xy 174.627588 -193.766294)
			(xy 174.665133 -193.72583) (xy 174.70829 -193.691413) (xy 174.756094 -193.663814) (xy 174.807478 -193.643647)
			(xy 174.861293 -193.631364) (xy 174.916338 -193.627239) (xy 174.971383 -193.631364) (xy 175.025198 -193.643647)
			(xy 175.076582 -193.663814) (xy 175.124386 -193.691413) (xy 175.167543 -193.72583) (xy 175.205088 -193.766294)
			(xy 175.236183 -193.811902) (xy 175.260133 -193.861634) (xy 175.276403 -193.914381) (xy 175.28463 -193.968964)
			(xy 175.285146 -193.996564) (xy 175.28465 -194.023849) (xy 175.276605 -194.077823) (xy 175.260699 -194.130024)
			(xy 175.237279 -194.179314) (xy 175.206857 -194.224618) (xy 175.170094 -194.264947) (xy 175.149256 -194.282568)
			(xy 175.13935 -194.290442) (xy 175.129698 -194.313556) (xy 175.13935 -194.422776) (xy 175.153066 -194.443858)
			(xy 175.163988 -194.449954) (xy 175.193235 -194.466877) (xy 175.247395 -194.507284) (xy 175.295727 -194.554506)
			(xy 175.337381 -194.607713) (xy 175.371622 -194.665966) (xy 175.397849 -194.72824) (xy 175.415599 -194.793439)
			(xy 175.42456 -194.860414) (xy 175.4251 -194.8942) (xy 175.424566 -194.927359) (xy 175.415949 -194.993115)
			(xy 175.398862 -195.057193) (xy 175.373595 -195.118509) (xy 175.340575 -195.176022) (xy 175.300363 -195.228758)
			(xy 175.25364 -195.275822) (xy 175.227742 -195.296536) (xy 175.218871 -195.304117) (xy 175.208543 -195.325016)
			(xy 175.20793 -195.336668) (xy 175.20793 -195.416932) (xy 175.208509 -195.428595) (xy 175.218841 -195.449505)
			(xy 175.227742 -195.457064) (xy 175.25364 -195.477781) (xy 175.300371 -195.52484) (xy 175.34059 -195.577573)
			(xy 175.373616 -195.635085) (xy 175.398889 -195.696402) (xy 175.415979 -195.760482) (xy 175.424597 -195.82624)
			(xy 175.4251 -195.8594) (xy 175.424669 -195.889295) (xy 175.417657 -195.948674) (xy 175.403729 -196.00682)
			(xy 175.383079 -196.062931) (xy 175.355991 -196.116233) (xy 175.339756 -196.14134) (xy 175.331882 -196.153278)
			(xy 175.330612 -196.180964) (xy 175.37938 -196.272404) (xy 175.384036 -196.280365) (xy 175.397867 -196.292542)
			(xy 175.415123 -196.299009) (xy 175.424338 -196.299328) (xy 175.725582 -196.299328) (xy 175.738003 -196.298715)
			(xy 175.759984 -196.287142) (xy 175.767492 -196.27723) (xy 175.78347 -196.25475) (xy 175.821012 -196.214349)
			(xy 175.864151 -196.179989) (xy 175.911926 -196.152437) (xy 175.963271 -196.132305) (xy 176.017041 -196.120044)
			(xy 176.072038 -196.115926) (xy 176.127035 -196.120044) (xy 176.180805 -196.132305) (xy 176.23215 -196.152437)
			(xy 176.279925 -196.179989) (xy 176.323064 -196.214349) (xy 176.360606 -196.25475) (xy 176.376584 -196.27723)
			(xy 176.384111 -196.287123) (xy 176.406079 -196.2987) (xy 176.418494 -196.299328) (xy 181.9529 -196.299328)
			(xy 181.962097 -196.298926) (xy 181.97931 -196.292436) (xy 181.99315 -196.280316) (xy 181.997858 -196.272404)
			(xy 182.046626 -196.180964) (xy 182.045356 -196.153278) (xy 182.037482 -196.14134) (xy 182.021258 -196.116226)
			(xy 181.994158 -196.06293) (xy 181.973502 -196.00682) (xy 181.959574 -195.948674) (xy 181.952567 -195.889295)
			(xy 181.952138 -195.8594) (xy 181.952673 -195.826241) (xy 181.961289 -195.760486) (xy 181.978377 -195.696409)
			(xy 182.003646 -195.635094) (xy 182.036667 -195.577583) (xy 182.076881 -195.524849) (xy 182.123606 -195.477788)
			(xy 182.149496 -195.457064) (xy 182.158362 -195.44948) (xy 182.168682 -195.428582) (xy 182.169308 -195.416932)
			(xy 182.169308 -195.336668) (xy 182.168728 -195.325007) (xy 182.158387 -195.304106) (xy 182.149496 -195.296536)
			(xy 182.123601 -195.275817) (xy 182.076875 -195.228756) (xy 182.036661 -195.176022) (xy 182.003639 -195.118509)
			(xy 181.97837 -195.057194) (xy 181.961282 -194.993115) (xy 181.952665 -194.927359) (xy 181.952138 -194.8942)
			(xy 181.95269 -194.860438) (xy 181.961631 -194.793508) (xy 181.979356 -194.728351) (xy 182.005552 -194.666115)
			(xy 182.039759 -194.607896) (xy 182.081373 -194.554719) (xy 182.129662 -194.50752) (xy 182.183776 -194.467131)
			(xy 182.212996 -194.450208) (xy 182.223918 -194.443858) (xy 182.237634 -194.422776) (xy 182.247286 -194.31381)
			(xy 182.23738 -194.290696) (xy 182.227474 -194.282568) (xy 182.206623 -194.264958) (xy 182.169843 -194.224638)
			(xy 182.139408 -194.179337) (xy 182.115986 -194.130043) (xy 182.100088 -194.077834) (xy 182.092061 -194.023852)
			(xy 182.091584 -193.996564) (xy 182.0921 -193.968964) (xy 182.100327 -193.914381) (xy 182.116597 -193.861634)
			(xy 182.140547 -193.811902) (xy 182.171642 -193.766294) (xy 182.209187 -193.72583) (xy 182.252344 -193.691413)
			(xy 182.300148 -193.663814) (xy 182.351532 -193.643647) (xy 182.405347 -193.631364) (xy 182.460392 -193.627239)
			(xy 182.515437 -193.631364) (xy 182.569252 -193.643647) (xy 182.620636 -193.663814) (xy 182.66844 -193.691413)
			(xy 182.711597 -193.72583) (xy 182.749142 -193.766294) (xy 182.780237 -193.811902) (xy 182.804187 -193.861634)
			(xy 182.820457 -193.914381) (xy 182.828684 -193.968964) (xy 182.8292 -193.996564) (xy 182.828704 -194.023849)
			(xy 182.820658 -194.077822) (xy 182.804751 -194.130022) (xy 182.781329 -194.179309) (xy 182.750904 -194.22461)
			(xy 182.714139 -194.264936) (xy 182.69331 -194.282568) (xy 182.683404 -194.290442) (xy 182.673752 -194.313556)
			(xy 182.683404 -194.422776) (xy 182.69712 -194.443858) (xy 182.708042 -194.449954) (xy 182.737291 -194.466875)
			(xy 182.791455 -194.50728) (xy 182.839792 -194.554501) (xy 182.881449 -194.607706) (xy 182.915694 -194.66596)
			(xy 182.941924 -194.728236) (xy 182.959676 -194.793436) (xy 182.968637 -194.860413) (xy 182.969154 -194.8942)
			(xy 182.968619 -194.927359) (xy 182.960002 -194.993113) (xy 182.942915 -195.057191) (xy 182.917646 -195.118505)
			(xy 182.884624 -195.176016) (xy 182.84441 -195.228749) (xy 182.797684 -195.27581) (xy 182.771796 -195.296536)
			(xy 182.762931 -195.30412) (xy 182.752612 -195.325018) (xy 182.751984 -195.336668) (xy 182.751984 -195.416932)
			(xy 182.752564 -195.428593) (xy 182.762903 -195.449496) (xy 182.771796 -195.457064) (xy 182.797691 -195.477782)
			(xy 182.844418 -195.524844) (xy 182.884633 -195.577578) (xy 182.917655 -195.63509) (xy 182.942925 -195.696405)
			(xy 182.960013 -195.760485) (xy 182.96863 -195.826241) (xy 182.969154 -195.8594) (xy 182.968723 -195.889295)
			(xy 182.96171 -195.948673) (xy 182.947782 -196.006818) (xy 182.92713 -196.062929) (xy 182.900039 -196.11623)
			(xy 182.88381 -196.14134) (xy 182.875936 -196.153278) (xy 182.874666 -196.180964) (xy 182.923434 -196.272404)
			(xy 182.928092 -196.280359) (xy 182.941926 -196.292521) (xy 182.95918 -196.29897) (xy 182.968392 -196.299328)
			(xy 183.269636 -196.299328) (xy 183.282051 -196.298704) (xy 183.304011 -196.287117) (xy 183.311546 -196.27723)
			(xy 183.327524 -196.25475) (xy 183.365066 -196.214349) (xy 183.408205 -196.179989) (xy 183.45598 -196.152437)
			(xy 183.507325 -196.132305) (xy 183.561095 -196.120044) (xy 183.616092 -196.115926) (xy 183.671089 -196.120044)
			(xy 183.724859 -196.132305) (xy 183.776204 -196.152437) (xy 183.823979 -196.179989) (xy 183.867118 -196.214349)
			(xy 183.90466 -196.25475) (xy 183.920638 -196.27723) (xy 183.928162 -196.28713) (xy 183.950129 -196.298727)
			(xy 183.962548 -196.299328) (xy 189.4967 -196.299328) (xy 189.505897 -196.298926) (xy 189.52311 -196.292436)
			(xy 189.53695 -196.280316) (xy 189.541658 -196.272404) (xy 189.590426 -196.180964) (xy 189.589156 -196.153278)
			(xy 189.581282 -196.14134) (xy 189.565058 -196.116226) (xy 189.537958 -196.06293) (xy 189.517302 -196.00682)
			(xy 189.503374 -195.948674) (xy 189.496367 -195.889295) (xy 189.495938 -195.8594) (xy 189.496473 -195.826241)
			(xy 189.505089 -195.760486) (xy 189.522177 -195.696409) (xy 189.547446 -195.635094) (xy 189.580467 -195.577583)
			(xy 189.620681 -195.524849) (xy 189.667406 -195.477788) (xy 189.693296 -195.457064) (xy 189.702162 -195.44948)
			(xy 189.712482 -195.428582) (xy 189.713108 -195.416932) (xy 189.713108 -195.336668) (xy 189.712528 -195.325007)
			(xy 189.702187 -195.304106) (xy 189.693296 -195.296536) (xy 189.667401 -195.275817) (xy 189.620675 -195.228756)
			(xy 189.580461 -195.176022) (xy 189.547439 -195.118509) (xy 189.52217 -195.057194) (xy 189.505082 -194.993115)
			(xy 189.496465 -194.927359) (xy 189.495938 -194.8942) (xy 189.49649 -194.860425) (xy 189.505431 -194.79347)
			(xy 189.523155 -194.728288) (xy 189.549351 -194.666024) (xy 189.583557 -194.607776) (xy 189.625171 -194.554568)
			(xy 189.673463 -194.507335) (xy 189.727581 -194.46691) (xy 189.756796 -194.449954) (xy 189.767972 -194.443858)
			(xy 189.781688 -194.422776) (xy 189.791086 -194.31381) (xy 189.781434 -194.290442) (xy 189.771528 -194.282568)
			(xy 189.75068 -194.264956) (xy 189.713903 -194.224635) (xy 189.683473 -194.179333) (xy 189.660054 -194.130039)
			(xy 189.644158 -194.077832) (xy 189.636132 -194.023851) (xy 189.635638 -193.996564) (xy 189.636154 -193.968964)
			(xy 189.644381 -193.914381) (xy 189.660651 -193.861634) (xy 189.684601 -193.811902) (xy 189.715696 -193.766294)
			(xy 189.753241 -193.72583) (xy 189.796398 -193.691413) (xy 189.844202 -193.663814) (xy 189.895586 -193.643647)
			(xy 189.949401 -193.631364) (xy 190.004446 -193.627239) (xy 190.059491 -193.631364) (xy 190.113306 -193.643647)
			(xy 190.16469 -193.663814) (xy 190.212494 -193.691413) (xy 190.255651 -193.72583) (xy 190.293196 -193.766294)
			(xy 190.324291 -193.811902) (xy 190.348241 -193.861634) (xy 190.364511 -193.914381) (xy 190.372738 -193.968964)
			(xy 190.373254 -193.996564) (xy 190.372758 -194.023849) (xy 190.364713 -194.077824) (xy 190.348807 -194.130025)
			(xy 190.325388 -194.179315) (xy 190.294966 -194.224619) (xy 190.258204 -194.264949) (xy 190.237364 -194.282568)
			(xy 190.227458 -194.290442) (xy 190.217806 -194.31381) (xy 190.227204 -194.422776) (xy 190.24092 -194.443858)
			(xy 190.252096 -194.449954) (xy 190.28132 -194.466895) (xy 190.33543 -194.50733) (xy 190.383715 -194.554568)
			(xy 190.425326 -194.60778) (xy 190.459531 -194.666029) (xy 190.485729 -194.728291) (xy 190.503459 -194.793472)
			(xy 190.512409 -194.860425) (xy 190.512954 -194.8942) (xy 190.512419 -194.927359) (xy 190.503802 -194.993113)
			(xy 190.486715 -195.057191) (xy 190.461446 -195.118505) (xy 190.428424 -195.176016) (xy 190.38821 -195.228749)
			(xy 190.341484 -195.27581) (xy 190.315596 -195.296536) (xy 190.306731 -195.30412) (xy 190.296412 -195.325018)
			(xy 190.295784 -195.336668) (xy 190.295784 -195.416932) (xy 190.296364 -195.428593) (xy 190.306703 -195.449496)
			(xy 190.315596 -195.457064) (xy 190.341491 -195.477782) (xy 190.388218 -195.524844) (xy 190.428433 -195.577578)
			(xy 190.461455 -195.63509) (xy 190.486725 -195.696405) (xy 190.503813 -195.760485) (xy 190.51243 -195.826241)
			(xy 190.512954 -195.8594) (xy 190.512523 -195.889295) (xy 190.50551 -195.948673) (xy 190.491582 -196.006818)
			(xy 190.47093 -196.062929) (xy 190.443839 -196.11623) (xy 190.42761 -196.14134) (xy 190.419736 -196.153278)
			(xy 190.418466 -196.180964) (xy 190.467234 -196.272404) (xy 190.471892 -196.280359) (xy 190.485726 -196.292521)
			(xy 190.50298 -196.29897) (xy 190.512192 -196.299328) (xy 190.81369 -196.299328) (xy 190.82611 -196.298714)
			(xy 190.848088 -196.287138) (xy 190.8556 -196.27723) (xy 190.871578 -196.25475) (xy 190.90912 -196.214349)
			(xy 190.952259 -196.179989) (xy 191.000034 -196.152437) (xy 191.051379 -196.132305) (xy 191.105149 -196.120044)
			(xy 191.160146 -196.115926) (xy 191.215143 -196.120044) (xy 191.268913 -196.132305) (xy 191.320258 -196.152437)
			(xy 191.368033 -196.179989) (xy 191.411172 -196.214349) (xy 191.448714 -196.25475) (xy 191.464692 -196.27723)
			(xy 191.47222 -196.287121) (xy 191.494187 -196.298694) (xy 191.506602 -196.299328) (xy 197.040754 -196.299328)
			(xy 197.049956 -196.298934) (xy 197.067181 -196.292453) (xy 197.081034 -196.280336) (xy 197.085712 -196.272404)
			(xy 197.13448 -196.180964) (xy 197.13321 -196.153278) (xy 197.125336 -196.14134) (xy 197.10911 -196.116227)
			(xy 197.082008 -196.062931) (xy 197.061349 -196.006822) (xy 197.04742 -195.948675) (xy 197.040412 -195.889296)
			(xy 197.039992 -195.8594) (xy 197.040526 -195.826241) (xy 197.049143 -195.760485) (xy 197.066229 -195.696406)
			(xy 197.091496 -195.63509) (xy 197.124516 -195.577577) (xy 197.164728 -195.524841) (xy 197.21145 -195.477776)
			(xy 197.23735 -195.457064) (xy 197.246222 -195.449484) (xy 197.256552 -195.428585) (xy 197.257162 -195.416932)
			(xy 197.257162 -195.336668) (xy 197.256583 -195.325006) (xy 197.24625 -195.304096) (xy 197.23735 -195.296536)
			(xy 197.211453 -195.275819) (xy 197.164722 -195.228759) (xy 197.124503 -195.176026) (xy 197.091478 -195.118514)
			(xy 197.066206 -195.057198) (xy 197.049116 -194.993118) (xy 197.040498 -194.92736) (xy 197.039992 -194.8942)
			(xy 197.040463 -194.862956) (xy 197.048111 -194.800938) (xy 197.063304 -194.740325) (xy 197.085812 -194.682031)
			(xy 197.115296 -194.626937) (xy 197.151312 -194.575872) (xy 197.193316 -194.529607) (xy 197.240675 -194.488841)
			(xy 197.292673 -194.454187) (xy 197.320408 -194.439794) (xy 197.331838 -194.433952) (xy 197.346316 -194.413378)
			(xy 197.36054 -194.304666) (xy 197.35165 -194.281298) (xy 197.342252 -194.272916) (xy 197.323049 -194.255324)
			(xy 197.28929 -194.215669) (xy 197.26144 -194.171664) (xy 197.240051 -194.124181) (xy 197.225548 -194.074163)
			(xy 197.218219 -194.022603) (xy 197.217792 -193.996564) (xy 197.218308 -193.968964) (xy 197.226535 -193.914381)
			(xy 197.242805 -193.861634) (xy 197.266755 -193.811902) (xy 197.29785 -193.766294) (xy 197.335395 -193.72583)
			(xy 197.378552 -193.691413) (xy 197.426356 -193.663814) (xy 197.47774 -193.643647) (xy 197.531555 -193.631364)
			(xy 197.5866 -193.627239) (xy 197.641645 -193.631364) (xy 197.69546 -193.643647) (xy 197.746844 -193.663814)
			(xy 197.794648 -193.691413) (xy 197.837805 -193.72583) (xy 197.87535 -193.766294) (xy 197.906445 -193.811902)
			(xy 197.930395 -193.861634) (xy 197.946665 -193.914381) (xy 197.954892 -193.968964) (xy 197.955408 -193.996564)
			(xy 197.954868 -194.025209) (xy 197.94601 -194.081811) (xy 197.928501 -194.13636) (xy 197.902763 -194.187544)
			(xy 197.869416 -194.23413) (xy 197.829264 -194.274995) (xy 197.806564 -194.292474) (xy 197.796404 -194.300094)
			(xy 197.785736 -194.3227) (xy 197.790562 -194.432428) (xy 197.803262 -194.454018) (xy 197.814184 -194.460622)
			(xy 197.841595 -194.47802) (xy 197.892184 -194.518711) (xy 197.937182 -194.56551) (xy 197.975857 -194.617657)
			(xy 198.007581 -194.674302) (xy 198.031836 -194.734524) (xy 198.048229 -194.797343) (xy 198.056493 -194.861738)
			(xy 198.057008 -194.8942) (xy 198.056474 -194.927359) (xy 198.047857 -194.993115) (xy 198.030771 -195.057194)
			(xy 198.005504 -195.11851) (xy 197.972484 -195.176023) (xy 197.932272 -195.228759) (xy 197.88555 -195.275824)
			(xy 197.85965 -195.296536) (xy 197.850778 -195.304116) (xy 197.840448 -195.325015) (xy 197.839838 -195.336668)
			(xy 197.839838 -195.416932) (xy 197.840417 -195.428594) (xy 197.85075 -195.449504) (xy 197.85965 -195.457064)
			(xy 197.885547 -195.477781) (xy 197.932278 -195.524841) (xy 197.972497 -195.577574) (xy 198.005522 -195.635086)
			(xy 198.030794 -195.696402) (xy 198.047884 -195.760482) (xy 198.056502 -195.82624) (xy 198.057008 -195.8594)
			(xy 198.056577 -195.889295) (xy 198.049565 -195.948674) (xy 198.035638 -196.00682) (xy 198.014988 -196.062931)
			(xy 197.9879 -196.116234) (xy 197.971664 -196.14134) (xy 197.96379 -196.153278) (xy 197.96252 -196.180964)
			(xy 198.011288 -196.272404) (xy 198.015944 -196.280364) (xy 198.029776 -196.292539) (xy 198.047031 -196.299003)
			(xy 198.056246 -196.299328) (xy 198.357744 -196.299328) (xy 198.370158 -196.298702) (xy 198.392115 -196.287114)
			(xy 198.399654 -196.27723) (xy 198.415632 -196.25475) (xy 198.453174 -196.214349) (xy 198.496313 -196.179989)
			(xy 198.544088 -196.152437) (xy 198.595433 -196.132305) (xy 198.649203 -196.120044) (xy 198.7042 -196.115926)
			(xy 198.759197 -196.120044) (xy 198.812967 -196.132305) (xy 198.864312 -196.152437) (xy 198.912087 -196.179989)
			(xy 198.955226 -196.214349) (xy 198.992768 -196.25475) (xy 199.008746 -196.27723) (xy 199.016271 -196.287129)
			(xy 199.038237 -196.298722) (xy 199.050656 -196.299328) (xy 204.52842 -196.299328) (xy 204.537908 -196.298927)
			(xy 204.555587 -196.292029) (xy 204.569579 -196.27921) (xy 204.57414 -196.27088) (xy 204.620622 -196.17563)
			(xy 204.617828 -196.146928) (xy 204.608684 -196.135498) (xy 204.588494 -196.108613) (xy 204.554614 -196.050539)
			(xy 204.528679 -195.988508) (xy 204.511142 -195.923601) (xy 204.502307 -195.856949) (xy 204.50175 -195.823332)
			(xy 204.502203 -195.792845) (xy 204.509499 -195.732308) (xy 204.523979 -195.673077) (xy 204.545435 -195.616001)
			(xy 204.573559 -195.5619) (xy 204.607948 -195.511548) (xy 204.648109 -195.465667) (xy 204.693467 -195.424916)
			(xy 204.718158 -195.407026) (xy 204.727556 -195.400422) (xy 204.738478 -195.381372) (xy 204.747368 -195.281296)
			(xy 204.740002 -195.260468) (xy 204.731874 -195.25234) (xy 204.708873 -195.22845) (xy 204.668626 -195.175742)
			(xy 204.635579 -195.118245) (xy 204.610294 -195.056937) (xy 204.593202 -194.992861) (xy 204.584593 -194.927105)
			(xy 204.584046 -194.893946) (xy 204.584595 -194.86017) (xy 204.593531 -194.793211) (xy 204.611251 -194.728025)
			(xy 204.637443 -194.665757) (xy 204.671647 -194.607504) (xy 204.713261 -194.554292) (xy 204.761552 -194.507055)
			(xy 204.81567 -194.466627) (xy 204.844904 -194.4497) (xy 204.85608 -194.443604) (xy 204.869796 -194.422522)
			(xy 204.879194 -194.313556) (xy 204.869542 -194.290188) (xy 204.859636 -194.282314) (xy 204.838785 -194.264704)
			(xy 204.802003 -194.224384) (xy 204.771566 -194.179083) (xy 204.74814 -194.129789) (xy 204.732237 -194.077581)
			(xy 204.724205 -194.023598) (xy 204.723746 -193.99631) (xy 204.724262 -193.96871) (xy 204.732489 -193.914127)
			(xy 204.748759 -193.86138) (xy 204.772709 -193.811648) (xy 204.803804 -193.76604) (xy 204.841349 -193.725576)
			(xy 204.884506 -193.691159) (xy 204.93231 -193.66356) (xy 204.983694 -193.643393) (xy 205.037509 -193.63111)
			(xy 205.092554 -193.626985) (xy 205.147599 -193.63111) (xy 205.201414 -193.643393) (xy 205.252798 -193.66356)
			(xy 205.300602 -193.691159) (xy 205.343759 -193.725576) (xy 205.381304 -193.76604) (xy 205.412399 -193.811648)
			(xy 205.436349 -193.86138) (xy 205.452619 -193.914127) (xy 205.460846 -193.96871) (xy 205.461362 -193.99631)
			(xy 205.46087 -194.023597) (xy 205.452832 -194.077576) (xy 205.436932 -194.129783) (xy 205.413518 -194.179079)
			(xy 205.383099 -194.224389) (xy 205.34634 -194.264727) (xy 205.325472 -194.282314) (xy 205.315566 -194.290188)
			(xy 205.305914 -194.313556) (xy 205.315312 -194.422522) (xy 205.329028 -194.443604) (xy 205.340204 -194.4497)
			(xy 205.369425 -194.466642) (xy 205.423531 -194.507079) (xy 205.471811 -194.554318) (xy 205.513417 -194.60753)
			(xy 205.547616 -194.665779) (xy 205.573808 -194.728041) (xy 205.58936 -194.785234) (xy 206.895192 -194.785234)
			(xy 206.895725 -194.752316) (xy 206.904228 -194.68703) (xy 206.921086 -194.623388) (xy 206.946014 -194.562453)
			(xy 206.978597 -194.505245) (xy 207.018289 -194.452719) (xy 207.040988 -194.428872) (xy 207.0481 -194.421506)
			(xy 207.055466 -194.403218) (xy 207.055212 -194.31127) (xy 207.047592 -194.292982) (xy 207.040226 -194.28587)
			(xy 207.017693 -194.262515) (xy 206.978217 -194.211006) (xy 206.945794 -194.15479) (xy 206.920978 -194.094827)
			(xy 206.904193 -194.032139) (xy 206.895724 -193.967798) (xy 206.895192 -193.93535) (xy 206.895681 -193.904187)
			(xy 206.903493 -193.842353) (xy 206.918993 -193.781985) (xy 206.941936 -193.724037) (xy 206.971962 -193.66942)
			(xy 207.008596 -193.618998) (xy 207.051261 -193.573564) (xy 207.099283 -193.533836) (xy 207.151907 -193.500441)
			(xy 207.208301 -193.473904) (xy 207.267576 -193.454644) (xy 207.328797 -193.442965) (xy 207.391 -193.439052)
			(xy 207.453203 -193.442965) (xy 207.514424 -193.454644) (xy 207.573699 -193.473904) (xy 207.630093 -193.500441)
			(xy 207.682717 -193.533836) (xy 207.730739 -193.573564) (xy 207.773404 -193.618998) (xy 207.810038 -193.66942)
			(xy 207.840064 -193.724037) (xy 207.863007 -193.781985) (xy 207.878507 -193.842353) (xy 207.886319 -193.904187)
			(xy 207.886808 -193.93535) (xy 207.886359 -193.96657) (xy 207.87852 -194.028515) (xy 207.862959 -194.088984)
			(xy 207.839924 -194.147019) (xy 207.809779 -194.201699) (xy 207.773002 -194.252158) (xy 207.751934 -194.275202)
			(xy 207.745076 -194.282568) (xy 207.737964 -194.30111) (xy 207.74025 -194.393058) (xy 207.748378 -194.411092)
			(xy 207.755744 -194.418204) (xy 207.780036 -194.442257) (xy 207.822572 -194.495774) (xy 207.857559 -194.554506)
			(xy 207.884364 -194.617394) (xy 207.902506 -194.683305) (xy 207.911656 -194.751053) (xy 207.912208 -194.785234)
			(xy 207.911662 -194.818781) (xy 207.902824 -194.885292) (xy 207.885319 -194.950063) (xy 207.859452 -195.011971)
			(xy 207.825671 -195.069941) (xy 207.784562 -195.122967) (xy 207.761078 -195.14693) (xy 207.753712 -195.154296)
			(xy 207.746092 -195.17233) (xy 207.745076 -195.264278) (xy 207.752442 -195.28282) (xy 207.759554 -195.290186)
			(xy 207.781383 -195.313361) (xy 207.8195 -195.364357) (xy 207.850775 -195.419813) (xy 207.874694 -195.478816)
			(xy 207.890863 -195.540396) (xy 207.899016 -195.603539) (xy 207.899508 -195.635372) (xy 207.899019 -195.666535)
			(xy 207.891207 -195.728369) (xy 207.875707 -195.788737) (xy 207.852764 -195.846685) (xy 207.822738 -195.901302)
			(xy 207.786104 -195.951724) (xy 207.743439 -195.997158) (xy 207.695417 -196.036886) (xy 207.642793 -196.070281)
			(xy 207.586399 -196.096818) (xy 207.527124 -196.116078) (xy 207.465903 -196.127757) (xy 207.4037 -196.13167)
			(xy 207.341497 -196.127757) (xy 207.280276 -196.116078) (xy 207.221001 -196.096818) (xy 207.164607 -196.070281)
			(xy 207.111983 -196.036886) (xy 207.063961 -195.997158) (xy 207.021296 -195.951724) (xy 206.984662 -195.901302)
			(xy 206.954636 -195.846685) (xy 206.931693 -195.788737) (xy 206.916193 -195.728369) (xy 206.908381 -195.666535)
			(xy 206.907892 -195.635372) (xy 206.908356 -195.603537) (xy 206.916504 -195.540391) (xy 206.932674 -195.478809)
			(xy 206.9566 -195.419806) (xy 206.987888 -195.364355) (xy 207.026023 -195.313369) (xy 207.047846 -195.290186)
			(xy 207.054958 -195.28282) (xy 207.062324 -195.264278) (xy 207.061308 -195.17233) (xy 207.053688 -195.154296)
			(xy 207.046322 -195.14693) (xy 207.022813 -195.122989) (xy 206.981693 -195.069966) (xy 206.947906 -195.011993)
			(xy 206.92204 -194.95008) (xy 206.904546 -194.885301) (xy 206.895726 -194.818784) (xy 206.895192 -194.785234)
			(xy 205.58936 -194.785234) (xy 205.591532 -194.793221) (xy 205.600476 -194.860173) (xy 205.601062 -194.893946)
			(xy 205.600611 -194.924434) (xy 205.593317 -194.984973) (xy 205.578839 -195.044206) (xy 205.557385 -195.101283)
			(xy 205.529263 -195.155387) (xy 205.494875 -195.205742) (xy 205.454715 -195.251626) (xy 205.409358 -195.29238)
			(xy 205.384654 -195.310252) (xy 205.375256 -195.316856) (xy 205.364334 -195.335906) (xy 205.355444 -195.435982)
			(xy 205.36281 -195.45681) (xy 205.370938 -195.464938) (xy 205.39394 -195.488828) (xy 205.434188 -195.541536)
			(xy 205.467237 -195.599032) (xy 205.492523 -195.66034) (xy 205.509618 -195.724417) (xy 205.51823 -195.790173)
			(xy 205.518766 -195.823332) (xy 205.518241 -195.856951) (xy 205.509411 -195.923606) (xy 205.491869 -195.988516)
			(xy 205.465922 -196.050545) (xy 205.432023 -196.108612) (xy 205.411832 -196.135498) (xy 205.402688 -196.146928)
			(xy 205.399894 -196.17563) (xy 205.446376 -196.27088) (xy 205.450892 -196.279248) (xy 205.464877 -196.292112)
			(xy 205.482594 -196.298982) (xy 205.492096 -196.299328) (xy 205.901544 -196.299328) (xy 205.913958 -196.298702)
			(xy 205.935915 -196.287114) (xy 205.943454 -196.27723) (xy 205.959432 -196.25475) (xy 205.996974 -196.214349)
			(xy 206.040113 -196.179989) (xy 206.087888 -196.152437) (xy 206.139233 -196.132305) (xy 206.193003 -196.120044)
			(xy 206.248 -196.115926) (xy 206.302997 -196.120044) (xy 206.356767 -196.132305) (xy 206.408112 -196.152437)
			(xy 206.455887 -196.179989) (xy 206.499026 -196.214349) (xy 206.536568 -196.25475) (xy 206.552546 -196.27723)
			(xy 206.560071 -196.287129) (xy 206.582037 -196.298722) (xy 206.594456 -196.299328) (xy 207.042766 -196.299328)
			(xy 207.05283 -196.299764) (xy 207.071415 -196.307498) (xy 207.078834 -196.314314) (xy 207.443324 -196.678804)
			(xy 207.450178 -196.686199) (xy 207.457923 -196.704798) (xy 207.45831 -196.714872) (xy 207.45831 -205.113847)
			(xy 208.420964 -205.113847) (xy 208.420964 -205.049925) (xy 208.428975 -204.986507) (xy 208.444872 -204.924593)
			(xy 208.468404 -204.86516) (xy 208.499198 -204.809145) (xy 208.536771 -204.75743) (xy 208.580528 -204.710833)
			(xy 208.629781 -204.670088) (xy 208.683752 -204.635837) (xy 208.741591 -204.60862) (xy 208.802384 -204.588867)
			(xy 208.865174 -204.576889) (xy 208.92897 -204.572876) (xy 208.992766 -204.576889) (xy 209.055556 -204.588867)
			(xy 209.116349 -204.60862) (xy 209.174188 -204.635837) (xy 209.228159 -204.670088) (xy 209.277412 -204.710833)
			(xy 209.321169 -204.75743) (xy 209.358742 -204.809145) (xy 209.389536 -204.86516) (xy 209.413068 -204.924593)
			(xy 209.428965 -204.986507) (xy 209.436976 -205.049925) (xy 209.437478 -205.081886) (xy 209.436976 -205.113847)
			(xy 209.428965 -205.177265) (xy 209.413068 -205.239179) (xy 209.389536 -205.298612) (xy 209.358742 -205.354627)
			(xy 209.321169 -205.406342) (xy 209.277412 -205.452939) (xy 209.228159 -205.493684) (xy 209.174188 -205.527935)
			(xy 209.116349 -205.555152) (xy 209.055556 -205.574905) (xy 208.992766 -205.586883) (xy 208.92897 -205.590897)
			(xy 208.865174 -205.586883) (xy 208.802384 -205.574905) (xy 208.741591 -205.555152) (xy 208.683752 -205.527935)
			(xy 208.629781 -205.493684) (xy 208.580528 -205.452939) (xy 208.536771 -205.406342) (xy 208.499198 -205.354627)
			(xy 208.468404 -205.298612) (xy 208.444872 -205.239179) (xy 208.428975 -205.177265) (xy 208.420964 -205.113847)
			(xy 207.45831 -205.113847) (xy 207.45831 -210.132422) (xy 207.476344 -210.15833) (xy 207.491838 -210.163918)
			(xy 207.516586 -210.173424) (xy 207.563284 -210.198517) (xy 207.605907 -210.23004) (xy 207.643578 -210.26734)
			(xy 207.675519 -210.309651) (xy 207.701071 -210.356099) (xy 207.719709 -210.405728) (xy 207.731049 -210.457515)
			(xy 207.734856 -210.510391) (xy 207.731051 -210.563268) (xy 207.719714 -210.615055) (xy 207.701079 -210.664684)
			(xy 207.675528 -210.711134) (xy 207.64359 -210.753446) (xy 207.605921 -210.790749) (xy 207.563299 -210.822273)
			(xy 207.516602 -210.847369) (xy 207.491838 -210.85683) (xy 207.476344 -210.862418) (xy 207.45831 -210.888326)
			(xy 207.45831 -219.338398) (xy 207.458733 -219.348468) (xy 207.466448 -219.367072) (xy 207.473296 -219.374466)
			(xy 212.128057 -224.029227) (xy 233.399832 -224.029227) (xy 233.399832 -223.965305) (xy 233.407843 -223.901887)
			(xy 233.42374 -223.839973) (xy 233.447272 -223.78054) (xy 233.478066 -223.724525) (xy 233.515639 -223.67281)
			(xy 233.559396 -223.626213) (xy 233.608649 -223.585468) (xy 233.66262 -223.551217) (xy 233.720459 -223.524)
			(xy 233.781252 -223.504247) (xy 233.844042 -223.492269) (xy 233.907838 -223.488256) (xy 233.971634 -223.492269)
			(xy 234.034424 -223.504247) (xy 234.095217 -223.524) (xy 234.153056 -223.551217) (xy 234.207027 -223.585468)
			(xy 234.25628 -223.626213) (xy 234.300037 -223.67281) (xy 234.33761 -223.724525) (xy 234.368404 -223.78054)
			(xy 234.391936 -223.839973) (xy 234.407833 -223.901887) (xy 234.415844 -223.965305) (xy 234.416346 -223.997266)
			(xy 234.415844 -224.029227) (xy 234.407833 -224.092645) (xy 234.391936 -224.154559) (xy 234.368404 -224.213992)
			(xy 234.33761 -224.270007) (xy 234.300037 -224.321722) (xy 234.25628 -224.368319) (xy 234.207027 -224.409064)
			(xy 234.153056 -224.443315) (xy 234.095217 -224.470532) (xy 234.034424 -224.490285) (xy 233.971634 -224.502263)
			(xy 233.907838 -224.506277) (xy 233.844042 -224.502263) (xy 233.781252 -224.490285) (xy 233.720459 -224.470532)
			(xy 233.66262 -224.443315) (xy 233.608649 -224.409064) (xy 233.559396 -224.368319) (xy 233.515639 -224.321722)
			(xy 233.478066 -224.270007) (xy 233.447272 -224.213992) (xy 233.42374 -224.154559) (xy 233.407843 -224.092645)
			(xy 233.399832 -224.029227) (xy 212.128057 -224.029227) (xy 213.53526 -225.43643) (xy 232.69397 -225.43643)
			(xy 232.698041 -225.380808) (xy 232.710167 -225.326371) (xy 232.73009 -225.27428) (xy 232.757386 -225.225645)
			(xy 232.791472 -225.181502) (xy 232.831621 -225.142793) (xy 232.876979 -225.110342) (xy 232.926579 -225.084841)
			(xy 232.979363 -225.066834) (xy 233.034206 -225.056704) (xy 233.08994 -225.054667) (xy 233.145377 -225.060767)
			(xy 233.199334 -225.074873) (xy 233.250663 -225.096685) (xy 233.298269 -225.125739) (xy 233.341137 -225.161414)
			(xy 233.378354 -225.202951) (xy 233.409127 -225.249464) (xy 233.432799 -225.299961) (xy 233.448867 -225.353368)
			(xy 233.456987 -225.408544) (xy 233.457496 -225.43643) (xy 233.456987 -225.464316) (xy 233.448867 -225.519492)
			(xy 233.432799 -225.572899) (xy 233.409127 -225.623396) (xy 233.378354 -225.669909) (xy 233.341137 -225.711446)
			(xy 233.298269 -225.747121) (xy 233.250663 -225.776175) (xy 233.199334 -225.797987) (xy 233.145377 -225.812093)
			(xy 233.08994 -225.818193) (xy 233.034206 -225.816156) (xy 232.979363 -225.806026) (xy 232.926579 -225.788019)
			(xy 232.876979 -225.762518) (xy 232.831621 -225.730067) (xy 232.791472 -225.691358) (xy 232.757386 -225.647215)
			(xy 232.73009 -225.59858) (xy 232.710167 -225.546489) (xy 232.698041 -225.492052) (xy 232.69397 -225.43643)
			(xy 213.53526 -225.43643) (xy 213.932053 -225.833223) (xy 235.738214 -225.833223) (xy 235.738218 -225.778727)
			(xy 235.745977 -225.724786) (xy 235.761333 -225.672499) (xy 235.783975 -225.622929) (xy 235.81344 -225.577086)
			(xy 235.849129 -225.535902) (xy 235.890316 -225.500217) (xy 235.936162 -225.470756) (xy 235.985734 -225.44812)
			(xy 236.038023 -225.432769) (xy 236.091965 -225.425015) (xy 236.146461 -225.425017) (xy 236.200402 -225.432774)
			(xy 236.252689 -225.448129) (xy 236.30226 -225.470769) (xy 236.348104 -225.500232) (xy 236.389289 -225.53592)
			(xy 236.424975 -225.577106) (xy 236.454438 -225.622951) (xy 236.477076 -225.672522) (xy 236.492428 -225.724811)
			(xy 236.500184 -225.778752) (xy 236.50067 -225.806) (xy 236.500007 -225.838115) (xy 236.489289 -225.901444)
			(xy 236.479334 -225.931984) (xy 236.474508 -225.9457) (xy 236.480604 -225.97364) (xy 236.563662 -226.06)
			(xy 236.591348 -226.066858) (xy 236.605318 -226.06254) (xy 236.632021 -226.0548) (xy 236.686994 -226.046515)
			(xy 236.714792 -226.04603) (xy 236.74442 -226.046612) (xy 236.802917 -226.056074) (xy 236.859152 -226.074756)
			(xy 236.911682 -226.102178) (xy 236.935772 -226.119436) (xy 236.9439 -226.125532) (xy 236.962442 -226.130612)
			(xy 237.052358 -226.119436) (xy 237.069376 -226.110038) (xy 237.075726 -226.102164) (xy 237.096443 -226.077306)
			(xy 237.143182 -226.032553) (xy 237.195226 -225.994096) (xy 237.25173 -225.962557) (xy 237.311781 -225.938446)
			(xy 237.374407 -225.922155) (xy 237.438595 -225.913946) (xy 237.47095 -225.913442) (xy 237.502918 -225.91382)
			(xy 237.566349 -225.921827) (xy 237.628277 -225.937722) (xy 237.687724 -225.961254) (xy 237.743752 -225.992051)
			(xy 237.795479 -226.029628) (xy 237.842088 -226.073392) (xy 237.882844 -226.122653) (xy 237.917104 -226.176634)
			(xy 237.944328 -226.234483) (xy 237.964086 -226.295289) (xy 237.976067 -226.358091) (xy 237.980082 -226.4219)
			(xy 237.976067 -226.485709) (xy 237.964086 -226.548511) (xy 237.944328 -226.609317) (xy 237.917104 -226.667166)
			(xy 237.882844 -226.721147) (xy 237.842088 -226.770408) (xy 237.795479 -226.814172) (xy 237.743752 -226.851749)
			(xy 237.687724 -226.882546) (xy 237.628277 -226.906078) (xy 237.566349 -226.921973) (xy 237.502918 -226.92998)
			(xy 237.47095 -226.930458) (xy 237.437909 -226.929915) (xy 237.372384 -226.921354) (xy 237.308518 -226.904382)
			(xy 237.247387 -226.879285) (xy 237.190019 -226.846486) (xy 237.137379 -226.806537) (xy 237.090355 -226.760109)
			(xy 237.06963 -226.73437) (xy 237.063534 -226.726242) (xy 237.04677 -226.71659) (xy 236.957108 -226.703636)
			(xy 236.938312 -226.708462) (xy 236.930184 -226.714304) (xy 236.906505 -226.73064) (xy 236.85514 -226.756538)
			(xy 236.800382 -226.774163) (xy 236.743554 -226.783091) (xy 236.714792 -226.783646) (xy 236.688449 -226.783146)
			(xy 236.636301 -226.775647) (xy 236.58575 -226.760804) (xy 236.537825 -226.738919) (xy 236.493503 -226.710436)
			(xy 236.453685 -226.675936) (xy 236.419182 -226.636121) (xy 236.390696 -226.591801) (xy 236.368806 -226.543878)
			(xy 236.353959 -226.493329) (xy 236.346456 -226.44118) (xy 236.345984 -226.414838) (xy 236.346532 -226.38503)
			(xy 236.35611 -226.32619) (xy 236.365034 -226.297744) (xy 236.369606 -226.283774) (xy 236.363256 -226.256088)
			(xy 236.278928 -226.170998) (xy 236.251242 -226.16414) (xy 236.237272 -226.168712) (xy 236.208527 -226.177447)
			(xy 236.149199 -226.186892) (xy 236.119162 -226.187508) (xy 236.091914 -226.186981) (xy 236.037974 -226.17922)
			(xy 235.985687 -226.163862) (xy 235.936118 -226.141219) (xy 235.890275 -226.111753) (xy 235.849093 -226.076062)
			(xy 235.813409 -226.034874) (xy 235.78395 -225.989027) (xy 235.761316 -225.939454) (xy 235.745966 -225.887164)
			(xy 235.738214 -225.833223) (xy 213.932053 -225.833223) (xy 215.55583 -227.457) (xy 233.17099 -227.457)
			(xy 233.175003 -227.393204) (xy 233.186981 -227.330414) (xy 233.206734 -227.269621) (xy 233.233951 -227.211782)
			(xy 233.268202 -227.157811) (xy 233.308947 -227.108558) (xy 233.355544 -227.064801) (xy 233.407259 -227.027228)
			(xy 233.463274 -226.996434) (xy 233.522707 -226.972902) (xy 233.584621 -226.957005) (xy 233.648039 -226.948994)
			(xy 233.68 -226.948492) (xy 233.710215 -226.94893) (xy 233.770218 -226.956117) (xy 233.828945 -226.970367)
			(xy 233.885569 -226.991478) (xy 233.939291 -227.019152) (xy 233.989354 -227.053) (xy 234.012486 -227.072444)
			(xy 234.019623 -227.078069) (xy 234.036678 -227.084313) (xy 234.04576 -227.084636) (xy 234.07624 -227.084636)
			(xy 234.08532 -227.084302) (xy 234.102371 -227.078059) (xy 234.109514 -227.072444) (xy 234.132649 -227.053005)
			(xy 234.182716 -227.019167) (xy 234.236439 -226.991498) (xy 234.293061 -226.970389) (xy 234.351786 -226.956137)
			(xy 234.411786 -226.948942) (xy 234.442 -226.948492) (xy 234.473961 -226.948994) (xy 234.537379 -226.957005)
			(xy 234.599293 -226.972902) (xy 234.658726 -226.996434) (xy 234.714741 -227.027228) (xy 234.766456 -227.064801)
			(xy 234.813053 -227.108558) (xy 234.853798 -227.157811) (xy 234.888049 -227.211782) (xy 234.915266 -227.269621)
			(xy 234.935019 -227.330414) (xy 234.946997 -227.393204) (xy 234.951011 -227.457) (xy 234.946997 -227.520796)
			(xy 234.935019 -227.583586) (xy 234.915266 -227.644379) (xy 234.888049 -227.702218) (xy 234.853798 -227.756189)
			(xy 234.813053 -227.805442) (xy 234.766456 -227.849199) (xy 234.714741 -227.886772) (xy 234.658726 -227.917566)
			(xy 234.599293 -227.941098) (xy 234.537379 -227.956995) (xy 234.473961 -227.965006) (xy 234.442 -227.965508)
			(xy 234.411785 -227.96507) (xy 234.351782 -227.957883) (xy 234.293055 -227.943633) (xy 234.236431 -227.922522)
			(xy 234.182709 -227.894848) (xy 234.132646 -227.861) (xy 234.109514 -227.841556) (xy 234.102377 -227.835931)
			(xy 234.085322 -227.829687) (xy 234.07624 -227.829364) (xy 234.04576 -227.829364) (xy 234.03668 -227.829698)
			(xy 234.019629 -227.835941) (xy 234.012486 -227.841556) (xy 233.989351 -227.860995) (xy 233.939284 -227.894833)
			(xy 233.885561 -227.922502) (xy 233.828939 -227.943611) (xy 233.770214 -227.957863) (xy 233.710214 -227.965058)
			(xy 233.68 -227.965508) (xy 233.648039 -227.965006) (xy 233.584621 -227.956995) (xy 233.522707 -227.941098)
			(xy 233.463274 -227.917566) (xy 233.407259 -227.886772) (xy 233.355544 -227.849199) (xy 233.308947 -227.805442)
			(xy 233.268202 -227.756189) (xy 233.233951 -227.702218) (xy 233.206734 -227.644379) (xy 233.186981 -227.583586)
			(xy 233.175003 -227.520796) (xy 233.17099 -227.457) (xy 215.55583 -227.457) (xy 216.202514 -228.103684)
			(xy 216.209913 -228.11053) (xy 216.228511 -228.118262) (xy 216.238582 -228.11867) (xy 230.083614 -228.11867)
			(xy 230.090653 -228.118446) (xy 230.104189 -228.114578) (xy 230.110284 -228.11105) (xy 230.137171 -228.094945)
			(xy 230.194108 -228.068745) (xy 230.253834 -228.049743) (xy 230.315443 -228.038224) (xy 230.378 -228.034366)
			(xy 230.440557 -228.038224) (xy 230.502166 -228.049743) (xy 230.561892 -228.068745) (xy 230.618829 -228.094945)
			(xy 230.645716 -228.11105) (xy 230.651823 -228.114547) (xy 230.665353 -228.118403) (xy 230.672386 -228.11867)
			(xy 232.100882 -228.11867) (xy 232.110932 -228.119176) (xy 232.129493 -228.126897) (xy 232.13695 -228.133656)
			(xy 232.74401 -228.740716) (xy 233.380803 -228.740716) (xy 233.384738 -228.686945) (xy 233.396461 -228.634321)
			(xy 233.415721 -228.583964) (xy 233.442107 -228.536947) (xy 233.475059 -228.494274) (xy 233.513872 -228.456853)
			(xy 233.55772 -228.425483) (xy 233.605668 -228.400831) (xy 233.656695 -228.383423) (xy 233.709713 -228.37363)
			(xy 233.763592 -228.371661) (xy 233.817183 -228.377558) (xy 233.869344 -228.391194) (xy 233.918964 -228.412281)
			(xy 233.964985 -228.440367) (xy 234.006427 -228.474855) (xy 234.042405 -228.515009) (xy 234.072153 -228.559973)
			(xy 234.095038 -228.60879) (xy 234.11057 -228.660419) (xy 234.11842 -228.713759) (xy 234.118912 -228.740716)
			(xy 234.11842 -228.767673) (xy 234.11057 -228.821013) (xy 234.095038 -228.872642) (xy 234.072153 -228.921459)
			(xy 234.042405 -228.966423) (xy 234.006427 -229.006577) (xy 233.964985 -229.041065) (xy 233.918964 -229.069151)
			(xy 233.869344 -229.090238) (xy 233.817183 -229.103874) (xy 233.763592 -229.109771) (xy 233.709713 -229.107802)
			(xy 233.656695 -229.098009) (xy 233.605668 -229.080601) (xy 233.55772 -229.055949) (xy 233.513872 -229.024579)
			(xy 233.475059 -228.987158) (xy 233.442107 -228.944485) (xy 233.415721 -228.897468) (xy 233.396461 -228.847111)
			(xy 233.384738 -228.794487) (xy 233.380803 -228.740716) (xy 232.74401 -228.740716) (xy 233.797348 -229.794054)
			(xy 233.804192 -229.801453) (xy 233.811915 -229.820052) (xy 233.812334 -229.830122) (xy 233.812334 -230.498142)
			(xy 233.812704 -230.507185) (xy 233.818994 -230.524142) (xy 233.830778 -230.537864) (xy 233.838496 -230.542592)
			(xy 233.862658 -230.556704) (xy 233.906806 -230.591082) (xy 233.94526 -230.631728) (xy 233.977142 -230.677711)
			(xy 234.00172 -230.727977) (xy 234.018432 -230.781377) (xy 234.026895 -230.836687) (xy 234.027472 -230.864664)
			(xy 234.027472 -230.871776) (xy 234.027955 -230.881789) (xy 234.03561 -230.900294) (xy 234.049763 -230.914461)
			(xy 234.06826 -230.922134) (xy 234.078272 -230.922576) (xy 237.07725 -230.922576) (xy 237.109054 -230.922992)
			(xy 237.172265 -230.930089) (xy 237.234283 -230.944221) (xy 237.294328 -230.965211) (xy 237.351644 -230.992795)
			(xy 237.40551 -231.026625) (xy 237.455247 -231.066275) (xy 237.478062 -231.088438) (xy 237.797086 -231.407462)
			(xy 237.804487 -231.414299) (xy 237.823086 -231.422008) (xy 237.833154 -231.422448)
		)
		(stroke
			(width 0)
			(type solid)
		)
		(fill yes)
		(layer "In11.Cu")
		(net "PVDD18_S5_P1")
	)
	(gr_poly
		(pts
			(xy 463.386932 -419.341554) (xy 463.396999 -419.341124) (xy 463.41559 -419.333396) (xy 463.423 -419.326568)
			(xy 463.875882 -418.873686) (xy 463.882728 -418.866287) (xy 463.89046 -418.847689) (xy 463.890868 -418.837618)
			(xy 463.890868 -408.086052) (xy 463.891299 -408.075985) (xy 463.899022 -408.05739) (xy 463.905854 -408.049984)
			(xy 466.986874 -404.968964) (xy 466.993718 -404.961565) (xy 467.001443 -404.942966) (xy 467.00186 -404.932896)
			(xy 467.00186 -375.924318) (xy 467.001421 -375.914255) (xy 466.993681 -375.895676) (xy 466.986874 -375.88825)
			(xy 464.521042 -373.422418) (xy 464.513641 -373.415579) (xy 464.495043 -373.407863) (xy 464.484974 -373.407432)
			(xy 442.597794 -373.407432) (xy 442.587725 -373.407857) (xy 442.569125 -373.415576) (xy 442.561726 -373.422418)
			(xy 438.995312 -376.988832) (xy 438.988632 -376.996243) (xy 438.981059 -377.014679) (xy 438.98058 -377.024646)
			(xy 438.98058 -383.388882) (xy 441.915547 -383.388882) (xy 441.919279 -383.335628) (xy 441.930398 -383.283415)
			(xy 441.948686 -383.233261) (xy 441.973787 -383.186146) (xy 442.005209 -383.14299) (xy 442.042341 -383.104634)
			(xy 442.063124 -383.08788) (xy 442.071895 -383.080327) (xy 442.082072 -383.059561) (xy 442.082682 -383.048002)
			(xy 442.082682 -382.967738) (xy 442.082096 -382.956172) (xy 442.071913 -382.9354) (xy 442.063124 -382.92786)
			(xy 442.042313 -382.911141) (xy 442.005185 -382.872782) (xy 441.973767 -382.829623) (xy 441.948671 -382.782505)
			(xy 441.930388 -382.73235) (xy 441.919274 -382.680135) (xy 441.915547 -382.626882) (xy 441.919279 -382.573628)
			(xy 441.930398 -382.521415) (xy 441.948686 -382.471261) (xy 441.973787 -382.424146) (xy 442.005209 -382.38099)
			(xy 442.042341 -382.342634) (xy 442.063124 -382.32588) (xy 442.071895 -382.318327) (xy 442.082072 -382.297561)
			(xy 442.082682 -382.286002) (xy 442.082682 -382.205738) (xy 442.082096 -382.194172) (xy 442.071913 -382.1734)
			(xy 442.063124 -382.16586) (xy 442.040626 -382.147685) (xy 442.000891 -382.105663) (xy 441.967953 -382.058125)
			(xy 441.942567 -382.00616) (xy 441.925314 -381.950959) (xy 441.91659 -381.893787) (xy 441.916058 -381.86487)
			(xy 441.916544 -381.837619) (xy 441.9243 -381.783671) (xy 441.939655 -381.731376) (xy 441.962297 -381.681799)
			(xy 441.991763 -381.635949) (xy 442.027454 -381.594758) (xy 442.068645 -381.559067) (xy 442.114495 -381.529601)
			(xy 442.164072 -381.506959) (xy 442.216367 -381.491604) (xy 442.270315 -381.483848) (xy 442.324817 -381.483848)
			(xy 442.378765 -381.491604) (xy 442.43106 -381.506959) (xy 442.480637 -381.529601) (xy 442.526487 -381.559067)
			(xy 442.567678 -381.594758) (xy 442.603369 -381.635949) (xy 442.632835 -381.681799) (xy 442.655477 -381.731376)
			(xy 442.670832 -381.783671) (xy 442.678588 -381.837619) (xy 442.679074 -381.86487) (xy 442.678544 -381.893787)
			(xy 442.669819 -381.950958) (xy 442.652564 -382.006157) (xy 442.627174 -382.058119) (xy 442.594232 -382.105653)
			(xy 442.554493 -382.14767) (xy 442.532008 -382.16586) (xy 442.52327 -382.173445) (xy 442.513073 -382.194186)
			(xy 442.51245 -382.205738) (xy 442.51245 -382.286002) (xy 442.513002 -382.297573) (xy 442.523208 -382.318345)
			(xy 442.532008 -382.32588) (xy 442.552763 -382.342668) (xy 442.589896 -382.381016) (xy 442.62132 -382.424166)
			(xy 442.646422 -382.471275) (xy 442.664711 -382.521424) (xy 442.675831 -382.573632) (xy 442.679563 -382.626882)
			(xy 442.675836 -382.680131) (xy 442.664721 -382.732341) (xy 442.646437 -382.782491) (xy 442.621339 -382.829603)
			(xy 442.589919 -382.872756) (xy 442.55279 -382.911107) (xy 442.532008 -382.92786) (xy 442.52327 -382.935445)
			(xy 442.513073 -382.956186) (xy 442.51245 -382.967738) (xy 442.51245 -383.048002) (xy 442.513002 -383.059573)
			(xy 442.523208 -383.080345) (xy 442.532008 -383.08788) (xy 442.552763 -383.104668) (xy 442.589896 -383.143016)
			(xy 442.62132 -383.186166) (xy 442.646422 -383.233275) (xy 442.664711 -383.283424) (xy 442.675831 -383.335632)
			(xy 442.679563 -383.388882) (xy 445.725547 -383.388882) (xy 445.729279 -383.335628) (xy 445.740398 -383.283415)
			(xy 445.758686 -383.233261) (xy 445.783787 -383.186146) (xy 445.815209 -383.14299) (xy 445.852341 -383.104634)
			(xy 445.873124 -383.08788) (xy 445.881895 -383.080327) (xy 445.892072 -383.059561) (xy 445.892682 -383.048002)
			(xy 445.892682 -382.967738) (xy 445.892096 -382.956172) (xy 445.881913 -382.9354) (xy 445.873124 -382.92786)
			(xy 445.852313 -382.911141) (xy 445.815185 -382.872782) (xy 445.783767 -382.829623) (xy 445.758671 -382.782505)
			(xy 445.740388 -382.73235) (xy 445.729274 -382.680135) (xy 445.725547 -382.626882) (xy 445.729279 -382.573628)
			(xy 445.740398 -382.521415) (xy 445.758686 -382.471261) (xy 445.783787 -382.424146) (xy 445.815209 -382.38099)
			(xy 445.852341 -382.342634) (xy 445.873124 -382.32588) (xy 445.881895 -382.318327) (xy 445.892072 -382.297561)
			(xy 445.892682 -382.286002) (xy 445.892682 -382.205738) (xy 445.892096 -382.194172) (xy 445.881913 -382.1734)
			(xy 445.873124 -382.16586) (xy 445.850626 -382.147685) (xy 445.810891 -382.105663) (xy 445.777953 -382.058125)
			(xy 445.752567 -382.00616) (xy 445.735314 -381.950959) (xy 445.72659 -381.893787) (xy 445.726058 -381.86487)
			(xy 445.726544 -381.837619) (xy 445.7343 -381.783671) (xy 445.749655 -381.731376) (xy 445.772297 -381.681799)
			(xy 445.801763 -381.635949) (xy 445.837454 -381.594758) (xy 445.878645 -381.559067) (xy 445.924495 -381.529601)
			(xy 445.974072 -381.506959) (xy 446.026367 -381.491604) (xy 446.080315 -381.483848) (xy 446.134817 -381.483848)
			(xy 446.188765 -381.491604) (xy 446.24106 -381.506959) (xy 446.290637 -381.529601) (xy 446.336487 -381.559067)
			(xy 446.377678 -381.594758) (xy 446.413369 -381.635949) (xy 446.442835 -381.681799) (xy 446.465477 -381.731376)
			(xy 446.480832 -381.783671) (xy 446.488588 -381.837619) (xy 446.489074 -381.86487) (xy 446.488544 -381.893787)
			(xy 446.479819 -381.950958) (xy 446.462564 -382.006157) (xy 446.437174 -382.058119) (xy 446.404232 -382.105653)
			(xy 446.364493 -382.14767) (xy 446.342008 -382.16586) (xy 446.33327 -382.173445) (xy 446.323073 -382.194186)
			(xy 446.32245 -382.205738) (xy 446.32245 -382.286002) (xy 446.323002 -382.297573) (xy 446.333208 -382.318345)
			(xy 446.342008 -382.32588) (xy 446.362763 -382.342668) (xy 446.399896 -382.381016) (xy 446.43132 -382.424166)
			(xy 446.456422 -382.471275) (xy 446.474711 -382.521424) (xy 446.485831 -382.573632) (xy 446.489563 -382.626882)
			(xy 446.485836 -382.680131) (xy 446.474721 -382.732341) (xy 446.456437 -382.782491) (xy 446.431339 -382.829603)
			(xy 446.399919 -382.872756) (xy 446.36279 -382.911107) (xy 446.342008 -382.92786) (xy 446.33327 -382.935445)
			(xy 446.323073 -382.956186) (xy 446.32245 -382.967738) (xy 446.32245 -383.048002) (xy 446.323002 -383.059573)
			(xy 446.333208 -383.080345) (xy 446.342008 -383.08788) (xy 446.362763 -383.104668) (xy 446.399896 -383.143016)
			(xy 446.43132 -383.186166) (xy 446.456422 -383.233275) (xy 446.474711 -383.283424) (xy 446.485831 -383.335632)
			(xy 446.489563 -383.388882) (xy 447.681347 -383.388882) (xy 447.685079 -383.335628) (xy 447.696198 -383.283415)
			(xy 447.714486 -383.233261) (xy 447.739587 -383.186146) (xy 447.771009 -383.14299) (xy 447.808141 -383.104634)
			(xy 447.828924 -383.08788) (xy 447.837695 -383.080327) (xy 447.847872 -383.059561) (xy 447.848482 -383.048002)
			(xy 447.848482 -382.967738) (xy 447.847896 -382.956172) (xy 447.837713 -382.9354) (xy 447.828924 -382.92786)
			(xy 447.808113 -382.911141) (xy 447.770985 -382.872782) (xy 447.739567 -382.829623) (xy 447.714471 -382.782505)
			(xy 447.696188 -382.73235) (xy 447.685074 -382.680135) (xy 447.681347 -382.626882) (xy 447.685079 -382.573628)
			(xy 447.696198 -382.521415) (xy 447.714486 -382.471261) (xy 447.739587 -382.424146) (xy 447.771009 -382.38099)
			(xy 447.808141 -382.342634) (xy 447.828924 -382.32588) (xy 447.837695 -382.318327) (xy 447.847872 -382.297561)
			(xy 447.848482 -382.286002) (xy 447.848482 -382.205738) (xy 447.847896 -382.194172) (xy 447.837713 -382.1734)
			(xy 447.828924 -382.16586) (xy 447.806426 -382.147685) (xy 447.766691 -382.105663) (xy 447.733753 -382.058125)
			(xy 447.708367 -382.00616) (xy 447.691114 -381.950959) (xy 447.68239 -381.893787) (xy 447.681858 -381.86487)
			(xy 447.682344 -381.837619) (xy 447.6901 -381.783671) (xy 447.705455 -381.731376) (xy 447.728097 -381.681799)
			(xy 447.757563 -381.635949) (xy 447.793254 -381.594758) (xy 447.834445 -381.559067) (xy 447.880295 -381.529601)
			(xy 447.929872 -381.506959) (xy 447.982167 -381.491604) (xy 448.036115 -381.483848) (xy 448.090617 -381.483848)
			(xy 448.144565 -381.491604) (xy 448.19686 -381.506959) (xy 448.246437 -381.529601) (xy 448.292287 -381.559067)
			(xy 448.333478 -381.594758) (xy 448.369169 -381.635949) (xy 448.398635 -381.681799) (xy 448.421277 -381.731376)
			(xy 448.436632 -381.783671) (xy 448.444388 -381.837619) (xy 448.444874 -381.86487) (xy 448.444344 -381.893787)
			(xy 448.435619 -381.950958) (xy 448.418364 -382.006157) (xy 448.392974 -382.058119) (xy 448.360032 -382.105653)
			(xy 448.320293 -382.14767) (xy 448.297808 -382.16586) (xy 448.28907 -382.173445) (xy 448.278873 -382.194186)
			(xy 448.27825 -382.205738) (xy 448.27825 -382.286002) (xy 448.278802 -382.297573) (xy 448.289008 -382.318345)
			(xy 448.297808 -382.32588) (xy 448.318563 -382.342668) (xy 448.355696 -382.381016) (xy 448.38712 -382.424166)
			(xy 448.412222 -382.471275) (xy 448.430511 -382.521424) (xy 448.441631 -382.573632) (xy 448.445363 -382.626882)
			(xy 448.441636 -382.680131) (xy 448.430521 -382.732341) (xy 448.412237 -382.782491) (xy 448.387139 -382.829603)
			(xy 448.355719 -382.872756) (xy 448.31859 -382.911107) (xy 448.297808 -382.92786) (xy 448.28907 -382.935445)
			(xy 448.278873 -382.956186) (xy 448.27825 -382.967738) (xy 448.27825 -383.048002) (xy 448.278802 -383.059573)
			(xy 448.289008 -383.080345) (xy 448.297808 -383.08788) (xy 448.318563 -383.104668) (xy 448.355696 -383.143016)
			(xy 448.38712 -383.186166) (xy 448.412222 -383.233275) (xy 448.430511 -383.283424) (xy 448.441631 -383.335632)
			(xy 448.445363 -383.388882) (xy 451.491347 -383.388882) (xy 451.495079 -383.335628) (xy 451.506198 -383.283415)
			(xy 451.524486 -383.233261) (xy 451.549587 -383.186146) (xy 451.581009 -383.14299) (xy 451.618141 -383.104634)
			(xy 451.638924 -383.08788) (xy 451.647695 -383.080327) (xy 451.657872 -383.059561) (xy 451.658482 -383.048002)
			(xy 451.658482 -382.967738) (xy 451.657896 -382.956172) (xy 451.647713 -382.9354) (xy 451.638924 -382.92786)
			(xy 451.618113 -382.911141) (xy 451.580985 -382.872782) (xy 451.549567 -382.829623) (xy 451.524471 -382.782505)
			(xy 451.506188 -382.73235) (xy 451.495074 -382.680135) (xy 451.491347 -382.626882) (xy 451.495079 -382.573628)
			(xy 451.506198 -382.521415) (xy 451.524486 -382.471261) (xy 451.549587 -382.424146) (xy 451.581009 -382.38099)
			(xy 451.618141 -382.342634) (xy 451.638924 -382.32588) (xy 451.647695 -382.318327) (xy 451.657872 -382.297561)
			(xy 451.658482 -382.286002) (xy 451.658482 -382.205738) (xy 451.657896 -382.194172) (xy 451.647713 -382.1734)
			(xy 451.638924 -382.16586) (xy 451.616426 -382.147685) (xy 451.576691 -382.105663) (xy 451.543753 -382.058125)
			(xy 451.518367 -382.00616) (xy 451.501114 -381.950959) (xy 451.49239 -381.893787) (xy 451.491858 -381.86487)
			(xy 451.492344 -381.837619) (xy 451.5001 -381.783671) (xy 451.515455 -381.731376) (xy 451.538097 -381.681799)
			(xy 451.567563 -381.635949) (xy 451.603254 -381.594758) (xy 451.644445 -381.559067) (xy 451.690295 -381.529601)
			(xy 451.739872 -381.506959) (xy 451.792167 -381.491604) (xy 451.846115 -381.483848) (xy 451.900617 -381.483848)
			(xy 451.954565 -381.491604) (xy 452.00686 -381.506959) (xy 452.056437 -381.529601) (xy 452.102287 -381.559067)
			(xy 452.143478 -381.594758) (xy 452.179169 -381.635949) (xy 452.208635 -381.681799) (xy 452.231277 -381.731376)
			(xy 452.246632 -381.783671) (xy 452.254388 -381.837619) (xy 452.254874 -381.86487) (xy 452.254344 -381.893787)
			(xy 452.245619 -381.950958) (xy 452.228364 -382.006157) (xy 452.202974 -382.058119) (xy 452.170032 -382.105653)
			(xy 452.130293 -382.14767) (xy 452.107808 -382.16586) (xy 452.09907 -382.173445) (xy 452.088873 -382.194186)
			(xy 452.08825 -382.205738) (xy 452.08825 -382.286002) (xy 452.088802 -382.297573) (xy 452.099008 -382.318345)
			(xy 452.107808 -382.32588) (xy 452.128563 -382.342668) (xy 452.165696 -382.381016) (xy 452.19712 -382.424166)
			(xy 452.222222 -382.471275) (xy 452.240511 -382.521424) (xy 452.251631 -382.573632) (xy 452.255363 -382.626882)
			(xy 452.251636 -382.680131) (xy 452.240521 -382.732341) (xy 452.222237 -382.782491) (xy 452.197139 -382.829603)
			(xy 452.165719 -382.872756) (xy 452.12859 -382.911107) (xy 452.107808 -382.92786) (xy 452.09907 -382.935445)
			(xy 452.088873 -382.956186) (xy 452.08825 -382.967738) (xy 452.08825 -383.048002) (xy 452.088802 -383.059573)
			(xy 452.099008 -383.080345) (xy 452.107808 -383.08788) (xy 452.128563 -383.104668) (xy 452.165696 -383.143016)
			(xy 452.19712 -383.186166) (xy 452.222222 -383.233275) (xy 452.240511 -383.283424) (xy 452.251631 -383.335632)
			(xy 452.255363 -383.388882) (xy 453.777347 -383.388882) (xy 453.781079 -383.335628) (xy 453.792198 -383.283415)
			(xy 453.810486 -383.233261) (xy 453.835587 -383.186146) (xy 453.867009 -383.14299) (xy 453.904141 -383.104634)
			(xy 453.924924 -383.08788) (xy 453.933695 -383.080327) (xy 453.943872 -383.059561) (xy 453.944482 -383.048002)
			(xy 453.944482 -382.967738) (xy 453.943896 -382.956172) (xy 453.933713 -382.9354) (xy 453.924924 -382.92786)
			(xy 453.904113 -382.911141) (xy 453.866985 -382.872782) (xy 453.835567 -382.829623) (xy 453.810471 -382.782505)
			(xy 453.792188 -382.73235) (xy 453.781074 -382.680135) (xy 453.777347 -382.626882) (xy 453.781079 -382.573628)
			(xy 453.792198 -382.521415) (xy 453.810486 -382.471261) (xy 453.835587 -382.424146) (xy 453.867009 -382.38099)
			(xy 453.904141 -382.342634) (xy 453.924924 -382.32588) (xy 453.933695 -382.318327) (xy 453.943872 -382.297561)
			(xy 453.944482 -382.286002) (xy 453.944482 -382.205738) (xy 453.943896 -382.194172) (xy 453.933713 -382.1734)
			(xy 453.924924 -382.16586) (xy 453.902426 -382.147685) (xy 453.862691 -382.105663) (xy 453.829753 -382.058125)
			(xy 453.804367 -382.00616) (xy 453.787114 -381.950959) (xy 453.77839 -381.893787) (xy 453.777858 -381.86487)
			(xy 453.778344 -381.837619) (xy 453.7861 -381.783671) (xy 453.801455 -381.731376) (xy 453.824097 -381.681799)
			(xy 453.853563 -381.635949) (xy 453.889254 -381.594758) (xy 453.930445 -381.559067) (xy 453.976295 -381.529601)
			(xy 454.025872 -381.506959) (xy 454.078167 -381.491604) (xy 454.132115 -381.483848) (xy 454.186617 -381.483848)
			(xy 454.240565 -381.491604) (xy 454.29286 -381.506959) (xy 454.342437 -381.529601) (xy 454.388287 -381.559067)
			(xy 454.429478 -381.594758) (xy 454.465169 -381.635949) (xy 454.494635 -381.681799) (xy 454.517277 -381.731376)
			(xy 454.532632 -381.783671) (xy 454.540388 -381.837619) (xy 454.540874 -381.86487) (xy 454.540344 -381.893787)
			(xy 454.531619 -381.950958) (xy 454.514364 -382.006157) (xy 454.488974 -382.058119) (xy 454.456032 -382.105653)
			(xy 454.416293 -382.14767) (xy 454.393808 -382.16586) (xy 454.38507 -382.173445) (xy 454.374873 -382.194186)
			(xy 454.37425 -382.205738) (xy 454.37425 -382.286002) (xy 454.374802 -382.297573) (xy 454.385008 -382.318345)
			(xy 454.393808 -382.32588) (xy 454.414563 -382.342668) (xy 454.451696 -382.381016) (xy 454.48312 -382.424166)
			(xy 454.508222 -382.471275) (xy 454.526511 -382.521424) (xy 454.537631 -382.573632) (xy 454.541363 -382.626882)
			(xy 454.537636 -382.680131) (xy 454.526521 -382.732341) (xy 454.508237 -382.782491) (xy 454.483139 -382.829603)
			(xy 454.451719 -382.872756) (xy 454.41459 -382.911107) (xy 454.393808 -382.92786) (xy 454.38507 -382.935445)
			(xy 454.374873 -382.956186) (xy 454.37425 -382.967738) (xy 454.37425 -383.048002) (xy 454.374802 -383.059573)
			(xy 454.385008 -383.080345) (xy 454.393808 -383.08788) (xy 454.414563 -383.104668) (xy 454.451696 -383.143016)
			(xy 454.48312 -383.186166) (xy 454.508222 -383.233275) (xy 454.526511 -383.283424) (xy 454.537631 -383.335632)
			(xy 454.541363 -383.388882) (xy 457.587347 -383.388882) (xy 457.591079 -383.335628) (xy 457.602198 -383.283415)
			(xy 457.620486 -383.233261) (xy 457.645587 -383.186146) (xy 457.677009 -383.14299) (xy 457.714141 -383.104634)
			(xy 457.734924 -383.08788) (xy 457.743695 -383.080327) (xy 457.753872 -383.059561) (xy 457.754482 -383.048002)
			(xy 457.754482 -382.967738) (xy 457.753896 -382.956172) (xy 457.743713 -382.9354) (xy 457.734924 -382.92786)
			(xy 457.714113 -382.911141) (xy 457.676985 -382.872782) (xy 457.645567 -382.829623) (xy 457.620471 -382.782505)
			(xy 457.602188 -382.73235) (xy 457.591074 -382.680135) (xy 457.587347 -382.626882) (xy 457.591079 -382.573628)
			(xy 457.602198 -382.521415) (xy 457.620486 -382.471261) (xy 457.645587 -382.424146) (xy 457.677009 -382.38099)
			(xy 457.714141 -382.342634) (xy 457.734924 -382.32588) (xy 457.743695 -382.318327) (xy 457.753872 -382.297561)
			(xy 457.754482 -382.286002) (xy 457.754482 -382.205738) (xy 457.753896 -382.194172) (xy 457.743713 -382.1734)
			(xy 457.734924 -382.16586) (xy 457.712426 -382.147685) (xy 457.672691 -382.105663) (xy 457.639753 -382.058125)
			(xy 457.614367 -382.00616) (xy 457.597114 -381.950959) (xy 457.58839 -381.893787) (xy 457.587858 -381.86487)
			(xy 457.588344 -381.837619) (xy 457.5961 -381.783671) (xy 457.611455 -381.731376) (xy 457.634097 -381.681799)
			(xy 457.663563 -381.635949) (xy 457.699254 -381.594758) (xy 457.740445 -381.559067) (xy 457.786295 -381.529601)
			(xy 457.835872 -381.506959) (xy 457.888167 -381.491604) (xy 457.942115 -381.483848) (xy 457.996617 -381.483848)
			(xy 458.050565 -381.491604) (xy 458.10286 -381.506959) (xy 458.152437 -381.529601) (xy 458.198287 -381.559067)
			(xy 458.239478 -381.594758) (xy 458.275169 -381.635949) (xy 458.304635 -381.681799) (xy 458.327277 -381.731376)
			(xy 458.342632 -381.783671) (xy 458.350388 -381.837619) (xy 458.350874 -381.86487) (xy 458.350344 -381.893787)
			(xy 458.341619 -381.950958) (xy 458.324364 -382.006157) (xy 458.298974 -382.058119) (xy 458.266032 -382.105653)
			(xy 458.226293 -382.14767) (xy 458.203808 -382.16586) (xy 458.19507 -382.173445) (xy 458.184873 -382.194186)
			(xy 458.18425 -382.205738) (xy 458.18425 -382.286002) (xy 458.184802 -382.297573) (xy 458.195008 -382.318345)
			(xy 458.203808 -382.32588) (xy 458.224563 -382.342668) (xy 458.261696 -382.381016) (xy 458.29312 -382.424166)
			(xy 458.318222 -382.471275) (xy 458.336511 -382.521424) (xy 458.347631 -382.573632) (xy 458.351363 -382.626882)
			(xy 458.347636 -382.680131) (xy 458.336521 -382.732341) (xy 458.318237 -382.782491) (xy 458.293139 -382.829603)
			(xy 458.261719 -382.872756) (xy 458.22459 -382.911107) (xy 458.203808 -382.92786) (xy 458.19507 -382.935445)
			(xy 458.184873 -382.956186) (xy 458.18425 -382.967738) (xy 458.18425 -383.048002) (xy 458.184802 -383.059573)
			(xy 458.195008 -383.080345) (xy 458.203808 -383.08788) (xy 458.224563 -383.104668) (xy 458.261696 -383.143016)
			(xy 458.29312 -383.186166) (xy 458.318222 -383.233275) (xy 458.336511 -383.283424) (xy 458.347631 -383.335632)
			(xy 458.351363 -383.388882) (xy 459.873347 -383.388882) (xy 459.877079 -383.335628) (xy 459.888198 -383.283415)
			(xy 459.906486 -383.233261) (xy 459.931587 -383.186146) (xy 459.963009 -383.14299) (xy 460.000141 -383.104634)
			(xy 460.020924 -383.08788) (xy 460.029695 -383.080327) (xy 460.039872 -383.059561) (xy 460.040482 -383.048002)
			(xy 460.040482 -382.967738) (xy 460.039896 -382.956172) (xy 460.029713 -382.9354) (xy 460.020924 -382.92786)
			(xy 460.000113 -382.911141) (xy 459.962985 -382.872782) (xy 459.931567 -382.829623) (xy 459.906471 -382.782505)
			(xy 459.888188 -382.73235) (xy 459.877074 -382.680135) (xy 459.873347 -382.626882) (xy 459.877079 -382.573628)
			(xy 459.888198 -382.521415) (xy 459.906486 -382.471261) (xy 459.931587 -382.424146) (xy 459.963009 -382.38099)
			(xy 460.000141 -382.342634) (xy 460.020924 -382.32588) (xy 460.029695 -382.318327) (xy 460.039872 -382.297561)
			(xy 460.040482 -382.286002) (xy 460.040482 -382.205738) (xy 460.039896 -382.194172) (xy 460.029713 -382.1734)
			(xy 460.020924 -382.16586) (xy 459.998426 -382.147685) (xy 459.958691 -382.105663) (xy 459.925753 -382.058125)
			(xy 459.900367 -382.00616) (xy 459.883114 -381.950959) (xy 459.87439 -381.893787) (xy 459.873858 -381.86487)
			(xy 459.874344 -381.837619) (xy 459.8821 -381.783671) (xy 459.897455 -381.731376) (xy 459.920097 -381.681799)
			(xy 459.949563 -381.635949) (xy 459.985254 -381.594758) (xy 460.026445 -381.559067) (xy 460.072295 -381.529601)
			(xy 460.121872 -381.506959) (xy 460.174167 -381.491604) (xy 460.228115 -381.483848) (xy 460.282617 -381.483848)
			(xy 460.336565 -381.491604) (xy 460.38886 -381.506959) (xy 460.438437 -381.529601) (xy 460.484287 -381.559067)
			(xy 460.525478 -381.594758) (xy 460.561169 -381.635949) (xy 460.590635 -381.681799) (xy 460.613277 -381.731376)
			(xy 460.628632 -381.783671) (xy 460.636388 -381.837619) (xy 460.636874 -381.86487) (xy 460.636344 -381.893787)
			(xy 460.627619 -381.950958) (xy 460.610364 -382.006157) (xy 460.584974 -382.058119) (xy 460.552032 -382.105653)
			(xy 460.512293 -382.14767) (xy 460.489808 -382.16586) (xy 460.48107 -382.173445) (xy 460.470873 -382.194186)
			(xy 460.47025 -382.205738) (xy 460.47025 -382.286002) (xy 460.470802 -382.297573) (xy 460.481008 -382.318345)
			(xy 460.489808 -382.32588) (xy 460.510563 -382.342668) (xy 460.547696 -382.381016) (xy 460.57912 -382.424166)
			(xy 460.604222 -382.471275) (xy 460.622511 -382.521424) (xy 460.633631 -382.573632) (xy 460.637363 -382.626882)
			(xy 460.633636 -382.680131) (xy 460.622521 -382.732341) (xy 460.604237 -382.782491) (xy 460.579139 -382.829603)
			(xy 460.547719 -382.872756) (xy 460.51059 -382.911107) (xy 460.489808 -382.92786) (xy 460.48107 -382.935445)
			(xy 460.470873 -382.956186) (xy 460.47025 -382.967738) (xy 460.47025 -383.048002) (xy 460.470802 -383.059573)
			(xy 460.481008 -383.080345) (xy 460.489808 -383.08788) (xy 460.510563 -383.104668) (xy 460.547696 -383.143016)
			(xy 460.57912 -383.186166) (xy 460.604222 -383.233275) (xy 460.622511 -383.283424) (xy 460.633631 -383.335632)
			(xy 460.637363 -383.388882) (xy 463.683347 -383.388882) (xy 463.687079 -383.335628) (xy 463.698198 -383.283415)
			(xy 463.716486 -383.233261) (xy 463.741587 -383.186146) (xy 463.773009 -383.14299) (xy 463.810141 -383.104634)
			(xy 463.830924 -383.08788) (xy 463.839695 -383.080327) (xy 463.849872 -383.059561) (xy 463.850482 -383.048002)
			(xy 463.850482 -382.967738) (xy 463.849896 -382.956172) (xy 463.839713 -382.9354) (xy 463.830924 -382.92786)
			(xy 463.810113 -382.911141) (xy 463.772985 -382.872782) (xy 463.741567 -382.829623) (xy 463.716471 -382.782505)
			(xy 463.698188 -382.73235) (xy 463.687074 -382.680135) (xy 463.683347 -382.626882) (xy 463.687079 -382.573628)
			(xy 463.698198 -382.521415) (xy 463.716486 -382.471261) (xy 463.741587 -382.424146) (xy 463.773009 -382.38099)
			(xy 463.810141 -382.342634) (xy 463.830924 -382.32588) (xy 463.839695 -382.318327) (xy 463.849872 -382.297561)
			(xy 463.850482 -382.286002) (xy 463.850482 -382.205738) (xy 463.849896 -382.194172) (xy 463.839713 -382.1734)
			(xy 463.830924 -382.16586) (xy 463.808426 -382.147685) (xy 463.768691 -382.105663) (xy 463.735753 -382.058125)
			(xy 463.710367 -382.00616) (xy 463.693114 -381.950959) (xy 463.68439 -381.893787) (xy 463.683858 -381.86487)
			(xy 463.684344 -381.837619) (xy 463.6921 -381.783671) (xy 463.707455 -381.731376) (xy 463.730097 -381.681799)
			(xy 463.759563 -381.635949) (xy 463.795254 -381.594758) (xy 463.836445 -381.559067) (xy 463.882295 -381.529601)
			(xy 463.931872 -381.506959) (xy 463.984167 -381.491604) (xy 464.038115 -381.483848) (xy 464.092617 -381.483848)
			(xy 464.146565 -381.491604) (xy 464.19886 -381.506959) (xy 464.248437 -381.529601) (xy 464.294287 -381.559067)
			(xy 464.335478 -381.594758) (xy 464.371169 -381.635949) (xy 464.400635 -381.681799) (xy 464.423277 -381.731376)
			(xy 464.438632 -381.783671) (xy 464.446388 -381.837619) (xy 464.446874 -381.86487) (xy 464.446344 -381.893787)
			(xy 464.437619 -381.950958) (xy 464.420364 -382.006157) (xy 464.394974 -382.058119) (xy 464.362032 -382.105653)
			(xy 464.322293 -382.14767) (xy 464.299808 -382.16586) (xy 464.29107 -382.173445) (xy 464.280873 -382.194186)
			(xy 464.28025 -382.205738) (xy 464.28025 -382.286002) (xy 464.280802 -382.297573) (xy 464.291008 -382.318345)
			(xy 464.299808 -382.32588) (xy 464.320563 -382.342668) (xy 464.357696 -382.381016) (xy 464.38912 -382.424166)
			(xy 464.414222 -382.471275) (xy 464.432511 -382.521424) (xy 464.443631 -382.573632) (xy 464.447363 -382.626882)
			(xy 464.443636 -382.680131) (xy 464.432521 -382.732341) (xy 464.414237 -382.782491) (xy 464.389139 -382.829603)
			(xy 464.357719 -382.872756) (xy 464.32059 -382.911107) (xy 464.299808 -382.92786) (xy 464.29107 -382.935445)
			(xy 464.280873 -382.956186) (xy 464.28025 -382.967738) (xy 464.28025 -383.048002) (xy 464.280802 -383.059573)
			(xy 464.291008 -383.080345) (xy 464.299808 -383.08788) (xy 464.320563 -383.104668) (xy 464.357696 -383.143016)
			(xy 464.38912 -383.186166) (xy 464.414222 -383.233275) (xy 464.432511 -383.283424) (xy 464.443631 -383.335632)
			(xy 464.447363 -383.388882) (xy 464.443636 -383.442131) (xy 464.432521 -383.494341) (xy 464.414237 -383.544491)
			(xy 464.389139 -383.591603) (xy 464.357719 -383.634756) (xy 464.32059 -383.673107) (xy 464.299808 -383.68986)
			(xy 464.29107 -383.697445) (xy 464.280873 -383.718186) (xy 464.28025 -383.729738) (xy 464.28025 -383.810002)
			(xy 464.280802 -383.821573) (xy 464.291008 -383.842345) (xy 464.299808 -383.84988) (xy 464.322284 -383.86808)
			(xy 464.362019 -383.910098) (xy 464.394959 -383.957631) (xy 464.420348 -384.009591) (xy 464.437606 -384.064787)
			(xy 464.446338 -384.121955) (xy 464.446874 -384.15087) (xy 464.446388 -384.178121) (xy 464.438632 -384.232069)
			(xy 464.423277 -384.284364) (xy 464.400635 -384.333941) (xy 464.371169 -384.379791) (xy 464.335478 -384.420982)
			(xy 464.294287 -384.456673) (xy 464.248437 -384.486139) (xy 464.19886 -384.508781) (xy 464.146565 -384.524136)
			(xy 464.092617 -384.531892) (xy 464.038115 -384.531892) (xy 463.984167 -384.524136) (xy 463.931872 -384.508781)
			(xy 463.882295 -384.486139) (xy 463.836445 -384.456673) (xy 463.795254 -384.420982) (xy 463.759563 -384.379791)
			(xy 463.730097 -384.333941) (xy 463.707455 -384.284364) (xy 463.6921 -384.232069) (xy 463.684344 -384.178121)
			(xy 463.683858 -384.15087) (xy 463.684405 -384.121954) (xy 463.693125 -384.064783) (xy 463.710376 -384.009584)
			(xy 463.735762 -383.957622) (xy 463.768702 -383.910087) (xy 463.80844 -383.86807) (xy 463.830924 -383.84988)
			(xy 463.839695 -383.842327) (xy 463.849872 -383.821561) (xy 463.850482 -383.810002) (xy 463.850482 -383.729738)
			(xy 463.849896 -383.718172) (xy 463.839713 -383.6974) (xy 463.830924 -383.68986) (xy 463.810113 -383.673141)
			(xy 463.772985 -383.634782) (xy 463.741567 -383.591623) (xy 463.716471 -383.544505) (xy 463.698188 -383.49435)
			(xy 463.687074 -383.442135) (xy 463.683347 -383.388882) (xy 460.637363 -383.388882) (xy 460.633636 -383.442131)
			(xy 460.622521 -383.494341) (xy 460.604237 -383.544491) (xy 460.579139 -383.591603) (xy 460.547719 -383.634756)
			(xy 460.51059 -383.673107) (xy 460.489808 -383.68986) (xy 460.48107 -383.697445) (xy 460.470873 -383.718186)
			(xy 460.47025 -383.729738) (xy 460.47025 -383.810002) (xy 460.470802 -383.821573) (xy 460.481008 -383.842345)
			(xy 460.489808 -383.84988) (xy 460.512284 -383.86808) (xy 460.552019 -383.910098) (xy 460.584959 -383.957631)
			(xy 460.610348 -384.009591) (xy 460.627606 -384.064787) (xy 460.636338 -384.121955) (xy 460.636874 -384.15087)
			(xy 460.636388 -384.178121) (xy 460.628632 -384.232069) (xy 460.613277 -384.284364) (xy 460.590635 -384.333941)
			(xy 460.561169 -384.379791) (xy 460.525478 -384.420982) (xy 460.484287 -384.456673) (xy 460.438437 -384.486139)
			(xy 460.38886 -384.508781) (xy 460.336565 -384.524136) (xy 460.282617 -384.531892) (xy 460.228115 -384.531892)
			(xy 460.174167 -384.524136) (xy 460.121872 -384.508781) (xy 460.072295 -384.486139) (xy 460.026445 -384.456673)
			(xy 459.985254 -384.420982) (xy 459.949563 -384.379791) (xy 459.920097 -384.333941) (xy 459.897455 -384.284364)
			(xy 459.8821 -384.232069) (xy 459.874344 -384.178121) (xy 459.873858 -384.15087) (xy 459.874405 -384.121954)
			(xy 459.883125 -384.064783) (xy 459.900376 -384.009584) (xy 459.925762 -383.957622) (xy 459.958702 -383.910087)
			(xy 459.99844 -383.86807) (xy 460.020924 -383.84988) (xy 460.029695 -383.842327) (xy 460.039872 -383.821561)
			(xy 460.040482 -383.810002) (xy 460.040482 -383.729738) (xy 460.039896 -383.718172) (xy 460.029713 -383.6974)
			(xy 460.020924 -383.68986) (xy 460.000113 -383.673141) (xy 459.962985 -383.634782) (xy 459.931567 -383.591623)
			(xy 459.906471 -383.544505) (xy 459.888188 -383.49435) (xy 459.877074 -383.442135) (xy 459.873347 -383.388882)
			(xy 458.351363 -383.388882) (xy 458.347636 -383.442131) (xy 458.336521 -383.494341) (xy 458.318237 -383.544491)
			(xy 458.293139 -383.591603) (xy 458.261719 -383.634756) (xy 458.22459 -383.673107) (xy 458.203808 -383.68986)
			(xy 458.19507 -383.697445) (xy 458.184873 -383.718186) (xy 458.18425 -383.729738) (xy 458.18425 -383.810002)
			(xy 458.184802 -383.821573) (xy 458.195008 -383.842345) (xy 458.203808 -383.84988) (xy 458.226284 -383.86808)
			(xy 458.266019 -383.910098) (xy 458.298959 -383.957631) (xy 458.324348 -384.009591) (xy 458.341606 -384.064787)
			(xy 458.350338 -384.121955) (xy 458.350874 -384.15087) (xy 458.350388 -384.178121) (xy 458.342632 -384.232069)
			(xy 458.327277 -384.284364) (xy 458.304635 -384.333941) (xy 458.275169 -384.379791) (xy 458.239478 -384.420982)
			(xy 458.198287 -384.456673) (xy 458.152437 -384.486139) (xy 458.10286 -384.508781) (xy 458.050565 -384.524136)
			(xy 457.996617 -384.531892) (xy 457.942115 -384.531892) (xy 457.888167 -384.524136) (xy 457.835872 -384.508781)
			(xy 457.786295 -384.486139) (xy 457.740445 -384.456673) (xy 457.699254 -384.420982) (xy 457.663563 -384.379791)
			(xy 457.634097 -384.333941) (xy 457.611455 -384.284364) (xy 457.5961 -384.232069) (xy 457.588344 -384.178121)
			(xy 457.587858 -384.15087) (xy 457.588405 -384.121954) (xy 457.597125 -384.064783) (xy 457.614376 -384.009584)
			(xy 457.639762 -383.957622) (xy 457.672702 -383.910087) (xy 457.71244 -383.86807) (xy 457.734924 -383.84988)
			(xy 457.743695 -383.842327) (xy 457.753872 -383.821561) (xy 457.754482 -383.810002) (xy 457.754482 -383.729738)
			(xy 457.753896 -383.718172) (xy 457.743713 -383.6974) (xy 457.734924 -383.68986) (xy 457.714113 -383.673141)
			(xy 457.676985 -383.634782) (xy 457.645567 -383.591623) (xy 457.620471 -383.544505) (xy 457.602188 -383.49435)
			(xy 457.591074 -383.442135) (xy 457.587347 -383.388882) (xy 454.541363 -383.388882) (xy 454.537636 -383.442131)
			(xy 454.526521 -383.494341) (xy 454.508237 -383.544491) (xy 454.483139 -383.591603) (xy 454.451719 -383.634756)
			(xy 454.41459 -383.673107) (xy 454.393808 -383.68986) (xy 454.38507 -383.697445) (xy 454.374873 -383.718186)
			(xy 454.37425 -383.729738) (xy 454.37425 -383.810002) (xy 454.374802 -383.821573) (xy 454.385008 -383.842345)
			(xy 454.393808 -383.84988) (xy 454.416284 -383.86808) (xy 454.456019 -383.910098) (xy 454.488959 -383.957631)
			(xy 454.514348 -384.009591) (xy 454.531606 -384.064787) (xy 454.540338 -384.121955) (xy 454.540874 -384.15087)
			(xy 454.540388 -384.178121) (xy 454.532632 -384.232069) (xy 454.517277 -384.284364) (xy 454.494635 -384.333941)
			(xy 454.465169 -384.379791) (xy 454.429478 -384.420982) (xy 454.388287 -384.456673) (xy 454.342437 -384.486139)
			(xy 454.29286 -384.508781) (xy 454.240565 -384.524136) (xy 454.186617 -384.531892) (xy 454.132115 -384.531892)
			(xy 454.078167 -384.524136) (xy 454.025872 -384.508781) (xy 453.976295 -384.486139) (xy 453.930445 -384.456673)
			(xy 453.889254 -384.420982) (xy 453.853563 -384.379791) (xy 453.824097 -384.333941) (xy 453.801455 -384.284364)
			(xy 453.7861 -384.232069) (xy 453.778344 -384.178121) (xy 453.777858 -384.15087) (xy 453.778405 -384.121954)
			(xy 453.787125 -384.064783) (xy 453.804376 -384.009584) (xy 453.829762 -383.957622) (xy 453.862702 -383.910087)
			(xy 453.90244 -383.86807) (xy 453.924924 -383.84988) (xy 453.933695 -383.842327) (xy 453.943872 -383.821561)
			(xy 453.944482 -383.810002) (xy 453.944482 -383.729738) (xy 453.943896 -383.718172) (xy 453.933713 -383.6974)
			(xy 453.924924 -383.68986) (xy 453.904113 -383.673141) (xy 453.866985 -383.634782) (xy 453.835567 -383.591623)
			(xy 453.810471 -383.544505) (xy 453.792188 -383.49435) (xy 453.781074 -383.442135) (xy 453.777347 -383.388882)
			(xy 452.255363 -383.388882) (xy 452.251636 -383.442131) (xy 452.240521 -383.494341) (xy 452.222237 -383.544491)
			(xy 452.197139 -383.591603) (xy 452.165719 -383.634756) (xy 452.12859 -383.673107) (xy 452.107808 -383.68986)
			(xy 452.09907 -383.697445) (xy 452.088873 -383.718186) (xy 452.08825 -383.729738) (xy 452.08825 -383.810002)
			(xy 452.088802 -383.821573) (xy 452.099008 -383.842345) (xy 452.107808 -383.84988) (xy 452.130284 -383.86808)
			(xy 452.170019 -383.910098) (xy 452.202959 -383.957631) (xy 452.228348 -384.009591) (xy 452.245606 -384.064787)
			(xy 452.254338 -384.121955) (xy 452.254874 -384.15087) (xy 452.254388 -384.178121) (xy 452.246632 -384.232069)
			(xy 452.231277 -384.284364) (xy 452.208635 -384.333941) (xy 452.179169 -384.379791) (xy 452.143478 -384.420982)
			(xy 452.102287 -384.456673) (xy 452.056437 -384.486139) (xy 452.00686 -384.508781) (xy 451.954565 -384.524136)
			(xy 451.900617 -384.531892) (xy 451.846115 -384.531892) (xy 451.792167 -384.524136) (xy 451.739872 -384.508781)
			(xy 451.690295 -384.486139) (xy 451.644445 -384.456673) (xy 451.603254 -384.420982) (xy 451.567563 -384.379791)
			(xy 451.538097 -384.333941) (xy 451.515455 -384.284364) (xy 451.5001 -384.232069) (xy 451.492344 -384.178121)
			(xy 451.491858 -384.15087) (xy 451.492405 -384.121954) (xy 451.501125 -384.064783) (xy 451.518376 -384.009584)
			(xy 451.543762 -383.957622) (xy 451.576702 -383.910087) (xy 451.61644 -383.86807) (xy 451.638924 -383.84988)
			(xy 451.647695 -383.842327) (xy 451.657872 -383.821561) (xy 451.658482 -383.810002) (xy 451.658482 -383.729738)
			(xy 451.657896 -383.718172) (xy 451.647713 -383.6974) (xy 451.638924 -383.68986) (xy 451.618113 -383.673141)
			(xy 451.580985 -383.634782) (xy 451.549567 -383.591623) (xy 451.524471 -383.544505) (xy 451.506188 -383.49435)
			(xy 451.495074 -383.442135) (xy 451.491347 -383.388882) (xy 448.445363 -383.388882) (xy 448.441636 -383.442131)
			(xy 448.430521 -383.494341) (xy 448.412237 -383.544491) (xy 448.387139 -383.591603) (xy 448.355719 -383.634756)
			(xy 448.31859 -383.673107) (xy 448.297808 -383.68986) (xy 448.28907 -383.697445) (xy 448.278873 -383.718186)
			(xy 448.27825 -383.729738) (xy 448.27825 -383.810002) (xy 448.278802 -383.821573) (xy 448.289008 -383.842345)
			(xy 448.297808 -383.84988) (xy 448.320284 -383.86808) (xy 448.360019 -383.910098) (xy 448.392959 -383.957631)
			(xy 448.418348 -384.009591) (xy 448.435606 -384.064787) (xy 448.444338 -384.121955) (xy 448.444874 -384.15087)
			(xy 448.444388 -384.178121) (xy 448.436632 -384.232069) (xy 448.421277 -384.284364) (xy 448.398635 -384.333941)
			(xy 448.369169 -384.379791) (xy 448.333478 -384.420982) (xy 448.292287 -384.456673) (xy 448.246437 -384.486139)
			(xy 448.19686 -384.508781) (xy 448.144565 -384.524136) (xy 448.090617 -384.531892) (xy 448.036115 -384.531892)
			(xy 447.982167 -384.524136) (xy 447.929872 -384.508781) (xy 447.880295 -384.486139) (xy 447.834445 -384.456673)
			(xy 447.793254 -384.420982) (xy 447.757563 -384.379791) (xy 447.728097 -384.333941) (xy 447.705455 -384.284364)
			(xy 447.6901 -384.232069) (xy 447.682344 -384.178121) (xy 447.681858 -384.15087) (xy 447.682405 -384.121954)
			(xy 447.691125 -384.064783) (xy 447.708376 -384.009584) (xy 447.733762 -383.957622) (xy 447.766702 -383.910087)
			(xy 447.80644 -383.86807) (xy 447.828924 -383.84988) (xy 447.837695 -383.842327) (xy 447.847872 -383.821561)
			(xy 447.848482 -383.810002) (xy 447.848482 -383.729738) (xy 447.847896 -383.718172) (xy 447.837713 -383.6974)
			(xy 447.828924 -383.68986) (xy 447.808113 -383.673141) (xy 447.770985 -383.634782) (xy 447.739567 -383.591623)
			(xy 447.714471 -383.544505) (xy 447.696188 -383.49435) (xy 447.685074 -383.442135) (xy 447.681347 -383.388882)
			(xy 446.489563 -383.388882) (xy 446.485836 -383.442131) (xy 446.474721 -383.494341) (xy 446.456437 -383.544491)
			(xy 446.431339 -383.591603) (xy 446.399919 -383.634756) (xy 446.36279 -383.673107) (xy 446.342008 -383.68986)
			(xy 446.33327 -383.697445) (xy 446.323073 -383.718186) (xy 446.32245 -383.729738) (xy 446.32245 -383.810002)
			(xy 446.323002 -383.821573) (xy 446.333208 -383.842345) (xy 446.342008 -383.84988) (xy 446.364484 -383.86808)
			(xy 446.404219 -383.910098) (xy 446.437159 -383.957631) (xy 446.462548 -384.009591) (xy 446.479806 -384.064787)
			(xy 446.488538 -384.121955) (xy 446.489074 -384.15087) (xy 446.488588 -384.178121) (xy 446.480832 -384.232069)
			(xy 446.465477 -384.284364) (xy 446.442835 -384.333941) (xy 446.413369 -384.379791) (xy 446.377678 -384.420982)
			(xy 446.336487 -384.456673) (xy 446.290637 -384.486139) (xy 446.24106 -384.508781) (xy 446.188765 -384.524136)
			(xy 446.134817 -384.531892) (xy 446.080315 -384.531892) (xy 446.026367 -384.524136) (xy 445.974072 -384.508781)
			(xy 445.924495 -384.486139) (xy 445.878645 -384.456673) (xy 445.837454 -384.420982) (xy 445.801763 -384.379791)
			(xy 445.772297 -384.333941) (xy 445.749655 -384.284364) (xy 445.7343 -384.232069) (xy 445.726544 -384.178121)
			(xy 445.726058 -384.15087) (xy 445.726605 -384.121954) (xy 445.735325 -384.064783) (xy 445.752576 -384.009584)
			(xy 445.777962 -383.957622) (xy 445.810902 -383.910087) (xy 445.85064 -383.86807) (xy 445.873124 -383.84988)
			(xy 445.881895 -383.842327) (xy 445.892072 -383.821561) (xy 445.892682 -383.810002) (xy 445.892682 -383.729738)
			(xy 445.892096 -383.718172) (xy 445.881913 -383.6974) (xy 445.873124 -383.68986) (xy 445.852313 -383.673141)
			(xy 445.815185 -383.634782) (xy 445.783767 -383.591623) (xy 445.758671 -383.544505) (xy 445.740388 -383.49435)
			(xy 445.729274 -383.442135) (xy 445.725547 -383.388882) (xy 442.679563 -383.388882) (xy 442.675836 -383.442131)
			(xy 442.664721 -383.494341) (xy 442.646437 -383.544491) (xy 442.621339 -383.591603) (xy 442.589919 -383.634756)
			(xy 442.55279 -383.673107) (xy 442.532008 -383.68986) (xy 442.52327 -383.697445) (xy 442.513073 -383.718186)
			(xy 442.51245 -383.729738) (xy 442.51245 -383.810002) (xy 442.513002 -383.821573) (xy 442.523208 -383.842345)
			(xy 442.532008 -383.84988) (xy 442.554484 -383.86808) (xy 442.594219 -383.910098) (xy 442.627159 -383.957631)
			(xy 442.652548 -384.009591) (xy 442.669806 -384.064787) (xy 442.678538 -384.121955) (xy 442.679074 -384.15087)
			(xy 442.678588 -384.178121) (xy 442.670832 -384.232069) (xy 442.655477 -384.284364) (xy 442.632835 -384.333941)
			(xy 442.603369 -384.379791) (xy 442.567678 -384.420982) (xy 442.526487 -384.456673) (xy 442.480637 -384.486139)
			(xy 442.43106 -384.508781) (xy 442.378765 -384.524136) (xy 442.324817 -384.531892) (xy 442.270315 -384.531892)
			(xy 442.216367 -384.524136) (xy 442.164072 -384.508781) (xy 442.114495 -384.486139) (xy 442.068645 -384.456673)
			(xy 442.027454 -384.420982) (xy 441.991763 -384.379791) (xy 441.962297 -384.333941) (xy 441.939655 -384.284364)
			(xy 441.9243 -384.232069) (xy 441.916544 -384.178121) (xy 441.916058 -384.15087) (xy 441.916605 -384.121954)
			(xy 441.925325 -384.064783) (xy 441.942576 -384.009584) (xy 441.967962 -383.957622) (xy 442.000902 -383.910087)
			(xy 442.04064 -383.86807) (xy 442.063124 -383.84988) (xy 442.071895 -383.842327) (xy 442.082072 -383.821561)
			(xy 442.082682 -383.810002) (xy 442.082682 -383.729738) (xy 442.082096 -383.718172) (xy 442.071913 -383.6974)
			(xy 442.063124 -383.68986) (xy 442.042313 -383.673141) (xy 442.005185 -383.634782) (xy 441.973767 -383.591623)
			(xy 441.948671 -383.544505) (xy 441.930388 -383.49435) (xy 441.919274 -383.442135) (xy 441.915547 -383.388882)
			(xy 438.98058 -383.388882) (xy 438.98058 -385.039108) (xy 447.973196 -385.039108) (xy 447.973663 -385.011855)
			(xy 447.981419 -384.957904) (xy 447.996774 -384.905606) (xy 448.019416 -384.856026) (xy 448.048883 -384.810172)
			(xy 448.084577 -384.76898) (xy 448.125769 -384.733286) (xy 448.171622 -384.703818) (xy 448.221202 -384.681175)
			(xy 448.2735 -384.66582) (xy 448.327451 -384.658063) (xy 448.354704 -384.6576) (xy 448.383621 -384.658116)
			(xy 448.440792 -384.666845) (xy 448.495991 -384.684104) (xy 448.547953 -384.709496) (xy 448.595487 -384.74244)
			(xy 448.637504 -384.782181) (xy 448.655694 -384.804666) (xy 448.663251 -384.813432) (xy 448.684014 -384.82361)
			(xy 448.695572 -384.824224) (xy 448.775836 -384.824224) (xy 448.787403 -384.823643) (xy 448.808176 -384.813459)
			(xy 448.815714 -384.804666) (xy 448.833889 -384.782169) (xy 448.875913 -384.742436) (xy 448.923451 -384.7095)
			(xy 448.975416 -384.684114) (xy 449.030616 -384.66686) (xy 449.087787 -384.658134) (xy 449.116704 -384.6576)
			(xy 449.145443 -384.658121) (xy 449.20227 -384.666744) (xy 449.257161 -384.683795) (xy 449.308873 -384.708887)
			(xy 449.356235 -384.741453) (xy 449.377562 -384.760724) (xy 449.384674 -384.767328) (xy 449.4022 -384.77444)
			(xy 449.491608 -384.77444) (xy 449.509134 -384.767328) (xy 449.516246 -384.760724) (xy 449.537569 -384.741449)
			(xy 449.584933 -384.708884) (xy 449.636645 -384.683792) (xy 449.691537 -384.666743) (xy 449.748365 -384.658121)
			(xy 449.777104 -384.6576) (xy 449.804357 -384.658052) (xy 449.858309 -384.665809) (xy 449.910608 -384.681166)
			(xy 449.960188 -384.70381) (xy 450.006042 -384.733279) (xy 450.047235 -384.768974) (xy 450.082928 -384.810168)
			(xy 450.112396 -384.856022) (xy 450.135038 -384.905604) (xy 450.150393 -384.957903) (xy 450.158149 -385.011855)
			(xy 450.158612 -385.039108) (xy 450.158178 -385.06581) (xy 450.150724 -385.11869) (xy 450.135962 -385.170013)
			(xy 450.114183 -385.218773) (xy 450.085811 -385.264017) (xy 450.06895 -385.284726) (xy 450.062854 -385.292092)
			(xy 450.056758 -385.310126) (xy 450.060568 -385.397756) (xy 450.068188 -385.415282) (xy 450.074792 -385.421886)
			(xy 450.095606 -385.443472) (xy 450.130859 -385.491977) (xy 450.158087 -385.545401) (xy 450.176618 -385.602428)
			(xy 450.185997 -385.661653) (xy 450.186552 -385.691634) (xy 450.186008 -385.720693) (xy 450.177172 -385.778134)
			(xy 450.159725 -385.833571) (xy 450.134071 -385.88572) (xy 450.100803 -385.933374) (xy 450.081142 -385.954778)
			(xy 450.074538 -385.96189) (xy 450.067172 -385.979924) (xy 450.067172 -386.06984) (xy 450.074538 -386.087874)
			(xy 450.081142 -386.094986) (xy 450.100804 -386.116391) (xy 450.134085 -386.164037) (xy 450.159743 -386.216185)
			(xy 450.177186 -386.271625) (xy 450.186007 -386.329071) (xy 450.186552 -386.35813) (xy 450.186034 -386.386232)
			(xy 450.18508 -386.392674) (xy 450.3547 -386.392674) (xy 450.355208 -386.363935) (xy 450.363834 -386.307106)
			(xy 450.380888 -386.252216) (xy 450.405983 -386.200504) (xy 450.438552 -386.153142) (xy 450.457824 -386.131816)
			(xy 450.464428 -386.124704) (xy 450.47154 -386.107178) (xy 450.47154 -386.01777) (xy 450.464428 -386.000244)
			(xy 450.457824 -385.993132) (xy 450.438527 -385.971828) (xy 450.405963 -385.924461) (xy 450.380873 -385.872746)
			(xy 450.363825 -385.817852) (xy 450.355205 -385.761021) (xy 450.355207 -385.703541) (xy 450.363833 -385.646711)
			(xy 450.380887 -385.591819) (xy 450.405982 -385.540106) (xy 450.438551 -385.492743) (xy 450.457824 -385.471416)
			(xy 450.464428 -385.464304) (xy 450.47154 -385.446778) (xy 450.47154 -385.35737) (xy 450.464428 -385.339844)
			(xy 450.457824 -385.332732) (xy 450.438539 -385.311418) (xy 450.405975 -385.264052) (xy 450.380885 -385.212337)
			(xy 450.363838 -385.157444) (xy 450.355219 -385.100614) (xy 450.3547 -385.071874) (xy 450.355154 -385.044622)
			(xy 450.362914 -384.990672) (xy 450.378273 -384.938377) (xy 450.400917 -384.888799) (xy 450.430387 -384.842948)
			(xy 450.466082 -384.801758) (xy 450.507275 -384.766067) (xy 450.553129 -384.736601) (xy 450.602709 -384.713961)
			(xy 450.655006 -384.698607) (xy 450.708956 -384.690851) (xy 450.736208 -384.690366) (xy 450.764947 -384.690894)
			(xy 450.821773 -384.699517) (xy 450.876664 -384.716566) (xy 450.928376 -384.741657) (xy 450.975739 -384.77422)
			(xy 450.997066 -384.79349) (xy 451.004178 -384.800094) (xy 451.021704 -384.807206) (xy 451.111112 -384.807206)
			(xy 451.128638 -384.800094) (xy 451.13575 -384.79349) (xy 451.157082 -384.774224) (xy 451.204442 -384.741656)
			(xy 451.256152 -384.716561) (xy 451.311042 -384.69951) (xy 451.367869 -384.690887) (xy 451.396608 -384.690366)
			(xy 451.42367 -384.690813) (xy 451.477248 -384.69848) (xy 451.529203 -384.713646) (xy 451.578493 -384.736004)
			(xy 451.624126 -384.765107) (xy 451.665187 -384.800369) (xy 451.683374 -384.820414) (xy 451.690944 -384.828277)
			(xy 451.710823 -384.83723) (xy 451.721728 -384.837686) (xy 451.797928 -384.837686) (xy 451.808828 -384.83722)
			(xy 451.828698 -384.828258) (xy 451.836282 -384.820414) (xy 451.854456 -384.800357) (xy 451.895516 -384.765093)
			(xy 451.941151 -384.735992) (xy 451.990445 -384.71364) (xy 452.042405 -384.698487) (xy 452.095986 -384.690836)
			(xy 452.123048 -384.690366) (xy 452.150299 -384.690833) (xy 452.204246 -384.698595) (xy 452.25654 -384.713955)
			(xy 452.306115 -384.7366) (xy 452.351964 -384.766069) (xy 452.393153 -384.801762) (xy 452.428844 -384.842953)
			(xy 452.45831 -384.888804) (xy 452.480952 -384.938381) (xy 452.496309 -384.990675) (xy 452.504068 -385.044623)
			(xy 452.504556 -385.071874) (xy 452.504001 -385.100612) (xy 452.495384 -385.157437) (xy 452.47834 -385.212327)
			(xy 452.453256 -385.264039) (xy 452.420699 -385.311403) (xy 452.401432 -385.332732) (xy 452.394828 -385.339844)
			(xy 452.387716 -385.35737) (xy 452.387716 -385.446778) (xy 452.394828 -385.464304) (xy 452.401432 -385.471416)
			(xy 452.420675 -385.492766) (xy 452.453236 -385.540126) (xy 452.478325 -385.591835) (xy 452.495374 -385.646721)
			(xy 452.503998 -385.703544) (xy 452.504001 -385.761018) (xy 452.495383 -385.817842) (xy 452.478339 -385.87273)
			(xy 452.453255 -385.924441) (xy 452.420698 -385.971804) (xy 452.401432 -385.993132) (xy 452.394828 -386.000244)
			(xy 452.387716 -386.01777) (xy 452.387716 -386.107178) (xy 452.394828 -386.124704) (xy 452.401432 -386.131816)
			(xy 452.420675 -386.153166) (xy 452.453236 -386.200526) (xy 452.478325 -386.252235) (xy 452.495374 -386.307121)
			(xy 452.503998 -386.363944) (xy 452.504001 -386.421418) (xy 452.495383 -386.478242) (xy 452.478339 -386.53313)
			(xy 452.453255 -386.584841) (xy 452.420698 -386.632204) (xy 452.401432 -386.653532) (xy 452.394574 -386.660898)
			(xy 452.387716 -386.678678) (xy 452.388478 -386.768848) (xy 452.395844 -386.786882) (xy 452.402956 -386.793994)
			(xy 452.423192 -386.815485) (xy 452.457414 -386.86358) (xy 452.48382 -386.916372) (xy 452.50178 -386.972601)
			(xy 452.510866 -387.030926) (xy 452.511414 -387.06044) (xy 452.510909 -387.087809) (xy 452.5031 -387.141986)
			(xy 452.48762 -387.194489) (xy 452.464787 -387.244236) (xy 452.435071 -387.290205) (xy 452.417434 -387.311138)
			(xy 452.411338 -387.31825) (xy 452.404988 -387.335268) (xy 452.404988 -387.420612) (xy 452.411338 -387.43763)
			(xy 452.417434 -387.444742) (xy 452.435065 -387.465681) (xy 452.464777 -387.511652) (xy 452.487614 -387.561398)
			(xy 452.503107 -387.613897) (xy 452.503953 -387.619748) (xy 455.361802 -387.619748) (xy 455.362294 -387.591008)
			(xy 455.370924 -387.534179) (xy 455.387981 -387.479288) (xy 455.41308 -387.427577) (xy 455.445652 -387.380216)
			(xy 455.464926 -387.35889) (xy 455.47153 -387.351778) (xy 455.478642 -387.334252) (xy 455.478642 -387.244844)
			(xy 455.47153 -387.227318) (xy 455.464926 -387.220206) (xy 455.445703 -387.198838) (xy 455.413136 -387.151483)
			(xy 455.388041 -387.099778) (xy 455.370988 -387.044893) (xy 455.362361 -386.988071) (xy 455.362355 -386.930599)
			(xy 455.370972 -386.873775) (xy 455.388016 -386.818888) (xy 455.4131 -386.767178) (xy 455.445659 -386.719817)
			(xy 455.464926 -386.69849) (xy 455.47153 -386.691378) (xy 455.478642 -386.673852) (xy 455.478642 -386.584444)
			(xy 455.47153 -386.566918) (xy 455.464926 -386.559806) (xy 455.445703 -386.538438) (xy 455.413136 -386.491083)
			(xy 455.388041 -386.439378) (xy 455.370988 -386.384493) (xy 455.362361 -386.327671) (xy 455.362355 -386.270199)
			(xy 455.370972 -386.213375) (xy 455.388016 -386.158488) (xy 455.4131 -386.106778) (xy 455.445659 -386.059417)
			(xy 455.464926 -386.03809) (xy 455.47153 -386.030978) (xy 455.478642 -386.013452) (xy 455.478642 -385.924044)
			(xy 455.47153 -385.906518) (xy 455.464926 -385.899406) (xy 455.445629 -385.878102) (xy 455.413066 -385.830734)
			(xy 455.387979 -385.779016) (xy 455.370935 -385.72412) (xy 455.362319 -385.667289) (xy 455.361802 -385.638548)
			(xy 455.3623 -385.611296) (xy 455.370051 -385.557346) (xy 455.385401 -385.505048) (xy 455.408039 -385.455467)
			(xy 455.437503 -385.409613) (xy 455.473193 -385.36842) (xy 455.514383 -385.332725) (xy 455.560234 -385.303257)
			(xy 455.609812 -385.280614) (xy 455.662108 -385.265259) (xy 455.716058 -385.257503) (xy 455.74331 -385.25704)
			(xy 455.769625 -385.257509) (xy 455.821757 -385.264732) (xy 455.8724 -385.279054) (xy 455.920594 -385.300203)
			(xy 455.965422 -385.327778) (xy 456.006034 -385.361253) (xy 456.041657 -385.399994) (xy 456.057 -385.421378)
			(xy 456.064112 -385.431538) (xy 456.085448 -385.442968) (xy 456.193144 -385.444492) (xy 456.214988 -385.43357)
			(xy 456.222354 -385.423664) (xy 456.240463 -385.399945) (xy 456.2828 -385.357892) (xy 456.33117 -385.322946)
			(xy 456.384392 -385.295959) (xy 456.441168 -385.277591) (xy 456.500112 -385.26829) (xy 456.529948 -385.267708)
			(xy 456.557716 -385.26821) (xy 456.612668 -385.276252) (xy 456.665873 -385.292172) (xy 456.71621 -385.315634)
			(xy 456.762615 -385.346145) (xy 456.783694 -385.364228) (xy 456.790552 -385.370324) (xy 456.807824 -385.377182)
			(xy 456.89393 -385.377436) (xy 456.911202 -385.370832) (xy 456.918314 -385.364736) (xy 456.939286 -385.346929)
			(xy 456.985399 -385.316922) (xy 457.035341 -385.293845) (xy 457.088079 -385.278176) (xy 457.14252 -385.27024)
			(xy 457.170028 -385.26974) (xy 457.197284 -385.270129) (xy 457.25124 -385.277891) (xy 457.303542 -385.293253)
			(xy 457.353126 -385.315902) (xy 457.398981 -385.345378) (xy 457.440175 -385.381079) (xy 457.475868 -385.42228)
			(xy 457.505334 -385.468141) (xy 457.527974 -385.517729) (xy 457.543325 -385.570034) (xy 457.551076 -385.623992)
			(xy 457.551536 -385.651248) (xy 457.551032 -385.679988) (xy 457.542403 -385.736815) (xy 457.525348 -385.791706)
			(xy 457.500252 -385.843417) (xy 457.467684 -385.890779) (xy 457.448412 -385.912106) (xy 457.441808 -385.919218)
			(xy 457.434696 -385.936744) (xy 457.434696 -386.026152) (xy 457.441808 -386.043678) (xy 457.448412 -386.05079)
			(xy 457.467729 -386.072076) (xy 457.500289 -386.119447) (xy 457.525376 -386.171165) (xy 457.542421 -386.226062)
			(xy 457.551038 -386.282894) (xy 457.551033 -386.340376) (xy 457.542405 -386.397206) (xy 457.52535 -386.4521)
			(xy 457.500254 -386.503814) (xy 457.467685 -386.551178) (xy 457.448412 -386.572506) (xy 457.441808 -386.579618)
			(xy 457.434696 -386.597144) (xy 457.434696 -386.686552) (xy 457.441808 -386.704078) (xy 457.448412 -386.71119)
			(xy 457.467729 -386.732476) (xy 457.500289 -386.779847) (xy 457.525376 -386.831565) (xy 457.542421 -386.886462)
			(xy 457.551038 -386.943294) (xy 457.551033 -387.000776) (xy 457.542405 -387.057606) (xy 457.52535 -387.1125)
			(xy 457.500254 -387.164214) (xy 457.467685 -387.211578) (xy 457.448412 -387.232906) (xy 457.441808 -387.240018)
			(xy 457.434696 -387.257544) (xy 457.434696 -387.258347) (xy 458.670706 -387.258347) (xy 458.670706 -387.203853)
			(xy 458.678461 -387.149912) (xy 458.693813 -387.097625) (xy 458.716449 -387.048054) (xy 458.74591 -387.002209)
			(xy 458.781594 -386.961023) (xy 458.822777 -386.925334) (xy 458.868619 -386.895869) (xy 458.918187 -386.873227)
			(xy 458.970473 -386.857869) (xy 459.024413 -386.850109) (xy 459.05166 -386.84962) (xy 459.080399 -386.850129)
			(xy 459.137226 -386.858758) (xy 459.192116 -386.875813) (xy 459.243828 -386.900907) (xy 459.291191 -386.933473)
			(xy 459.312518 -386.952744) (xy 459.31963 -386.959348) (xy 459.337156 -386.96646) (xy 459.426564 -386.96646)
			(xy 459.44409 -386.959348) (xy 459.451202 -386.952744) (xy 459.472546 -386.933493) (xy 459.519904 -386.900924)
			(xy 459.571611 -386.875828) (xy 459.626498 -386.858772) (xy 459.683322 -386.850144) (xy 459.71206 -386.84962)
			(xy 459.739317 -386.850024) (xy 459.793276 -386.857777) (xy 459.845583 -386.873131) (xy 459.895171 -386.895773)
			(xy 459.941033 -386.925242) (xy 459.982234 -386.960938) (xy 460.017934 -387.002135) (xy 460.047408 -387.047993)
			(xy 460.070055 -387.09758) (xy 460.085414 -387.149885) (xy 460.093173 -387.203843) (xy 460.093173 -387.258357)
			(xy 460.087696 -387.296447) (xy 460.851306 -387.296447) (xy 460.851306 -387.241953) (xy 460.859061 -387.188014)
			(xy 460.874412 -387.135727) (xy 460.897048 -387.086157) (xy 460.926507 -387.040312) (xy 460.962191 -386.999126)
			(xy 461.003372 -386.963437) (xy 461.049213 -386.933972) (xy 461.09878 -386.91133) (xy 461.151065 -386.895971)
			(xy 461.205003 -386.88821) (xy 461.23225 -386.88772) (xy 461.260989 -386.888235) (xy 461.317816 -386.896863)
			(xy 461.372706 -386.913916) (xy 461.424417 -386.939009) (xy 461.47178 -386.971574) (xy 461.493108 -386.990844)
			(xy 461.50022 -386.997448) (xy 461.517746 -387.00456) (xy 461.607154 -387.00456) (xy 461.62468 -386.997448)
			(xy 461.631792 -386.990844) (xy 461.653099 -386.971551) (xy 461.700467 -386.938987) (xy 461.752183 -386.913899)
			(xy 461.807078 -386.896854) (xy 461.86391 -386.888237) (xy 461.89265 -386.88772) (xy 461.919907 -386.888124)
			(xy 461.973868 -386.895875) (xy 462.026175 -386.911228) (xy 462.075765 -386.933869) (xy 462.121628 -386.963338)
			(xy 462.16283 -386.999035) (xy 462.198532 -387.040232) (xy 462.228007 -387.086091) (xy 462.250654 -387.135678)
			(xy 462.266014 -387.187983) (xy 462.273773 -387.241943) (xy 462.273773 -387.296457) (xy 462.266014 -387.350416)
			(xy 462.255395 -387.386576) (xy 462.824828 -387.386576) (xy 462.828899 -387.330954) (xy 462.841025 -387.276517)
			(xy 462.860948 -387.224426) (xy 462.888244 -387.175791) (xy 462.92233 -387.131648) (xy 462.962479 -387.092939)
			(xy 463.007837 -387.060488) (xy 463.057437 -387.034987) (xy 463.110221 -387.01698) (xy 463.165064 -387.00685)
			(xy 463.220798 -387.004813) (xy 463.276235 -387.010913) (xy 463.330192 -387.025019) (xy 463.381521 -387.046831)
			(xy 463.429127 -387.075885) (xy 463.471995 -387.11156) (xy 463.509212 -387.153097) (xy 463.539985 -387.19961)
			(xy 463.563657 -387.250107) (xy 463.579725 -387.303514) (xy 463.587845 -387.35869) (xy 463.588354 -387.386576)
			(xy 463.587845 -387.414462) (xy 463.579725 -387.469638) (xy 463.563657 -387.523045) (xy 463.539985 -387.573542)
			(xy 463.509212 -387.620055) (xy 463.471995 -387.661592) (xy 463.429127 -387.697267) (xy 463.381521 -387.726321)
			(xy 463.330192 -387.748133) (xy 463.276235 -387.762239) (xy 463.220798 -387.768339) (xy 463.165064 -387.766302)
			(xy 463.110221 -387.756172) (xy 463.057437 -387.738165) (xy 463.007837 -387.712664) (xy 462.962479 -387.680213)
			(xy 462.92233 -387.641504) (xy 462.888244 -387.597361) (xy 462.860948 -387.548726) (xy 462.841025 -387.496635)
			(xy 462.828899 -387.442198) (xy 462.824828 -387.386576) (xy 462.255395 -387.386576) (xy 462.250654 -387.402722)
			(xy 462.228007 -387.452309) (xy 462.198532 -387.498168) (xy 462.16283 -387.539365) (xy 462.121628 -387.575062)
			(xy 462.075765 -387.604531) (xy 462.026175 -387.627172) (xy 461.973868 -387.642525) (xy 461.919907 -387.650276)
			(xy 461.89265 -387.650736) (xy 461.86391 -387.650233) (xy 461.807083 -387.641604) (xy 461.752192 -387.624548)
			(xy 461.700481 -387.599453) (xy 461.653119 -387.566884) (xy 461.631792 -387.547612) (xy 461.62468 -387.541008)
			(xy 461.607154 -387.533896) (xy 461.517746 -387.533896) (xy 461.50022 -387.541008) (xy 461.493108 -387.547612)
			(xy 461.471794 -387.566898) (xy 461.424429 -387.599464) (xy 461.372715 -387.624555) (xy 461.317821 -387.641601)
			(xy 461.26099 -387.650219) (xy 461.23225 -387.650736) (xy 461.205003 -387.65019) (xy 461.151065 -387.642429)
			(xy 461.09878 -387.62707) (xy 461.049213 -387.604428) (xy 461.003372 -387.574963) (xy 460.962191 -387.539274)
			(xy 460.926507 -387.498088) (xy 460.897048 -387.452243) (xy 460.874412 -387.402673) (xy 460.859061 -387.350386)
			(xy 460.851306 -387.296447) (xy 460.087696 -387.296447) (xy 460.085414 -387.312315) (xy 460.070055 -387.36462)
			(xy 460.047408 -387.414207) (xy 460.017934 -387.460065) (xy 459.982234 -387.501262) (xy 459.941033 -387.536958)
			(xy 459.895171 -387.566427) (xy 459.845583 -387.589069) (xy 459.793276 -387.604423) (xy 459.739317 -387.612176)
			(xy 459.71206 -387.612636) (xy 459.683321 -387.612127) (xy 459.626493 -387.603499) (xy 459.571603 -387.586445)
			(xy 459.519891 -387.561351) (xy 459.472529 -387.528783) (xy 459.451202 -387.509512) (xy 459.44409 -387.502908)
			(xy 459.426564 -387.495796) (xy 459.337156 -387.495796) (xy 459.31963 -387.502908) (xy 459.312518 -387.509512)
			(xy 459.2912 -387.528793) (xy 459.243836 -387.56136) (xy 459.192123 -387.586451) (xy 459.137229 -387.603499)
			(xy 459.0804 -387.612118) (xy 459.05166 -387.612636) (xy 459.024413 -387.612091) (xy 458.970473 -387.604331)
			(xy 458.918187 -387.588973) (xy 458.868619 -387.566331) (xy 458.822777 -387.536866) (xy 458.781594 -387.501177)
			(xy 458.74591 -387.459991) (xy 458.716449 -387.414146) (xy 458.693813 -387.364575) (xy 458.678461 -387.312288)
			(xy 458.670706 -387.258347) (xy 457.434696 -387.258347) (xy 457.434696 -387.346952) (xy 457.441808 -387.364478)
			(xy 457.448412 -387.37159) (xy 457.467697 -387.392905) (xy 457.500263 -387.440269) (xy 457.525354 -387.491984)
			(xy 457.542401 -387.546878) (xy 457.551018 -387.603708) (xy 457.551536 -387.632448) (xy 457.551061 -387.659007)
			(xy 457.543703 -387.711613) (xy 457.529123 -387.762691) (xy 457.507601 -387.811254) (xy 457.479554 -387.856364)
			(xy 457.46289 -387.87705) (xy 457.45654 -387.884416) (xy 457.450698 -387.90245) (xy 457.454508 -387.989826)
			(xy 457.462128 -388.007098) (xy 457.468732 -388.013956) (xy 457.489405 -388.035575) (xy 457.524504 -388.084004)
			(xy 457.542741 -388.119874) (xy 457.846428 -388.119874) (xy 457.850499 -388.064252) (xy 457.862625 -388.009815)
			(xy 457.882548 -387.957724) (xy 457.909844 -387.909089) (xy 457.94393 -387.864946) (xy 457.984079 -387.826237)
			(xy 458.029437 -387.793786) (xy 458.079037 -387.768285) (xy 458.131821 -387.750278) (xy 458.186664 -387.740148)
			(xy 458.242398 -387.738111) (xy 458.297835 -387.744211) (xy 458.351792 -387.758317) (xy 458.403121 -387.780129)
			(xy 458.450727 -387.809183) (xy 458.493595 -387.844858) (xy 458.530812 -387.886395) (xy 458.561585 -387.932908)
			(xy 458.585257 -387.983405) (xy 458.601325 -388.036812) (xy 458.609445 -388.091988) (xy 458.609954 -388.119874)
			(xy 458.609445 -388.14776) (xy 458.601325 -388.202936) (xy 458.585257 -388.256343) (xy 458.561585 -388.30684)
			(xy 458.530812 -388.353353) (xy 458.493595 -388.39489) (xy 458.450727 -388.430565) (xy 458.403121 -388.459619)
			(xy 458.351792 -388.481431) (xy 458.297835 -388.495537) (xy 458.242398 -388.501637) (xy 458.186664 -388.4996)
			(xy 458.131821 -388.48947) (xy 458.079037 -388.471463) (xy 458.029437 -388.445962) (xy 457.984079 -388.413511)
			(xy 457.94393 -388.374802) (xy 457.909844 -388.330659) (xy 457.882548 -388.282024) (xy 457.862625 -388.229933)
			(xy 457.850499 -388.175496) (xy 457.846428 -388.119874) (xy 457.542741 -388.119874) (xy 457.551611 -388.137319)
			(xy 457.570061 -388.194213) (xy 457.5794 -388.253291) (xy 457.579984 -388.283196) (xy 457.579541 -388.31045)
			(xy 457.571784 -388.364403) (xy 457.556427 -388.416702) (xy 457.533783 -388.466284) (xy 457.504313 -388.512138)
			(xy 457.468618 -388.553332) (xy 457.427422 -388.589025) (xy 457.381567 -388.618493) (xy 457.331984 -388.641134)
			(xy 457.279683 -388.656488) (xy 457.22573 -388.664242) (xy 457.198476 -388.664704) (xy 457.171906 -388.664233)
			(xy 457.119283 -388.656837) (xy 457.068197 -388.642205) (xy 457.019637 -388.620622) (xy 456.974545 -388.592504)
			(xy 456.953874 -388.575804) (xy 456.946508 -388.569708) (xy 456.928982 -388.563866) (xy 456.84186 -388.566914)
			(xy 456.824842 -388.57428) (xy 456.817984 -388.580884) (xy 456.796502 -388.600972) (xy 456.748506 -388.634959)
			(xy 456.695863 -388.66118) (xy 456.639821 -388.679013) (xy 456.581706 -388.688037) (xy 456.5523 -388.68858)
			(xy 456.524869 -388.688153) (xy 456.470576 -388.680275) (xy 456.417969 -388.66471) (xy 456.36813 -388.641778)
			(xy 456.322085 -388.611952) (xy 456.280781 -388.575844) (xy 456.245068 -388.534198) (xy 456.229974 -388.511288)
			(xy 456.223116 -388.500366) (xy 456.200764 -388.48792) (xy 456.09002 -388.486142) (xy 456.067414 -388.497826)
			(xy 456.060048 -388.508748) (xy 456.044731 -388.530502) (xy 456.009069 -388.569982) (xy 455.968269 -388.604127)
			(xy 455.923123 -388.632275) (xy 455.874505 -388.65388) (xy 455.823358 -388.668523) (xy 455.770673 -388.675922)
			(xy 455.744072 -388.676388) (xy 455.716819 -388.675948) (xy 455.662869 -388.668187) (xy 455.610572 -388.652828)
			(xy 455.560993 -388.630182) (xy 455.515142 -388.600711) (xy 455.473952 -388.565014) (xy 455.43826 -388.523819)
			(xy 455.408795 -388.477965) (xy 455.386156 -388.428383) (xy 455.370802 -388.376084) (xy 455.363048 -388.322133)
			(xy 455.362564 -388.29488) (xy 455.363074 -388.265401) (xy 455.372148 -388.207146) (xy 455.390076 -388.15098)
			(xy 455.416433 -388.098241) (xy 455.450589 -388.050185) (xy 455.470768 -388.028688) (xy 455.47788 -388.021322)
			(xy 455.485246 -388.003034) (xy 455.485246 -387.912102) (xy 455.477626 -387.893814) (xy 455.470768 -387.886702)
			(xy 455.450437 -387.865202) (xy 455.416059 -387.817042) (xy 455.389529 -387.764151) (xy 455.371483 -387.707798)
			(xy 455.362355 -387.649334) (xy 455.361802 -387.619748) (xy 452.503953 -387.619748) (xy 452.510938 -387.668071)
			(xy 452.511414 -387.69544) (xy 452.510874 -387.723834) (xy 452.502458 -387.779995) (xy 452.485804 -387.834286)
			(xy 452.46128 -387.885505) (xy 452.429428 -387.932519) (xy 452.410576 -387.953758) (xy 452.404226 -387.960616)
			(xy 452.397368 -387.977888) (xy 452.396098 -388.064248) (xy 452.402194 -388.08152) (xy 452.408544 -388.088632)
			(xy 452.425852 -388.109521) (xy 452.455038 -388.155246) (xy 452.47745 -388.204647) (xy 452.492635 -388.256725)
			(xy 452.500286 -388.310429) (xy 452.500746 -388.337552) (xy 452.50026 -388.364803) (xy 452.492504 -388.418751)
			(xy 452.477149 -388.471046) (xy 452.454507 -388.520623) (xy 452.425041 -388.566473) (xy 452.38935 -388.607664)
			(xy 452.348159 -388.643355) (xy 452.302309 -388.672821) (xy 452.252732 -388.695463) (xy 452.200437 -388.710818)
			(xy 452.146489 -388.718574) (xy 452.091987 -388.718574) (xy 452.038039 -388.710818) (xy 451.985744 -388.695463)
			(xy 451.936167 -388.672821) (xy 451.890317 -388.643355) (xy 451.849126 -388.607664) (xy 451.813435 -388.566473)
			(xy 451.783969 -388.520623) (xy 451.761327 -388.471046) (xy 451.745972 -388.418751) (xy 451.738216 -388.364803)
			(xy 451.73773 -388.337552) (xy 451.738128 -388.312092) (xy 451.744897 -388.261624) (xy 451.758321 -388.212505)
			(xy 451.778162 -388.16561) (xy 451.804066 -388.121772) (xy 451.835573 -388.08177) (xy 451.853554 -388.06374)
			(xy 451.860334 -388.056435) (xy 451.86817 -388.038128) (xy 451.868794 -388.02818) (xy 451.869556 -387.996176)
			(xy 451.869232 -387.98619) (xy 451.861915 -387.967623) (xy 451.855332 -387.960108) (xy 451.84314 -387.9469)
			(xy 451.835578 -387.93903) (xy 451.815692 -387.930084) (xy 451.804786 -387.929628) (xy 451.728586 -387.929628)
			(xy 451.717691 -387.930128) (xy 451.697822 -387.939068) (xy 451.690232 -387.9469) (xy 451.672054 -387.966953)
			(xy 451.630995 -388.002217) (xy 451.58536 -388.031318) (xy 451.536067 -388.05367) (xy 451.484108 -388.068825)
			(xy 451.430528 -388.076477) (xy 451.403466 -388.076948) (xy 451.374727 -388.076432) (xy 451.3179 -388.067806)
			(xy 451.263009 -388.050753) (xy 451.211298 -388.02566) (xy 451.163935 -387.993095) (xy 451.142608 -387.973824)
			(xy 451.135496 -387.96722) (xy 451.11797 -387.960108) (xy 451.028562 -387.960108) (xy 451.011036 -387.96722)
			(xy 451.003924 -387.973824) (xy 450.982605 -387.993105) (xy 450.935242 -388.025671) (xy 450.883528 -388.050762)
			(xy 450.828635 -388.06781) (xy 450.771806 -388.076429) (xy 450.743066 -388.076948) (xy 450.715816 -388.076454)
			(xy 450.66187 -388.068694) (xy 450.609578 -388.053336) (xy 450.560004 -388.030694) (xy 450.514155 -388.001228)
			(xy 450.472966 -387.965538) (xy 450.437275 -387.92435) (xy 450.407809 -387.878502) (xy 450.385166 -387.828927)
			(xy 450.369807 -387.776635) (xy 450.362046 -387.72269) (xy 450.361558 -387.69544) (xy 450.362033 -387.66807)
			(xy 450.369847 -387.613891) (xy 450.385333 -387.561387) (xy 450.408173 -387.51164) (xy 450.437897 -387.465673)
			(xy 450.455538 -387.444742) (xy 450.461634 -387.43763) (xy 450.467984 -387.420612) (xy 450.467984 -387.335268)
			(xy 450.461634 -387.31825) (xy 450.455538 -387.311138) (xy 450.437909 -387.290198) (xy 450.408194 -387.244228)
			(xy 450.385356 -387.194482) (xy 450.369863 -387.141983) (xy 450.362033 -387.087809) (xy 450.361558 -387.06044)
			(xy 450.362056 -387.0317) (xy 450.370687 -386.974872) (xy 450.387744 -386.919982) (xy 450.41284 -386.86827)
			(xy 450.44541 -386.820909) (xy 450.464682 -386.799582) (xy 450.47154 -386.792216) (xy 450.478398 -386.774436)
			(xy 450.477636 -386.684266) (xy 450.47027 -386.666232) (xy 450.463158 -386.65912) (xy 450.442931 -386.637621)
			(xy 450.408707 -386.589528) (xy 450.382299 -386.536738) (xy 450.364337 -386.480511) (xy 450.35525 -386.422187)
			(xy 450.3547 -386.392674) (xy 450.18508 -386.392674) (xy 450.177797 -386.441828) (xy 450.16149 -386.495614)
			(xy 450.137467 -386.546424) (xy 450.106249 -386.59316) (xy 450.06851 -386.634808) (xy 450.047106 -386.653024)
			(xy 450.03847 -386.660136) (xy 450.028818 -386.680202) (xy 450.027294 -386.780532) (xy 450.036438 -386.800598)
			(xy 450.045074 -386.808218) (xy 450.065287 -386.826445) (xy 450.100884 -386.867614) (xy 450.130271 -386.913424)
			(xy 450.152851 -386.962944) (xy 450.168167 -387.015169) (xy 450.175906 -387.069041) (xy 450.176392 -387.096254)
			(xy 450.175903 -387.124994) (xy 450.167272 -387.181823) (xy 450.150214 -387.236714) (xy 450.125115 -387.288426)
			(xy 450.092542 -387.335786) (xy 450.073268 -387.357112) (xy 450.066664 -387.364224) (xy 450.059552 -387.38175)
			(xy 450.059552 -387.471158) (xy 450.066664 -387.488684) (xy 450.073268 -387.495796) (xy 450.092565 -387.5171)
			(xy 450.125128 -387.564468) (xy 450.150215 -387.616186) (xy 450.167259 -387.671082) (xy 450.175875 -387.727913)
			(xy 450.176392 -387.756654) (xy 450.175902 -387.783906) (xy 450.168151 -387.837857) (xy 450.1528 -387.890156)
			(xy 450.130161 -387.939737) (xy 450.100697 -387.985591) (xy 450.065006 -388.026784) (xy 450.023815 -388.062479)
			(xy 449.977963 -388.091947) (xy 449.928384 -388.114589) (xy 449.876087 -388.129944) (xy 449.822136 -388.1377)
			(xy 449.794884 -388.138162) (xy 449.769022 -388.137724) (xy 449.717771 -388.13074) (xy 449.667935 -388.11689)
			(xy 449.620431 -388.096427) (xy 449.57613 -388.069728) (xy 449.535847 -388.037283) (xy 449.51777 -388.018782)
			(xy 449.510244 -388.011554) (xy 449.491108 -388.003288) (xy 449.480686 -388.00278) (xy 449.448682 -388.00278)
			(xy 449.43825 -388.003245) (xy 449.419097 -388.011514) (xy 449.411598 -388.018782) (xy 449.407534 -388.0231)
			(xy 449.400168 -388.030466) (xy 449.392802 -388.04977) (xy 449.39585 -388.14375) (xy 449.404486 -388.162546)
			(xy 449.41236 -388.169404) (xy 449.431867 -388.187546) (xy 449.466085 -388.228374) (xy 449.494285 -388.27357)
			(xy 449.515917 -388.322252) (xy 449.530559 -388.373472) (xy 449.537926 -388.426232) (xy 449.538344 -388.452868)
			(xy 449.537792 -388.480117) (xy 449.530041 -388.53406) (xy 449.514692 -388.586352) (xy 449.492057 -388.635926)
			(xy 449.462597 -388.681775) (xy 449.426913 -388.722965) (xy 449.385729 -388.758657) (xy 449.339886 -388.788124)
			(xy 449.290315 -388.810768) (xy 449.238027 -388.826126) (xy 449.184085 -388.833887) (xy 449.156836 -388.834376)
			(xy 449.12792 -388.833841) (xy 449.070749 -388.825117) (xy 449.01555 -388.807863) (xy 448.963588 -388.782474)
			(xy 448.916054 -388.749533) (xy 448.874036 -388.709794) (xy 448.855846 -388.68731) (xy 448.848258 -388.678575)
			(xy 448.827519 -388.668376) (xy 448.815968 -388.667752) (xy 448.735704 -388.667752) (xy 448.724134 -388.668307)
			(xy 448.703362 -388.678511) (xy 448.695826 -388.68731) (xy 448.677623 -388.709783) (xy 448.635605 -388.749519)
			(xy 448.588073 -388.782458) (xy 448.536114 -388.807848) (xy 448.480919 -388.825107) (xy 448.423751 -388.833839)
			(xy 448.394836 -388.834376) (xy 448.367583 -388.833911) (xy 448.31363 -388.826158) (xy 448.26133 -388.810805)
			(xy 448.211748 -388.788164) (xy 448.165893 -388.758697) (xy 448.124699 -388.723003) (xy 448.089005 -388.68181)
			(xy 448.059537 -388.635955) (xy 448.036896 -388.586374) (xy 448.021543 -388.534074) (xy 448.013789 -388.480121)
			(xy 448.013328 -388.452868) (xy 448.013848 -388.423354) (xy 448.022944 -388.36503) (xy 448.040916 -388.308804)
			(xy 448.067333 -388.256017) (xy 448.101565 -388.207928) (xy 448.121786 -388.186422) (xy 448.129152 -388.179056)
			(xy 448.136518 -388.159752) (xy 448.13347 -388.065772) (xy 448.124834 -388.046976) (xy 448.11696 -388.040118)
			(xy 448.097468 -388.021961) (xy 448.063247 -387.981136) (xy 448.035045 -387.935944) (xy 448.013411 -387.887265)
			(xy 447.998766 -387.836047) (xy 447.991395 -387.783289) (xy 447.990976 -387.756654) (xy 447.991478 -387.727914)
			(xy 448.000107 -387.671086) (xy 448.017162 -387.616196) (xy 448.042259 -387.564484) (xy 448.074828 -387.517122)
			(xy 448.0941 -387.495796) (xy 448.100704 -387.488684) (xy 448.107816 -387.471158) (xy 448.107816 -387.38175)
			(xy 448.100704 -387.364224) (xy 448.0941 -387.357112) (xy 448.074818 -387.335794) (xy 448.042251 -387.288431)
			(xy 448.01716 -387.236717) (xy 448.000112 -387.181824) (xy 447.991494 -387.124994) (xy 447.990976 -387.096254)
			(xy 447.991473 -387.068151) (xy 447.999713 -387.012554) (xy 448.016023 -386.958767) (xy 448.04005 -386.907956)
			(xy 448.071273 -386.861222) (xy 448.109016 -386.819575) (xy 448.130422 -386.80136) (xy 448.139058 -386.794248)
			(xy 448.14871 -386.774182) (xy 448.150234 -386.673852) (xy 448.14109 -386.653786) (xy 448.132454 -386.646166)
			(xy 448.112239 -386.627941) (xy 448.076641 -386.586772) (xy 448.047253 -386.540963) (xy 448.024673 -386.491442)
			(xy 448.009359 -386.439215) (xy 448.001621 -386.385343) (xy 448.001136 -386.35813) (xy 448.001696 -386.329072)
			(xy 448.010524 -386.27163) (xy 448.027966 -386.216192) (xy 448.053618 -386.164043) (xy 448.086885 -386.11639)
			(xy 448.106546 -386.094986) (xy 448.11315 -386.087874) (xy 448.120516 -386.06984) (xy 448.120516 -385.979924)
			(xy 448.11315 -385.96189) (xy 448.106546 -385.954778) (xy 448.086865 -385.93339) (xy 448.053587 -385.885739)
			(xy 448.027932 -385.833586) (xy 448.010495 -385.778143) (xy 448.001679 -385.720695) (xy 448.001136 -385.691634)
			(xy 448.001606 -385.664934) (xy 448.009054 -385.612055) (xy 448.023807 -385.560733) (xy 448.045578 -385.511973)
			(xy 448.073941 -385.466727) (xy 448.090798 -385.446016) (xy 448.096894 -385.43865) (xy 448.10299 -385.420616)
			(xy 448.09918 -385.332986) (xy 448.09156 -385.31546) (xy 448.084956 -385.308856) (xy 448.064171 -385.287243)
			(xy 448.028912 -385.238746) (xy 448.001679 -385.185329) (xy 447.98314 -385.128308) (xy 447.973755 -385.069088)
			(xy 447.973196 -385.039108) (xy 438.98058 -385.039108) (xy 438.98058 -386.106416) (xy 438.981029 -386.116444)
			(xy 438.988617 -386.135004) (xy 438.995312 -386.142484) (xy 439.247534 -386.394706) (xy 442.279024 -386.394706)
			(xy 442.279461 -386.367452) (xy 442.287218 -386.313498) (xy 442.302575 -386.261198) (xy 442.325219 -386.211616)
			(xy 442.354689 -386.165761) (xy 442.390386 -386.124568) (xy 442.431582 -386.088874) (xy 442.477439 -386.059407)
			(xy 442.527022 -386.036766) (xy 442.579324 -386.021412) (xy 442.633278 -386.013659) (xy 442.660532 -386.013198)
			(xy 442.687801 -386.013699) (xy 442.741781 -386.02148) (xy 442.794103 -386.036866) (xy 442.843704 -386.059542)
			(xy 442.889571 -386.089047) (xy 442.930772 -386.124781) (xy 442.966467 -386.166015) (xy 442.981588 -386.188712)
			(xy 442.989127 -386.198999) (xy 443.011525 -386.21113) (xy 443.02426 -386.211826) (xy 443.055756 -386.211826)
			(xy 443.06422 -386.211559) (xy 443.080231 -386.20607) (xy 443.093566 -386.195646) (xy 443.098428 -386.188712)
			(xy 443.118748 -386.16001) (xy 443.12459 -386.152644) (xy 443.129924 -386.134356) (xy 443.123066 -386.04698)
			(xy 443.114938 -386.029708) (xy 443.107826 -386.023358) (xy 443.089012 -386.005256) (xy 443.056035 -385.96478)
			(xy 443.028882 -385.920186) (xy 443.008061 -385.872308) (xy 442.993959 -385.822039) (xy 442.986841 -385.770317)
			(xy 442.986414 -385.744212) (xy 442.986867 -385.716958) (xy 442.994622 -385.663006) (xy 443.009978 -385.610707)
			(xy 443.032621 -385.561125) (xy 443.06209 -385.515271) (xy 443.097785 -385.474077) (xy 443.138979 -385.438384)
			(xy 443.184834 -385.408916) (xy 443.234416 -385.386275) (xy 443.286716 -385.37092) (xy 443.340668 -385.363166)
			(xy 443.367922 -385.362704) (xy 443.394158 -385.363146) (xy 443.446135 -385.370344) (xy 443.496634 -385.384602)
			(xy 443.5447 -385.405649) (xy 443.589427 -385.433089) (xy 443.629968 -385.466403) (xy 443.648084 -385.485386)
			(xy 443.65545 -385.493006) (xy 443.6745 -385.501642) (xy 443.769496 -385.502404) (xy 443.7888 -385.494276)
			(xy 443.796166 -385.486656) (xy 443.814239 -385.468464) (xy 443.854381 -385.436556) (xy 443.898434 -385.41031)
			(xy 443.945606 -385.390201) (xy 443.995046 -385.37659) (xy 444.045863 -385.369723) (xy 444.071502 -385.369308)
			(xy 444.097485 -385.369722) (xy 444.148968 -385.376788) (xy 444.199017 -385.390774) (xy 444.246704 -385.411422)
			(xy 444.291149 -385.43835) (xy 444.331529 -385.471061) (xy 444.349632 -385.489704) (xy 444.357159 -385.496931)
			(xy 444.376294 -385.505198) (xy 444.386716 -385.505706) (xy 444.460884 -385.505706) (xy 444.471315 -385.505227)
			(xy 444.490468 -385.496968) (xy 444.497968 -385.489704) (xy 444.516083 -385.471073) (xy 444.556457 -385.438359)
			(xy 444.600899 -385.41143) (xy 444.648585 -385.390784) (xy 444.698633 -385.376803) (xy 444.750116 -385.369748)
			(xy 444.776098 -385.369308) (xy 444.803352 -385.369757) (xy 444.857304 -385.377514) (xy 444.909603 -385.392871)
			(xy 444.959184 -385.415514) (xy 445.005038 -385.444984) (xy 445.046231 -385.480679) (xy 445.081925 -385.521873)
			(xy 445.111392 -385.567728) (xy 445.134034 -385.61731) (xy 445.149389 -385.66961) (xy 445.157144 -385.723562)
			(xy 445.157606 -385.750816) (xy 445.157128 -385.77795) (xy 445.149441 -385.831671) (xy 445.134212 -385.883758)
			(xy 445.111748 -385.933158) (xy 445.082504 -385.978871) (xy 445.06515 -385.999736) (xy 445.059054 -386.006848)
			(xy 445.052704 -386.02412) (xy 445.053974 -386.110226) (xy 445.060832 -386.127244) (xy 445.066928 -386.134356)
			(xy 445.085435 -386.155533) (xy 445.116711 -386.202273) (xy 445.140793 -386.253095) (xy 445.157162 -386.3069)
			(xy 445.165462 -386.362523) (xy 445.165988 -386.390642) (xy 445.165412 -386.419767) (xy 445.156552 -386.477339)
			(xy 445.139044 -386.532895) (xy 445.113296 -386.585145) (xy 445.079906 -386.632874) (xy 445.039649 -386.674974)
			(xy 445.01689 -386.693156) (xy 445.007492 -386.700268) (xy 444.997078 -386.721604) (xy 444.997586 -386.826252)
			(xy 445.008 -386.847588) (xy 445.017652 -386.8547) (xy 445.040752 -386.872847) (xy 445.081617 -386.915042)
			(xy 445.115533 -386.963003) (xy 445.141697 -387.015595) (xy 445.159491 -387.071575) (xy 445.168495 -387.129622)
			(xy 445.169036 -387.158992) (xy 445.168581 -387.186363) (xy 445.160763 -387.240543) (xy 445.145272 -387.293047)
			(xy 445.122427 -387.342794) (xy 445.092699 -387.388759) (xy 445.075056 -387.40969) (xy 445.06896 -387.416802)
			(xy 445.06261 -387.43382) (xy 445.06261 -387.519164) (xy 445.06896 -387.536182) (xy 445.075056 -387.543294)
			(xy 445.09269 -387.564233) (xy 445.122416 -387.610199) (xy 445.145263 -387.659944) (xy 445.16076 -387.712446)
			(xy 445.16859 -387.766624) (xy 445.168591 -387.821364) (xy 445.160763 -387.875543) (xy 445.145267 -387.928044)
			(xy 445.122422 -387.97779) (xy 445.092697 -388.023758) (xy 445.075056 -388.04469) (xy 445.06896 -388.051802)
			(xy 445.06261 -388.06882) (xy 445.06261 -388.154164) (xy 445.06896 -388.171182) (xy 445.075056 -388.178294)
			(xy 445.092699 -388.199223) (xy 445.122412 -388.245196) (xy 445.145248 -388.294944) (xy 445.160738 -388.347446)
			(xy 445.168564 -388.401623) (xy 445.169036 -388.428992) (xy 445.168515 -388.456242) (xy 445.16076 -388.510187)
			(xy 445.145407 -388.562479) (xy 445.122769 -388.612055) (xy 445.093306 -388.657904) (xy 445.057619 -388.699093)
			(xy 445.016432 -388.734785) (xy 444.970586 -388.764252) (xy 444.921013 -388.786895) (xy 444.868722 -388.802253)
			(xy 444.814778 -388.810012) (xy 444.787528 -388.8105) (xy 444.761546 -388.810064) (xy 444.710064 -388.803002)
			(xy 444.660016 -388.78902) (xy 444.612328 -388.768376) (xy 444.567883 -388.741452) (xy 444.527502 -388.708746)
			(xy 444.509398 -388.690104) (xy 444.501859 -388.682891) (xy 444.482733 -388.674616) (xy 444.472314 -388.674102)
			(xy 444.398146 -388.674102) (xy 444.387711 -388.674541) (xy 444.368558 -388.682828) (xy 444.361062 -388.690104)
			(xy 444.342982 -388.70877) (xy 444.3026 -388.741481) (xy 444.258151 -388.768405) (xy 444.210458 -388.789045)
			(xy 444.160404 -388.803018) (xy 444.108916 -388.810065) (xy 444.082932 -388.8105) (xy 444.05568 -388.810015)
			(xy 444.001729 -388.802262) (xy 443.949431 -388.78691) (xy 443.899851 -388.76427) (xy 443.853997 -388.734805)
			(xy 443.812804 -388.699113) (xy 443.777109 -388.657922) (xy 443.747641 -388.612071) (xy 443.724999 -388.562491)
			(xy 443.709643 -388.510194) (xy 443.701887 -388.456244) (xy 443.701424 -388.428992) (xy 443.70188 -388.401621)
			(xy 443.709699 -388.347442) (xy 443.72519 -388.294938) (xy 443.748034 -388.245191) (xy 443.777762 -388.199225)
			(xy 443.795404 -388.178294) (xy 443.8015 -388.171182) (xy 443.80785 -388.154164) (xy 443.80785 -388.06882)
			(xy 443.8015 -388.051802) (xy 443.795404 -388.04469) (xy 443.777747 -388.023772) (xy 443.748038 -387.977795)
			(xy 443.725205 -387.928044) (xy 443.709718 -387.875541) (xy 443.701895 -387.821362) (xy 443.701424 -387.793992)
			(xy 443.701952 -387.764514) (xy 443.711023 -387.70626) (xy 443.728948 -387.650095) (xy 443.7553 -387.597356)
			(xy 443.789452 -387.549299) (xy 443.809628 -387.5278) (xy 443.816159 -387.520463) (xy 443.823606 -387.502304)
			(xy 443.824106 -387.492494) (xy 443.824106 -387.439154) (xy 443.81039 -387.425946) (xy 443.802262 -387.417564)
			(xy 443.780672 -387.40969) (xy 443.678818 -387.419596) (xy 443.65926 -387.431534) (xy 443.65291 -387.441186)
			(xy 443.637716 -387.463474) (xy 443.602042 -387.503932) (xy 443.561022 -387.538959) (xy 443.515476 -387.567856)
			(xy 443.466313 -387.590047) (xy 443.414513 -387.605089) (xy 443.36111 -387.612682) (xy 443.33414 -387.613144)
			(xy 443.3054 -387.612645) (xy 443.248572 -387.604015) (xy 443.193682 -387.586958) (xy 443.141971 -387.561861)
			(xy 443.094609 -387.529292) (xy 443.073282 -387.51002) (xy 443.06617 -387.503416) (xy 443.048644 -387.496304)
			(xy 442.959236 -387.496304) (xy 442.94171 -387.503416) (xy 442.934598 -387.51002) (xy 442.913248 -387.529265)
			(xy 442.865893 -387.561836) (xy 442.814187 -387.586934) (xy 442.759301 -387.603991) (xy 442.702478 -387.61262)
			(xy 442.67374 -387.613144) (xy 442.64649 -387.612608) (xy 442.592543 -387.604857) (xy 442.540249 -387.589508)
			(xy 442.490671 -387.566873) (xy 442.44482 -387.537412) (xy 442.403628 -387.501726) (xy 442.367933 -387.460541)
			(xy 442.338464 -387.414695) (xy 442.315819 -387.365122) (xy 442.300459 -387.312831) (xy 442.292698 -387.258886)
			(xy 442.292232 -387.231636) (xy 442.292795 -387.203509) (xy 442.30105 -387.147864) (xy 442.317387 -387.094035)
			(xy 442.341452 -387.043188) (xy 442.372723 -386.996426) (xy 442.410521 -386.954764) (xy 442.454028 -386.919103)
			(xy 442.477906 -386.90423) (xy 442.489844 -386.897118) (xy 442.503052 -386.87375) (xy 442.50102 -386.757926)
			(xy 442.487304 -386.734812) (xy 442.475112 -386.728208) (xy 442.450014 -386.713677) (xy 442.404186 -386.678139)
			(xy 442.364263 -386.636074) (xy 442.331165 -386.588453) (xy 442.305654 -386.536372) (xy 442.288319 -386.481031)
			(xy 442.279557 -386.423703) (xy 442.279024 -386.394706) (xy 439.247534 -386.394706) (xy 440.67349 -387.820662)
			(xy 440.696647 -387.844577) (xy 440.737189 -387.897378) (xy 440.770497 -387.955015) (xy 440.796005 -388.016504)
			(xy 440.813275 -388.080794) (xy 440.820937 -388.13867) (xy 441.467492 -388.13867) (xy 441.471563 -388.083048)
			(xy 441.483689 -388.028611) (xy 441.503612 -387.97652) (xy 441.530908 -387.927885) (xy 441.564994 -387.883742)
			(xy 441.605143 -387.845033) (xy 441.650501 -387.812582) (xy 441.700101 -387.787081) (xy 441.752885 -387.769074)
			(xy 441.807728 -387.758944) (xy 441.863462 -387.756907) (xy 441.918899 -387.763007) (xy 441.972856 -387.777113)
			(xy 442.024185 -387.798925) (xy 442.071791 -387.827979) (xy 442.114659 -387.863654) (xy 442.151876 -387.905191)
			(xy 442.182649 -387.951704) (xy 442.206321 -388.002201) (xy 442.222389 -388.055608) (xy 442.230509 -388.110784)
			(xy 442.231018 -388.13867) (xy 442.230509 -388.166556) (xy 442.222389 -388.221732) (xy 442.206321 -388.275139)
			(xy 442.182649 -388.325636) (xy 442.151876 -388.372149) (xy 442.114659 -388.413686) (xy 442.071791 -388.449361)
			(xy 442.024185 -388.478415) (xy 441.972856 -388.500227) (xy 441.918899 -388.514333) (xy 441.863462 -388.520433)
			(xy 441.807728 -388.518396) (xy 441.752885 -388.508266) (xy 441.700101 -388.490259) (xy 441.650501 -388.464758)
			(xy 441.605143 -388.432307) (xy 441.564994 -388.393598) (xy 441.530908 -388.349455) (xy 441.503612 -388.30082)
			(xy 441.483689 -388.248729) (xy 441.471563 -388.194292) (xy 441.467492 -388.13867) (xy 440.820937 -388.13867)
			(xy 440.822012 -388.146788) (xy 440.822588 -388.180072) (xy 440.822588 -393.156186) (xy 440.822054 -393.189474)
			(xy 440.813336 -393.255478) (xy 440.796074 -393.319779) (xy 440.770563 -393.381274) (xy 440.73724 -393.438912)
			(xy 440.696677 -393.491705) (xy 440.67349 -393.515596) (xy 439.65368 -394.535406) (xy 439.646906 -394.542832)
			(xy 439.639317 -394.561428) (xy 439.638948 -394.571474) (xy 439.638948 -397.835628) (xy 440.404248 -397.835628)
			(xy 440.408319 -397.780006) (xy 440.420445 -397.725569) (xy 440.440368 -397.673478) (xy 440.467664 -397.624843)
			(xy 440.50175 -397.5807) (xy 440.541899 -397.541991) (xy 440.587257 -397.50954) (xy 440.636857 -397.484039)
			(xy 440.689641 -397.466032) (xy 440.744484 -397.455902) (xy 440.800218 -397.453865) (xy 440.855655 -397.459965)
			(xy 440.909612 -397.474071) (xy 440.960941 -397.495883) (xy 441.008547 -397.524937) (xy 441.051415 -397.560612)
			(xy 441.088632 -397.602149) (xy 441.119405 -397.648662) (xy 441.143077 -397.699159) (xy 441.159145 -397.752566)
			(xy 441.167265 -397.807742) (xy 441.167774 -397.835628) (xy 441.167265 -397.863514) (xy 441.159145 -397.91869)
			(xy 441.145926 -397.962628) (xy 449.472048 -397.962628) (xy 449.476119 -397.907006) (xy 449.488245 -397.852569)
			(xy 449.508168 -397.800478) (xy 449.535464 -397.751843) (xy 449.56955 -397.7077) (xy 449.609699 -397.668991)
			(xy 449.655057 -397.63654) (xy 449.704657 -397.611039) (xy 449.757441 -397.593032) (xy 449.812284 -397.582902)
			(xy 449.868018 -397.580865) (xy 449.923455 -397.586965) (xy 449.977412 -397.601071) (xy 450.028741 -397.622883)
			(xy 450.076347 -397.651937) (xy 450.119215 -397.687612) (xy 450.156432 -397.729149) (xy 450.187205 -397.775662)
			(xy 450.210877 -397.826159) (xy 450.226945 -397.879566) (xy 450.235065 -397.934742) (xy 450.235574 -397.962628)
			(xy 450.235065 -397.990514) (xy 450.226945 -398.04569) (xy 450.210877 -398.099097) (xy 450.187205 -398.149594)
			(xy 450.156432 -398.196107) (xy 450.119215 -398.237644) (xy 450.076347 -398.273319) (xy 450.028741 -398.302373)
			(xy 449.977412 -398.324185) (xy 449.923455 -398.338291) (xy 449.868018 -398.344391) (xy 449.812284 -398.342354)
			(xy 449.757441 -398.332224) (xy 449.704657 -398.314217) (xy 449.655057 -398.288716) (xy 449.609699 -398.256265)
			(xy 449.56955 -398.217556) (xy 449.535464 -398.173413) (xy 449.508168 -398.124778) (xy 449.488245 -398.072687)
			(xy 449.476119 -398.01825) (xy 449.472048 -397.962628) (xy 441.145926 -397.962628) (xy 441.143077 -397.972097)
			(xy 441.119405 -398.022594) (xy 441.088632 -398.069107) (xy 441.051415 -398.110644) (xy 441.008547 -398.146319)
			(xy 440.960941 -398.175373) (xy 440.909612 -398.197185) (xy 440.855655 -398.211291) (xy 440.800218 -398.217391)
			(xy 440.744484 -398.215354) (xy 440.689641 -398.205224) (xy 440.636857 -398.187217) (xy 440.587257 -398.161716)
			(xy 440.541899 -398.129265) (xy 440.50175 -398.090556) (xy 440.467664 -398.046413) (xy 440.440368 -397.997778)
			(xy 440.420445 -397.945687) (xy 440.408319 -397.89125) (xy 440.404248 -397.835628) (xy 439.638948 -397.835628)
			(xy 439.638948 -398.737328) (xy 440.397136 -398.737328) (xy 440.401207 -398.681706) (xy 440.413333 -398.627269)
			(xy 440.433256 -398.575178) (xy 440.460552 -398.526543) (xy 440.494638 -398.4824) (xy 440.534787 -398.443691)
			(xy 440.580145 -398.41124) (xy 440.629745 -398.385739) (xy 440.682529 -398.367732) (xy 440.737372 -398.357602)
			(xy 440.793106 -398.355565) (xy 440.848543 -398.361665) (xy 440.9025 -398.375771) (xy 440.953829 -398.397583)
			(xy 441.001435 -398.426637) (xy 441.044303 -398.462312) (xy 441.08152 -398.503849) (xy 441.112293 -398.550362)
			(xy 441.135965 -398.600859) (xy 441.152033 -398.654266) (xy 441.160153 -398.709442) (xy 441.160662 -398.737328)
			(xy 441.160153 -398.765214) (xy 441.152033 -398.82039) (xy 441.138814 -398.864328) (xy 449.475858 -398.864328)
			(xy 449.479929 -398.808706) (xy 449.492055 -398.754269) (xy 449.511978 -398.702178) (xy 449.539274 -398.653543)
			(xy 449.57336 -398.6094) (xy 449.613509 -398.570691) (xy 449.658867 -398.53824) (xy 449.708467 -398.512739)
			(xy 449.761251 -398.494732) (xy 449.816094 -398.484602) (xy 449.871828 -398.482565) (xy 449.927265 -398.488665)
			(xy 449.981222 -398.502771) (xy 450.032551 -398.524583) (xy 450.080157 -398.553637) (xy 450.123025 -398.589312)
			(xy 450.160242 -398.630849) (xy 450.191015 -398.677362) (xy 450.214687 -398.727859) (xy 450.230755 -398.781266)
			(xy 450.238875 -398.836442) (xy 450.239384 -398.864328) (xy 450.238875 -398.892214) (xy 450.230755 -398.94739)
			(xy 450.214687 -399.000797) (xy 450.191015 -399.051294) (xy 450.160242 -399.097807) (xy 450.123025 -399.139344)
			(xy 450.080157 -399.175019) (xy 450.032551 -399.204073) (xy 449.981222 -399.225885) (xy 449.927265 -399.239991)
			(xy 449.871828 -399.246091) (xy 449.816094 -399.244054) (xy 449.761251 -399.233924) (xy 449.708467 -399.215917)
			(xy 449.658867 -399.190416) (xy 449.613509 -399.157965) (xy 449.57336 -399.119256) (xy 449.539274 -399.075113)
			(xy 449.511978 -399.026478) (xy 449.492055 -398.974387) (xy 449.479929 -398.91995) (xy 449.475858 -398.864328)
			(xy 441.138814 -398.864328) (xy 441.135965 -398.873797) (xy 441.112293 -398.924294) (xy 441.08152 -398.970807)
			(xy 441.044303 -399.012344) (xy 441.001435 -399.048019) (xy 440.953829 -399.077073) (xy 440.9025 -399.098885)
			(xy 440.848543 -399.112991) (xy 440.793106 -399.119091) (xy 440.737372 -399.117054) (xy 440.682529 -399.106924)
			(xy 440.629745 -399.088917) (xy 440.580145 -399.063416) (xy 440.534787 -399.030965) (xy 440.494638 -398.992256)
			(xy 440.460552 -398.948113) (xy 440.433256 -398.899478) (xy 440.413333 -398.847387) (xy 440.401207 -398.79295)
			(xy 440.397136 -398.737328) (xy 439.638948 -398.737328) (xy 439.638948 -399.2834) (xy 445.415396 -399.2834)
			(xy 445.419379 -399.230248) (xy 445.431241 -399.178283) (xy 445.450715 -399.128667) (xy 445.477367 -399.082508)
			(xy 445.510601 -399.040836) (xy 445.549675 -399.004584) (xy 445.593717 -398.974561) (xy 445.641741 -398.951438)
			(xy 445.692675 -398.935731) (xy 445.745381 -398.927791) (xy 445.772032 -398.92732) (xy 445.798392 -398.927815)
			(xy 445.850533 -398.9356) (xy 445.900956 -398.950994) (xy 445.948554 -398.973661) (xy 445.992286 -399.003103)
			(xy 446.012062 -399.020538) (xy 446.019174 -399.026888) (xy 446.036954 -399.033746) (xy 446.12433 -399.033746)
			(xy 446.14211 -399.026888) (xy 446.149222 -399.020538) (xy 446.169016 -399.003127) (xy 446.212754 -398.973702)
			(xy 446.260349 -398.95104) (xy 446.310763 -398.935634) (xy 446.362895 -398.92782) (xy 446.389252 -398.92732)
			(xy 446.415612 -398.927803) (xy 446.467754 -398.935591) (xy 446.518177 -398.950988) (xy 446.565775 -398.973657)
			(xy 446.609506 -399.003102) (xy 446.629282 -399.020538) (xy 446.636394 -399.026888) (xy 446.654174 -399.033746)
			(xy 446.74155 -399.033746) (xy 446.75933 -399.026888) (xy 446.766442 -399.020538) (xy 446.786228 -399.003117)
			(xy 446.829969 -398.973694) (xy 446.877566 -398.951034) (xy 446.927981 -398.93563) (xy 446.980115 -398.927819)
			(xy 447.006472 -398.92732) (xy 447.031468 -398.927745) (xy 447.080968 -398.93474) (xy 447.129005 -398.948582)
			(xy 447.174638 -398.968999) (xy 447.21697 -398.995592) (xy 447.236342 -399.011394) (xy 447.243454 -399.01749)
			(xy 447.259964 -399.023586) (xy 447.344038 -399.023586) (xy 447.360548 -399.01749) (xy 447.36766 -399.011394)
			(xy 447.387032 -398.995591) (xy 447.42936 -398.968989) (xy 447.474992 -398.948567) (xy 447.523031 -398.934727)
			(xy 447.572533 -398.92774) (xy 447.59753 -398.92732) (xy 447.624436 -398.927823) (xy 447.677639 -398.9359)
			(xy 447.72902 -398.951895) (xy 447.777406 -398.975444) (xy 447.821695 -399.00601) (xy 447.841624 -399.024094)
			(xy 447.848736 -399.030698) (xy 447.865754 -399.03781) (xy 447.953384 -399.039588) (xy 447.970656 -399.033238)
			(xy 447.978022 -399.026888) (xy 447.998965 -399.009317) (xy 448.044897 -398.979676) (xy 448.094591 -398.956895)
			(xy 448.147027 -398.941443) (xy 448.201133 -398.933634) (xy 448.228466 -398.933162) (xy 448.255718 -398.933683)
			(xy 448.309669 -398.941435) (xy 448.361966 -398.956787) (xy 448.411547 -398.979426) (xy 448.457401 -399.008891)
			(xy 448.498594 -399.044582) (xy 448.534289 -399.085772) (xy 448.563758 -399.131623) (xy 448.586401 -399.181202)
			(xy 448.601757 -399.233498) (xy 448.608933 -399.2834) (xy 454.494221 -399.2834) (xy 454.498203 -399.230259)
			(xy 454.51006 -399.178305) (xy 454.529528 -399.128698) (xy 454.556171 -399.082546) (xy 454.589394 -399.040881)
			(xy 454.628456 -399.004632) (xy 454.672484 -398.974609) (xy 454.720494 -398.951483) (xy 454.771415 -398.93577)
			(xy 454.824109 -398.927821) (xy 454.850754 -398.92732) (xy 454.877114 -398.927802) (xy 454.929257 -398.93559)
			(xy 454.979679 -398.950987) (xy 455.027277 -398.973657) (xy 455.071008 -399.003102) (xy 455.090784 -399.020538)
			(xy 455.097896 -399.026888) (xy 455.115676 -399.033746) (xy 455.203052 -399.033746) (xy 455.220832 -399.026888)
			(xy 455.227944 -399.020538) (xy 455.247729 -399.003116) (xy 455.29147 -398.973694) (xy 455.339067 -398.951033)
			(xy 455.389482 -398.93563) (xy 455.441616 -398.927819) (xy 455.467974 -398.92732) (xy 455.494335 -398.92779)
			(xy 455.546478 -398.935581) (xy 455.5969 -398.950981) (xy 455.644498 -398.973653) (xy 455.688228 -399.003101)
			(xy 455.708004 -399.020538) (xy 455.715116 -399.026888) (xy 455.732896 -399.033746) (xy 455.820272 -399.033746)
			(xy 455.838052 -399.026888) (xy 455.845164 -399.020538) (xy 455.864941 -399.003107) (xy 455.908684 -398.973685)
			(xy 455.956283 -398.951027) (xy 456.0067 -398.935626) (xy 456.058836 -398.927817) (xy 456.085194 -398.92732)
			(xy 456.11019 -398.927733) (xy 456.159691 -398.93473) (xy 456.207729 -398.948575) (xy 456.253361 -398.968996)
			(xy 456.295692 -398.995591) (xy 456.315064 -399.011394) (xy 456.322176 -399.01749) (xy 456.338686 -399.023586)
			(xy 456.42276 -399.023586) (xy 456.43927 -399.01749) (xy 456.446382 -399.011394) (xy 456.465746 -398.995581)
			(xy 456.508076 -398.96898) (xy 456.55371 -398.94856) (xy 456.601751 -398.934722) (xy 456.651255 -398.927738)
			(xy 456.676252 -398.92732) (xy 456.701833 -398.927781) (xy 456.75247 -398.935097) (xy 456.801538 -398.949585)
			(xy 456.848027 -398.970947) (xy 456.89098 -398.998743) (xy 456.929513 -399.032401) (xy 456.946508 -399.051526)
			(xy 456.952858 -399.059146) (xy 456.97013 -399.068036) (xy 457.059792 -399.076926) (xy 457.078334 -399.071338)
			(xy 457.086208 -399.065242) (xy 457.106427 -399.049888) (xy 457.150186 -399.024146) (xy 457.196972 -399.004433)
			(xy 457.245959 -398.991098) (xy 457.296281 -398.984375) (xy 457.321666 -398.983962) (xy 457.348918 -398.984483)
			(xy 457.402869 -398.992235) (xy 457.455166 -399.007587) (xy 457.504747 -399.030226) (xy 457.550601 -399.059691)
			(xy 457.591794 -399.095382) (xy 457.627489 -399.136572) (xy 457.656958 -399.182423) (xy 457.679601 -399.232002)
			(xy 457.694957 -399.284298) (xy 457.702715 -399.338248) (xy 457.702715 -399.392752) (xy 457.694957 -399.446702)
			(xy 457.679601 -399.498998) (xy 457.656958 -399.548577) (xy 457.627489 -399.594428) (xy 457.591794 -399.635618)
			(xy 457.550601 -399.671309) (xy 457.504747 -399.700774) (xy 457.455166 -399.723413) (xy 457.402869 -399.738765)
			(xy 457.348918 -399.746517) (xy 457.321666 -399.746978) (xy 457.292465 -399.746417) (xy 457.234744 -399.737518)
			(xy 457.179057 -399.719918) (xy 457.126706 -399.694029) (xy 457.078917 -399.660458) (xy 457.036808 -399.619989)
			(xy 457.018644 -399.597118) (xy 457.012548 -399.589244) (xy 456.996038 -399.579338) (xy 456.906884 -399.565622)
			(xy 456.888088 -399.56994) (xy 456.87996 -399.575528) (xy 456.857414 -399.59061) (xy 456.808731 -399.61453)
			(xy 456.756986 -399.630793) (xy 456.703373 -399.639024) (xy 456.676252 -399.639536) (xy 456.651257 -399.639084)
			(xy 456.601759 -399.632094) (xy 456.553722 -399.618257) (xy 456.508089 -399.597846) (xy 456.465756 -399.57126)
			(xy 456.446382 -399.555462) (xy 456.43927 -399.549366) (xy 456.42276 -399.54327) (xy 456.338686 -399.54327)
			(xy 456.322176 -399.549366) (xy 456.315064 -399.555462) (xy 456.29569 -399.571262) (xy 456.253362 -399.597863)
			(xy 456.207731 -399.618285) (xy 456.159692 -399.632126) (xy 456.11019 -399.639114) (xy 456.085194 -399.639536)
			(xy 456.058833 -399.639071) (xy 456.006691 -399.631277) (xy 455.956269 -399.615875) (xy 455.908672 -399.593202)
			(xy 455.86494 -399.563754) (xy 455.845164 -399.546318) (xy 455.838052 -399.539968) (xy 455.820272 -399.53311)
			(xy 455.732896 -399.53311) (xy 455.715116 -399.539968) (xy 455.708004 -399.546318) (xy 455.688233 -399.563757)
			(xy 455.644489 -399.593179) (xy 455.596888 -399.615836) (xy 455.54647 -399.631236) (xy 455.494333 -399.639041)
			(xy 455.467974 -399.639536) (xy 455.441615 -399.639023) (xy 455.389475 -399.63124) (xy 455.339054 -399.615849)
			(xy 455.291455 -399.593187) (xy 455.247722 -399.56375) (xy 455.227944 -399.546318) (xy 455.220832 -399.539968)
			(xy 455.203052 -399.53311) (xy 455.115676 -399.53311) (xy 455.097896 -399.539968) (xy 455.090784 -399.546318)
			(xy 455.070981 -399.563719) (xy 455.027246 -399.593146) (xy 454.979653 -399.615811) (xy 454.929242 -399.631219)
			(xy 454.87711 -399.639035) (xy 454.850754 -399.639536) (xy 454.824109 -399.638979) (xy 454.771415 -399.63103)
			(xy 454.720494 -399.615317) (xy 454.672484 -399.592191) (xy 454.628456 -399.562168) (xy 454.589394 -399.525919)
			(xy 454.556171 -399.484254) (xy 454.529528 -399.438102) (xy 454.51006 -399.388495) (xy 454.498203 -399.336541)
			(xy 454.494221 -399.2834) (xy 448.608933 -399.2834) (xy 448.609515 -399.287448) (xy 448.609515 -399.341952)
			(xy 448.601757 -399.395902) (xy 448.586401 -399.448198) (xy 448.563758 -399.497777) (xy 448.534289 -399.543628)
			(xy 448.498594 -399.584818) (xy 448.457401 -399.620509) (xy 448.411547 -399.649974) (xy 448.361966 -399.672613)
			(xy 448.309669 -399.687965) (xy 448.255718 -399.695717) (xy 448.228466 -399.696178) (xy 448.202545 -399.69574)
			(xy 448.151182 -399.688705) (xy 448.101244 -399.674782) (xy 448.05365 -399.654229) (xy 448.009276 -399.627422)
			(xy 447.968939 -399.594855) (xy 447.950844 -399.57629) (xy 447.94424 -399.569178) (xy 447.927476 -399.561304)
			(xy 447.840354 -399.554446) (xy 447.822574 -399.559526) (xy 447.814954 -399.565622) (xy 447.79142 -399.582994)
			(xy 447.739865 -399.610621) (xy 447.684487 -399.629448) (xy 447.626776 -399.638967) (xy 447.59753 -399.639536)
			(xy 447.572535 -399.639096) (xy 447.523036 -399.632103) (xy 447.474999 -399.618264) (xy 447.429367 -399.59785)
			(xy 447.387033 -399.571261) (xy 447.36766 -399.555462) (xy 447.360548 -399.549366) (xy 447.344038 -399.54327)
			(xy 447.259964 -399.54327) (xy 447.243454 -399.549366) (xy 447.236342 -399.555462) (xy 447.216976 -399.571273)
			(xy 447.174646 -399.597872) (xy 447.129012 -399.618291) (xy 447.080972 -399.63213) (xy 447.031469 -399.639116)
			(xy 447.006472 -399.639536) (xy 446.980113 -399.639024) (xy 446.927973 -399.631241) (xy 446.877551 -399.61585)
			(xy 446.829953 -399.593188) (xy 446.78622 -399.56375) (xy 446.766442 -399.546318) (xy 446.75933 -399.539968)
			(xy 446.74155 -399.53311) (xy 446.654174 -399.53311) (xy 446.636394 -399.539968) (xy 446.629282 -399.546318)
			(xy 446.60948 -399.56372) (xy 446.565744 -399.593147) (xy 446.518152 -399.615812) (xy 446.46774 -399.63122)
			(xy 446.415608 -399.639035) (xy 446.389252 -399.639536) (xy 446.362893 -399.639036) (xy 446.310752 -399.63125)
			(xy 446.26033 -399.615856) (xy 446.212732 -399.593191) (xy 446.168999 -399.563751) (xy 446.149222 -399.546318)
			(xy 446.14211 -399.539968) (xy 446.12433 -399.53311) (xy 446.036954 -399.53311) (xy 446.019174 -399.539968)
			(xy 446.012062 -399.546318) (xy 445.992268 -399.563729) (xy 445.94853 -399.593155) (xy 445.900935 -399.615818)
			(xy 445.850522 -399.631224) (xy 445.798389 -399.639036) (xy 445.772032 -399.639536) (xy 445.745381 -399.639009)
			(xy 445.692675 -399.631069) (xy 445.641741 -399.615362) (xy 445.593716 -399.592239) (xy 445.549675 -399.562216)
			(xy 445.510601 -399.525964) (xy 445.477367 -399.484292) (xy 445.450715 -399.438133) (xy 445.431241 -399.388517)
			(xy 445.419379 -399.336552) (xy 445.415396 -399.2834) (xy 439.638948 -399.2834) (xy 439.638948 -400.15287)
			(xy 447.338958 -400.15287) (xy 447.33945 -400.12562) (xy 447.34721 -400.071674) (xy 447.362567 -400.019381)
			(xy 447.385209 -399.969806) (xy 447.414675 -399.923958) (xy 447.450366 -399.882769) (xy 447.491554 -399.847078)
			(xy 447.537403 -399.817611) (xy 447.586978 -399.794968) (xy 447.63927 -399.77961) (xy 447.693216 -399.77185)
			(xy 447.720466 -399.771362) (xy 447.749383 -399.771881) (xy 447.806555 -399.780607) (xy 447.861755 -399.797863)
			(xy 447.913718 -399.823254) (xy 447.961251 -399.856199) (xy 448.003267 -399.895941) (xy 448.021456 -399.918428)
			(xy 448.029036 -399.92717) (xy 448.049781 -399.937363) (xy 448.061334 -399.937986) (xy 448.141598 -399.937986)
			(xy 448.153166 -399.937419) (xy 448.173937 -399.927222) (xy 448.181476 -399.918428) (xy 448.199688 -399.895962)
			(xy 448.241702 -399.856224) (xy 448.289233 -399.823282) (xy 448.34119 -399.797891) (xy 448.396384 -399.780631)
			(xy 448.453551 -399.771899) (xy 448.482466 -399.771362) (xy 448.509717 -399.771887) (xy 448.563664 -399.779638)
			(xy 448.615959 -399.794989) (xy 448.665537 -399.817625) (xy 448.711389 -399.847087) (xy 448.752581 -399.882774)
			(xy 448.788275 -399.92396) (xy 448.817744 -399.969807) (xy 448.840389 -400.019381) (xy 448.855748 -400.071674)
			(xy 448.863509 -400.125619) (xy 448.863649 -400.13382) (xy 449.300598 -400.13382) (xy 449.304669 -400.078198)
			(xy 449.316795 -400.023761) (xy 449.336718 -399.97167) (xy 449.364014 -399.923035) (xy 449.3981 -399.878892)
			(xy 449.438249 -399.840183) (xy 449.483607 -399.807732) (xy 449.533207 -399.782231) (xy 449.585991 -399.764224)
			(xy 449.640834 -399.754094) (xy 449.696568 -399.752057) (xy 449.752005 -399.758157) (xy 449.805962 -399.772263)
			(xy 449.857291 -399.794075) (xy 449.904897 -399.823129) (xy 449.947765 -399.858804) (xy 449.984982 -399.900341)
			(xy 450.015755 -399.946854) (xy 450.039427 -399.997351) (xy 450.055495 -400.050758) (xy 450.063615 -400.105934)
			(xy 450.064124 -400.13382) (xy 450.063615 -400.161706) (xy 450.057439 -400.20367) (xy 456.432158 -400.20367)
			(xy 456.43265 -400.17642) (xy 456.44041 -400.122474) (xy 456.455767 -400.070181) (xy 456.478409 -400.020606)
			(xy 456.507875 -399.974758) (xy 456.543566 -399.933569) (xy 456.584754 -399.897878) (xy 456.630603 -399.868411)
			(xy 456.680178 -399.845768) (xy 456.73247 -399.83041) (xy 456.786416 -399.82265) (xy 456.813666 -399.822162)
			(xy 456.842583 -399.822681) (xy 456.899755 -399.831407) (xy 456.954955 -399.848663) (xy 457.006918 -399.874054)
			(xy 457.054451 -399.906999) (xy 457.096467 -399.946741) (xy 457.114656 -399.969228) (xy 457.122236 -399.97797)
			(xy 457.142981 -399.988163) (xy 457.154534 -399.988786) (xy 457.234798 -399.988786) (xy 457.246366 -399.988219)
			(xy 457.267137 -399.978022) (xy 457.274676 -399.969228) (xy 457.292888 -399.946762) (xy 457.334902 -399.907024)
			(xy 457.382433 -399.874082) (xy 457.43439 -399.848691) (xy 457.489584 -399.831431) (xy 457.546751 -399.822699)
			(xy 457.575666 -399.822162) (xy 457.602917 -399.822687) (xy 457.656864 -399.830438) (xy 457.709159 -399.845789)
			(xy 457.758737 -399.868425) (xy 457.804589 -399.897887) (xy 457.845781 -399.933574) (xy 457.881475 -399.97476)
			(xy 457.910944 -400.020607) (xy 457.933589 -400.070181) (xy 457.948948 -400.122474) (xy 457.956709 -400.176419)
			(xy 457.957174 -400.20367) (xy 457.956772 -400.22936) (xy 457.949869 -400.280274) (xy 457.936196 -400.329801)
			(xy 457.916 -400.377046) (xy 457.889648 -400.421154) (xy 457.857616 -400.461326) (xy 457.820483 -400.496838)
			(xy 457.799948 -400.51228) (xy 457.788772 -400.520408) (xy 457.777596 -400.545808) (xy 457.791566 -400.661378)
			(xy 457.80833 -400.683476) (xy 457.821284 -400.688556) (xy 457.847233 -400.699707) (xy 457.895816 -400.728508)
			(xy 457.939623 -400.764156) (xy 457.977696 -400.805872) (xy 458.009205 -400.852744) (xy 458.03346 -400.903748)
			(xy 458.049932 -400.95777) (xy 458.058262 -401.013631) (xy 458.058774 -401.04187) (xy 458.058317 -401.069124)
			(xy 458.050563 -401.123077) (xy 458.035209 -401.175377) (xy 458.012567 -401.224959) (xy 457.983099 -401.270814)
			(xy 457.947405 -401.312008) (xy 457.906211 -401.347702) (xy 457.860355 -401.377169) (xy 457.810773 -401.39981)
			(xy 457.758473 -401.415164) (xy 457.70452 -401.422917) (xy 457.677266 -401.423378) (xy 457.64835 -401.422821)
			(xy 457.591181 -401.414101) (xy 457.535982 -401.396851) (xy 457.48402 -401.371467) (xy 457.436485 -401.33853)
			(xy 457.394467 -401.298795) (xy 457.376276 -401.276312) (xy 457.368718 -401.267546) (xy 457.347957 -401.257364)
			(xy 457.336398 -401.256754) (xy 457.256134 -401.256754) (xy 457.244566 -401.257325) (xy 457.223794 -401.267517)
			(xy 457.216256 -401.276312) (xy 457.198093 -401.298819) (xy 457.156067 -401.338552) (xy 457.108526 -401.371488)
			(xy 457.056559 -401.396872) (xy 457.001357 -401.414123) (xy 456.944184 -401.422846) (xy 456.915266 -401.423378)
			(xy 456.888013 -401.422954) (xy 456.834061 -401.415192) (xy 456.781763 -401.399831) (xy 456.732184 -401.377184)
			(xy 456.686332 -401.347711) (xy 456.645142 -401.312013) (xy 456.609451 -401.270816) (xy 456.579986 -401.22496)
			(xy 456.557347 -401.175377) (xy 456.541995 -401.123076) (xy 456.534242 -401.069124) (xy 456.533758 -401.04187)
			(xy 456.534176 -401.01618) (xy 456.541075 -400.965267) (xy 456.554745 -400.915739) (xy 456.574937 -400.868494)
			(xy 456.601286 -400.824386) (xy 456.633317 -400.784213) (xy 456.670449 -400.748702) (xy 456.690984 -400.73326)
			(xy 456.70216 -400.725132) (xy 456.713336 -400.699732) (xy 456.699366 -400.584162) (xy 456.682602 -400.562064)
			(xy 456.669648 -400.556984) (xy 456.643698 -400.545835) (xy 456.595119 -400.517029) (xy 456.551316 -400.481379)
			(xy 456.513245 -400.439663) (xy 456.481737 -400.392791) (xy 456.457481 -400.341788) (xy 456.441006 -400.287767)
			(xy 456.432673 -400.231908) (xy 456.432158 -400.20367) (xy 450.057439 -400.20367) (xy 450.055495 -400.216882)
			(xy 450.039427 -400.270289) (xy 450.015755 -400.320786) (xy 449.984982 -400.367299) (xy 449.947765 -400.408836)
			(xy 449.904897 -400.444511) (xy 449.857291 -400.473565) (xy 449.805962 -400.495377) (xy 449.752005 -400.509483)
			(xy 449.696568 -400.515583) (xy 449.640834 -400.513546) (xy 449.585991 -400.503416) (xy 449.533207 -400.485409)
			(xy 449.483607 -400.459908) (xy 449.438249 -400.427457) (xy 449.3981 -400.388748) (xy 449.364014 -400.344605)
			(xy 449.336718 -400.29597) (xy 449.316795 -400.243879) (xy 449.304669 -400.189442) (xy 449.300598 -400.13382)
			(xy 448.863649 -400.13382) (xy 448.863974 -400.15287) (xy 448.863572 -400.17856) (xy 448.856669 -400.229474)
			(xy 448.842996 -400.279001) (xy 448.8228 -400.326246) (xy 448.796448 -400.370354) (xy 448.764416 -400.410526)
			(xy 448.727283 -400.446038) (xy 448.706748 -400.46148) (xy 448.695572 -400.469608) (xy 448.684396 -400.495008)
			(xy 448.698366 -400.610578) (xy 448.71513 -400.632676) (xy 448.728084 -400.637756) (xy 448.754033 -400.648907)
			(xy 448.802616 -400.677708) (xy 448.846423 -400.713356) (xy 448.884496 -400.755072) (xy 448.916005 -400.801944)
			(xy 448.94026 -400.852948) (xy 448.956732 -400.90697) (xy 448.965062 -400.962831) (xy 448.965574 -400.99107)
			(xy 448.965117 -401.018324) (xy 448.957363 -401.072277) (xy 448.953672 -401.084848) (xy 452.907696 -401.084848)
			(xy 452.907696 -401.030352) (xy 452.915451 -400.976411) (xy 452.930803 -400.924123) (xy 452.95344 -400.874551)
			(xy 452.9829 -400.828705) (xy 453.018585 -400.787518) (xy 453.059768 -400.751828) (xy 453.10561 -400.722362)
			(xy 453.155179 -400.699719) (xy 453.207466 -400.684361) (xy 453.261406 -400.676599) (xy 453.288654 -400.67611)
			(xy 453.314407 -400.676537) (xy 453.365442 -400.683484) (xy 453.415079 -400.697231) (xy 453.462417 -400.717528)
			(xy 453.506596 -400.744006) (xy 453.546812 -400.776185) (xy 453.582336 -400.813479) (xy 453.597772 -400.834098)
			(xy 453.603868 -400.842226) (xy 453.620632 -400.85264) (xy 453.711056 -400.867626) (xy 453.73036 -400.863308)
			(xy 453.738742 -400.857466) (xy 453.763002 -400.840983) (xy 453.815524 -400.814883) (xy 453.871423 -400.797134)
			(xy 453.929381 -400.788154) (xy 453.958706 -400.787616) (xy 453.985959 -400.788054) (xy 454.039909 -400.795812)
			(xy 454.092206 -400.811169) (xy 454.141786 -400.833811) (xy 454.187639 -400.86328) (xy 454.228831 -400.898974)
			(xy 454.264524 -400.940166) (xy 454.293991 -400.986019) (xy 454.316634 -401.035599) (xy 454.331989 -401.087897)
			(xy 454.339746 -401.141847) (xy 454.339746 -401.196353) (xy 454.331989 -401.250303) (xy 454.316634 -401.302601)
			(xy 454.293991 -401.352181) (xy 454.264524 -401.398034) (xy 454.228831 -401.439226) (xy 454.187639 -401.47492)
			(xy 454.141786 -401.504389) (xy 454.092206 -401.527031) (xy 454.039909 -401.542388) (xy 453.985959 -401.550146)
			(xy 453.958706 -401.550632) (xy 453.932954 -401.550184) (xy 453.881919 -401.543244) (xy 453.832281 -401.529503)
			(xy 453.784942 -401.50921) (xy 453.740763 -401.482734) (xy 453.700546 -401.450557) (xy 453.665023 -401.413263)
			(xy 453.649588 -401.392644) (xy 453.643492 -401.384516) (xy 453.626728 -401.374102) (xy 453.536304 -401.359116)
			(xy 453.517 -401.363434) (xy 453.508618 -401.369276) (xy 453.484365 -401.385769) (xy 453.431841 -401.411869)
			(xy 453.375939 -401.429615) (xy 453.317979 -401.438591) (xy 453.288654 -401.439126) (xy 453.261406 -401.438601)
			(xy 453.207466 -401.430839) (xy 453.155179 -401.415481) (xy 453.10561 -401.392838) (xy 453.059768 -401.363372)
			(xy 453.018585 -401.327682) (xy 452.9829 -401.286495) (xy 452.95344 -401.240649) (xy 452.930803 -401.191077)
			(xy 452.915451 -401.138789) (xy 452.907696 -401.084848) (xy 448.953672 -401.084848) (xy 448.942009 -401.124577)
			(xy 448.919367 -401.174159) (xy 448.889899 -401.220014) (xy 448.854205 -401.261208) (xy 448.813011 -401.296902)
			(xy 448.767155 -401.326369) (xy 448.717573 -401.34901) (xy 448.665273 -401.364364) (xy 448.61132 -401.372117)
			(xy 448.584066 -401.372578) (xy 448.55515 -401.372021) (xy 448.497981 -401.363301) (xy 448.442782 -401.346051)
			(xy 448.39082 -401.320667) (xy 448.343285 -401.28773) (xy 448.301267 -401.247995) (xy 448.283076 -401.225512)
			(xy 448.275518 -401.216746) (xy 448.254757 -401.206564) (xy 448.243198 -401.205954) (xy 448.162934 -401.205954)
			(xy 448.151366 -401.206525) (xy 448.130594 -401.216717) (xy 448.123056 -401.225512) (xy 448.104893 -401.248019)
			(xy 448.062867 -401.287752) (xy 448.015326 -401.320688) (xy 447.963359 -401.346072) (xy 447.908157 -401.363323)
			(xy 447.850984 -401.372046) (xy 447.822066 -401.372578) (xy 447.794813 -401.372154) (xy 447.740861 -401.364392)
			(xy 447.688563 -401.349031) (xy 447.638984 -401.326384) (xy 447.593132 -401.296911) (xy 447.551942 -401.261213)
			(xy 447.516251 -401.220016) (xy 447.486786 -401.17416) (xy 447.464147 -401.124577) (xy 447.448795 -401.072276)
			(xy 447.441042 -401.018324) (xy 447.440558 -400.99107) (xy 447.440976 -400.96538) (xy 447.447875 -400.914467)
			(xy 447.461545 -400.864939) (xy 447.481737 -400.817694) (xy 447.508086 -400.773586) (xy 447.540117 -400.733413)
			(xy 447.577249 -400.697902) (xy 447.597784 -400.68246) (xy 447.60896 -400.674332) (xy 447.620136 -400.648932)
			(xy 447.606166 -400.533362) (xy 447.589402 -400.511264) (xy 447.576448 -400.506184) (xy 447.550498 -400.495035)
			(xy 447.501919 -400.466229) (xy 447.458116 -400.430579) (xy 447.420045 -400.388863) (xy 447.388537 -400.341991)
			(xy 447.364281 -400.290988) (xy 447.347806 -400.236967) (xy 447.339473 -400.181108) (xy 447.338958 -400.15287)
			(xy 439.638948 -400.15287) (xy 439.638948 -401.44192) (xy 440.397898 -401.44192) (xy 440.401969 -401.386298)
			(xy 440.414095 -401.331861) (xy 440.434018 -401.27977) (xy 440.461314 -401.231135) (xy 440.4954 -401.186992)
			(xy 440.535549 -401.148283) (xy 440.580907 -401.115832) (xy 440.630507 -401.090331) (xy 440.683291 -401.072324)
			(xy 440.738134 -401.062194) (xy 440.793868 -401.060157) (xy 440.849305 -401.066257) (xy 440.903262 -401.080363)
			(xy 440.954591 -401.102175) (xy 441.002197 -401.131229) (xy 441.025147 -401.150328) (xy 444.513714 -401.150328)
			(xy 444.517785 -401.094706) (xy 444.529911 -401.040269) (xy 444.549834 -400.988178) (xy 444.57713 -400.939543)
			(xy 444.611216 -400.8954) (xy 444.651365 -400.856691) (xy 444.696723 -400.82424) (xy 444.746323 -400.798739)
			(xy 444.799107 -400.780732) (xy 444.85395 -400.770602) (xy 444.909684 -400.768565) (xy 444.965121 -400.774665)
			(xy 445.019078 -400.788771) (xy 445.070407 -400.810583) (xy 445.118013 -400.839637) (xy 445.160881 -400.875312)
			(xy 445.198098 -400.916849) (xy 445.228871 -400.963362) (xy 445.252543 -401.013859) (xy 445.268611 -401.067266)
			(xy 445.276731 -401.122442) (xy 445.27724 -401.150328) (xy 445.276731 -401.178214) (xy 445.268611 -401.23339)
			(xy 445.252543 -401.286797) (xy 445.228871 -401.337294) (xy 445.198098 -401.383807) (xy 445.160881 -401.425344)
			(xy 445.118013 -401.461019) (xy 445.070407 -401.490073) (xy 445.019078 -401.511885) (xy 444.965121 -401.525991)
			(xy 444.909684 -401.532091) (xy 444.85395 -401.530054) (xy 444.799107 -401.519924) (xy 444.746323 -401.501917)
			(xy 444.696723 -401.476416) (xy 444.651365 -401.443965) (xy 444.611216 -401.405256) (xy 444.57713 -401.361113)
			(xy 444.549834 -401.312478) (xy 444.529911 -401.260387) (xy 444.517785 -401.20595) (xy 444.513714 -401.150328)
			(xy 441.025147 -401.150328) (xy 441.045065 -401.166904) (xy 441.082282 -401.208441) (xy 441.113055 -401.254954)
			(xy 441.136727 -401.305451) (xy 441.152795 -401.358858) (xy 441.160915 -401.414034) (xy 441.161424 -401.44192)
			(xy 441.160915 -401.469806) (xy 441.152795 -401.524982) (xy 441.136727 -401.578389) (xy 441.113055 -401.628886)
			(xy 441.082282 -401.675399) (xy 441.045065 -401.716936) (xy 441.002197 -401.752611) (xy 440.954591 -401.781665)
			(xy 440.903262 -401.803477) (xy 440.849305 -401.817583) (xy 440.793868 -401.823683) (xy 440.738134 -401.821646)
			(xy 440.683291 -401.811516) (xy 440.630507 -401.793509) (xy 440.580907 -401.768008) (xy 440.535549 -401.735557)
			(xy 440.4954 -401.696848) (xy 440.461314 -401.652705) (xy 440.434018 -401.60407) (xy 440.414095 -401.551979)
			(xy 440.401969 -401.497542) (xy 440.397898 -401.44192) (xy 439.638948 -401.44192) (xy 439.638948 -402.41982)
			(xy 440.683648 -402.41982) (xy 440.687719 -402.364198) (xy 440.699845 -402.309761) (xy 440.719768 -402.25767)
			(xy 440.747064 -402.209035) (xy 440.78115 -402.164892) (xy 440.821299 -402.126183) (xy 440.866657 -402.093732)
			(xy 440.916257 -402.068231) (xy 440.969041 -402.050224) (xy 441.023884 -402.040094) (xy 441.079618 -402.038057)
			(xy 441.135055 -402.044157) (xy 441.189012 -402.058263) (xy 441.240341 -402.080075) (xy 441.287947 -402.109129)
			(xy 441.330815 -402.144804) (xy 441.360569 -402.178012) (xy 443.299848 -402.178012) (xy 443.303919 -402.12239)
			(xy 443.316045 -402.067953) (xy 443.335968 -402.015862) (xy 443.363264 -401.967227) (xy 443.39735 -401.923084)
			(xy 443.437499 -401.884375) (xy 443.482857 -401.851924) (xy 443.532457 -401.826423) (xy 443.585241 -401.808416)
			(xy 443.640084 -401.798286) (xy 443.695818 -401.796249) (xy 443.751255 -401.802349) (xy 443.805212 -401.816455)
			(xy 443.856541 -401.838267) (xy 443.904147 -401.867321) (xy 443.947015 -401.902996) (xy 443.984232 -401.944533)
			(xy 444.015005 -401.991046) (xy 444.038677 -402.041543) (xy 444.054745 -402.09495) (xy 444.062865 -402.150126)
			(xy 444.063374 -402.178012) (xy 444.06291 -402.203412) (xy 445.01003 -402.203412) (xy 445.014101 -402.14779)
			(xy 445.026227 -402.093353) (xy 445.04615 -402.041262) (xy 445.073446 -401.992627) (xy 445.107532 -401.948484)
			(xy 445.147681 -401.909775) (xy 445.193039 -401.877324) (xy 445.242639 -401.851823) (xy 445.295423 -401.833816)
			(xy 445.350266 -401.823686) (xy 445.406 -401.821649) (xy 445.461437 -401.827749) (xy 445.515394 -401.841855)
			(xy 445.566723 -401.863667) (xy 445.582363 -401.873212) (xy 451.885048 -401.873212) (xy 451.889119 -401.81759)
			(xy 451.901245 -401.763153) (xy 451.921168 -401.711062) (xy 451.948464 -401.662427) (xy 451.98255 -401.618284)
			(xy 452.022699 -401.579575) (xy 452.068057 -401.547124) (xy 452.117657 -401.521623) (xy 452.170441 -401.503616)
			(xy 452.225284 -401.493486) (xy 452.281018 -401.491449) (xy 452.336455 -401.497549) (xy 452.390412 -401.511655)
			(xy 452.441741 -401.533467) (xy 452.489347 -401.562521) (xy 452.532215 -401.598196) (xy 452.569432 -401.639733)
			(xy 452.600205 -401.686246) (xy 452.623877 -401.736743) (xy 452.639945 -401.79015) (xy 452.648065 -401.845326)
			(xy 452.648574 -401.873212) (xy 452.648065 -401.901098) (xy 452.639945 -401.956274) (xy 452.623877 -402.009681)
			(xy 452.600205 -402.060178) (xy 452.569432 -402.106691) (xy 452.532215 -402.148228) (xy 452.526947 -402.152612)
			(xy 454.098658 -402.152612) (xy 454.102729 -402.09699) (xy 454.114855 -402.042553) (xy 454.134778 -401.990462)
			(xy 454.162074 -401.941827) (xy 454.19616 -401.897684) (xy 454.236309 -401.858975) (xy 454.281667 -401.826524)
			(xy 454.331267 -401.801023) (xy 454.384051 -401.783016) (xy 454.438894 -401.772886) (xy 454.494628 -401.770849)
			(xy 454.550065 -401.776949) (xy 454.604022 -401.791055) (xy 454.655351 -401.812867) (xy 454.702957 -401.841921)
			(xy 454.745825 -401.877596) (xy 454.783042 -401.919133) (xy 454.813815 -401.965646) (xy 454.837487 -402.016143)
			(xy 454.853555 -402.06955) (xy 454.861675 -402.124726) (xy 454.862184 -402.152612) (xy 454.861675 -402.180498)
			(xy 454.853555 -402.235674) (xy 454.837487 -402.289081) (xy 454.813815 -402.339578) (xy 454.783042 -402.386091)
			(xy 454.745825 -402.427628) (xy 454.702957 -402.463303) (xy 454.655351 -402.492357) (xy 454.604022 -402.514169)
			(xy 454.550065 -402.528275) (xy 454.494628 -402.534375) (xy 454.438894 -402.532338) (xy 454.384051 -402.522208)
			(xy 454.331267 -402.504201) (xy 454.281667 -402.4787) (xy 454.236309 -402.446249) (xy 454.19616 -402.40754)
			(xy 454.162074 -402.363397) (xy 454.134778 -402.314762) (xy 454.114855 -402.262671) (xy 454.102729 -402.208234)
			(xy 454.098658 -402.152612) (xy 452.526947 -402.152612) (xy 452.489347 -402.183903) (xy 452.441741 -402.212957)
			(xy 452.390412 -402.234769) (xy 452.336455 -402.248875) (xy 452.281018 -402.254975) (xy 452.225284 -402.252938)
			(xy 452.170441 -402.242808) (xy 452.117657 -402.224801) (xy 452.068057 -402.1993) (xy 452.022699 -402.166849)
			(xy 451.98255 -402.12814) (xy 451.948464 -402.083997) (xy 451.921168 -402.035362) (xy 451.901245 -401.983271)
			(xy 451.889119 -401.928834) (xy 451.885048 -401.873212) (xy 445.582363 -401.873212) (xy 445.614329 -401.892721)
			(xy 445.657197 -401.928396) (xy 445.694414 -401.969933) (xy 445.725187 -402.016446) (xy 445.748859 -402.066943)
			(xy 445.764927 -402.12035) (xy 445.773047 -402.175526) (xy 445.773556 -402.203412) (xy 445.773047 -402.231298)
			(xy 445.764927 -402.286474) (xy 445.748859 -402.339881) (xy 445.725187 -402.390378) (xy 445.694414 -402.436891)
			(xy 445.657197 -402.478428) (xy 445.614329 -402.514103) (xy 445.566723 -402.543157) (xy 445.515394 -402.564969)
			(xy 445.461437 -402.579075) (xy 445.406 -402.585175) (xy 445.350266 -402.583138) (xy 445.295423 -402.573008)
			(xy 445.242639 -402.555001) (xy 445.193039 -402.5295) (xy 445.147681 -402.497049) (xy 445.107532 -402.45834)
			(xy 445.073446 -402.414197) (xy 445.04615 -402.365562) (xy 445.026227 -402.313471) (xy 445.014101 -402.259034)
			(xy 445.01003 -402.203412) (xy 444.06291 -402.203412) (xy 444.062865 -402.205898) (xy 444.054745 -402.261074)
			(xy 444.038677 -402.314481) (xy 444.015005 -402.364978) (xy 443.984232 -402.411491) (xy 443.947015 -402.453028)
			(xy 443.904147 -402.488703) (xy 443.856541 -402.517757) (xy 443.805212 -402.539569) (xy 443.751255 -402.553675)
			(xy 443.695818 -402.559775) (xy 443.640084 -402.557738) (xy 443.585241 -402.547608) (xy 443.532457 -402.529601)
			(xy 443.482857 -402.5041) (xy 443.437499 -402.471649) (xy 443.39735 -402.43294) (xy 443.363264 -402.388797)
			(xy 443.335968 -402.340162) (xy 443.316045 -402.288071) (xy 443.303919 -402.233634) (xy 443.299848 -402.178012)
			(xy 441.360569 -402.178012) (xy 441.368032 -402.186341) (xy 441.398805 -402.232854) (xy 441.422477 -402.283351)
			(xy 441.438545 -402.336758) (xy 441.446665 -402.391934) (xy 441.447174 -402.41982) (xy 441.446665 -402.447706)
			(xy 441.438545 -402.502882) (xy 441.422477 -402.556289) (xy 441.398805 -402.606786) (xy 441.368032 -402.653299)
			(xy 441.330815 -402.694836) (xy 441.32275 -402.701548) (xy 450.670706 -402.701548) (xy 450.670706 -402.647052)
			(xy 450.678461 -402.59311) (xy 450.693814 -402.540821) (xy 450.716452 -402.491249) (xy 450.745914 -402.445404)
			(xy 450.7816 -402.404217) (xy 450.822784 -402.368528) (xy 450.868628 -402.339063) (xy 450.918199 -402.316423)
			(xy 450.970487 -402.301067) (xy 451.024428 -402.293308) (xy 451.051676 -402.29282) (xy 451.080593 -402.293348)
			(xy 451.137764 -402.302074) (xy 451.192963 -402.31933) (xy 451.244925 -402.344719) (xy 451.292459 -402.377661)
			(xy 451.334476 -402.417401) (xy 451.352666 -402.439886) (xy 451.360249 -402.448626) (xy 451.380992 -402.458822)
			(xy 451.392544 -402.459444) (xy 451.472808 -402.459444) (xy 451.48438 -402.458898) (xy 451.505151 -402.448688)
			(xy 451.512686 -402.439886) (xy 451.530881 -402.417406) (xy 451.572901 -402.377672) (xy 451.620435 -402.344732)
			(xy 451.672395 -402.319344) (xy 451.727592 -402.302086) (xy 451.78476 -402.293356) (xy 451.813676 -402.29282)
			(xy 451.840932 -402.293225) (xy 451.89489 -402.30098) (xy 451.947194 -402.316335) (xy 451.996781 -402.338978)
			(xy 452.042641 -402.368448) (xy 452.083839 -402.404144) (xy 452.119538 -402.44534) (xy 452.149011 -402.491198)
			(xy 452.171656 -402.540783) (xy 452.187015 -402.593087) (xy 452.194773 -402.647044) (xy 452.194773 -402.701556)
			(xy 452.187015 -402.755513) (xy 452.171656 -402.807817) (xy 452.149011 -402.857402) (xy 452.119538 -402.90326)
			(xy 452.083839 -402.944456) (xy 452.042641 -402.980152) (xy 451.996781 -403.009622) (xy 451.947194 -403.032265)
			(xy 451.89489 -403.04762) (xy 451.840932 -403.055375) (xy 451.813676 -403.055836) (xy 451.78476 -403.055287)
			(xy 451.727589 -403.046568) (xy 451.67239 -403.029318) (xy 451.620427 -403.003932) (xy 451.572893 -402.970992)
			(xy 451.530876 -402.931254) (xy 451.512686 -402.90877) (xy 451.505131 -402.900001) (xy 451.484367 -402.889823)
			(xy 451.472808 -402.889212) (xy 451.392544 -402.889212) (xy 451.380979 -402.889803) (xy 451.360207 -402.899983)
			(xy 451.352666 -402.90877) (xy 451.334487 -402.931264) (xy 451.292465 -402.970999) (xy 451.244928 -403.003938)
			(xy 451.192965 -403.029325) (xy 451.137765 -403.046579) (xy 451.080593 -403.055304) (xy 451.051676 -403.055836)
			(xy 451.024428 -403.055292) (xy 450.970487 -403.047533) (xy 450.918199 -403.032177) (xy 450.868628 -403.009537)
			(xy 450.822784 -402.980072) (xy 450.7816 -402.944383) (xy 450.745914 -402.903196) (xy 450.716452 -402.857351)
			(xy 450.693814 -402.807779) (xy 450.678461 -402.75549) (xy 450.670706 -402.701548) (xy 441.32275 -402.701548)
			(xy 441.287947 -402.730511) (xy 441.240341 -402.759565) (xy 441.189012 -402.781377) (xy 441.135055 -402.795483)
			(xy 441.079618 -402.801583) (xy 441.023884 -402.799546) (xy 440.969041 -402.789416) (xy 440.916257 -402.771409)
			(xy 440.866657 -402.745908) (xy 440.821299 -402.713457) (xy 440.78115 -402.674748) (xy 440.747064 -402.630605)
			(xy 440.719768 -402.58197) (xy 440.699845 -402.529879) (xy 440.687719 -402.475442) (xy 440.683648 -402.41982)
			(xy 439.638948 -402.41982) (xy 439.638948 -403.27707) (xy 443.122048 -403.27707) (xy 443.126119 -403.221448)
			(xy 443.138245 -403.167011) (xy 443.158168 -403.11492) (xy 443.185464 -403.066285) (xy 443.21955 -403.022142)
			(xy 443.259699 -402.983433) (xy 443.305057 -402.950982) (xy 443.354657 -402.925481) (xy 443.407441 -402.907474)
			(xy 443.462284 -402.897344) (xy 443.518018 -402.895307) (xy 443.573455 -402.901407) (xy 443.627412 -402.915513)
			(xy 443.678741 -402.937325) (xy 443.726347 -402.966379) (xy 443.769215 -403.002054) (xy 443.806432 -403.043591)
			(xy 443.837205 -403.090104) (xy 443.860877 -403.140601) (xy 443.876945 -403.194008) (xy 443.885065 -403.249184)
			(xy 443.885574 -403.27707) (xy 443.885065 -403.304956) (xy 443.876945 -403.360132) (xy 443.860877 -403.413539)
			(xy 443.837205 -403.464036) (xy 443.806432 -403.510549) (xy 443.769215 -403.552086) (xy 443.726347 -403.587761)
			(xy 443.678741 -403.616815) (xy 443.627412 -403.638627) (xy 443.573455 -403.652733) (xy 443.518018 -403.658833)
			(xy 443.462284 -403.656796) (xy 443.407441 -403.646666) (xy 443.354657 -403.628659) (xy 443.305057 -403.603158)
			(xy 443.259699 -403.570707) (xy 443.21955 -403.531998) (xy 443.185464 -403.487855) (xy 443.158168 -403.43922)
			(xy 443.138245 -403.387129) (xy 443.126119 -403.332692) (xy 443.122048 -403.27707) (xy 439.638948 -403.27707)
			(xy 439.638948 -403.668992) (xy 439.639394 -403.67902) (xy 439.646984 -403.697581) (xy 439.65368 -403.70506)
			(xy 439.830718 -403.882098) (xy 439.853876 -403.906012) (xy 439.894419 -403.958812) (xy 439.927729 -404.016448)
			(xy 439.953236 -404.077938) (xy 439.970504 -404.142229) (xy 439.979238 -404.208224) (xy 439.979816 -404.241508)
			(xy 439.979816 -406.209246) (xy 448.698112 -406.209246) (xy 448.698678 -406.179635) (xy 448.707823 -406.121123)
			(xy 448.7259 -406.064727) (xy 448.752476 -406.011803) (xy 448.786911 -405.963621) (xy 448.828378 -405.92134)
			(xy 448.875882 -405.885974) (xy 448.90182 -405.87168) (xy 448.913621 -405.865041) (xy 448.933432 -405.846593)
			(xy 448.947695 -405.823585) (xy 448.955406 -405.797636) (xy 448.956023 -405.770573) (xy 448.949502 -405.7443)
			(xy 448.936302 -405.720666) (xy 448.917353 -405.701334) (xy 448.905884 -405.694134) (xy 448.881637 -405.679373)
			(xy 448.837444 -405.643748) (xy 448.799017 -405.601968) (xy 448.767207 -405.554953) (xy 448.742716 -405.503744)
			(xy 448.726084 -405.449471) (xy 448.717679 -405.393332) (xy 448.717162 -405.36495) (xy 448.717648 -405.337699)
			(xy 448.725404 -405.283751) (xy 448.740759 -405.231456) (xy 448.763401 -405.181879) (xy 448.792867 -405.136029)
			(xy 448.828558 -405.094838) (xy 448.869749 -405.059147) (xy 448.915599 -405.029681) (xy 448.965176 -405.007039)
			(xy 449.017471 -404.991684) (xy 449.071419 -404.983928) (xy 449.125921 -404.983928) (xy 449.179869 -404.991684)
			(xy 449.232164 -405.007039) (xy 449.281741 -405.029681) (xy 449.327591 -405.059147) (xy 449.368782 -405.094838)
			(xy 449.404473 -405.136029) (xy 449.433939 -405.181879) (xy 449.456581 -405.231456) (xy 449.471936 -405.283751)
			(xy 449.479692 -405.337699) (xy 449.480178 -405.36495) (xy 449.479614 -405.394561) (xy 449.47047 -405.453073)
			(xy 449.452392 -405.509469) (xy 449.425817 -405.562394) (xy 449.391381 -405.610576) (xy 449.349913 -405.652857)
			(xy 449.302409 -405.688222) (xy 449.27647 -405.702516) (xy 449.264673 -405.709161) (xy 449.244864 -405.727609)
			(xy 449.230603 -405.750616) (xy 449.222893 -405.776563) (xy 449.222275 -405.803624) (xy 449.228795 -405.829896)
			(xy 449.241992 -405.853529) (xy 449.260939 -405.872861) (xy 449.272406 -405.880062) (xy 449.296649 -405.894829)
			(xy 449.340843 -405.930453) (xy 449.37927 -405.972232) (xy 449.41108 -406.019245) (xy 449.435572 -406.070453)
			(xy 449.452205 -406.124726) (xy 449.46061 -406.180864) (xy 449.461128 -406.209246) (xy 449.460642 -406.236497)
			(xy 449.452886 -406.290445) (xy 449.437531 -406.34274) (xy 449.433305 -406.351994) (xy 456.067414 -406.351994)
			(xy 456.067927 -406.323785) (xy 456.076229 -406.267981) (xy 456.092666 -406.214011) (xy 456.116878 -406.163053)
			(xy 456.148338 -406.11622) (xy 456.186356 -406.074536) (xy 456.230104 -406.038912) (xy 456.254104 -406.02408)
			(xy 456.266496 -406.016145) (xy 456.286401 -405.994487) (xy 456.299322 -405.968061) (xy 456.30419 -405.939051)
			(xy 456.300602 -405.909854) (xy 456.288857 -405.882886) (xy 456.269923 -405.860373) (xy 456.257914 -405.851868)
			(xy 456.235704 -405.836632) (xy 456.195365 -405.800945) (xy 456.160445 -405.759942) (xy 456.131636 -405.714436)
			(xy 456.109511 -405.665331) (xy 456.09451 -405.613604) (xy 456.08693 -405.560281) (xy 456.086464 -405.533352)
			(xy 456.08695 -405.506101) (xy 456.094706 -405.452153) (xy 456.110061 -405.399858) (xy 456.132703 -405.350281)
			(xy 456.162169 -405.304431) (xy 456.19786 -405.26324) (xy 456.239051 -405.227549) (xy 456.284901 -405.198083)
			(xy 456.334478 -405.175441) (xy 456.386773 -405.160086) (xy 456.440721 -405.15233) (xy 456.495223 -405.15233)
			(xy 456.549171 -405.160086) (xy 456.601466 -405.175441) (xy 456.651043 -405.198083) (xy 456.696893 -405.227549)
			(xy 456.738084 -405.26324) (xy 456.773775 -405.304431) (xy 456.803241 -405.350281) (xy 456.825883 -405.399858)
			(xy 456.841238 -405.452153) (xy 456.848994 -405.506101) (xy 456.84948 -405.533352) (xy 456.848927 -405.56156)
			(xy 456.840633 -405.617362) (xy 456.824203 -405.671331) (xy 456.799998 -405.722289) (xy 456.768544 -405.769122)
			(xy 456.730531 -405.810808) (xy 456.686788 -405.846434) (xy 456.66279 -405.861266) (xy 456.650449 -405.869273)
			(xy 456.630548 -405.890916) (xy 456.617626 -405.917326) (xy 456.612753 -405.946321) (xy 456.61633 -405.975505)
			(xy 456.628062 -406.002465) (xy 456.646979 -406.024973) (xy 456.65898 -406.033478) (xy 456.68121 -406.048686)
			(xy 456.721549 -406.084377) (xy 456.756468 -406.125386) (xy 456.785275 -406.170896) (xy 456.807396 -406.220005)
			(xy 456.822393 -406.271737) (xy 456.829967 -406.325063) (xy 456.83043 -406.351994) (xy 456.829944 -406.379245)
			(xy 456.822188 -406.433193) (xy 456.806833 -406.485488) (xy 456.784191 -406.535065) (xy 456.754725 -406.580915)
			(xy 456.719034 -406.622106) (xy 456.677843 -406.657797) (xy 456.631993 -406.687263) (xy 456.582416 -406.709905)
			(xy 456.530121 -406.72526) (xy 456.476173 -406.733016) (xy 456.421671 -406.733016) (xy 456.367723 -406.72526)
			(xy 456.315428 -406.709905) (xy 456.265851 -406.687263) (xy 456.220001 -406.657797) (xy 456.17881 -406.622106)
			(xy 456.143119 -406.580915) (xy 456.113653 -406.535065) (xy 456.091011 -406.485488) (xy 456.075656 -406.433193)
			(xy 456.0679 -406.379245) (xy 456.067414 -406.351994) (xy 449.433305 -406.351994) (xy 449.414889 -406.392317)
			(xy 449.385423 -406.438167) (xy 449.349732 -406.479358) (xy 449.308541 -406.515049) (xy 449.262691 -406.544515)
			(xy 449.213114 -406.567157) (xy 449.160819 -406.582512) (xy 449.106871 -406.590268) (xy 449.052369 -406.590268)
			(xy 448.998421 -406.582512) (xy 448.946126 -406.567157) (xy 448.896549 -406.544515) (xy 448.850699 -406.515049)
			(xy 448.809508 -406.479358) (xy 448.773817 -406.438167) (xy 448.744351 -406.392317) (xy 448.721709 -406.34274)
			(xy 448.706354 -406.290445) (xy 448.698598 -406.236497) (xy 448.698112 -406.209246) (xy 439.979816 -406.209246)
			(xy 439.979816 -407.199846) (xy 448.698112 -407.199846) (xy 448.698598 -407.172595) (xy 448.706354 -407.118647)
			(xy 448.721709 -407.066352) (xy 448.744351 -407.016775) (xy 448.773817 -406.970925) (xy 448.809508 -406.929734)
			(xy 448.850699 -406.894043) (xy 448.896549 -406.864577) (xy 448.946126 -406.841935) (xy 448.998421 -406.82658)
			(xy 449.052369 -406.818824) (xy 449.106871 -406.818824) (xy 449.160819 -406.82658) (xy 449.213114 -406.841935)
			(xy 449.262691 -406.864577) (xy 449.308541 -406.894043) (xy 449.349732 -406.929734) (xy 449.385423 -406.970925)
			(xy 449.414889 -407.016775) (xy 449.437531 -407.066352) (xy 449.452886 -407.118647) (xy 449.460642 -407.172595)
			(xy 449.461128 -407.199846) (xy 449.460563 -407.228837) (xy 449.451777 -407.286151) (xy 449.43798 -407.330148)
			(xy 456.075796 -407.330148) (xy 456.076282 -407.302897) (xy 456.084038 -407.248949) (xy 456.099393 -407.196654)
			(xy 456.122035 -407.147077) (xy 456.151501 -407.101227) (xy 456.187192 -407.060036) (xy 456.228383 -407.024345)
			(xy 456.274233 -406.994879) (xy 456.32381 -406.972237) (xy 456.376105 -406.956882) (xy 456.430053 -406.949126)
			(xy 456.484555 -406.949126) (xy 456.538503 -406.956882) (xy 456.590798 -406.972237) (xy 456.640375 -406.994879)
			(xy 456.686225 -407.024345) (xy 456.727416 -407.060036) (xy 456.763107 -407.101227) (xy 456.792573 -407.147077)
			(xy 456.815215 -407.196654) (xy 456.83057 -407.248949) (xy 456.838326 -407.302897) (xy 456.838812 -407.330148)
			(xy 456.838291 -407.35901) (xy 456.829609 -407.416078) (xy 456.812419 -407.471184) (xy 456.787116 -407.523067)
			(xy 456.754278 -407.570541) (xy 456.714656 -407.612519) (xy 456.669156 -407.648043) (xy 456.644248 -407.662634)
			(xy 456.632498 -407.669733) (xy 456.61303 -407.689076) (xy 456.599416 -407.712904) (xy 456.592637 -407.739497)
			(xy 456.593184 -407.766935) (xy 456.601016 -407.793237) (xy 456.615569 -407.816504) (xy 456.635792 -407.835056)
			(xy 456.647804 -407.841704) (xy 456.670957 -407.854001) (xy 456.713937 -407.884023) (xy 456.752403 -407.919644)
			(xy 456.785633 -407.960193) (xy 456.813001 -408.004909) (xy 456.833993 -408.05295) (xy 456.848213 -408.103411)
			(xy 456.855393 -408.155343) (xy 456.85583 -408.181556) (xy 456.855344 -408.208807) (xy 456.847588 -408.262755)
			(xy 456.832233 -408.31505) (xy 456.809591 -408.364627) (xy 456.780125 -408.410477) (xy 456.744434 -408.451668)
			(xy 456.703243 -408.487359) (xy 456.657393 -408.516825) (xy 456.607816 -408.539467) (xy 456.555521 -408.554822)
			(xy 456.501573 -408.562578) (xy 456.447071 -408.562578) (xy 456.393123 -408.554822) (xy 456.340828 -408.539467)
			(xy 456.291251 -408.516825) (xy 456.245401 -408.487359) (xy 456.20421 -408.451668) (xy 456.168519 -408.410477)
			(xy 456.139053 -408.364627) (xy 456.116411 -408.31505) (xy 456.101056 -408.262755) (xy 456.0933 -408.208807)
			(xy 456.092814 -408.181556) (xy 456.093325 -408.152693) (xy 456.102008 -408.095624) (xy 456.119198 -408.040518)
			(xy 456.144503 -407.988634) (xy 456.177343 -407.94116) (xy 456.216967 -407.899183) (xy 456.262469 -407.863661)
			(xy 456.287378 -407.84907) (xy 456.299122 -407.841963) (xy 456.318584 -407.822619) (xy 456.332195 -407.798793)
			(xy 456.338971 -407.772203) (xy 456.338425 -407.744769) (xy 456.330596 -407.718469) (xy 456.316048 -407.695203)
			(xy 456.295831 -407.67665) (xy 456.283822 -407.67) (xy 456.260676 -407.657689) (xy 456.217696 -407.62767)
			(xy 456.179228 -407.592052) (xy 456.145997 -407.551504) (xy 456.118628 -407.50679) (xy 456.097635 -407.458752)
			(xy 456.083415 -407.408292) (xy 456.076233 -407.356361) (xy 456.075796 -407.330148) (xy 449.43798 -407.330148)
			(xy 449.434427 -407.341477) (xy 449.408913 -407.393546) (xy 449.375822 -407.441159) (xy 449.335914 -407.483223)
			(xy 449.290106 -407.51877) (xy 449.26504 -407.533348) (xy 449.25296 -407.540612) (xy 449.233005 -407.560503)
			(xy 449.219245 -407.585089) (xy 449.212726 -407.6125) (xy 449.213945 -407.640649) (xy 449.222808 -407.667394)
			(xy 449.238641 -407.690699) (xy 449.260239 -407.708792) (xy 449.272914 -407.714958) (xy 449.29783 -407.726553)
			(xy 449.344309 -407.755877) (xy 449.386098 -407.791567) (xy 449.422332 -407.832886) (xy 449.452262 -407.878977)
			(xy 449.475267 -407.928886) (xy 449.490871 -407.98158) (xy 449.498752 -408.035968) (xy 449.499228 -408.063446)
			(xy 449.498742 -408.090697) (xy 449.490986 -408.144645) (xy 449.475631 -408.19694) (xy 449.452989 -408.246517)
			(xy 449.423523 -408.292367) (xy 449.387832 -408.333558) (xy 449.346641 -408.369249) (xy 449.300791 -408.398715)
			(xy 449.251214 -408.421357) (xy 449.198919 -408.436712) (xy 449.144971 -408.444468) (xy 449.090469 -408.444468)
			(xy 449.036521 -408.436712) (xy 448.984226 -408.421357) (xy 448.934649 -408.398715) (xy 448.888799 -408.369249)
			(xy 448.847608 -408.333558) (xy 448.811917 -408.292367) (xy 448.782451 -408.246517) (xy 448.759809 -408.19694)
			(xy 448.744454 -408.144645) (xy 448.736698 -408.090697) (xy 448.736212 -408.063446) (xy 448.73675 -408.034453)
			(xy 448.745539 -407.977138) (xy 448.762892 -407.92181) (xy 448.788409 -407.869741) (xy 448.821505 -407.822128)
			(xy 448.861418 -407.780065) (xy 448.907232 -407.74452) (xy 448.9323 -407.729944) (xy 448.944382 -407.722687)
			(xy 448.964329 -407.702791) (xy 448.978083 -407.678204) (xy 448.984598 -407.650795) (xy 448.983379 -407.622649)
			(xy 448.974518 -407.595905) (xy 448.95869 -407.5726) (xy 448.937098 -407.554503) (xy 448.924426 -407.548334)
			(xy 448.899516 -407.536726) (xy 448.853036 -407.507406) (xy 448.811245 -407.471718) (xy 448.775009 -407.430402)
			(xy 448.745078 -407.384313) (xy 448.722072 -407.334405) (xy 448.706468 -407.281711) (xy 448.698588 -407.227324)
			(xy 448.698112 -407.199846) (xy 439.979816 -407.199846) (xy 439.979816 -410.578554) (xy 446.710306 -410.578554)
			(xy 446.714377 -410.522932) (xy 446.726503 -410.468495) (xy 446.746426 -410.416404) (xy 446.773722 -410.367769)
			(xy 446.807808 -410.323626) (xy 446.847957 -410.284917) (xy 446.893315 -410.252466) (xy 446.942915 -410.226965)
			(xy 446.995699 -410.208958) (xy 447.050542 -410.198828) (xy 447.106276 -410.196791) (xy 447.161713 -410.202891)
			(xy 447.21567 -410.216997) (xy 447.266999 -410.238809) (xy 447.314605 -410.267863) (xy 447.357473 -410.303538)
			(xy 447.39469 -410.345075) (xy 447.425463 -410.391588) (xy 447.449135 -410.442085) (xy 447.465203 -410.495492)
			(xy 447.473323 -410.550668) (xy 447.473832 -410.578554) (xy 447.599306 -410.578554) (xy 447.603377 -410.522932)
			(xy 447.615503 -410.468495) (xy 447.635426 -410.416404) (xy 447.662722 -410.367769) (xy 447.696808 -410.323626)
			(xy 447.736957 -410.284917) (xy 447.782315 -410.252466) (xy 447.831915 -410.226965) (xy 447.884699 -410.208958)
			(xy 447.939542 -410.198828) (xy 447.995276 -410.196791) (xy 448.050713 -410.202891) (xy 448.10467 -410.216997)
			(xy 448.155999 -410.238809) (xy 448.203605 -410.267863) (xy 448.246473 -410.303538) (xy 448.28369 -410.345075)
			(xy 448.314463 -410.391588) (xy 448.338135 -410.442085) (xy 448.354203 -410.495492) (xy 448.362323 -410.550668)
			(xy 448.362832 -410.578554) (xy 448.488306 -410.578554) (xy 448.492377 -410.522932) (xy 448.504503 -410.468495)
			(xy 448.524426 -410.416404) (xy 448.551722 -410.367769) (xy 448.585808 -410.323626) (xy 448.625957 -410.284917)
			(xy 448.671315 -410.252466) (xy 448.720915 -410.226965) (xy 448.773699 -410.208958) (xy 448.828542 -410.198828)
			(xy 448.884276 -410.196791) (xy 448.939713 -410.202891) (xy 448.99367 -410.216997) (xy 449.044999 -410.238809)
			(xy 449.092605 -410.267863) (xy 449.135473 -410.303538) (xy 449.17269 -410.345075) (xy 449.203463 -410.391588)
			(xy 449.227135 -410.442085) (xy 449.243203 -410.495492) (xy 449.251323 -410.550668) (xy 449.251832 -410.578554)
			(xy 449.251323 -410.60644) (xy 449.243203 -410.661616) (xy 449.227135 -410.715023) (xy 449.203463 -410.76552)
			(xy 449.17269 -410.812033) (xy 449.135473 -410.85357) (xy 449.092605 -410.889245) (xy 449.071044 -410.902404)
			(xy 451.091808 -410.902404) (xy 451.092365 -410.87228) (xy 451.101847 -410.812782) (xy 451.12056 -410.755513)
			(xy 451.14804 -410.701897) (xy 451.183603 -410.653264) (xy 451.204584 -410.63164) (xy 451.21195 -410.624528)
			(xy 451.21957 -410.605732) (xy 451.21957 -410.513276) (xy 451.21195 -410.49448) (xy 451.204584 -410.487368)
			(xy 451.183608 -410.465739) (xy 451.14804 -410.417111) (xy 451.12056 -410.363495) (xy 451.10185 -410.306226)
			(xy 451.092377 -410.246728) (xy 451.091808 -410.216604) (xy 451.092259 -410.189351) (xy 451.100016 -410.135398)
			(xy 451.115372 -410.083099) (xy 451.138015 -410.033518) (xy 451.167485 -409.987664) (xy 451.20318 -409.946471)
			(xy 451.244374 -409.910777) (xy 451.290229 -409.88131) (xy 451.339811 -409.858668) (xy 451.39211 -409.843313)
			(xy 451.446063 -409.835558) (xy 451.473316 -409.835096) (xy 451.503441 -409.835643) (xy 451.562939 -409.845128)
			(xy 451.620207 -409.863844) (xy 451.673824 -409.891325) (xy 451.722457 -409.92689) (xy 451.74408 -409.947872)
			(xy 451.751192 -409.955238) (xy 451.769988 -409.962858) (xy 451.862444 -409.962858) (xy 451.88124 -409.955238)
			(xy 451.888352 -409.947872) (xy 451.909987 -409.926903) (xy 451.958612 -409.89133) (xy 452.012225 -409.863847)
			(xy 452.069494 -409.845136) (xy 452.128992 -409.835665) (xy 452.159116 -409.835096) (xy 452.186487 -409.835554)
			(xy 452.240666 -409.843374) (xy 452.293169 -409.858865) (xy 452.342916 -409.881708) (xy 452.388882 -409.911434)
			(xy 452.409814 -409.929076) (xy 452.416926 -409.935172) (xy 452.433944 -409.941522) (xy 452.519288 -409.941522)
			(xy 452.536306 -409.935172) (xy 452.543418 -409.929076) (xy 452.564367 -409.911458) (xy 452.610336 -409.881744)
			(xy 452.660079 -409.858904) (xy 452.712576 -409.843408) (xy 452.766748 -409.835574) (xy 452.794116 -409.835096)
			(xy 452.821368 -409.835563) (xy 452.875316 -409.843322) (xy 452.927612 -409.858679) (xy 452.977189 -409.881322)
			(xy 453.02304 -409.910791) (xy 453.06423 -409.946484) (xy 453.099921 -409.987676) (xy 453.129387 -410.033528)
			(xy 453.152028 -410.083107) (xy 453.167383 -410.135403) (xy 453.175139 -410.189352) (xy 453.175624 -410.216604)
			(xy 453.175063 -410.246728) (xy 453.165581 -410.306225) (xy 453.146868 -410.363493) (xy 453.11939 -410.41711)
			(xy 453.083828 -410.465744) (xy 453.062848 -410.487368) (xy 453.055482 -410.49448) (xy 453.047862 -410.513276)
			(xy 453.047862 -410.6037) (xy 454.780648 -410.6037) (xy 454.784719 -410.548078) (xy 454.796845 -410.493641)
			(xy 454.816768 -410.44155) (xy 454.844064 -410.392915) (xy 454.87815 -410.348772) (xy 454.918299 -410.310063)
			(xy 454.963657 -410.277612) (xy 455.013257 -410.252111) (xy 455.066041 -410.234104) (xy 455.120884 -410.223974)
			(xy 455.176618 -410.221937) (xy 455.232055 -410.228037) (xy 455.286012 -410.242143) (xy 455.337341 -410.263955)
			(xy 455.384947 -410.293009) (xy 455.427815 -410.328684) (xy 455.465032 -410.370221) (xy 455.495805 -410.416734)
			(xy 455.519477 -410.467231) (xy 455.535545 -410.520638) (xy 455.543665 -410.575814) (xy 455.544174 -410.6037)
			(xy 455.669648 -410.6037) (xy 455.673719 -410.548078) (xy 455.685845 -410.493641) (xy 455.705768 -410.44155)
			(xy 455.733064 -410.392915) (xy 455.76715 -410.348772) (xy 455.807299 -410.310063) (xy 455.852657 -410.277612)
			(xy 455.902257 -410.252111) (xy 455.955041 -410.234104) (xy 456.009884 -410.223974) (xy 456.065618 -410.221937)
			(xy 456.121055 -410.228037) (xy 456.175012 -410.242143) (xy 456.226341 -410.263955) (xy 456.273947 -410.293009)
			(xy 456.316815 -410.328684) (xy 456.354032 -410.370221) (xy 456.384805 -410.416734) (xy 456.408477 -410.467231)
			(xy 456.424545 -410.520638) (xy 456.432665 -410.575814) (xy 456.433174 -410.6037) (xy 456.558648 -410.6037)
			(xy 456.562719 -410.548078) (xy 456.574845 -410.493641) (xy 456.594768 -410.44155) (xy 456.622064 -410.392915)
			(xy 456.65615 -410.348772) (xy 456.696299 -410.310063) (xy 456.741657 -410.277612) (xy 456.791257 -410.252111)
			(xy 456.844041 -410.234104) (xy 456.898884 -410.223974) (xy 456.954618 -410.221937) (xy 457.010055 -410.228037)
			(xy 457.064012 -410.242143) (xy 457.115341 -410.263955) (xy 457.162947 -410.293009) (xy 457.205815 -410.328684)
			(xy 457.243032 -410.370221) (xy 457.273805 -410.416734) (xy 457.297477 -410.467231) (xy 457.313545 -410.520638)
			(xy 457.321665 -410.575814) (xy 457.322174 -410.6037) (xy 457.321665 -410.631586) (xy 457.313545 -410.686762)
			(xy 457.297477 -410.740169) (xy 457.273805 -410.790666) (xy 457.243032 -410.837179) (xy 457.205815 -410.878716)
			(xy 457.162947 -410.914391) (xy 457.115341 -410.943445) (xy 457.064012 -410.965257) (xy 457.010055 -410.979363)
			(xy 456.954618 -410.985463) (xy 456.898884 -410.983426) (xy 456.844041 -410.973296) (xy 456.791257 -410.955289)
			(xy 456.741657 -410.929788) (xy 456.696299 -410.897337) (xy 456.65615 -410.858628) (xy 456.622064 -410.814485)
			(xy 456.594768 -410.76585) (xy 456.574845 -410.713759) (xy 456.562719 -410.659322) (xy 456.558648 -410.6037)
			(xy 456.433174 -410.6037) (xy 456.432665 -410.631586) (xy 456.424545 -410.686762) (xy 456.408477 -410.740169)
			(xy 456.384805 -410.790666) (xy 456.354032 -410.837179) (xy 456.316815 -410.878716) (xy 456.273947 -410.914391)
			(xy 456.226341 -410.943445) (xy 456.175012 -410.965257) (xy 456.121055 -410.979363) (xy 456.065618 -410.985463)
			(xy 456.009884 -410.983426) (xy 455.955041 -410.973296) (xy 455.902257 -410.955289) (xy 455.852657 -410.929788)
			(xy 455.807299 -410.897337) (xy 455.76715 -410.858628) (xy 455.733064 -410.814485) (xy 455.705768 -410.76585)
			(xy 455.685845 -410.713759) (xy 455.673719 -410.659322) (xy 455.669648 -410.6037) (xy 455.544174 -410.6037)
			(xy 455.543665 -410.631586) (xy 455.535545 -410.686762) (xy 455.519477 -410.740169) (xy 455.495805 -410.790666)
			(xy 455.465032 -410.837179) (xy 455.427815 -410.878716) (xy 455.384947 -410.914391) (xy 455.337341 -410.943445)
			(xy 455.286012 -410.965257) (xy 455.232055 -410.979363) (xy 455.176618 -410.985463) (xy 455.120884 -410.983426)
			(xy 455.066041 -410.973296) (xy 455.013257 -410.955289) (xy 454.963657 -410.929788) (xy 454.918299 -410.897337)
			(xy 454.87815 -410.858628) (xy 454.844064 -410.814485) (xy 454.816768 -410.76585) (xy 454.796845 -410.713759)
			(xy 454.784719 -410.659322) (xy 454.780648 -410.6037) (xy 453.047862 -410.6037) (xy 453.047862 -410.605732)
			(xy 453.055482 -410.624528) (xy 453.062848 -410.63164) (xy 453.083816 -410.653277) (xy 453.119388 -410.701901)
			(xy 453.146871 -410.755515) (xy 453.165582 -410.812783) (xy 453.175055 -410.87228) (xy 453.175624 -410.902404)
			(xy 453.175126 -410.929655) (xy 453.167369 -410.983601) (xy 453.152015 -411.035895) (xy 453.129374 -411.085471)
			(xy 453.099909 -411.13132) (xy 453.064219 -411.17251) (xy 453.02303 -411.208202) (xy 452.977181 -411.237668)
			(xy 452.927606 -411.26031) (xy 452.875313 -411.275667) (xy 452.821367 -411.283425) (xy 452.794116 -411.283912)
			(xy 452.766746 -411.283434) (xy 452.712568 -411.275618) (xy 452.660065 -411.260132) (xy 452.610318 -411.237293)
			(xy 452.56435 -411.207572) (xy 452.543418 -411.189932) (xy 452.536306 -411.183836) (xy 452.519288 -411.177486)
			(xy 452.433944 -411.177486) (xy 452.416926 -411.183836) (xy 452.409814 -411.189932) (xy 452.388892 -411.207583)
			(xy 452.342916 -411.237292) (xy 452.293166 -411.260125) (xy 452.240663 -411.275613) (xy 452.186486 -411.283439)
			(xy 452.159116 -411.283912) (xy 452.128992 -411.283342) (xy 452.069496 -411.273862) (xy 452.012227 -411.255152)
			(xy 451.95861 -411.227675) (xy 451.909976 -411.192116) (xy 451.888352 -411.171136) (xy 451.88124 -411.16377)
			(xy 451.862444 -411.15615) (xy 451.769988 -411.15615) (xy 451.751192 -411.16377) (xy 451.74408 -411.171136)
			(xy 451.722432 -411.192091) (xy 451.673811 -411.227665) (xy 451.6202 -411.255151) (xy 451.562935 -411.273865)
			(xy 451.503439 -411.283341) (xy 451.473316 -411.283912) (xy 451.446064 -411.28343) (xy 451.392114 -411.275675)
			(xy 451.339816 -411.260321) (xy 451.290237 -411.237681) (xy 451.244384 -411.208215) (xy 451.203191 -411.172523)
			(xy 451.167497 -411.131332) (xy 451.138029 -411.085481) (xy 451.115386 -411.035902) (xy 451.100029 -410.983606)
			(xy 451.092272 -410.929656) (xy 451.091808 -410.902404) (xy 449.071044 -410.902404) (xy 449.044999 -410.918299)
			(xy 448.99367 -410.940111) (xy 448.939713 -410.954217) (xy 448.884276 -410.960317) (xy 448.828542 -410.95828)
			(xy 448.773699 -410.94815) (xy 448.720915 -410.930143) (xy 448.671315 -410.904642) (xy 448.625957 -410.872191)
			(xy 448.585808 -410.833482) (xy 448.551722 -410.789339) (xy 448.524426 -410.740704) (xy 448.504503 -410.688613)
			(xy 448.492377 -410.634176) (xy 448.488306 -410.578554) (xy 448.362832 -410.578554) (xy 448.362323 -410.60644)
			(xy 448.354203 -410.661616) (xy 448.338135 -410.715023) (xy 448.314463 -410.76552) (xy 448.28369 -410.812033)
			(xy 448.246473 -410.85357) (xy 448.203605 -410.889245) (xy 448.155999 -410.918299) (xy 448.10467 -410.940111)
			(xy 448.050713 -410.954217) (xy 447.995276 -410.960317) (xy 447.939542 -410.95828) (xy 447.884699 -410.94815)
			(xy 447.831915 -410.930143) (xy 447.782315 -410.904642) (xy 447.736957 -410.872191) (xy 447.696808 -410.833482)
			(xy 447.662722 -410.789339) (xy 447.635426 -410.740704) (xy 447.615503 -410.688613) (xy 447.603377 -410.634176)
			(xy 447.599306 -410.578554) (xy 447.473832 -410.578554) (xy 447.473323 -410.60644) (xy 447.465203 -410.661616)
			(xy 447.449135 -410.715023) (xy 447.425463 -410.76552) (xy 447.39469 -410.812033) (xy 447.357473 -410.85357)
			(xy 447.314605 -410.889245) (xy 447.266999 -410.918299) (xy 447.21567 -410.940111) (xy 447.161713 -410.954217)
			(xy 447.106276 -410.960317) (xy 447.050542 -410.95828) (xy 446.995699 -410.94815) (xy 446.942915 -410.930143)
			(xy 446.893315 -410.904642) (xy 446.847957 -410.872191) (xy 446.807808 -410.833482) (xy 446.773722 -410.789339)
			(xy 446.746426 -410.740704) (xy 446.726503 -410.688613) (xy 446.714377 -410.634176) (xy 446.710306 -410.578554)
			(xy 439.979816 -410.578554) (xy 439.979816 -414.758886) (xy 439.980306 -414.768846) (xy 439.987901 -414.787264)
			(xy 439.994548 -414.7947) (xy 440.3471 -415.147252) (xy 449.363338 -415.147252) (xy 449.363825 -415.119882)
			(xy 449.371637 -415.065704) (xy 449.38712 -415.013201) (xy 449.409957 -414.963453) (xy 449.439678 -414.917486)
			(xy 449.457318 -414.896554) (xy 449.463414 -414.889442) (xy 449.469764 -414.872424) (xy 449.469764 -414.78708)
			(xy 449.463414 -414.770062) (xy 449.457318 -414.76295) (xy 449.439692 -414.742008) (xy 449.409977 -414.696038)
			(xy 449.387139 -414.646293) (xy 449.371645 -414.593795) (xy 449.363813 -414.539621) (xy 449.363338 -414.512252)
			(xy 449.363733 -414.484997) (xy 449.371498 -414.431044) (xy 449.386861 -414.378745) (xy 449.409511 -414.329164)
			(xy 449.438987 -414.283312) (xy 449.474688 -414.242121) (xy 449.515887 -414.20643) (xy 449.561747 -414.176966)
			(xy 449.611333 -414.154328) (xy 449.663636 -414.138978) (xy 449.717591 -414.131227) (xy 449.744846 -414.130744)
			(xy 449.774968 -414.13135) (xy 449.834463 -414.140823) (xy 449.89173 -414.159526) (xy 449.945348 -414.186993)
			(xy 449.993984 -414.222544) (xy 450.01561 -414.24352) (xy 450.022722 -414.250886) (xy 450.041518 -414.258506)
			(xy 450.133974 -414.258506) (xy 450.15277 -414.250886) (xy 450.159882 -414.24352) (xy 450.181495 -414.222527)
			(xy 450.230127 -414.186959) (xy 450.283746 -414.159481) (xy 450.341019 -414.140776) (xy 450.400521 -414.13131)
			(xy 450.430646 -414.130744) (xy 450.457896 -414.131235) (xy 450.511841 -414.138996) (xy 450.564133 -414.154355)
			(xy 450.613707 -414.176998) (xy 450.659555 -414.206465) (xy 450.700743 -414.242155) (xy 450.736434 -414.283343)
			(xy 450.765901 -414.329191) (xy 450.788544 -414.378765) (xy 450.803903 -414.431057) (xy 450.811665 -414.485002)
			(xy 450.812154 -414.512252) (xy 450.811597 -414.541729) (xy 450.802533 -414.599982) (xy 450.784616 -414.656147)
			(xy 450.75827 -414.708887) (xy 450.724123 -414.756945) (xy 450.70395 -414.778444) (xy 450.697396 -414.785764)
			(xy 450.689964 -414.803936) (xy 450.689472 -414.81375) (xy 450.689472 -414.86709) (xy 450.702426 -414.879536)
			(xy 450.710329 -414.886933) (xy 450.730463 -414.894828) (xy 450.741288 -414.894776) (xy 450.7738 -414.892998)
			(xy 450.784574 -414.891856) (xy 450.803779 -414.881872) (xy 450.810884 -414.873694) (xy 450.829064 -414.851551)
			(xy 450.870964 -414.812479) (xy 450.918237 -414.780112) (xy 450.969818 -414.755179) (xy 451.024548 -414.738242)
			(xy 451.081196 -414.729679) (xy 451.109842 -414.729168) (xy 451.139964 -414.72977) (xy 451.199459 -414.739243)
			(xy 451.256727 -414.757946) (xy 451.310345 -414.785415) (xy 451.35898 -414.820968) (xy 451.380606 -414.841944)
			(xy 451.387718 -414.84931) (xy 451.406514 -414.85693) (xy 451.49897 -414.85693) (xy 451.517766 -414.84931)
			(xy 451.524878 -414.841944) (xy 451.546497 -414.820957) (xy 451.595126 -414.785388) (xy 451.648744 -414.757908)
			(xy 451.706016 -414.739202) (xy 451.765517 -414.729734) (xy 451.795642 -414.729168) (xy 451.821941 -414.729585)
			(xy 451.87404 -414.73681) (xy 451.92465 -414.751129) (xy 451.972811 -414.772271) (xy 452.017608 -414.799834)
			(xy 452.058189 -414.833295) (xy 452.076312 -414.852358) (xy 452.083424 -414.859978) (xy 452.101712 -414.86836)
			(xy 452.194168 -414.871662) (xy 452.213218 -414.864804) (xy 452.220584 -414.857692) (xy 452.241902 -414.838411)
			(xy 452.289266 -414.805844) (xy 452.340979 -414.780753) (xy 452.395873 -414.763705) (xy 452.452702 -414.755087)
			(xy 452.481442 -414.754568) (xy 452.510242 -414.755066) (xy 452.567191 -414.763698) (xy 452.622196 -414.78079)
			(xy 452.674009 -414.805954) (xy 452.721451 -414.838618) (xy 452.742808 -414.857946) (xy 452.74992 -414.864804)
			(xy 452.767954 -414.871916) (xy 452.85787 -414.871154) (xy 452.875904 -414.864042) (xy 452.883016 -414.857184)
			(xy 452.904484 -414.837172) (xy 452.9524 -414.803287) (xy 453.004938 -414.777135) (xy 453.060861 -414.759334)
			(xy 453.118849 -414.750304) (xy 453.148192 -414.749742) (xy 453.17451 -414.750141) (xy 453.226647 -414.75737)
			(xy 453.277297 -414.771693) (xy 453.325499 -414.792837) (xy 453.370339 -414.820403) (xy 453.410968 -414.853867)
			(xy 453.429116 -414.872932) (xy 453.43626 -414.879989) (xy 453.454426 -414.888492) (xy 453.464422 -414.889442)
			(xy 453.51827 -414.891474) (xy 453.52462 -414.885124) (xy 453.531732 -414.878012) (xy 453.539352 -414.859724)
			(xy 453.540368 -414.76803) (xy 453.533002 -414.749742) (xy 453.52589 -414.742376) (xy 453.505877 -414.720922)
			(xy 453.472052 -414.672985) (xy 453.44596 -414.620436) (xy 453.428217 -414.564514) (xy 453.419239 -414.506535)
			(xy 453.418702 -414.4772) (xy 453.419188 -414.449949) (xy 453.426944 -414.396001) (xy 453.442299 -414.343706)
			(xy 453.464941 -414.294129) (xy 453.494407 -414.248279) (xy 453.530098 -414.207088) (xy 453.571289 -414.171397)
			(xy 453.617139 -414.141931) (xy 453.666716 -414.119289) (xy 453.719011 -414.103934) (xy 453.772959 -414.096178)
			(xy 453.827461 -414.096178) (xy 453.881409 -414.103934) (xy 453.933704 -414.119289) (xy 453.983281 -414.141931)
			(xy 454.029131 -414.171397) (xy 454.070322 -414.207088) (xy 454.106013 -414.248279) (xy 454.135479 -414.294129)
			(xy 454.158121 -414.343706) (xy 454.173476 -414.396001) (xy 454.181232 -414.449949) (xy 454.181718 -414.4772)
			(xy 454.181157 -414.507324) (xy 454.171675 -414.566821) (xy 454.152962 -414.62409) (xy 454.125484 -414.677707)
			(xy 454.089923 -414.72634) (xy 454.068942 -414.747964) (xy 454.06183 -414.755076) (xy 454.05421 -414.773364)
			(xy 454.053194 -414.865058) (xy 454.06056 -414.883346) (xy 454.067672 -414.890712) (xy 454.087673 -414.912177)
			(xy 454.121501 -414.960111) (xy 454.147596 -415.012656) (xy 454.165342 -415.068577) (xy 454.174322 -415.126554)
			(xy 454.17486 -415.155888) (xy 454.174371 -415.183386) (xy 454.166481 -415.237812) (xy 454.150863 -415.290544)
			(xy 454.12784 -415.340488) (xy 454.097888 -415.386612) (xy 454.080118 -415.407602) (xy 454.073768 -415.414714)
			(xy 454.067418 -415.43224) (xy 454.068688 -415.519362) (xy 454.075546 -415.536634) (xy 454.081896 -415.543746)
			(xy 454.100923 -415.565062) (xy 454.133149 -415.612242) (xy 454.157985 -415.663697) (xy 454.174875 -415.718278)
			(xy 454.183443 -415.774767) (xy 454.184004 -415.803334) (xy 454.183554 -415.830586) (xy 454.175793 -415.884535)
			(xy 454.160433 -415.936831) (xy 454.137788 -415.986409) (xy 454.108317 -416.032259) (xy 454.072622 -416.073449)
			(xy 454.031429 -416.10914) (xy 453.985575 -416.138606) (xy 453.935995 -416.161246) (xy 453.883698 -416.176601)
			(xy 453.829748 -416.184357) (xy 453.802496 -416.184842) (xy 453.776975 -416.18445) (xy 453.726387 -416.177654)
			(xy 453.677158 -416.164171) (xy 453.630167 -416.144242) (xy 453.586254 -416.118222) (xy 453.546205 -416.086578)
			(xy 453.528176 -416.06851) (xy 453.521572 -416.061652) (xy 453.5043 -416.053778) (xy 453.416162 -416.048698)
			(xy 453.398128 -416.05454) (xy 453.390762 -416.06089) (xy 453.37018 -416.077259) (xy 453.325366 -416.104777)
			(xy 453.277195 -416.125875) (xy 453.226582 -416.140152) (xy 453.174487 -416.147338) (xy 453.148192 -416.147758)
			(xy 453.119392 -416.14726) (xy 453.062442 -416.138631) (xy 453.007436 -416.12154) (xy 452.955623 -416.096376)
			(xy 452.908182 -416.06371) (xy 452.886826 -416.04438) (xy 452.879714 -416.037522) (xy 452.86168 -416.03041)
			(xy 452.771764 -416.031172) (xy 452.75373 -416.038284) (xy 452.746618 -416.045142) (xy 452.725182 -416.06519)
			(xy 452.677257 -416.099069) (xy 452.62471 -416.125214) (xy 452.568781 -416.143006) (xy 452.510787 -416.152027)
			(xy 452.481442 -416.152584) (xy 452.45132 -416.151977) (xy 452.391826 -416.142503) (xy 452.334559 -416.1238)
			(xy 452.280941 -416.096333) (xy 452.232305 -416.060783) (xy 452.210678 -416.039808) (xy 452.203566 -416.032442)
			(xy 452.18477 -416.024822) (xy 452.092314 -416.024822) (xy 452.073518 -416.032442) (xy 452.066406 -416.039808)
			(xy 452.046782 -416.05891) (xy 452.003043 -416.091863) (xy 451.955042 -416.118223) (xy 451.903764 -416.137449)
			(xy 451.850264 -416.149145) (xy 451.795642 -416.15307) (xy 451.74102 -416.149145) (xy 451.68752 -416.137449)
			(xy 451.636242 -416.118223) (xy 451.588241 -416.091863) (xy 451.544502 -416.05891) (xy 451.524878 -416.039808)
			(xy 451.517766 -416.032442) (xy 451.49897 -416.024822) (xy 451.406514 -416.024822) (xy 451.387718 -416.032442)
			(xy 451.380606 -416.039808) (xy 451.359003 -416.060812) (xy 451.310368 -416.096377) (xy 451.256746 -416.123852)
			(xy 451.199471 -416.142555) (xy 451.139968 -416.152019) (xy 451.109842 -416.152584) (xy 451.080711 -416.152045)
			(xy 451.023129 -416.14317) (xy 450.967568 -416.125637) (xy 450.915322 -416.099853) (xy 450.867607 -416.06642)
			(xy 450.84619 -416.046666) (xy 450.838824 -416.039808) (xy 450.820282 -416.032442) (xy 450.728588 -416.033966)
			(xy 450.710554 -416.04184) (xy 450.703188 -416.049206) (xy 450.681532 -416.070516) (xy 450.632677 -416.106631)
			(xy 450.578715 -416.134546) (xy 450.521011 -416.153554) (xy 450.461023 -416.163175) (xy 450.430646 -416.16376)
			(xy 450.403392 -416.163302) (xy 450.349438 -416.15555) (xy 450.297138 -416.140197) (xy 450.247554 -416.117557)
			(xy 450.201699 -416.088089) (xy 450.160504 -416.052394) (xy 450.12481 -416.0112) (xy 450.095343 -415.965344)
			(xy 450.072702 -415.915761) (xy 450.05735 -415.86346) (xy 450.049598 -415.809506) (xy 450.049138 -415.782252)
			(xy 450.0497 -415.752775) (xy 450.058762 -415.694522) (xy 450.076679 -415.638357) (xy 450.103024 -415.585618)
			(xy 450.137169 -415.537559) (xy 450.157342 -415.51606) (xy 450.163893 -415.508738) (xy 450.171327 -415.490568)
			(xy 450.17182 -415.480754) (xy 450.17182 -415.427414) (xy 450.159882 -415.415984) (xy 450.15277 -415.408618)
			(xy 450.133974 -415.400998) (xy 450.041518 -415.400998) (xy 450.022722 -415.408618) (xy 450.01561 -415.415984)
			(xy 449.994001 -415.436982) (xy 449.945368 -415.472548) (xy 449.891748 -415.500026) (xy 449.834474 -415.51873)
			(xy 449.774971 -415.528195) (xy 449.744846 -415.52876) (xy 449.717592 -415.528302) (xy 449.663638 -415.52055)
			(xy 449.611338 -415.505197) (xy 449.561754 -415.482557) (xy 449.515899 -415.453089) (xy 449.474704 -415.417394)
			(xy 449.43901 -415.3762) (xy 449.409543 -415.330344) (xy 449.386902 -415.280761) (xy 449.37155 -415.22846)
			(xy 449.363798 -415.174506) (xy 449.363338 -415.147252) (xy 440.3471 -415.147252) (xy 441.935362 -416.735514)
			(xy 441.94276 -416.74236) (xy 441.961359 -416.750085) (xy 441.97143 -416.7505) (xy 443.742318 -416.7505)
			(xy 443.74981 -416.7502) (xy 443.764143 -416.74582) (xy 443.770512 -416.741864) (xy 443.794178 -416.72667)
			(xy 443.845028 -416.70265) (xy 443.898851 -416.686346) (xy 443.954483 -416.678113) (xy 443.982602 -416.677602)
			(xy 444.010723 -416.678083) (xy 444.066361 -416.686305) (xy 444.120186 -416.702616) (xy 444.17103 -416.72666)
			(xy 444.194692 -416.741864) (xy 444.201053 -416.74584) (xy 444.215389 -416.750228) (xy 444.222886 -416.7505)
			(xy 445.383158 -416.7505) (xy 445.394089 -416.749984) (xy 445.413976 -416.740908) (xy 445.421512 -416.732974)
			(xy 445.439726 -416.712706) (xy 445.480916 -416.67703) (xy 445.526763 -416.647578) (xy 445.576333 -416.624947)
			(xy 445.628619 -416.6096) (xy 445.682556 -416.601847) (xy 445.737048 -416.601847) (xy 445.790985 -416.6096)
			(xy 445.843271 -416.624947) (xy 445.892841 -416.647578) (xy 445.938688 -416.67703) (xy 445.979878 -416.712706)
			(xy 445.998092 -416.732974) (xy 446.005647 -416.740881) (xy 446.025522 -416.749954) (xy 446.036446 -416.7505)
			(xy 447.9671 -416.7505) (xy 447.97717 -416.750923) (xy 447.995775 -416.758638) (xy 448.003168 -416.765486)
			(xy 450.56425 -419.326568) (xy 450.57165 -419.33341) (xy 450.590248 -419.341131) (xy 450.600318 -419.341554)
		)
		(stroke
			(width 0)
			(type solid)
		)
		(fill yes)
		(layer "In11.Cu")
		(net "GND")
	)
	(gr_poly
		(pts
			(xy 414.333436 -194.329558) (xy 414.34104 -194.328041) (xy 414.354872 -194.321053) (xy 414.360614 -194.315842)
			(xy 415.322766 -193.35369) (xy 415.330164 -193.346844) (xy 415.348763 -193.33912) (xy 415.358834 -193.338704)
			(xy 417.802568 -193.338704) (xy 417.81359 -193.33817) (xy 417.833616 -193.32896) (xy 417.841176 -193.320924)
			(xy 417.89858 -193.253614) (xy 417.904676 -193.232278) (xy 417.902898 -193.221356) (xy 417.89985 -193.200274)
			(xy 417.89985 -193.20002) (xy 417.897818 -193.184018) (xy 417.896548 -193.17335) (xy 417.886134 -193.155316)
			(xy 417.817554 -193.105024) (xy 417.809718 -193.099698) (xy 417.791447 -193.09473) (xy 417.781994 -193.095372)
			(xy 417.777676 -193.09588) (xy 417.775136 -193.096388) (xy 417.735317 -193.103499) (xy 417.654798 -193.111256)
			(xy 417.614354 -193.111882) (xy 417.610036 -193.111882) (xy 417.567021 -193.111303) (xy 417.481415 -193.102773)
			(xy 417.397056 -193.0859) (xy 417.314754 -193.060845) (xy 417.235303 -193.027849) (xy 417.159465 -192.987231)
			(xy 417.08797 -192.93938) (xy 417.021506 -192.884757) (xy 416.960711 -192.823886) (xy 416.90617 -192.757354)
			(xy 416.858408 -192.685799) (xy 416.817884 -192.609911) (xy 416.784988 -192.530419) (xy 416.760035 -192.448087)
			(xy 416.743266 -192.363706) (xy 416.734843 -192.278089) (xy 416.734244 -192.235074) (xy 416.734774 -192.192025)
			(xy 416.743215 -192.106342) (xy 416.760013 -192.021899) (xy 416.785007 -191.939509) (xy 416.817956 -191.859965)
			(xy 416.858543 -191.784034) (xy 416.906376 -191.712446) (xy 416.960995 -191.645891) (xy 417.021875 -191.58501)
			(xy 417.088428 -191.530389) (xy 417.160015 -191.482554) (xy 417.235945 -191.441965) (xy 417.315488 -191.409015)
			(xy 417.397878 -191.384018) (xy 417.48232 -191.367218) (xy 417.568003 -191.358775) (xy 417.611052 -191.358266)
			(xy 417.63061 -191.358266) (xy 417.6708 -191.359614) (xy 417.750699 -191.368759) (xy 417.829425 -191.385183)
			(xy 417.906315 -191.408748) (xy 417.980725 -191.439255) (xy 418.052028 -191.476448) (xy 418.119625 -191.520016)
			(xy 418.151564 -191.544448) (xy 418.158422 -191.550036) (xy 418.171122 -191.554354) (xy 418.18031 -191.557601)
			(xy 418.19978 -191.557601) (xy 418.208968 -191.554354) (xy 418.221668 -191.550036) (xy 418.228526 -191.544702)
			(xy 418.261591 -191.519439) (xy 418.331681 -191.474579) (xy 418.405706 -191.436561) (xy 418.482999 -191.405727)
			(xy 418.562866 -191.382354) (xy 418.644588 -191.366652) (xy 418.72743 -191.358762) (xy 418.769038 -191.358266)
			(xy 418.812086 -191.358796) (xy 418.897767 -191.367238) (xy 418.982209 -191.384038) (xy 419.064597 -191.409033)
			(xy 419.144139 -191.441982) (xy 419.220068 -191.482569) (xy 419.291654 -191.530403) (xy 419.358207 -191.585023)
			(xy 419.419085 -191.645902) (xy 419.473704 -191.712456) (xy 419.521537 -191.784042) (xy 419.562123 -191.859972)
			(xy 419.595071 -191.939514) (xy 419.620065 -192.021903) (xy 419.636863 -192.106344) (xy 419.645305 -192.192026)
			(xy 419.645635 -192.21831) (xy 420.698437 -192.21831) (xy 420.702372 -192.164539) (xy 420.714095 -192.111915)
			(xy 420.733355 -192.061558) (xy 420.759741 -192.014541) (xy 420.792693 -191.971868) (xy 420.831506 -191.934447)
			(xy 420.875354 -191.903077) (xy 420.923302 -191.878425) (xy 420.974329 -191.861017) (xy 421.027347 -191.851224)
			(xy 421.081226 -191.849255) (xy 421.134817 -191.855152) (xy 421.186978 -191.868788) (xy 421.236598 -191.889875)
			(xy 421.282619 -191.917961) (xy 421.324061 -191.952449) (xy 421.360039 -191.992603) (xy 421.389787 -192.037567)
			(xy 421.412672 -192.086384) (xy 421.428204 -192.138013) (xy 421.436054 -192.191353) (xy 421.436546 -192.21831)
			(xy 422.487105 -192.21831) (xy 422.49104 -192.164539) (xy 422.502763 -192.111915) (xy 422.522023 -192.061558)
			(xy 422.548409 -192.014541) (xy 422.581361 -191.971868) (xy 422.620174 -191.934447) (xy 422.664022 -191.903077)
			(xy 422.71197 -191.878425) (xy 422.762997 -191.861017) (xy 422.816015 -191.851224) (xy 422.869894 -191.849255)
			(xy 422.923485 -191.855152) (xy 422.975646 -191.868788) (xy 423.025266 -191.889875) (xy 423.071287 -191.917961)
			(xy 423.112729 -191.952449) (xy 423.148707 -191.992603) (xy 423.178455 -192.037567) (xy 423.20134 -192.086384)
			(xy 423.216872 -192.138013) (xy 423.224722 -192.191353) (xy 423.225214 -192.21831) (xy 423.224722 -192.245267)
			(xy 423.216872 -192.298607) (xy 423.20134 -192.350236) (xy 423.178455 -192.399053) (xy 423.148707 -192.444017)
			(xy 423.112729 -192.484171) (xy 423.071287 -192.518659) (xy 423.025266 -192.546745) (xy 422.975646 -192.567832)
			(xy 422.923485 -192.581468) (xy 422.869894 -192.587365) (xy 422.816015 -192.585396) (xy 422.762997 -192.575603)
			(xy 422.71197 -192.558195) (xy 422.664022 -192.533543) (xy 422.620174 -192.502173) (xy 422.581361 -192.464752)
			(xy 422.548409 -192.422079) (xy 422.522023 -192.375062) (xy 422.502763 -192.324705) (xy 422.49104 -192.272081)
			(xy 422.487105 -192.21831) (xy 421.436546 -192.21831) (xy 421.436054 -192.245267) (xy 421.428204 -192.298607)
			(xy 421.412672 -192.350236) (xy 421.389787 -192.399053) (xy 421.360039 -192.444017) (xy 421.324061 -192.484171)
			(xy 421.282619 -192.518659) (xy 421.236598 -192.546745) (xy 421.186978 -192.567832) (xy 421.134817 -192.581468)
			(xy 421.081226 -192.587365) (xy 421.027347 -192.585396) (xy 420.974329 -192.575603) (xy 420.923302 -192.558195)
			(xy 420.875354 -192.533543) (xy 420.831506 -192.502173) (xy 420.792693 -192.464752) (xy 420.759741 -192.422079)
			(xy 420.733355 -192.375062) (xy 420.714095 -192.324705) (xy 420.702372 -192.272081) (xy 420.698437 -192.21831)
			(xy 419.645635 -192.21831) (xy 419.645846 -192.235074) (xy 419.645364 -192.276255) (xy 419.637618 -192.358254)
			(xy 419.622221 -192.439165) (xy 419.599307 -192.518276) (xy 419.569079 -192.594892) (xy 419.55085 -192.631822)
			(xy 419.54831 -192.636902) (xy 419.54577 -192.64757) (xy 419.544414 -192.65372) (xy 419.544417 -192.666311)
			(xy 419.54577 -192.672462) (xy 419.54831 -192.68313) (xy 419.55085 -192.68821) (xy 419.569022 -192.725055)
			(xy 419.599202 -192.80147) (xy 419.622098 -192.880374) (xy 419.637508 -192.961074) (xy 419.645297 -193.042863)
			(xy 419.645846 -193.083942) (xy 419.645846 -193.084958) (xy 419.645629 -193.10731) (xy 420.698437 -193.10731)
			(xy 420.702372 -193.053539) (xy 420.714095 -193.000915) (xy 420.733355 -192.950558) (xy 420.759741 -192.903541)
			(xy 420.792693 -192.860868) (xy 420.831506 -192.823447) (xy 420.875354 -192.792077) (xy 420.923302 -192.767425)
			(xy 420.974329 -192.750017) (xy 421.027347 -192.740224) (xy 421.081226 -192.738255) (xy 421.134817 -192.744152)
			(xy 421.186978 -192.757788) (xy 421.236598 -192.778875) (xy 421.282619 -192.806961) (xy 421.324061 -192.841449)
			(xy 421.360039 -192.881603) (xy 421.389787 -192.926567) (xy 421.412672 -192.975384) (xy 421.428204 -193.027013)
			(xy 421.436054 -193.080353) (xy 421.436546 -193.10731) (xy 421.436054 -193.134267) (xy 421.428204 -193.187607)
			(xy 421.412672 -193.239236) (xy 421.389787 -193.288053) (xy 421.360039 -193.333017) (xy 421.324061 -193.373171)
			(xy 421.282619 -193.407659) (xy 421.236598 -193.435745) (xy 421.186978 -193.456832) (xy 421.134817 -193.470468)
			(xy 421.081226 -193.476365) (xy 421.027347 -193.474396) (xy 420.974329 -193.464603) (xy 420.923302 -193.447195)
			(xy 420.875354 -193.422543) (xy 420.831506 -193.391173) (xy 420.792693 -193.353752) (xy 420.759741 -193.311079)
			(xy 420.733355 -193.264062) (xy 420.714095 -193.213705) (xy 420.702372 -193.161081) (xy 420.698437 -193.10731)
			(xy 419.645629 -193.10731) (xy 419.645514 -193.119201) (xy 419.640174 -193.187478) (xy 419.635178 -193.221356)
			(xy 419.6334 -193.232278) (xy 419.639496 -193.253614) (xy 419.6969 -193.320924) (xy 419.704473 -193.328945)
			(xy 419.72449 -193.33816) (xy 419.735508 -193.338704) (xy 419.989254 -193.338704) (xy 419.99932 -193.339137)
			(xy 420.01791 -193.346866) (xy 420.025322 -193.35369) (xy 420.864792 -194.19316) (xy 420.8653 -194.193668)
			(xy 420.872684 -194.200241) (xy 420.890983 -194.207672) (xy 420.90086 -194.208146) (xy 421.415464 -194.208146)
			(xy 421.423846 -194.207384) (xy 421.431454 -194.205876) (xy 421.445297 -194.198898) (xy 421.451024 -194.193668)
			(xy 421.951404 -193.693288) (xy 421.958799 -193.686433) (xy 421.977398 -193.678686) (xy 421.987472 -193.678302)
			(xy 422.650412 -193.678302) (xy 422.663366 -193.676524) (xy 422.68013 -193.672206) (xy 422.685464 -193.669412)
			(xy 422.708171 -193.658017) (xy 422.755996 -193.640875) (xy 422.805722 -193.630459) (xy 422.856406 -193.626964)
			(xy 422.90709 -193.630459) (xy 422.956816 -193.640875) (xy 423.004641 -193.658017) (xy 423.027348 -193.669412)
			(xy 423.032682 -193.672206) (xy 423.049446 -193.676524) (xy 423.0624 -193.678302) (xy 424.691048 -193.678302)
			(xy 424.697341 -193.678108) (xy 424.709542 -193.675014) (xy 424.715178 -193.672206) (xy 424.732958 -193.662808)
			(xy 424.736149 -193.660964) (xy 424.742015 -193.656503) (xy 424.744642 -193.653918) (xy 424.7515 -193.64706)
			(xy 424.75404 -193.643758) (xy 424.774095 -193.617052) (xy 424.820226 -193.568756) (xy 424.872425 -193.527095)
			(xy 424.929747 -193.492822) (xy 424.991153 -193.466558) (xy 425.055531 -193.448781) (xy 425.121713 -193.439811)
			(xy 425.155106 -193.439288) (xy 425.187065 -193.439786) (xy 425.250452 -193.447997) (xy 425.312259 -193.464283)
			(xy 425.34205 -193.475864) (xy 425.348908 -193.478658) (xy 425.356782 -193.47942) (xy 425.366875 -193.479978)
			(xy 425.386233 -193.474234) (xy 425.394374 -193.468244) (xy 425.410376 -193.455036) (xy 425.41063 -193.453004)
			(xy 425.474892 -193.393568) (xy 425.482258 -193.365374) (xy 425.477686 -193.35115) (xy 425.465171 -193.310209)
			(xy 425.447236 -193.226492) (xy 425.441872 -193.184018) (xy 425.440602 -193.17335) (xy 425.430188 -193.155316)
			(xy 425.361608 -193.105024) (xy 425.35377 -193.099706) (xy 425.335501 -193.094755) (xy 425.326048 -193.095372)
			(xy 425.32173 -193.09588) (xy 425.31919 -193.096388) (xy 425.279371 -193.103501) (xy 425.198852 -193.111263)
			(xy 425.158408 -193.111882) (xy 425.15409 -193.111882) (xy 425.111074 -193.111306) (xy 425.025463 -193.10278)
			(xy 424.9411 -193.085911) (xy 424.858794 -193.060859) (xy 424.779338 -193.027866) (xy 424.703496 -192.987249)
			(xy 424.631996 -192.939399) (xy 424.565527 -192.884776) (xy 424.504728 -192.823905) (xy 424.450183 -192.757371)
			(xy 424.402418 -192.685815) (xy 424.361891 -192.609925) (xy 424.328992 -192.53043) (xy 424.304037 -192.448095)
			(xy 424.287267 -192.363711) (xy 424.278843 -192.278091) (xy 424.278298 -192.235074) (xy 424.278828 -192.192026)
			(xy 424.287269 -192.106345) (xy 424.304068 -192.021904) (xy 424.329062 -191.939516) (xy 424.362011 -191.859974)
			(xy 424.402598 -191.784046) (xy 424.450432 -191.71246) (xy 424.505052 -191.645909) (xy 424.565932 -191.585031)
			(xy 424.632486 -191.530413) (xy 424.704073 -191.482582) (xy 424.780003 -191.441998) (xy 424.859546 -191.409051)
			(xy 424.941935 -191.38406) (xy 425.026377 -191.367264) (xy 425.112058 -191.358826) (xy 425.155106 -191.358266)
			(xy 425.174664 -191.358266) (xy 425.214855 -191.359612) (xy 425.294756 -191.368753) (xy 425.373483 -191.385174)
			(xy 425.450376 -191.408735) (xy 425.524788 -191.439239) (xy 425.596094 -191.47643) (xy 425.663694 -191.519995)
			(xy 425.695618 -191.544448) (xy 425.702476 -191.550036) (xy 425.715176 -191.554354) (xy 425.724364 -191.557601)
			(xy 425.743834 -191.557601) (xy 425.753022 -191.554354) (xy 425.765722 -191.550036) (xy 425.77258 -191.544702)
			(xy 425.805644 -191.519437) (xy 425.875733 -191.474574) (xy 425.949758 -191.436552) (xy 426.027051 -191.405713)
			(xy 426.106918 -191.382336) (xy 426.18864 -191.36663) (xy 426.271483 -191.358736) (xy 426.313092 -191.358266)
			(xy 426.356142 -191.358794) (xy 426.441826 -191.367232) (xy 426.526271 -191.384028) (xy 426.608663 -191.409021)
			(xy 426.688209 -191.441968) (xy 426.764142 -191.482554) (xy 426.835732 -191.530387) (xy 426.902288 -191.585006)
			(xy 426.963171 -191.645886) (xy 427.017793 -191.712441) (xy 427.065629 -191.784029) (xy 427.106217 -191.85996)
			(xy 427.139168 -191.939505) (xy 427.164163 -192.021896) (xy 427.180963 -192.10634) (xy 427.189404 -192.192024)
			(xy 427.189707 -192.21831) (xy 428.242491 -192.21831) (xy 428.246426 -192.164539) (xy 428.258149 -192.111915)
			(xy 428.277409 -192.061558) (xy 428.303795 -192.014541) (xy 428.336747 -191.971868) (xy 428.37556 -191.934447)
			(xy 428.419408 -191.903077) (xy 428.467356 -191.878425) (xy 428.518383 -191.861017) (xy 428.571401 -191.851224)
			(xy 428.62528 -191.849255) (xy 428.678871 -191.855152) (xy 428.731032 -191.868788) (xy 428.780652 -191.889875)
			(xy 428.826673 -191.917961) (xy 428.868115 -191.952449) (xy 428.904093 -191.992603) (xy 428.933841 -192.037567)
			(xy 428.956726 -192.086384) (xy 428.972258 -192.138013) (xy 428.980108 -192.191353) (xy 428.9806 -192.21831)
			(xy 430.031159 -192.21831) (xy 430.035094 -192.164539) (xy 430.046817 -192.111915) (xy 430.066077 -192.061558)
			(xy 430.092463 -192.014541) (xy 430.125415 -191.971868) (xy 430.164228 -191.934447) (xy 430.208076 -191.903077)
			(xy 430.256024 -191.878425) (xy 430.307051 -191.861017) (xy 430.360069 -191.851224) (xy 430.413948 -191.849255)
			(xy 430.467539 -191.855152) (xy 430.5197 -191.868788) (xy 430.56932 -191.889875) (xy 430.615341 -191.917961)
			(xy 430.656783 -191.952449) (xy 430.692761 -191.992603) (xy 430.722509 -192.037567) (xy 430.745394 -192.086384)
			(xy 430.760926 -192.138013) (xy 430.768776 -192.191353) (xy 430.769268 -192.21831) (xy 430.768776 -192.245267)
			(xy 430.760926 -192.298607) (xy 430.745394 -192.350236) (xy 430.722509 -192.399053) (xy 430.692761 -192.444017)
			(xy 430.656783 -192.484171) (xy 430.615341 -192.518659) (xy 430.56932 -192.546745) (xy 430.5197 -192.567832)
			(xy 430.467539 -192.581468) (xy 430.413948 -192.587365) (xy 430.360069 -192.585396) (xy 430.307051 -192.575603)
			(xy 430.256024 -192.558195) (xy 430.208076 -192.533543) (xy 430.164228 -192.502173) (xy 430.125415 -192.464752)
			(xy 430.092463 -192.422079) (xy 430.066077 -192.375062) (xy 430.046817 -192.324705) (xy 430.035094 -192.272081)
			(xy 430.031159 -192.21831) (xy 428.9806 -192.21831) (xy 428.980108 -192.245267) (xy 428.972258 -192.298607)
			(xy 428.956726 -192.350236) (xy 428.933841 -192.399053) (xy 428.904093 -192.444017) (xy 428.868115 -192.484171)
			(xy 428.826673 -192.518659) (xy 428.780652 -192.546745) (xy 428.731032 -192.567832) (xy 428.678871 -192.581468)
			(xy 428.62528 -192.587365) (xy 428.571401 -192.585396) (xy 428.518383 -192.575603) (xy 428.467356 -192.558195)
			(xy 428.419408 -192.533543) (xy 428.37556 -192.502173) (xy 428.336747 -192.464752) (xy 428.303795 -192.422079)
			(xy 428.277409 -192.375062) (xy 428.258149 -192.324705) (xy 428.246426 -192.272081) (xy 428.242491 -192.21831)
			(xy 427.189707 -192.21831) (xy 427.1899 -192.235074) (xy 427.189418 -192.276256) (xy 427.181673 -192.358254)
			(xy 427.166276 -192.439165) (xy 427.143364 -192.518278) (xy 427.113138 -192.594894) (xy 427.094904 -192.631822)
			(xy 427.092364 -192.636902) (xy 427.089824 -192.64757) (xy 427.088466 -192.65372) (xy 427.08847 -192.666311)
			(xy 427.089824 -192.672462) (xy 427.092364 -192.68313) (xy 427.094904 -192.68821) (xy 427.113132 -192.725141)
			(xy 427.143371 -192.801753) (xy 427.166289 -192.880864) (xy 427.181681 -192.961776) (xy 427.189414 -193.043776)
			(xy 427.1899 -193.084958) (xy 427.18962 -193.10731) (xy 428.242491 -193.10731) (xy 428.246426 -193.053539)
			(xy 428.258149 -193.000915) (xy 428.277409 -192.950558) (xy 428.303795 -192.903541) (xy 428.336747 -192.860868)
			(xy 428.37556 -192.823447) (xy 428.419408 -192.792077) (xy 428.467356 -192.767425) (xy 428.518383 -192.750017)
			(xy 428.571401 -192.740224) (xy 428.62528 -192.738255) (xy 428.678871 -192.744152) (xy 428.731032 -192.757788)
			(xy 428.780652 -192.778875) (xy 428.826673 -192.806961) (xy 428.868115 -192.841449) (xy 428.904093 -192.881603)
			(xy 428.933841 -192.926567) (xy 428.956726 -192.975384) (xy 428.972258 -193.027013) (xy 428.980108 -193.080353)
			(xy 428.9806 -193.10731) (xy 428.980108 -193.134267) (xy 428.972258 -193.187607) (xy 428.956726 -193.239236)
			(xy 428.933841 -193.288053) (xy 428.904093 -193.333017) (xy 428.868115 -193.373171) (xy 428.826673 -193.407659)
			(xy 428.780652 -193.435745) (xy 428.731032 -193.456832) (xy 428.678871 -193.470468) (xy 428.62528 -193.476365)
			(xy 428.571401 -193.474396) (xy 428.518383 -193.464603) (xy 428.467356 -193.447195) (xy 428.419408 -193.422543)
			(xy 428.37556 -193.391173) (xy 428.336747 -193.353752) (xy 428.303795 -193.311079) (xy 428.277409 -193.264062)
			(xy 428.258149 -193.213705) (xy 428.246426 -193.161081) (xy 428.242491 -193.10731) (xy 427.18962 -193.10731)
			(xy 427.18933 -193.130523) (xy 427.179904 -193.221164) (xy 427.161128 -193.310338) (xy 427.133205 -193.397084)
			(xy 427.096437 -193.480467) (xy 427.07433 -193.520314) (xy 427.071028 -193.525648) (xy 427.067218 -193.539364)
			(xy 427.064954 -193.549228) (xy 427.067571 -193.569278) (xy 427.072298 -193.578226) (xy 427.11497 -193.652902)
			(xy 427.119741 -193.660456) (xy 427.133442 -193.671906) (xy 427.150237 -193.677969) (xy 427.159166 -193.678302)
			(xy 427.758606 -193.678302) (xy 427.768676 -193.678726) (xy 427.787278 -193.686443) (xy 427.794674 -193.693288)
			(xy 428.294292 -194.192906) (xy 428.2948 -194.193414) (xy 428.302182 -194.199993) (xy 428.320481 -194.207433)
			(xy 428.33036 -194.207892) (xy 428.7774 -194.207892) (xy 428.785782 -194.20713) (xy 428.793389 -194.205619)
			(xy 428.807229 -194.198639) (xy 428.81296 -194.193414) (xy 429.394366 -193.612008) (xy 429.401768 -193.605171)
			(xy 429.420366 -193.59746) (xy 429.430434 -193.597022) (xy 432.304952 -193.597022) (xy 432.309984 -193.596881)
			(xy 432.319838 -193.594833) (xy 432.32451 -193.592958) (xy 432.350672 -193.582036) (xy 432.35753 -193.575432)
			(xy 432.380641 -193.554146) (xy 432.431294 -193.51697) (xy 432.486237 -193.486488) (xy 432.544589 -193.463187)
			(xy 432.605416 -193.447442) (xy 432.667744 -193.439503) (xy 432.69916 -193.439034) (xy 432.69916 -193.439288)
			(xy 432.731119 -193.439783) (xy 432.794508 -193.447989) (xy 432.856318 -193.464269) (xy 432.886104 -193.475864)
			(xy 432.892962 -193.478658) (xy 432.900836 -193.47942) (xy 432.910925 -193.479968) (xy 432.93027 -193.474208)
			(xy 432.938428 -193.468244) (xy 432.95443 -193.455036) (xy 432.954684 -193.453004) (xy 433.018946 -193.393568)
			(xy 433.026312 -193.365374) (xy 433.02174 -193.35115) (xy 433.009226 -193.310209) (xy 432.991292 -193.226492)
			(xy 432.985926 -193.184018) (xy 432.984656 -193.17335) (xy 432.974242 -193.155316) (xy 432.905662 -193.105024)
			(xy 432.897826 -193.099697) (xy 432.879555 -193.094726) (xy 432.870102 -193.095372) (xy 432.865784 -193.09588)
			(xy 432.863244 -193.096388) (xy 432.823425 -193.103499) (xy 432.742906 -193.111257) (xy 432.702462 -193.111882)
			(xy 432.698144 -193.111882) (xy 432.655129 -193.111304) (xy 432.569522 -193.102774) (xy 432.485162 -193.085901)
			(xy 432.40286 -193.060847) (xy 432.323408 -193.027852) (xy 432.24757 -192.987234) (xy 432.176074 -192.939383)
			(xy 432.109609 -192.884759) (xy 432.048814 -192.823889) (xy 431.994272 -192.757356) (xy 431.94651 -192.685802)
			(xy 431.905985 -192.609913) (xy 431.873088 -192.53042) (xy 431.848135 -192.448088) (xy 431.831366 -192.363707)
			(xy 431.822943 -192.278089) (xy 431.822352 -192.235074) (xy 431.822882 -192.192025) (xy 431.831323 -192.106343)
			(xy 431.848121 -192.0219) (xy 431.873115 -191.93951) (xy 431.906064 -191.859966) (xy 431.946651 -191.784035)
			(xy 431.994484 -191.712448) (xy 432.049104 -191.645894) (xy 432.109983 -191.585013) (xy 432.176537 -191.530392)
			(xy 432.248123 -191.482558) (xy 432.324054 -191.44197) (xy 432.403597 -191.40902) (xy 432.485986 -191.384025)
			(xy 432.570429 -191.367225) (xy 432.656111 -191.358782) (xy 432.69916 -191.358266) (xy 432.718718 -191.358266)
			(xy 432.758948 -191.359624) (xy 432.838926 -191.368793) (xy 432.917728 -191.385246) (xy 432.994693 -191.408845)
			(xy 433.069174 -191.439392) (xy 433.140546 -191.47663) (xy 433.208208 -191.520246) (xy 433.24018 -191.544702)
			(xy 433.247038 -191.55029) (xy 433.262024 -191.555116) (xy 433.269922 -191.55746) (xy 433.286384 -191.55746)
			(xy 433.294282 -191.555116) (xy 433.309776 -191.550036) (xy 433.316634 -191.544702) (xy 433.349699 -191.519439)
			(xy 433.419789 -191.47458) (xy 433.493814 -191.436563) (xy 433.571107 -191.405729) (xy 433.650974 -191.382357)
			(xy 433.732696 -191.366655) (xy 433.815538 -191.358767) (xy 433.857146 -191.358266) (xy 433.900194 -191.358796)
			(xy 433.985875 -191.367239) (xy 434.070315 -191.384039) (xy 434.152703 -191.409035) (xy 434.232244 -191.441985)
			(xy 434.308173 -191.482572) (xy 434.379758 -191.530406) (xy 434.44631 -191.585025) (xy 434.507188 -191.645905)
			(xy 434.561806 -191.712458) (xy 434.609638 -191.784044) (xy 434.650224 -191.859974) (xy 434.683172 -191.939516)
			(xy 434.708165 -192.021904) (xy 434.724964 -192.106345) (xy 434.733405 -192.192026) (xy 434.73374 -192.21831)
			(xy 435.786545 -192.21831) (xy 435.79048 -192.164539) (xy 435.802203 -192.111915) (xy 435.821463 -192.061558)
			(xy 435.847849 -192.014541) (xy 435.880801 -191.971868) (xy 435.919614 -191.934447) (xy 435.963462 -191.903077)
			(xy 436.01141 -191.878425) (xy 436.062437 -191.861017) (xy 436.115455 -191.851224) (xy 436.169334 -191.849255)
			(xy 436.222925 -191.855152) (xy 436.275086 -191.868788) (xy 436.324706 -191.889875) (xy 436.370727 -191.917961)
			(xy 436.412169 -191.952449) (xy 436.448147 -191.992603) (xy 436.477895 -192.037567) (xy 436.50078 -192.086384)
			(xy 436.516312 -192.138013) (xy 436.524162 -192.191353) (xy 436.524654 -192.21831) (xy 437.575213 -192.21831)
			(xy 437.579148 -192.164539) (xy 437.590871 -192.111915) (xy 437.610131 -192.061558) (xy 437.636517 -192.014541)
			(xy 437.669469 -191.971868) (xy 437.708282 -191.934447) (xy 437.75213 -191.903077) (xy 437.800078 -191.878425)
			(xy 437.851105 -191.861017) (xy 437.904123 -191.851224) (xy 437.958002 -191.849255) (xy 438.011593 -191.855152)
			(xy 438.063754 -191.868788) (xy 438.113374 -191.889875) (xy 438.159395 -191.917961) (xy 438.200837 -191.952449)
			(xy 438.236815 -191.992603) (xy 438.266563 -192.037567) (xy 438.289448 -192.086384) (xy 438.30498 -192.138013)
			(xy 438.31283 -192.191353) (xy 438.313322 -192.21831) (xy 438.31283 -192.245267) (xy 438.30498 -192.298607)
			(xy 438.289448 -192.350236) (xy 438.266563 -192.399053) (xy 438.236815 -192.444017) (xy 438.200837 -192.484171)
			(xy 438.159395 -192.518659) (xy 438.113374 -192.546745) (xy 438.063754 -192.567832) (xy 438.011593 -192.581468)
			(xy 437.958002 -192.587365) (xy 437.904123 -192.585396) (xy 437.851105 -192.575603) (xy 437.800078 -192.558195)
			(xy 437.75213 -192.533543) (xy 437.708282 -192.502173) (xy 437.669469 -192.464752) (xy 437.636517 -192.422079)
			(xy 437.610131 -192.375062) (xy 437.590871 -192.324705) (xy 437.579148 -192.272081) (xy 437.575213 -192.21831)
			(xy 436.524654 -192.21831) (xy 436.524162 -192.245267) (xy 436.516312 -192.298607) (xy 436.50078 -192.350236)
			(xy 436.477895 -192.399053) (xy 436.448147 -192.444017) (xy 436.412169 -192.484171) (xy 436.370727 -192.518659)
			(xy 436.324706 -192.546745) (xy 436.275086 -192.567832) (xy 436.222925 -192.581468) (xy 436.169334 -192.587365)
			(xy 436.115455 -192.585396) (xy 436.062437 -192.575603) (xy 436.01141 -192.558195) (xy 435.963462 -192.533543)
			(xy 435.919614 -192.502173) (xy 435.880801 -192.464752) (xy 435.847849 -192.422079) (xy 435.821463 -192.375062)
			(xy 435.802203 -192.324705) (xy 435.79048 -192.272081) (xy 435.786545 -192.21831) (xy 434.73374 -192.21831)
			(xy 434.733954 -192.235074) (xy 434.733472 -192.276255) (xy 434.725726 -192.358254) (xy 434.710329 -192.439165)
			(xy 434.687416 -192.518277) (xy 434.657188 -192.594892) (xy 434.638958 -192.631822) (xy 434.636418 -192.636902)
			(xy 434.633878 -192.64757) (xy 434.632521 -192.65372) (xy 434.632525 -192.666311) (xy 434.633878 -192.672462)
			(xy 434.636418 -192.68313) (xy 434.638958 -192.68821) (xy 434.657038 -192.724846) (xy 434.687095 -192.80082)
			(xy 434.709952 -192.879261) (xy 434.725408 -192.959488) (xy 434.733332 -193.040807) (xy 434.733954 -193.081656)
			(xy 434.733954 -193.085212) (xy 434.733714 -193.10731) (xy 435.786545 -193.10731) (xy 435.79048 -193.053539)
			(xy 435.802203 -193.000915) (xy 435.821463 -192.950558) (xy 435.847849 -192.903541) (xy 435.880801 -192.860868)
			(xy 435.919614 -192.823447) (xy 435.963462 -192.792077) (xy 436.01141 -192.767425) (xy 436.062437 -192.750017)
			(xy 436.115455 -192.740224) (xy 436.169334 -192.738255) (xy 436.222925 -192.744152) (xy 436.275086 -192.757788)
			(xy 436.324706 -192.778875) (xy 436.370727 -192.806961) (xy 436.412169 -192.841449) (xy 436.448147 -192.881603)
			(xy 436.477895 -192.926567) (xy 436.50078 -192.975384) (xy 436.516312 -193.027013) (xy 436.524162 -193.080353)
			(xy 436.524654 -193.10731) (xy 436.524162 -193.134267) (xy 436.516312 -193.187607) (xy 436.50078 -193.239236)
			(xy 436.477895 -193.288053) (xy 436.448147 -193.333017) (xy 436.412169 -193.373171) (xy 436.370727 -193.407659)
			(xy 436.324706 -193.435745) (xy 436.275086 -193.456832) (xy 436.222925 -193.470468) (xy 436.169334 -193.476365)
			(xy 436.115455 -193.474396) (xy 436.062437 -193.464603) (xy 436.01141 -193.447195) (xy 435.963462 -193.422543)
			(xy 435.919614 -193.391173) (xy 435.880801 -193.353752) (xy 435.847849 -193.311079) (xy 435.821463 -193.264062)
			(xy 435.802203 -193.213705) (xy 435.79048 -193.161081) (xy 435.786545 -193.10731) (xy 434.733714 -193.10731)
			(xy 434.733543 -193.123119) (xy 434.726975 -193.198648) (xy 434.713907 -193.273327) (xy 434.694436 -193.346598)
			(xy 434.668709 -193.417913) (xy 434.653182 -193.452496) (xy 434.653182 -193.45275) (xy 434.649896 -193.460577)
			(xy 434.648205 -193.477456) (xy 434.652176 -193.493949) (xy 434.656484 -193.501264) (xy 434.699918 -193.56959)
			(xy 434.701188 -193.571622) (xy 434.707792 -193.583052) (xy 434.729382 -193.59626) (xy 434.744876 -193.597022)
			(xy 435.229762 -193.597022) (xy 435.239827 -193.597457) (xy 435.258413 -193.60519) (xy 435.26583 -193.612008)
			(xy 435.860444 -194.206622) (xy 435.860952 -194.20713) (xy 435.868332 -194.213715) (xy 435.886631 -194.221169)
			(xy 435.896512 -194.221608) (xy 436.601362 -194.221608) (xy 436.609744 -194.220846) (xy 436.617354 -194.219341)
			(xy 436.631203 -194.212369) (xy 436.636922 -194.20713) (xy 437.177942 -193.66611) (xy 437.185342 -193.659269)
			(xy 437.203941 -193.651548) (xy 437.21401 -193.651124) (xy 437.814466 -193.651124) (xy 437.822594 -193.64833)
			(xy 437.852139 -193.638638) (xy 437.913427 -193.628167) (xy 437.944514 -193.627502) (xy 437.975602 -193.628164)
			(xy 438.036891 -193.638629) (xy 438.066434 -193.64833) (xy 438.074562 -193.651124) (xy 439.798206 -193.651124)
			(xy 439.803929 -193.65097) (xy 439.815083 -193.648396) (xy 439.820304 -193.646044) (xy 439.836306 -193.63817)
			(xy 439.845704 -193.632328) (xy 439.857896 -193.62293) (xy 439.861452 -193.618612) (xy 439.88169 -193.594944)
			(xy 439.927107 -193.552337) (xy 439.9775 -193.515751) (xy 440.032078 -193.485761) (xy 440.08998 -193.46284)
			(xy 440.150296 -193.447348) (xy 440.212077 -193.439529) (xy 440.243214 -193.439034) (xy 440.277758 -193.440304)
			(xy 440.288934 -193.44132) (xy 440.325213 -193.445348) (xy 440.396116 -193.46269) (xy 440.430158 -193.475864)
			(xy 440.437016 -193.478658) (xy 440.44489 -193.47942) (xy 440.454982 -193.479977) (xy 440.474338 -193.47423)
			(xy 440.482482 -193.468244) (xy 440.498484 -193.455036) (xy 440.498738 -193.453004) (xy 440.563 -193.393568)
			(xy 440.570366 -193.365374) (xy 440.565794 -193.35115) (xy 440.553279 -193.310209) (xy 440.535344 -193.226492)
			(xy 440.52998 -193.184018) (xy 440.52871 -193.17335) (xy 440.518296 -193.155316) (xy 440.449716 -193.105024)
			(xy 440.441878 -193.099704) (xy 440.423609 -193.09475) (xy 440.414156 -193.095372) (xy 440.409838 -193.09588)
			(xy 440.407298 -193.096388) (xy 440.367479 -193.103501) (xy 440.28696 -193.111264) (xy 440.246516 -193.111882)
			(xy 440.242198 -193.111882) (xy 440.199181 -193.111306) (xy 440.113571 -193.102781) (xy 440.029206 -193.085912)
			(xy 439.9469 -193.060861) (xy 439.867443 -193.027868) (xy 439.7916 -192.987252) (xy 439.7201 -192.939402)
			(xy 439.65363 -192.884779) (xy 439.592831 -192.823908) (xy 439.538285 -192.757374) (xy 439.490519 -192.685818)
			(xy 439.449992 -192.609927) (xy 439.417092 -192.530432) (xy 439.392137 -192.448096) (xy 439.375367 -192.363712)
			(xy 439.366943 -192.278091) (xy 439.366406 -192.235074) (xy 439.366936 -192.192026) (xy 439.375377 -192.106345)
			(xy 439.392176 -192.021905) (xy 439.41717 -191.939517) (xy 439.45012 -191.859976) (xy 439.490707 -191.784047)
			(xy 439.538541 -191.712463) (xy 439.593161 -191.645911) (xy 439.654041 -191.585034) (xy 439.720595 -191.530417)
			(xy 439.792182 -191.482586) (xy 439.868112 -191.442002) (xy 439.947655 -191.409057) (xy 440.030043 -191.384066)
			(xy 440.114485 -191.367271) (xy 440.200166 -191.358834) (xy 440.243214 -191.358266) (xy 440.262772 -191.358266)
			(xy 440.302963 -191.359613) (xy 440.382863 -191.368754) (xy 440.46159 -191.385175) (xy 440.538483 -191.408737)
			(xy 440.612895 -191.439242) (xy 440.6842 -191.476433) (xy 440.751799 -191.519999) (xy 440.783726 -191.544448)
			(xy 440.790584 -191.550036) (xy 440.803284 -191.554354) (xy 440.812472 -191.557601) (xy 440.831942 -191.557601)
			(xy 440.84113 -191.554354) (xy 440.85383 -191.550036) (xy 440.860688 -191.544702) (xy 440.893752 -191.519437)
			(xy 440.963842 -191.474575) (xy 441.037866 -191.436553) (xy 441.115159 -191.405716) (xy 441.195026 -191.382339)
			(xy 441.276748 -191.366634) (xy 441.359591 -191.358741) (xy 441.4012 -191.358266) (xy 441.444249 -191.358794)
			(xy 441.529933 -191.367233) (xy 441.614378 -191.38403) (xy 441.696769 -191.409023) (xy 441.776314 -191.441971)
			(xy 441.852247 -191.482556) (xy 441.923836 -191.53039) (xy 441.990392 -191.585009) (xy 442.051273 -191.645889)
			(xy 442.105895 -191.712443) (xy 442.15373 -191.784031) (xy 442.194318 -191.859962) (xy 442.227269 -191.939506)
			(xy 442.252264 -192.021897) (xy 442.269063 -192.106341) (xy 442.277504 -192.192025) (xy 442.277812 -192.21831)
			(xy 443.330599 -192.21831) (xy 443.334534 -192.164539) (xy 443.346257 -192.111915) (xy 443.365517 -192.061558)
			(xy 443.391903 -192.014541) (xy 443.424855 -191.971868) (xy 443.463668 -191.934447) (xy 443.507516 -191.903077)
			(xy 443.555464 -191.878425) (xy 443.606491 -191.861017) (xy 443.659509 -191.851224) (xy 443.713388 -191.849255)
			(xy 443.766979 -191.855152) (xy 443.81914 -191.868788) (xy 443.86876 -191.889875) (xy 443.914781 -191.917961)
			(xy 443.956223 -191.952449) (xy 443.992201 -191.992603) (xy 444.021949 -192.037567) (xy 444.044834 -192.086384)
			(xy 444.060366 -192.138013) (xy 444.068216 -192.191353) (xy 444.068708 -192.21831) (xy 445.119267 -192.21831)
			(xy 445.123202 -192.164539) (xy 445.134925 -192.111915) (xy 445.154185 -192.061558) (xy 445.180571 -192.014541)
			(xy 445.213523 -191.971868) (xy 445.252336 -191.934447) (xy 445.296184 -191.903077) (xy 445.344132 -191.878425)
			(xy 445.395159 -191.861017) (xy 445.448177 -191.851224) (xy 445.502056 -191.849255) (xy 445.555647 -191.855152)
			(xy 445.607808 -191.868788) (xy 445.657428 -191.889875) (xy 445.703449 -191.917961) (xy 445.744891 -191.952449)
			(xy 445.780869 -191.992603) (xy 445.810617 -192.037567) (xy 445.833502 -192.086384) (xy 445.849034 -192.138013)
			(xy 445.856884 -192.191353) (xy 445.857376 -192.21831) (xy 445.856884 -192.245267) (xy 445.849034 -192.298607)
			(xy 445.833502 -192.350236) (xy 445.810617 -192.399053) (xy 445.780869 -192.444017) (xy 445.744891 -192.484171)
			(xy 445.703449 -192.518659) (xy 445.657428 -192.546745) (xy 445.607808 -192.567832) (xy 445.555647 -192.581468)
			(xy 445.502056 -192.587365) (xy 445.448177 -192.585396) (xy 445.395159 -192.575603) (xy 445.344132 -192.558195)
			(xy 445.296184 -192.533543) (xy 445.252336 -192.502173) (xy 445.213523 -192.464752) (xy 445.180571 -192.422079)
			(xy 445.154185 -192.375062) (xy 445.134925 -192.324705) (xy 445.123202 -192.272081) (xy 445.119267 -192.21831)
			(xy 444.068708 -192.21831) (xy 444.068216 -192.245267) (xy 444.060366 -192.298607) (xy 444.044834 -192.350236)
			(xy 444.021949 -192.399053) (xy 443.992201 -192.444017) (xy 443.956223 -192.484171) (xy 443.914781 -192.518659)
			(xy 443.86876 -192.546745) (xy 443.81914 -192.567832) (xy 443.766979 -192.581468) (xy 443.713388 -192.587365)
			(xy 443.659509 -192.585396) (xy 443.606491 -192.575603) (xy 443.555464 -192.558195) (xy 443.507516 -192.533543)
			(xy 443.463668 -192.502173) (xy 443.424855 -192.464752) (xy 443.391903 -192.422079) (xy 443.365517 -192.375062)
			(xy 443.346257 -192.324705) (xy 443.334534 -192.272081) (xy 443.330599 -192.21831) (xy 442.277812 -192.21831)
			(xy 442.278008 -192.235074) (xy 442.277526 -192.276256) (xy 442.269781 -192.358254) (xy 442.254385 -192.439165)
			(xy 442.231472 -192.518278) (xy 442.201246 -192.594894) (xy 442.183012 -192.631822) (xy 442.180472 -192.636902)
			(xy 442.177932 -192.64757) (xy 442.176574 -192.65372) (xy 442.176578 -192.666311) (xy 442.177932 -192.672462)
			(xy 442.180472 -192.68313) (xy 442.183012 -192.68821) (xy 442.20124 -192.725141) (xy 442.231479 -192.801753)
			(xy 442.254396 -192.880864) (xy 442.269789 -192.961776) (xy 442.277521 -193.043776) (xy 442.278008 -193.084958)
			(xy 442.277728 -193.10731) (xy 443.330599 -193.10731) (xy 443.334534 -193.053539) (xy 443.346257 -193.000915)
			(xy 443.365517 -192.950558) (xy 443.391903 -192.903541) (xy 443.424855 -192.860868) (xy 443.463668 -192.823447)
			(xy 443.507516 -192.792077) (xy 443.555464 -192.767425) (xy 443.606491 -192.750017) (xy 443.659509 -192.740224)
			(xy 443.713388 -192.738255) (xy 443.766979 -192.744152) (xy 443.81914 -192.757788) (xy 443.86876 -192.778875)
			(xy 443.914781 -192.806961) (xy 443.956223 -192.841449) (xy 443.992201 -192.881603) (xy 444.021949 -192.926567)
			(xy 444.044834 -192.975384) (xy 444.060366 -193.027013) (xy 444.068216 -193.080353) (xy 444.068708 -193.10731)
			(xy 444.068216 -193.134267) (xy 444.060366 -193.187607) (xy 444.044834 -193.239236) (xy 444.021949 -193.288053)
			(xy 443.992201 -193.333017) (xy 443.956223 -193.373171) (xy 443.914781 -193.407659) (xy 443.86876 -193.435745)
			(xy 443.81914 -193.456832) (xy 443.766979 -193.470468) (xy 443.713388 -193.476365) (xy 443.659509 -193.474396)
			(xy 443.606491 -193.464603) (xy 443.555464 -193.447195) (xy 443.507516 -193.422543) (xy 443.463668 -193.391173)
			(xy 443.424855 -193.353752) (xy 443.391903 -193.311079) (xy 443.365517 -193.264062) (xy 443.346257 -193.213705)
			(xy 443.334534 -193.161081) (xy 443.330599 -193.10731) (xy 442.277728 -193.10731) (xy 442.277458 -193.12881)
			(xy 442.268671 -193.216074) (xy 442.25122 -193.302026) (xy 442.22528 -193.385807) (xy 442.19111 -193.466582)
			(xy 442.170566 -193.505328) (xy 442.168261 -193.509858) (xy 442.165321 -193.519585) (xy 442.164724 -193.524632)
			(xy 442.163708 -193.533776) (xy 442.169804 -193.553588) (xy 442.17717 -193.565272) (xy 442.18225 -193.569844)
			(xy 442.185504 -193.572895) (xy 442.190997 -193.57992) (xy 442.193172 -193.583814) (xy 442.193934 -193.585338)
			(xy 442.218826 -193.626486) (xy 442.219588 -193.627756) (xy 442.224443 -193.634717) (xy 442.237768 -193.645211)
			(xy 442.253781 -193.650802) (xy 442.26226 -193.651124) (xy 442.713618 -193.651124) (xy 442.723686 -193.651551)
			(xy 442.742284 -193.659273) (xy 442.749686 -193.66611) (xy 443.303914 -194.220338) (xy 443.304422 -194.220846)
			(xy 443.311801 -194.227434) (xy 443.3301 -194.234896) (xy 443.339982 -194.235324) (xy 444.017654 -194.235324)
			(xy 444.026036 -194.234562) (xy 444.03364 -194.233045) (xy 444.047472 -194.226057) (xy 444.053214 -194.220846)
			(xy 444.689484 -193.584576) (xy 444.696883 -193.577735) (xy 444.715483 -193.570019) (xy 444.725552 -193.56959)
			(xy 447.423286 -193.56959) (xy 447.427761 -193.56952) (xy 447.436577 -193.567989) (xy 447.440812 -193.566542)
			(xy 447.45783 -193.560192) (xy 447.466212 -193.557144) (xy 447.47307 -193.551556) (xy 447.499304 -193.530782)
			(xy 447.556305 -193.495729) (xy 447.617501 -193.468657) (xy 447.681781 -193.450055) (xy 447.747977 -193.440263)
			(xy 447.781426 -193.439288) (xy 447.787522 -193.439288) (xy 447.819438 -193.439803) (xy 447.882737 -193.448029)
			(xy 447.944459 -193.464305) (xy 447.974212 -193.475864) (xy 447.974466 -193.475864) (xy 447.98352 -193.47914)
			(xy 448.002757 -193.479356) (xy 448.020703 -193.472426) (xy 448.02806 -193.466212) (xy 448.106546 -193.393822)
			(xy 448.113912 -193.36512) (xy 448.109594 -193.350896) (xy 448.098646 -193.315367) (xy 448.08211 -193.242879)
			(xy 448.076574 -193.206116) (xy 448.076574 -193.205862) (xy 448.07378 -193.184018) (xy 448.07251 -193.17335)
			(xy 448.062096 -193.155316) (xy 447.993516 -193.105024) (xy 447.985642 -193.099182) (xy 447.967354 -193.094356)
			(xy 447.954654 -193.09588) (xy 447.952876 -193.096134) (xy 447.911871 -193.103505) (xy 447.828927 -193.111391)
			(xy 447.787268 -193.111882) (xy 447.745526 -193.111384) (xy 447.662421 -193.103445) (xy 447.580447 -193.087643)
			(xy 447.500346 -193.064121) (xy 447.422844 -193.033091) (xy 447.348642 -192.994835) (xy 447.278412 -192.949699)
			(xy 447.212791 -192.898092) (xy 447.152373 -192.840481) (xy 447.097704 -192.777387) (xy 447.04928 -192.709383)
			(xy 447.007539 -192.637084) (xy 446.972859 -192.561144) (xy 446.945555 -192.482252) (xy 446.925874 -192.401122)
			(xy 446.913993 -192.318489) (xy 446.910021 -192.2351) (xy 446.913993 -192.151711) (xy 446.925874 -192.069078)
			(xy 446.945555 -191.987948) (xy 446.972859 -191.909056) (xy 447.007539 -191.833116) (xy 447.04928 -191.760817)
			(xy 447.097704 -191.692813) (xy 447.152373 -191.629719) (xy 447.212791 -191.572108) (xy 447.278412 -191.520501)
			(xy 447.348642 -191.475365) (xy 447.422844 -191.437109) (xy 447.500346 -191.406079) (xy 447.580447 -191.382557)
			(xy 447.662421 -191.366755) (xy 447.745526 -191.358816) (xy 447.787268 -191.358266) (xy 447.829458 -191.358767)
			(xy 447.913447 -191.366873) (xy 447.996269 -191.383012) (xy 448.077157 -191.407036) (xy 448.155361 -191.438721)
			(xy 448.230159 -191.477775) (xy 448.300858 -191.523837) (xy 448.33413 -191.549782) (xy 448.347592 -191.56045)
			(xy 448.381628 -191.561212) (xy 448.40017 -191.548004) (xy 448.401186 -191.547242) (xy 448.434368 -191.521641)
			(xy 448.504784 -191.476182) (xy 448.579214 -191.437647) (xy 448.65698 -191.406387) (xy 448.737374 -191.382686)
			(xy 448.819662 -191.366761) (xy 448.903093 -191.358758) (xy 448.945 -191.358266) (xy 448.988049 -191.358794)
			(xy 449.073733 -191.367233) (xy 449.158178 -191.38403) (xy 449.240569 -191.409023) (xy 449.320114 -191.441971)
			(xy 449.396047 -191.482556) (xy 449.467636 -191.53039) (xy 449.534192 -191.585009) (xy 449.595073 -191.645889)
			(xy 449.649695 -191.712443) (xy 449.69753 -191.784031) (xy 449.738118 -191.859962) (xy 449.771069 -191.939506)
			(xy 449.796064 -192.021897) (xy 449.812863 -192.106341) (xy 449.821304 -192.192025) (xy 449.821612 -192.21831)
			(xy 450.874399 -192.21831) (xy 450.878334 -192.164539) (xy 450.890057 -192.111915) (xy 450.909317 -192.061558)
			(xy 450.935703 -192.014541) (xy 450.968655 -191.971868) (xy 451.007468 -191.934447) (xy 451.051316 -191.903077)
			(xy 451.099264 -191.878425) (xy 451.150291 -191.861017) (xy 451.203309 -191.851224) (xy 451.257188 -191.849255)
			(xy 451.310779 -191.855152) (xy 451.36294 -191.868788) (xy 451.41256 -191.889875) (xy 451.458581 -191.917961)
			(xy 451.500023 -191.952449) (xy 451.536001 -191.992603) (xy 451.565749 -192.037567) (xy 451.588634 -192.086384)
			(xy 451.604166 -192.138013) (xy 451.612016 -192.191353) (xy 451.612508 -192.21831) (xy 452.663067 -192.21831)
			(xy 452.667002 -192.164539) (xy 452.678725 -192.111915) (xy 452.697985 -192.061558) (xy 452.724371 -192.014541)
			(xy 452.757323 -191.971868) (xy 452.796136 -191.934447) (xy 452.839984 -191.903077) (xy 452.887932 -191.878425)
			(xy 452.938959 -191.861017) (xy 452.991977 -191.851224) (xy 453.045856 -191.849255) (xy 453.099447 -191.855152)
			(xy 453.151608 -191.868788) (xy 453.201228 -191.889875) (xy 453.247249 -191.917961) (xy 453.288691 -191.952449)
			(xy 453.324669 -191.992603) (xy 453.354417 -192.037567) (xy 453.377302 -192.086384) (xy 453.392834 -192.138013)
			(xy 453.400684 -192.191353) (xy 453.401176 -192.21831) (xy 453.400684 -192.245267) (xy 453.396041 -192.276818)
			(xy 454.454757 -192.276818) (xy 454.454757 -192.19333) (xy 454.462693 -192.11022) (xy 454.478493 -192.028242)
			(xy 454.502014 -191.948136) (xy 454.533043 -191.870628) (xy 454.5713 -191.796422) (xy 454.616436 -191.726187)
			(xy 454.668045 -191.660561) (xy 454.725658 -191.600139) (xy 454.788754 -191.545466) (xy 454.856761 -191.497038)
			(xy 454.929064 -191.455294) (xy 455.005007 -191.420612) (xy 455.083903 -191.393306) (xy 455.165037 -191.373623)
			(xy 455.247675 -191.361742) (xy 455.331068 -191.357769) (xy 455.414461 -191.361742) (xy 455.497099 -191.373623)
			(xy 455.578233 -191.393306) (xy 455.657129 -191.420612) (xy 455.733072 -191.455294) (xy 455.805375 -191.497038)
			(xy 455.873382 -191.545466) (xy 455.936478 -191.600139) (xy 455.994091 -191.660561) (xy 456.0457 -191.726187)
			(xy 456.090836 -191.796422) (xy 456.129093 -191.870628) (xy 456.160122 -191.948136) (xy 456.183643 -192.028242)
			(xy 456.199443 -192.11022) (xy 456.207379 -192.19333) (xy 456.207876 -192.235074) (xy 456.207379 -192.276818)
			(xy 456.199443 -192.359928) (xy 456.183643 -192.441906) (xy 456.160122 -192.522012) (xy 456.129093 -192.59952)
			(xy 456.090836 -192.673727) (xy 456.0457 -192.743961) (xy 455.994091 -192.809587) (xy 455.936478 -192.870009)
			(xy 455.873382 -192.924682) (xy 455.805375 -192.97311) (xy 455.733072 -193.014854) (xy 455.657129 -193.049536)
			(xy 455.578233 -193.076842) (xy 455.497099 -193.096525) (xy 455.414461 -193.108406) (xy 455.331068 -193.112379)
			(xy 455.247675 -193.108406) (xy 455.165037 -193.096525) (xy 455.083903 -193.076842) (xy 455.005007 -193.049536)
			(xy 454.929064 -193.014854) (xy 454.856761 -192.97311) (xy 454.788754 -192.924682) (xy 454.725658 -192.870009)
			(xy 454.668045 -192.809587) (xy 454.616436 -192.743961) (xy 454.5713 -192.673727) (xy 454.533043 -192.59952)
			(xy 454.502014 -192.522012) (xy 454.478493 -192.441906) (xy 454.462693 -192.359928) (xy 454.454757 -192.276818)
			(xy 453.396041 -192.276818) (xy 453.392834 -192.298607) (xy 453.377302 -192.350236) (xy 453.354417 -192.399053)
			(xy 453.324669 -192.444017) (xy 453.288691 -192.484171) (xy 453.247249 -192.518659) (xy 453.201228 -192.546745)
			(xy 453.151608 -192.567832) (xy 453.099447 -192.581468) (xy 453.045856 -192.587365) (xy 452.991977 -192.585396)
			(xy 452.938959 -192.575603) (xy 452.887932 -192.558195) (xy 452.839984 -192.533543) (xy 452.796136 -192.502173)
			(xy 452.757323 -192.464752) (xy 452.724371 -192.422079) (xy 452.697985 -192.375062) (xy 452.678725 -192.324705)
			(xy 452.667002 -192.272081) (xy 452.663067 -192.21831) (xy 451.612508 -192.21831) (xy 451.612016 -192.245267)
			(xy 451.604166 -192.298607) (xy 451.588634 -192.350236) (xy 451.565749 -192.399053) (xy 451.536001 -192.444017)
			(xy 451.500023 -192.484171) (xy 451.458581 -192.518659) (xy 451.41256 -192.546745) (xy 451.36294 -192.567832)
			(xy 451.310779 -192.581468) (xy 451.257188 -192.587365) (xy 451.203309 -192.585396) (xy 451.150291 -192.575603)
			(xy 451.099264 -192.558195) (xy 451.051316 -192.533543) (xy 451.007468 -192.502173) (xy 450.968655 -192.464752)
			(xy 450.935703 -192.422079) (xy 450.909317 -192.375062) (xy 450.890057 -192.324705) (xy 450.878334 -192.272081)
			(xy 450.874399 -192.21831) (xy 449.821612 -192.21831) (xy 449.821808 -192.235074) (xy 449.821326 -192.276256)
			(xy 449.813581 -192.358254) (xy 449.798185 -192.439165) (xy 449.775272 -192.518278) (xy 449.745046 -192.594894)
			(xy 449.726812 -192.631822) (xy 449.724272 -192.636902) (xy 449.721732 -192.64757) (xy 449.720374 -192.65372)
			(xy 449.720378 -192.666311) (xy 449.721732 -192.672462) (xy 449.724272 -192.68313) (xy 449.726812 -192.68821)
			(xy 449.74504 -192.725141) (xy 449.775279 -192.801753) (xy 449.798196 -192.880864) (xy 449.813589 -192.961776)
			(xy 449.821321 -193.043776) (xy 449.821808 -193.084958) (xy 449.821531 -193.10731) (xy 450.874399 -193.10731)
			(xy 450.878334 -193.053539) (xy 450.890057 -193.000915) (xy 450.909317 -192.950558) (xy 450.935703 -192.903541)
			(xy 450.968655 -192.860868) (xy 451.007468 -192.823447) (xy 451.051316 -192.792077) (xy 451.099264 -192.767425)
			(xy 451.150291 -192.750017) (xy 451.203309 -192.740224) (xy 451.257188 -192.738255) (xy 451.310779 -192.744152)
			(xy 451.36294 -192.757788) (xy 451.41256 -192.778875) (xy 451.458581 -192.806961) (xy 451.500023 -192.841449)
			(xy 451.536001 -192.881603) (xy 451.565749 -192.926567) (xy 451.588634 -192.975384) (xy 451.604166 -193.027013)
			(xy 451.612016 -193.080353) (xy 451.612508 -193.10731) (xy 451.612016 -193.134267) (xy 451.604166 -193.187607)
			(xy 451.588634 -193.239236) (xy 451.565749 -193.288053) (xy 451.536001 -193.333017) (xy 451.500023 -193.373171)
			(xy 451.458581 -193.407659) (xy 451.41256 -193.435745) (xy 451.36294 -193.456832) (xy 451.310779 -193.470468)
			(xy 451.257188 -193.476365) (xy 451.203309 -193.474396) (xy 451.150291 -193.464603) (xy 451.099264 -193.447195)
			(xy 451.051316 -193.422543) (xy 451.007468 -193.391173) (xy 450.968655 -193.353752) (xy 450.935703 -193.311079)
			(xy 450.909317 -193.264062) (xy 450.890057 -193.213705) (xy 450.878334 -193.161081) (xy 450.874399 -193.10731)
			(xy 449.821531 -193.10731) (xy 449.821268 -193.128592) (xy 449.812594 -193.215429) (xy 449.795327 -193.300973)
			(xy 449.769638 -193.384375) (xy 449.753228 -193.42481) (xy 449.75145 -193.428874) (xy 449.749418 -193.438526)
			(xy 449.747858 -193.448155) (xy 449.751266 -193.467346) (xy 449.756022 -193.475864) (xy 449.756784 -193.47688)
			(xy 449.803012 -193.54673) (xy 449.803774 -193.548) (xy 449.811391 -193.557639) (xy 449.833163 -193.568934)
			(xy 449.84543 -193.56959) (xy 450.184774 -193.56959) (xy 450.194838 -193.570026) (xy 450.213424 -193.577758)
			(xy 450.220842 -193.584576) (xy 450.924168 -194.287902) (xy 450.924676 -194.28841) (xy 450.932056 -194.294993)
			(xy 450.950356 -194.302442) (xy 450.960236 -194.302888) (xy 452.60895 -194.302888) (xy 452.617561 -194.302551)
			(xy 452.633818 -194.296865) (xy 452.647297 -194.286145) (xy 452.65213 -194.279012) (xy 452.69785 -194.206114)
			(xy 452.702117 -194.198673) (xy 452.705883 -194.181951) (xy 452.703879 -194.164927) (xy 452.70039 -194.157092)
			(xy 452.688745 -194.131908) (xy 452.672321 -194.078913) (xy 452.664044 -194.024052) (xy 452.66356 -193.99631)
			(xy 452.66356 -193.991484) (xy 452.664417 -193.96412) (xy 452.673216 -193.910087) (xy 452.689906 -193.857948)
			(xy 452.714119 -193.808848) (xy 452.745323 -193.763867) (xy 452.782834 -193.723992) (xy 452.825826 -193.6901)
			(xy 452.873355 -193.662934) (xy 452.924378 -193.643093) (xy 452.977773 -193.631011) (xy 453.032368 -193.626953)
			(xy 453.086963 -193.631011) (xy 453.140358 -193.643093) (xy 453.191381 -193.662934) (xy 453.23891 -193.6901)
			(xy 453.281902 -193.723992) (xy 453.319413 -193.763867) (xy 453.350617 -193.808848) (xy 453.37483 -193.857948)
			(xy 453.39152 -193.910087) (xy 453.400319 -193.96412) (xy 453.401176 -193.991484) (xy 453.401176 -193.99631)
			(xy 453.400672 -194.024049) (xy 453.39237 -194.078902) (xy 453.375968 -194.1319) (xy 453.364346 -194.157092)
			(xy 453.360923 -194.164944) (xy 453.358954 -194.181951) (xy 453.362657 -194.198666) (xy 453.366886 -194.206114)
			(xy 453.412606 -194.279012) (xy 453.417449 -194.28614) (xy 453.430905 -194.296888) (xy 453.447173 -194.302536)
			(xy 453.455786 -194.302888) (xy 454.810368 -194.302888) (xy 454.833736 -194.289172) (xy 454.840086 -194.277996)
			(xy 454.841102 -194.275964) (xy 454.885298 -194.205098) (xy 454.888559 -194.19951) (xy 454.892419 -194.187165)
			(xy 454.892918 -194.180714) (xy 454.893426 -194.168014) (xy 454.879586 -194.141034) (xy 454.857837 -194.08443)
			(xy 454.843143 -194.025598) (xy 454.835723 -193.965415) (xy 454.83526 -193.935096) (xy 454.835749 -193.903933)
			(xy 454.843561 -193.842099) (xy 454.859061 -193.781731) (xy 454.882004 -193.723783) (xy 454.91203 -193.669166)
			(xy 454.948664 -193.618744) (xy 454.991329 -193.57331) (xy 455.039351 -193.533582) (xy 455.091975 -193.500187)
			(xy 455.148369 -193.47365) (xy 455.207644 -193.45439) (xy 455.268865 -193.442711) (xy 455.331068 -193.438798)
			(xy 455.393271 -193.442711) (xy 455.454492 -193.45439) (xy 455.513767 -193.47365) (xy 455.570161 -193.500187)
			(xy 455.622785 -193.533582) (xy 455.670807 -193.57331) (xy 455.713472 -193.618744) (xy 455.750106 -193.669166)
			(xy 455.780132 -193.723783) (xy 455.803075 -193.781731) (xy 455.818575 -193.842099) (xy 455.826387 -193.903933)
			(xy 455.826876 -193.935096) (xy 455.826449 -193.963808) (xy 455.819786 -194.020843) (xy 455.806583 -194.076728)
			(xy 455.787017 -194.130716) (xy 455.774552 -194.156584) (xy 455.771871 -194.162503) (xy 455.769292 -194.175235)
			(xy 455.769472 -194.18173) (xy 455.76998 -194.193922) (xy 455.821034 -194.275964) (xy 455.82205 -194.277996)
			(xy 455.8284 -194.289172) (xy 455.851768 -194.302888) (xy 457.166472 -194.302888) (xy 457.174854 -194.302126)
			(xy 457.182463 -194.300618) (xy 457.196308 -194.293643) (xy 457.202032 -194.28841) (xy 463.209894 -188.280548)
			(xy 463.210402 -188.28004) (xy 463.216989 -188.272661) (xy 463.224444 -188.254361) (xy 463.22488 -188.24448)
			(xy 463.22488 -170.315382) (xy 463.224453 -170.305314) (xy 463.216732 -170.286716) (xy 463.209894 -170.279314)
			(xy 456.115674 -163.185094) (xy 456.108821 -163.177699) (xy 456.101077 -163.1591) (xy 456.100688 -163.149026)
			(xy 456.100688 -156.72562) (xy 456.101125 -156.715556) (xy 456.108859 -156.696971) (xy 456.115674 -156.689552)
			(xy 463.040222 -149.765004) (xy 463.047622 -149.758161) (xy 463.06622 -149.750434) (xy 463.07629 -149.750018)
			(xy 463.25155 -149.750018) (xy 463.259932 -149.749256) (xy 463.267536 -149.747739) (xy 463.281369 -149.740752)
			(xy 463.28711 -149.73554) (xy 465.322412 -147.700238) (xy 465.32292 -147.69973) (xy 465.329503 -147.692349)
			(xy 465.336952 -147.67405) (xy 465.337398 -147.66417) (xy 465.337398 -80.05572) (xy 465.33696 -80.045656)
			(xy 465.329225 -80.027073) (xy 465.322412 -80.019652) (xy 463.488278 -78.185518) (xy 463.480879 -78.178673)
			(xy 463.462281 -78.170944) (xy 463.45221 -78.170532) (xy 450.671184 -78.170532) (xy 450.661114 -78.170107)
			(xy 450.642511 -78.162392) (xy 450.635116 -78.155546) (xy 429.681386 -57.201816) (xy 429.674543 -57.194417)
			(xy 429.666826 -57.175818) (xy 429.6664 -57.165748) (xy 429.6664 -52.239926) (xy 429.665963 -52.229862)
			(xy 429.65823 -52.211277) (xy 429.651414 -52.203858) (xy 429.081438 -51.633882) (xy 429.07404 -51.627037)
			(xy 429.055441 -51.619312) (xy 429.04537 -51.618896) (xy 425.129198 -51.618896) (xy 425.119128 -51.61932)
			(xy 425.100524 -51.627034) (xy 425.09313 -51.633882) (xy 424.673014 -52.053998) (xy 424.666166 -52.061396)
			(xy 424.658429 -52.079994) (xy 424.658028 -52.090066) (xy 424.658028 -55.677816) (xy 424.658632 -55.692979)
			(xy 424.667619 -55.721945) (xy 424.684707 -55.747002) (xy 424.708394 -55.765943) (xy 424.736596 -55.777102)
			(xy 424.76683 -55.779498) (xy 424.796436 -55.772919) (xy 424.80992 -55.765954) (xy 424.831564 -55.754071)
			(xy 424.877262 -55.735368) (xy 424.924991 -55.722716) (xy 424.973953 -55.716326) (xy 424.998642 -55.715916)
			(xy 425.025911 -55.716405) (xy 425.079893 -55.724172) (xy 425.132221 -55.739542) (xy 425.181828 -55.762202)
			(xy 425.227707 -55.791691) (xy 425.268922 -55.827408) (xy 425.304634 -55.868627) (xy 425.334118 -55.914509)
			(xy 425.356773 -55.964119) (xy 425.372137 -56.016448) (xy 425.379898 -56.070431) (xy 425.379898 -56.097678)
			(xy 426.955964 -56.097678) (xy 426.960035 -56.042056) (xy 426.972161 -55.987619) (xy 426.992084 -55.935528)
			(xy 427.01938 -55.886893) (xy 427.053466 -55.84275) (xy 427.093615 -55.804041) (xy 427.138973 -55.77159)
			(xy 427.188573 -55.746089) (xy 427.241357 -55.728082) (xy 427.2962 -55.717952) (xy 427.351934 -55.715915)
			(xy 427.407371 -55.722015) (xy 427.461328 -55.736121) (xy 427.512657 -55.757933) (xy 427.560263 -55.786987)
			(xy 427.603131 -55.822662) (xy 427.640348 -55.864199) (xy 427.671121 -55.910712) (xy 427.694793 -55.961209)
			(xy 427.710861 -56.014616) (xy 427.718981 -56.069792) (xy 427.71949 -56.097678) (xy 427.718981 -56.125564)
			(xy 427.710861 -56.18074) (xy 427.694793 -56.234147) (xy 427.671121 -56.284644) (xy 427.640348 -56.331157)
			(xy 427.603131 -56.372694) (xy 427.560263 -56.408369) (xy 427.512657 -56.437423) (xy 427.461328 -56.459235)
			(xy 427.407371 -56.473341) (xy 427.351934 -56.479441) (xy 427.2962 -56.477404) (xy 427.241357 -56.467274)
			(xy 427.188573 -56.449267) (xy 427.138973 -56.423766) (xy 427.093615 -56.391315) (xy 427.053466 -56.352606)
			(xy 427.01938 -56.308463) (xy 426.992084 -56.259828) (xy 426.972161 -56.207737) (xy 426.960035 -56.1533)
			(xy 426.955964 -56.097678) (xy 425.379898 -56.097678) (xy 425.379898 -56.124969) (xy 425.372137 -56.178952)
			(xy 425.356773 -56.231281) (xy 425.334118 -56.280891) (xy 425.304634 -56.326773) (xy 425.268922 -56.367992)
			(xy 425.227707 -56.403709) (xy 425.181828 -56.433198) (xy 425.132221 -56.455858) (xy 425.079893 -56.471228)
			(xy 425.025911 -56.478995) (xy 424.998642 -56.47944) (xy 424.973953 -56.479035) (xy 424.924992 -56.472639)
			(xy 424.877263 -56.459986) (xy 424.831563 -56.441288) (xy 424.80992 -56.429402) (xy 424.796453 -56.422372)
			(xy 424.766822 -56.415752) (xy 424.736554 -56.418128) (xy 424.708319 -56.429292) (xy 424.68461 -56.448258)
			(xy 424.667519 -56.473352) (xy 424.658554 -56.50236) (xy 424.658028 -56.51754) (xy 424.658028 -57.997598)
			(xy 426.949614 -57.997598) (xy 426.953685 -57.941976) (xy 426.965811 -57.887539) (xy 426.985734 -57.835448)
			(xy 427.01303 -57.786813) (xy 427.047116 -57.74267) (xy 427.087265 -57.703961) (xy 427.132623 -57.67151)
			(xy 427.182223 -57.646009) (xy 427.235007 -57.628002) (xy 427.28985 -57.617872) (xy 427.345584 -57.615835)
			(xy 427.401021 -57.621935) (xy 427.454978 -57.636041) (xy 427.506307 -57.657853) (xy 427.553913 -57.686907)
			(xy 427.596781 -57.722582) (xy 427.633998 -57.764119) (xy 427.664771 -57.810632) (xy 427.688443 -57.861129)
			(xy 427.704511 -57.914536) (xy 427.712631 -57.969712) (xy 427.71314 -57.997598) (xy 427.712631 -58.025484)
			(xy 427.704511 -58.08066) (xy 427.688443 -58.134067) (xy 427.664771 -58.184564) (xy 427.633998 -58.231077)
			(xy 427.596781 -58.272614) (xy 427.553913 -58.308289) (xy 427.506307 -58.337343) (xy 427.454978 -58.359155)
			(xy 427.401021 -58.373261) (xy 427.345584 -58.379361) (xy 427.28985 -58.377324) (xy 427.235007 -58.367194)
			(xy 427.182223 -58.349187) (xy 427.132623 -58.323686) (xy 427.087265 -58.291235) (xy 427.047116 -58.252526)
			(xy 427.01303 -58.208383) (xy 426.985734 -58.159748) (xy 426.965811 -58.107657) (xy 426.953685 -58.05322)
			(xy 426.949614 -57.997598) (xy 424.658028 -57.997598) (xy 424.658028 -59.436) (xy 427.59325 -59.436)
			(xy 427.597321 -59.380378) (xy 427.609447 -59.325941) (xy 427.62937 -59.27385) (xy 427.656666 -59.225215)
			(xy 427.690752 -59.181072) (xy 427.730901 -59.142363) (xy 427.776259 -59.109912) (xy 427.825859 -59.084411)
			(xy 427.878643 -59.066404) (xy 427.933486 -59.056274) (xy 427.98922 -59.054237) (xy 428.044657 -59.060337)
			(xy 428.098614 -59.074443) (xy 428.149943 -59.096255) (xy 428.197549 -59.125309) (xy 428.240417 -59.160984)
			(xy 428.277634 -59.202521) (xy 428.308407 -59.249034) (xy 428.332079 -59.299531) (xy 428.348147 -59.352938)
			(xy 428.356267 -59.408114) (xy 428.356776 -59.436) (xy 428.49699 -59.436) (xy 428.501003 -59.372204)
			(xy 428.512981 -59.309414) (xy 428.532734 -59.248621) (xy 428.559951 -59.190782) (xy 428.594202 -59.136811)
			(xy 428.634947 -59.087558) (xy 428.681544 -59.043801) (xy 428.733259 -59.006228) (xy 428.789274 -58.975434)
			(xy 428.848707 -58.951902) (xy 428.910621 -58.936005) (xy 428.974039 -58.927994) (xy 429.006 -58.927492)
			(xy 429.03728 -58.927911) (xy 429.099369 -58.935575) (xy 429.160047 -58.950801) (xy 429.218399 -58.973358)
			(xy 429.273542 -59.002904) (xy 429.324642 -59.038995) (xy 429.370928 -59.081083) (xy 429.411699 -59.128532)
			(xy 429.429418 -59.154314) (xy 429.43687 -59.164474) (xy 429.459001 -59.17646) (xy 429.471582 -59.177174)
			(xy 429.556418 -59.177174) (xy 429.569001 -59.176494) (xy 429.59112 -59.164472) (xy 429.598582 -59.154314)
			(xy 429.616344 -59.128567) (xy 429.657124 -59.081139) (xy 429.703411 -59.039068) (xy 429.754508 -59.00299)
			(xy 429.809642 -58.97345) (xy 429.867983 -58.950892) (xy 429.928649 -58.935657) (xy 429.990725 -58.927976)
			(xy 430.022 -58.927492) (xy 430.053961 -58.927994) (xy 430.117379 -58.936005) (xy 430.179293 -58.951902)
			(xy 430.238726 -58.975434) (xy 430.294741 -59.006228) (xy 430.346456 -59.043801) (xy 430.393053 -59.087558)
			(xy 430.433798 -59.136811) (xy 430.468049 -59.190782) (xy 430.495266 -59.248621) (xy 430.515019 -59.309414)
			(xy 430.526997 -59.372204) (xy 430.531011 -59.436) (xy 430.526997 -59.499796) (xy 430.515019 -59.562586)
			(xy 430.495266 -59.623379) (xy 430.468049 -59.681218) (xy 430.433798 -59.735189) (xy 430.393053 -59.784442)
			(xy 430.346456 -59.828199) (xy 430.294741 -59.865772) (xy 430.238726 -59.896566) (xy 430.179293 -59.920098)
			(xy 430.117379 -59.935995) (xy 430.053961 -59.944006) (xy 430.022 -59.944508) (xy 429.99072 -59.944089)
			(xy 429.928631 -59.936425) (xy 429.867953 -59.921199) (xy 429.809601 -59.898642) (xy 429.754458 -59.869096)
			(xy 429.703358 -59.833005) (xy 429.657072 -59.790917) (xy 429.616301 -59.743468) (xy 429.598582 -59.717686)
			(xy 429.59113 -59.707526) (xy 429.568999 -59.69554) (xy 429.556418 -59.694826) (xy 429.471582 -59.694826)
			(xy 429.458999 -59.695506) (xy 429.43688 -59.707528) (xy 429.429418 -59.717686) (xy 429.411656 -59.743433)
			(xy 429.370876 -59.790861) (xy 429.324589 -59.832932) (xy 429.273492 -59.86901) (xy 429.218358 -59.89855)
			(xy 429.160017 -59.921108) (xy 429.099351 -59.936343) (xy 429.037275 -59.944024) (xy 429.006 -59.944508)
			(xy 428.974039 -59.944006) (xy 428.910621 -59.935995) (xy 428.848707 -59.920098) (xy 428.789274 -59.896566)
			(xy 428.733259 -59.865772) (xy 428.681544 -59.828199) (xy 428.634947 -59.784442) (xy 428.594202 -59.735189)
			(xy 428.559951 -59.681218) (xy 428.532734 -59.623379) (xy 428.512981 -59.562586) (xy 428.501003 -59.499796)
			(xy 428.49699 -59.436) (xy 428.356776 -59.436) (xy 428.356267 -59.463886) (xy 428.348147 -59.519062)
			(xy 428.332079 -59.572469) (xy 428.308407 -59.622966) (xy 428.277634 -59.669479) (xy 428.240417 -59.711016)
			(xy 428.197549 -59.746691) (xy 428.149943 -59.775745) (xy 428.098614 -59.797557) (xy 428.044657 -59.811663)
			(xy 427.98922 -59.817763) (xy 427.933486 -59.815726) (xy 427.878643 -59.805596) (xy 427.825859 -59.787589)
			(xy 427.776259 -59.762088) (xy 427.730901 -59.729637) (xy 427.690752 -59.690928) (xy 427.656666 -59.646785)
			(xy 427.62937 -59.59815) (xy 427.609447 -59.546059) (xy 427.597321 -59.491622) (xy 427.59325 -59.436)
			(xy 424.658028 -59.436) (xy 424.658028 -60.84316) (xy 424.658638 -60.855581) (xy 424.670214 -60.877561)
			(xy 424.680126 -60.88507) (xy 424.748706 -60.931806) (xy 424.757708 -60.937332) (xy 424.778438 -60.941271)
			(xy 424.788838 -60.939426) (xy 424.797474 -60.937394) (xy 424.801538 -60.935616) (xy 424.89712 -60.898844)
			(xy 425.090576 -60.831568) (xy 425.2864 -60.771531) (xy 425.48432 -60.718817) (xy 425.684064 -60.673498)
			(xy 425.885354 -60.635636) (xy 426.087913 -60.605285) (xy 426.291461 -60.582485) (xy 426.495715 -60.567269)
			(xy 426.700394 -60.559658) (xy 426.802804 -60.559188) (xy 426.810678 -60.559188) (xy 426.84319 -60.559442)
			(xy 426.948218 -60.56071) (xy 427.15807 -60.570261) (xy 427.367405 -60.587805) (xy 427.575919 -60.613317)
			(xy 427.783309 -60.64676) (xy 427.989273 -60.688085) (xy 428.193513 -60.737231) (xy 428.39573 -60.794128)
			(xy 428.595631 -60.858693) (xy 428.792925 -60.930832) (xy 428.987326 -61.010439) (xy 429.17855 -61.0974)
			(xy 429.36632 -61.191588) (xy 429.550364 -61.292865) (xy 429.730412 -61.401085) (xy 429.906204 -61.516091)
			(xy 430.077483 -61.637714) (xy 430.244002 -61.765779) (xy 430.405517 -61.900099) (xy 430.561794 -62.040479)
			(xy 430.712606 -62.186714) (xy 430.857734 -62.338593) (xy 430.996965 -62.495893) (xy 431.130099 -62.658388)
			(xy 431.256942 -62.825839) (xy 431.377308 -62.998005) (xy 431.491023 -63.174634) (xy 431.597922 -63.35547)
			(xy 431.69785 -63.540249) (xy 431.79066 -63.728704) (xy 431.876219 -63.92056) (xy 431.954401 -64.115538)
			(xy 432.025094 -64.313356) (xy 432.088193 -64.513724) (xy 432.143608 -64.716352) (xy 432.191258 -64.920945)
			(xy 432.231074 -65.127207) (xy 432.262997 -65.334836) (xy 432.286982 -65.543531) (xy 432.302993 -65.752989)
			(xy 432.311008 -65.962905) (xy 432.311556 -66.06794) (xy 432.311556 -74.439272) (xy 437.38495 -74.439272)
			(xy 437.389021 -74.38365) (xy 437.401147 -74.329213) (xy 437.42107 -74.277122) (xy 437.448366 -74.228487)
			(xy 437.482452 -74.184344) (xy 437.522601 -74.145635) (xy 437.567959 -74.113184) (xy 437.617559 -74.087683)
			(xy 437.670343 -74.069676) (xy 437.725186 -74.059546) (xy 437.78092 -74.057509) (xy 437.836357 -74.063609)
			(xy 437.890314 -74.077715) (xy 437.941643 -74.099527) (xy 437.989249 -74.128581) (xy 438.032117 -74.164256)
			(xy 438.069334 -74.205793) (xy 438.100107 -74.252306) (xy 438.123779 -74.302803) (xy 438.139847 -74.35621)
			(xy 438.147967 -74.411386) (xy 438.148476 -74.439272) (xy 438.147967 -74.467158) (xy 438.139847 -74.522334)
			(xy 438.123779 -74.575741) (xy 438.100107 -74.626238) (xy 438.069334 -74.672751) (xy 438.032117 -74.714288)
			(xy 437.989249 -74.749963) (xy 437.941643 -74.779017) (xy 437.890314 -74.800829) (xy 437.836357 -74.814935)
			(xy 437.78092 -74.821035) (xy 437.725186 -74.818998) (xy 437.670343 -74.808868) (xy 437.617559 -74.790861)
			(xy 437.567959 -74.76536) (xy 437.522601 -74.732909) (xy 437.482452 -74.6942) (xy 437.448366 -74.650057)
			(xy 437.42107 -74.601422) (xy 437.401147 -74.549331) (xy 437.389021 -74.494894) (xy 437.38495 -74.439272)
			(xy 432.311556 -74.439272) (xy 432.311556 -74.767948) (xy 432.31106 -74.872924) (xy 432.303059 -75.082723)
			(xy 432.287069 -75.292064) (xy 432.263114 -75.500645) (xy 432.231229 -75.708161) (xy 432.19146 -75.914312)
			(xy 432.143865 -76.118797) (xy 432.088513 -76.321321) (xy 432.025484 -76.521588) (xy 431.95487 -76.719308)
			(xy 431.876774 -76.914195) (xy 431.791308 -77.105963) (xy 431.742491 -77.205151) (xy 444.690478 -77.205151)
			(xy 444.690478 -77.150649) (xy 444.698234 -77.096701) (xy 444.713589 -77.044406) (xy 444.736231 -76.994829)
			(xy 444.765697 -76.948979) (xy 444.801388 -76.907788) (xy 444.842579 -76.872097) (xy 444.888429 -76.842631)
			(xy 444.938006 -76.819989) (xy 444.990301 -76.804634) (xy 445.044249 -76.796878) (xy 445.0715 -76.796392)
			(xy 445.101406 -76.796966) (xy 445.160484 -76.806313) (xy 445.217381 -76.824762) (xy 445.270702 -76.851862)
			(xy 445.319143 -76.886949) (xy 445.34074 -76.907644) (xy 445.347852 -76.914756) (xy 445.365124 -76.922122)
			(xy 445.454532 -76.924916) (xy 445.472312 -76.918566) (xy 445.479678 -76.911962) (xy 445.500683 -76.8941)
			(xy 445.546872 -76.863989) (xy 445.596915 -76.840839) (xy 445.649768 -76.825133) (xy 445.704331 -76.817197)
			(xy 445.7319 -76.816712) (xy 445.759153 -76.817158) (xy 445.813103 -76.824915) (xy 445.865401 -76.840271)
			(xy 445.914981 -76.862913) (xy 445.960833 -76.892381) (xy 446.002026 -76.928074) (xy 446.037719 -76.969267)
			(xy 446.067187 -77.015119) (xy 446.089829 -77.064699) (xy 446.105185 -77.116997) (xy 446.112942 -77.170947)
			(xy 446.112942 -77.225453) (xy 446.105185 -77.279403) (xy 446.089829 -77.331701) (xy 446.067187 -77.381281)
			(xy 446.037719 -77.427133) (xy 446.002026 -77.468326) (xy 445.960833 -77.504019) (xy 445.914981 -77.533487)
			(xy 445.865401 -77.556129) (xy 445.813103 -77.571485) (xy 445.759153 -77.579242) (xy 445.7319 -77.579728)
			(xy 445.701994 -77.579148) (xy 445.642917 -77.569802) (xy 445.586021 -77.551353) (xy 445.532699 -77.524255)
			(xy 445.484258 -77.48917) (xy 445.46266 -77.468476) (xy 445.455548 -77.461364) (xy 445.438276 -77.453998)
			(xy 445.348868 -77.451204) (xy 445.331088 -77.457554) (xy 445.323722 -77.464158) (xy 445.30272 -77.482024)
			(xy 445.256529 -77.512133) (xy 445.206486 -77.535282) (xy 445.153633 -77.550987) (xy 445.099069 -77.558923)
			(xy 445.0715 -77.559408) (xy 445.044249 -77.558922) (xy 444.990301 -77.551166) (xy 444.938006 -77.535811)
			(xy 444.888429 -77.513169) (xy 444.842579 -77.483703) (xy 444.801388 -77.448012) (xy 444.765697 -77.406821)
			(xy 444.736231 -77.360971) (xy 444.713589 -77.311394) (xy 444.698234 -77.259099) (xy 444.690478 -77.205151)
			(xy 431.742491 -77.205151) (xy 431.698598 -77.294336) (xy 431.598777 -77.47904) (xy 431.491991 -77.659806)
			(xy 431.378395 -77.836372) (xy 431.258153 -78.008482) (xy 431.131441 -78.175884) (xy 430.998442 -78.338337)
			(xy 430.85935 -78.495605) (xy 430.714367 -78.647458) (xy 430.563702 -78.793677) (xy 430.407576 -78.934048)
			(xy 430.246214 -79.068369) (xy 430.079852 -79.196444) (xy 429.90873 -79.318087) (xy 429.733098 -79.433121)
			(xy 429.55321 -79.541379) (xy 429.369327 -79.642705) (xy 429.181717 -79.73695) (xy 428.990653 -79.823979)
			(xy 428.796411 -79.903664) (xy 428.599274 -79.97589) (xy 428.399528 -80.040552) (xy 428.197463 -80.097556)
			(xy 427.993373 -80.146819) (xy 427.787554 -80.18827) (xy 427.580305 -80.221849) (xy 427.371927 -80.247506)
			(xy 427.26737 -80.256888) (xy 427.258226 -80.25765) (xy 427.242224 -80.26527) (xy 427.234858 -80.272636)
			(xy 427.231106 -80.276622) (xy 427.225212 -80.285844) (xy 427.223174 -80.290924) (xy 427.187614 -80.387444)
			(xy 427.190154 -80.410812) (xy 427.196504 -80.420972) (xy 427.199806 -80.426306) (xy 427.914054 -81.140554)
			(xy 427.914562 -81.141062) (xy 427.921944 -81.147642) (xy 427.940243 -81.155088) (xy 427.950122 -81.15554)
			(xy 443.065154 -81.15554) (xy 443.075219 -81.155974) (xy 443.093805 -81.163707) (xy 443.101222 -81.170526)
			(xy 443.29223 -81.361534) (xy 461.778348 -81.361534) (xy 461.782419 -81.305912) (xy 461.794545 -81.251475)
			(xy 461.814468 -81.199384) (xy 461.841764 -81.150749) (xy 461.87585 -81.106606) (xy 461.915999 -81.067897)
			(xy 461.961357 -81.035446) (xy 462.010957 -81.009945) (xy 462.063741 -80.991938) (xy 462.118584 -80.981808)
			(xy 462.174318 -80.979771) (xy 462.229755 -80.985871) (xy 462.283712 -80.999977) (xy 462.335041 -81.021789)
			(xy 462.382647 -81.050843) (xy 462.425515 -81.086518) (xy 462.462732 -81.128055) (xy 462.493505 -81.174568)
			(xy 462.517177 -81.225065) (xy 462.533245 -81.278472) (xy 462.541365 -81.333648) (xy 462.541874 -81.361534)
			(xy 462.541365 -81.38942) (xy 462.533245 -81.444596) (xy 462.517177 -81.498003) (xy 462.493505 -81.5485)
			(xy 462.462732 -81.595013) (xy 462.425515 -81.63655) (xy 462.382647 -81.672225) (xy 462.335041 -81.701279)
			(xy 462.283712 -81.723091) (xy 462.229755 -81.737197) (xy 462.174318 -81.743297) (xy 462.118584 -81.74126)
			(xy 462.063741 -81.73113) (xy 462.010957 -81.713123) (xy 461.961357 -81.687622) (xy 461.915999 -81.655171)
			(xy 461.87585 -81.616462) (xy 461.841764 -81.572319) (xy 461.814468 -81.523684) (xy 461.794545 -81.471593)
			(xy 461.782419 -81.417156) (xy 461.778348 -81.361534) (xy 443.29223 -81.361534) (xy 454.043653 -92.112957)
			(xy 456.859523 -92.112957) (xy 456.859523 -92.058443) (xy 456.867282 -92.004484) (xy 456.882641 -91.952179)
			(xy 456.905288 -91.902592) (xy 456.934763 -91.856733) (xy 456.970464 -91.815535) (xy 457.011665 -91.779839)
			(xy 457.057527 -91.750369) (xy 457.107116 -91.727727) (xy 457.159423 -91.712373) (xy 457.213383 -91.70462)
			(xy 457.24064 -91.70416) (xy 457.266592 -91.704573) (xy 457.318016 -91.711626) (xy 457.36801 -91.725583)
			(xy 457.41565 -91.746187) (xy 457.460059 -91.773057) (xy 457.500417 -91.805697) (xy 457.518516 -91.824302)
			(xy 457.526644 -91.832938) (xy 457.54798 -91.841066) (xy 457.65085 -91.83243) (xy 457.670662 -91.821)
			(xy 457.677266 -91.811094) (xy 457.692505 -91.78903) (xy 457.728155 -91.748977) (xy 457.769065 -91.714313)
			(xy 457.814428 -91.685723) (xy 457.86335 -91.663771) (xy 457.914864 -91.648889) (xy 457.967956 -91.641372)
			(xy 457.994766 -91.640914) (xy 458.022022 -91.641331) (xy 458.07598 -91.649084) (xy 458.128285 -91.664438)
			(xy 458.177872 -91.68708) (xy 458.223732 -91.716549) (xy 458.264931 -91.752245) (xy 458.300631 -91.793441)
			(xy 458.330104 -91.839298) (xy 458.35275 -91.888883) (xy 458.368109 -91.941187) (xy 458.375867 -91.995144)
			(xy 458.375867 -92.049656) (xy 458.368109 -92.103613) (xy 458.35275 -92.155917) (xy 458.330104 -92.205502)
			(xy 458.300631 -92.251359) (xy 458.264931 -92.292555) (xy 458.223732 -92.328251) (xy 458.177872 -92.35772)
			(xy 458.128285 -92.380362) (xy 458.07598 -92.395716) (xy 458.022022 -92.403469) (xy 457.994766 -92.40393)
			(xy 457.968814 -92.403516) (xy 457.91739 -92.396464) (xy 457.867396 -92.382507) (xy 457.819755 -92.361904)
			(xy 457.775346 -92.335034) (xy 457.734989 -92.302393) (xy 457.71689 -92.283788) (xy 457.708762 -92.275152)
			(xy 457.687426 -92.267024) (xy 457.584556 -92.27566) (xy 457.564744 -92.28709) (xy 457.55814 -92.296996)
			(xy 457.542894 -92.319055) (xy 457.507246 -92.359109) (xy 457.466337 -92.393773) (xy 457.420975 -92.422364)
			(xy 457.372054 -92.444317) (xy 457.320541 -92.459199) (xy 457.26745 -92.466718) (xy 457.24064 -92.467176)
			(xy 457.213383 -92.46678) (xy 457.159423 -92.459027) (xy 457.107116 -92.443673) (xy 457.057527 -92.421031)
			(xy 457.011665 -92.391561) (xy 456.970464 -92.355865) (xy 456.934763 -92.314667) (xy 456.905288 -92.268809)
			(xy 456.882641 -92.219221) (xy 456.867282 -92.166916) (xy 456.859523 -92.112957) (xy 454.043653 -92.112957)
			(xy 455.239882 -93.309186) (xy 464.36991 -93.309186) (xy 464.373981 -93.253564) (xy 464.386107 -93.199127)
			(xy 464.40603 -93.147036) (xy 464.433326 -93.098401) (xy 464.467412 -93.054258) (xy 464.507561 -93.015549)
			(xy 464.552919 -92.983098) (xy 464.602519 -92.957597) (xy 464.655303 -92.93959) (xy 464.710146 -92.92946)
			(xy 464.76588 -92.927423) (xy 464.821317 -92.933523) (xy 464.875274 -92.947629) (xy 464.926603 -92.969441)
			(xy 464.974209 -92.998495) (xy 465.017077 -93.03417) (xy 465.054294 -93.075707) (xy 465.085067 -93.12222)
			(xy 465.108739 -93.172717) (xy 465.124807 -93.226124) (xy 465.132927 -93.2813) (xy 465.133436 -93.309186)
			(xy 465.132927 -93.337072) (xy 465.124807 -93.392248) (xy 465.108739 -93.445655) (xy 465.085067 -93.496152)
			(xy 465.054294 -93.542665) (xy 465.017077 -93.584202) (xy 464.974209 -93.619877) (xy 464.926603 -93.648931)
			(xy 464.875274 -93.670743) (xy 464.821317 -93.684849) (xy 464.76588 -93.690949) (xy 464.710146 -93.688912)
			(xy 464.655303 -93.678782) (xy 464.602519 -93.660775) (xy 464.552919 -93.635274) (xy 464.507561 -93.602823)
			(xy 464.467412 -93.564114) (xy 464.433326 -93.519971) (xy 464.40603 -93.471336) (xy 464.386107 -93.419245)
			(xy 464.373981 -93.364808) (xy 464.36991 -93.309186) (xy 455.239882 -93.309186) (xy 456.248262 -94.317566)
			(xy 464.36991 -94.317566) (xy 464.373981 -94.261944) (xy 464.386107 -94.207507) (xy 464.40603 -94.155416)
			(xy 464.433326 -94.106781) (xy 464.467412 -94.062638) (xy 464.507561 -94.023929) (xy 464.552919 -93.991478)
			(xy 464.602519 -93.965977) (xy 464.655303 -93.94797) (xy 464.710146 -93.93784) (xy 464.76588 -93.935803)
			(xy 464.821317 -93.941903) (xy 464.875274 -93.956009) (xy 464.926603 -93.977821) (xy 464.974209 -94.006875)
			(xy 465.017077 -94.04255) (xy 465.054294 -94.084087) (xy 465.085067 -94.1306) (xy 465.108739 -94.181097)
			(xy 465.124807 -94.234504) (xy 465.132927 -94.28968) (xy 465.133436 -94.317566) (xy 465.132927 -94.345452)
			(xy 465.124807 -94.400628) (xy 465.108739 -94.454035) (xy 465.085067 -94.504532) (xy 465.054294 -94.551045)
			(xy 465.017077 -94.592582) (xy 464.974209 -94.628257) (xy 464.926603 -94.657311) (xy 464.875274 -94.679123)
			(xy 464.821317 -94.693229) (xy 464.76588 -94.699329) (xy 464.710146 -94.697292) (xy 464.655303 -94.687162)
			(xy 464.602519 -94.669155) (xy 464.552919 -94.643654) (xy 464.507561 -94.611203) (xy 464.467412 -94.572494)
			(xy 464.433326 -94.528351) (xy 464.40603 -94.479716) (xy 464.386107 -94.427625) (xy 464.373981 -94.373188)
			(xy 464.36991 -94.317566) (xy 456.248262 -94.317566) (xy 456.883296 -94.9526) (xy 461.048855 -94.9526)
			(xy 461.052869 -94.888802) (xy 461.064847 -94.826009) (xy 461.0846 -94.765213) (xy 461.111818 -94.707372)
			(xy 461.146069 -94.653398) (xy 461.186815 -94.604143) (xy 461.233413 -94.560382) (xy 461.285128 -94.522807)
			(xy 461.341145 -94.49201) (xy 461.40058 -94.468475) (xy 461.462496 -94.452576) (xy 461.525916 -94.444561)
			(xy 461.557878 -94.444058) (xy 461.591437 -94.444566) (xy 461.657969 -94.453416) (xy 461.722759 -94.470939)
			(xy 461.784682 -94.49683) (xy 461.842663 -94.53064) (xy 461.895693 -94.571782) (xy 461.942852 -94.61954)
			(xy 461.963516 -94.645988) (xy 461.97012 -94.654624) (xy 461.9879 -94.664784) (xy 462.082896 -94.675198)
			(xy 462.102454 -94.669102) (xy 462.110582 -94.662244) (xy 462.13139 -94.645136) (xy 462.176882 -94.616288)
			(xy 462.225983 -94.594133) (xy 462.277714 -94.579112) (xy 462.331044 -94.571524) (xy 462.357978 -94.571058)
			(xy 462.385229 -94.571588) (xy 462.439178 -94.579341) (xy 462.491474 -94.594694) (xy 462.541052 -94.617333)
			(xy 462.586904 -94.646798) (xy 462.628096 -94.682489) (xy 462.663789 -94.723678) (xy 462.693256 -94.769528)
			(xy 462.715898 -94.819106) (xy 462.731254 -94.871401) (xy 462.739011 -94.925349) (xy 462.739011 -94.979851)
			(xy 462.731254 -95.033799) (xy 462.715898 -95.086094) (xy 462.693256 -95.135672) (xy 462.663789 -95.181522)
			(xy 462.628096 -95.222711) (xy 462.586904 -95.258402) (xy 462.541052 -95.287867) (xy 462.491474 -95.310506)
			(xy 462.439178 -95.325859) (xy 462.385229 -95.333612) (xy 462.357978 -95.334074) (xy 462.331045 -95.33358)
			(xy 462.277715 -95.325997) (xy 462.225983 -95.310985) (xy 462.176878 -95.288842) (xy 462.131378 -95.260009)
			(xy 462.110582 -95.242888) (xy 462.102454 -95.23603) (xy 462.082896 -95.229934) (xy 461.9879 -95.240348)
			(xy 461.97012 -95.250508) (xy 461.963516 -95.259144) (xy 461.942838 -95.285582) (xy 461.895691 -95.33335)
			(xy 461.842667 -95.374498) (xy 461.784688 -95.408309) (xy 461.722763 -95.434195) (xy 461.65797 -95.451706)
			(xy 461.591437 -95.460537) (xy 461.557878 -95.461074) (xy 461.525916 -95.460639) (xy 461.462496 -95.452624)
			(xy 461.40058 -95.436725) (xy 461.341145 -95.41319) (xy 461.285128 -95.382393) (xy 461.233413 -95.344818)
			(xy 461.186815 -95.301057) (xy 461.146069 -95.251802) (xy 461.111818 -95.197828) (xy 461.0846 -95.139987)
			(xy 461.064847 -95.079191) (xy 461.052869 -95.016398) (xy 461.048855 -94.9526) (xy 456.883296 -94.9526)
			(xy 457.9874 -96.056704) (xy 457.994246 -96.064103) (xy 458.001979 -96.082701) (xy 458.002386 -96.092772)
			(xy 458.002386 -96.406208) (xy 464.099908 -96.406208) (xy 464.103979 -96.350586) (xy 464.116105 -96.296149)
			(xy 464.136028 -96.244058) (xy 464.163324 -96.195423) (xy 464.19741 -96.15128) (xy 464.237559 -96.112571)
			(xy 464.282917 -96.08012) (xy 464.332517 -96.054619) (xy 464.385301 -96.036612) (xy 464.440144 -96.026482)
			(xy 464.495878 -96.024445) (xy 464.551315 -96.030545) (xy 464.605272 -96.044651) (xy 464.656601 -96.066463)
			(xy 464.704207 -96.095517) (xy 464.747075 -96.131192) (xy 464.784292 -96.172729) (xy 464.815065 -96.219242)
			(xy 464.838737 -96.269739) (xy 464.854805 -96.323146) (xy 464.862925 -96.378322) (xy 464.863434 -96.406208)
			(xy 464.862925 -96.434094) (xy 464.854805 -96.48927) (xy 464.838737 -96.542677) (xy 464.815065 -96.593174)
			(xy 464.784292 -96.639687) (xy 464.747075 -96.681224) (xy 464.704207 -96.716899) (xy 464.656601 -96.745953)
			(xy 464.605272 -96.767765) (xy 464.551315 -96.781871) (xy 464.495878 -96.787971) (xy 464.440144 -96.785934)
			(xy 464.385301 -96.775804) (xy 464.332517 -96.757797) (xy 464.282917 -96.732296) (xy 464.237559 -96.699845)
			(xy 464.19741 -96.661136) (xy 464.163324 -96.616993) (xy 464.136028 -96.568358) (xy 464.116105 -96.516267)
			(xy 464.103979 -96.46183) (xy 464.099908 -96.406208) (xy 458.002386 -96.406208) (xy 458.002386 -97.46361)
			(xy 458.023468 -97.490788) (xy 458.040232 -97.49536) (xy 458.067109 -97.502856) (xy 458.118484 -97.524627)
			(xy 458.166138 -97.553652) (xy 458.209053 -97.589312) (xy 458.246314 -97.630845) (xy 458.277124 -97.677365)
			(xy 458.300826 -97.727877) (xy 458.316914 -97.781305) (xy 458.325045 -97.836507) (xy 458.325044 -97.892304)
			(xy 458.316912 -97.947506) (xy 458.300822 -98.000933) (xy 458.277118 -98.051445) (xy 458.246307 -98.097964)
			(xy 458.209045 -98.139496) (xy 458.166129 -98.175154) (xy 458.118474 -98.204178) (xy 458.067099 -98.225947)
			(xy 458.040232 -98.233484) (xy 458.023468 -98.238056) (xy 458.002386 -98.265234) (xy 458.002386 -98.564954)
			(xy 462.064606 -98.564954) (xy 462.068677 -98.509332) (xy 462.080803 -98.454895) (xy 462.100726 -98.402804)
			(xy 462.128022 -98.354169) (xy 462.162108 -98.310026) (xy 462.202257 -98.271317) (xy 462.247615 -98.238866)
			(xy 462.297215 -98.213365) (xy 462.349999 -98.195358) (xy 462.404842 -98.185228) (xy 462.460576 -98.183191)
			(xy 462.516013 -98.189291) (xy 462.56997 -98.203397) (xy 462.621299 -98.225209) (xy 462.668905 -98.254263)
			(xy 462.711773 -98.289938) (xy 462.74899 -98.331475) (xy 462.779763 -98.377988) (xy 462.803435 -98.428485)
			(xy 462.819503 -98.481892) (xy 462.827623 -98.537068) (xy 462.828132 -98.564954) (xy 462.827623 -98.59284)
			(xy 462.819503 -98.648016) (xy 462.803435 -98.701423) (xy 462.779763 -98.75192) (xy 462.74899 -98.798433)
			(xy 462.711773 -98.83997) (xy 462.668905 -98.875645) (xy 462.621299 -98.904699) (xy 462.56997 -98.926511)
			(xy 462.516013 -98.940617) (xy 462.460576 -98.946717) (xy 462.404842 -98.94468) (xy 462.349999 -98.93455)
			(xy 462.297215 -98.916543) (xy 462.247615 -98.891042) (xy 462.202257 -98.858591) (xy 462.162108 -98.819882)
			(xy 462.128022 -98.775739) (xy 462.100726 -98.727104) (xy 462.080803 -98.675013) (xy 462.068677 -98.620576)
			(xy 462.064606 -98.564954) (xy 458.002386 -98.564954) (xy 458.002386 -101.1052) (xy 461.007497 -101.1052)
			(xy 461.011511 -101.041407) (xy 461.023488 -100.97862) (xy 461.043239 -100.917829) (xy 461.070454 -100.859993)
			(xy 461.104703 -100.806024) (xy 461.145445 -100.756772) (xy 461.192039 -100.713015) (xy 461.24375 -100.675443)
			(xy 461.299762 -100.644648) (xy 461.359191 -100.621116) (xy 461.421102 -100.605217) (xy 461.484516 -100.597203)
			(xy 461.516476 -100.5967) (xy 461.550034 -100.597232) (xy 461.616564 -100.606081) (xy 461.681353 -100.623601)
			(xy 461.743275 -100.649489) (xy 461.801256 -100.683295) (xy 461.854287 -100.724431) (xy 461.901449 -100.772184)
			(xy 461.922114 -100.79863) (xy 461.928718 -100.807266) (xy 461.946498 -100.817426) (xy 462.041494 -100.82784)
			(xy 462.061052 -100.821744) (xy 462.06918 -100.814886) (xy 462.089994 -100.797785) (xy 462.135484 -100.768935)
			(xy 462.184583 -100.746778) (xy 462.236313 -100.731755) (xy 462.289643 -100.724167) (xy 462.316576 -100.7237)
			(xy 462.343831 -100.724146) (xy 462.397785 -100.7319) (xy 462.450087 -100.747254) (xy 462.499671 -100.769896)
			(xy 462.545528 -100.799364) (xy 462.586725 -100.835058) (xy 462.622422 -100.876252) (xy 462.651893 -100.922108)
			(xy 462.674537 -100.97169) (xy 462.689895 -101.023991) (xy 462.697653 -101.077945) (xy 462.697653 -101.132455)
			(xy 462.689895 -101.186409) (xy 462.674537 -101.23871) (xy 462.651893 -101.288292) (xy 462.622422 -101.334148)
			(xy 462.586725 -101.375342) (xy 462.545528 -101.411036) (xy 462.499671 -101.440504) (xy 462.450087 -101.463146)
			(xy 462.397785 -101.4785) (xy 462.343831 -101.486254) (xy 462.316576 -101.486716) (xy 462.289642 -101.486237)
			(xy 462.236311 -101.478652) (xy 462.184578 -101.463637) (xy 462.135474 -101.441491) (xy 462.089975 -101.412654)
			(xy 462.06918 -101.39553) (xy 462.061052 -101.388672) (xy 462.041494 -101.382576) (xy 461.946498 -101.39299)
			(xy 461.928718 -101.40315) (xy 461.922114 -101.411786) (xy 461.901449 -101.438234) (xy 461.854298 -101.486)
			(xy 461.801271 -101.527146) (xy 461.74329 -101.560955) (xy 461.681364 -101.586839) (xy 461.61657 -101.604349)
			(xy 461.550035 -101.613179) (xy 461.516476 -101.613716) (xy 461.484516 -101.613197) (xy 461.421102 -101.605183)
			(xy 461.359191 -101.589284) (xy 461.299762 -101.565752) (xy 461.24375 -101.534957) (xy 461.192039 -101.497385)
			(xy 461.145445 -101.453628) (xy 461.104703 -101.404376) (xy 461.070454 -101.350407) (xy 461.043239 -101.292571)
			(xy 461.023488 -101.23178) (xy 461.011511 -101.168993) (xy 461.007497 -101.1052) (xy 458.002386 -101.1052)
			(xy 458.002386 -104.2497) (xy 460.811917 -104.2497) (xy 460.815931 -104.185908) (xy 460.827908 -104.123122)
			(xy 460.84766 -104.062332) (xy 460.874875 -104.004497) (xy 460.909124 -103.950529) (xy 460.949866 -103.901279)
			(xy 460.996461 -103.857524) (xy 461.048171 -103.819953) (xy 461.104183 -103.78916) (xy 461.163613 -103.76563)
			(xy 461.225523 -103.749734) (xy 461.288937 -103.741722) (xy 461.320896 -103.74122) (xy 461.354452 -103.741803)
			(xy 461.42098 -103.750642) (xy 461.485768 -103.768153) (xy 461.547691 -103.794032) (xy 461.605672 -103.82783)
			(xy 461.658705 -103.86896) (xy 461.705868 -103.916707) (xy 461.726534 -103.94315) (xy 461.733138 -103.951786)
			(xy 461.750918 -103.961946) (xy 461.845914 -103.97236) (xy 461.865472 -103.966264) (xy 461.8736 -103.959406)
			(xy 461.894397 -103.942283) (xy 461.939892 -103.913439) (xy 461.988996 -103.891287) (xy 462.040729 -103.87627)
			(xy 462.094062 -103.868685) (xy 462.120996 -103.86822) (xy 462.148251 -103.868627) (xy 462.202206 -103.876384)
			(xy 462.254509 -103.891741) (xy 462.304093 -103.914385) (xy 462.34995 -103.943855) (xy 462.391146 -103.979551)
			(xy 462.426843 -104.020747) (xy 462.456314 -104.066603) (xy 462.478958 -104.116188) (xy 462.494315 -104.16849)
			(xy 462.502073 -104.222445) (xy 462.502073 -104.276955) (xy 462.494315 -104.33091) (xy 462.478958 -104.383212)
			(xy 462.456314 -104.432797) (xy 462.426843 -104.478653) (xy 462.391146 -104.519849) (xy 462.34995 -104.555545)
			(xy 462.304093 -104.585015) (xy 462.254509 -104.607659) (xy 462.202206 -104.623016) (xy 462.148251 -104.630773)
			(xy 462.120996 -104.631236) (xy 462.094061 -104.630799) (xy 462.040728 -104.623203) (xy 461.988995 -104.608178)
			(xy 461.939891 -104.586023) (xy 461.894394 -104.557177) (xy 461.8736 -104.54005) (xy 461.865472 -104.533192)
			(xy 461.845914 -104.527096) (xy 461.750918 -104.53751) (xy 461.733138 -104.54767) (xy 461.726534 -104.556306)
			(xy 461.705894 -104.582774) (xy 461.658741 -104.630543) (xy 461.605711 -104.671689) (xy 461.547725 -104.705497)
			(xy 461.485794 -104.731378) (xy 461.420996 -104.748882) (xy 461.354457 -104.757703) (xy 461.320896 -104.758236)
			(xy 461.288937 -104.757678) (xy 461.225523 -104.749666) (xy 461.163613 -104.73377) (xy 461.104183 -104.71024)
			(xy 461.048171 -104.679447) (xy 460.996461 -104.641876) (xy 460.949866 -104.598121) (xy 460.909124 -104.548871)
			(xy 460.874875 -104.494903) (xy 460.84766 -104.437068) (xy 460.827908 -104.376278) (xy 460.815931 -104.313492)
			(xy 460.811917 -104.2497) (xy 458.002386 -104.2497) (xy 458.002386 -107.6787) (xy 460.684917 -107.6787)
			(xy 460.688931 -107.614908) (xy 460.700908 -107.552122) (xy 460.72066 -107.491332) (xy 460.747875 -107.433497)
			(xy 460.782124 -107.379529) (xy 460.822866 -107.330279) (xy 460.869461 -107.286524) (xy 460.921171 -107.248953)
			(xy 460.977183 -107.21816) (xy 461.036613 -107.19463) (xy 461.098523 -107.178734) (xy 461.161937 -107.170722)
			(xy 461.193896 -107.17022) (xy 461.227452 -107.170803) (xy 461.29398 -107.179642) (xy 461.358768 -107.197153)
			(xy 461.420691 -107.223032) (xy 461.478672 -107.25683) (xy 461.531705 -107.29796) (xy 461.578868 -107.345707)
			(xy 461.599534 -107.37215) (xy 461.606138 -107.380786) (xy 461.623918 -107.390946) (xy 461.718914 -107.40136)
			(xy 461.738472 -107.395264) (xy 461.7466 -107.388406) (xy 461.767397 -107.371283) (xy 461.812892 -107.342439)
			(xy 461.861996 -107.320287) (xy 461.913729 -107.30527) (xy 461.967062 -107.297685) (xy 461.993996 -107.29722)
			(xy 462.021251 -107.297627) (xy 462.075206 -107.305384) (xy 462.127509 -107.320741) (xy 462.177093 -107.343385)
			(xy 462.22295 -107.372855) (xy 462.264146 -107.408551) (xy 462.299843 -107.449747) (xy 462.329314 -107.495603)
			(xy 462.351958 -107.545188) (xy 462.367315 -107.59749) (xy 462.375073 -107.651445) (xy 462.375073 -107.705955)
			(xy 462.367315 -107.75991) (xy 462.351958 -107.812212) (xy 462.329314 -107.861797) (xy 462.299843 -107.907653)
			(xy 462.264146 -107.948849) (xy 462.246601 -107.964052) (xy 462.59087 -107.964052) (xy 462.59087 -107.909548)
			(xy 462.598626 -107.8556) (xy 462.613982 -107.803304) (xy 462.636623 -107.753726) (xy 462.666089 -107.707875)
			(xy 462.701781 -107.666684) (xy 462.742972 -107.630992) (xy 462.788823 -107.601525) (xy 462.838401 -107.578883)
			(xy 462.890696 -107.563527) (xy 462.944644 -107.55577) (xy 462.971896 -107.555284) (xy 462.998831 -107.555721)
			(xy 463.052164 -107.563316) (xy 463.103897 -107.578341) (xy 463.153001 -107.600497) (xy 463.198498 -107.629342)
			(xy 463.219292 -107.64647) (xy 463.22742 -107.653328) (xy 463.246978 -107.659424) (xy 463.341974 -107.64901)
			(xy 463.359754 -107.63885) (xy 463.366358 -107.630214) (xy 463.386981 -107.603732) (xy 463.434139 -107.555967)
			(xy 463.487174 -107.514824) (xy 463.545162 -107.481019) (xy 463.607095 -107.455141) (xy 463.671895 -107.437638)
			(xy 463.738435 -107.428817) (xy 463.771996 -107.428284) (xy 463.803958 -107.428781) (xy 463.867378 -107.436792)
			(xy 463.929294 -107.452689) (xy 463.988729 -107.476221) (xy 464.044746 -107.507016) (xy 464.096462 -107.544589)
			(xy 464.143061 -107.588348) (xy 464.183808 -107.637602) (xy 464.21806 -107.691575) (xy 464.245278 -107.749415)
			(xy 464.265031 -107.81021) (xy 464.27701 -107.873002) (xy 464.281024 -107.9368) (xy 464.27701 -108.000598)
			(xy 464.265031 -108.06339) (xy 464.245278 -108.124185) (xy 464.21806 -108.182025) (xy 464.183808 -108.235998)
			(xy 464.143061 -108.285252) (xy 464.096462 -108.329011) (xy 464.044746 -108.366584) (xy 463.988729 -108.397379)
			(xy 463.929294 -108.420911) (xy 463.867378 -108.436808) (xy 463.803958 -108.444819) (xy 463.771996 -108.4453)
			(xy 463.73844 -108.444715) (xy 463.671912 -108.435875) (xy 463.607124 -108.418364) (xy 463.545202 -108.392485)
			(xy 463.487221 -108.358687) (xy 463.434188 -108.317558) (xy 463.387025 -108.269812) (xy 463.366358 -108.24337)
			(xy 463.359754 -108.234734) (xy 463.341974 -108.224574) (xy 463.246978 -108.21416) (xy 463.22742 -108.220256)
			(xy 463.219292 -108.227114) (xy 463.198488 -108.244228) (xy 463.152996 -108.273076) (xy 463.103894 -108.295231)
			(xy 463.052162 -108.31025) (xy 462.99883 -108.317835) (xy 462.971896 -108.3183) (xy 462.944644 -108.31783)
			(xy 462.890696 -108.310073) (xy 462.838401 -108.294717) (xy 462.788823 -108.272075) (xy 462.742972 -108.242608)
			(xy 462.701781 -108.206916) (xy 462.666089 -108.165725) (xy 462.636623 -108.119874) (xy 462.613982 -108.070296)
			(xy 462.598626 -108.018) (xy 462.59087 -107.964052) (xy 462.246601 -107.964052) (xy 462.22295 -107.984545)
			(xy 462.177093 -108.014015) (xy 462.127509 -108.036659) (xy 462.075206 -108.052016) (xy 462.021251 -108.059773)
			(xy 461.993996 -108.060236) (xy 461.967061 -108.059799) (xy 461.913728 -108.052203) (xy 461.861995 -108.037178)
			(xy 461.812891 -108.015023) (xy 461.767394 -107.986177) (xy 461.7466 -107.96905) (xy 461.738472 -107.962192)
			(xy 461.718914 -107.956096) (xy 461.623918 -107.96651) (xy 461.606138 -107.97667) (xy 461.599534 -107.985306)
			(xy 461.578894 -108.011774) (xy 461.531741 -108.059543) (xy 461.478711 -108.100689) (xy 461.420725 -108.134497)
			(xy 461.358794 -108.160378) (xy 461.293996 -108.177882) (xy 461.227457 -108.186703) (xy 461.193896 -108.187236)
			(xy 461.161937 -108.186678) (xy 461.098523 -108.178666) (xy 461.036613 -108.16277) (xy 460.977183 -108.13924)
			(xy 460.921171 -108.108447) (xy 460.869461 -108.070876) (xy 460.822866 -108.027121) (xy 460.782124 -107.977871)
			(xy 460.747875 -107.923903) (xy 460.72066 -107.866068) (xy 460.700908 -107.805278) (xy 460.688931 -107.742492)
			(xy 460.684917 -107.6787) (xy 458.002386 -107.6787) (xy 458.002386 -109.678173) (xy 463.926676 -109.678173)
			(xy 463.926676 -109.614251) (xy 463.934687 -109.550833) (xy 463.950584 -109.488919) (xy 463.974116 -109.429486)
			(xy 464.00491 -109.373471) (xy 464.042483 -109.321756) (xy 464.08624 -109.275159) (xy 464.135493 -109.234414)
			(xy 464.189464 -109.200163) (xy 464.247303 -109.172946) (xy 464.308096 -109.153193) (xy 464.370886 -109.141215)
			(xy 464.434682 -109.137202) (xy 464.498478 -109.141215) (xy 464.561268 -109.153193) (xy 464.622061 -109.172946)
			(xy 464.6799 -109.200163) (xy 464.733871 -109.234414) (xy 464.783124 -109.275159) (xy 464.826881 -109.321756)
			(xy 464.864454 -109.373471) (xy 464.895248 -109.429486) (xy 464.91878 -109.488919) (xy 464.934677 -109.550833)
			(xy 464.942688 -109.614251) (xy 464.94319 -109.646212) (xy 464.942688 -109.678173) (xy 464.934677 -109.741591)
			(xy 464.91878 -109.803505) (xy 464.895248 -109.862938) (xy 464.864454 -109.918953) (xy 464.826881 -109.970668)
			(xy 464.783124 -110.017265) (xy 464.733871 -110.05801) (xy 464.6799 -110.092261) (xy 464.622061 -110.119478)
			(xy 464.561268 -110.139231) (xy 464.498478 -110.151209) (xy 464.434682 -110.155223) (xy 464.370886 -110.151209)
			(xy 464.308096 -110.139231) (xy 464.247303 -110.119478) (xy 464.189464 -110.092261) (xy 464.135493 -110.05801)
			(xy 464.08624 -110.017265) (xy 464.042483 -109.970668) (xy 464.00491 -109.918953) (xy 463.974116 -109.862938)
			(xy 463.950584 -109.803505) (xy 463.934687 -109.741591) (xy 463.926676 -109.678173) (xy 458.002386 -109.678173)
			(xy 458.002386 -110.534958) (xy 458.001952 -110.545023) (xy 457.994221 -110.563611) (xy 457.9874 -110.571026)
			(xy 457.757276 -110.80115) (xy 462.506058 -110.80115) (xy 462.510129 -110.745528) (xy 462.522255 -110.691091)
			(xy 462.542178 -110.639) (xy 462.569474 -110.590365) (xy 462.60356 -110.546222) (xy 462.643709 -110.507513)
			(xy 462.689067 -110.475062) (xy 462.738667 -110.449561) (xy 462.791451 -110.431554) (xy 462.846294 -110.421424)
			(xy 462.902028 -110.419387) (xy 462.957465 -110.425487) (xy 463.011422 -110.439593) (xy 463.062751 -110.461405)
			(xy 463.110357 -110.490459) (xy 463.153225 -110.526134) (xy 463.190442 -110.567671) (xy 463.221215 -110.614184)
			(xy 463.244887 -110.664681) (xy 463.260955 -110.718088) (xy 463.269075 -110.773264) (xy 463.269584 -110.80115)
			(xy 463.269075 -110.829036) (xy 463.260955 -110.884212) (xy 463.244887 -110.937619) (xy 463.221215 -110.988116)
			(xy 463.190442 -111.034629) (xy 463.153225 -111.076166) (xy 463.110357 -111.111841) (xy 463.062751 -111.140895)
			(xy 463.011422 -111.162707) (xy 462.957465 -111.176813) (xy 462.902028 -111.182913) (xy 462.846294 -111.180876)
			(xy 462.791451 -111.170746) (xy 462.738667 -111.152739) (xy 462.689067 -111.127238) (xy 462.643709 -111.094787)
			(xy 462.60356 -111.056078) (xy 462.569474 -111.011935) (xy 462.542178 -110.9633) (xy 462.522255 -110.911209)
			(xy 462.510129 -110.856772) (xy 462.506058 -110.80115) (xy 457.757276 -110.80115) (xy 439.544968 -129.013458)
			(xy 446.500248 -129.013458) (xy 446.504319 -128.957836) (xy 446.516445 -128.903399) (xy 446.536368 -128.851308)
			(xy 446.563664 -128.802673) (xy 446.59775 -128.75853) (xy 446.637899 -128.719821) (xy 446.683257 -128.68737)
			(xy 446.732857 -128.661869) (xy 446.785641 -128.643862) (xy 446.840484 -128.633732) (xy 446.896218 -128.631695)
			(xy 446.951655 -128.637795) (xy 447.005612 -128.651901) (xy 447.056941 -128.673713) (xy 447.104547 -128.702767)
			(xy 447.147415 -128.738442) (xy 447.184632 -128.779979) (xy 447.215405 -128.826492) (xy 447.239077 -128.876989)
			(xy 447.255145 -128.930396) (xy 447.263265 -128.985572) (xy 447.263774 -129.013458) (xy 447.263265 -129.041344)
			(xy 447.255145 -129.09652) (xy 447.239077 -129.149927) (xy 447.215405 -129.200424) (xy 447.184632 -129.246937)
			(xy 447.147415 -129.288474) (xy 447.104547 -129.324149) (xy 447.056941 -129.353203) (xy 447.005612 -129.375015)
			(xy 446.951655 -129.389121) (xy 446.896218 -129.395221) (xy 446.840484 -129.393184) (xy 446.785641 -129.383054)
			(xy 446.732857 -129.365047) (xy 446.683257 -129.339546) (xy 446.637899 -129.307095) (xy 446.59775 -129.268386)
			(xy 446.563664 -129.224243) (xy 446.536368 -129.175608) (xy 446.516445 -129.123517) (xy 446.504319 -129.06908)
			(xy 446.500248 -129.013458) (xy 439.544968 -129.013458) (xy 438.264554 -130.293872) (xy 445.023746 -130.293872)
			(xy 445.027817 -130.23825) (xy 445.039943 -130.183813) (xy 445.059866 -130.131722) (xy 445.087162 -130.083087)
			(xy 445.121248 -130.038944) (xy 445.161397 -130.000235) (xy 445.206755 -129.967784) (xy 445.256355 -129.942283)
			(xy 445.309139 -129.924276) (xy 445.363982 -129.914146) (xy 445.419716 -129.912109) (xy 445.475153 -129.918209)
			(xy 445.52911 -129.932315) (xy 445.580439 -129.954127) (xy 445.628045 -129.983181) (xy 445.670913 -130.018856)
			(xy 445.70813 -130.060393) (xy 445.738903 -130.106906) (xy 445.762575 -130.157403) (xy 445.778643 -130.21081)
			(xy 445.786763 -130.265986) (xy 445.787272 -130.293872) (xy 445.786763 -130.321758) (xy 445.778643 -130.376934)
			(xy 445.762575 -130.430341) (xy 445.738903 -130.480838) (xy 445.70813 -130.527351) (xy 445.670913 -130.568888)
			(xy 445.628045 -130.604563) (xy 445.580439 -130.633617) (xy 445.52911 -130.655429) (xy 445.475153 -130.669535)
			(xy 445.419716 -130.675635) (xy 445.363982 -130.673598) (xy 445.309139 -130.663468) (xy 445.256355 -130.645461)
			(xy 445.206755 -130.61996) (xy 445.161397 -130.587509) (xy 445.121248 -130.5488) (xy 445.087162 -130.504657)
			(xy 445.059866 -130.456022) (xy 445.039943 -130.403931) (xy 445.027817 -130.349494) (xy 445.023746 -130.293872)
			(xy 438.264554 -130.293872) (xy 435.932326 -132.6261) (xy 435.925477 -132.633497) (xy 435.917738 -132.652096)
			(xy 435.91734 -132.662168) (xy 435.91734 -141.387654) (xy 448.701353 -141.387654) (xy 448.701353 -141.333146)
			(xy 448.709111 -141.279194) (xy 448.724468 -141.226895) (xy 448.747111 -141.177313) (xy 448.776581 -141.131459)
			(xy 448.812276 -141.090266) (xy 448.853471 -141.054572) (xy 448.899326 -141.025104) (xy 448.948908 -141.002463)
			(xy 449.001208 -140.987108) (xy 449.05516 -140.979352) (xy 449.082414 -140.97889) (xy 449.108819 -140.979364)
			(xy 449.161122 -140.986662) (xy 449.211918 -141.001102) (xy 449.260239 -141.022409) (xy 449.30516 -141.050175)
			(xy 449.345823 -141.083871) (xy 449.381451 -141.122851) (xy 449.411363 -141.166373) (xy 449.434988 -141.213603)
			(xy 449.443856 -141.238478) (xy 449.448174 -141.251432) (xy 449.467986 -141.268958) (xy 449.58 -141.293088)
			(xy 449.6054 -141.285214) (xy 449.614544 -141.275054) (xy 449.632666 -141.256217) (xy 449.673157 -141.223163)
			(xy 449.717782 -141.195946) (xy 449.765705 -141.175076) (xy 449.816028 -141.160944) (xy 449.867809 -141.153814)
			(xy 449.893944 -141.153388) (xy 449.923219 -141.153957) (xy 449.981081 -141.162915) (xy 450.036893 -141.180613)
			(xy 450.089344 -141.206635) (xy 450.1372 -141.24037) (xy 450.179336 -141.281024) (xy 450.197474 -141.30401)
			(xy 450.203824 -141.312138) (xy 450.221858 -141.322298) (xy 450.31533 -141.33322) (xy 450.335142 -141.327378)
			(xy 450.34327 -141.32052) (xy 450.363907 -141.304056) (xy 450.408823 -141.276316) (xy 450.457135 -141.255033)
			(xy 450.507919 -141.240615) (xy 450.560206 -141.233337) (xy 450.586602 -141.23289) (xy 450.613853 -141.23338)
			(xy 450.6678 -141.241137) (xy 450.720094 -141.256492) (xy 450.769671 -141.279133) (xy 450.815521 -141.308599)
			(xy 450.856711 -141.344291) (xy 450.892402 -141.38548) (xy 450.921868 -141.431331) (xy 450.944509 -141.480907)
			(xy 450.959864 -141.533202) (xy 450.96762 -141.587149) (xy 450.96762 -141.641651) (xy 450.959864 -141.695598)
			(xy 450.944509 -141.747893) (xy 450.921868 -141.797469) (xy 450.911052 -141.8143) (xy 451.452464 -141.8143)
			(xy 451.456478 -141.750501) (xy 451.468457 -141.687707) (xy 451.488211 -141.626911) (xy 451.515429 -141.569069)
			(xy 451.549683 -141.515095) (xy 451.59043 -141.46584) (xy 451.63703 -141.42208) (xy 451.688747 -141.384506)
			(xy 451.744766 -141.35371) (xy 451.804202 -141.330177) (xy 451.86612 -141.31428) (xy 451.929541 -141.306269)
			(xy 451.961504 -141.305788) (xy 451.99172 -141.306224) (xy 452.051722 -141.313412) (xy 452.110449 -141.327662)
			(xy 452.167073 -141.348773) (xy 452.220795 -141.376448) (xy 452.270858 -141.410296) (xy 452.29399 -141.42974)
			(xy 452.301127 -141.435366) (xy 452.318181 -141.441609) (xy 452.327264 -141.441932) (xy 452.357744 -141.441932)
			(xy 452.366825 -141.4416) (xy 452.383875 -141.435356) (xy 452.391018 -141.42974) (xy 452.414164 -141.410314)
			(xy 452.464227 -141.376472) (xy 452.517947 -141.348799) (xy 452.574568 -141.327687) (xy 452.633291 -141.313433)
			(xy 452.69329 -141.306238) (xy 452.723504 -141.305788) (xy 452.75372 -141.306224) (xy 452.813722 -141.313412)
			(xy 452.872449 -141.327662) (xy 452.929073 -141.348773) (xy 452.982795 -141.376448) (xy 453.032858 -141.410296)
			(xy 453.05599 -141.42974) (xy 453.063127 -141.435366) (xy 453.080181 -141.441609) (xy 453.089264 -141.441932)
			(xy 453.119744 -141.441932) (xy 453.128825 -141.4416) (xy 453.145875 -141.435356) (xy 453.153018 -141.42974)
			(xy 453.176164 -141.410314) (xy 453.226227 -141.376472) (xy 453.279947 -141.348799) (xy 453.336568 -141.327687)
			(xy 453.395291 -141.313433) (xy 453.45529 -141.306238) (xy 453.485504 -141.305788) (xy 453.51572 -141.306224)
			(xy 453.575722 -141.313412) (xy 453.634449 -141.327662) (xy 453.691073 -141.348773) (xy 453.744795 -141.376448)
			(xy 453.794858 -141.410296) (xy 453.81799 -141.42974) (xy 453.825127 -141.435366) (xy 453.842181 -141.441609)
			(xy 453.851264 -141.441932) (xy 453.881744 -141.441932) (xy 453.890825 -141.4416) (xy 453.907875 -141.435356)
			(xy 453.915018 -141.42974) (xy 453.938164 -141.410314) (xy 453.988227 -141.376472) (xy 454.041947 -141.348799)
			(xy 454.098568 -141.327687) (xy 454.157291 -141.313433) (xy 454.21729 -141.306238) (xy 454.247504 -141.305788)
			(xy 454.279465 -141.306298) (xy 454.342882 -141.31431) (xy 454.404795 -141.330207) (xy 454.464227 -141.353738)
			(xy 454.520241 -141.384533) (xy 454.571955 -141.422105) (xy 454.618551 -141.465862) (xy 454.659296 -141.515115)
			(xy 454.693546 -141.569085) (xy 454.720763 -141.626923) (xy 454.740515 -141.687716) (xy 454.752493 -141.750505)
			(xy 454.756507 -141.8143) (xy 454.752493 -141.878095) (xy 454.740515 -141.940884) (xy 454.720763 -142.001677)
			(xy 454.693546 -142.059515) (xy 454.659296 -142.113485) (xy 454.618551 -142.162738) (xy 454.571955 -142.206495)
			(xy 454.520241 -142.244067) (xy 454.464227 -142.274862) (xy 454.404795 -142.298393) (xy 454.342882 -142.31429)
			(xy 454.279465 -142.322302) (xy 454.247504 -142.322804) (xy 454.217289 -142.322365) (xy 454.157286 -142.315178)
			(xy 454.098559 -142.300929) (xy 454.041935 -142.279818) (xy 453.988213 -142.252144) (xy 453.93815 -142.218296)
			(xy 453.915018 -142.198852) (xy 453.90788 -142.193228) (xy 453.890826 -142.186984) (xy 453.881744 -142.18666)
			(xy 453.851264 -142.18666) (xy 453.842184 -142.186997) (xy 453.825133 -142.193237) (xy 453.81799 -142.198852)
			(xy 453.794853 -142.218289) (xy 453.744787 -142.252127) (xy 453.691064 -142.279796) (xy 453.634442 -142.300906)
			(xy 453.575718 -142.315159) (xy 453.515718 -142.322354) (xy 453.485504 -142.322804) (xy 453.455289 -142.322365)
			(xy 453.395286 -142.315178) (xy 453.336559 -142.300929) (xy 453.279935 -142.279818) (xy 453.226213 -142.252144)
			(xy 453.17615 -142.218296) (xy 453.153018 -142.198852) (xy 453.14588 -142.193228) (xy 453.128826 -142.186984)
			(xy 453.119744 -142.18666) (xy 453.089264 -142.18666) (xy 453.080184 -142.186997) (xy 453.063133 -142.193237)
			(xy 453.05599 -142.198852) (xy 453.032853 -142.218289) (xy 452.982787 -142.252127) (xy 452.929064 -142.279796)
			(xy 452.872442 -142.300906) (xy 452.813718 -142.315159) (xy 452.753718 -142.322354) (xy 452.723504 -142.322804)
			(xy 452.693289 -142.322365) (xy 452.633286 -142.315178) (xy 452.574559 -142.300929) (xy 452.517935 -142.279818)
			(xy 452.464213 -142.252144) (xy 452.41415 -142.218296) (xy 452.391018 -142.198852) (xy 452.38388 -142.193228)
			(xy 452.366826 -142.186984) (xy 452.357744 -142.18666) (xy 452.327264 -142.18666) (xy 452.318184 -142.186997)
			(xy 452.301133 -142.193237) (xy 452.29399 -142.198852) (xy 452.270853 -142.218289) (xy 452.220787 -142.252127)
			(xy 452.167064 -142.279796) (xy 452.110442 -142.300906) (xy 452.051718 -142.315159) (xy 451.991718 -142.322354)
			(xy 451.961504 -142.322804) (xy 451.929541 -142.322331) (xy 451.86612 -142.31432) (xy 451.804202 -142.298423)
			(xy 451.744766 -142.27489) (xy 451.688747 -142.244094) (xy 451.63703 -142.20652) (xy 451.59043 -142.16276)
			(xy 451.549683 -142.113505) (xy 451.515429 -142.059531) (xy 451.488211 -142.001689) (xy 451.468457 -141.940893)
			(xy 451.456478 -141.878099) (xy 451.452464 -141.8143) (xy 450.911052 -141.8143) (xy 450.892402 -141.84332)
			(xy 450.856711 -141.884509) (xy 450.815521 -141.920201) (xy 450.769671 -141.949667) (xy 450.720094 -141.972308)
			(xy 450.6678 -141.987663) (xy 450.613853 -141.99542) (xy 450.586602 -141.995906) (xy 450.557325 -141.995378)
			(xy 450.499461 -141.986412) (xy 450.443648 -141.968706) (xy 450.391198 -141.942676) (xy 450.343343 -141.908934)
			(xy 450.301209 -141.868273) (xy 450.283072 -141.845284) (xy 450.276722 -141.837156) (xy 450.258688 -141.826996)
			(xy 450.165216 -141.816074) (xy 450.145404 -141.821916) (xy 450.137276 -141.828774) (xy 450.116669 -141.845277)
			(xy 450.071743 -141.873008) (xy 450.023424 -141.894281) (xy 449.972634 -141.908691) (xy 449.920342 -141.915961)
			(xy 449.893944 -141.916404) (xy 449.867538 -141.915971) (xy 449.815233 -141.908668) (xy 449.764435 -141.894222)
			(xy 449.716114 -141.872909) (xy 449.671193 -141.845138) (xy 449.630531 -141.811437) (xy 449.594904 -141.772452)
			(xy 449.564993 -141.728927) (xy 449.541369 -141.681693) (xy 449.532502 -141.656816) (xy 449.528184 -141.643862)
			(xy 449.508372 -141.626336) (xy 449.396358 -141.602206) (xy 449.370958 -141.61008) (xy 449.361814 -141.62024)
			(xy 449.343711 -141.639096) (xy 449.303216 -141.672149) (xy 449.258587 -141.699363) (xy 449.210661 -141.72023)
			(xy 449.160334 -141.734358) (xy 449.10855 -141.741483) (xy 449.082414 -141.741906) (xy 449.05516 -141.741448)
			(xy 449.001208 -141.733692) (xy 448.948908 -141.718337) (xy 448.899326 -141.695696) (xy 448.853471 -141.666228)
			(xy 448.812276 -141.630534) (xy 448.776581 -141.589341) (xy 448.747111 -141.543487) (xy 448.724468 -141.493905)
			(xy 448.709111 -141.441606) (xy 448.701353 -141.387654) (xy 435.91734 -141.387654) (xy 435.91734 -143.5499)
			(xy 462.043446 -143.5499) (xy 462.047461 -143.486095) (xy 462.059441 -143.423297) (xy 462.079198 -143.362496)
			(xy 462.106419 -143.30465) (xy 462.140677 -143.250672) (xy 462.18143 -143.201414) (xy 462.228035 -143.157653)
			(xy 462.279758 -143.120077) (xy 462.335783 -143.089282) (xy 462.395226 -143.065751) (xy 462.457149 -143.049856)
			(xy 462.520577 -143.041848) (xy 462.552542 -143.04137) (xy 462.582757 -143.041823) (xy 462.64276 -143.049005)
			(xy 462.701487 -143.06325) (xy 462.758112 -143.084358) (xy 462.811834 -143.112031) (xy 462.861896 -143.145878)
			(xy 462.885028 -143.165322) (xy 462.892155 -143.170962) (xy 462.909217 -143.177197) (xy 462.918302 -143.177514)
			(xy 462.948782 -143.177514) (xy 462.957865 -143.177205) (xy 462.974916 -143.170946) (xy 462.982056 -143.165322)
			(xy 463.005185 -143.145876) (xy 463.055252 -143.112036) (xy 463.108976 -143.084367) (xy 463.1656 -143.063259)
			(xy 463.224326 -143.049009) (xy 463.284327 -143.041818) (xy 463.314542 -143.04137) (xy 463.344757 -143.041823)
			(xy 463.40476 -143.049005) (xy 463.463487 -143.06325) (xy 463.520112 -143.084358) (xy 463.573834 -143.112031)
			(xy 463.623896 -143.145878) (xy 463.647028 -143.165322) (xy 463.654155 -143.170962) (xy 463.671217 -143.177197)
			(xy 463.680302 -143.177514) (xy 463.710782 -143.177514) (xy 463.719865 -143.177205) (xy 463.736916 -143.170946)
			(xy 463.744056 -143.165322) (xy 463.767185 -143.145876) (xy 463.817252 -143.112036) (xy 463.870976 -143.084367)
			(xy 463.9276 -143.063259) (xy 463.986326 -143.049009) (xy 464.046327 -143.041818) (xy 464.076542 -143.04137)
			(xy 464.1085 -143.041918) (xy 464.171911 -143.049934) (xy 464.233818 -143.065834) (xy 464.293244 -143.089366)
			(xy 464.349252 -143.120161) (xy 464.40096 -143.157733) (xy 464.44755 -143.201488) (xy 464.48829 -143.250738)
			(xy 464.522537 -143.304705) (xy 464.549749 -143.362538) (xy 464.569499 -143.423326) (xy 464.581475 -143.48611)
			(xy 464.585489 -143.5499) (xy 464.581475 -143.61369) (xy 464.569499 -143.676474) (xy 464.549749 -143.737262)
			(xy 464.522537 -143.795095) (xy 464.48829 -143.849062) (xy 464.44755 -143.898312) (xy 464.40096 -143.942067)
			(xy 464.349252 -143.979639) (xy 464.293244 -144.010434) (xy 464.233818 -144.033966) (xy 464.171911 -144.049866)
			(xy 464.1085 -144.057882) (xy 464.076542 -144.058386) (xy 464.046327 -144.057929) (xy 463.986325 -144.050746)
			(xy 463.927598 -144.0365) (xy 463.870974 -144.015393) (xy 463.817252 -143.987722) (xy 463.767188 -143.953877)
			(xy 463.744056 -143.934434) (xy 463.736908 -143.928824) (xy 463.719862 -143.922572) (xy 463.710782 -143.922242)
			(xy 463.680302 -143.922242) (xy 463.671222 -143.92258) (xy 463.65417 -143.928817) (xy 463.647028 -143.934434)
			(xy 463.623912 -143.953897) (xy 463.573841 -143.987733) (xy 463.520114 -144.015399) (xy 463.463488 -144.036504)
			(xy 463.40476 -144.050751) (xy 463.344758 -144.057939) (xy 463.314542 -144.058386) (xy 463.284327 -144.057929)
			(xy 463.224325 -144.050746) (xy 463.165598 -144.0365) (xy 463.108974 -144.015393) (xy 463.055252 -143.987722)
			(xy 463.005188 -143.953877) (xy 462.982056 -143.934434) (xy 462.974908 -143.928824) (xy 462.957862 -143.922572)
			(xy 462.948782 -143.922242) (xy 462.918302 -143.922242) (xy 462.909222 -143.92258) (xy 462.89217 -143.928817)
			(xy 462.885028 -143.934434) (xy 462.861912 -143.953897) (xy 462.811841 -143.987733) (xy 462.758114 -144.015399)
			(xy 462.701488 -144.036504) (xy 462.64276 -144.050751) (xy 462.582758 -144.057939) (xy 462.552542 -144.058386)
			(xy 462.520577 -144.057952) (xy 462.457149 -144.049944) (xy 462.395226 -144.034049) (xy 462.335783 -144.010518)
			(xy 462.279758 -143.979723) (xy 462.228035 -143.942147) (xy 462.18143 -143.898386) (xy 462.140677 -143.849128)
			(xy 462.106419 -143.79515) (xy 462.079198 -143.737304) (xy 462.059441 -143.676503) (xy 462.047461 -143.613705)
			(xy 462.043446 -143.5499) (xy 435.91734 -143.5499) (xy 435.91734 -153.774394) (xy 436.382169 -153.774394)
			(xy 436.386165 -153.564508) (xy 436.39815 -153.354926) (xy 436.418104 -153.145952) (xy 436.446 -152.93789)
			(xy 436.481797 -152.73104) (xy 436.525442 -152.525703) (xy 436.576874 -152.322177) (xy 436.636016 -152.120756)
			(xy 436.702784 -151.921733) (xy 436.77708 -151.725396) (xy 436.858798 -151.53203) (xy 436.947817 -151.341915)
			(xy 437.04401 -151.155327) (xy 437.147237 -150.972536) (xy 437.257348 -150.793808) (xy 437.374183 -150.619401)
			(xy 437.497573 -150.449569) (xy 437.62734 -150.284557) (xy 437.763294 -150.124606) (xy 437.90524 -149.969946)
			(xy 438.05297 -149.820802) (xy 438.206272 -149.677391) (xy 438.364922 -149.53992) (xy 438.528691 -149.408588)
			(xy 438.697341 -149.283587) (xy 438.870627 -149.165096) (xy 439.048299 -149.053289) (xy 439.230099 -148.948327)
			(xy 439.415763 -148.850362) (xy 439.605021 -148.759537) (xy 439.797601 -148.675983) (xy 439.993222 -148.59982)
			(xy 440.1916 -148.531161) (xy 440.392449 -148.470104) (xy 440.595476 -148.416737) (xy 440.800389 -148.371139)
			(xy 441.006888 -148.333374) (xy 441.214675 -148.303499) (xy 441.42345 -148.281556) (xy 441.632908 -148.267577)
			(xy 441.842747 -148.261582) (xy 442.052661 -148.263581) (xy 442.262348 -148.273569) (xy 442.471502 -148.291534)
			(xy 442.67982 -148.317448) (xy 442.887001 -148.351273) (xy 443.092745 -148.392962) (xy 443.296751 -148.442454)
			(xy 443.498726 -148.499676) (xy 443.698376 -148.564546) (xy 443.895411 -148.63697) (xy 444.089547 -148.716843)
			(xy 444.2805 -148.804049) (xy 444.467996 -148.898461) (xy 444.651761 -148.999943) (xy 444.831529 -149.108347)
			(xy 445.00704 -149.223517) (xy 445.178039 -149.345285) (xy 445.344279 -149.473474) (xy 445.505518 -149.6079)
			(xy 445.661522 -149.748367) (xy 445.812065 -149.894671) (xy 445.956929 -150.0466) (xy 446.095904 -150.203934)
			(xy 446.228789 -150.366445) (xy 446.35539 -150.533898) (xy 446.475525 -150.706048) (xy 446.589019 -150.882648)
			(xy 446.695707 -151.06344) (xy 446.795434 -151.248163) (xy 446.888057 -151.436549) (xy 446.973441 -151.628324)
			(xy 447.051462 -151.823211) (xy 447.122007 -152.020927) (xy 447.184974 -152.221185) (xy 447.240271 -152.423695)
			(xy 447.287818 -152.628164) (xy 447.327546 -152.834295) (xy 447.359398 -153.041788) (xy 447.383328 -153.250344)
			(xy 447.3993 -153.45966) (xy 447.407292 -153.669432) (xy 447.407792 -153.774394) (xy 447.407292 -153.879356)
			(xy 447.3993 -154.089128) (xy 447.383328 -154.298444) (xy 447.359398 -154.507) (xy 447.327546 -154.714493)
			(xy 447.287818 -154.920624) (xy 447.240271 -155.125093) (xy 447.184974 -155.327603) (xy 447.122007 -155.527861)
			(xy 447.051462 -155.725577) (xy 446.973441 -155.920464) (xy 446.888057 -156.112239) (xy 446.795434 -156.300625)
			(xy 446.695707 -156.485348) (xy 446.589019 -156.66614) (xy 446.475525 -156.84274) (xy 446.35539 -157.01489)
			(xy 446.228789 -157.182343) (xy 446.095904 -157.344854) (xy 445.956929 -157.502188) (xy 445.812065 -157.654117)
			(xy 445.661522 -157.800421) (xy 445.505518 -157.940888) (xy 445.344279 -158.075314) (xy 445.178039 -158.203503)
			(xy 445.00704 -158.325271) (xy 444.831529 -158.440441) (xy 444.651761 -158.548845) (xy 444.467996 -158.650327)
			(xy 444.2805 -158.744739) (xy 444.089547 -158.831945) (xy 443.895411 -158.911818) (xy 443.698376 -158.984242)
			(xy 443.498726 -159.049112) (xy 443.296751 -159.106334) (xy 443.092745 -159.155826) (xy 442.887001 -159.197515)
			(xy 442.67982 -159.23134) (xy 442.471502 -159.257254) (xy 442.262348 -159.275219) (xy 442.052661 -159.285207)
			(xy 441.842747 -159.287206) (xy 441.632908 -159.281211) (xy 441.42345 -159.267232) (xy 441.214675 -159.245289)
			(xy 441.006888 -159.215414) (xy 440.800389 -159.177649) (xy 440.595476 -159.132051) (xy 440.392449 -159.078684)
			(xy 440.1916 -159.017627) (xy 439.993222 -158.948968) (xy 439.797601 -158.872805) (xy 439.605021 -158.789251)
			(xy 439.415763 -158.698426) (xy 439.230099 -158.600461) (xy 439.048299 -158.495499) (xy 438.870627 -158.383692)
			(xy 438.697341 -158.265201) (xy 438.528691 -158.1402) (xy 438.364922 -158.008868) (xy 438.206272 -157.871397)
			(xy 438.05297 -157.727986) (xy 437.90524 -157.578842) (xy 437.763294 -157.424182) (xy 437.62734 -157.264231)
			(xy 437.497573 -157.099219) (xy 437.374183 -156.929387) (xy 437.257348 -156.75498) (xy 437.147237 -156.576252)
			(xy 437.04401 -156.393461) (xy 436.947817 -156.206873) (xy 436.858798 -156.016758) (xy 436.77708 -155.823392)
			(xy 436.702784 -155.627055) (xy 436.636016 -155.428032) (xy 436.576874 -155.226611) (xy 436.525442 -155.023085)
			(xy 436.481797 -154.817748) (xy 436.446 -154.610898) (xy 436.418104 -154.402836) (xy 436.39815 -154.193862)
			(xy 436.386165 -153.98428) (xy 436.382169 -153.774394) (xy 435.91734 -153.774394) (xy 435.91734 -164.882068)
			(xy 436.510682 -164.882068) (xy 436.514753 -164.826446) (xy 436.526879 -164.772009) (xy 436.546802 -164.719918)
			(xy 436.574098 -164.671283) (xy 436.608184 -164.62714) (xy 436.648333 -164.588431) (xy 436.693691 -164.55598)
			(xy 436.743291 -164.530479) (xy 436.796075 -164.512472) (xy 436.850918 -164.502342) (xy 436.906652 -164.500305)
			(xy 436.962089 -164.506405) (xy 437.016046 -164.520511) (xy 437.067375 -164.542323) (xy 437.114981 -164.571377)
			(xy 437.157849 -164.607052) (xy 437.195066 -164.648589) (xy 437.225839 -164.695102) (xy 437.249511 -164.745599)
			(xy 437.265579 -164.799006) (xy 437.273699 -164.854182) (xy 437.274208 -164.882068) (xy 437.273699 -164.909954)
			(xy 437.265579 -164.96513) (xy 437.249511 -165.018537) (xy 437.225839 -165.069034) (xy 437.195066 -165.115547)
			(xy 437.157849 -165.157084) (xy 437.114981 -165.192759) (xy 437.067375 -165.221813) (xy 437.016046 -165.243625)
			(xy 436.962089 -165.257731) (xy 436.906652 -165.263831) (xy 436.850918 -165.261794) (xy 436.796075 -165.251664)
			(xy 436.743291 -165.233657) (xy 436.693691 -165.208156) (xy 436.648333 -165.175705) (xy 436.608184 -165.136996)
			(xy 436.574098 -165.092853) (xy 436.546802 -165.044218) (xy 436.526879 -164.992127) (xy 436.514753 -164.93769)
			(xy 436.510682 -164.882068) (xy 435.91734 -164.882068) (xy 435.91734 -165.63467) (xy 436.051196 -165.63467)
			(xy 436.055267 -165.579048) (xy 436.067393 -165.524611) (xy 436.087316 -165.47252) (xy 436.114612 -165.423885)
			(xy 436.148698 -165.379742) (xy 436.188847 -165.341033) (xy 436.234205 -165.308582) (xy 436.283805 -165.283081)
			(xy 436.336589 -165.265074) (xy 436.391432 -165.254944) (xy 436.447166 -165.252907) (xy 436.502603 -165.259007)
			(xy 436.55656 -165.273113) (xy 436.607889 -165.294925) (xy 436.655495 -165.323979) (xy 436.683633 -165.347396)
			(xy 440.777374 -165.347396) (xy 440.781445 -165.291774) (xy 440.793571 -165.237337) (xy 440.813494 -165.185246)
			(xy 440.84079 -165.136611) (xy 440.874876 -165.092468) (xy 440.915025 -165.053759) (xy 440.960383 -165.021308)
			(xy 441.009983 -164.995807) (xy 441.062767 -164.9778) (xy 441.11761 -164.96767) (xy 441.173344 -164.965633)
			(xy 441.228781 -164.971733) (xy 441.282738 -164.985839) (xy 441.334067 -165.007651) (xy 441.381673 -165.036705)
			(xy 441.424541 -165.07238) (xy 441.461758 -165.113917) (xy 441.492531 -165.16043) (xy 441.516203 -165.210927)
			(xy 441.532271 -165.264334) (xy 441.540391 -165.31951) (xy 441.5409 -165.347396) (xy 441.540391 -165.375282)
			(xy 441.532271 -165.430458) (xy 441.516203 -165.483865) (xy 441.492531 -165.534362) (xy 441.461758 -165.580875)
			(xy 441.424541 -165.622412) (xy 441.381673 -165.658087) (xy 441.334067 -165.687141) (xy 441.282738 -165.708953)
			(xy 441.228781 -165.723059) (xy 441.173344 -165.729159) (xy 441.11761 -165.727122) (xy 441.062767 -165.716992)
			(xy 441.009983 -165.698985) (xy 440.960383 -165.673484) (xy 440.915025 -165.641033) (xy 440.874876 -165.602324)
			(xy 440.84079 -165.558181) (xy 440.813494 -165.509546) (xy 440.793571 -165.457455) (xy 440.781445 -165.403018)
			(xy 440.777374 -165.347396) (xy 436.683633 -165.347396) (xy 436.698363 -165.359654) (xy 436.73558 -165.401191)
			(xy 436.766353 -165.447704) (xy 436.790025 -165.498201) (xy 436.806093 -165.551608) (xy 436.814213 -165.606784)
			(xy 436.814722 -165.63467) (xy 436.814213 -165.662556) (xy 436.806093 -165.717732) (xy 436.790025 -165.771139)
			(xy 436.766353 -165.821636) (xy 436.73558 -165.868149) (xy 436.698363 -165.909686) (xy 436.655495 -165.945361)
			(xy 436.607889 -165.974415) (xy 436.55656 -165.996227) (xy 436.502603 -166.010333) (xy 436.447166 -166.016433)
			(xy 436.391432 -166.014396) (xy 436.336589 -166.004266) (xy 436.283805 -165.986259) (xy 436.234205 -165.960758)
			(xy 436.188847 -165.928307) (xy 436.148698 -165.889598) (xy 436.114612 -165.845455) (xy 436.087316 -165.79682)
			(xy 436.067393 -165.744729) (xy 436.055267 -165.690292) (xy 436.051196 -165.63467) (xy 435.91734 -165.63467)
			(xy 435.91734 -165.921944) (xy 435.917594 -165.922198) (xy 435.917594 -165.96995) (xy 435.918102 -165.970458)
			(xy 435.91734 -165.974776) (xy 435.91734 -166.05205) (xy 437.326792 -166.05205) (xy 437.326792 -165.99755)
			(xy 437.334548 -165.943606) (xy 437.349902 -165.891314) (xy 437.372541 -165.84174) (xy 437.402005 -165.795892)
			(xy 437.437694 -165.754704) (xy 437.478881 -165.719013) (xy 437.524728 -165.689548) (xy 437.574301 -165.666907)
			(xy 437.626592 -165.651551) (xy 437.680536 -165.643793) (xy 437.707786 -165.643306) (xy 437.73472 -165.643767)
			(xy 437.788051 -165.651359) (xy 437.839784 -165.666379) (xy 437.888888 -165.688529) (xy 437.934387 -165.717368)
			(xy 437.955182 -165.734492) (xy 437.96331 -165.74135) (xy 437.982868 -165.747446) (xy 438.077864 -165.737032)
			(xy 438.095644 -165.726872) (xy 438.102248 -165.718236) (xy 438.122883 -165.691764) (xy 438.170038 -165.643997)
			(xy 438.22307 -165.602853) (xy 438.281056 -165.569047) (xy 438.342988 -165.543166) (xy 438.407786 -165.525662)
			(xy 438.474325 -165.516839) (xy 438.507886 -165.516306) (xy 438.53985 -165.516758) (xy 438.603274 -165.524769)
			(xy 438.665193 -165.540665) (xy 438.724632 -165.564198) (xy 438.780653 -165.594994) (xy 438.832372 -165.632569)
			(xy 438.878974 -165.676329) (xy 438.919723 -165.725586) (xy 438.953978 -165.779562) (xy 438.981197 -165.837405)
			(xy 439.000952 -165.898203) (xy 439.012931 -165.960999) (xy 439.016946 -166.0248) (xy 439.012931 -166.088601)
			(xy 439.000952 -166.151397) (xy 438.981197 -166.212195) (xy 438.953978 -166.270038) (xy 438.919723 -166.324014)
			(xy 438.878974 -166.373271) (xy 438.832372 -166.417031) (xy 438.780653 -166.454606) (xy 438.724632 -166.485402)
			(xy 438.665193 -166.508935) (xy 438.603274 -166.524831) (xy 438.53985 -166.532842) (xy 438.507886 -166.533322)
			(xy 438.47433 -166.532735) (xy 438.407803 -166.523895) (xy 438.343015 -166.506383) (xy 438.281094 -166.480504)
			(xy 438.223113 -166.446707) (xy 438.170079 -166.405579) (xy 438.122915 -166.357834) (xy 438.102248 -166.331392)
			(xy 438.095644 -166.322756) (xy 438.077864 -166.312596) (xy 437.982868 -166.302182) (xy 437.96331 -166.308278)
			(xy 437.955182 -166.315136) (xy 437.934385 -166.332258) (xy 437.88889 -166.361104) (xy 437.839787 -166.383257)
			(xy 437.788053 -166.398275) (xy 437.734721 -166.405858) (xy 437.707786 -166.406322) (xy 437.680536 -166.405807)
			(xy 437.626592 -166.398049) (xy 437.574301 -166.382693) (xy 437.524728 -166.360052) (xy 437.478881 -166.330587)
			(xy 437.437694 -166.294896) (xy 437.402005 -166.253708) (xy 437.372541 -166.20786) (xy 437.349902 -166.158286)
			(xy 437.334548 -166.105994) (xy 437.326792 -166.05205) (xy 435.91734 -166.05205) (xy 435.91734 -167.127428)
			(xy 436.108092 -167.127428) (xy 436.112163 -167.071806) (xy 436.124289 -167.017369) (xy 436.144212 -166.965278)
			(xy 436.171508 -166.916643) (xy 436.205594 -166.8725) (xy 436.245743 -166.833791) (xy 436.291101 -166.80134)
			(xy 436.340701 -166.775839) (xy 436.393485 -166.757832) (xy 436.448328 -166.747702) (xy 436.504062 -166.745665)
			(xy 436.559499 -166.751765) (xy 436.613456 -166.765871) (xy 436.664785 -166.787683) (xy 436.712391 -166.816737)
			(xy 436.755259 -166.852412) (xy 436.792476 -166.893949) (xy 436.797216 -166.901114) (xy 439.811414 -166.901114)
			(xy 439.811862 -166.875308) (xy 439.818825 -166.824168) (xy 439.832613 -166.774432) (xy 439.852974 -166.727006)
			(xy 439.879537 -166.682755) (xy 439.911818 -166.642485) (xy 439.94923 -166.60693) (xy 439.96991 -166.591488)
			(xy 439.980686 -166.583231) (xy 439.997743 -166.56212) (xy 440.008642 -166.537265) (xy 440.012618 -166.510418)
			(xy 440.009388 -166.48347) (xy 439.999182 -166.458322) (xy 439.982718 -166.436746) (xy 439.972196 -166.428166)
			(xy 439.94922 -166.410018) (xy 439.908584 -166.367869) (xy 439.874858 -166.320011) (xy 439.848834 -166.267566)
			(xy 439.83112 -166.211763) (xy 439.822131 -166.153909) (xy 439.821574 -166.124636) (xy 439.82206 -166.097385)
			(xy 439.829816 -166.043437) (xy 439.845171 -165.991142) (xy 439.867813 -165.941565) (xy 439.897279 -165.895715)
			(xy 439.93297 -165.854524) (xy 439.974161 -165.818833) (xy 440.020011 -165.789367) (xy 440.069588 -165.766725)
			(xy 440.121883 -165.75137) (xy 440.175831 -165.743614) (xy 440.230333 -165.743614) (xy 440.284281 -165.75137)
			(xy 440.336576 -165.766725) (xy 440.386153 -165.789367) (xy 440.432003 -165.818833) (xy 440.473194 -165.854524)
			(xy 440.508885 -165.895715) (xy 440.538351 -165.941565) (xy 440.560993 -165.991142) (xy 440.576348 -166.043437)
			(xy 440.584104 -166.097385) (xy 440.58459 -166.124636) (xy 440.584178 -166.150443) (xy 440.577208 -166.201584)
			(xy 440.563414 -166.251321) (xy 440.543047 -166.298747) (xy 440.516479 -166.342998) (xy 440.484192 -166.383267)
			(xy 440.446776 -166.418821) (xy 440.426094 -166.434262) (xy 440.415366 -166.442577) (xy 440.39831 -166.463675)
			(xy 440.387407 -166.488517) (xy 440.383425 -166.515353) (xy 440.386646 -166.542291) (xy 440.396841 -166.567432)
			(xy 440.413293 -166.589004) (xy 440.423808 -166.597584) (xy 440.446809 -166.615702) (xy 440.487443 -166.657857)
			(xy 440.521166 -166.705721) (xy 440.547186 -166.758172) (xy 440.564895 -166.813981) (xy 440.573876 -166.871839)
			(xy 440.57443 -166.901114) (xy 440.573944 -166.928365) (xy 440.566188 -166.982313) (xy 440.550833 -167.034608)
			(xy 440.528191 -167.084185) (xy 440.498725 -167.130035) (xy 440.463034 -167.171226) (xy 440.421843 -167.206917)
			(xy 440.375993 -167.236383) (xy 440.326416 -167.259025) (xy 440.274121 -167.27438) (xy 440.220173 -167.282136)
			(xy 440.165671 -167.282136) (xy 440.111723 -167.27438) (xy 440.059428 -167.259025) (xy 440.009851 -167.236383)
			(xy 439.964001 -167.206917) (xy 439.92281 -167.171226) (xy 439.887119 -167.130035) (xy 439.857653 -167.084185)
			(xy 439.835011 -167.034608) (xy 439.819656 -166.982313) (xy 439.8119 -166.928365) (xy 439.811414 -166.901114)
			(xy 436.797216 -166.901114) (xy 436.823249 -166.940462) (xy 436.846921 -166.990959) (xy 436.862989 -167.044366)
			(xy 436.871109 -167.099542) (xy 436.871618 -167.127428) (xy 436.871109 -167.155314) (xy 436.862989 -167.21049)
			(xy 436.846921 -167.263897) (xy 436.823249 -167.314394) (xy 436.792476 -167.360907) (xy 436.755259 -167.402444)
			(xy 436.712391 -167.438119) (xy 436.664785 -167.467173) (xy 436.613456 -167.488985) (xy 436.559499 -167.503091)
			(xy 436.504062 -167.509191) (xy 436.448328 -167.507154) (xy 436.393485 -167.497024) (xy 436.340701 -167.479017)
			(xy 436.291101 -167.453516) (xy 436.245743 -167.421065) (xy 436.205594 -167.382356) (xy 436.171508 -167.338213)
			(xy 436.144212 -167.289578) (xy 436.124289 -167.237487) (xy 436.112163 -167.18305) (xy 436.108092 -167.127428)
			(xy 435.91734 -167.127428) (xy 435.91734 -167.929352) (xy 442.164683 -167.929352) (xy 442.164683 -167.874848)
			(xy 442.17244 -167.820899) (xy 442.187796 -167.768603) (xy 442.210439 -167.719025) (xy 442.239907 -167.673174)
			(xy 442.275601 -167.631984) (xy 442.316793 -167.596293) (xy 442.362646 -167.566828) (xy 442.412226 -167.544188)
			(xy 442.464522 -167.528835) (xy 442.518472 -167.521082) (xy 442.545724 -167.52062) (xy 442.575522 -167.521188)
			(xy 442.634392 -167.53047) (xy 442.691104 -167.548789) (xy 442.74428 -167.575699) (xy 442.792627 -167.610548)
			(xy 442.814202 -167.63111) (xy 442.824147 -167.640387) (xy 442.847816 -167.653764) (xy 442.874179 -167.66041)
			(xy 442.901361 -167.659853) (xy 442.92743 -167.652132) (xy 442.950531 -167.637797) (xy 442.969024 -167.617867)
			(xy 442.981591 -167.593759) (xy 442.98489 -167.580564) (xy 442.991567 -167.552618) (xy 443.012155 -167.498978)
			(xy 443.040555 -167.449032) (xy 443.076124 -167.403911) (xy 443.118058 -167.364634) (xy 443.165408 -167.332091)
			(xy 443.217104 -167.307017) (xy 443.271975 -167.289979) (xy 443.32878 -167.281364) (xy 443.357508 -167.280844)
			(xy 443.384755 -167.281427) (xy 443.438695 -167.289183) (xy 443.490983 -167.304537) (xy 443.540553 -167.327176)
			(xy 443.586396 -167.356639) (xy 443.62758 -167.392326) (xy 443.663266 -167.43351) (xy 443.692728 -167.479355)
			(xy 443.715366 -167.528925) (xy 443.730719 -167.581212) (xy 443.738474 -167.635153) (xy 443.738474 -167.689647)
			(xy 443.730719 -167.743588) (xy 443.715366 -167.795875) (xy 443.692728 -167.845445) (xy 443.663266 -167.89129)
			(xy 443.62758 -167.932474) (xy 443.586396 -167.968161) (xy 443.540553 -167.997624) (xy 443.490983 -168.020263)
			(xy 443.438695 -168.035617) (xy 443.384755 -168.043373) (xy 443.357508 -168.04386) (xy 443.32771 -168.043278)
			(xy 443.26884 -168.034) (xy 443.212128 -168.015685) (xy 443.158952 -167.988777) (xy 443.110605 -167.953931)
			(xy 443.08903 -167.93337) (xy 443.079044 -167.92414) (xy 443.055385 -167.910766) (xy 443.029032 -167.904119)
			(xy 443.001859 -167.904671) (xy 442.975798 -167.912385) (xy 442.952702 -167.92671) (xy 442.934212 -167.946629)
			(xy 442.921643 -167.970727) (xy 442.918342 -167.983916) (xy 442.911622 -168.011851) (xy 442.891039 -168.065489)
			(xy 442.862644 -168.115433) (xy 442.827081 -168.160554) (xy 442.785152 -168.199832) (xy 442.737808 -168.232377)
			(xy 442.686117 -168.257453) (xy 442.631251 -168.274494) (xy 442.57445 -168.283114) (xy 442.545724 -168.283636)
			(xy 442.518472 -168.283118) (xy 442.464522 -168.275365) (xy 442.412226 -168.260012) (xy 442.362646 -168.237372)
			(xy 442.316793 -168.207907) (xy 442.275601 -168.172216) (xy 442.239907 -168.131026) (xy 442.210439 -168.085175)
			(xy 442.187796 -168.035597) (xy 442.17244 -167.983301) (xy 442.164683 -167.929352) (xy 435.91734 -167.929352)
			(xy 435.91734 -169.293286) (xy 435.917684 -169.301893) (xy 435.923379 -169.318139) (xy 435.934106 -169.331604)
			(xy 435.941216 -169.336466) (xy 435.95671 -169.346118) (xy 435.964584 -169.34815) (xy 435.991708 -169.35548)
			(xy 436.043603 -169.377016) (xy 436.091778 -169.405929) (xy 436.135193 -169.441595) (xy 436.172907 -169.483241)
			(xy 436.204106 -169.529969) (xy 436.228116 -169.580766) (xy 436.244416 -169.634536) (xy 436.252655 -169.690114)
			(xy 436.252654 -169.7463) (xy 436.250797 -169.758825) (xy 442.84493 -169.758825) (xy 442.84493 -169.694903)
			(xy 442.852941 -169.631485) (xy 442.868838 -169.569571) (xy 442.89237 -169.510138) (xy 442.923164 -169.454123)
			(xy 442.960737 -169.402408) (xy 443.004494 -169.355811) (xy 443.053747 -169.315066) (xy 443.107718 -169.280815)
			(xy 443.165557 -169.253598) (xy 443.22635 -169.233845) (xy 443.28914 -169.221867) (xy 443.352936 -169.217854)
			(xy 443.416732 -169.221867) (xy 443.479522 -169.233845) (xy 443.540315 -169.253598) (xy 443.598154 -169.280815)
			(xy 443.652125 -169.315066) (xy 443.701378 -169.355811) (xy 443.745135 -169.402408) (xy 443.782708 -169.454123)
			(xy 443.813502 -169.510138) (xy 443.837034 -169.569571) (xy 443.852931 -169.631485) (xy 443.860942 -169.694903)
			(xy 443.861444 -169.726864) (xy 443.860942 -169.758825) (xy 443.852931 -169.822243) (xy 443.837034 -169.884157)
			(xy 443.813502 -169.94359) (xy 443.782708 -169.999605) (xy 443.745135 -170.05132) (xy 443.701378 -170.097917)
			(xy 443.652125 -170.138662) (xy 443.598154 -170.172913) (xy 443.540315 -170.20013) (xy 443.479522 -170.219883)
			(xy 443.416732 -170.231861) (xy 443.352936 -170.235875) (xy 443.28914 -170.231861) (xy 443.22635 -170.219883)
			(xy 443.165557 -170.20013) (xy 443.107718 -170.172913) (xy 443.053747 -170.138662) (xy 443.004494 -170.097917)
			(xy 442.960737 -170.05132) (xy 442.923164 -169.999605) (xy 442.89237 -169.94359) (xy 442.868838 -169.884157)
			(xy 442.852941 -169.822243) (xy 442.84493 -169.758825) (xy 436.250797 -169.758825) (xy 436.244413 -169.801878)
			(xy 436.228111 -169.855647) (xy 436.2041 -169.906443) (xy 436.172899 -169.953169) (xy 436.135183 -169.994815)
			(xy 436.091767 -170.030479) (xy 436.043591 -170.05939) (xy 435.991695 -170.080924) (xy 435.964584 -170.088306)
			(xy 435.95671 -170.090338) (xy 435.941216 -170.09999) (xy 435.934083 -170.10483) (xy 435.923325 -170.118284)
			(xy 435.917668 -170.134555) (xy 435.91734 -170.14317) (xy 435.91734 -170.26763) (xy 438.106818 -170.26763)
			(xy 438.110889 -170.212008) (xy 438.123015 -170.157571) (xy 438.142938 -170.10548) (xy 438.170234 -170.056845)
			(xy 438.20432 -170.012702) (xy 438.244469 -169.973993) (xy 438.289827 -169.941542) (xy 438.339427 -169.916041)
			(xy 438.392211 -169.898034) (xy 438.447054 -169.887904) (xy 438.502788 -169.885867) (xy 438.558225 -169.891967)
			(xy 438.612182 -169.906073) (xy 438.663511 -169.927885) (xy 438.711117 -169.956939) (xy 438.753985 -169.992614)
			(xy 438.791202 -170.034151) (xy 438.821975 -170.080664) (xy 438.845647 -170.131161) (xy 438.861715 -170.184568)
			(xy 438.869835 -170.239744) (xy 438.870344 -170.26763) (xy 438.869835 -170.295516) (xy 438.861715 -170.350692)
			(xy 438.845647 -170.404099) (xy 438.821975 -170.454596) (xy 438.791202 -170.501109) (xy 438.753985 -170.542646)
			(xy 438.733762 -170.559476) (xy 440.81649 -170.559476) (xy 440.820561 -170.503854) (xy 440.832687 -170.449417)
			(xy 440.85261 -170.397326) (xy 440.879906 -170.348691) (xy 440.913992 -170.304548) (xy 440.954141 -170.265839)
			(xy 440.999499 -170.233388) (xy 441.049099 -170.207887) (xy 441.101883 -170.18988) (xy 441.156726 -170.17975)
			(xy 441.21246 -170.177713) (xy 441.267897 -170.183813) (xy 441.321854 -170.197919) (xy 441.373183 -170.219731)
			(xy 441.420789 -170.248785) (xy 441.463657 -170.28446) (xy 441.500874 -170.325997) (xy 441.531647 -170.37251)
			(xy 441.555319 -170.423007) (xy 441.571387 -170.476414) (xy 441.579507 -170.53159) (xy 441.580016 -170.559476)
			(xy 442.25159 -170.559476) (xy 442.255661 -170.503854) (xy 442.267787 -170.449417) (xy 442.28771 -170.397326)
			(xy 442.315006 -170.348691) (xy 442.349092 -170.304548) (xy 442.389241 -170.265839) (xy 442.434599 -170.233388)
			(xy 442.484199 -170.207887) (xy 442.536983 -170.18988) (xy 442.591826 -170.17975) (xy 442.64756 -170.177713)
			(xy 442.702997 -170.183813) (xy 442.756954 -170.197919) (xy 442.808283 -170.219731) (xy 442.855889 -170.248785)
			(xy 442.898757 -170.28446) (xy 442.935974 -170.325997) (xy 442.966747 -170.37251) (xy 442.990419 -170.423007)
			(xy 443.006487 -170.476414) (xy 443.014607 -170.53159) (xy 443.015116 -170.559476) (xy 443.014607 -170.587362)
			(xy 443.006487 -170.642538) (xy 442.990419 -170.695945) (xy 442.966747 -170.746442) (xy 442.935974 -170.792955)
			(xy 442.898757 -170.834492) (xy 442.855889 -170.870167) (xy 442.808283 -170.899221) (xy 442.756954 -170.921033)
			(xy 442.702997 -170.935139) (xy 442.64756 -170.941239) (xy 442.591826 -170.939202) (xy 442.536983 -170.929072)
			(xy 442.484199 -170.911065) (xy 442.434599 -170.885564) (xy 442.389241 -170.853113) (xy 442.349092 -170.814404)
			(xy 442.315006 -170.770261) (xy 442.28771 -170.721626) (xy 442.267787 -170.669535) (xy 442.255661 -170.615098)
			(xy 442.25159 -170.559476) (xy 441.580016 -170.559476) (xy 441.579507 -170.587362) (xy 441.571387 -170.642538)
			(xy 441.555319 -170.695945) (xy 441.531647 -170.746442) (xy 441.500874 -170.792955) (xy 441.463657 -170.834492)
			(xy 441.420789 -170.870167) (xy 441.373183 -170.899221) (xy 441.321854 -170.921033) (xy 441.267897 -170.935139)
			(xy 441.21246 -170.941239) (xy 441.156726 -170.939202) (xy 441.101883 -170.929072) (xy 441.049099 -170.911065)
			(xy 440.999499 -170.885564) (xy 440.954141 -170.853113) (xy 440.913992 -170.814404) (xy 440.879906 -170.770261)
			(xy 440.85261 -170.721626) (xy 440.832687 -170.669535) (xy 440.820561 -170.615098) (xy 440.81649 -170.559476)
			(xy 438.733762 -170.559476) (xy 438.711117 -170.578321) (xy 438.663511 -170.607375) (xy 438.612182 -170.629187)
			(xy 438.558225 -170.643293) (xy 438.502788 -170.649393) (xy 438.447054 -170.647356) (xy 438.392211 -170.637226)
			(xy 438.339427 -170.619219) (xy 438.289827 -170.593718) (xy 438.244469 -170.561267) (xy 438.20432 -170.522558)
			(xy 438.170234 -170.478415) (xy 438.142938 -170.42978) (xy 438.123015 -170.377689) (xy 438.110889 -170.323252)
			(xy 438.106818 -170.26763) (xy 435.91734 -170.26763) (xy 435.91734 -171.743116) (xy 436.164226 -171.743116)
			(xy 436.168297 -171.687494) (xy 436.180423 -171.633057) (xy 436.200346 -171.580966) (xy 436.227642 -171.532331)
			(xy 436.261728 -171.488188) (xy 436.301877 -171.449479) (xy 436.347235 -171.417028) (xy 436.396835 -171.391527)
			(xy 436.449619 -171.37352) (xy 436.504462 -171.36339) (xy 436.560196 -171.361353) (xy 436.615633 -171.367453)
			(xy 436.66959 -171.381559) (xy 436.720919 -171.403371) (xy 436.768525 -171.432425) (xy 436.811393 -171.4681)
			(xy 436.84861 -171.509637) (xy 436.879383 -171.55615) (xy 436.903055 -171.606647) (xy 436.919123 -171.660054)
			(xy 436.927243 -171.71523) (xy 436.927752 -171.743116) (xy 436.927243 -171.771002) (xy 436.919123 -171.826178)
			(xy 436.903055 -171.879585) (xy 436.879383 -171.930082) (xy 436.84861 -171.976595) (xy 436.811393 -172.018132)
			(xy 436.768525 -172.053807) (xy 436.720919 -172.082861) (xy 436.66959 -172.104673) (xy 436.615633 -172.118779)
			(xy 436.560196 -172.124879) (xy 436.504462 -172.122842) (xy 436.449619 -172.112712) (xy 436.396835 -172.094705)
			(xy 436.347235 -172.069204) (xy 436.301877 -172.036753) (xy 436.261728 -171.998044) (xy 436.227642 -171.953901)
			(xy 436.200346 -171.905266) (xy 436.180423 -171.853175) (xy 436.168297 -171.798738) (xy 436.164226 -171.743116)
			(xy 435.91734 -171.743116) (xy 435.91734 -173.444154) (xy 435.916905 -173.454219) (xy 435.90917 -173.472803)
			(xy 435.902354 -173.480222) (xy 435.732471 -173.650105) (xy 454.887324 -173.650105) (xy 454.887324 -173.586183)
			(xy 454.895335 -173.522765) (xy 454.911232 -173.460851) (xy 454.934764 -173.401418) (xy 454.965558 -173.345403)
			(xy 455.003131 -173.293688) (xy 455.046888 -173.247091) (xy 455.096141 -173.206346) (xy 455.150112 -173.172095)
			(xy 455.207951 -173.144878) (xy 455.268744 -173.125125) (xy 455.331534 -173.113147) (xy 455.39533 -173.109134)
			(xy 455.459126 -173.113147) (xy 455.521916 -173.125125) (xy 455.582709 -173.144878) (xy 455.640548 -173.172095)
			(xy 455.694519 -173.206346) (xy 455.743772 -173.247091) (xy 455.787529 -173.293688) (xy 455.825102 -173.345403)
			(xy 455.855896 -173.401418) (xy 455.879428 -173.460851) (xy 455.895325 -173.522765) (xy 455.903336 -173.586183)
			(xy 455.903838 -173.618144) (xy 455.903336 -173.650105) (xy 455.895325 -173.713523) (xy 455.879428 -173.775437)
			(xy 455.855896 -173.83487) (xy 455.825102 -173.890885) (xy 455.787529 -173.9426) (xy 455.743772 -173.989197)
			(xy 455.694519 -174.029942) (xy 455.640548 -174.064193) (xy 455.582709 -174.09141) (xy 455.521916 -174.111163)
			(xy 455.459126 -174.123141) (xy 455.39533 -174.127155) (xy 455.331534 -174.123141) (xy 455.268744 -174.111163)
			(xy 455.207951 -174.09141) (xy 455.150112 -174.064193) (xy 455.096141 -174.029942) (xy 455.046888 -173.989197)
			(xy 455.003131 -173.9426) (xy 454.965558 -173.890885) (xy 454.934764 -173.83487) (xy 454.911232 -173.775437)
			(xy 454.895335 -173.713523) (xy 454.887324 -173.650105) (xy 435.732471 -173.650105) (xy 428.054516 -181.32806)
			(xy 442.083952 -181.32806) (xy 442.084389 -181.289772) (xy 442.09101 -181.213482) (xy 442.104157 -181.138042)
			(xy 442.123733 -181.06401) (xy 442.136276 -181.027832) (xy 442.138939 -181.019399) (xy 442.138926 -181.001726)
			(xy 442.136276 -180.993288) (xy 442.123707 -180.957118) (xy 442.104114 -180.883087) (xy 442.090966 -180.807644)
			(xy 442.084361 -180.73135) (xy 442.083952 -180.69306) (xy 442.084389 -180.654772) (xy 442.09101 -180.578482)
			(xy 442.104157 -180.503042) (xy 442.123733 -180.42901) (xy 442.136276 -180.392832) (xy 442.138939 -180.384399)
			(xy 442.138926 -180.366726) (xy 442.136276 -180.358288) (xy 442.123707 -180.322118) (xy 442.104114 -180.248087)
			(xy 442.090966 -180.172644) (xy 442.084361 -180.09635) (xy 442.083952 -180.05806) (xy 442.084389 -180.019772)
			(xy 442.09101 -179.943482) (xy 442.104157 -179.868042) (xy 442.123733 -179.79401) (xy 442.136276 -179.757832)
			(xy 442.138939 -179.749399) (xy 442.138926 -179.731726) (xy 442.136276 -179.723288) (xy 442.123707 -179.687118)
			(xy 442.104114 -179.613087) (xy 442.090966 -179.537644) (xy 442.084361 -179.46135) (xy 442.083952 -179.42306)
			(xy 442.084428 -179.381958) (xy 442.092016 -179.300105) (xy 442.107124 -179.219301) (xy 442.129623 -179.140236)
			(xy 442.15932 -179.063584) (xy 442.195963 -178.989998) (xy 442.239239 -178.920108) (xy 442.288778 -178.854508)
			(xy 442.344159 -178.793759) (xy 442.404908 -178.738378) (xy 442.470508 -178.688839) (xy 442.540398 -178.645563)
			(xy 442.613984 -178.60892) (xy 442.690636 -178.579223) (xy 442.769701 -178.556724) (xy 442.850505 -178.541616)
			(xy 442.932358 -178.534028) (xy 442.97346 -178.533552) (xy 443.011748 -178.533983) (xy 443.088038 -178.540606)
			(xy 443.163478 -178.553754) (xy 443.23751 -178.573332) (xy 443.273688 -178.585876) (xy 443.282126 -178.588518)
			(xy 443.299794 -178.588518) (xy 443.308232 -178.585876) (xy 443.3444 -178.573301) (xy 443.418432 -178.55371)
			(xy 443.493875 -178.540564) (xy 443.57017 -178.53396) (xy 443.60846 -178.533552) (xy 443.646748 -178.533983)
			(xy 443.723038 -178.540606) (xy 443.798478 -178.553754) (xy 443.87251 -178.573332) (xy 443.908688 -178.585876)
			(xy 443.917126 -178.588518) (xy 443.934794 -178.588518) (xy 443.943232 -178.585876) (xy 443.9794 -178.573301)
			(xy 444.053432 -178.55371) (xy 444.128875 -178.540564) (xy 444.20517 -178.53396) (xy 444.24346 -178.533552)
			(xy 444.281748 -178.533983) (xy 444.358038 -178.540606) (xy 444.433478 -178.553754) (xy 444.50751 -178.573332)
			(xy 444.543688 -178.585876) (xy 444.552126 -178.588518) (xy 444.569794 -178.588518) (xy 444.578232 -178.585876)
			(xy 444.6144 -178.573301) (xy 444.688432 -178.55371) (xy 444.763875 -178.540564) (xy 444.84017 -178.53396)
			(xy 444.87846 -178.533552) (xy 444.916748 -178.533983) (xy 444.993038 -178.540606) (xy 445.068478 -178.553754)
			(xy 445.14251 -178.573332) (xy 445.178688 -178.585876) (xy 445.187126 -178.588518) (xy 445.204794 -178.588518)
			(xy 445.213232 -178.585876) (xy 445.2494 -178.573301) (xy 445.323432 -178.55371) (xy 445.398875 -178.540564)
			(xy 445.47517 -178.53396) (xy 445.51346 -178.533552) (xy 445.554561 -178.534105) (xy 445.636412 -178.541686)
			(xy 445.717214 -178.556786) (xy 445.796278 -178.579278) (xy 445.87293 -178.608969) (xy 445.946515 -178.645606)
			(xy 446.016406 -178.688877) (xy 446.082006 -178.738411) (xy 446.142756 -178.793787) (xy 446.198138 -178.854532)
			(xy 446.247678 -178.920128) (xy 446.290955 -178.990015) (xy 446.327598 -179.063597) (xy 446.357296 -179.140246)
			(xy 446.379795 -179.219308) (xy 446.394903 -179.300109) (xy 446.402492 -179.381959) (xy 446.402968 -179.42306)
			(xy 446.402542 -179.461348) (xy 446.395918 -179.537639) (xy 446.382768 -179.613079) (xy 446.363189 -179.687111)
			(xy 446.350644 -179.723288) (xy 446.348021 -179.731731) (xy 446.348008 -179.749395) (xy 446.350644 -179.757832)
			(xy 446.36322 -179.794) (xy 446.376973 -179.84597) (xy 455.91984 -179.84597) (xy 455.920275 -179.807682)
			(xy 455.926896 -179.731392) (xy 455.940043 -179.655952) (xy 455.95962 -179.58192) (xy 455.972164 -179.545742)
			(xy 455.974822 -179.537308) (xy 455.974812 -179.519636) (xy 455.972164 -179.511198) (xy 455.959597 -179.475027)
			(xy 455.940004 -179.400996) (xy 455.926855 -179.325554) (xy 455.920249 -179.24926) (xy 455.91984 -179.21097)
			(xy 455.920275 -179.172682) (xy 455.926896 -179.096392) (xy 455.940043 -179.020952) (xy 455.95962 -178.94692)
			(xy 455.972164 -178.910742) (xy 455.974822 -178.902308) (xy 455.974812 -178.884636) (xy 455.972164 -178.876198)
			(xy 455.959597 -178.840027) (xy 455.940004 -178.765996) (xy 455.926855 -178.690554) (xy 455.920249 -178.61426)
			(xy 455.91984 -178.57597) (xy 455.920275 -178.537682) (xy 455.926896 -178.461392) (xy 455.940043 -178.385952)
			(xy 455.95962 -178.31192) (xy 455.972164 -178.275742) (xy 455.974822 -178.267308) (xy 455.974812 -178.249636)
			(xy 455.972164 -178.241198) (xy 455.959597 -178.205027) (xy 455.940004 -178.130996) (xy 455.926855 -178.055554)
			(xy 455.920249 -177.97926) (xy 455.91984 -177.94097) (xy 455.920275 -177.902682) (xy 455.926896 -177.826392)
			(xy 455.940043 -177.750952) (xy 455.95962 -177.67692) (xy 455.972164 -177.640742) (xy 455.974822 -177.632308)
			(xy 455.974812 -177.614636) (xy 455.972164 -177.606198) (xy 455.959597 -177.570027) (xy 455.940004 -177.495996)
			(xy 455.926855 -177.420554) (xy 455.920249 -177.34426) (xy 455.91984 -177.30597) (xy 455.920224 -177.264865)
			(xy 455.927812 -177.183006) (xy 455.942921 -177.102196) (xy 455.965422 -177.023125) (xy 455.995122 -176.946467)
			(xy 456.031769 -176.872877) (xy 456.07505 -176.802983) (xy 456.124596 -176.73738) (xy 456.179983 -176.676628)
			(xy 456.24074 -176.621246) (xy 456.306347 -176.571706) (xy 456.376245 -176.528432) (xy 456.449839 -176.491791)
			(xy 456.526499 -176.462097) (xy 456.605572 -176.439603) (xy 456.686383 -176.424501) (xy 456.768243 -176.41692)
			(xy 456.809348 -176.416462) (xy 456.853142 -176.417005) (xy 456.940303 -176.425639) (xy 457.026195 -176.44279)
			(xy 457.109989 -176.46829) (xy 457.190874 -176.501895) (xy 457.229718 -176.522126) (xy 457.241184 -176.527544)
			(xy 457.266512 -176.527544) (xy 457.277978 -176.522126) (xy 457.31681 -176.501866) (xy 457.397688 -176.468235)
			(xy 457.481484 -176.442726) (xy 457.567383 -176.425586) (xy 457.654552 -176.416981) (xy 457.698348 -176.416462)
			(xy 457.742142 -176.417005) (xy 457.829303 -176.425639) (xy 457.915195 -176.44279) (xy 457.998989 -176.46829)
			(xy 458.079874 -176.501895) (xy 458.118718 -176.522126) (xy 458.130184 -176.527544) (xy 458.155512 -176.527544)
			(xy 458.166978 -176.522126) (xy 458.20581 -176.501866) (xy 458.286688 -176.468235) (xy 458.370484 -176.442726)
			(xy 458.456383 -176.425586) (xy 458.543552 -176.416981) (xy 458.587348 -176.416462) (xy 458.631142 -176.417005)
			(xy 458.718303 -176.425639) (xy 458.804195 -176.44279) (xy 458.887989 -176.46829) (xy 458.968874 -176.501895)
			(xy 459.007718 -176.522126) (xy 459.019184 -176.527544) (xy 459.044512 -176.527544) (xy 459.055978 -176.522126)
			(xy 459.09481 -176.501866) (xy 459.175688 -176.468235) (xy 459.259484 -176.442726) (xy 459.345383 -176.425586)
			(xy 459.432552 -176.416981) (xy 459.476348 -176.416462) (xy 459.520142 -176.417005) (xy 459.607303 -176.425639)
			(xy 459.693195 -176.44279) (xy 459.776989 -176.46829) (xy 459.857874 -176.501895) (xy 459.896718 -176.522126)
			(xy 459.908184 -176.527544) (xy 459.933512 -176.527544) (xy 459.944978 -176.522126) (xy 459.98381 -176.501866)
			(xy 460.064688 -176.468235) (xy 460.148484 -176.442726) (xy 460.234383 -176.425586) (xy 460.321552 -176.416981)
			(xy 460.365348 -176.416462) (xy 460.40645 -176.416921) (xy 460.488304 -176.42451) (xy 460.569109 -176.439618)
			(xy 460.648175 -176.462118) (xy 460.724827 -176.491816) (xy 460.798413 -176.52846) (xy 460.868304 -176.571737)
			(xy 460.933904 -176.621278) (xy 460.994653 -176.676659) (xy 461.050034 -176.73741) (xy 461.099573 -176.803011)
			(xy 461.142849 -176.872903) (xy 461.179491 -176.946489) (xy 461.209188 -177.023143) (xy 461.231686 -177.102209)
			(xy 461.246793 -177.183014) (xy 461.25438 -177.264868) (xy 461.254856 -177.30597) (xy 461.254433 -177.344258)
			(xy 461.247809 -177.420549) (xy 461.234658 -177.495989) (xy 461.215078 -177.570021) (xy 461.202532 -177.606198)
			(xy 461.199904 -177.61464) (xy 461.199894 -177.632304) (xy 461.202532 -177.640742) (xy 461.21511 -177.676909)
			(xy 461.2347 -177.750941) (xy 461.247846 -177.826385) (xy 461.254448 -177.90268) (xy 461.254856 -177.94097)
			(xy 461.254433 -177.979258) (xy 461.247809 -178.055549) (xy 461.234658 -178.130989) (xy 461.215078 -178.205021)
			(xy 461.202532 -178.241198) (xy 461.199904 -178.24964) (xy 461.199894 -178.267304) (xy 461.202532 -178.275742)
			(xy 461.21511 -178.311909) (xy 461.2347 -178.385941) (xy 461.247846 -178.461385) (xy 461.254448 -178.53768)
			(xy 461.254856 -178.57597) (xy 461.254433 -178.614258) (xy 461.247809 -178.690549) (xy 461.234658 -178.765989)
			(xy 461.215078 -178.840021) (xy 461.202532 -178.876198) (xy 461.199904 -178.88464) (xy 461.199894 -178.902304)
			(xy 461.202532 -178.910742) (xy 461.21511 -178.946909) (xy 461.2347 -179.020941) (xy 461.247846 -179.096385)
			(xy 461.254448 -179.17268) (xy 461.254856 -179.21097) (xy 461.254433 -179.249258) (xy 461.247809 -179.325549)
			(xy 461.234658 -179.400989) (xy 461.215078 -179.475021) (xy 461.202532 -179.511198) (xy 461.199904 -179.51964)
			(xy 461.199894 -179.537304) (xy 461.202532 -179.545742) (xy 461.21511 -179.581909) (xy 461.2347 -179.655941)
			(xy 461.247846 -179.731385) (xy 461.254448 -179.80768) (xy 461.254856 -179.84597) (xy 461.254364 -179.889019)
			(xy 461.246048 -179.974715) (xy 461.229492 -180.059206) (xy 461.204851 -180.141702) (xy 461.18907 -180.181758)
			(xy 461.185669 -180.191403) (xy 461.185918 -180.211834) (xy 461.189578 -180.221382) (xy 461.207643 -180.263858)
			(xy 461.235907 -180.351732) (xy 461.254909 -180.442062) (xy 461.264444 -180.533876) (xy 461.265016 -180.58003)
			(xy 461.264578 -180.618318) (xy 461.257958 -180.694608) (xy 461.244811 -180.770048) (xy 461.225236 -180.84408)
			(xy 461.212692 -180.880258) (xy 461.210036 -180.888692) (xy 461.210046 -180.906364) (xy 461.212692 -180.914802)
			(xy 461.225257 -180.950974) (xy 461.244851 -181.025004) (xy 461.258 -181.100446) (xy 461.264607 -181.17674)
			(xy 461.265016 -181.21503) (xy 461.264578 -181.253318) (xy 461.257958 -181.329608) (xy 461.244811 -181.405048)
			(xy 461.225236 -181.47908) (xy 461.212692 -181.515258) (xy 461.210036 -181.523692) (xy 461.210046 -181.541364)
			(xy 461.212692 -181.549802) (xy 461.225257 -181.585974) (xy 461.244851 -181.660004) (xy 461.258 -181.735446)
			(xy 461.264607 -181.81174) (xy 461.265016 -181.85003) (xy 461.264562 -181.891133) (xy 461.256974 -181.972987)
			(xy 461.241867 -182.053793) (xy 461.219368 -182.13286) (xy 461.18967 -182.209513) (xy 461.153027 -182.2831)
			(xy 461.10975 -182.352992) (xy 461.060209 -182.418592) (xy 461.004826 -182.479342) (xy 460.944075 -182.534723)
			(xy 460.878473 -182.584262) (xy 460.808581 -182.627537) (xy 460.734993 -182.664179) (xy 460.658339 -182.693875)
			(xy 460.579271 -182.716372) (xy 460.498466 -182.731478) (xy 460.416611 -182.739063) (xy 460.375508 -182.739538)
			(xy 460.331714 -182.739013) (xy 460.244552 -182.730375) (xy 460.158659 -182.713221) (xy 460.074866 -182.687716)
			(xy 459.993982 -182.654107) (xy 459.955138 -182.633874) (xy 459.943672 -182.628456) (xy 459.918344 -182.628456)
			(xy 459.906878 -182.633874) (xy 459.868035 -182.654113) (xy 459.78716 -182.687748) (xy 459.703367 -182.713261)
			(xy 459.61747 -182.730406) (xy 459.530304 -182.739016) (xy 459.486508 -182.739538) (xy 459.442714 -182.739013)
			(xy 459.355552 -182.730375) (xy 459.269659 -182.713221) (xy 459.185866 -182.687716) (xy 459.104982 -182.654107)
			(xy 459.066138 -182.633874) (xy 459.054672 -182.628456) (xy 459.029344 -182.628456) (xy 459.017878 -182.633874)
			(xy 458.979035 -182.654113) (xy 458.89816 -182.687748) (xy 458.814367 -182.713261) (xy 458.72847 -182.730406)
			(xy 458.641304 -182.739016) (xy 458.597508 -182.739538) (xy 458.556407 -182.739026) (xy 458.474554 -182.731442)
			(xy 458.393751 -182.716338) (xy 458.314685 -182.693843) (xy 458.238033 -182.664149) (xy 458.164447 -182.627509)
			(xy 458.094556 -182.584236) (xy 458.028956 -182.534699) (xy 457.968206 -182.479321) (xy 457.912825 -182.418573)
			(xy 457.863285 -182.352975) (xy 457.820009 -182.283086) (xy 457.783366 -182.209502) (xy 457.753669 -182.132851)
			(xy 457.731171 -182.053786) (xy 457.716063 -181.972984) (xy 457.708476 -181.891131) (xy 457.708 -181.85003)
			(xy 457.708425 -181.811742) (xy 457.715049 -181.735451) (xy 457.7282 -181.660011) (xy 457.747779 -181.585979)
			(xy 457.760324 -181.549802) (xy 457.76295 -181.54136) (xy 457.76296 -181.523696) (xy 457.760324 -181.515258)
			(xy 457.755752 -181.502558) (xy 457.751941 -181.492855) (xy 457.73791 -181.477461) (xy 457.718915 -181.468915)
			(xy 457.708508 -181.468268) (xy 457.666108 -181.467237) (xy 457.581791 -181.458007) (xy 457.498735 -181.440793)
			(xy 457.417695 -181.415752) (xy 457.339407 -181.383111) (xy 457.26458 -181.343166) (xy 457.193896 -181.296281)
			(xy 457.127995 -181.24288) (xy 457.067477 -181.183449) (xy 457.01289 -181.118527) (xy 456.96473 -181.048705)
			(xy 456.923435 -180.974615) (xy 456.88938 -180.896931) (xy 456.862873 -180.816359) (xy 456.853036 -180.775102)
			(xy 456.84988 -180.764103) (xy 456.835715 -180.74618) (xy 456.815179 -180.73617) (xy 456.80376 -180.735478)
			(xy 456.760264 -180.734739) (xy 456.673736 -180.725697) (xy 456.588503 -180.708251) (xy 456.505382 -180.682567)
			(xy 456.425164 -180.648891) (xy 456.348617 -180.607545) (xy 456.276473 -180.558924) (xy 456.209419 -180.503491)
			(xy 456.148098 -180.441778) (xy 456.093094 -180.374372) (xy 456.044933 -180.301919) (xy 456.004076 -180.22511)
			(xy 455.970912 -180.14468) (xy 455.945759 -180.061396) (xy 455.928856 -179.976054) (xy 455.920366 -179.88947)
			(xy 455.91984 -179.84597) (xy 446.376973 -179.84597) (xy 446.382811 -179.868032) (xy 446.395956 -179.943475)
			(xy 446.40256 -180.01977) (xy 446.402968 -180.05806) (xy 446.402542 -180.096348) (xy 446.395918 -180.172639)
			(xy 446.382768 -180.248079) (xy 446.363189 -180.322111) (xy 446.350644 -180.358288) (xy 446.348021 -180.366731)
			(xy 446.348008 -180.384395) (xy 446.350644 -180.392832) (xy 446.36322 -180.429) (xy 446.382811 -180.503032)
			(xy 446.395956 -180.578475) (xy 446.40256 -180.65477) (xy 446.402968 -180.69306) (xy 446.402542 -180.731348)
			(xy 446.395918 -180.807639) (xy 446.382768 -180.883079) (xy 446.363189 -180.957111) (xy 446.350644 -180.993288)
			(xy 446.348021 -181.001731) (xy 446.348008 -181.019395) (xy 446.350644 -181.027832) (xy 446.36322 -181.064)
			(xy 446.382811 -181.138032) (xy 446.395956 -181.213475) (xy 446.40256 -181.28977) (xy 446.402968 -181.32806)
			(xy 446.40251 -181.369164) (xy 446.394928 -181.451021) (xy 446.379825 -181.531829) (xy 446.35733 -181.610899)
			(xy 446.327635 -181.687555) (xy 446.290994 -181.761145) (xy 446.247718 -181.83104) (xy 446.198178 -181.896643)
			(xy 446.142795 -181.957395) (xy 446.082043 -182.012778) (xy 446.01644 -182.062318) (xy 445.946545 -182.105594)
			(xy 445.872955 -182.142235) (xy 445.796299 -182.17193) (xy 445.717229 -182.194425) (xy 445.636421 -182.209528)
			(xy 445.554564 -182.21711) (xy 445.51346 -182.217568) (xy 445.475172 -182.217136) (xy 445.398882 -182.210514)
			(xy 445.323442 -182.197366) (xy 445.24941 -182.177789) (xy 445.213232 -182.165244) (xy 445.204794 -182.162602)
			(xy 445.187126 -182.162602) (xy 445.178688 -182.165244) (xy 445.142518 -182.177814) (xy 445.068487 -182.197406)
			(xy 444.993044 -182.210554) (xy 444.91675 -182.217159) (xy 444.87846 -182.217568) (xy 444.840172 -182.217136)
			(xy 444.763882 -182.210514) (xy 444.688442 -182.197366) (xy 444.61441 -182.177789) (xy 444.578232 -182.165244)
			(xy 444.569794 -182.162602) (xy 444.552126 -182.162602) (xy 444.543688 -182.165244) (xy 444.507518 -182.177814)
			(xy 444.433487 -182.197406) (xy 444.358044 -182.210554) (xy 444.28175 -182.217159) (xy 444.24346 -182.217568)
			(xy 444.205172 -182.217136) (xy 444.128882 -182.210514) (xy 444.053442 -182.197366) (xy 443.97941 -182.177789)
			(xy 443.943232 -182.165244) (xy 443.934794 -182.162602) (xy 443.917126 -182.162602) (xy 443.908688 -182.165244)
			(xy 443.872518 -182.177814) (xy 443.798487 -182.197406) (xy 443.723044 -182.210554) (xy 443.64675 -182.217159)
			(xy 443.60846 -182.217568) (xy 443.570172 -182.217136) (xy 443.493882 -182.210514) (xy 443.418442 -182.197366)
			(xy 443.34441 -182.177789) (xy 443.308232 -182.165244) (xy 443.299794 -182.162602) (xy 443.282126 -182.162602)
			(xy 443.273688 -182.165244) (xy 443.237518 -182.177814) (xy 443.163487 -182.197406) (xy 443.088044 -182.210554)
			(xy 443.01175 -182.217159) (xy 442.97346 -182.217568) (xy 442.932356 -182.217171) (xy 442.850498 -182.209583)
			(xy 442.76969 -182.194473) (xy 442.69062 -182.171972) (xy 442.613964 -182.142271) (xy 442.540376 -182.105625)
			(xy 442.470483 -182.062344) (xy 442.404881 -182.012799) (xy 442.34413 -181.957413) (xy 442.28875 -181.896658)
			(xy 442.239211 -181.831051) (xy 442.195937 -181.761154) (xy 442.159296 -181.687562) (xy 442.129602 -181.610904)
			(xy 442.107109 -181.531832) (xy 442.092006 -181.451023) (xy 442.084425 -181.369164) (xy 442.083952 -181.32806)
			(xy 428.054516 -181.32806) (xy 424.168062 -185.214514) (xy 424.161211 -185.22191) (xy 424.153472 -185.240509)
			(xy 424.153076 -185.250582) (xy 424.153076 -186.5851) (xy 427.63843 -186.5851) (xy 427.642421 -186.496233)
			(xy 427.654362 -186.408081) (xy 427.674157 -186.321355) (xy 427.701647 -186.236752) (xy 427.73661 -186.154954)
			(xy 427.778764 -186.076619) (xy 427.827771 -186.002379) (xy 427.883235 -185.93283) (xy 427.944711 -185.868534)
			(xy 428.011703 -185.810006) (xy 428.083671 -185.75772) (xy 428.160037 -185.712096) (xy 428.240185 -185.6735)
			(xy 428.32347 -185.642245) (xy 428.409221 -185.618581) (xy 428.496749 -185.602699) (xy 428.585348 -185.594727)
			(xy 428.629826 -185.594244) (xy 430.382426 -185.594244) (xy 430.426902 -185.594748) (xy 430.515496 -185.602724)
			(xy 430.603018 -185.618609) (xy 430.688764 -185.642275) (xy 430.772044 -185.673532) (xy 430.852186 -185.712129)
			(xy 430.928546 -185.757754) (xy 431.000509 -185.810039) (xy 431.067496 -185.868565) (xy 431.128966 -185.93286)
			(xy 431.184426 -186.002407) (xy 431.233429 -186.076644) (xy 431.27558 -186.154975) (xy 431.31054 -186.23677)
			(xy 431.338027 -186.321368) (xy 431.357821 -186.40809) (xy 431.369761 -186.496237) (xy 431.373752 -186.5851)
			(xy 435.182544 -186.5851) (xy 435.186535 -186.496237) (xy 435.198476 -186.408089) (xy 435.218269 -186.321366)
			(xy 435.245757 -186.236767) (xy 435.280717 -186.154972) (xy 435.322869 -186.07664) (xy 435.371872 -186.002402)
			(xy 435.427332 -185.932856) (xy 435.488804 -185.86856) (xy 435.555791 -185.810034) (xy 435.627755 -185.757748)
			(xy 435.704116 -185.712123) (xy 435.784259 -185.673527) (xy 435.867539 -185.64227) (xy 435.953286 -185.618604)
			(xy 436.040809 -185.602719) (xy 436.129404 -185.594744) (xy 436.17388 -185.594244) (xy 437.92648 -185.594244)
			(xy 437.970958 -185.594731) (xy 438.059556 -185.602704) (xy 438.147083 -185.618586) (xy 438.232834 -185.64225)
			(xy 438.316118 -185.673506) (xy 438.396265 -185.712101) (xy 438.47263 -185.757726) (xy 438.544598 -185.810012)
			(xy 438.611589 -185.868539) (xy 438.673063 -185.932835) (xy 438.728527 -186.002383) (xy 438.777533 -186.076623)
			(xy 438.819687 -186.154957) (xy 438.85465 -186.236755) (xy 438.882139 -186.321357) (xy 438.901934 -186.408083)
			(xy 438.913875 -186.496233) (xy 438.917866 -186.5851) (xy 442.72653 -186.5851) (xy 442.730521 -186.496232)
			(xy 442.742462 -186.40808) (xy 442.762258 -186.321353) (xy 442.789748 -186.23675) (xy 442.824711 -186.154952)
			(xy 442.866866 -186.076617) (xy 442.915873 -186.002376) (xy 442.971338 -185.932828) (xy 443.032814 -185.868531)
			(xy 443.099806 -185.810004) (xy 443.171775 -185.757717) (xy 443.248141 -185.712093) (xy 443.32829 -185.673498)
			(xy 443.411576 -185.642243) (xy 443.497328 -185.618579) (xy 443.584856 -185.602698) (xy 443.673455 -185.594727)
			(xy 443.717934 -185.594244) (xy 445.470534 -185.594244) (xy 445.51501 -185.594748) (xy 445.603603 -185.602725)
			(xy 445.691125 -185.61861) (xy 445.77687 -185.642277) (xy 445.860149 -185.673535) (xy 445.940291 -185.712131)
			(xy 446.01665 -185.757756) (xy 446.088613 -185.810042) (xy 446.155599 -185.868568) (xy 446.217069 -185.932863)
			(xy 446.272528 -186.002409) (xy 446.32153 -186.076647) (xy 446.363681 -186.154977) (xy 446.398641 -186.236771)
			(xy 446.426128 -186.32137) (xy 446.445921 -186.408091) (xy 446.457861 -186.496238) (xy 446.461852 -186.5851)
			(xy 450.27033 -186.5851) (xy 450.274321 -186.496232) (xy 450.286262 -186.40808) (xy 450.306058 -186.321353)
			(xy 450.333548 -186.23675) (xy 450.368511 -186.154952) (xy 450.410666 -186.076617) (xy 450.459673 -186.002376)
			(xy 450.515138 -185.932828) (xy 450.576614 -185.868531) (xy 450.643606 -185.810004) (xy 450.715575 -185.757717)
			(xy 450.791941 -185.712093) (xy 450.87209 -185.673498) (xy 450.955376 -185.642243) (xy 451.041128 -185.618579)
			(xy 451.128656 -185.602698) (xy 451.217255 -185.594727) (xy 451.261734 -185.594244) (xy 453.014334 -185.594244)
			(xy 453.05881 -185.594748) (xy 453.147403 -185.602725) (xy 453.234925 -185.61861) (xy 453.32067 -185.642277)
			(xy 453.403949 -185.673535) (xy 453.484091 -185.712131) (xy 453.56045 -185.757756) (xy 453.632413 -185.810042)
			(xy 453.699399 -185.868568) (xy 453.760869 -185.932863) (xy 453.816328 -186.002409) (xy 453.86533 -186.076647)
			(xy 453.907481 -186.154977) (xy 453.942441 -186.236771) (xy 453.969928 -186.32137) (xy 453.989721 -186.408091)
			(xy 454.001661 -186.496238) (xy 454.005652 -186.5851) (xy 454.001661 -186.673962) (xy 453.989721 -186.762109)
			(xy 453.969928 -186.84883) (xy 453.942441 -186.933429) (xy 453.907481 -187.015223) (xy 453.86533 -187.093553)
			(xy 453.816328 -187.167791) (xy 453.760869 -187.237337) (xy 453.699399 -187.301632) (xy 453.632413 -187.360158)
			(xy 453.56045 -187.412444) (xy 453.484091 -187.458069) (xy 453.403949 -187.496665) (xy 453.32067 -187.527923)
			(xy 453.234925 -187.55159) (xy 453.147403 -187.567475) (xy 453.05881 -187.575452) (xy 453.014334 -187.575952)
			(xy 451.261734 -187.575952) (xy 451.217255 -187.575473) (xy 451.128656 -187.567502) (xy 451.041128 -187.551621)
			(xy 450.955376 -187.527957) (xy 450.87209 -187.496702) (xy 450.791941 -187.458107) (xy 450.715575 -187.412483)
			(xy 450.643606 -187.360196) (xy 450.576614 -187.301669) (xy 450.515138 -187.237372) (xy 450.459673 -187.167824)
			(xy 450.410666 -187.093583) (xy 450.368511 -187.015248) (xy 450.333548 -186.93345) (xy 450.306058 -186.848847)
			(xy 450.286262 -186.76212) (xy 450.274321 -186.673968) (xy 450.27033 -186.5851) (xy 446.461852 -186.5851)
			(xy 446.457861 -186.673962) (xy 446.445921 -186.762109) (xy 446.426128 -186.84883) (xy 446.398641 -186.933429)
			(xy 446.363681 -187.015223) (xy 446.32153 -187.093553) (xy 446.272528 -187.167791) (xy 446.217069 -187.237337)
			(xy 446.155599 -187.301632) (xy 446.088613 -187.360158) (xy 446.01665 -187.412444) (xy 445.940291 -187.458069)
			(xy 445.860149 -187.496665) (xy 445.77687 -187.527923) (xy 445.691125 -187.55159) (xy 445.603603 -187.567475)
			(xy 445.51501 -187.575452) (xy 445.470534 -187.575952) (xy 443.717934 -187.575952) (xy 443.673455 -187.575473)
			(xy 443.584856 -187.567502) (xy 443.497328 -187.551621) (xy 443.411576 -187.527957) (xy 443.32829 -187.496702)
			(xy 443.248141 -187.458107) (xy 443.171775 -187.412483) (xy 443.099806 -187.360196) (xy 443.032814 -187.301669)
			(xy 442.971338 -187.237372) (xy 442.915873 -187.167824) (xy 442.866866 -187.093583) (xy 442.824711 -187.015248)
			(xy 442.789748 -186.93345) (xy 442.762258 -186.848847) (xy 442.742462 -186.76212) (xy 442.730521 -186.673968)
			(xy 442.72653 -186.5851) (xy 438.917866 -186.5851) (xy 438.913875 -186.673967) (xy 438.901934 -186.762117)
			(xy 438.882139 -186.848843) (xy 438.85465 -186.933445) (xy 438.819687 -187.015243) (xy 438.777533 -187.093577)
			(xy 438.728527 -187.167817) (xy 438.673063 -187.237365) (xy 438.611589 -187.301661) (xy 438.544598 -187.360188)
			(xy 438.47263 -187.412474) (xy 438.396265 -187.458099) (xy 438.316118 -187.496694) (xy 438.232834 -187.52795)
			(xy 438.147083 -187.551614) (xy 438.059556 -187.567496) (xy 437.970958 -187.575469) (xy 437.92648 -187.575952)
			(xy 436.17388 -187.575952) (xy 436.129404 -187.575456) (xy 436.040809 -187.567481) (xy 435.953286 -187.551596)
			(xy 435.867539 -187.52793) (xy 435.784259 -187.496673) (xy 435.704116 -187.458077) (xy 435.627755 -187.412452)
			(xy 435.555791 -187.360166) (xy 435.488804 -187.30164) (xy 435.427332 -187.237344) (xy 435.371872 -187.167798)
			(xy 435.322869 -187.09356) (xy 435.280717 -187.015228) (xy 435.245757 -186.933433) (xy 435.218269 -186.848834)
			(xy 435.198476 -186.762111) (xy 435.186535 -186.673963) (xy 435.182544 -186.5851) (xy 431.373752 -186.5851)
			(xy 431.369761 -186.673963) (xy 431.357821 -186.76211) (xy 431.338027 -186.848832) (xy 431.31054 -186.93343)
			(xy 431.27558 -187.015225) (xy 431.233429 -187.093556) (xy 431.184426 -187.167793) (xy 431.128966 -187.23734)
			(xy 431.067496 -187.301635) (xy 431.000509 -187.360161) (xy 430.928546 -187.412446) (xy 430.852186 -187.458071)
			(xy 430.772044 -187.496668) (xy 430.688764 -187.527925) (xy 430.603018 -187.551591) (xy 430.515496 -187.567476)
			(xy 430.426902 -187.575452) (xy 430.382426 -187.575952) (xy 428.629826 -187.575952) (xy 428.585348 -187.575473)
			(xy 428.496749 -187.567501) (xy 428.409221 -187.551619) (xy 428.32347 -187.527955) (xy 428.240185 -187.4967)
			(xy 428.160037 -187.458104) (xy 428.083671 -187.41248) (xy 428.011703 -187.360194) (xy 427.944711 -187.301666)
			(xy 427.883235 -187.23737) (xy 427.827771 -187.167821) (xy 427.778764 -187.093581) (xy 427.73661 -187.015246)
			(xy 427.701647 -186.933448) (xy 427.674157 -186.848845) (xy 427.654362 -186.762119) (xy 427.642421 -186.673967)
			(xy 427.63843 -186.5851) (xy 424.153076 -186.5851) (xy 424.153076 -187.218574) (xy 424.152639 -187.228638)
			(xy 424.144903 -187.24722) (xy 424.13809 -187.254642) (xy 423.5704 -187.822332) (xy 423.563005 -187.829186)
			(xy 423.544406 -187.836931) (xy 423.534332 -187.837318) (xy 419.039802 -187.837318) (xy 419.029732 -187.837741)
			(xy 419.011129 -187.845457) (xy 419.003734 -187.852304) (xy 416.604196 -190.251842) (xy 450.972426 -190.251842)
			(xy 450.976497 -190.19622) (xy 450.988623 -190.141783) (xy 451.008546 -190.089692) (xy 451.035842 -190.041057)
			(xy 451.069928 -189.996914) (xy 451.110077 -189.958205) (xy 451.155435 -189.925754) (xy 451.205035 -189.900253)
			(xy 451.257819 -189.882246) (xy 451.312662 -189.872116) (xy 451.368396 -189.870079) (xy 451.423833 -189.876179)
			(xy 451.47779 -189.890285) (xy 451.529119 -189.912097) (xy 451.576725 -189.941151) (xy 451.619593 -189.976826)
			(xy 451.65681 -190.018363) (xy 451.687583 -190.064876) (xy 451.711255 -190.115373) (xy 451.727323 -190.16878)
			(xy 451.735443 -190.223956) (xy 451.735952 -190.251842) (xy 451.735443 -190.279728) (xy 451.727323 -190.334904)
			(xy 451.711255 -190.388311) (xy 451.687583 -190.438808) (xy 451.65681 -190.485321) (xy 451.619593 -190.526858)
			(xy 451.576725 -190.562533) (xy 451.529119 -190.591587) (xy 451.47779 -190.613399) (xy 451.423833 -190.627505)
			(xy 451.368396 -190.633605) (xy 451.312662 -190.631568) (xy 451.257819 -190.621438) (xy 451.205035 -190.603431)
			(xy 451.155435 -190.57793) (xy 451.110077 -190.545479) (xy 451.069928 -190.50677) (xy 451.035842 -190.462627)
			(xy 451.008546 -190.413992) (xy 450.988623 -190.361901) (xy 450.976497 -190.307464) (xy 450.972426 -190.251842)
			(xy 416.604196 -190.251842) (xy 415.610548 -191.24549) (xy 415.603147 -191.252329) (xy 415.584549 -191.260047)
			(xy 415.57448 -191.260476) (xy 412.7373 -191.260476) (xy 412.727229 -191.260898) (xy 412.708623 -191.26861)
			(xy 412.701232 -191.275462) (xy 412.64967 -191.327024) (xy 412.64282 -191.33442) (xy 412.635083 -191.353019)
			(xy 412.634684 -191.363092) (xy 412.634684 -192.21831) (xy 413.154383 -192.21831) (xy 413.158318 -192.164539)
			(xy 413.170041 -192.111915) (xy 413.189301 -192.061558) (xy 413.215687 -192.014541) (xy 413.248639 -191.971868)
			(xy 413.287452 -191.934447) (xy 413.3313 -191.903077) (xy 413.379248 -191.878425) (xy 413.430275 -191.861017)
			(xy 413.483293 -191.851224) (xy 413.537172 -191.849255) (xy 413.590763 -191.855152) (xy 413.642924 -191.868788)
			(xy 413.692544 -191.889875) (xy 413.738565 -191.917961) (xy 413.780007 -191.952449) (xy 413.815985 -191.992603)
			(xy 413.845733 -192.037567) (xy 413.868618 -192.086384) (xy 413.88415 -192.138013) (xy 413.892 -192.191353)
			(xy 413.892492 -192.21831) (xy 414.943051 -192.21831) (xy 414.946986 -192.164539) (xy 414.958709 -192.111915)
			(xy 414.977969 -192.061558) (xy 415.004355 -192.014541) (xy 415.037307 -191.971868) (xy 415.07612 -191.934447)
			(xy 415.119968 -191.903077) (xy 415.167916 -191.878425) (xy 415.218943 -191.861017) (xy 415.271961 -191.851224)
			(xy 415.32584 -191.849255) (xy 415.379431 -191.855152) (xy 415.431592 -191.868788) (xy 415.481212 -191.889875)
			(xy 415.527233 -191.917961) (xy 415.568675 -191.952449) (xy 415.604653 -191.992603) (xy 415.634401 -192.037567)
			(xy 415.657286 -192.086384) (xy 415.672818 -192.138013) (xy 415.680668 -192.191353) (xy 415.68116 -192.21831)
			(xy 415.680668 -192.245267) (xy 415.672818 -192.298607) (xy 415.657286 -192.350236) (xy 415.634401 -192.399053)
			(xy 415.604653 -192.444017) (xy 415.568675 -192.484171) (xy 415.527233 -192.518659) (xy 415.481212 -192.546745)
			(xy 415.431592 -192.567832) (xy 415.379431 -192.581468) (xy 415.32584 -192.587365) (xy 415.271961 -192.585396)
			(xy 415.218943 -192.575603) (xy 415.167916 -192.558195) (xy 415.119968 -192.533543) (xy 415.07612 -192.502173)
			(xy 415.037307 -192.464752) (xy 415.004355 -192.422079) (xy 414.977969 -192.375062) (xy 414.958709 -192.324705)
			(xy 414.946986 -192.272081) (xy 414.943051 -192.21831) (xy 413.892492 -192.21831) (xy 413.892 -192.245267)
			(xy 413.88415 -192.298607) (xy 413.868618 -192.350236) (xy 413.845733 -192.399053) (xy 413.815985 -192.444017)
			(xy 413.780007 -192.484171) (xy 413.738565 -192.518659) (xy 413.692544 -192.546745) (xy 413.642924 -192.567832)
			(xy 413.590763 -192.581468) (xy 413.537172 -192.587365) (xy 413.483293 -192.585396) (xy 413.430275 -192.575603)
			(xy 413.379248 -192.558195) (xy 413.3313 -192.533543) (xy 413.287452 -192.502173) (xy 413.248639 -192.464752)
			(xy 413.215687 -192.422079) (xy 413.189301 -192.375062) (xy 413.170041 -192.324705) (xy 413.158318 -192.272081)
			(xy 413.154383 -192.21831) (xy 412.634684 -192.21831) (xy 412.634684 -193.10731) (xy 413.154383 -193.10731)
			(xy 413.158318 -193.053539) (xy 413.170041 -193.000915) (xy 413.189301 -192.950558) (xy 413.215687 -192.903541)
			(xy 413.248639 -192.860868) (xy 413.287452 -192.823447) (xy 413.3313 -192.792077) (xy 413.379248 -192.767425)
			(xy 413.430275 -192.750017) (xy 413.483293 -192.740224) (xy 413.537172 -192.738255) (xy 413.590763 -192.744152)
			(xy 413.642924 -192.757788) (xy 413.692544 -192.778875) (xy 413.738565 -192.806961) (xy 413.780007 -192.841449)
			(xy 413.815985 -192.881603) (xy 413.845733 -192.926567) (xy 413.868618 -192.975384) (xy 413.88415 -193.027013)
			(xy 413.892 -193.080353) (xy 413.892492 -193.10731) (xy 413.892 -193.134267) (xy 413.88415 -193.187607)
			(xy 413.868618 -193.239236) (xy 413.845733 -193.288053) (xy 413.815985 -193.333017) (xy 413.780007 -193.373171)
			(xy 413.738565 -193.407659) (xy 413.692544 -193.435745) (xy 413.642924 -193.456832) (xy 413.590763 -193.470468)
			(xy 413.537172 -193.476365) (xy 413.483293 -193.474396) (xy 413.430275 -193.464603) (xy 413.379248 -193.447195)
			(xy 413.3313 -193.422543) (xy 413.287452 -193.391173) (xy 413.248639 -193.353752) (xy 413.215687 -193.311079)
			(xy 413.189301 -193.264062) (xy 413.170041 -193.213705) (xy 413.158318 -193.161081) (xy 413.154383 -193.10731)
			(xy 412.634684 -193.10731) (xy 412.634684 -194.132708) (xy 412.635142 -194.142586) (xy 412.642581 -194.160889)
			(xy 412.649162 -194.168268) (xy 412.649416 -194.168522) (xy 412.796228 -194.315334) (xy 412.796736 -194.315842)
			(xy 412.804116 -194.322428) (xy 412.822415 -194.329886) (xy 412.832296 -194.33032) (xy 414.325054 -194.33032)
		)
		(stroke
			(width 0)
			(type solid)
		)
		(fill yes)
		(layer "In11.Cu")
		(net "P3V3")
	)
	(gr_poly
		(pts
			(xy 33.281112 -418.84727) (xy 33.291181 -418.846844) (xy 33.309779 -418.839123) (xy 33.31718 -418.832284)
			(xy 33.430464 -418.719) (xy 33.438049 -418.710483) (xy 33.445576 -418.688985) (xy 33.444942 -418.677598)
			(xy 33.435036 -418.587174) (xy 33.422844 -418.567616) (xy 33.413192 -418.56152) (xy 33.390311 -418.546433)
			(xy 33.348721 -418.510739) (xy 33.312666 -418.469462) (xy 33.282887 -418.423452) (xy 33.259998 -418.373654)
			(xy 33.24447 -418.321093) (xy 33.236621 -418.266851) (xy 33.236154 -418.239448) (xy 33.236614 -418.212192)
			(xy 33.244365 -418.158234) (xy 33.259716 -418.105928) (xy 33.282356 -418.056339) (xy 33.311822 -418.010477)
			(xy 33.347515 -417.969276) (xy 33.388708 -417.933573) (xy 33.434564 -417.904097) (xy 33.484147 -417.881446)
			(xy 33.53645 -417.866083) (xy 33.590406 -417.85832) (xy 33.617662 -417.85794) (xy 33.641236 -417.858289)
			(xy 33.688025 -417.864097) (xy 33.733741 -417.875628) (xy 33.755838 -417.883848) (xy 33.767776 -417.88842)
			(xy 33.792414 -417.885626) (xy 33.87217 -417.831016) (xy 33.882071 -417.823494) (xy 33.893663 -417.801525)
			(xy 33.894268 -417.789106) (xy 33.894268 -396.16126) (xy 33.893837 -396.151194) (xy 33.886109 -396.132603)
			(xy 33.879282 -396.125192) (xy 30.327854 -392.573764) (xy 30.321007 -392.566366) (xy 30.313278 -392.547767)
			(xy 30.312868 -392.537696) (xy 30.312868 -383.359914) (xy 30.312428 -383.349851) (xy 30.304689 -383.331273)
			(xy 30.297882 -383.323846) (xy 29.163518 -382.189482) (xy 29.156672 -382.182083) (xy 29.148942 -382.163485)
			(xy 29.148532 -382.153414) (xy 29.148532 -376.526806) (xy 29.148111 -376.516735) (xy 29.140402 -376.498126)
			(xy 29.133546 -376.490738) (xy 28.425902 -375.783094) (xy 28.419056 -375.775695) (xy 28.411324 -375.757097)
			(xy 28.410916 -375.747026) (xy 28.410916 -373.14505) (xy 28.390088 -373.117618) (xy 28.373324 -373.1133)
			(xy 28.346745 -373.105545) (xy 28.295992 -373.083423) (xy 28.248967 -373.054201) (xy 28.206657 -373.018492)
			(xy 28.169949 -372.977046) (xy 28.139613 -372.930732) (xy 28.116287 -372.880521) (xy 28.100458 -372.827467)
			(xy 28.09246 -372.772682) (xy 28.09246 -372.717318) (xy 28.100458 -372.662533) (xy 28.116287 -372.609479)
			(xy 28.139613 -372.559268) (xy 28.169949 -372.512954) (xy 28.206657 -372.471508) (xy 28.248967 -372.435799)
			(xy 28.295992 -372.406577) (xy 28.346745 -372.384455) (xy 28.373324 -372.3767) (xy 28.390088 -372.372382)
			(xy 28.410916 -372.34495) (xy 28.410916 -371.62613) (xy 28.410384 -371.61614) (xy 28.40268 -371.597698)
			(xy 28.39593 -371.590316) (xy 26.298144 -369.49253) (xy 26.290797 -369.485725) (xy 26.272334 -369.478008)
			(xy 26.26233 -369.477544) (xy 7.057136 -369.477544) (xy 7.047072 -369.47798) (xy 7.028489 -369.485716)
			(xy 7.021068 -369.49253) (xy 6.467856 -370.045488) (xy 6.461002 -370.052883) (xy 6.453254 -370.071482)
			(xy 6.45287 -370.081556) (xy 6.45287 -376.70105) (xy 8.208781 -376.70105) (xy 8.21251 -376.647799)
			(xy 8.223627 -376.595587) (xy 8.241913 -376.545435) (xy 8.267012 -376.498321) (xy 8.298433 -376.455167)
			(xy 8.335563 -376.416813) (xy 8.356346 -376.40006) (xy 8.365129 -376.392519) (xy 8.375299 -376.371744)
			(xy 8.375904 -376.360182) (xy 8.375904 -376.279918) (xy 8.375322 -376.268352) (xy 8.365135 -376.247581)
			(xy 8.356346 -376.24004) (xy 8.335563 -376.223287) (xy 8.298433 -376.184933) (xy 8.267012 -376.141779)
			(xy 8.241913 -376.094665) (xy 8.223627 -376.044513) (xy 8.21251 -375.992301) (xy 8.208781 -375.93905)
			(xy 8.21251 -375.885799) (xy 8.223627 -375.833587) (xy 8.241913 -375.783435) (xy 8.267012 -375.736321)
			(xy 8.298433 -375.693167) (xy 8.335563 -375.654813) (xy 8.356346 -375.63806) (xy 8.365129 -375.630519)
			(xy 8.375299 -375.609744) (xy 8.375904 -375.598182) (xy 8.375904 -375.517918) (xy 8.375322 -375.506352)
			(xy 8.365135 -375.485581) (xy 8.356346 -375.47804) (xy 8.33387 -375.45984) (xy 8.294137 -375.417821)
			(xy 8.261199 -375.370287) (xy 8.23581 -375.318328) (xy 8.218551 -375.263133) (xy 8.209818 -375.205965)
			(xy 8.20928 -375.17705) (xy 8.209766 -375.149799) (xy 8.217522 -375.095851) (xy 8.232877 -375.043556)
			(xy 8.255519 -374.993979) (xy 8.284985 -374.948129) (xy 8.320676 -374.906938) (xy 8.361867 -374.871247)
			(xy 8.407717 -374.841781) (xy 8.457294 -374.819139) (xy 8.509589 -374.803784) (xy 8.563537 -374.796028)
			(xy 8.618039 -374.796028) (xy 8.671987 -374.803784) (xy 8.724282 -374.819139) (xy 8.773859 -374.841781)
			(xy 8.819709 -374.871247) (xy 8.8609 -374.906938) (xy 8.896591 -374.948129) (xy 8.926057 -374.993979)
			(xy 8.948699 -375.043556) (xy 8.964054 -375.095851) (xy 8.97181 -375.149799) (xy 8.972296 -375.17705)
			(xy 8.971743 -375.205966) (xy 8.963022 -375.263135) (xy 8.945771 -375.318334) (xy 8.920385 -375.370295)
			(xy 8.887448 -375.41783) (xy 8.847713 -375.459849) (xy 8.82523 -375.47804) (xy 8.816443 -375.485577)
			(xy 8.806276 -375.506355) (xy 8.805672 -375.517918) (xy 8.805672 -375.598182) (xy 8.806228 -375.609752)
			(xy 8.81643 -375.630525) (xy 8.82523 -375.63806) (xy 8.846013 -375.654813) (xy 8.883144 -375.693166)
			(xy 8.914565 -375.736321) (xy 8.939664 -375.783435) (xy 8.95795 -375.833587) (xy 8.969067 -375.885798)
			(xy 8.972797 -375.93905) (xy 8.969067 -375.992302) (xy 8.95795 -376.044513) (xy 8.939664 -376.094665)
			(xy 8.914565 -376.141779) (xy 8.883144 -376.184934) (xy 8.846013 -376.223287) (xy 8.82523 -376.24004)
			(xy 8.816443 -376.247577) (xy 8.806276 -376.268355) (xy 8.805672 -376.279918) (xy 8.805672 -376.360182)
			(xy 8.806228 -376.371752) (xy 8.81643 -376.392525) (xy 8.82523 -376.40006) (xy 8.846013 -376.416813)
			(xy 8.883144 -376.455166) (xy 8.914565 -376.498321) (xy 8.939664 -376.545435) (xy 8.95795 -376.595587)
			(xy 8.969067 -376.647798) (xy 8.972797 -376.70105) (xy 10.494781 -376.70105) (xy 10.49851 -376.647799)
			(xy 10.509627 -376.595587) (xy 10.527913 -376.545435) (xy 10.553012 -376.498321) (xy 10.584433 -376.455167)
			(xy 10.621563 -376.416813) (xy 10.642346 -376.40006) (xy 10.651129 -376.392519) (xy 10.661299 -376.371744)
			(xy 10.661904 -376.360182) (xy 10.661904 -376.279918) (xy 10.661322 -376.268352) (xy 10.651135 -376.247581)
			(xy 10.642346 -376.24004) (xy 10.621563 -376.223287) (xy 10.584433 -376.184933) (xy 10.553012 -376.141779)
			(xy 10.527913 -376.094665) (xy 10.509627 -376.044513) (xy 10.49851 -375.992301) (xy 10.494781 -375.93905)
			(xy 10.49851 -375.885799) (xy 10.509627 -375.833587) (xy 10.527913 -375.783435) (xy 10.553012 -375.736321)
			(xy 10.584433 -375.693167) (xy 10.621563 -375.654813) (xy 10.642346 -375.63806) (xy 10.651129 -375.630519)
			(xy 10.661299 -375.609744) (xy 10.661904 -375.598182) (xy 10.661904 -375.517918) (xy 10.661322 -375.506352)
			(xy 10.651135 -375.485581) (xy 10.642346 -375.47804) (xy 10.61987 -375.45984) (xy 10.580137 -375.417821)
			(xy 10.547199 -375.370287) (xy 10.52181 -375.318328) (xy 10.504551 -375.263133) (xy 10.495818 -375.205965)
			(xy 10.49528 -375.17705) (xy 10.495766 -375.149799) (xy 10.503522 -375.095851) (xy 10.518877 -375.043556)
			(xy 10.541519 -374.993979) (xy 10.570985 -374.948129) (xy 10.606676 -374.906938) (xy 10.647867 -374.871247)
			(xy 10.693717 -374.841781) (xy 10.743294 -374.819139) (xy 10.795589 -374.803784) (xy 10.849537 -374.796028)
			(xy 10.904039 -374.796028) (xy 10.957987 -374.803784) (xy 11.010282 -374.819139) (xy 11.059859 -374.841781)
			(xy 11.105709 -374.871247) (xy 11.1469 -374.906938) (xy 11.182591 -374.948129) (xy 11.212057 -374.993979)
			(xy 11.234699 -375.043556) (xy 11.250054 -375.095851) (xy 11.25781 -375.149799) (xy 11.258296 -375.17705)
			(xy 11.257743 -375.205966) (xy 11.249022 -375.263135) (xy 11.231771 -375.318334) (xy 11.206385 -375.370295)
			(xy 11.173448 -375.41783) (xy 11.133713 -375.459849) (xy 11.11123 -375.47804) (xy 11.102443 -375.485577)
			(xy 11.092276 -375.506355) (xy 11.091672 -375.517918) (xy 11.091672 -375.598182) (xy 11.092228 -375.609752)
			(xy 11.10243 -375.630525) (xy 11.11123 -375.63806) (xy 11.132013 -375.654813) (xy 11.169144 -375.693166)
			(xy 11.200565 -375.736321) (xy 11.225664 -375.783435) (xy 11.24395 -375.833587) (xy 11.255067 -375.885798)
			(xy 11.258797 -375.93905) (xy 11.255067 -375.992302) (xy 11.24395 -376.044513) (xy 11.225664 -376.094665)
			(xy 11.200565 -376.141779) (xy 11.169144 -376.184934) (xy 11.132013 -376.223287) (xy 11.11123 -376.24004)
			(xy 11.102443 -376.247577) (xy 11.092276 -376.268355) (xy 11.091672 -376.279918) (xy 11.091672 -376.360182)
			(xy 11.092228 -376.371752) (xy 11.10243 -376.392525) (xy 11.11123 -376.40006) (xy 11.132013 -376.416813)
			(xy 11.169144 -376.455166) (xy 11.200565 -376.498321) (xy 11.225664 -376.545435) (xy 11.24395 -376.595587)
			(xy 11.255067 -376.647798) (xy 11.258797 -376.70105) (xy 11.255067 -376.754302) (xy 11.24395 -376.806513)
			(xy 11.225664 -376.856665) (xy 11.200565 -376.903779) (xy 11.169144 -376.946934) (xy 11.132013 -376.985287)
			(xy 11.11123 -377.00204) (xy 11.102443 -377.009577) (xy 11.092276 -377.030355) (xy 11.091672 -377.041918)
			(xy 11.091672 -377.122182) (xy 11.092228 -377.133752) (xy 11.10243 -377.154525) (xy 11.11123 -377.16206)
			(xy 11.133701 -377.180266) (xy 11.173435 -377.222284) (xy 11.206375 -377.269816) (xy 11.231765 -377.321774)
			(xy 11.249025 -377.376968) (xy 11.257758 -377.434135) (xy 11.258296 -377.46305) (xy 11.25781 -377.490301)
			(xy 11.250054 -377.544249) (xy 11.234699 -377.596544) (xy 11.212057 -377.646121) (xy 11.182591 -377.691971)
			(xy 11.1469 -377.733162) (xy 11.105709 -377.768853) (xy 11.059859 -377.798319) (xy 11.010282 -377.820961)
			(xy 10.957987 -377.836316) (xy 10.904039 -377.844072) (xy 10.849537 -377.844072) (xy 10.795589 -377.836316)
			(xy 10.743294 -377.820961) (xy 10.693717 -377.798319) (xy 10.647867 -377.768853) (xy 10.606676 -377.733162)
			(xy 10.570985 -377.691971) (xy 10.541519 -377.646121) (xy 10.518877 -377.596544) (xy 10.503522 -377.544249)
			(xy 10.495766 -377.490301) (xy 10.49528 -377.46305) (xy 10.495804 -377.434133) (xy 10.504528 -377.376961)
			(xy 10.521783 -377.321761) (xy 10.547173 -377.269798) (xy 10.580117 -377.222265) (xy 10.61986 -377.180249)
			(xy 10.642346 -377.16206) (xy 10.651129 -377.154519) (xy 10.661299 -377.133744) (xy 10.661904 -377.122182)
			(xy 10.661904 -377.041918) (xy 10.661322 -377.030352) (xy 10.651135 -377.009581) (xy 10.642346 -377.00204)
			(xy 10.621563 -376.985287) (xy 10.584433 -376.946933) (xy 10.553012 -376.903779) (xy 10.527913 -376.856665)
			(xy 10.509627 -376.806513) (xy 10.49851 -376.754301) (xy 10.494781 -376.70105) (xy 8.972797 -376.70105)
			(xy 8.969067 -376.754302) (xy 8.95795 -376.806513) (xy 8.939664 -376.856665) (xy 8.914565 -376.903779)
			(xy 8.883144 -376.946934) (xy 8.846013 -376.985287) (xy 8.82523 -377.00204) (xy 8.816443 -377.009577)
			(xy 8.806276 -377.030355) (xy 8.805672 -377.041918) (xy 8.805672 -377.122182) (xy 8.806228 -377.133752)
			(xy 8.81643 -377.154525) (xy 8.82523 -377.16206) (xy 8.847701 -377.180266) (xy 8.887435 -377.222284)
			(xy 8.920375 -377.269816) (xy 8.945765 -377.321774) (xy 8.963025 -377.376968) (xy 8.971758 -377.434135)
			(xy 8.972296 -377.46305) (xy 8.97181 -377.490301) (xy 8.964054 -377.544249) (xy 8.948699 -377.596544)
			(xy 8.926057 -377.646121) (xy 8.896591 -377.691971) (xy 8.8609 -377.733162) (xy 8.819709 -377.768853)
			(xy 8.773859 -377.798319) (xy 8.724282 -377.820961) (xy 8.671987 -377.836316) (xy 8.618039 -377.844072)
			(xy 8.563537 -377.844072) (xy 8.509589 -377.836316) (xy 8.457294 -377.820961) (xy 8.407717 -377.798319)
			(xy 8.361867 -377.768853) (xy 8.320676 -377.733162) (xy 8.284985 -377.691971) (xy 8.255519 -377.646121)
			(xy 8.232877 -377.596544) (xy 8.217522 -377.544249) (xy 8.209766 -377.490301) (xy 8.20928 -377.46305)
			(xy 8.209804 -377.434133) (xy 8.218528 -377.376961) (xy 8.235783 -377.321761) (xy 8.261173 -377.269798)
			(xy 8.294117 -377.222265) (xy 8.33386 -377.180249) (xy 8.356346 -377.16206) (xy 8.365129 -377.154519)
			(xy 8.375299 -377.133744) (xy 8.375904 -377.122182) (xy 8.375904 -377.041918) (xy 8.375322 -377.030352)
			(xy 8.365135 -377.009581) (xy 8.356346 -377.00204) (xy 8.335563 -376.985287) (xy 8.298433 -376.946933)
			(xy 8.267012 -376.903779) (xy 8.241913 -376.856665) (xy 8.223627 -376.806513) (xy 8.21251 -376.754301)
			(xy 8.208781 -376.70105) (xy 6.45287 -376.70105) (xy 6.45287 -377.963938) (xy 14.292072 -377.963938)
			(xy 14.292535 -377.937592) (xy 14.299764 -377.885398) (xy 14.314103 -377.834694) (xy 14.335281 -377.786445)
			(xy 14.362894 -377.741567) (xy 14.396418 -377.700914) (xy 14.415516 -377.68276) (xy 14.42339 -377.675648)
			(xy 14.431772 -377.656852) (xy 14.43355 -377.562364) (xy 14.42593 -377.543314) (xy 14.41831 -377.535694)
			(xy 14.397291 -377.514057) (xy 14.361641 -377.465399) (xy 14.334096 -377.411735) (xy 14.315343 -377.354404)
			(xy 14.30585 -377.294836) (xy 14.30528 -377.264676) (xy 14.305729 -377.23727) (xy 14.313582 -377.183025)
			(xy 14.329122 -377.130463) (xy 14.352029 -377.080668) (xy 14.38183 -377.034666) (xy 14.399514 -377.013724)
			(xy 14.40561 -377.006612) (xy 14.41196 -376.989594) (xy 14.41196 -376.903996) (xy 14.40561 -376.886978)
			(xy 14.399514 -376.879866) (xy 14.381832 -376.858924) (xy 14.352039 -376.812919) (xy 14.329139 -376.763124)
			(xy 14.313605 -376.710562) (xy 14.305756 -376.656318) (xy 14.30528 -376.628914) (xy 14.305825 -376.598573)
			(xy 14.315443 -376.538657) (xy 14.334423 -376.481018) (xy 14.362287 -376.427111) (xy 14.398332 -376.378293)
			(xy 14.41958 -376.356626) (xy 14.4272 -376.34926) (xy 14.43482 -376.330718) (xy 14.43482 -376.237246)
			(xy 14.4272 -376.218704) (xy 14.41958 -376.211338) (xy 14.39832 -376.189683) (xy 14.362282 -376.140862)
			(xy 14.334429 -376.08695) (xy 14.315462 -376.029309) (xy 14.305862 -375.969391) (xy 14.30528 -375.93905)
			(xy 14.305804 -375.910133) (xy 14.314528 -375.852961) (xy 14.331783 -375.797761) (xy 14.357173 -375.745798)
			(xy 14.390117 -375.698265) (xy 14.42986 -375.656249) (xy 14.452346 -375.63806) (xy 14.461129 -375.630519)
			(xy 14.471299 -375.609744) (xy 14.471904 -375.598182) (xy 14.471904 -375.517918) (xy 14.471322 -375.506352)
			(xy 14.461135 -375.485581) (xy 14.452346 -375.47804) (xy 14.42987 -375.45984) (xy 14.390137 -375.417821)
			(xy 14.357199 -375.370287) (xy 14.33181 -375.318328) (xy 14.314551 -375.263133) (xy 14.305818 -375.205965)
			(xy 14.30528 -375.17705) (xy 14.305766 -375.149799) (xy 14.313522 -375.095851) (xy 14.328877 -375.043556)
			(xy 14.351519 -374.993979) (xy 14.380985 -374.948129) (xy 14.416676 -374.906938) (xy 14.457867 -374.871247)
			(xy 14.503717 -374.841781) (xy 14.553294 -374.819139) (xy 14.605589 -374.803784) (xy 14.659537 -374.796028)
			(xy 14.714039 -374.796028) (xy 14.767987 -374.803784) (xy 14.820282 -374.819139) (xy 14.869859 -374.841781)
			(xy 14.915709 -374.871247) (xy 14.9569 -374.906938) (xy 14.992591 -374.948129) (xy 15.022057 -374.993979)
			(xy 15.044699 -375.043556) (xy 15.060054 -375.095851) (xy 15.06781 -375.149799) (xy 15.068296 -375.17705)
			(xy 15.067743 -375.205966) (xy 15.059022 -375.263135) (xy 15.041771 -375.318334) (xy 15.016385 -375.370295)
			(xy 14.983448 -375.41783) (xy 14.943713 -375.459849) (xy 14.92123 -375.47804) (xy 14.912443 -375.485577)
			(xy 14.902276 -375.506355) (xy 14.901672 -375.517918) (xy 14.901672 -375.598182) (xy 14.902228 -375.609752)
			(xy 14.91243 -375.630525) (xy 14.92123 -375.63806) (xy 14.943701 -375.656266) (xy 14.983435 -375.698284)
			(xy 15.016375 -375.745816) (xy 15.041765 -375.797774) (xy 15.059025 -375.852968) (xy 15.067758 -375.910135)
			(xy 15.068296 -375.93905) (xy 15.067706 -375.969389) (xy 15.058096 -376.029302) (xy 15.039125 -376.086939)
			(xy 15.011272 -376.140847) (xy 14.975238 -376.189668) (xy 14.953996 -376.211338) (xy 14.946376 -376.218704)
			(xy 14.938756 -376.237246) (xy 14.938756 -376.330718) (xy 14.946376 -376.34926) (xy 14.953996 -376.356626)
			(xy 14.975234 -376.378301) (xy 15.011276 -376.427116) (xy 15.039134 -376.481023) (xy 15.058105 -376.53866)
			(xy 15.067711 -376.598574) (xy 15.068296 -376.628914) (xy 15.067847 -376.65632) (xy 15.059995 -376.710566)
			(xy 15.044456 -376.763128) (xy 15.021548 -376.812923) (xy 14.991746 -376.858924) (xy 14.974062 -376.879866)
			(xy 14.967966 -376.886978) (xy 14.961616 -376.903996) (xy 14.961616 -376.989594) (xy 14.967966 -377.006612)
			(xy 14.974062 -377.013724) (xy 14.991735 -377.034673) (xy 15.021531 -377.080675) (xy 15.044432 -377.130469)
			(xy 15.059969 -377.183029) (xy 15.06782 -377.237272) (xy 15.068296 -377.264676) (xy 15.067853 -377.291023)
			(xy 15.060621 -377.343219) (xy 15.046279 -377.393923) (xy 15.025097 -377.442172) (xy 14.99748 -377.48705)
			(xy 14.963953 -377.527701) (xy 14.944852 -377.545854) (xy 14.936978 -377.552966) (xy 14.928596 -377.571762)
			(xy 14.926818 -377.66625) (xy 14.934438 -377.6853) (xy 14.942058 -377.69292) (xy 14.963096 -377.71454)
			(xy 14.998741 -377.763204) (xy 15.026281 -377.816872) (xy 15.045029 -377.874206) (xy 15.054519 -377.933777)
			(xy 15.054911 -377.95454) (xy 16.559276 -377.95454) (xy 16.559865 -377.924417) (xy 16.56934 -377.864921)
			(xy 16.588047 -377.807653) (xy 16.615519 -377.754036) (xy 16.651074 -377.705401) (xy 16.672052 -377.683776)
			(xy 16.679418 -377.67641) (xy 16.687038 -377.658376) (xy 16.687546 -377.56592) (xy 16.68018 -377.547632)
			(xy 16.672814 -377.540266) (xy 16.652346 -377.5187) (xy 16.617644 -377.470424) (xy 16.590855 -377.417347)
			(xy 16.572626 -377.360757) (xy 16.563401 -377.302023) (xy 16.562832 -377.272296) (xy 16.563335 -377.243378)
			(xy 16.572066 -377.186206) (xy 16.589326 -377.131006) (xy 16.61472 -377.079044) (xy 16.647667 -377.031511)
			(xy 16.687411 -376.989495) (xy 16.709898 -376.971306) (xy 16.718652 -376.963737) (xy 16.72884 -376.942984)
			(xy 16.729456 -376.931428) (xy 16.729456 -376.851164) (xy 16.728864 -376.839599) (xy 16.718686 -376.818826)
			(xy 16.709898 -376.811286) (xy 16.687407 -376.793103) (xy 16.647673 -376.751082) (xy 16.614735 -376.703545)
			(xy 16.589347 -376.651582) (xy 16.572093 -376.596383) (xy 16.563366 -376.539212) (xy 16.562832 -376.510296)
			(xy 16.563308 -376.483052) (xy 16.571066 -376.429118) (xy 16.586423 -376.376839) (xy 16.609066 -376.327278)
			(xy 16.638534 -376.281445) (xy 16.674227 -376.240275) (xy 16.715418 -376.204605) (xy 16.738092 -376.189494)
			(xy 16.74876 -376.182382) (xy 16.760952 -376.160538) (xy 16.763746 -376.051064) (xy 16.752316 -376.028458)
			(xy 16.742156 -376.021092) (xy 16.721253 -376.00571) (xy 16.68343 -375.970175) (xy 16.650778 -375.929836)
			(xy 16.623903 -375.885439) (xy 16.6033 -375.837806) (xy 16.589352 -375.787818) (xy 16.582316 -375.736399)
			(xy 16.581882 -375.71045) (xy 16.582315 -375.684786) (xy 16.589185 -375.633921) (xy 16.602819 -375.584437)
			(xy 16.622972 -375.537232) (xy 16.649278 -375.493158) (xy 16.681262 -375.453015) (xy 16.718345 -375.417527)
			(xy 16.738854 -375.402094) (xy 16.747998 -375.39549) (xy 16.758666 -375.376186) (xy 16.76654 -375.276618)
			(xy 16.75892 -375.256044) (xy 16.750792 -375.247916) (xy 16.729976 -375.226332) (xy 16.694724 -375.177826)
			(xy 16.667497 -375.124401) (xy 16.648966 -375.067374) (xy 16.639587 -375.008149) (xy 16.639032 -374.978168)
			(xy 16.639518 -374.950917) (xy 16.647274 -374.896969) (xy 16.662629 -374.844674) (xy 16.685271 -374.795097)
			(xy 16.714737 -374.749247) (xy 16.750428 -374.708056) (xy 16.791619 -374.672365) (xy 16.837469 -374.642899)
			(xy 16.887046 -374.620257) (xy 16.939341 -374.604902) (xy 16.993289 -374.597146) (xy 17.047791 -374.597146)
			(xy 17.101739 -374.604902) (xy 17.154034 -374.620257) (xy 17.203611 -374.642899) (xy 17.249461 -374.672365)
			(xy 17.290652 -374.708056) (xy 17.326343 -374.749247) (xy 17.355809 -374.795097) (xy 17.378451 -374.844674)
			(xy 17.393806 -374.896969) (xy 17.401562 -374.950917) (xy 17.402048 -374.978168) (xy 17.401616 -375.003832)
			(xy 17.394745 -375.054697) (xy 17.38111 -375.10418) (xy 17.360956 -375.151385) (xy 17.33465 -375.195458)
			(xy 17.302666 -375.235602) (xy 17.265584 -375.27109) (xy 17.245076 -375.286524) (xy 17.235932 -375.293128)
			(xy 17.225264 -375.312432) (xy 17.21739 -375.412) (xy 17.22501 -375.432574) (xy 17.233138 -375.440702)
			(xy 17.25395 -375.46229) (xy 17.289205 -375.510794) (xy 17.316434 -375.564217) (xy 17.334966 -375.621244)
			(xy 17.344343 -375.680469) (xy 17.344898 -375.71045) (xy 17.344444 -375.737695) (xy 17.33668 -375.791629)
			(xy 17.321318 -375.843908) (xy 17.298671 -375.893469) (xy 17.2692 -375.939301) (xy 17.233505 -375.980471)
			(xy 17.192313 -376.016141) (xy 17.169638 -376.031252) (xy 17.15897 -376.038364) (xy 17.146778 -376.060208)
			(xy 17.143984 -376.169682) (xy 17.155414 -376.192288) (xy 17.165574 -376.199654) (xy 17.186458 -376.21506)
			(xy 17.224281 -376.250592) (xy 17.256933 -376.290928) (xy 17.28381 -376.33532) (xy 17.304416 -376.382949)
			(xy 17.318368 -376.432933) (xy 17.32541 -376.484348) (xy 17.325848 -376.510296) (xy 17.325346 -376.539214)
			(xy 17.316617 -376.596387) (xy 17.299357 -376.651587) (xy 17.273962 -376.703549) (xy 17.241015 -376.751082)
			(xy 17.20127 -376.793097) (xy 17.178782 -376.811286) (xy 17.170028 -376.818855) (xy 17.159841 -376.839608)
			(xy 17.159224 -376.851164) (xy 17.159224 -376.931428) (xy 17.159827 -376.942992) (xy 17.169998 -376.963764)
			(xy 17.178782 -376.971306) (xy 17.201265 -376.989498) (xy 17.241001 -377.031517) (xy 17.27394 -377.079052)
			(xy 17.299329 -377.131013) (xy 17.316585 -377.18621) (xy 17.325314 -377.24338) (xy 17.325848 -377.272296)
			(xy 17.325275 -377.302419) (xy 17.315795 -377.361916) (xy 17.297085 -377.419184) (xy 17.269609 -377.472801)
			(xy 17.234051 -377.521435) (xy 17.213072 -377.54306) (xy 17.205706 -377.550426) (xy 17.198086 -377.56846)
			(xy 17.197578 -377.660916) (xy 17.204944 -377.679204) (xy 17.21231 -377.68657) (xy 17.232799 -377.708117)
			(xy 17.267497 -377.756399) (xy 17.294282 -377.80948) (xy 17.312506 -377.866075) (xy 17.321726 -377.924812)
			(xy 17.322292 -377.95454) (xy 17.321806 -377.981791) (xy 17.31405 -378.035739) (xy 17.298695 -378.088034)
			(xy 17.276053 -378.137611) (xy 17.246587 -378.183461) (xy 17.210896 -378.224652) (xy 17.169705 -378.260343)
			(xy 17.123855 -378.289809) (xy 17.074278 -378.312451) (xy 17.021983 -378.327806) (xy 16.968035 -378.335562)
			(xy 16.913533 -378.335562) (xy 16.859585 -378.327806) (xy 16.80729 -378.312451) (xy 16.757713 -378.289809)
			(xy 16.711863 -378.260343) (xy 16.670672 -378.224652) (xy 16.634981 -378.183461) (xy 16.605515 -378.137611)
			(xy 16.582873 -378.088034) (xy 16.567518 -378.035739) (xy 16.559762 -377.981791) (xy 16.559276 -377.95454)
			(xy 15.054911 -377.95454) (xy 15.055088 -377.963938) (xy 15.054596 -377.991648) (xy 15.046568 -378.046482)
			(xy 15.030685 -378.099577) (xy 15.007284 -378.149813) (xy 14.976857 -378.196133) (xy 14.958822 -378.217176)
			(xy 14.952726 -378.224288) (xy 14.946122 -378.24156) (xy 14.946376 -378.328174) (xy 14.95298 -378.345446)
			(xy 14.95933 -378.352558) (xy 14.977614 -378.373652) (xy 15.00844 -378.420193) (xy 15.032153 -378.470729)
			(xy 15.048248 -378.524181) (xy 15.056381 -378.579408) (xy 15.056866 -378.60732) (xy 15.05638 -378.634571)
			(xy 15.048624 -378.688519) (xy 15.033269 -378.740814) (xy 15.010627 -378.790391) (xy 14.981161 -378.836241)
			(xy 14.94547 -378.877432) (xy 14.904279 -378.913123) (xy 14.858429 -378.942589) (xy 14.808852 -378.965231)
			(xy 14.756557 -378.980586) (xy 14.702609 -378.988342) (xy 14.648107 -378.988342) (xy 14.594159 -378.980586)
			(xy 14.541864 -378.965231) (xy 14.492287 -378.942589) (xy 14.446437 -378.913123) (xy 14.405246 -378.877432)
			(xy 14.369555 -378.836241) (xy 14.340089 -378.790391) (xy 14.317447 -378.740814) (xy 14.302092 -378.688519)
			(xy 14.294336 -378.634571) (xy 14.29385 -378.60732) (xy 14.294333 -378.57961) (xy 14.302366 -378.524776)
			(xy 14.318251 -378.471681) (xy 14.341654 -378.421445) (xy 14.372081 -378.375126) (xy 14.390116 -378.354082)
			(xy 14.396212 -378.34697) (xy 14.402816 -378.329698) (xy 14.402562 -378.243084) (xy 14.395958 -378.225812)
			(xy 14.389608 -378.2187) (xy 14.371357 -378.197578) (xy 14.340525 -378.151046) (xy 14.316805 -378.100517)
			(xy 14.300702 -378.047071) (xy 14.292561 -377.991848) (xy 14.292072 -377.963938) (xy 6.45287 -377.963938)
			(xy 6.45287 -380.223522) (xy 6.453311 -380.233701) (xy 6.461215 -380.252461) (xy 6.475805 -380.266658)
			(xy 6.485128 -380.270766) (xy 6.588252 -380.310898) (xy 6.618478 -380.303786) (xy 6.629146 -380.292102)
			(xy 6.647296 -380.273041) (xy 6.687927 -380.239587) (xy 6.732769 -380.21203) (xy 6.780971 -380.190895)
			(xy 6.831619 -380.176582) (xy 6.883754 -380.169361) (xy 6.91007 -380.168912) (xy 6.937324 -380.169373)
			(xy 6.991277 -380.177127) (xy 7.043577 -380.192481) (xy 7.09316 -380.215122) (xy 7.139015 -380.244589)
			(xy 7.18021 -380.280283) (xy 7.215905 -380.321477) (xy 7.245374 -380.367331) (xy 7.268016 -380.416913)
			(xy 7.283371 -380.469213) (xy 7.291126 -380.523166) (xy 7.291578 -380.55042) (xy 7.291132 -380.576799)
			(xy 7.283867 -380.629055) (xy 7.269477 -380.679813) (xy 7.248238 -380.728107) (xy 7.220552 -380.773017)
			(xy 7.186948 -380.813689) (xy 7.148065 -380.849347) (xy 7.138351 -380.856051) (xy 9.436082 -380.856051)
			(xy 9.436082 -380.801549) (xy 9.443838 -380.747602) (xy 9.459193 -380.695308) (xy 9.481834 -380.645731)
			(xy 9.5113 -380.599881) (xy 9.546991 -380.558691) (xy 9.588181 -380.523) (xy 9.634031 -380.493534)
			(xy 9.683608 -380.470893) (xy 9.735902 -380.455538) (xy 9.789849 -380.447782) (xy 9.8171 -380.447296)
			(xy 9.842716 -380.447723) (xy 9.893486 -380.454584) (xy 9.942881 -380.46818) (xy 9.990009 -380.488269)
			(xy 10.034024 -380.514487) (xy 10.054336 -380.5301) (xy 10.062464 -380.53645) (xy 10.082276 -380.542038)
			(xy 10.17524 -380.529846) (xy 10.19302 -380.519432) (xy 10.199116 -380.51105) (xy 10.208935 -380.498203)
			(xy 10.230428 -380.474041) (xy 10.242042 -380.46279) (xy 10.249916 -380.45517) (xy 10.25779 -380.435866)
			(xy 10.256012 -380.3396) (xy 10.247376 -380.32055) (xy 10.239248 -380.313184) (xy 10.219468 -380.294997)
			(xy 10.184674 -380.254051) (xy 10.155972 -380.208626) (xy 10.133932 -380.159621) (xy 10.118989 -380.108008)
			(xy 10.11144 -380.054808) (xy 10.110978 -380.027942) (xy 10.111464 -380.000691) (xy 10.11922 -379.946743)
			(xy 10.134575 -379.894448) (xy 10.157217 -379.844871) (xy 10.186683 -379.799021) (xy 10.222374 -379.75783)
			(xy 10.263565 -379.722139) (xy 10.309415 -379.692673) (xy 10.358992 -379.670031) (xy 10.411287 -379.654676)
			(xy 10.465235 -379.64692) (xy 10.519737 -379.64692) (xy 10.573685 -379.654676) (xy 10.62598 -379.670031)
			(xy 10.675557 -379.692673) (xy 10.721407 -379.722139) (xy 10.762598 -379.75783) (xy 10.798289 -379.799021)
			(xy 10.827755 -379.844871) (xy 10.850397 -379.894448) (xy 10.865752 -379.946743) (xy 10.873508 -380.000691)
			(xy 10.873994 -380.027942) (xy 10.873606 -380.053088) (xy 12.10945 -380.053088) (xy 12.109966 -380.025484)
			(xy 12.117913 -379.97085) (xy 12.133654 -379.917933) (xy 12.15686 -379.867839) (xy 12.187045 -379.821613)
			(xy 12.22358 -379.780222) (xy 12.244324 -379.762004) (xy 12.252452 -379.755146) (xy 12.26185 -379.735842)
			(xy 12.264898 -379.63856) (xy 12.25677 -379.619002) (xy 12.248896 -379.611382) (xy 12.230736 -379.593319)
			(xy 12.198897 -379.553199) (xy 12.17271 -379.50918) (xy 12.152646 -379.462055) (xy 12.139067 -379.412668)
			(xy 12.132215 -379.36191) (xy 12.131802 -379.3363) (xy 12.132268 -379.30893) (xy 12.140085 -379.254751)
			(xy 12.155575 -379.202247) (xy 12.178416 -379.152501) (xy 12.208141 -379.106534) (xy 12.225782 -379.085602)
			(xy 12.231878 -379.07849) (xy 12.238228 -379.061472) (xy 12.238228 -378.976128) (xy 12.231878 -378.95911)
			(xy 12.225782 -378.951998) (xy 12.208126 -378.93108) (xy 12.178417 -378.885103) (xy 12.155585 -378.835352)
			(xy 12.140098 -378.782848) (xy 12.132274 -378.72867) (xy 12.131802 -378.7013) (xy 12.132288 -378.674049)
			(xy 12.140044 -378.620101) (xy 12.155399 -378.567806) (xy 12.178041 -378.518229) (xy 12.207507 -378.472379)
			(xy 12.243198 -378.431188) (xy 12.284389 -378.395497) (xy 12.330239 -378.366031) (xy 12.379816 -378.343389)
			(xy 12.432111 -378.328034) (xy 12.486059 -378.320278) (xy 12.540561 -378.320278) (xy 12.594509 -378.328034)
			(xy 12.646804 -378.343389) (xy 12.696381 -378.366031) (xy 12.742231 -378.395497) (xy 12.783422 -378.431188)
			(xy 12.819113 -378.472379) (xy 12.848579 -378.518229) (xy 12.871221 -378.567806) (xy 12.886576 -378.620101)
			(xy 12.894332 -378.674049) (xy 12.894818 -378.7013) (xy 12.894372 -378.728671) (xy 12.886552 -378.782852)
			(xy 12.87106 -378.835356) (xy 12.848213 -378.885103) (xy 12.818482 -378.931068) (xy 12.800838 -378.951998)
			(xy 12.794742 -378.95911) (xy 12.788392 -378.976128) (xy 12.788392 -379.061472) (xy 12.794742 -379.07849)
			(xy 12.800838 -379.085602) (xy 12.818498 -379.106517) (xy 12.848205 -379.152495) (xy 12.871037 -379.202247)
			(xy 12.886523 -379.254751) (xy 12.894347 -379.30893) (xy 12.894818 -379.3363) (xy 12.894374 -379.363907)
			(xy 12.886414 -379.418544) (xy 12.870659 -379.471463) (xy 12.84744 -379.521558) (xy 12.817241 -379.567781)
			(xy 12.780694 -379.609168) (xy 12.759944 -379.627384) (xy 12.751816 -379.634242) (xy 12.742418 -379.653546)
			(xy 12.73937 -379.750828) (xy 12.747498 -379.770386) (xy 12.755372 -379.778006) (xy 12.773568 -379.796033)
			(xy 12.805406 -379.836161) (xy 12.831589 -379.880187) (xy 12.851646 -379.927319) (xy 12.865217 -379.976712)
			(xy 12.872058 -380.027476) (xy 12.872466 -380.053088) (xy 12.872004 -380.080663) (xy 12.864052 -380.135236)
			(xy 12.848327 -380.188097) (xy 12.825157 -380.238143) (xy 12.795023 -380.284332) (xy 12.758554 -380.325703)
			(xy 12.737846 -380.343918) (xy 12.72921 -380.351284) (xy 12.719812 -380.37135) (xy 12.72032 -380.471934)
			(xy 12.729718 -380.492) (xy 12.738354 -380.499366) (xy 12.759369 -380.517586) (xy 12.796408 -380.559077)
			(xy 12.827037 -380.605502) (xy 12.850607 -380.655879) (xy 12.866619 -380.709142) (xy 12.874734 -380.764165)
			(xy 12.87526 -380.791974) (xy 12.874774 -380.819225) (xy 12.867018 -380.873173) (xy 12.851663 -380.925468)
			(xy 12.829021 -380.975045) (xy 12.799555 -381.020895) (xy 12.763864 -381.062086) (xy 12.722673 -381.097777)
			(xy 12.676823 -381.127243) (xy 12.627246 -381.149885) (xy 12.574951 -381.16524) (xy 12.521003 -381.172996)
			(xy 12.466501 -381.172996) (xy 12.412553 -381.16524) (xy 12.360258 -381.149885) (xy 12.310681 -381.127243)
			(xy 12.264831 -381.097777) (xy 12.22364 -381.062086) (xy 12.187949 -381.020895) (xy 12.158483 -380.975045)
			(xy 12.135841 -380.925468) (xy 12.120486 -380.873173) (xy 12.11273 -380.819225) (xy 12.112244 -380.791974)
			(xy 12.112745 -380.764401) (xy 12.120688 -380.709829) (xy 12.136405 -380.656969) (xy 12.159569 -380.606922)
			(xy 12.189696 -380.560732) (xy 12.226159 -380.51936) (xy 12.246864 -380.501144) (xy 12.2555 -380.493778)
			(xy 12.264898 -380.473712) (xy 12.26439 -380.373128) (xy 12.254992 -380.353062) (xy 12.246356 -380.345696)
			(xy 12.225325 -380.327494) (xy 12.188286 -380.286) (xy 12.157659 -380.239571) (xy 12.134092 -380.18919)
			(xy 12.118084 -380.135924) (xy 12.109973 -380.080898) (xy 12.10945 -380.053088) (xy 10.873606 -380.053088)
			(xy 10.873597 -380.053653) (xy 10.866669 -380.104608) (xy 10.852958 -380.154169) (xy 10.832712 -380.20144)
			(xy 10.806299 -380.245561) (xy 10.774197 -380.285734) (xy 10.755884 -380.303786) (xy 10.74801 -380.311406)
			(xy 10.740136 -380.33071) (xy 10.741914 -380.426976) (xy 10.75055 -380.446026) (xy 10.758678 -380.453392)
			(xy 10.7785 -380.471535) (xy 10.81329 -380.512491) (xy 10.841985 -380.557926) (xy 10.864018 -380.606939)
			(xy 10.878952 -380.658559) (xy 10.886491 -380.711765) (xy 10.886948 -380.738634) (xy 10.886454 -380.765884)
			(xy 10.878694 -380.81983) (xy 10.863336 -380.872122) (xy 10.840694 -380.921696) (xy 10.811228 -380.967545)
			(xy 10.775538 -381.008734) (xy 10.73435 -381.044425) (xy 10.688502 -381.073891) (xy 10.638927 -381.096534)
			(xy 10.586635 -381.111893) (xy 10.53269 -381.119654) (xy 10.50544 -381.120142) (xy 10.479824 -381.119706)
			(xy 10.429054 -381.11285) (xy 10.379659 -381.099256) (xy 10.33253 -381.079169) (xy 10.288516 -381.052951)
			(xy 10.268204 -381.037338) (xy 10.260076 -381.030988) (xy 10.240264 -381.0254) (xy 10.1473 -381.037592)
			(xy 10.12952 -381.048006) (xy 10.123424 -381.056388) (xy 10.105294 -381.079848) (xy 10.062978 -381.121375)
			(xy 10.014752 -381.155861) (xy 9.961775 -381.182479) (xy 9.90532 -381.200587) (xy 9.846744 -381.209752)
			(xy 9.8171 -381.210312) (xy 9.789849 -381.209818) (xy 9.735902 -381.202062) (xy 9.683608 -381.186707)
			(xy 9.634031 -381.164066) (xy 9.588181 -381.1346) (xy 9.546991 -381.098909) (xy 9.5113 -381.057719)
			(xy 9.481834 -381.011869) (xy 9.459193 -380.962292) (xy 9.443838 -380.909998) (xy 9.436082 -380.856051)
			(xy 7.138351 -380.856051) (xy 7.104643 -380.879314) (xy 7.081266 -380.891542) (xy 7.068058 -380.897892)
			(xy 7.053072 -380.922276) (xy 7.053072 -381.042164) (xy 7.068058 -381.066548) (xy 7.081266 -381.072898)
			(xy 7.10464 -381.085139) (xy 7.148075 -381.115093) (xy 7.186972 -381.150743) (xy 7.220588 -381.191411)
			(xy 7.248283 -381.236321) (xy 7.269529 -381.284617) (xy 7.283921 -381.335378) (xy 7.291185 -381.387639)
			(xy 7.291446 -381.40513) (xy 15.882112 -381.40513) (xy 15.882593 -381.37776) (xy 15.890407 -381.323582)
			(xy 15.905892 -381.271079) (xy 15.928731 -381.221332) (xy 15.958452 -381.175364) (xy 15.976092 -381.154432)
			(xy 15.982188 -381.14732) (xy 15.988538 -381.130302) (xy 15.988538 -381.044958) (xy 15.982188 -381.02794)
			(xy 15.976092 -381.020828) (xy 15.958482 -380.999871) (xy 15.928759 -380.953906) (xy 15.905914 -380.904164)
			(xy 15.890417 -380.851666) (xy 15.882586 -380.797491) (xy 15.882583 -380.742754) (xy 15.890407 -380.688578)
			(xy 15.905898 -380.636078) (xy 15.928737 -380.586333) (xy 15.958455 -380.540365) (xy 15.976092 -380.519432)
			(xy 15.982188 -380.51232) (xy 15.988538 -380.495302) (xy 15.988538 -380.409958) (xy 15.982188 -380.39294)
			(xy 15.976092 -380.385828) (xy 15.958482 -380.364871) (xy 15.928759 -380.318906) (xy 15.905914 -380.269164)
			(xy 15.890417 -380.216666) (xy 15.882586 -380.162491) (xy 15.882583 -380.107754) (xy 15.890407 -380.053578)
			(xy 15.905898 -380.001078) (xy 15.928737 -379.951333) (xy 15.958455 -379.905365) (xy 15.976092 -379.884432)
			(xy 15.982188 -379.87732) (xy 15.988538 -379.860302) (xy 15.988538 -379.774958) (xy 15.982188 -379.75794)
			(xy 15.976092 -379.750828) (xy 15.958482 -379.729871) (xy 15.928759 -379.683906) (xy 15.905914 -379.634164)
			(xy 15.890417 -379.581666) (xy 15.882586 -379.527491) (xy 15.882583 -379.472754) (xy 15.890407 -379.418578)
			(xy 15.905898 -379.366078) (xy 15.928737 -379.316333) (xy 15.958455 -379.270365) (xy 15.976092 -379.249432)
			(xy 15.982188 -379.24232) (xy 15.988538 -379.225302) (xy 15.988538 -379.139958) (xy 15.982188 -379.12294)
			(xy 15.976092 -379.115828) (xy 15.958451 -379.094897) (xy 15.92874 -379.048924) (xy 15.905904 -378.999176)
			(xy 15.890414 -378.946675) (xy 15.882586 -378.892499) (xy 15.882112 -378.86513) (xy 15.882598 -378.837879)
			(xy 15.890354 -378.783931) (xy 15.905709 -378.731636) (xy 15.928351 -378.682059) (xy 15.957817 -378.636209)
			(xy 15.993508 -378.595018) (xy 16.034699 -378.559327) (xy 16.080549 -378.529861) (xy 16.130126 -378.507219)
			(xy 16.182421 -378.491864) (xy 16.236369 -378.484108) (xy 16.290871 -378.484108) (xy 16.344819 -378.491864)
			(xy 16.397114 -378.507219) (xy 16.446691 -378.529861) (xy 16.492541 -378.559327) (xy 16.533732 -378.595018)
			(xy 16.569423 -378.636209) (xy 16.598889 -378.682059) (xy 16.621531 -378.731636) (xy 16.636886 -378.783931)
			(xy 16.644642 -378.837879) (xy 16.645128 -378.86513) (xy 16.644697 -378.892502) (xy 16.636873 -378.946683)
			(xy 16.621377 -378.999187) (xy 16.598527 -379.048934) (xy 16.568794 -379.094898) (xy 16.551148 -379.115828)
			(xy 16.545052 -379.12294) (xy 16.538702 -379.139958) (xy 16.538702 -379.225302) (xy 16.545052 -379.24232)
			(xy 16.551148 -379.249432) (xy 16.568819 -379.27034) (xy 16.598545 -379.316312) (xy 16.62139 -379.366062)
			(xy 16.636885 -379.418568) (xy 16.644711 -379.47275) (xy 16.644708 -379.527495) (xy 16.636875 -379.581676)
			(xy 16.621374 -379.63418) (xy 16.598523 -379.683928) (xy 16.568792 -379.729896) (xy 16.551148 -379.750828)
			(xy 16.545052 -379.75794) (xy 16.538702 -379.774958) (xy 16.538702 -379.860302) (xy 16.545052 -379.87732)
			(xy 16.551148 -379.884432) (xy 16.568819 -379.90534) (xy 16.598545 -379.951312) (xy 16.62139 -380.001062)
			(xy 16.636885 -380.053568) (xy 16.644711 -380.10775) (xy 16.644708 -380.162495) (xy 16.636875 -380.216676)
			(xy 16.621374 -380.26918) (xy 16.598523 -380.318928) (xy 16.568792 -380.364896) (xy 16.551148 -380.385828)
			(xy 16.545052 -380.39294) (xy 16.538702 -380.409958) (xy 16.538702 -380.495302) (xy 16.545052 -380.51232)
			(xy 16.551148 -380.519432) (xy 16.568819 -380.54034) (xy 16.598545 -380.586312) (xy 16.62139 -380.636062)
			(xy 16.636885 -380.688568) (xy 16.644711 -380.74275) (xy 16.644708 -380.797495) (xy 16.644405 -380.799594)
			(xy 18.005552 -380.799594) (xy 18.005939 -380.774164) (xy 18.012698 -380.723755) (xy 18.026095 -380.674691)
			(xy 18.045893 -380.627843) (xy 18.071741 -380.584041) (xy 18.103179 -380.544061) (xy 18.121122 -380.526036)
			(xy 18.128488 -380.518924) (xy 18.136362 -380.500382) (xy 18.136616 -380.406656) (xy 18.128742 -380.388114)
			(xy 18.121376 -380.380748) (xy 18.10012 -380.35909) (xy 18.064082 -380.310269) (xy 18.036228 -380.256358)
			(xy 18.01726 -380.198718) (xy 18.007659 -380.138801) (xy 18.007076 -380.10846) (xy 18.007582 -380.079721)
			(xy 18.01621 -380.022893) (xy 18.033264 -379.968002) (xy 18.05836 -379.916291) (xy 18.090928 -379.868929)
			(xy 18.1102 -379.847602) (xy 18.116804 -379.84049) (xy 18.123916 -379.822964) (xy 18.123916 -379.733556)
			(xy 18.116804 -379.71603) (xy 18.1102 -379.708918) (xy 18.090929 -379.687591) (xy 18.058364 -379.640229)
			(xy 18.033273 -379.588517) (xy 18.016223 -379.533626) (xy 18.007601 -379.476799) (xy 18.007601 -379.419321)
			(xy 18.016223 -379.362494) (xy 18.033273 -379.307603) (xy 18.058364 -379.255891) (xy 18.090929 -379.208529)
			(xy 18.1102 -379.187202) (xy 18.116804 -379.18009) (xy 18.123916 -379.162564) (xy 18.123916 -379.073156)
			(xy 18.116804 -379.05563) (xy 18.1102 -379.048518) (xy 18.090921 -379.027198) (xy 18.058354 -378.979835)
			(xy 18.033262 -378.928122) (xy 18.016213 -378.873229) (xy 18.007595 -378.8164) (xy 18.007076 -378.78766)
			(xy 18.007541 -378.760408) (xy 18.015302 -378.706461) (xy 18.030661 -378.654167) (xy 18.053306 -378.60459)
			(xy 18.082775 -378.558741) (xy 18.118469 -378.517552) (xy 18.15966 -378.481861) (xy 18.205511 -378.452395)
			(xy 18.255089 -378.429753) (xy 18.307384 -378.414397) (xy 18.361332 -378.406639) (xy 18.388584 -378.406152)
			(xy 18.417229 -378.406637) (xy 18.473874 -378.415214) (xy 18.528601 -378.432164) (xy 18.580178 -378.457104)
			(xy 18.627447 -378.489474) (xy 18.669346 -378.528548) (xy 18.687542 -378.550678) (xy 18.6944 -378.559314)
			(xy 18.713704 -378.56922) (xy 18.811748 -378.574554) (xy 18.832068 -378.56668) (xy 18.839688 -378.558806)
			(xy 18.861356 -378.537509) (xy 18.910208 -378.501392) (xy 18.964166 -378.473475) (xy 19.021868 -378.454464)
			(xy 19.081854 -378.444839) (xy 19.11223 -378.444252) (xy 19.14149 -378.444813) (xy 19.199321 -378.453759)
			(xy 19.255112 -378.471422) (xy 19.307555 -378.497388) (xy 19.355424 -378.53105) (xy 19.376898 -378.550932)
			(xy 19.38401 -378.55779) (xy 19.402044 -378.565156) (xy 19.492468 -378.565156) (xy 19.510502 -378.55779)
			(xy 19.517614 -378.550932) (xy 19.539048 -378.531001) (xy 19.586919 -378.497327) (xy 19.639371 -378.471358)
			(xy 19.695174 -378.453703) (xy 19.753018 -378.444778) (xy 19.782282 -378.444252) (xy 19.811862 -378.444836)
			(xy 19.870315 -378.453966) (xy 19.926657 -378.472009) (xy 19.979539 -378.498533) (xy 20.027693 -378.532901)
			(xy 20.069964 -378.574291) (xy 20.088098 -378.597668) (xy 20.095686 -378.606789) (xy 20.116888 -378.617376)
			(xy 20.128738 -378.617988) (xy 20.210272 -378.617988) (xy 20.222117 -378.617357) (xy 20.243308 -378.60677)
			(xy 20.250912 -378.597668) (xy 20.260074 -378.585618) (xy 20.280037 -378.562857) (xy 20.29079 -378.552202)
			(xy 20.298664 -378.544582) (xy 20.306538 -378.525024) (xy 20.303744 -378.428504) (xy 20.294854 -378.409454)
			(xy 20.286726 -378.402342) (xy 20.266449 -378.384128) (xy 20.230747 -378.342943) (xy 20.201264 -378.297102)
			(xy 20.178597 -378.247534) (xy 20.163208 -378.195247) (xy 20.155409 -378.141304) (xy 20.1549 -378.114052)
			(xy 20.155347 -378.086223) (xy 20.163428 -378.031153) (xy 20.179427 -377.977844) (xy 20.203003 -377.927425)
			(xy 20.233657 -377.880968) (xy 20.270736 -377.839458) (xy 20.313455 -377.803779) (xy 20.360905 -377.774686)
			(xy 20.386294 -377.763278) (xy 20.395946 -377.759214) (xy 20.41017 -377.744482) (xy 20.443444 -377.656344)
			(xy 20.442428 -377.63577) (xy 20.43811 -377.626372) (xy 20.42649 -377.600731) (xy 20.410102 -377.546875)
			(xy 20.4018 -377.491197) (xy 20.40128 -377.46305) (xy 20.401804 -377.434133) (xy 20.410528 -377.376961)
			(xy 20.427783 -377.321761) (xy 20.453173 -377.269798) (xy 20.486117 -377.222265) (xy 20.52586 -377.180249)
			(xy 20.548346 -377.16206) (xy 20.557129 -377.154519) (xy 20.567299 -377.133744) (xy 20.567904 -377.122182)
			(xy 20.567904 -377.041918) (xy 20.567322 -377.030352) (xy 20.557135 -377.009581) (xy 20.548346 -377.00204)
			(xy 20.527563 -376.985287) (xy 20.490433 -376.946933) (xy 20.459012 -376.903779) (xy 20.433913 -376.856665)
			(xy 20.415627 -376.806513) (xy 20.40451 -376.754301) (xy 20.400781 -376.70105) (xy 20.40451 -376.647799)
			(xy 20.415627 -376.595587) (xy 20.433913 -376.545435) (xy 20.459012 -376.498321) (xy 20.490433 -376.455167)
			(xy 20.527563 -376.416813) (xy 20.548346 -376.40006) (xy 20.557129 -376.392519) (xy 20.567299 -376.371744)
			(xy 20.567904 -376.360182) (xy 20.567904 -376.279918) (xy 20.567322 -376.268352) (xy 20.557135 -376.247581)
			(xy 20.548346 -376.24004) (xy 20.527563 -376.223287) (xy 20.490433 -376.184933) (xy 20.459012 -376.141779)
			(xy 20.433913 -376.094665) (xy 20.415627 -376.044513) (xy 20.40451 -375.992301) (xy 20.400781 -375.93905)
			(xy 20.40451 -375.885799) (xy 20.415627 -375.833587) (xy 20.433913 -375.783435) (xy 20.459012 -375.736321)
			(xy 20.490433 -375.693167) (xy 20.527563 -375.654813) (xy 20.548346 -375.63806) (xy 20.557129 -375.630519)
			(xy 20.567299 -375.609744) (xy 20.567904 -375.598182) (xy 20.567904 -375.517918) (xy 20.567322 -375.506352)
			(xy 20.557135 -375.485581) (xy 20.548346 -375.47804) (xy 20.52587 -375.45984) (xy 20.486137 -375.417821)
			(xy 20.453199 -375.370287) (xy 20.42781 -375.318328) (xy 20.410551 -375.263133) (xy 20.401818 -375.205965)
			(xy 20.40128 -375.17705) (xy 20.401766 -375.149799) (xy 20.409522 -375.095851) (xy 20.424877 -375.043556)
			(xy 20.447519 -374.993979) (xy 20.476985 -374.948129) (xy 20.512676 -374.906938) (xy 20.553867 -374.871247)
			(xy 20.599717 -374.841781) (xy 20.649294 -374.819139) (xy 20.701589 -374.803784) (xy 20.755537 -374.796028)
			(xy 20.810039 -374.796028) (xy 20.863987 -374.803784) (xy 20.916282 -374.819139) (xy 20.965859 -374.841781)
			(xy 21.011709 -374.871247) (xy 21.0529 -374.906938) (xy 21.088591 -374.948129) (xy 21.118057 -374.993979)
			(xy 21.140699 -375.043556) (xy 21.156054 -375.095851) (xy 21.16381 -375.149799) (xy 21.164296 -375.17705)
			(xy 21.163743 -375.205966) (xy 21.155022 -375.263135) (xy 21.137771 -375.318334) (xy 21.112385 -375.370295)
			(xy 21.079448 -375.41783) (xy 21.039713 -375.459849) (xy 21.01723 -375.47804) (xy 21.008443 -375.485577)
			(xy 20.998276 -375.506355) (xy 20.997672 -375.517918) (xy 20.997672 -375.598182) (xy 20.998228 -375.609752)
			(xy 21.00843 -375.630525) (xy 21.01723 -375.63806) (xy 21.038013 -375.654813) (xy 21.075144 -375.693166)
			(xy 21.106565 -375.736321) (xy 21.131664 -375.783435) (xy 21.14995 -375.833587) (xy 21.161067 -375.885798)
			(xy 21.164797 -375.93905) (xy 21.161067 -375.992302) (xy 21.14995 -376.044513) (xy 21.131664 -376.094665)
			(xy 21.106565 -376.141779) (xy 21.075144 -376.184934) (xy 21.038013 -376.223287) (xy 21.01723 -376.24004)
			(xy 21.008443 -376.247577) (xy 20.998276 -376.268355) (xy 20.997672 -376.279918) (xy 20.997672 -376.360182)
			(xy 20.998228 -376.371752) (xy 21.00843 -376.392525) (xy 21.01723 -376.40006) (xy 21.038013 -376.416813)
			(xy 21.075144 -376.455166) (xy 21.106565 -376.498321) (xy 21.131664 -376.545435) (xy 21.14995 -376.595587)
			(xy 21.154341 -376.616209) (xy 22.153395 -376.616209) (xy 22.157124 -376.562959) (xy 22.168239 -376.510749)
			(xy 22.186523 -376.460598) (xy 22.211619 -376.413485) (xy 22.243037 -376.370331) (xy 22.280165 -376.331978)
			(xy 22.300946 -376.315224) (xy 22.3097 -376.307655) (xy 22.319886 -376.286901) (xy 22.320504 -376.275346)
			(xy 22.320504 -376.195082) (xy 22.319942 -376.183513) (xy 22.309741 -376.162742) (xy 22.300946 -376.155204)
			(xy 22.280177 -376.138434) (xy 22.243048 -376.100082) (xy 22.211628 -376.056929) (xy 22.18653 -376.009818)
			(xy 22.168243 -375.959668) (xy 22.157126 -375.907458) (xy 22.153395 -375.854209) (xy 22.157124 -375.800959)
			(xy 22.168239 -375.748749) (xy 22.186523 -375.698598) (xy 22.211619 -375.651485) (xy 22.243037 -375.608331)
			(xy 22.280165 -375.569978) (xy 22.300946 -375.553224) (xy 22.3097 -375.545655) (xy 22.319886 -375.524901)
			(xy 22.320504 -375.513346) (xy 22.320504 -375.433082) (xy 22.319942 -375.421513) (xy 22.309741 -375.400742)
			(xy 22.300946 -375.393204) (xy 22.278453 -375.375024) (xy 22.238721 -375.333001) (xy 22.205785 -375.285463)
			(xy 22.180398 -375.2335) (xy 22.163144 -375.178301) (xy 22.154415 -375.12113) (xy 22.15388 -375.092214)
			(xy 22.154366 -375.064963) (xy 22.162122 -375.011015) (xy 22.177477 -374.95872) (xy 22.200119 -374.909143)
			(xy 22.229585 -374.863293) (xy 22.265276 -374.822102) (xy 22.306467 -374.786411) (xy 22.352317 -374.756945)
			(xy 22.401894 -374.734303) (xy 22.454189 -374.718948) (xy 22.508137 -374.711192) (xy 22.562639 -374.711192)
			(xy 22.616587 -374.718948) (xy 22.668882 -374.734303) (xy 22.718459 -374.756945) (xy 22.764309 -374.786411)
			(xy 22.8055 -374.822102) (xy 22.841191 -374.863293) (xy 22.870657 -374.909143) (xy 22.893299 -374.95872)
			(xy 22.908654 -375.011015) (xy 22.91641 -375.064963) (xy 22.916896 -375.092214) (xy 22.916318 -375.121129)
			(xy 22.907601 -375.178297) (xy 22.890355 -375.233495) (xy 22.864975 -375.285457) (xy 22.832042 -375.332992)
			(xy 22.792311 -375.375012) (xy 22.76983 -375.393204) (xy 22.761059 -375.400757) (xy 22.750883 -375.421523)
			(xy 22.750272 -375.433082) (xy 22.750272 -375.513346) (xy 22.750848 -375.524914) (xy 22.761036 -375.545686)
			(xy 22.76983 -375.553224) (xy 22.790627 -375.569961) (xy 22.827759 -375.608315) (xy 22.859181 -375.651472)
			(xy 22.884281 -375.698587) (xy 22.902567 -375.748741) (xy 22.913683 -375.800955) (xy 22.917412 -375.854209)
			(xy 22.913681 -375.907462) (xy 22.902562 -375.959675) (xy 22.884274 -376.009829) (xy 22.859172 -376.056943)
			(xy 22.827748 -376.100098) (xy 22.790614 -376.138451) (xy 22.76983 -376.155204) (xy 22.761059 -376.162757)
			(xy 22.750883 -376.183523) (xy 22.750272 -376.195082) (xy 22.750272 -376.275346) (xy 22.750848 -376.286914)
			(xy 22.761036 -376.307686) (xy 22.76983 -376.315224) (xy 22.790627 -376.331961) (xy 22.827759 -376.370315)
			(xy 22.859181 -376.413472) (xy 22.884281 -376.460587) (xy 22.902567 -376.510741) (xy 22.913683 -376.562955)
			(xy 22.917412 -376.616209) (xy 22.913681 -376.669462) (xy 22.902562 -376.721675) (xy 22.884274 -376.771829)
			(xy 22.859172 -376.818943) (xy 22.827748 -376.862098) (xy 22.790614 -376.900451) (xy 22.76983 -376.917204)
			(xy 22.761059 -376.924757) (xy 22.750883 -376.945523) (xy 22.750272 -376.957082) (xy 22.750272 -377.037346)
			(xy 22.750848 -377.048914) (xy 22.761036 -377.069686) (xy 22.76983 -377.077224) (xy 22.792331 -377.095394)
			(xy 22.832064 -377.137419) (xy 22.865 -377.184958) (xy 22.890385 -377.236924) (xy 22.907638 -377.292125)
			(xy 22.916363 -377.349297) (xy 22.916896 -377.378214) (xy 22.916393 -377.405147) (xy 22.908811 -377.458476)
			(xy 22.8938 -377.510208) (xy 22.87166 -377.559313) (xy 22.84283 -377.604813) (xy 22.82571 -377.62561)
			(xy 22.818852 -377.633738) (xy 22.812756 -377.653804) (xy 22.823678 -377.7488) (xy 22.834346 -377.767088)
			(xy 22.842982 -377.773438) (xy 22.866608 -377.791547) (xy 22.908468 -377.833868) (xy 22.943245 -377.882178)
			(xy 22.970093 -377.935305) (xy 22.983421 -377.976638) (xy 25.762966 -377.976638) (xy 25.763465 -377.949665)
			(xy 25.771047 -377.896255) (xy 25.78608 -377.844446) (xy 25.808263 -377.795272) (xy 25.837154 -377.749715)
			(xy 25.872176 -377.708683) (xy 25.912631 -377.672996) (xy 25.95771 -377.643366) (xy 25.981914 -377.631452)
			(xy 25.992836 -377.626372) (xy 26.007314 -377.60783) (xy 26.029158 -377.50496) (xy 26.023062 -377.4821)
			(xy 26.015188 -377.472956) (xy 25.997606 -377.452022) (xy 25.967967 -377.406087) (xy 25.945189 -377.356391)
			(xy 25.929738 -377.303953) (xy 25.921932 -377.249846) (xy 25.921462 -377.222512) (xy 25.921965 -377.193594)
			(xy 25.930694 -377.136421) (xy 25.947954 -377.081221) (xy 25.973348 -377.029259) (xy 26.006295 -376.981726)
			(xy 26.04604 -376.939711) (xy 26.068528 -376.921522) (xy 26.07728 -376.913951) (xy 26.087468 -376.893199)
			(xy 26.088086 -376.881644) (xy 26.088086 -376.80138) (xy 26.087475 -376.789817) (xy 26.07731 -376.769045)
			(xy 26.068528 -376.761502) (xy 26.047758 -376.744734) (xy 26.010631 -376.706381) (xy 25.979212 -376.663227)
			(xy 25.954115 -376.616116) (xy 25.93583 -376.565966) (xy 25.924713 -376.513756) (xy 25.920983 -376.460507)
			(xy 25.924711 -376.407258) (xy 25.935826 -376.355049) (xy 25.954109 -376.304898) (xy 25.979204 -376.257785)
			(xy 26.010621 -376.21463) (xy 26.047747 -376.176276) (xy 26.068528 -376.159522) (xy 26.07728 -376.151951)
			(xy 26.087468 -376.131199) (xy 26.088086 -376.119644) (xy 26.088086 -376.03938) (xy 26.087475 -376.027817)
			(xy 26.07731 -376.007045) (xy 26.068528 -375.999502) (xy 26.046051 -375.981303) (xy 26.006314 -375.939286)
			(xy 25.973374 -375.891753) (xy 25.947984 -375.839793) (xy 25.930727 -375.784596) (xy 25.921997 -375.727428)
			(xy 25.921462 -375.698512) (xy 25.922035 -375.668964) (xy 25.931145 -375.610575) (xy 25.949149 -375.554289)
			(xy 25.975617 -375.501453) (xy 26.009916 -375.453329) (xy 26.030174 -375.431812) (xy 26.037286 -375.424446)
			(xy 26.044652 -375.406666) (xy 26.04516 -375.315988) (xy 26.038048 -375.297954) (xy 26.030936 -375.290588)
			(xy 26.011249 -375.269175) (xy 25.977978 -375.221464) (xy 25.952327 -375.169258) (xy 25.93489 -375.113767)
			(xy 25.926071 -375.056273) (xy 25.925526 -375.02719) (xy 25.926012 -374.999939) (xy 25.933768 -374.945991)
			(xy 25.949123 -374.893696) (xy 25.971765 -374.844119) (xy 26.001231 -374.798269) (xy 26.036922 -374.757078)
			(xy 26.078113 -374.721387) (xy 26.123963 -374.691921) (xy 26.17354 -374.669279) (xy 26.225835 -374.653924)
			(xy 26.279783 -374.646168) (xy 26.334285 -374.646168) (xy 26.388233 -374.653924) (xy 26.440528 -374.669279)
			(xy 26.490105 -374.691921) (xy 26.535955 -374.721387) (xy 26.577146 -374.757078) (xy 26.612837 -374.798269)
			(xy 26.642303 -374.844119) (xy 26.664945 -374.893696) (xy 26.6803 -374.945991) (xy 26.688056 -374.999939)
			(xy 26.688542 -375.02719) (xy 26.68797 -375.056738) (xy 26.678859 -375.115127) (xy 26.660855 -375.171413)
			(xy 26.634386 -375.224249) (xy 26.600088 -375.272373) (xy 26.57983 -375.29389) (xy 26.572718 -375.301256)
			(xy 26.565352 -375.319036) (xy 26.564844 -375.409714) (xy 26.571956 -375.427748) (xy 26.579068 -375.435114)
			(xy 26.598757 -375.456526) (xy 26.632027 -375.504237) (xy 26.657678 -375.556443) (xy 26.675114 -375.611935)
			(xy 26.683933 -375.669429) (xy 26.684478 -375.698512) (xy 26.683905 -375.727427) (xy 26.675188 -375.784596)
			(xy 26.657942 -375.839794) (xy 26.63256 -375.891756) (xy 26.599626 -375.939291) (xy 26.559893 -375.98131)
			(xy 26.537412 -375.999502) (xy 26.528655 -376.007069) (xy 26.518469 -376.027824) (xy 26.517854 -376.03938)
			(xy 26.517854 -376.119644) (xy 26.518438 -376.131211) (xy 26.528621 -376.151983) (xy 26.537412 -376.159522)
			(xy 26.55165 -376.170897) (xy 26.578109 -376.195963) (xy 26.590244 -376.20956) (xy 26.597356 -376.217688)
			(xy 26.61666 -376.226578) (xy 26.713434 -376.228356) (xy 26.733246 -376.220228) (xy 26.740612 -376.212354)
			(xy 26.758715 -376.193795) (xy 26.799041 -376.161212) (xy 26.84341 -376.134395) (xy 26.891005 -376.113838)
			(xy 26.940946 -376.099921) (xy 26.992312 -376.092899) (xy 27.018234 -376.092466) (xy 27.046973 -376.092978)
			(xy 27.103801 -376.101605) (xy 27.158691 -376.118658) (xy 27.210403 -376.143752) (xy 27.257765 -376.176319)
			(xy 27.279092 -376.19559) (xy 27.286204 -376.202194) (xy 27.30373 -376.209306) (xy 27.393138 -376.209306)
			(xy 27.410664 -376.202194) (xy 27.417776 -376.19559) (xy 27.439097 -376.176312) (xy 27.48646 -376.143745)
			(xy 27.538173 -376.118653) (xy 27.593065 -376.101604) (xy 27.649894 -376.092985) (xy 27.678634 -376.092466)
			(xy 27.705885 -376.092946) (xy 27.759831 -376.100707) (xy 27.812125 -376.116065) (xy 27.8617 -376.138708)
			(xy 27.907549 -376.168175) (xy 27.948738 -376.203867) (xy 27.984429 -376.245057) (xy 28.013896 -376.290907)
			(xy 28.036538 -376.340483) (xy 28.051895 -376.392776) (xy 28.059654 -376.446723) (xy 28.060142 -376.473974)
			(xy 28.059678 -376.501703) (xy 28.051658 -376.556577) (xy 28.035782 -376.609714) (xy 28.012386 -376.659995)
			(xy 27.98196 -376.706361) (xy 27.945146 -376.747838) (xy 27.924252 -376.766074) (xy 27.915362 -376.77344)
			(xy 27.905964 -376.79376) (xy 27.906726 -376.895106) (xy 27.916632 -376.915426) (xy 27.925522 -376.922538)
			(xy 27.94716 -376.940735) (xy 27.985293 -376.982476) (xy 28.016851 -377.029386) (xy 28.041144 -377.080438)
			(xy 28.057641 -377.134515) (xy 28.06598 -377.190433) (xy 28.066492 -377.218702) (xy 28.065908 -377.249398)
			(xy 28.056111 -377.310001) (xy 28.036738 -377.368255) (xy 28.023058 -377.39574) (xy 28.016708 -377.407424)
			(xy 28.017216 -377.433332) (xy 28.073604 -377.530614) (xy 28.095702 -377.543822) (xy 28.10891 -377.54433)
			(xy 28.135429 -377.545853) (xy 28.187695 -377.555325) (xy 28.238142 -377.571955) (xy 28.285796 -377.595421)
			(xy 28.329733 -377.625269) (xy 28.369107 -377.660923) (xy 28.403154 -377.701694) (xy 28.431218 -377.746793)
			(xy 28.452755 -377.795348) (xy 28.467349 -377.846421) (xy 28.474719 -377.899025) (xy 28.475178 -377.925584)
			(xy 28.47473 -377.952838) (xy 28.466974 -378.006791) (xy 28.451619 -378.059091) (xy 28.428976 -378.108673)
			(xy 28.399507 -378.154528) (xy 28.363811 -378.195721) (xy 28.322616 -378.231415) (xy 28.276761 -378.260883)
			(xy 28.227178 -378.283524) (xy 28.174877 -378.298877) (xy 28.120924 -378.306631) (xy 28.09367 -378.307092)
			(xy 28.065559 -378.306574) (xy 28.009945 -378.298337) (xy 27.956141 -378.28203) (xy 27.905311 -378.258006)
			(xy 27.858555 -378.226786) (xy 27.837384 -378.208286) (xy 27.830272 -378.201682) (xy 27.813 -378.195078)
			(xy 27.725624 -378.194824) (xy 27.708352 -378.201682) (xy 27.700986 -378.208032) (xy 27.679871 -378.226454)
			(xy 27.633232 -378.257517) (xy 27.582549 -378.281417) (xy 27.528913 -378.29764) (xy 27.47348 -378.305838)
			(xy 27.445462 -378.30633) (xy 27.416723 -378.305821) (xy 27.359895 -378.297194) (xy 27.305004 -378.28014)
			(xy 27.253293 -378.255045) (xy 27.205931 -378.222478) (xy 27.184604 -378.203206) (xy 27.177492 -378.196602)
			(xy 27.159966 -378.18949) (xy 27.070558 -378.18949) (xy 27.053032 -378.196602) (xy 27.04592 -378.203206)
			(xy 27.0246 -378.222485) (xy 26.977237 -378.255052) (xy 26.925524 -378.280144) (xy 26.870631 -378.297192)
			(xy 26.813802 -378.305811) (xy 26.785062 -378.30633) (xy 26.754197 -378.305705) (xy 26.693278 -378.295729)
			(xy 26.63476 -378.276075) (xy 26.58017 -378.247256) (xy 26.555192 -378.229114) (xy 26.547572 -378.223526)
			(xy 26.529792 -378.218446) (xy 26.443686 -378.225304) (xy 26.426922 -378.233178) (xy 26.420318 -378.240036)
			(xy 26.402257 -378.258341) (xy 26.362093 -378.290451) (xy 26.317974 -378.316868) (xy 26.270704 -378.337111)
			(xy 26.221141 -378.350813) (xy 26.170185 -378.357725) (xy 26.144474 -378.358146) (xy 26.117224 -378.357647)
			(xy 26.063279 -378.349887) (xy 26.010986 -378.334531) (xy 25.961412 -378.31189) (xy 25.915563 -378.282424)
			(xy 25.874374 -378.246734) (xy 25.838683 -378.205546) (xy 25.809216 -378.159699) (xy 25.786573 -378.110125)
			(xy 25.771215 -378.057833) (xy 25.763454 -378.003888) (xy 25.762966 -377.976638) (xy 22.983421 -377.976638)
			(xy 22.988361 -377.991958) (xy 22.997606 -378.050761) (xy 22.998176 -378.080524) (xy 22.997696 -378.10853)
			(xy 22.989523 -378.163942) (xy 22.973341 -378.217566) (xy 22.949498 -378.26825) (xy 22.918505 -378.314906)
			(xy 22.900132 -378.336048) (xy 22.893528 -378.343414) (xy 22.886924 -378.36094) (xy 22.888448 -378.450348)
			(xy 22.895814 -378.46762) (xy 22.902672 -378.474732) (xy 22.922864 -378.496215) (xy 22.957006 -378.544279)
			(xy 22.983348 -378.597023) (xy 23.001265 -378.653191) (xy 23.010329 -378.711446) (xy 23.010876 -378.740924)
			(xy 23.01039 -378.768175) (xy 23.002634 -378.822123) (xy 22.987279 -378.874418) (xy 22.964637 -378.923995)
			(xy 22.935171 -378.969845) (xy 22.89948 -379.011036) (xy 22.858289 -379.046727) (xy 22.812439 -379.076193)
			(xy 22.762862 -379.098835) (xy 22.710567 -379.11419) (xy 22.656619 -379.121946) (xy 22.602117 -379.121946)
			(xy 22.548169 -379.11419) (xy 22.495874 -379.098835) (xy 22.446297 -379.076193) (xy 22.400447 -379.046727)
			(xy 22.359256 -379.011036) (xy 22.323565 -378.969845) (xy 22.294099 -378.923995) (xy 22.271457 -378.874418)
			(xy 22.256102 -378.822123) (xy 22.248346 -378.768175) (xy 22.24786 -378.740924) (xy 22.248385 -378.71292)
			(xy 22.256549 -378.65751) (xy 22.272722 -378.603888) (xy 22.296554 -378.553203) (xy 22.327536 -378.506545)
			(xy 22.345904 -378.4854) (xy 22.352508 -378.478034) (xy 22.359112 -378.460508) (xy 22.357588 -378.3711)
			(xy 22.350222 -378.353828) (xy 22.343364 -378.346716) (xy 22.323201 -378.325207) (xy 22.289054 -378.277151)
			(xy 22.262705 -378.224414) (xy 22.244782 -378.168251) (xy 22.23571 -378.11) (xy 22.23516 -378.080524)
			(xy 22.235614 -378.053589) (xy 22.243206 -378.000258) (xy 22.258227 -377.948525) (xy 22.280379 -377.899421)
			(xy 22.30922 -377.853922) (xy 22.326346 -377.833128) (xy 22.333204 -377.825) (xy 22.3393 -377.804934)
			(xy 22.328378 -377.709938) (xy 22.31771 -377.69165) (xy 22.309074 -377.6853) (xy 22.28543 -377.667212)
			(xy 22.243569 -377.624889) (xy 22.208792 -377.576575) (xy 22.181946 -377.523443) (xy 22.163683 -377.466786)
			(xy 22.154445 -377.407978) (xy 22.15388 -377.378214) (xy 22.154378 -377.349296) (xy 22.163107 -377.292122)
			(xy 22.180367 -377.236922) (xy 22.205762 -377.18496) (xy 22.238711 -377.137426) (xy 22.278458 -377.095412)
			(xy 22.300946 -377.077224) (xy 22.3097 -377.069655) (xy 22.319886 -377.048901) (xy 22.320504 -377.037346)
			(xy 22.320504 -376.957082) (xy 22.319942 -376.945513) (xy 22.309741 -376.924742) (xy 22.300946 -376.917204)
			(xy 22.280177 -376.900434) (xy 22.243048 -376.862082) (xy 22.211628 -376.818929) (xy 22.18653 -376.771818)
			(xy 22.168243 -376.721668) (xy 22.157126 -376.669458) (xy 22.153395 -376.616209) (xy 21.154341 -376.616209)
			(xy 21.161067 -376.647798) (xy 21.164797 -376.70105) (xy 21.161067 -376.754302) (xy 21.14995 -376.806513)
			(xy 21.131664 -376.856665) (xy 21.106565 -376.903779) (xy 21.075144 -376.946934) (xy 21.038013 -376.985287)
			(xy 21.01723 -377.00204) (xy 21.008443 -377.009577) (xy 20.998276 -377.030355) (xy 20.997672 -377.041918)
			(xy 20.997672 -377.122182) (xy 20.998228 -377.133752) (xy 21.00843 -377.154525) (xy 21.01723 -377.16206)
			(xy 21.039701 -377.180266) (xy 21.079435 -377.222284) (xy 21.112375 -377.269816) (xy 21.137765 -377.321774)
			(xy 21.155025 -377.376968) (xy 21.163758 -377.434135) (xy 21.164296 -377.46305) (xy 21.163853 -377.49088)
			(xy 21.155772 -377.545949) (xy 21.139772 -377.599259) (xy 21.116195 -377.649678) (xy 21.085541 -377.696135)
			(xy 21.048461 -377.737644) (xy 21.005742 -377.773324) (xy 20.958291 -377.802416) (xy 20.932902 -377.813824)
			(xy 20.92325 -377.817888) (xy 20.909026 -377.83262) (xy 20.875752 -377.920758) (xy 20.876768 -377.941332)
			(xy 20.881086 -377.95073) (xy 20.888452 -377.966986) (xy 20.892425 -377.975526) (xy 20.905503 -377.989068)
			(xy 20.922589 -377.996973) (xy 20.941376 -377.998175) (xy 20.959329 -377.992513) (xy 20.974027 -377.980749)
			(xy 20.97913 -377.972828) (xy 20.993908 -377.94856) (xy 21.029543 -377.904305) (xy 21.071346 -377.865824)
			(xy 21.118394 -377.833968) (xy 21.169645 -377.809441) (xy 21.223967 -377.792785) (xy 21.280159 -377.78437)
			(xy 21.308568 -377.783852) (xy 21.335817 -377.784408) (xy 21.38976 -377.792159) (xy 21.442051 -377.807508)
			(xy 21.491625 -377.830143) (xy 21.537474 -377.859602) (xy 21.578663 -377.895286) (xy 21.614355 -377.936469)
			(xy 21.643823 -377.982312) (xy 21.666467 -378.031882) (xy 21.681826 -378.08417) (xy 21.689587 -378.138111)
			(xy 21.690076 -378.16536) (xy 21.689633 -378.19266) (xy 21.681852 -378.246704) (xy 21.666445 -378.299085)
			(xy 21.643725 -378.348734) (xy 21.614157 -378.394636) (xy 21.596604 -378.41555) (xy 21.59 -378.422916)
			(xy 21.583904 -378.44095) (xy 21.587206 -378.530104) (xy 21.594826 -378.547376) (xy 21.601938 -378.554488)
			(xy 21.623017 -378.576118) (xy 21.658744 -378.624811) (xy 21.686349 -378.678527) (xy 21.705141 -378.735923)
			(xy 21.714652 -378.795563) (xy 21.715222 -378.82576) (xy 21.714729 -378.8545) (xy 21.706098 -378.911328)
			(xy 21.68904 -378.966219) (xy 21.663942 -379.01793) (xy 21.631371 -379.065292) (xy 21.612098 -379.086618)
			(xy 21.605494 -379.09373) (xy 21.598382 -379.111256) (xy 21.598382 -379.200664) (xy 21.605494 -379.21819)
			(xy 21.612098 -379.225302) (xy 21.631339 -379.246655) (xy 21.663911 -379.294009) (xy 21.689011 -379.345714)
			(xy 21.706068 -379.400599) (xy 21.714697 -379.457423) (xy 21.715222 -379.48616) (xy 21.714752 -379.51353)
			(xy 21.706938 -379.56771) (xy 21.691451 -379.620214) (xy 21.668609 -379.669961) (xy 21.638884 -379.715927)
			(xy 21.621242 -379.736858) (xy 21.615146 -379.74397) (xy 21.608796 -379.760988) (xy 21.608796 -379.846332)
			(xy 21.615146 -379.86335) (xy 21.621242 -379.870462) (xy 21.638884 -379.891392) (xy 21.668594 -379.937366)
			(xy 21.691429 -379.987114) (xy 21.706919 -380.039615) (xy 21.714748 -380.093791) (xy 21.715222 -380.12116)
			(xy 21.714631 -380.151355) (xy 21.705111 -380.210989) (xy 21.686316 -380.26838) (xy 21.658718 -380.322094)
			(xy 21.623003 -380.370792) (xy 21.601938 -380.392432) (xy 21.594826 -380.399544) (xy 21.587206 -380.416816)
			(xy 21.583904 -380.50597) (xy 21.59 -380.524004) (xy 21.596604 -380.53137) (xy 21.614134 -380.552301)
			(xy 21.643695 -380.598202) (xy 21.666411 -380.647848) (xy 21.68182 -380.700224) (xy 21.689607 -380.754262)
			(xy 21.690076 -380.78156) (xy 21.689631 -380.807303) (xy 21.68954 -380.807976) (xy 25.408128 -380.807976)
			(xy 25.408547 -380.781076) (xy 25.416102 -380.727809) (xy 25.431074 -380.676133) (xy 25.453165 -380.627077)
			(xy 25.481935 -380.581616) (xy 25.516812 -380.540652) (xy 25.536652 -380.52248) (xy 25.544526 -380.515368)
			(xy 25.553416 -380.496826) (xy 25.556718 -380.402084) (xy 25.549352 -380.383034) (xy 25.541986 -380.375414)
			(xy 25.521744 -380.353929) (xy 25.487525 -380.305831) (xy 25.461121 -380.253037) (xy 25.443162 -380.196807)
			(xy 25.434077 -380.138482) (xy 25.433528 -380.108968) (xy 25.433968 -380.081597) (xy 25.441791 -380.027416)
			(xy 25.457286 -379.974913) (xy 25.480134 -379.925166) (xy 25.509864 -379.879201) (xy 25.527508 -379.85827)
			(xy 25.533604 -379.851158) (xy 25.539954 -379.83414) (xy 25.539954 -379.748796) (xy 25.533604 -379.731778)
			(xy 25.527508 -379.724666) (xy 25.509888 -379.703719) (xy 25.480173 -379.65775) (xy 25.457333 -379.608007)
			(xy 25.441838 -379.555509) (xy 25.434005 -379.501336) (xy 25.433528 -379.473968) (xy 25.434095 -379.444527)
			(xy 25.443132 -379.386344) (xy 25.461004 -379.33024) (xy 25.487284 -379.277549) (xy 25.521349 -379.229522)
			(xy 25.541478 -379.20803) (xy 25.54859 -379.200918) (xy 25.555956 -379.182122) (xy 25.554178 -379.089412)
			(xy 25.54605 -379.071124) (xy 25.538684 -379.064012) (xy 25.520399 -379.045947) (xy 25.488359 -379.005753)
			(xy 25.462003 -378.961624) (xy 25.441808 -378.914356) (xy 25.428139 -378.864805) (xy 25.421245 -378.813869)
			(xy 25.420828 -378.788168) (xy 25.421225 -378.760913) (xy 25.428987 -378.706957) (xy 25.444349 -378.654656)
			(xy 25.466998 -378.605073) (xy 25.496473 -378.559219) (xy 25.532174 -378.518025) (xy 25.573373 -378.482332)
			(xy 25.619233 -378.452866) (xy 25.66882 -378.430226) (xy 25.721124 -378.414873) (xy 25.775081 -378.40712)
			(xy 25.802336 -378.40666) (xy 25.831075 -378.407173) (xy 25.887903 -378.415799) (xy 25.942793 -378.432853)
			(xy 25.994505 -378.457947) (xy 26.041867 -378.490513) (xy 26.063194 -378.509784) (xy 26.070306 -378.516388)
			(xy 26.087832 -378.5235) (xy 26.17724 -378.5235) (xy 26.194766 -378.516388) (xy 26.201878 -378.509784)
			(xy 26.223205 -378.490514) (xy 26.270568 -378.457949) (xy 26.322279 -378.432858) (xy 26.37717 -378.415808)
			(xy 26.433997 -378.407186) (xy 26.491475 -378.407186) (xy 26.548302 -378.415808) (xy 26.603193 -378.432858)
			(xy 26.654904 -378.457949) (xy 26.702267 -378.490514) (xy 26.723594 -378.509784) (xy 26.730706 -378.516388)
			(xy 26.748232 -378.5235) (xy 26.83764 -378.5235) (xy 26.855166 -378.516388) (xy 26.862278 -378.509784)
			(xy 26.883597 -378.490504) (xy 26.93096 -378.457937) (xy 26.982674 -378.432846) (xy 27.037567 -378.415797)
			(xy 27.094396 -378.407178) (xy 27.123136 -378.40666) (xy 27.152189 -378.40722) (xy 27.209625 -378.416011)
			(xy 27.265063 -378.433414) (xy 27.317218 -378.459027) (xy 27.364884 -378.492256) (xy 27.406957 -378.532332)
			(xy 27.425142 -378.554996) (xy 27.432254 -378.56414) (xy 27.45232 -378.5743) (xy 27.554428 -378.57684)
			(xy 27.575002 -378.567696) (xy 27.582622 -378.558806) (xy 27.600825 -378.538308) (xy 27.642111 -378.502243)
			(xy 27.688133 -378.472457) (xy 27.737943 -378.449563) (xy 27.790517 -378.434032) (xy 27.844772 -378.426185)
			(xy 27.872182 -378.42571) (xy 27.899435 -378.426172) (xy 27.953387 -378.433927) (xy 28.005686 -378.449282)
			(xy 28.055267 -378.471923) (xy 28.101121 -378.501391) (xy 28.142315 -378.537085) (xy 28.178009 -378.578279)
			(xy 28.207477 -378.624133) (xy 28.230118 -378.673714) (xy 28.245473 -378.726013) (xy 28.253228 -378.779965)
			(xy 28.25369 -378.807218) (xy 28.25318 -378.835957) (xy 28.244554 -378.892786) (xy 28.227501 -378.947677)
			(xy 28.202407 -378.999388) (xy 28.169838 -379.04675) (xy 28.150566 -379.068076) (xy 28.143962 -379.075188)
			(xy 28.13685 -379.092714) (xy 28.13685 -379.182122) (xy 28.143962 -379.199648) (xy 28.150566 -379.20676)
			(xy 28.169855 -379.228071) (xy 28.202421 -379.275436) (xy 28.227512 -379.32715) (xy 28.244561 -379.382043)
			(xy 28.253182 -379.438873) (xy 28.25318 -379.496353) (xy 28.244555 -379.553182) (xy 28.227502 -379.608074)
			(xy 28.202407 -379.659787) (xy 28.169839 -379.707149) (xy 28.150566 -379.728476) (xy 28.143962 -379.735588)
			(xy 28.13685 -379.753114) (xy 28.13685 -379.842522) (xy 28.143962 -379.860048) (xy 28.150566 -379.86716)
			(xy 28.169846 -379.888479) (xy 28.202411 -379.935843) (xy 28.227501 -379.987557) (xy 28.24455 -380.04245)
			(xy 28.25317 -380.099278) (xy 28.25369 -380.128018) (xy 28.25311 -380.157458) (xy 28.244074 -380.215641)
			(xy 28.226206 -380.271744) (xy 28.199929 -380.324436) (xy 28.165867 -380.372464) (xy 28.14574 -380.393956)
			(xy 28.138882 -380.401068) (xy 28.131516 -380.418848) (xy 28.130754 -380.509018) (xy 28.137866 -380.527052)
			(xy 28.144724 -380.534418) (xy 28.164114 -380.555734) (xy 28.196836 -380.603167) (xy 28.222048 -380.654983)
			(xy 28.239178 -380.710002) (xy 28.247835 -380.766972) (xy 28.248356 -380.795784) (xy 28.247898 -380.823389)
			(xy 28.239929 -380.87802) (xy 28.224171 -380.930933) (xy 28.200952 -380.981023) (xy 28.170757 -381.027244)
			(xy 28.152852 -381.04826) (xy 28.146248 -381.05588) (xy 28.139644 -381.07493) (xy 28.145486 -381.166624)
			(xy 28.154122 -381.184912) (xy 28.161742 -381.191516) (xy 28.181621 -381.209687) (xy 28.216553 -381.250681)
			(xy 28.245368 -381.296182) (xy 28.267495 -381.345285) (xy 28.282492 -381.397013) (xy 28.290061 -381.450337)
			(xy 28.29052 -381.477266) (xy 28.290013 -381.504517) (xy 28.282261 -381.558466) (xy 28.26691 -381.610763)
			(xy 28.244272 -381.660342) (xy 28.214809 -381.706194) (xy 28.17912 -381.747387) (xy 28.137931 -381.783081)
			(xy 28.092082 -381.81255) (xy 28.042506 -381.835194) (xy 27.990211 -381.850551) (xy 27.936263 -381.85831)
			(xy 27.909012 -381.858774) (xy 27.882656 -381.858307) (xy 27.830447 -381.851041) (xy 27.779735 -381.836659)
			(xy 27.731484 -381.815435) (xy 27.686613 -381.787773) (xy 27.645976 -381.754199) (xy 27.627834 -381.735076)
			(xy 27.620722 -381.727456) (xy 27.602942 -381.719074) (xy 27.51074 -381.714756) (xy 27.492198 -381.721614)
			(xy 27.484578 -381.728472) (xy 27.463411 -381.747032) (xy 27.41662 -381.778333) (xy 27.365739 -381.802421)
			(xy 27.311871 -381.818773) (xy 27.256186 -381.827034) (xy 27.228038 -381.827532) (xy 27.200375 -381.827041)
			(xy 27.145625 -381.819074) (xy 27.0926 -381.803286) (xy 27.042409 -381.780008) (xy 26.996104 -381.749729)
			(xy 26.975054 -381.731774) (xy 26.967942 -381.72517) (xy 26.950162 -381.71882) (xy 26.86177 -381.720598)
			(xy 26.844244 -381.727964) (xy 26.837386 -381.734568) (xy 26.81591 -381.754503) (xy 26.768013 -381.788255)
			(xy 26.71552 -381.814291) (xy 26.659666 -381.831999) (xy 26.601761 -381.840963) (xy 26.572464 -381.841502)
			(xy 26.546974 -381.84109) (xy 26.496449 -381.834307) (xy 26.447277 -381.820855) (xy 26.400335 -381.800972)
			(xy 26.35646 -381.775012) (xy 26.316435 -381.74344) (xy 26.298398 -381.725424) (xy 26.291032 -381.717804)
			(xy 26.271728 -381.709676) (xy 26.17597 -381.711454) (xy 26.15692 -381.720344) (xy 26.149808 -381.728218)
			(xy 26.131629 -381.747742) (xy 26.090799 -381.782074) (xy 26.045582 -381.810379) (xy 25.996861 -381.832107)
			(xy 25.945588 -381.846831) (xy 25.892763 -381.854265) (xy 25.86609 -381.85471) (xy 25.838839 -381.854232)
			(xy 25.784891 -381.846474) (xy 25.732596 -381.831117) (xy 25.683019 -381.808475) (xy 25.637169 -381.779008)
			(xy 25.595978 -381.743316) (xy 25.560287 -381.702125) (xy 25.530821 -381.656274) (xy 25.50818 -381.606697)
			(xy 25.492825 -381.554401) (xy 25.485068 -381.500453) (xy 25.484582 -381.473202) (xy 25.485165 -381.442144)
			(xy 25.495229 -381.38085) (xy 25.515091 -381.321996) (xy 25.544226 -381.267138) (xy 25.56256 -381.242062)
			(xy 25.568656 -381.233934) (xy 25.57399 -381.215392) (xy 25.563576 -381.125476) (xy 25.554432 -381.108458)
			(xy 25.546558 -381.102108) (xy 25.52529 -381.083892) (xy 25.487817 -381.042282) (xy 25.456825 -380.995644)
			(xy 25.432982 -380.944977) (xy 25.416797 -380.891371) (xy 25.408618 -380.835974) (xy 25.408128 -380.807976)
			(xy 21.68954 -380.807976) (xy 21.682701 -380.85832) (xy 21.668976 -380.907942) (xy 21.648705 -380.955269)
			(xy 21.622254 -380.999441) (xy 21.60651 -381.019812) (xy 21.600668 -381.027178) (xy 21.59508 -381.044958)
			(xy 21.600414 -381.132334) (xy 21.608034 -381.149098) (xy 21.615146 -381.155956) (xy 21.633035 -381.17399)
			(xy 21.664398 -381.213947) (xy 21.690182 -381.257712) (xy 21.709931 -381.304511) (xy 21.723296 -381.353517)
			(xy 21.730041 -381.403862) (xy 21.730462 -381.42926) (xy 21.729976 -381.456511) (xy 21.72222 -381.510459)
			(xy 21.706865 -381.562754) (xy 21.684223 -381.612331) (xy 21.654757 -381.658181) (xy 21.619066 -381.699372)
			(xy 21.577875 -381.735063) (xy 21.532025 -381.764529) (xy 21.482448 -381.787171) (xy 21.430153 -381.802526)
			(xy 21.376205 -381.810282) (xy 21.321703 -381.810282) (xy 21.267755 -381.802526) (xy 21.21546 -381.787171)
			(xy 21.165883 -381.764529) (xy 21.120033 -381.735063) (xy 21.078842 -381.699372) (xy 21.043151 -381.658181)
			(xy 21.013685 -381.612331) (xy 20.991043 -381.562754) (xy 20.975688 -381.510459) (xy 20.967932 -381.456511)
			(xy 20.967446 -381.42926) (xy 20.967897 -381.403517) (xy 20.974825 -381.3525) (xy 20.988548 -381.302878)
			(xy 21.008819 -381.255551) (xy 21.035268 -381.211379) (xy 21.051012 -381.191008) (xy 21.056854 -381.183642)
			(xy 21.062442 -381.165862) (xy 21.057108 -381.078486) (xy 21.049488 -381.061722) (xy 21.042376 -381.054864)
			(xy 21.033534 -381.046143) (xy 21.016883 -381.027713) (xy 21.009102 -381.018034) (xy 21.001736 -381.008382)
			(xy 20.979892 -380.998222) (xy 20.87372 -381.001778) (xy 20.852638 -381.013208) (xy 20.84578 -381.023368)
			(xy 20.830474 -381.044859) (xy 20.794837 -381.083769) (xy 20.754179 -381.117397) (xy 20.709276 -381.145103)
			(xy 20.660984 -381.166358) (xy 20.610223 -381.180756) (xy 20.557963 -381.188023) (xy 20.531582 -381.188468)
			(xy 20.503346 -381.187942) (xy 20.447491 -381.179616) (xy 20.393474 -381.163148) (xy 20.342474 -381.138898)
			(xy 20.295605 -381.107396) (xy 20.253891 -381.06933) (xy 20.235672 -381.047752) (xy 20.228068 -381.039366)
			(xy 20.20761 -381.029744) (xy 20.196302 -381.02921) (xy 20.117562 -381.02921) (xy 20.106274 -381.02982)
			(xy 20.085845 -381.039433) (xy 20.078192 -381.047752) (xy 20.059979 -381.069337) (xy 20.018268 -381.107409)
			(xy 19.971399 -381.138916) (xy 19.920397 -381.163168) (xy 19.866377 -381.179636) (xy 19.810519 -381.187959)
			(xy 19.782282 -381.188468) (xy 19.753023 -381.187894) (xy 19.695192 -381.178951) (xy 19.639402 -381.161291)
			(xy 19.586959 -381.135327) (xy 19.539089 -381.101669) (xy 19.517614 -381.081788) (xy 19.510502 -381.07493)
			(xy 19.492468 -381.067564) (xy 19.402044 -381.067564) (xy 19.38401 -381.07493) (xy 19.376898 -381.081788)
			(xy 19.355462 -381.101717) (xy 19.307591 -381.135391) (xy 19.25514 -381.16136) (xy 19.199338 -381.179014)
			(xy 19.141494 -381.187941) (xy 19.11223 -381.188468) (xy 19.08491 -381.188023) (xy 19.03083 -381.180225)
			(xy 18.978417 -381.164786) (xy 18.928746 -381.142022) (xy 18.882833 -381.112399) (xy 18.841621 -381.076524)
			(xy 18.823432 -381.056134) (xy 18.816066 -381.047752) (xy 18.796508 -381.038608) (xy 18.69821 -381.037592)
			(xy 18.678144 -381.046482) (xy 18.670778 -381.05461) (xy 18.652632 -381.074166) (xy 18.611793 -381.108492)
			(xy 18.566569 -381.136791) (xy 18.517842 -381.158512) (xy 18.466563 -381.17323) (xy 18.413734 -381.180659)
			(xy 18.38706 -381.181102) (xy 18.359807 -381.180659) (xy 18.305858 -381.172897) (xy 18.253562 -381.157537)
			(xy 18.203984 -381.134891) (xy 18.158134 -381.10542) (xy 18.116944 -381.069724) (xy 18.081253 -381.028529)
			(xy 18.051787 -380.982675) (xy 18.029147 -380.933095) (xy 18.013793 -380.880797) (xy 18.006037 -380.826847)
			(xy 18.005552 -380.799594) (xy 16.644405 -380.799594) (xy 16.636875 -380.851676) (xy 16.621374 -380.90418)
			(xy 16.598523 -380.953928) (xy 16.568792 -380.999896) (xy 16.551148 -381.020828) (xy 16.545052 -381.02794)
			(xy 16.538702 -381.044958) (xy 16.538702 -381.130302) (xy 16.545052 -381.14732) (xy 16.551148 -381.154432)
			(xy 16.568761 -381.175386) (xy 16.598478 -381.221352) (xy 16.62132 -381.271094) (xy 16.636817 -381.32359)
			(xy 16.644651 -381.377762) (xy 16.645128 -381.40513) (xy 16.644642 -381.432381) (xy 16.636886 -381.486329)
			(xy 16.621531 -381.538624) (xy 16.598889 -381.588201) (xy 16.569423 -381.634051) (xy 16.533732 -381.675242)
			(xy 16.492541 -381.710933) (xy 16.446691 -381.740399) (xy 16.397114 -381.763041) (xy 16.344819 -381.778396)
			(xy 16.290871 -381.786152) (xy 16.236369 -381.786152) (xy 16.182421 -381.778396) (xy 16.130126 -381.763041)
			(xy 16.080549 -381.740399) (xy 16.034699 -381.710933) (xy 15.993508 -381.675242) (xy 15.957817 -381.634051)
			(xy 15.928351 -381.588201) (xy 15.905709 -381.538624) (xy 15.890354 -381.486329) (xy 15.882598 -381.432381)
			(xy 15.882112 -381.40513) (xy 7.291446 -381.40513) (xy 7.291578 -381.41402) (xy 7.291069 -381.442613)
			(xy 7.282534 -381.499159) (xy 7.265655 -381.553798) (xy 7.24081 -381.605306) (xy 7.208554 -381.652527)
			(xy 7.169612 -381.694405) (xy 7.124854 -381.730002) (xy 7.075285 -381.758518) (xy 7.022015 -381.779317)
			(xy 6.966237 -381.791931) (xy 6.937756 -381.794512) (xy 6.928534 -381.79555) (xy 6.911719 -381.803362)
			(xy 6.90499 -381.809752) (xy 6.883908 -381.831342) (xy 6.877328 -381.838724) (xy 6.86988 -381.857023)
			(xy 6.86943 -381.866902) (xy 6.86943 -384.16738) (xy 6.869868 -384.177443) (xy 6.877607 -384.196024)
			(xy 6.884416 -384.203448) (xy 7.764526 -385.083558) (xy 7.771924 -385.090405) (xy 7.790522 -385.098137)
			(xy 7.800594 -385.098544) (xy 10.09523 -385.098544) (xy 10.105297 -385.098974) (xy 10.123889 -385.106701)
			(xy 10.131298 -385.11353) (xy 12.996672 -387.978904) (xy 13.003521 -387.986301) (xy 13.011258 -388.0049)
			(xy 13.011658 -388.014972) (xy 13.011658 -389.306054) (xy 13.012093 -389.316119) (xy 13.019827 -389.334703)
			(xy 13.026644 -389.342122) (xy 13.256006 -389.571484) (xy 20.902166 -389.571484) (xy 20.906237 -389.515862)
			(xy 20.918363 -389.461425) (xy 20.938286 -389.409334) (xy 20.965582 -389.360699) (xy 20.999668 -389.316556)
			(xy 21.039817 -389.277847) (xy 21.085175 -389.245396) (xy 21.134775 -389.219895) (xy 21.187559 -389.201888)
			(xy 21.242402 -389.191758) (xy 21.298136 -389.189721) (xy 21.353573 -389.195821) (xy 21.40753 -389.209927)
			(xy 21.458859 -389.231739) (xy 21.506465 -389.260793) (xy 21.549333 -389.296468) (xy 21.58655 -389.338005)
			(xy 21.617323 -389.384518) (xy 21.640995 -389.435015) (xy 21.657063 -389.488422) (xy 21.665183 -389.543598)
			(xy 21.665692 -389.571484) (xy 21.665183 -389.59937) (xy 21.657063 -389.654546) (xy 21.640995 -389.707953)
			(xy 21.617323 -389.75845) (xy 21.58655 -389.804963) (xy 21.549333 -389.8465) (xy 21.506465 -389.882175)
			(xy 21.458859 -389.911229) (xy 21.40753 -389.933041) (xy 21.353573 -389.947147) (xy 21.298136 -389.953247)
			(xy 21.242402 -389.95121) (xy 21.187559 -389.94108) (xy 21.134775 -389.923073) (xy 21.085175 -389.897572)
			(xy 21.039817 -389.865121) (xy 20.999668 -389.826412) (xy 20.965582 -389.782269) (xy 20.938286 -389.733634)
			(xy 20.918363 -389.681543) (xy 20.906237 -389.627106) (xy 20.902166 -389.571484) (xy 13.256006 -389.571484)
			(xy 13.601954 -389.917432) (xy 13.6088 -389.92483) (xy 13.61653 -389.943429) (xy 13.61694 -389.9535)
			(xy 13.61694 -390.89228) (xy 16.845547 -390.89228) (xy 16.849529 -390.839131) (xy 16.861389 -390.787169)
			(xy 16.880861 -390.737556) (xy 16.90751 -390.691398) (xy 16.940741 -390.649728) (xy 16.979811 -390.613476)
			(xy 17.023848 -390.583452) (xy 17.071868 -390.560327) (xy 17.122798 -390.544617) (xy 17.175501 -390.536674)
			(xy 17.20215 -390.536176) (xy 17.22851 -390.536672) (xy 17.280651 -390.544458) (xy 17.331072 -390.559853)
			(xy 17.37867 -390.582519) (xy 17.422403 -390.61196) (xy 17.44218 -390.629394) (xy 17.449292 -390.635744)
			(xy 17.467072 -390.642602) (xy 17.554448 -390.642602) (xy 17.572228 -390.635744) (xy 17.57934 -390.629394)
			(xy 17.599135 -390.611984) (xy 17.642872 -390.582557) (xy 17.690467 -390.559894) (xy 17.74088 -390.544488)
			(xy 17.793013 -390.536675) (xy 17.81937 -390.536176) (xy 17.84573 -390.53666) (xy 17.897872 -390.544449)
			(xy 17.948294 -390.559846) (xy 17.995891 -390.582515) (xy 18.039623 -390.611959) (xy 18.0594 -390.629394)
			(xy 18.066512 -390.635744) (xy 18.084292 -390.642602) (xy 18.171668 -390.642602) (xy 18.189448 -390.635744)
			(xy 18.19656 -390.629394) (xy 18.216347 -390.611974) (xy 18.260086 -390.582549) (xy 18.307683 -390.559888)
			(xy 18.358098 -390.544484) (xy 18.410232 -390.536674) (xy 18.43659 -390.536176) (xy 18.461586 -390.536601)
			(xy 18.511085 -390.543597) (xy 18.559123 -390.55744) (xy 18.604755 -390.577857) (xy 18.647087 -390.604449)
			(xy 18.66646 -390.62025) (xy 18.673572 -390.626346) (xy 18.690082 -390.632442) (xy 18.774156 -390.632442)
			(xy 18.790666 -390.626346) (xy 18.797778 -390.62025) (xy 18.817138 -390.604432) (xy 18.85947 -390.577833)
			(xy 18.905105 -390.557415) (xy 18.953146 -390.543578) (xy 19.002651 -390.536595) (xy 19.027648 -390.536176)
			(xy 19.053974 -390.536628) (xy 19.106051 -390.544396) (xy 19.156413 -390.559754) (xy 19.203962 -390.582368)
			(xy 19.247659 -390.611743) (xy 19.267424 -390.62914) (xy 19.277076 -390.637776) (xy 19.301714 -390.643872)
			(xy 19.408648 -390.616948) (xy 19.427444 -390.599676) (xy 19.431762 -390.587738) (xy 19.44086 -390.563228)
			(xy 19.464763 -390.516732) (xy 19.494791 -390.473936) (xy 19.530383 -390.435642) (xy 19.57087 -390.402567)
			(xy 19.615495 -390.37533) (xy 19.663421 -390.354442) (xy 19.71375 -390.340295) (xy 19.76554 -390.333153)
			(xy 19.79168 -390.332722) (xy 19.818936 -390.333124) (xy 19.872893 -390.340879) (xy 19.925198 -390.356234)
			(xy 19.974784 -390.378878) (xy 20.020644 -390.408347) (xy 20.061842 -390.444044) (xy 20.087094 -390.473184)
			(xy 20.905976 -390.473184) (xy 20.910047 -390.417562) (xy 20.922173 -390.363125) (xy 20.942096 -390.311034)
			(xy 20.969392 -390.262399) (xy 21.003478 -390.218256) (xy 21.043627 -390.179547) (xy 21.088985 -390.147096)
			(xy 21.138585 -390.121595) (xy 21.191369 -390.103588) (xy 21.246212 -390.093458) (xy 21.301946 -390.091421)
			(xy 21.357383 -390.097521) (xy 21.41134 -390.111627) (xy 21.462669 -390.133439) (xy 21.510275 -390.162493)
			(xy 21.553143 -390.198168) (xy 21.59036 -390.239705) (xy 21.621133 -390.286218) (xy 21.644805 -390.336715)
			(xy 21.660873 -390.390122) (xy 21.668993 -390.445298) (xy 21.669502 -390.473184) (xy 21.668993 -390.50107)
			(xy 21.660873 -390.556246) (xy 21.644805 -390.609653) (xy 21.621133 -390.66015) (xy 21.59036 -390.706663)
			(xy 21.553143 -390.7482) (xy 21.510275 -390.783875) (xy 21.462669 -390.812929) (xy 21.41134 -390.834741)
			(xy 21.357383 -390.848847) (xy 21.301946 -390.854947) (xy 21.246212 -390.85291) (xy 21.191369 -390.84278)
			(xy 21.138585 -390.824773) (xy 21.088985 -390.799272) (xy 21.043627 -390.766821) (xy 21.003478 -390.728112)
			(xy 20.969392 -390.683969) (xy 20.942096 -390.635334) (xy 20.922173 -390.583243) (xy 20.910047 -390.528806)
			(xy 20.905976 -390.473184) (xy 20.087094 -390.473184) (xy 20.097541 -390.48524) (xy 20.127013 -390.531098)
			(xy 20.149659 -390.580683) (xy 20.165017 -390.632987) (xy 20.172775 -390.686944) (xy 20.172775 -390.741456)
			(xy 20.165017 -390.795413) (xy 20.149659 -390.847717) (xy 20.129297 -390.8923) (xy 25.924276 -390.8923)
			(xy 25.928259 -390.839151) (xy 25.940119 -390.787188) (xy 25.95959 -390.737574) (xy 25.986238 -390.691416)
			(xy 26.019467 -390.649744) (xy 26.058536 -390.613491) (xy 26.102572 -390.583464) (xy 26.150591 -390.560336)
			(xy 26.20152 -390.544623) (xy 26.254223 -390.536676) (xy 26.280872 -390.536176) (xy 26.307232 -390.536658)
			(xy 26.359374 -390.544448) (xy 26.409796 -390.559846) (xy 26.457393 -390.582515) (xy 26.501125 -390.611959)
			(xy 26.520902 -390.629394) (xy 26.528014 -390.635744) (xy 26.545794 -390.642602) (xy 26.63317 -390.642602)
			(xy 26.65095 -390.635744) (xy 26.658062 -390.629394) (xy 26.677848 -390.611973) (xy 26.721588 -390.582548)
			(xy 26.769185 -390.559887) (xy 26.8196 -390.544484) (xy 26.871734 -390.536674) (xy 26.898092 -390.536176)
			(xy 26.924453 -390.536646) (xy 26.976595 -390.544439) (xy 27.027017 -390.55984) (xy 27.074614 -390.582511)
			(xy 27.118346 -390.611958) (xy 27.138122 -390.629394) (xy 27.145234 -390.635744) (xy 27.163014 -390.642602)
			(xy 27.25039 -390.642602) (xy 27.26817 -390.635744) (xy 27.275282 -390.629394) (xy 27.29506 -390.611964)
			(xy 27.338802 -390.58254) (xy 27.386401 -390.559881) (xy 27.436818 -390.54448) (xy 27.488954 -390.536672)
			(xy 27.515312 -390.536176) (xy 27.540308 -390.536589) (xy 27.589808 -390.543588) (xy 27.637846 -390.557433)
			(xy 27.683478 -390.577853) (xy 27.72581 -390.604448) (xy 27.745182 -390.62025) (xy 27.752294 -390.626346)
			(xy 27.768804 -390.632442) (xy 27.852878 -390.632442) (xy 27.869388 -390.626346) (xy 27.8765 -390.62025)
			(xy 27.895852 -390.604422) (xy 27.938186 -390.577825) (xy 27.983823 -390.557409) (xy 28.031866 -390.543574)
			(xy 28.081372 -390.536593) (xy 28.10637 -390.536176) (xy 28.133805 -390.53668) (xy 28.188024 -390.545101)
			(xy 28.21432 -390.55294) (xy 28.22575 -390.556496) (xy 28.24861 -390.553194) (xy 28.334462 -390.49452)
			(xy 28.345892 -390.4742) (xy 28.346654 -390.462516) (xy 28.348971 -390.433797) (xy 28.361097 -390.377473)
			(xy 28.381556 -390.323614) (xy 28.409882 -390.273444) (xy 28.445432 -390.228105) (xy 28.487397 -390.188628)
			(xy 28.534821 -390.155912) (xy 28.586626 -390.130701) (xy 28.641634 -390.113568) (xy 28.698593 -390.104903)
			(xy 28.7274 -390.104376) (xy 28.75465 -390.104894) (xy 28.808595 -390.11265) (xy 28.860888 -390.128005)
			(xy 28.910463 -390.150645) (xy 28.956311 -390.18011) (xy 28.9975 -390.2158) (xy 29.03319 -390.256989)
			(xy 29.062655 -390.302837) (xy 29.085295 -390.352412) (xy 29.10065 -390.404705) (xy 29.108406 -390.45865)
			(xy 29.108406 -390.51315) (xy 29.10065 -390.567095) (xy 29.085295 -390.619388) (xy 29.062655 -390.668963)
			(xy 29.03319 -390.714811) (xy 28.9975 -390.756) (xy 28.956311 -390.79169) (xy 28.910463 -390.821155)
			(xy 28.860888 -390.843795) (xy 28.808595 -390.85915) (xy 28.75465 -390.866906) (xy 28.7274 -390.867392)
			(xy 28.693996 -390.866697) (xy 28.628208 -390.855075) (xy 28.59659 -390.844278) (xy 28.585414 -390.840214)
			(xy 28.5623 -390.8425) (xy 28.474162 -390.897618) (xy 28.461716 -390.91743) (xy 28.460446 -390.929114)
			(xy 28.457324 -390.955063) (xy 28.444379 -391.0057) (xy 28.424171 -391.053902) (xy 28.397134 -391.098631)
			(xy 28.36385 -391.138928) (xy 28.325032 -391.173926) (xy 28.281516 -391.202875) (xy 28.234235 -391.225151)
			(xy 28.184206 -391.240277) (xy 28.132503 -391.247927) (xy 28.10637 -391.248392) (xy 28.081375 -391.24794)
			(xy 28.031876 -391.240951) (xy 27.983839 -391.227115) (xy 27.938206 -391.206704) (xy 27.895873 -391.180117)
			(xy 27.8765 -391.164318) (xy 27.869388 -391.158222) (xy 27.852878 -391.152126) (xy 27.768804 -391.152126)
			(xy 27.752294 -391.158222) (xy 27.745182 -391.164318) (xy 27.725796 -391.180103) (xy 27.683472 -391.206708)
			(xy 27.637844 -391.227133) (xy 27.589808 -391.240977) (xy 27.540308 -391.247969) (xy 27.515312 -391.248392)
			(xy 27.488951 -391.247927) (xy 27.436808 -391.240135) (xy 27.386386 -391.224733) (xy 27.338788 -391.20206)
			(xy 27.295058 -391.172611) (xy 27.275282 -391.155174) (xy 27.26817 -391.148824) (xy 27.25039 -391.141966)
			(xy 27.163014 -391.141966) (xy 27.145234 -391.148824) (xy 27.138122 -391.155174) (xy 27.118352 -391.172614)
			(xy 27.074607 -391.202033) (xy 27.027006 -391.22469) (xy 26.976587 -391.24009) (xy 26.924451 -391.247896)
			(xy 26.898092 -391.248392) (xy 26.871731 -391.247939) (xy 26.819587 -391.240144) (xy 26.769165 -391.22474)
			(xy 26.721567 -391.202064) (xy 26.677837 -391.172612) (xy 26.658062 -391.155174) (xy 26.65095 -391.148824)
			(xy 26.63317 -391.141966) (xy 26.545794 -391.141966) (xy 26.528014 -391.148824) (xy 26.520902 -391.155174)
			(xy 26.50114 -391.172623) (xy 26.457393 -391.202042) (xy 26.40979 -391.224696) (xy 26.359369 -391.240094)
			(xy 26.307231 -391.247897) (xy 26.280872 -391.248392) (xy 26.254223 -391.247924) (xy 26.20152 -391.239977)
			(xy 26.150591 -391.224264) (xy 26.102572 -391.201136) (xy 26.058536 -391.171109) (xy 26.019467 -391.134856)
			(xy 25.986238 -391.093184) (xy 25.95959 -391.047026) (xy 25.940119 -390.997412) (xy 25.928259 -390.945449)
			(xy 25.924276 -390.8923) (xy 20.129297 -390.8923) (xy 20.127013 -390.897302) (xy 20.097541 -390.94316)
			(xy 20.061842 -390.984356) (xy 20.020644 -391.020053) (xy 19.974784 -391.049522) (xy 19.925198 -391.072166)
			(xy 19.872893 -391.087521) (xy 19.818936 -391.095276) (xy 19.79168 -391.095738) (xy 19.762096 -391.095179)
			(xy 19.703637 -391.086042) (xy 19.64729 -391.06799) (xy 19.594405 -391.041455) (xy 19.546251 -391.007075)
			(xy 19.524726 -390.986772) (xy 19.515582 -390.977882) (xy 19.491198 -390.97077) (xy 19.383248 -390.993884)
			(xy 19.363944 -391.010394) (xy 19.359118 -391.022332) (xy 19.348961 -391.046979) (xy 19.322322 -391.093153)
			(xy 19.289095 -391.134839) (xy 19.250024 -391.171104) (xy 19.205982 -391.201138) (xy 19.157955 -391.22427)
			(xy 19.107015 -391.239981) (xy 19.054302 -391.247922) (xy 19.027648 -391.248392) (xy 19.002653 -391.247952)
			(xy 18.953153 -391.240961) (xy 18.905116 -391.227122) (xy 18.859484 -391.206708) (xy 18.817151 -391.180118)
			(xy 18.797778 -391.164318) (xy 18.790666 -391.158222) (xy 18.774156 -391.152126) (xy 18.690082 -391.152126)
			(xy 18.673572 -391.158222) (xy 18.66646 -391.164318) (xy 18.647082 -391.180114) (xy 18.604756 -391.206717)
			(xy 18.559125 -391.22714) (xy 18.511088 -391.240982) (xy 18.461586 -391.247971) (xy 18.43659 -391.248392)
			(xy 18.410229 -391.247941) (xy 18.358085 -391.240145) (xy 18.307663 -391.22474) (xy 18.260065 -391.202064)
			(xy 18.216335 -391.172613) (xy 18.19656 -391.155174) (xy 18.189448 -391.148824) (xy 18.171668 -391.141966)
			(xy 18.084292 -391.141966) (xy 18.066512 -391.148824) (xy 18.0594 -391.155174) (xy 18.039599 -391.172577)
			(xy 17.995862 -391.202002) (xy 17.948269 -391.224666) (xy 17.897857 -391.240074) (xy 17.845726 -391.24789)
			(xy 17.81937 -391.248392) (xy 17.79301 -391.247893) (xy 17.740869 -391.240108) (xy 17.690447 -391.224715)
			(xy 17.642849 -391.202049) (xy 17.599117 -391.172608) (xy 17.57934 -391.155174) (xy 17.572228 -391.148824)
			(xy 17.554448 -391.141966) (xy 17.467072 -391.141966) (xy 17.449292 -391.148824) (xy 17.44218 -391.155174)
			(xy 17.422387 -391.172586) (xy 17.378648 -391.20201) (xy 17.331053 -391.224672) (xy 17.280639 -391.240078)
			(xy 17.228507 -391.247892) (xy 17.20215 -391.248392) (xy 17.175501 -391.247886) (xy 17.122798 -391.239943)
			(xy 17.071868 -391.224233) (xy 17.023848 -391.201108) (xy 16.979811 -391.171084) (xy 16.940741 -391.134832)
			(xy 16.90751 -391.093162) (xy 16.880861 -391.047004) (xy 16.861389 -390.997391) (xy 16.849529 -390.945429)
			(xy 16.845547 -390.89228) (xy 13.61694 -390.89228) (xy 13.61694 -391.761726) (xy 18.769076 -391.761726)
			(xy 18.769579 -391.734475) (xy 18.777332 -391.680526) (xy 18.792684 -391.62823) (xy 18.815323 -391.578651)
			(xy 18.844787 -391.532798) (xy 18.880476 -391.491606) (xy 18.921665 -391.455912) (xy 18.967514 -391.426443)
			(xy 19.01709 -391.403799) (xy 19.069385 -391.388441) (xy 19.123333 -391.380682) (xy 19.150584 -391.380218)
			(xy 19.176567 -391.380641) (xy 19.22805 -391.387704) (xy 19.278098 -391.401688) (xy 19.325786 -391.422335)
			(xy 19.370231 -391.449262) (xy 19.410611 -391.481971) (xy 19.428714 -391.500614) (xy 19.435826 -391.508234)
			(xy 19.454114 -391.516362) (xy 19.546824 -391.519156) (xy 19.56562 -391.51179) (xy 19.572986 -391.504678)
			(xy 19.594416 -391.48501) (xy 19.642122 -391.451735) (xy 19.694323 -391.42608) (xy 19.749811 -391.408639)
			(xy 19.807302 -391.399815) (xy 19.836384 -391.399268) (xy 19.863634 -391.399793) (xy 19.917579 -391.407547)
			(xy 19.969871 -391.422899) (xy 20.019447 -391.445536) (xy 20.065296 -391.474998) (xy 20.106486 -391.510686)
			(xy 20.142178 -391.551872) (xy 20.171645 -391.597718) (xy 20.194287 -391.647291) (xy 20.209645 -391.699582)
			(xy 20.215843 -391.742676) (xy 20.730716 -391.742676) (xy 20.734787 -391.687054) (xy 20.746913 -391.632617)
			(xy 20.766836 -391.580526) (xy 20.794132 -391.531891) (xy 20.828218 -391.487748) (xy 20.868367 -391.449039)
			(xy 20.913725 -391.416588) (xy 20.963325 -391.391087) (xy 21.016109 -391.37308) (xy 21.070952 -391.36295)
			(xy 21.126686 -391.360913) (xy 21.182123 -391.367013) (xy 21.23608 -391.381119) (xy 21.287409 -391.402931)
			(xy 21.335015 -391.431985) (xy 21.377883 -391.46766) (xy 21.4151 -391.509197) (xy 21.445873 -391.55571)
			(xy 21.469545 -391.606207) (xy 21.485613 -391.659614) (xy 21.493733 -391.71479) (xy 21.494242 -391.742676)
			(xy 21.493733 -391.770562) (xy 21.487557 -391.812526) (xy 27.862276 -391.812526) (xy 27.862779 -391.785275)
			(xy 27.870532 -391.731326) (xy 27.885884 -391.67903) (xy 27.908523 -391.629451) (xy 27.937987 -391.583598)
			(xy 27.973676 -391.542406) (xy 28.014865 -391.506712) (xy 28.060714 -391.477243) (xy 28.11029 -391.454599)
			(xy 28.162585 -391.439241) (xy 28.216533 -391.431482) (xy 28.243784 -391.431018) (xy 28.273907 -391.431608)
			(xy 28.333402 -391.441086) (xy 28.390669 -391.459793) (xy 28.444286 -391.487264) (xy 28.492922 -391.522818)
			(xy 28.514548 -391.543794) (xy 28.522422 -391.551668) (xy 28.542234 -391.559288) (xy 28.640024 -391.554208)
			(xy 28.659074 -391.544302) (xy 28.665932 -391.535666) (xy 28.68415 -391.513789) (xy 28.725992 -391.475185)
			(xy 28.773102 -391.443223) (xy 28.824436 -391.41861) (xy 28.878856 -391.401893) (xy 28.935155 -391.393442)
			(xy 28.96362 -391.392918) (xy 28.990875 -391.393336) (xy 29.044828 -391.401097) (xy 29.097129 -391.416457)
			(xy 29.146711 -391.439103) (xy 29.192565 -391.468576) (xy 29.233758 -391.504274) (xy 29.269452 -391.545472)
			(xy 29.298919 -391.59133) (xy 29.321559 -391.640914) (xy 29.336913 -391.693217) (xy 29.344667 -391.747171)
			(xy 29.345128 -391.774426) (xy 29.344717 -391.800035) (xy 29.337855 -391.850792) (xy 29.324271 -391.900177)
			(xy 29.304209 -391.947303) (xy 29.278029 -391.991325) (xy 29.246201 -392.031453) (xy 29.228034 -392.049508)
			(xy 29.218636 -392.058398) (xy 29.211016 -392.082782) (xy 29.231082 -392.191494) (xy 29.247084 -392.211306)
			(xy 29.259022 -392.216386) (xy 29.284595 -392.227703) (xy 29.332418 -392.256689) (xy 29.375495 -392.292347)
			(xy 29.412903 -392.333914) (xy 29.443839 -392.380499) (xy 29.46764 -392.431103) (xy 29.483795 -392.484639)
			(xy 29.491959 -392.539961) (xy 29.492448 -392.567922) (xy 29.491943 -392.595172) (xy 29.484184 -392.649117)
			(xy 29.468828 -392.701409) (xy 29.446188 -392.750983) (xy 29.416723 -392.796832) (xy 29.381034 -392.838021)
			(xy 29.339846 -392.873712) (xy 29.293999 -392.903179) (xy 29.244426 -392.925822) (xy 29.192135 -392.94118)
			(xy 29.13819 -392.948942) (xy 29.11094 -392.94943) (xy 29.080673 -392.948837) (xy 29.0209 -392.939271)
			(xy 28.963386 -392.920389) (xy 28.909575 -392.892664) (xy 28.860815 -392.856792) (xy 28.83916 -392.835638)
			(xy 28.832048 -392.828272) (xy 28.813506 -392.820652) (xy 28.720288 -392.820652) (xy 28.701746 -392.828272)
			(xy 28.694634 -392.835638) (xy 28.672998 -392.856814) (xy 28.624238 -392.892693) (xy 28.570422 -392.92042)
			(xy 28.512903 -392.939298) (xy 28.453123 -392.948853) (xy 28.422854 -392.94943) (xy 28.395603 -392.948965)
			(xy 28.341655 -392.941203) (xy 28.289362 -392.925843) (xy 28.239786 -392.903198) (xy 28.193936 -392.873729)
			(xy 28.152747 -392.838036) (xy 28.117057 -392.796844) (xy 28.08759 -392.750993) (xy 28.064949 -392.701416)
			(xy 28.049592 -392.649121) (xy 28.041833 -392.595173) (xy 28.041346 -392.567922) (xy 28.041819 -392.541189)
			(xy 28.049324 -392.488253) (xy 28.064134 -392.436879) (xy 28.085961 -392.38807) (xy 28.114378 -392.342781)
			(xy 28.131262 -392.32205) (xy 28.138882 -392.312652) (xy 28.14447 -392.289284) (xy 28.120086 -392.186414)
			(xy 28.104592 -392.167872) (xy 28.093416 -392.1633) (xy 28.068068 -392.151839) (xy 28.020679 -392.122711)
			(xy 27.978019 -392.087013) (xy 27.940992 -392.045501) (xy 27.910382 -391.999054) (xy 27.886838 -391.948656)
			(xy 27.870858 -391.895375) (xy 27.862781 -391.840339) (xy 27.862276 -391.812526) (xy 21.487557 -391.812526)
			(xy 21.485613 -391.825738) (xy 21.469545 -391.879145) (xy 21.445873 -391.929642) (xy 21.4151 -391.976155)
			(xy 21.377883 -392.017692) (xy 21.335015 -392.053367) (xy 21.287409 -392.082421) (xy 21.23608 -392.104233)
			(xy 21.182123 -392.118339) (xy 21.126686 -392.124439) (xy 21.070952 -392.122402) (xy 21.016109 -392.112272)
			(xy 20.963325 -392.094265) (xy 20.913725 -392.068764) (xy 20.868367 -392.036313) (xy 20.828218 -391.997604)
			(xy 20.794132 -391.953461) (xy 20.766836 -391.904826) (xy 20.746913 -391.852735) (xy 20.734787 -391.798298)
			(xy 20.730716 -391.742676) (xy 20.215843 -391.742676) (xy 20.217404 -391.753526) (xy 20.217892 -391.780776)
			(xy 20.217454 -391.807389) (xy 20.210053 -391.860097) (xy 20.195392 -391.911264) (xy 20.173755 -391.959893)
			(xy 20.145564 -392.00504) (xy 20.111367 -392.045826) (xy 20.091908 -392.063986) (xy 20.081748 -392.07313)
			(xy 20.07362 -392.099038) (xy 20.098004 -392.212068) (xy 20.116292 -392.232134) (xy 20.1295 -392.236198)
			(xy 20.154903 -392.244743) (xy 20.203216 -392.267948) (xy 20.247807 -392.297683) (xy 20.2878 -392.333364)
			(xy 20.322409 -392.374289) (xy 20.350951 -392.419653) (xy 20.372867 -392.468564) (xy 20.387726 -392.52006)
			(xy 20.395234 -392.573128) (xy 20.395692 -392.599926) (xy 20.395246 -392.627179) (xy 20.387486 -392.681129)
			(xy 20.372127 -392.733425) (xy 20.349481 -392.783003) (xy 20.341544 -392.795352) (xy 24.261552 -392.795352)
			(xy 24.261552 -392.740848) (xy 24.269308 -392.686899) (xy 24.284663 -392.634603) (xy 24.307303 -392.585024)
			(xy 24.336769 -392.539172) (xy 24.37246 -392.49798) (xy 24.41365 -392.462286) (xy 24.4595 -392.432817)
			(xy 24.509077 -392.410173) (xy 24.561372 -392.394814) (xy 24.61532 -392.387054) (xy 24.642572 -392.386566)
			(xy 24.668493 -392.386996) (xy 24.719856 -392.394035) (xy 24.769793 -392.407961) (xy 24.817387 -392.428516)
			(xy 24.861761 -392.455323) (xy 24.902098 -392.487889) (xy 24.920194 -392.506454) (xy 24.92756 -392.514328)
			(xy 24.946864 -392.522456) (xy 25.043384 -392.521186) (xy 25.062434 -392.51255) (xy 25.0698 -392.504422)
			(xy 25.087992 -392.484869) (xy 25.128845 -392.450472) (xy 25.174096 -392.42211) (xy 25.222861 -392.400337)
			(xy 25.274187 -392.385579) (xy 25.327069 -392.378126) (xy 25.353772 -392.377676) (xy 25.381025 -392.378169)
			(xy 25.434977 -392.385923) (xy 25.487276 -392.401276) (xy 25.536857 -392.423916) (xy 25.582712 -392.453382)
			(xy 25.623906 -392.489074) (xy 25.659601 -392.530266) (xy 25.689071 -392.576118) (xy 25.711714 -392.625698)
			(xy 25.727071 -392.677996) (xy 25.734829 -392.731947) (xy 25.734829 -392.786453) (xy 25.727071 -392.840404)
			(xy 25.711714 -392.892702) (xy 25.689071 -392.942282) (xy 25.659601 -392.988134) (xy 25.623906 -393.029326)
			(xy 25.582712 -393.065018) (xy 25.536857 -393.094484) (xy 25.487276 -393.117124) (xy 25.434977 -393.132477)
			(xy 25.381025 -393.140231) (xy 25.353772 -393.140692) (xy 25.327851 -393.140246) (xy 25.276489 -393.133212)
			(xy 25.226551 -393.119291) (xy 25.178957 -393.098738) (xy 25.134583 -393.071933) (xy 25.094245 -393.039369)
			(xy 25.07615 -393.020804) (xy 25.068784 -393.01293) (xy 25.04948 -393.004802) (xy 24.95296 -393.006072)
			(xy 24.93391 -393.014708) (xy 24.926544 -393.022836) (xy 24.908391 -393.042427) (xy 24.867529 -393.076819)
			(xy 24.822269 -393.105175) (xy 24.773496 -393.126941) (xy 24.722164 -393.14169) (xy 24.669277 -393.149136)
			(xy 24.642572 -393.149582) (xy 24.61532 -393.149146) (xy 24.561372 -393.141386) (xy 24.509077 -393.126027)
			(xy 24.4595 -393.103383) (xy 24.41365 -393.073914) (xy 24.37246 -393.03822) (xy 24.336769 -392.997028)
			(xy 24.307303 -392.951176) (xy 24.284663 -392.901597) (xy 24.269308 -392.849301) (xy 24.261552 -392.795352)
			(xy 20.341544 -392.795352) (xy 20.320011 -392.828855) (xy 20.284315 -392.870045) (xy 20.243121 -392.905736)
			(xy 20.197267 -392.935201) (xy 20.147686 -392.957841) (xy 20.095388 -392.973195) (xy 20.041437 -392.980949)
			(xy 20.014184 -392.981434) (xy 19.985268 -392.98088) (xy 19.928097 -392.972162) (xy 19.872898 -392.954913)
			(xy 19.820936 -392.929528) (xy 19.773401 -392.896589) (xy 19.731384 -392.856852) (xy 19.713194 -392.834368)
			(xy 19.705636 -392.825602) (xy 19.684874 -392.815422) (xy 19.673316 -392.81481) (xy 19.593052 -392.81481)
			(xy 19.581488 -392.815407) (xy 19.560716 -392.825583) (xy 19.553174 -392.834368) (xy 19.53499 -392.856857)
			(xy 19.492969 -392.896594) (xy 19.445433 -392.929533) (xy 19.393471 -392.954921) (xy 19.338272 -392.972175)
			(xy 19.281101 -392.980901) (xy 19.252184 -392.981434) (xy 19.224934 -392.980937) (xy 19.170988 -392.973179)
			(xy 19.118695 -392.957823) (xy 19.069119 -392.935182) (xy 19.02327 -392.905717) (xy 18.982081 -392.870026)
			(xy 18.946389 -392.828838) (xy 18.916923 -392.78299) (xy 18.89428 -392.733415) (xy 18.878923 -392.681122)
			(xy 18.871164 -392.627176) (xy 18.870676 -392.599926) (xy 18.871129 -392.574237) (xy 18.878021 -392.523325)
			(xy 18.891684 -392.473798) (xy 18.91187 -392.426553) (xy 18.938215 -392.382444) (xy 18.970241 -392.342271)
			(xy 19.007369 -392.306759) (xy 19.027902 -392.291316) (xy 19.039078 -392.283188) (xy 19.050254 -392.257788)
			(xy 19.036284 -392.142218) (xy 19.01952 -392.12012) (xy 19.006566 -392.11504) (xy 18.980604 -392.103918)
			(xy 18.932023 -392.07511) (xy 18.888218 -392.039457) (xy 18.850147 -391.997737) (xy 18.81864 -391.950861)
			(xy 18.794387 -391.899854) (xy 18.777916 -391.845829) (xy 18.769588 -391.789966) (xy 18.769076 -391.761726)
			(xy 13.61694 -391.761726) (xy 13.61694 -392.457686) (xy 13.6165 -392.467748) (xy 13.608756 -392.486324)
			(xy 13.601954 -392.493754) (xy 13.172877 -392.922831) (xy 15.26665 -392.922831) (xy 15.26665 -392.868329)
			(xy 15.274406 -392.814381) (xy 15.289761 -392.762087) (xy 15.312402 -392.71251) (xy 15.341868 -392.66666)
			(xy 15.37756 -392.62547) (xy 15.41875 -392.589778) (xy 15.4646 -392.560312) (xy 15.514177 -392.537671)
			(xy 15.566471 -392.522316) (xy 15.620419 -392.51456) (xy 15.64767 -392.514074) (xy 15.676293 -392.514562)
			(xy 15.732896 -392.523107) (xy 15.787589 -392.540011) (xy 15.839143 -392.564893) (xy 15.863062 -392.580622)
			(xy 15.871698 -392.586464) (xy 15.891256 -392.590528) (xy 15.983204 -392.571986) (xy 15.999968 -392.56081)
			(xy 16.005556 -392.55192) (xy 16.020677 -392.529346) (xy 16.056374 -392.488382) (xy 16.097522 -392.452896)
			(xy 16.143288 -392.423608) (xy 16.192746 -392.401109) (xy 16.244896 -392.385854) (xy 16.298682 -392.378152)
			(xy 16.32585 -392.377676) (xy 16.353102 -392.378154) (xy 16.40705 -392.38591) (xy 16.459345 -392.401266)
			(xy 16.508923 -392.423907) (xy 16.554774 -392.453374) (xy 16.595964 -392.489066) (xy 16.631656 -392.530256)
			(xy 16.661123 -392.576107) (xy 16.683764 -392.625685) (xy 16.69912 -392.67798) (xy 16.706876 -392.731928)
			(xy 16.706876 -392.786432) (xy 16.69912 -392.84038) (xy 16.683764 -392.892675) (xy 16.661123 -392.942253)
			(xy 16.631656 -392.988104) (xy 16.595964 -393.029294) (xy 16.554774 -393.064986) (xy 16.508923 -393.094453)
			(xy 16.459345 -393.117094) (xy 16.40705 -393.13245) (xy 16.353102 -393.140206) (xy 16.32585 -393.140692)
			(xy 16.297228 -393.1402) (xy 16.240624 -393.131657) (xy 16.185931 -393.114755) (xy 16.134377 -393.089873)
			(xy 16.110458 -393.074144) (xy 16.101822 -393.068302) (xy 16.082264 -393.064238) (xy 15.990316 -393.08278)
			(xy 15.973552 -393.093956) (xy 15.967964 -393.102846) (xy 15.952818 -393.125403) (xy 15.917126 -393.166369)
			(xy 15.875984 -393.201857) (xy 15.830222 -393.231148) (xy 15.780767 -393.25365) (xy 15.728621 -393.268907)
			(xy 15.674837 -393.276612) (xy 15.64767 -393.27709) (xy 15.620419 -393.2766) (xy 15.566471 -393.268844)
			(xy 15.514177 -393.253489) (xy 15.4646 -393.230848) (xy 15.41875 -393.201382) (xy 15.37756 -393.16569)
			(xy 15.341868 -393.1245) (xy 15.312402 -393.07865) (xy 15.289761 -393.029073) (xy 15.274406 -392.976779)
			(xy 15.26665 -392.922831) (xy 13.172877 -392.922831) (xy 12.591796 -393.503912) (xy 12.58331 -393.513484)
			(xy 12.576129 -393.538003) (xy 12.57808 -393.550648) (xy 12.584978 -393.582144) (xy 16.440148 -393.582144)
			(xy 16.444219 -393.526522) (xy 16.456345 -393.472085) (xy 16.476268 -393.419994) (xy 16.503564 -393.371359)
			(xy 16.53765 -393.327216) (xy 16.577799 -393.288507) (xy 16.623157 -393.256056) (xy 16.672757 -393.230555)
			(xy 16.725541 -393.212548) (xy 16.780384 -393.202418) (xy 16.836118 -393.200381) (xy 16.891555 -393.206481)
			(xy 16.945512 -393.220587) (xy 16.996841 -393.242399) (xy 17.044447 -393.271453) (xy 17.087315 -393.307128)
			(xy 17.124532 -393.348665) (xy 17.155305 -393.395178) (xy 17.178977 -393.445675) (xy 17.189926 -393.482068)
			(xy 23.315166 -393.482068) (xy 23.319237 -393.426446) (xy 23.331363 -393.372009) (xy 23.351286 -393.319918)
			(xy 23.378582 -393.271283) (xy 23.412668 -393.22714) (xy 23.452817 -393.188431) (xy 23.498175 -393.15598)
			(xy 23.547775 -393.130479) (xy 23.600559 -393.112472) (xy 23.655402 -393.102342) (xy 23.711136 -393.100305)
			(xy 23.766573 -393.106405) (xy 23.82053 -393.120511) (xy 23.871859 -393.142323) (xy 23.919465 -393.171377)
			(xy 23.962333 -393.207052) (xy 23.99955 -393.248589) (xy 24.030323 -393.295102) (xy 24.053995 -393.345599)
			(xy 24.070063 -393.399006) (xy 24.078183 -393.454182) (xy 24.078692 -393.482068) (xy 24.078183 -393.509954)
			(xy 24.070063 -393.56513) (xy 24.053995 -393.618537) (xy 24.030323 -393.669034) (xy 23.99955 -393.715547)
			(xy 23.962333 -393.757084) (xy 23.957065 -393.761468) (xy 25.528776 -393.761468) (xy 25.532847 -393.705846)
			(xy 25.544973 -393.651409) (xy 25.564896 -393.599318) (xy 25.592192 -393.550683) (xy 25.626278 -393.50654)
			(xy 25.666427 -393.467831) (xy 25.711785 -393.43538) (xy 25.761385 -393.409879) (xy 25.814169 -393.391872)
			(xy 25.869012 -393.381742) (xy 25.924746 -393.379705) (xy 25.980183 -393.385805) (xy 26.03414 -393.399911)
			(xy 26.085469 -393.421723) (xy 26.133075 -393.450777) (xy 26.175943 -393.486452) (xy 26.21316 -393.527989)
			(xy 26.243933 -393.574502) (xy 26.267605 -393.624999) (xy 26.283673 -393.678406) (xy 26.291793 -393.733582)
			(xy 26.292302 -393.761468) (xy 26.291793 -393.789354) (xy 26.283673 -393.84453) (xy 26.267605 -393.897937)
			(xy 26.243933 -393.948434) (xy 26.21316 -393.994947) (xy 26.175943 -394.036484) (xy 26.133075 -394.072159)
			(xy 26.085469 -394.101213) (xy 26.03414 -394.123025) (xy 25.980183 -394.137131) (xy 25.924746 -394.143231)
			(xy 25.869012 -394.141194) (xy 25.814169 -394.131064) (xy 25.761385 -394.113057) (xy 25.711785 -394.087556)
			(xy 25.666427 -394.055105) (xy 25.626278 -394.016396) (xy 25.592192 -393.972253) (xy 25.564896 -393.923618)
			(xy 25.544973 -393.871527) (xy 25.532847 -393.81709) (xy 25.528776 -393.761468) (xy 23.957065 -393.761468)
			(xy 23.919465 -393.792759) (xy 23.871859 -393.821813) (xy 23.82053 -393.843625) (xy 23.766573 -393.857731)
			(xy 23.711136 -393.863831) (xy 23.655402 -393.861794) (xy 23.600559 -393.851664) (xy 23.547775 -393.833657)
			(xy 23.498175 -393.808156) (xy 23.452817 -393.775705) (xy 23.412668 -393.736996) (xy 23.378582 -393.692853)
			(xy 23.351286 -393.644218) (xy 23.331363 -393.592127) (xy 23.319237 -393.53769) (xy 23.315166 -393.482068)
			(xy 17.189926 -393.482068) (xy 17.195045 -393.499082) (xy 17.203165 -393.554258) (xy 17.203674 -393.582144)
			(xy 17.203165 -393.61003) (xy 17.195045 -393.665206) (xy 17.178977 -393.718613) (xy 17.155305 -393.76911)
			(xy 17.124532 -393.815623) (xy 17.087315 -393.85716) (xy 17.044447 -393.892835) (xy 16.996841 -393.921889)
			(xy 16.945512 -393.943701) (xy 16.891555 -393.957807) (xy 16.836118 -393.963907) (xy 16.780384 -393.96187)
			(xy 16.725541 -393.95174) (xy 16.672757 -393.933733) (xy 16.623157 -393.908232) (xy 16.577799 -393.875781)
			(xy 16.53765 -393.837072) (xy 16.503564 -393.792929) (xy 16.476268 -393.744294) (xy 16.456345 -393.692203)
			(xy 16.444219 -393.637766) (xy 16.440148 -393.582144) (xy 12.584978 -393.582144) (xy 12.599162 -393.646914)
			(xy 12.61618 -393.666472) (xy 12.628372 -393.671044) (xy 12.655389 -393.681612) (xy 12.706121 -393.709744)
			(xy 12.752004 -393.745239) (xy 12.791977 -393.787278) (xy 12.825118 -393.83489) (xy 12.850661 -393.886973)
			(xy 12.868015 -393.942327) (xy 12.87678 -393.999671) (xy 12.877292 -394.028676) (xy 12.877047 -394.043154)
			(xy 13.681962 -394.043154) (xy 13.686033 -393.987532) (xy 13.698159 -393.933095) (xy 13.718082 -393.881004)
			(xy 13.745378 -393.832369) (xy 13.779464 -393.788226) (xy 13.819613 -393.749517) (xy 13.864971 -393.717066)
			(xy 13.914571 -393.691565) (xy 13.967355 -393.673558) (xy 14.022198 -393.663428) (xy 14.077932 -393.661391)
			(xy 14.133369 -393.667491) (xy 14.187326 -393.681597) (xy 14.238655 -393.703409) (xy 14.286261 -393.732463)
			(xy 14.329129 -393.768138) (xy 14.366346 -393.809675) (xy 14.397119 -393.856188) (xy 14.420791 -393.906685)
			(xy 14.436859 -393.960092) (xy 14.444979 -394.015268) (xy 14.445488 -394.043154) (xy 14.444979 -394.07104)
			(xy 14.436859 -394.126216) (xy 14.420791 -394.179623) (xy 14.397119 -394.23012) (xy 14.366346 -394.276633)
			(xy 14.336044 -394.310452) (xy 22.100762 -394.310452) (xy 22.100762 -394.255948) (xy 22.108518 -394.201998)
			(xy 22.123874 -394.149702) (xy 22.146516 -394.100123) (xy 22.175983 -394.054271) (xy 22.211675 -394.013079)
			(xy 22.252866 -393.977386) (xy 22.298718 -393.947918) (xy 22.348296 -393.925276) (xy 22.400593 -393.90992)
			(xy 22.454542 -393.902162) (xy 22.481794 -393.901676) (xy 22.510712 -393.90217) (xy 22.567886 -393.9109)
			(xy 22.623086 -393.928161) (xy 22.675049 -393.953557) (xy 22.722582 -393.986506) (xy 22.764596 -394.026253)
			(xy 22.782784 -394.048742) (xy 22.79035 -394.057499) (xy 22.811106 -394.067683) (xy 22.822662 -394.0683)
			(xy 22.902926 -394.0683) (xy 22.914488 -394.067687) (xy 22.93526 -394.057523) (xy 22.942804 -394.048742)
			(xy 22.961003 -394.026265) (xy 23.00302 -393.986528) (xy 23.050553 -393.953587) (xy 23.102513 -393.928197)
			(xy 23.157709 -393.91094) (xy 23.214878 -393.902211) (xy 23.243794 -393.901676) (xy 23.271046 -393.902171)
			(xy 23.324995 -393.909927) (xy 23.377292 -393.925282) (xy 23.42687 -393.947923) (xy 23.472722 -393.97739)
			(xy 23.513914 -394.013082) (xy 23.549607 -394.054273) (xy 23.579074 -394.100124) (xy 23.601716 -394.149703)
			(xy 23.617072 -394.201999) (xy 23.624829 -394.255948) (xy 23.624829 -394.310452) (xy 23.617072 -394.364401)
			(xy 23.601716 -394.416697) (xy 23.579074 -394.466276) (xy 23.549607 -394.512127) (xy 23.513914 -394.553318)
			(xy 23.472722 -394.58901) (xy 23.42687 -394.618477) (xy 23.377292 -394.641118) (xy 23.324995 -394.656473)
			(xy 23.271046 -394.664229) (xy 23.243794 -394.664692) (xy 23.214877 -394.664181) (xy 23.157705 -394.655451)
			(xy 23.102506 -394.638191) (xy 23.050544 -394.612799) (xy 23.003011 -394.579854) (xy 22.960994 -394.540112)
			(xy 22.942804 -394.517626) (xy 22.935249 -394.508858) (xy 22.914484 -394.498681) (xy 22.902926 -394.498068)
			(xy 22.822662 -394.498068) (xy 22.811095 -394.49865) (xy 22.790322 -394.508834) (xy 22.782784 -394.517626)
			(xy 22.764609 -394.540123) (xy 22.722585 -394.579856) (xy 22.675046 -394.612792) (xy 22.623082 -394.638178)
			(xy 22.567882 -394.655432) (xy 22.510711 -394.664158) (xy 22.481794 -394.664692) (xy 22.454542 -394.664238)
			(xy 22.400593 -394.65648) (xy 22.348296 -394.641124) (xy 22.298718 -394.618482) (xy 22.252866 -394.589014)
			(xy 22.211675 -394.553321) (xy 22.175983 -394.512129) (xy 22.146516 -394.466277) (xy 22.123874 -394.416698)
			(xy 22.108518 -394.364402) (xy 22.100762 -394.310452) (xy 14.336044 -394.310452) (xy 14.329129 -394.31817)
			(xy 14.286261 -394.353845) (xy 14.238655 -394.382899) (xy 14.187326 -394.404711) (xy 14.133369 -394.418817)
			(xy 14.077932 -394.424917) (xy 14.022198 -394.42288) (xy 13.967355 -394.41275) (xy 13.914571 -394.394743)
			(xy 13.864971 -394.369242) (xy 13.819613 -394.336791) (xy 13.779464 -394.298082) (xy 13.745378 -394.253939)
			(xy 13.718082 -394.205304) (xy 13.698159 -394.153213) (xy 13.686033 -394.098776) (xy 13.681962 -394.043154)
			(xy 12.877047 -394.043154) (xy 12.87683 -394.05593) (xy 12.869076 -394.109882) (xy 12.853722 -394.162182)
			(xy 12.831081 -394.211764) (xy 12.801613 -394.257619) (xy 12.765919 -394.298813) (xy 12.724726 -394.334508)
			(xy 12.678871 -394.363977) (xy 12.62929 -394.386619) (xy 12.57699 -394.401974) (xy 12.523038 -394.40973)
			(xy 12.495784 -394.410184) (xy 12.466781 -394.409642) (xy 12.409445 -394.400858) (xy 12.354099 -394.383495)
			(xy 12.30202 -394.357954) (xy 12.254407 -394.324822) (xy 12.212359 -394.284864) (xy 12.176846 -394.239002)
			(xy 12.148684 -394.188291) (xy 12.138152 -394.161264) (xy 12.13358 -394.149072) (xy 12.114022 -394.132054)
			(xy 12.017756 -394.110972) (xy 12.009389 -394.109445) (xy 11.992507 -394.11143) (xy 11.977224 -394.118871)
			(xy 11.97102 -394.124688) (xy 11.135614 -394.960094) (xy 11.133027 -394.962888) (xy 12.04036 -394.962888)
			(xy 12.044431 -394.907266) (xy 12.056557 -394.852829) (xy 12.07648 -394.800738) (xy 12.103776 -394.752103)
			(xy 12.137862 -394.70796) (xy 12.178011 -394.669251) (xy 12.223369 -394.6368) (xy 12.272969 -394.611299)
			(xy 12.325753 -394.593292) (xy 12.380596 -394.583162) (xy 12.43633 -394.581125) (xy 12.491767 -394.587225)
			(xy 12.545724 -394.601331) (xy 12.597053 -394.623143) (xy 12.644659 -394.652197) (xy 12.687527 -394.687872)
			(xy 12.724744 -394.729409) (xy 12.755517 -394.775922) (xy 12.779189 -394.826419) (xy 12.795257 -394.879826)
			(xy 12.803377 -394.935002) (xy 12.803886 -394.962888) (xy 12.803377 -394.990774) (xy 12.795257 -395.04595)
			(xy 12.779189 -395.099357) (xy 12.755517 -395.149854) (xy 12.724744 -395.196367) (xy 12.687527 -395.237904)
			(xy 12.644659 -395.273579) (xy 12.597053 -395.302633) (xy 12.545724 -395.324445) (xy 12.491767 -395.338551)
			(xy 12.43633 -395.344651) (xy 12.380596 -395.342614) (xy 12.325753 -395.332484) (xy 12.272969 -395.314477)
			(xy 12.223369 -395.288976) (xy 12.178011 -395.256525) (xy 12.137862 -395.217816) (xy 12.103776 -395.173673)
			(xy 12.07648 -395.125038) (xy 12.056557 -395.072947) (xy 12.044431 -395.01851) (xy 12.04036 -394.962888)
			(xy 11.133027 -394.962888) (xy 11.128765 -394.967491) (xy 11.121026 -394.98609) (xy 11.120628 -394.996162)
			(xy 11.120628 -396.06093) (xy 12.003024 -396.06093) (xy 12.00351 -396.033679) (xy 12.011266 -395.979731)
			(xy 12.026621 -395.927436) (xy 12.049263 -395.877859) (xy 12.078729 -395.832009) (xy 12.11442 -395.790818)
			(xy 12.155611 -395.755127) (xy 12.201461 -395.725661) (xy 12.251038 -395.703019) (xy 12.303333 -395.687664)
			(xy 12.357281 -395.679908) (xy 12.411783 -395.679908) (xy 12.465731 -395.687664) (xy 12.518026 -395.703019)
			(xy 12.567603 -395.725661) (xy 12.613453 -395.755127) (xy 12.654644 -395.790818) (xy 12.690335 -395.832009)
			(xy 12.719801 -395.877859) (xy 12.742443 -395.927436) (xy 12.753374 -395.964664) (xy 19.52498 -395.964664)
			(xy 19.525405 -395.937292) (xy 19.53323 -395.88311) (xy 19.548728 -395.830606) (xy 19.571579 -395.78086)
			(xy 19.601314 -395.734896) (xy 19.61896 -395.713966) (xy 19.625056 -395.706854) (xy 19.631406 -395.689836)
			(xy 19.631406 -395.604492) (xy 19.625056 -395.587474) (xy 19.61896 -395.580362) (xy 19.60133 -395.559423)
			(xy 19.571618 -395.513451) (xy 19.548781 -395.463706) (xy 19.533287 -395.411207) (xy 19.525456 -395.357033)
			(xy 19.52498 -395.329664) (xy 19.525466 -395.302413) (xy 19.533222 -395.248465) (xy 19.548577 -395.19617)
			(xy 19.571219 -395.146593) (xy 19.600685 -395.100743) (xy 19.636376 -395.059552) (xy 19.677567 -395.023861)
			(xy 19.723417 -394.994395) (xy 19.772994 -394.971753) (xy 19.825289 -394.956398) (xy 19.879237 -394.948642)
			(xy 19.933739 -394.948642) (xy 19.987687 -394.956398) (xy 20.039982 -394.971753) (xy 20.089559 -394.994395)
			(xy 20.135409 -395.023861) (xy 20.1766 -395.059552) (xy 20.212291 -395.100743) (xy 20.241757 -395.146593)
			(xy 20.264399 -395.19617) (xy 20.279754 -395.248465) (xy 20.28751 -395.302413) (xy 20.287996 -395.329664)
			(xy 20.28751 -395.357034) (xy 20.279697 -395.411212) (xy 20.264213 -395.463715) (xy 20.241375 -395.513462)
			(xy 20.211655 -395.55943) (xy 20.194016 -395.580362) (xy 20.18792 -395.587474) (xy 20.18157 -395.604492)
			(xy 20.18157 -395.689836) (xy 20.18792 -395.706854) (xy 20.194016 -395.713966) (xy 20.211655 -395.734898)
			(xy 20.23933 -395.77772) (xy 28.172664 -395.77772) (xy 28.173126 -395.750349) (xy 28.180943 -395.69617)
			(xy 28.196432 -395.643666) (xy 28.219275 -395.593919) (xy 28.249001 -395.547953) (xy 28.266644 -395.527022)
			(xy 28.27274 -395.51991) (xy 28.27909 -395.502892) (xy 28.27909 -395.417548) (xy 28.27274 -395.40053)
			(xy 28.266644 -395.393418) (xy 28.249007 -395.372484) (xy 28.219293 -395.326513) (xy 28.196456 -395.276766)
			(xy 28.180965 -395.224265) (xy 28.173137 -395.170089) (xy 28.172664 -395.14272) (xy 28.17315 -395.115469)
			(xy 28.180906 -395.061521) (xy 28.196261 -395.009226) (xy 28.218903 -394.959649) (xy 28.248369 -394.913799)
			(xy 28.28406 -394.872608) (xy 28.325251 -394.836917) (xy 28.371101 -394.807451) (xy 28.420678 -394.784809)
			(xy 28.472973 -394.769454) (xy 28.526921 -394.761698) (xy 28.581423 -394.761698) (xy 28.635371 -394.769454)
			(xy 28.687666 -394.784809) (xy 28.737243 -394.807451) (xy 28.783093 -394.836917) (xy 28.824284 -394.872608)
			(xy 28.859975 -394.913799) (xy 28.889441 -394.959649) (xy 28.912083 -395.009226) (xy 28.927438 -395.061521)
			(xy 28.935194 -395.115469) (xy 28.93568 -395.14272) (xy 28.935231 -395.170091) (xy 28.927409 -395.224271)
			(xy 28.911917 -395.276774) (xy 28.889071 -395.326521) (xy 28.859343 -395.372487) (xy 28.8417 -395.393418)
			(xy 28.835604 -395.40053) (xy 28.829254 -395.417548) (xy 28.829254 -395.502892) (xy 28.835604 -395.51991)
			(xy 28.8417 -395.527022) (xy 28.859316 -395.547973) (xy 28.889031 -395.59394) (xy 28.911872 -395.643683)
			(xy 28.927368 -395.69618) (xy 28.935203 -395.750352) (xy 28.93568 -395.77772) (xy 28.935194 -395.804971)
			(xy 28.927438 -395.858919) (xy 28.912083 -395.911214) (xy 28.889441 -395.960791) (xy 28.859975 -396.006641)
			(xy 28.824284 -396.047832) (xy 28.783093 -396.083523) (xy 28.737243 -396.112989) (xy 28.687666 -396.135631)
			(xy 28.635371 -396.150986) (xy 28.581423 -396.158742) (xy 28.526921 -396.158742) (xy 28.472973 -396.150986)
			(xy 28.420678 -396.135631) (xy 28.371101 -396.112989) (xy 28.325251 -396.083523) (xy 28.28406 -396.047832)
			(xy 28.248369 -396.006641) (xy 28.218903 -395.960791) (xy 28.196261 -395.911214) (xy 28.180906 -395.858919)
			(xy 28.17315 -395.804971) (xy 28.172664 -395.77772) (xy 20.23933 -395.77772) (xy 20.241366 -395.780871)
			(xy 20.264202 -395.830619) (xy 20.279693 -395.883119) (xy 20.287522 -395.937295) (xy 20.287996 -395.964664)
			(xy 20.28751 -395.991915) (xy 20.279754 -396.045863) (xy 20.264399 -396.098158) (xy 20.241757 -396.147735)
			(xy 20.212291 -396.193585) (xy 20.1766 -396.234776) (xy 20.135409 -396.270467) (xy 20.089559 -396.299933)
			(xy 20.039982 -396.322575) (xy 19.987687 -396.33793) (xy 19.933739 -396.345686) (xy 19.879237 -396.345686)
			(xy 19.825289 -396.33793) (xy 19.772994 -396.322575) (xy 19.723417 -396.299933) (xy 19.677567 -396.270467)
			(xy 19.636376 -396.234776) (xy 19.600685 -396.193585) (xy 19.571219 -396.147735) (xy 19.548577 -396.098158)
			(xy 19.533222 -396.045863) (xy 19.525466 -395.991915) (xy 19.52498 -395.964664) (xy 12.753374 -395.964664)
			(xy 12.757798 -395.979731) (xy 12.765554 -396.033679) (xy 12.76604 -396.06093) (xy 12.765315 -396.093863)
			(xy 12.753944 -396.158742) (xy 12.743434 -396.189962) (xy 12.74064 -396.198344) (xy 12.74064 -398.878552)
			(xy 19.56308 -398.878552) (xy 19.563557 -398.851182) (xy 19.571369 -398.797003) (xy 19.586855 -398.744499)
			(xy 19.609694 -398.694752) (xy 19.639419 -398.648785) (xy 19.65706 -398.627854) (xy 19.663156 -398.620742)
			(xy 19.669506 -398.603724) (xy 19.669506 -398.51838) (xy 19.663156 -398.501362) (xy 19.65706 -398.49425)
			(xy 19.639424 -398.473315) (xy 19.609713 -398.427343) (xy 19.586877 -398.377596) (xy 19.571385 -398.325096)
			(xy 19.563555 -398.270921) (xy 19.56308 -398.243552) (xy 19.563499 -398.217882) (xy 19.570385 -398.167007)
			(xy 19.584026 -398.117513) (xy 19.604176 -398.070293) (xy 19.630472 -398.026199) (xy 19.662439 -397.986026)
			(xy 19.680682 -397.967962) (xy 19.687787 -397.960528) (xy 19.69591 -397.941656) (xy 19.69643 -397.931386)
			(xy 19.69643 -397.85798) (xy 19.695957 -397.847701) (xy 19.687813 -397.828823) (xy 19.680682 -397.821404)
			(xy 19.662461 -397.803318) (xy 19.630484 -397.763154) (xy 19.604181 -397.719066) (xy 19.584026 -397.67185)
			(xy 19.570383 -397.622358) (xy 19.563498 -397.571483) (xy 19.56308 -397.545814) (xy 19.563535 -397.518443)
			(xy 19.571352 -397.464263) (xy 19.586843 -397.411759) (xy 19.609688 -397.362012) (xy 19.639416 -397.316046)
			(xy 19.65706 -397.295116) (xy 19.663156 -397.288004) (xy 19.669506 -397.270986) (xy 19.669506 -397.185642)
			(xy 19.663156 -397.168624) (xy 19.65706 -397.161512) (xy 19.639406 -397.140592) (xy 19.609698 -397.094615)
			(xy 19.586865 -397.044864) (xy 19.571378 -396.992361) (xy 19.563552 -396.938184) (xy 19.56308 -396.910814)
			(xy 19.563566 -396.883563) (xy 19.571322 -396.829615) (xy 19.586677 -396.77732) (xy 19.609319 -396.727743)
			(xy 19.638785 -396.681893) (xy 19.674476 -396.640702) (xy 19.715667 -396.605011) (xy 19.761517 -396.575545)
			(xy 19.811094 -396.552903) (xy 19.863389 -396.537548) (xy 19.917337 -396.529792) (xy 19.971839 -396.529792)
			(xy 20.025787 -396.537548) (xy 20.078082 -396.552903) (xy 20.127659 -396.575545) (xy 20.173509 -396.605011)
			(xy 20.2147 -396.640702) (xy 20.250391 -396.681893) (xy 20.279857 -396.727743) (xy 20.302499 -396.77732)
			(xy 20.317854 -396.829615) (xy 20.32561 -396.883563) (xy 20.326096 -396.910814) (xy 20.325639 -396.938185)
			(xy 20.317819 -396.992364) (xy 20.302328 -397.044867) (xy 20.279484 -397.094614) (xy 20.249758 -397.140581)
			(xy 20.232116 -397.161512) (xy 20.22602 -397.168624) (xy 20.21967 -397.185642) (xy 20.21967 -397.270986)
			(xy 20.22602 -397.288004) (xy 20.232116 -397.295116) (xy 20.249732 -397.316067) (xy 20.279446 -397.362035)
			(xy 20.302287 -397.411778) (xy 20.317783 -397.464274) (xy 20.324947 -397.51381) (xy 28.152598 -397.51381)
			(xy 28.15307 -397.48644) (xy 28.160887 -397.432261) (xy 28.176374 -397.379758) (xy 28.199215 -397.330011)
			(xy 28.228938 -397.284044) (xy 28.246578 -397.263112) (xy 28.252674 -397.256) (xy 28.259024 -397.238982)
			(xy 28.259024 -397.153638) (xy 28.252674 -397.13662) (xy 28.246578 -397.129508) (xy 28.228926 -397.108587)
			(xy 28.199217 -397.06261) (xy 28.176384 -397.01286) (xy 28.160896 -396.960357) (xy 28.15307 -396.90618)
			(xy 28.152598 -396.87881) (xy 28.153084 -396.851559) (xy 28.16084 -396.797611) (xy 28.176195 -396.745316)
			(xy 28.198837 -396.695739) (xy 28.228303 -396.649889) (xy 28.263994 -396.608698) (xy 28.305185 -396.573007)
			(xy 28.351035 -396.543541) (xy 28.400612 -396.520899) (xy 28.452907 -396.505544) (xy 28.506855 -396.497788)
			(xy 28.561357 -396.497788) (xy 28.615305 -396.505544) (xy 28.6676 -396.520899) (xy 28.717177 -396.543541)
			(xy 28.763027 -396.573007) (xy 28.804218 -396.608698) (xy 28.839909 -396.649889) (xy 28.869375 -396.695739)
			(xy 28.892017 -396.745316) (xy 28.907372 -396.797611) (xy 28.915128 -396.851559) (xy 28.915614 -396.87881)
			(xy 28.91515 -396.90618) (xy 28.907331 -396.960359) (xy 28.891842 -397.012862) (xy 28.868999 -397.062609)
			(xy 28.839275 -397.108576) (xy 28.821634 -397.129508) (xy 28.815538 -397.13662) (xy 28.809188 -397.153638)
			(xy 28.809188 -397.238982) (xy 28.815538 -397.256) (xy 28.821634 -397.263112) (xy 28.839251 -397.284062)
			(xy 28.868965 -397.33003) (xy 28.891804 -397.379773) (xy 28.907301 -397.43227) (xy 28.915136 -397.486442)
			(xy 28.915614 -397.51381) (xy 28.915128 -397.541061) (xy 28.907372 -397.595009) (xy 28.892017 -397.647304)
			(xy 28.869375 -397.696881) (xy 28.839909 -397.742731) (xy 28.804218 -397.783922) (xy 28.763027 -397.819613)
			(xy 28.717177 -397.849079) (xy 28.6676 -397.871721) (xy 28.615305 -397.887076) (xy 28.561357 -397.894832)
			(xy 28.506855 -397.894832) (xy 28.452907 -397.887076) (xy 28.400612 -397.871721) (xy 28.351035 -397.849079)
			(xy 28.305185 -397.819613) (xy 28.263994 -397.783922) (xy 28.228303 -397.742731) (xy 28.198837 -397.696881)
			(xy 28.176195 -397.647304) (xy 28.16084 -397.595009) (xy 28.153084 -397.541061) (xy 28.152598 -397.51381)
			(xy 20.324947 -397.51381) (xy 20.325618 -397.518446) (xy 20.326096 -397.545814) (xy 20.325662 -397.571483)
			(xy 20.31878 -397.622359) (xy 20.305143 -397.671853) (xy 20.284995 -397.719073) (xy 20.258702 -397.763167)
			(xy 20.226736 -397.80334) (xy 20.208494 -397.821404) (xy 20.201401 -397.828847) (xy 20.193272 -397.847712)
			(xy 20.192746 -397.85798) (xy 20.192746 -397.931386) (xy 20.193244 -397.941662) (xy 20.201371 -397.960539)
			(xy 20.208494 -397.967962) (xy 20.226761 -397.986003) (xy 20.258731 -398.026178) (xy 20.285026 -398.070276)
			(xy 20.305172 -398.117501) (xy 20.318807 -398.167) (xy 20.325682 -398.217881) (xy 20.326096 -398.243552)
			(xy 20.325527 -398.273028) (xy 20.316465 -398.33128) (xy 20.29855 -398.387445) (xy 20.272207 -398.440185)
			(xy 20.238064 -398.488244) (xy 20.217892 -398.509744) (xy 20.211344 -398.517069) (xy 20.203907 -398.535237)
			(xy 20.203414 -398.54505) (xy 20.203414 -398.577054) (xy 20.203878 -398.586871) (xy 20.211338 -398.605035)
			(xy 20.217892 -398.61236) (xy 20.231608 -398.627346) (xy 20.239228 -398.635982) (xy 20.260056 -398.644872)
			(xy 20.36191 -398.641316) (xy 20.381976 -398.631156) (xy 20.389088 -398.621758) (xy 20.407229 -398.598733)
			(xy 20.449382 -398.558002) (xy 20.497271 -398.524202) (xy 20.549769 -398.498128) (xy 20.605639 -398.480395)
			(xy 20.663564 -398.471421) (xy 20.692872 -398.470882) (xy 20.721929 -398.471455) (xy 20.77937 -398.480283)
			(xy 20.834807 -398.497722) (xy 20.886956 -398.52337) (xy 20.934611 -398.556633) (xy 20.956016 -398.576292)
			(xy 20.963382 -398.58315) (xy 20.981162 -398.590262) (xy 21.071332 -398.590262) (xy 21.089112 -398.58315)
			(xy 21.096478 -398.576292) (xy 21.117891 -398.556639) (xy 21.165535 -398.523356) (xy 21.217681 -398.497695)
			(xy 21.273119 -398.480251) (xy 21.330563 -398.471428) (xy 21.359622 -398.470882) (xy 21.386871 -398.47139)
			(xy 21.440815 -398.479149) (xy 21.493106 -398.494505) (xy 21.542679 -398.517147) (xy 21.588525 -398.546613)
			(xy 21.629712 -398.582304) (xy 21.6654 -398.623492) (xy 21.694864 -398.66934) (xy 21.717502 -398.718915)
			(xy 21.732856 -398.771206) (xy 21.740612 -398.825151) (xy 21.740612 -398.879649) (xy 21.732856 -398.933594)
			(xy 21.717502 -398.985885) (xy 21.694864 -399.03546) (xy 21.6654 -399.081308) (xy 21.629712 -399.122496)
			(xy 21.588526 -399.158187) (xy 21.542679 -399.187653) (xy 21.493106 -399.210295) (xy 21.440815 -399.225651)
			(xy 21.386871 -399.23341) (xy 21.359622 -399.233898) (xy 21.330564 -399.233334) (xy 21.273123 -399.224505)
			(xy 21.217686 -399.207064) (xy 21.165536 -399.181413) (xy 21.117882 -399.148148) (xy 21.096478 -399.128488)
			(xy 21.089112 -399.12163) (xy 21.071332 -399.114518) (xy 20.981162 -399.114518) (xy 20.963382 -399.12163)
			(xy 20.956016 -399.128488) (xy 20.934618 -399.148157) (xy 20.886969 -399.181435) (xy 20.834819 -399.207092)
			(xy 20.779378 -399.224533) (xy 20.721932 -399.233353) (xy 20.692872 -399.233898) (xy 20.665778 -399.233464)
			(xy 20.612138 -399.225788) (xy 20.560125 -399.210593) (xy 20.510787 -399.188187) (xy 20.465119 -399.159021)
			(xy 20.42404 -399.123682) (xy 20.405852 -399.103596) (xy 20.398232 -399.09496) (xy 20.377404 -399.08607)
			(xy 20.27555 -399.089626) (xy 20.255484 -399.099786) (xy 20.248372 -399.109184) (xy 20.230239 -399.132216)
			(xy 20.188086 -399.172949) (xy 20.140196 -399.20675) (xy 20.087696 -399.232823) (xy 20.031824 -399.250554)
			(xy 19.973897 -399.259524) (xy 19.944588 -399.26006) (xy 19.917333 -399.259656) (xy 19.863377 -399.251896)
			(xy 19.811075 -399.236536) (xy 19.761492 -399.213889) (xy 19.715636 -399.184415) (xy 19.674442 -399.148715)
			(xy 19.638749 -399.107516) (xy 19.609282 -399.061656) (xy 19.586643 -399.012069) (xy 19.571291 -398.959764)
			(xy 19.56354 -398.905807) (xy 19.56308 -398.878552) (xy 12.74064 -398.878552) (xy 12.74064 -400.48307)
			(xy 23.694136 -400.48307) (xy 23.694576 -400.455699) (xy 23.702399 -400.401518) (xy 23.717893 -400.349014)
			(xy 23.740741 -400.299268) (xy 23.770472 -400.253303) (xy 23.788116 -400.232372) (xy 23.794212 -400.22526)
			(xy 23.800562 -400.208242) (xy 23.800562 -400.122898) (xy 23.794212 -400.10588) (xy 23.788116 -400.098768)
			(xy 23.770498 -400.077819) (xy 23.740782 -400.031851) (xy 23.717942 -399.982108) (xy 23.702446 -399.929611)
			(xy 23.694613 -399.875438) (xy 23.694136 -399.84807) (xy 23.694527 -399.820814) (xy 23.702289 -399.766859)
			(xy 23.717651 -399.714557) (xy 23.740301 -399.664973) (xy 23.769776 -399.619118) (xy 23.805477 -399.577925)
			(xy 23.846678 -399.542231) (xy 23.892538 -399.512765) (xy 23.942126 -399.490125) (xy 23.994431 -399.474774)
			(xy 24.048388 -399.467022) (xy 24.075644 -399.466562) (xy 24.105766 -399.467165) (xy 24.165261 -399.476638)
			(xy 24.222529 -399.495341) (xy 24.276146 -399.52281) (xy 24.324782 -399.558362) (xy 24.346408 -399.579338)
			(xy 24.35352 -399.586704) (xy 24.372316 -399.594324) (xy 24.464772 -399.594324) (xy 24.483568 -399.586704)
			(xy 24.49068 -399.579338) (xy 24.512297 -399.558349) (xy 24.560927 -399.52278) (xy 24.614545 -399.495301)
			(xy 24.671818 -399.476595) (xy 24.731319 -399.467128) (xy 24.761444 -399.466562) (xy 24.788814 -399.467046)
			(xy 24.842993 -399.474857) (xy 24.895496 -399.490341) (xy 24.945243 -399.513179) (xy 24.99121 -399.542902)
			(xy 25.012142 -399.560542) (xy 25.019254 -399.566638) (xy 25.036272 -399.572988) (xy 25.121616 -399.572988)
			(xy 25.138634 -399.566638) (xy 25.145746 -399.560542) (xy 25.166693 -399.542921) (xy 25.212661 -399.513205)
			(xy 25.262405 -399.490365) (xy 25.314902 -399.47487) (xy 25.369076 -399.467038) (xy 25.396444 -399.466562)
			(xy 25.423695 -399.467037) (xy 25.477642 -399.474799) (xy 25.529935 -399.490158) (xy 25.57951 -399.512802)
			(xy 25.625359 -399.54227) (xy 25.666548 -399.577962) (xy 25.702239 -399.619152) (xy 25.731705 -399.665002)
			(xy 25.754347 -399.714579) (xy 25.769704 -399.766872) (xy 25.777464 -399.820819) (xy 25.777952 -399.84807)
			(xy 25.77748 -399.87544) (xy 25.769665 -399.929619) (xy 25.754178 -399.982123) (xy 25.731338 -400.03187)
			(xy 25.701613 -400.077837) (xy 25.683972 -400.098768) (xy 25.677876 -400.10588) (xy 25.671526 -400.122898)
			(xy 25.671526 -400.208242) (xy 25.677876 -400.22526) (xy 25.683972 -400.232372) (xy 25.701607 -400.253307)
			(xy 25.73132 -400.299279) (xy 25.754158 -400.349025) (xy 25.76965 -400.401526) (xy 25.777478 -400.455701)
			(xy 25.777952 -400.48307) (xy 25.777394 -400.510318) (xy 25.769643 -400.564261) (xy 25.754294 -400.616552)
			(xy 25.731659 -400.666126) (xy 25.725734 -400.675348) (xy 27.191462 -400.675348) (xy 27.191889 -400.64897)
			(xy 27.199135 -400.596713) (xy 27.21351 -400.545953) (xy 27.234739 -400.497656) (xy 27.262418 -400.452744)
			(xy 27.29602 -400.412072) (xy 27.31516 -400.393916) (xy 27.322678 -400.386475) (xy 27.33123 -400.367147)
			(xy 27.33167 -400.356578) (xy 27.33167 -400.281648) (xy 27.331059 -400.271115) (xy 27.322551 -400.251837)
			(xy 27.31516 -400.24431) (xy 27.295999 -400.226174) (xy 27.262389 -400.185504) (xy 27.234707 -400.140589)
			(xy 27.213481 -400.092288) (xy 27.199116 -400.041521) (xy 27.191887 -399.989258) (xy 27.191462 -399.962878)
			(xy 27.191948 -399.935627) (xy 27.199704 -399.881679) (xy 27.215059 -399.829384) (xy 27.237701 -399.779807)
			(xy 27.267167 -399.733957) (xy 27.302858 -399.692766) (xy 27.344049 -399.657075) (xy 27.389899 -399.627609)
			(xy 27.439476 -399.604967) (xy 27.491771 -399.589612) (xy 27.545719 -399.581856) (xy 27.600221 -399.581856)
			(xy 27.654169 -399.589612) (xy 27.706464 -399.604967) (xy 27.756041 -399.627609) (xy 27.801891 -399.657075)
			(xy 27.843082 -399.692766) (xy 27.878773 -399.733957) (xy 27.908239 -399.779807) (xy 27.930881 -399.829384)
			(xy 27.946236 -399.881679) (xy 27.953992 -399.935627) (xy 27.954478 -399.962878) (xy 27.954055 -399.989256)
			(xy 27.946806 -400.041512) (xy 27.93243 -400.092272) (xy 27.9112 -400.140569) (xy 27.883521 -400.185481)
			(xy 27.84992 -400.226153) (xy 27.83078 -400.24431) (xy 27.82331 -400.251783) (xy 27.814786 -400.271093)
			(xy 27.81427 -400.281648) (xy 27.81427 -400.356578) (xy 27.814855 -400.367114) (xy 27.82338 -400.386393)
			(xy 27.83078 -400.393916) (xy 27.849913 -400.412081) (xy 27.883524 -400.452745) (xy 27.911209 -400.497654)
			(xy 27.932439 -400.54595) (xy 27.946811 -400.596712) (xy 27.954048 -400.648969) (xy 27.954478 -400.675348)
			(xy 27.953992 -400.702599) (xy 27.946236 -400.756547) (xy 27.930881 -400.808842) (xy 27.908239 -400.858419)
			(xy 27.878773 -400.904269) (xy 27.843082 -400.94546) (xy 27.801891 -400.981151) (xy 27.756041 -401.010617)
			(xy 27.706464 -401.033259) (xy 27.654169 -401.048614) (xy 27.600221 -401.05637) (xy 27.545719 -401.05637)
			(xy 27.491771 -401.048614) (xy 27.439476 -401.033259) (xy 27.389899 -401.010617) (xy 27.344049 -400.981151)
			(xy 27.302858 -400.94546) (xy 27.267167 -400.904269) (xy 27.237701 -400.858419) (xy 27.215059 -400.808842)
			(xy 27.199704 -400.756547) (xy 27.191948 -400.702599) (xy 27.191462 -400.675348) (xy 25.725734 -400.675348)
			(xy 25.7022 -400.711974) (xy 25.666516 -400.753164) (xy 25.625334 -400.788856) (xy 25.579491 -400.818324)
			(xy 25.529921 -400.840968) (xy 25.477634 -400.856327) (xy 25.423692 -400.864089) (xy 25.396444 -400.864578)
			(xy 25.369074 -400.864092) (xy 25.314896 -400.856279) (xy 25.262393 -400.840795) (xy 25.212646 -400.817958)
			(xy 25.166678 -400.788237) (xy 25.145746 -400.770598) (xy 25.138634 -400.764502) (xy 25.121616 -400.758152)
			(xy 25.036272 -400.758152) (xy 25.019254 -400.764502) (xy 25.012142 -400.770598) (xy 24.991205 -400.788231)
			(xy 24.945233 -400.817943) (xy 24.895487 -400.840781) (xy 24.842988 -400.856273) (xy 24.788813 -400.864103)
			(xy 24.761444 -400.864578) (xy 24.731322 -400.863971) (xy 24.671828 -400.854498) (xy 24.614561 -400.835795)
			(xy 24.560943 -400.808327) (xy 24.512306 -400.772777) (xy 24.49068 -400.751802) (xy 24.483568 -400.744436)
			(xy 24.464772 -400.736816) (xy 24.372316 -400.736816) (xy 24.35352 -400.744436) (xy 24.346408 -400.751802)
			(xy 24.324803 -400.772804) (xy 24.276169 -400.808369) (xy 24.222547 -400.835845) (xy 24.165273 -400.854548)
			(xy 24.10577 -400.864013) (xy 24.075644 -400.864578) (xy 24.048391 -400.864104) (xy 23.994439 -400.856352)
			(xy 23.942139 -400.841) (xy 23.892557 -400.81836) (xy 23.846703 -400.788894) (xy 23.805509 -400.753201)
			(xy 23.769814 -400.712009) (xy 23.740346 -400.666155) (xy 23.717705 -400.616574) (xy 23.702351 -400.564275)
			(xy 23.694597 -400.510323) (xy 23.694136 -400.48307) (xy 12.74064 -400.48307) (xy 12.74064 -400.840702)
			(xy 12.741105 -400.85067) (xy 12.748689 -400.869106) (xy 12.755372 -400.876516) (xy 13.305099 -401.426243)
			(xy 19.533319 -401.426243) (xy 19.533319 -401.371737) (xy 19.541076 -401.317787) (xy 19.556432 -401.265489)
			(xy 19.579075 -401.21591) (xy 19.608543 -401.170057) (xy 19.644236 -401.128865) (xy 19.685428 -401.093171)
			(xy 19.731281 -401.063704) (xy 19.780861 -401.041062) (xy 19.833159 -401.025706) (xy 19.887109 -401.017949)
			(xy 19.914362 -401.017486) (xy 19.944485 -401.018071) (xy 20.003981 -401.027547) (xy 20.061249 -401.046254)
			(xy 20.114867 -401.073727) (xy 20.163501 -401.109284) (xy 20.185126 -401.130262) (xy 20.192238 -401.137628)
			(xy 20.211034 -401.145248) (xy 20.30349 -401.145248) (xy 20.322286 -401.137628) (xy 20.329398 -401.130262)
			(xy 20.351011 -401.109268) (xy 20.399642 -401.073699) (xy 20.453261 -401.046221) (xy 20.510534 -401.027516)
			(xy 20.570037 -401.018051) (xy 20.600162 -401.017486) (xy 20.627531 -401.017978) (xy 20.681709 -401.02579)
			(xy 20.734212 -401.041273) (xy 20.783959 -401.064109) (xy 20.829927 -401.093828) (xy 20.85086 -401.111466)
			(xy 20.857972 -401.117562) (xy 20.87499 -401.123912) (xy 20.960334 -401.123912) (xy 20.977352 -401.117562)
			(xy 20.984464 -401.111466) (xy 21.005394 -401.093825) (xy 21.051368 -401.064115) (xy 21.101116 -401.04128)
			(xy 21.153617 -401.025789) (xy 21.207793 -401.01796) (xy 21.235162 -401.017486) (xy 21.262416 -401.017959)
			(xy 21.31637 -401.025711) (xy 21.368672 -401.041064) (xy 21.418256 -401.063704) (xy 21.464113 -401.09317)
			(xy 21.50531 -401.128863) (xy 21.541007 -401.170056) (xy 21.570478 -401.215911) (xy 21.593123 -401.265492)
			(xy 21.608481 -401.317792) (xy 21.616239 -401.371746) (xy 21.616239 -401.426254) (xy 21.608481 -401.480208)
			(xy 21.593123 -401.532508) (xy 21.570478 -401.582089) (xy 21.541007 -401.627944) (xy 21.50531 -401.669137)
			(xy 21.464113 -401.70483) (xy 21.418256 -401.734296) (xy 21.368672 -401.756936) (xy 21.31637 -401.772289)
			(xy 21.262416 -401.780041) (xy 21.235162 -401.780502) (xy 21.207793 -401.779999) (xy 21.153616 -401.77219)
			(xy 21.101113 -401.75671) (xy 21.051365 -401.733876) (xy 21.005397 -401.704159) (xy 20.984464 -401.686522)
			(xy 20.977352 -401.680426) (xy 20.960334 -401.674076) (xy 20.87499 -401.674076) (xy 20.857972 -401.680426)
			(xy 20.85086 -401.686522) (xy 20.829919 -401.70415) (xy 20.783948 -401.733863) (xy 20.734203 -401.7567)
			(xy 20.681704 -401.772194) (xy 20.62753 -401.780026) (xy 20.600162 -401.780502) (xy 20.570039 -401.779906)
			(xy 20.510544 -401.770433) (xy 20.453275 -401.751729) (xy 20.399658 -401.724258) (xy 20.351023 -401.688703)
			(xy 20.329398 -401.667726) (xy 20.322286 -401.66036) (xy 20.30349 -401.65274) (xy 20.211034 -401.65274)
			(xy 20.192238 -401.66036) (xy 20.185126 -401.667726) (xy 20.1635 -401.688706) (xy 20.114873 -401.724277)
			(xy 20.061257 -401.751758) (xy 20.003986 -401.770466) (xy 19.944486 -401.779935) (xy 19.914362 -401.780502)
			(xy 19.887109 -401.780031) (xy 19.833159 -401.772274) (xy 19.780861 -401.756918) (xy 19.731281 -401.734276)
			(xy 19.685428 -401.704809) (xy 19.644236 -401.669115) (xy 19.608543 -401.627923) (xy 19.579075 -401.58207)
			(xy 19.556432 -401.532491) (xy 19.541076 -401.480193) (xy 19.533319 -401.426243) (xy 13.305099 -401.426243)
			(xy 13.979906 -402.10105) (xy 13.999288 -402.121232) (xy 14.032187 -402.166489) (xy 14.057609 -402.216331)
			(xy 14.074931 -402.269533) (xy 14.083727 -402.324789) (xy 14.0843 -402.352764) (xy 14.0843 -403.220174)
			(xy 14.510764 -403.220174) (xy 14.514835 -403.164552) (xy 14.526961 -403.110115) (xy 14.546884 -403.058024)
			(xy 14.57418 -403.009389) (xy 14.608266 -402.965246) (xy 14.648415 -402.926537) (xy 14.693773 -402.894086)
			(xy 14.743373 -402.868585) (xy 14.796157 -402.850578) (xy 14.851 -402.840448) (xy 14.906734 -402.838411)
			(xy 14.962171 -402.844511) (xy 15.016128 -402.858617) (xy 15.067457 -402.880429) (xy 15.115063 -402.909483)
			(xy 15.157931 -402.945158) (xy 15.195148 -402.986695) (xy 15.225921 -403.033208) (xy 15.249593 -403.083705)
			(xy 15.265661 -403.137112) (xy 15.273781 -403.192288) (xy 15.27429 -403.220174) (xy 15.780764 -403.220174)
			(xy 15.784835 -403.164552) (xy 15.796961 -403.110115) (xy 15.816884 -403.058024) (xy 15.84418 -403.009389)
			(xy 15.878266 -402.965246) (xy 15.918415 -402.926537) (xy 15.963773 -402.894086) (xy 16.013373 -402.868585)
			(xy 16.066157 -402.850578) (xy 16.121 -402.840448) (xy 16.176734 -402.838411) (xy 16.232171 -402.844511)
			(xy 16.286128 -402.858617) (xy 16.337457 -402.880429) (xy 16.385063 -402.909483) (xy 16.427931 -402.945158)
			(xy 16.465148 -402.986695) (xy 16.495921 -403.033208) (xy 16.519593 -403.083705) (xy 16.535661 -403.137112)
			(xy 16.543781 -403.192288) (xy 16.54429 -403.220174) (xy 16.543781 -403.24806) (xy 16.535661 -403.303236)
			(xy 16.519593 -403.356643) (xy 16.495921 -403.40714) (xy 16.465148 -403.453653) (xy 16.427931 -403.49519)
			(xy 16.385063 -403.530865) (xy 16.337457 -403.559919) (xy 16.286128 -403.581731) (xy 16.232171 -403.595837)
			(xy 16.176734 -403.601937) (xy 16.121 -403.5999) (xy 16.066157 -403.58977) (xy 16.013373 -403.571763)
			(xy 15.963773 -403.546262) (xy 15.918415 -403.513811) (xy 15.878266 -403.475102) (xy 15.84418 -403.430959)
			(xy 15.816884 -403.382324) (xy 15.796961 -403.330233) (xy 15.784835 -403.275796) (xy 15.780764 -403.220174)
			(xy 15.27429 -403.220174) (xy 15.273781 -403.24806) (xy 15.265661 -403.303236) (xy 15.249593 -403.356643)
			(xy 15.225921 -403.40714) (xy 15.195148 -403.453653) (xy 15.157931 -403.49519) (xy 15.115063 -403.530865)
			(xy 15.067457 -403.559919) (xy 15.016128 -403.581731) (xy 14.962171 -403.595837) (xy 14.906734 -403.601937)
			(xy 14.851 -403.5999) (xy 14.796157 -403.58977) (xy 14.743373 -403.571763) (xy 14.693773 -403.546262)
			(xy 14.648415 -403.513811) (xy 14.608266 -403.475102) (xy 14.57418 -403.430959) (xy 14.546884 -403.382324)
			(xy 14.526961 -403.330233) (xy 14.514835 -403.275796) (xy 14.510764 -403.220174) (xy 14.0843 -403.220174)
			(xy 14.0843 -403.604476) (xy 14.084763 -403.614445) (xy 14.092346 -403.632881) (xy 14.099032 -403.64029)
			(xy 14.302994 -403.844252) (xy 14.310398 -403.85094) (xy 14.32884 -403.858511) (xy 14.338808 -403.858984)
			(xy 16.247872 -403.858984) (xy 16.257838 -403.858497) (xy 16.276273 -403.850928) (xy 16.283686 -403.844252)
			(xy 16.956786 -403.171152) (xy 16.960596 -403.163024) (xy 16.972506 -403.138819) (xy 17.002146 -403.093745)
			(xy 17.037837 -403.053294) (xy 17.07887 -403.018272) (xy 17.124425 -402.989378) (xy 17.173596 -402.967188)
			(xy 17.225401 -402.952142) (xy 17.278809 -402.944543) (xy 17.305782 -402.944076) (xy 17.333034 -402.944572)
			(xy 17.386983 -402.952326) (xy 17.439279 -402.967679) (xy 17.488858 -402.990318) (xy 17.53471 -403.019783)
			(xy 17.575903 -403.055473) (xy 17.611597 -403.096662) (xy 17.641065 -403.142512) (xy 17.663079 -403.19071)
			(xy 18.073622 -403.19071) (xy 18.077693 -403.135088) (xy 18.089819 -403.080651) (xy 18.109742 -403.02856)
			(xy 18.137038 -402.979925) (xy 18.171124 -402.935782) (xy 18.211273 -402.897073) (xy 18.256631 -402.864622)
			(xy 18.306231 -402.839121) (xy 18.359015 -402.821114) (xy 18.413858 -402.810984) (xy 18.469592 -402.808947)
			(xy 18.525029 -402.815047) (xy 18.578986 -402.829153) (xy 18.630315 -402.850965) (xy 18.677921 -402.880019)
			(xy 18.720789 -402.915694) (xy 18.758006 -402.957231) (xy 18.788779 -403.003744) (xy 18.812451 -403.054241)
			(xy 18.828519 -403.107648) (xy 18.836639 -403.162824) (xy 18.837148 -403.19071) (xy 18.836639 -403.218596)
			(xy 18.828519 -403.273772) (xy 18.812451 -403.327179) (xy 18.788779 -403.377676) (xy 18.758006 -403.424189)
			(xy 18.720789 -403.465726) (xy 18.677921 -403.501401) (xy 18.630315 -403.530455) (xy 18.578986 -403.552267)
			(xy 18.525029 -403.566373) (xy 18.469592 -403.572473) (xy 18.413858 -403.570436) (xy 18.359015 -403.560306)
			(xy 18.306231 -403.542299) (xy 18.256631 -403.516798) (xy 18.211273 -403.484347) (xy 18.171124 -403.445638)
			(xy 18.137038 -403.401495) (xy 18.109742 -403.35286) (xy 18.089819 -403.300769) (xy 18.077693 -403.246332)
			(xy 18.073622 -403.19071) (xy 17.663079 -403.19071) (xy 17.663709 -403.192089) (xy 17.679067 -403.244384)
			(xy 17.686826 -403.298332) (xy 17.68729 -403.325584) (xy 17.686551 -403.358516) (xy 17.675189 -403.423396)
			(xy 17.664684 -403.454616) (xy 17.661636 -403.462998) (xy 17.661636 -404.179024) (xy 17.662106 -404.189028)
			(xy 17.669819 -404.20749) (xy 17.676622 -404.214838) (xy 18.151094 -404.68931) (xy 20.193506 -404.68931)
			(xy 20.197577 -404.633688) (xy 20.209703 -404.579251) (xy 20.229626 -404.52716) (xy 20.256922 -404.478525)
			(xy 20.291008 -404.434382) (xy 20.331157 -404.395673) (xy 20.376515 -404.363222) (xy 20.426115 -404.337721)
			(xy 20.478899 -404.319714) (xy 20.533742 -404.309584) (xy 20.589476 -404.307547) (xy 20.644913 -404.313647)
			(xy 20.69887 -404.327753) (xy 20.750199 -404.349565) (xy 20.797805 -404.378619) (xy 20.840673 -404.414294)
			(xy 20.87789 -404.455831) (xy 20.908663 -404.502344) (xy 20.932335 -404.552841) (xy 20.948403 -404.606248)
			(xy 20.956523 -404.661424) (xy 20.957032 -404.68931) (xy 20.956523 -404.717196) (xy 20.948403 -404.772372)
			(xy 20.932335 -404.825779) (xy 20.908663 -404.876276) (xy 20.87789 -404.922789) (xy 20.840673 -404.964326)
			(xy 20.797805 -405.000001) (xy 20.750199 -405.029055) (xy 20.69887 -405.050867) (xy 20.644913 -405.064973)
			(xy 20.589476 -405.071073) (xy 20.533742 -405.069036) (xy 20.478899 -405.058906) (xy 20.426115 -405.040899)
			(xy 20.376515 -405.015398) (xy 20.331157 -404.982947) (xy 20.291008 -404.944238) (xy 20.256922 -404.900095)
			(xy 20.229626 -404.85146) (xy 20.209703 -404.799369) (xy 20.197577 -404.744932) (xy 20.193506 -404.68931)
			(xy 18.151094 -404.68931) (xy 19.482562 -406.020778) (xy 22.643338 -406.020778) (xy 22.64375 -405.995078)
			(xy 22.65065 -405.944142) (xy 22.664322 -405.894593) (xy 22.684518 -405.847326) (xy 22.710874 -405.803197)
			(xy 22.742913 -405.763003) (xy 22.761194 -405.744934) (xy 22.768814 -405.737822) (xy 22.776688 -405.71928)
			(xy 22.777704 -405.625554) (xy 22.770084 -405.607012) (xy 22.762464 -405.599646) (xy 22.741488 -405.578031)
			(xy 22.705977 -405.529382) (xy 22.678555 -405.475756) (xy 22.659903 -405.418487) (xy 22.650485 -405.358998)
			(xy 22.649942 -405.328882) (xy 22.650387 -405.301511) (xy 22.658209 -405.247331) (xy 22.673702 -405.194827)
			(xy 22.696549 -405.14508) (xy 22.726278 -405.099115) (xy 22.743922 -405.078184) (xy 22.750018 -405.071072)
			(xy 22.756368 -405.054054) (xy 22.756368 -404.96871) (xy 22.750018 -404.951692) (xy 22.743922 -404.94458)
			(xy 22.726264 -404.923661) (xy 22.69654 -404.877691) (xy 22.673696 -404.827942) (xy 22.658202 -404.775438)
			(xy 22.650375 -404.721258) (xy 22.650377 -404.666515) (xy 22.658207 -404.612335) (xy 22.673706 -404.559832)
			(xy 22.696553 -404.510085) (xy 22.72628 -404.464117) (xy 22.743922 -404.443184) (xy 22.750018 -404.436072)
			(xy 22.756368 -404.419054) (xy 22.756368 -404.33371) (xy 22.750018 -404.316692) (xy 22.743922 -404.30958)
			(xy 22.72631 -404.288626) (xy 22.696594 -404.242659) (xy 22.673752 -404.192918) (xy 22.658255 -404.140422)
			(xy 22.65042 -404.08625) (xy 22.649942 -404.058882) (xy 22.650428 -404.031631) (xy 22.658184 -403.977683)
			(xy 22.673539 -403.925388) (xy 22.696181 -403.875811) (xy 22.725647 -403.829961) (xy 22.761338 -403.78877)
			(xy 22.802529 -403.753079) (xy 22.848379 -403.723613) (xy 22.897956 -403.700971) (xy 22.950251 -403.685616)
			(xy 23.004199 -403.67786) (xy 23.058701 -403.67786) (xy 23.112649 -403.685616) (xy 23.164944 -403.700971)
			(xy 23.214521 -403.723613) (xy 23.260371 -403.753079) (xy 23.301562 -403.78877) (xy 23.337253 -403.829961)
			(xy 23.366719 -403.875811) (xy 23.389361 -403.925388) (xy 23.404716 -403.977683) (xy 23.412472 -404.031631)
			(xy 23.412958 -404.058882) (xy 23.412492 -404.086252) (xy 23.404675 -404.140432) (xy 23.389187 -404.192935)
			(xy 23.366345 -404.242682) (xy 23.33662 -404.288649) (xy 23.318978 -404.30958) (xy 23.312882 -404.316692)
			(xy 23.306532 -404.33371) (xy 23.306532 -404.419054) (xy 23.312882 -404.436072) (xy 23.318978 -404.443184)
			(xy 23.323804 -404.448772) (xy 23.330662 -404.4569) (xy 23.34895 -404.466298) (xy 23.443692 -404.472394)
			(xy 23.462996 -404.465282) (xy 23.470616 -404.45817) (xy 23.491895 -404.439221) (xy 23.539032 -404.407212)
			(xy 23.590401 -404.382562) (xy 23.644862 -404.365818) (xy 23.701207 -404.357351) (xy 23.729696 -404.356824)
			(xy 23.759819 -404.357405) (xy 23.819314 -404.366885) (xy 23.876582 -404.385593) (xy 23.930199 -404.413067)
			(xy 23.978834 -404.448623) (xy 24.00046 -404.4696) (xy 24.007572 -404.476966) (xy 24.026368 -404.484586)
			(xy 24.118824 -404.484586) (xy 24.13762 -404.476966) (xy 24.144732 -404.4696) (xy 24.166364 -404.448627)
			(xy 24.214991 -404.413058) (xy 24.268605 -404.385577) (xy 24.325874 -404.366867) (xy 24.385372 -404.357393)
			(xy 24.415496 -404.356824) (xy 24.441793 -404.357286) (xy 24.493889 -404.364503) (xy 24.544499 -404.378814)
			(xy 24.59266 -404.399948) (xy 24.637458 -404.427503) (xy 24.678041 -404.460956) (xy 24.696166 -404.480014)
			(xy 24.703278 -404.487634) (xy 24.721566 -404.496016) (xy 24.814022 -404.499318) (xy 24.833072 -404.49246)
			(xy 24.840438 -404.485348) (xy 24.861768 -404.466081) (xy 24.909129 -404.433514) (xy 24.96084 -404.40842)
			(xy 25.01573 -404.391369) (xy 25.072557 -404.382745) (xy 25.101296 -404.382224) (xy 25.131419 -404.382805)
			(xy 25.190914 -404.392285) (xy 25.248182 -404.410993) (xy 25.301799 -404.438467) (xy 25.350434 -404.474023)
			(xy 25.37206 -404.495) (xy 25.379172 -404.502366) (xy 25.397968 -404.509986) (xy 25.490424 -404.509986)
			(xy 25.50922 -404.502366) (xy 25.516332 -404.495) (xy 25.537964 -404.474027) (xy 25.586591 -404.438458)
			(xy 25.640205 -404.410977) (xy 25.697474 -404.392267) (xy 25.756972 -404.382793) (xy 25.787096 -404.382224)
			(xy 25.81435 -404.382659) (xy 25.868304 -404.390416) (xy 25.920604 -404.405774) (xy 25.970186 -404.428418)
			(xy 26.016041 -404.457888) (xy 26.057235 -404.493585) (xy 26.092928 -404.534781) (xy 26.122396 -404.580638)
			(xy 26.145036 -404.630222) (xy 26.16039 -404.682524) (xy 26.168143 -404.736478) (xy 26.168604 -404.763732)
			(xy 26.168156 -404.791103) (xy 26.160333 -404.845283) (xy 26.14484 -404.897786) (xy 26.121995 -404.947532)
			(xy 26.092267 -404.993499) (xy 26.074624 -405.01443) (xy 26.068528 -405.021542) (xy 26.062178 -405.03856)
			(xy 26.062178 -405.123904) (xy 26.068528 -405.140922) (xy 26.074624 -405.148034) (xy 26.092249 -405.168977)
			(xy 26.121962 -405.214947) (xy 26.144801 -405.264692) (xy 26.160295 -405.31719) (xy 26.168127 -405.371364)
			(xy 26.168604 -405.398732) (xy 26.168145 -405.425093) (xy 26.160898 -405.477315) (xy 26.146532 -405.528043)
			(xy 26.125321 -405.57631) (xy 26.097669 -405.621199) (xy 26.081228 -405.64181) (xy 26.075132 -405.649176)
			(xy 26.06929 -405.666702) (xy 26.0731 -405.754078) (xy 26.080466 -405.771096) (xy 26.087324 -405.777954)
			(xy 26.107808 -405.799505) (xy 26.142506 -405.847786) (xy 26.169292 -405.900866) (xy 26.187517 -405.95746)
			(xy 26.196739 -406.016196) (xy 26.197306 -406.045924) (xy 26.196845 -406.073176) (xy 26.189085 -406.127125)
			(xy 26.173726 -406.17942) (xy 26.151082 -406.228997) (xy 26.121613 -406.274848) (xy 26.085919 -406.316038)
			(xy 26.044727 -406.351729) (xy 25.998875 -406.381195) (xy 25.949296 -406.403836) (xy 25.896999 -406.41919)
			(xy 25.84305 -406.426946) (xy 25.815798 -406.427432) (xy 25.785674 -406.426868) (xy 25.726177 -406.417386)
			(xy 25.668909 -406.398674) (xy 25.615292 -406.371196) (xy 25.566658 -406.335636) (xy 25.545034 -406.314656)
			(xy 25.537922 -406.30729) (xy 25.519126 -406.29967) (xy 25.42667 -406.29967) (xy 25.407874 -406.30729)
			(xy 25.400762 -406.314656) (xy 25.379126 -406.335624) (xy 25.330501 -406.371196) (xy 25.276887 -406.398679)
			(xy 25.219619 -406.41739) (xy 25.160122 -406.426863) (xy 25.129998 -406.427432) (xy 25.1037 -406.426988)
			(xy 25.051602 -406.419769) (xy 25.000992 -406.405455) (xy 24.952831 -406.384318) (xy 24.908034 -406.356759)
			(xy 24.867451 -406.323303) (xy 24.849328 -406.304242) (xy 24.842216 -406.296622) (xy 24.823928 -406.28824)
			(xy 24.731472 -406.284938) (xy 24.712422 -406.291796) (xy 24.705056 -406.298908) (xy 24.683722 -406.31817)
			(xy 24.636363 -406.35074) (xy 24.584653 -406.375835) (xy 24.529763 -406.392887) (xy 24.472937 -406.401511)
			(xy 24.444198 -406.402032) (xy 24.414074 -406.401468) (xy 24.354577 -406.391986) (xy 24.297309 -406.373274)
			(xy 24.243692 -406.345796) (xy 24.195058 -406.310236) (xy 24.173434 -406.289256) (xy 24.166322 -406.28189)
			(xy 24.147526 -406.27427) (xy 24.05507 -406.27427) (xy 24.036274 -406.28189) (xy 24.029162 -406.289256)
			(xy 24.007526 -406.310224) (xy 23.958901 -406.345796) (xy 23.905287 -406.373279) (xy 23.848019 -406.39199)
			(xy 23.788522 -406.401463) (xy 23.758398 -406.402032) (xy 23.730987 -406.401592) (xy 23.676728 -406.393743)
			(xy 23.624152 -406.378209) (xy 23.574342 -406.355307) (xy 23.528323 -406.325511) (xy 23.487043 -406.289434)
			(xy 23.468838 -406.268936) (xy 23.461472 -406.260554) (xy 23.441406 -406.251156) (xy 23.342092 -406.251156)
			(xy 23.321772 -406.260554) (xy 23.31466 -406.268936) (xy 23.296441 -406.28946) (xy 23.255134 -406.325592)
			(xy 23.209079 -406.355436) (xy 23.159225 -406.378377) (xy 23.106598 -406.393941) (xy 23.052286 -406.401807)
			(xy 23.024846 -406.402286) (xy 22.997593 -406.401802) (xy 22.943642 -406.394051) (xy 22.891343 -406.378699)
			(xy 22.841762 -406.35606) (xy 22.795907 -406.326595) (xy 22.754714 -406.290903) (xy 22.719019 -406.249712)
			(xy 22.689551 -406.203859) (xy 22.666909 -406.154279) (xy 22.651555 -406.101982) (xy 22.6438 -406.048031)
			(xy 22.643338 -406.020778) (xy 19.482562 -406.020778) (xy 19.63674 -406.174956) (xy 19.656171 -406.195085)
			(xy 19.689047 -406.240353) (xy 19.714425 -406.290212) (xy 19.731681 -406.343431) (xy 19.740387 -406.398696)
			(xy 19.74088 -406.42667) (xy 19.74088 -407.090626) (xy 19.741336 -407.100631) (xy 19.749058 -407.119095)
			(xy 19.755866 -407.12644) (xy 21.147278 -408.517852) (xy 32.401762 -408.517852) (xy 32.405833 -408.46223)
			(xy 32.417959 -408.407793) (xy 32.437882 -408.355702) (xy 32.465178 -408.307067) (xy 32.499264 -408.262924)
			(xy 32.539413 -408.224215) (xy 32.584771 -408.191764) (xy 32.634371 -408.166263) (xy 32.687155 -408.148256)
			(xy 32.741998 -408.138126) (xy 32.797732 -408.136089) (xy 32.853169 -408.142189) (xy 32.907126 -408.156295)
			(xy 32.958455 -408.178107) (xy 33.006061 -408.207161) (xy 33.048929 -408.242836) (xy 33.086146 -408.284373)
			(xy 33.116919 -408.330886) (xy 33.140591 -408.381383) (xy 33.156659 -408.43479) (xy 33.164779 -408.489966)
			(xy 33.165288 -408.517852) (xy 33.164779 -408.545738) (xy 33.156659 -408.600914) (xy 33.140591 -408.654321)
			(xy 33.116919 -408.704818) (xy 33.086146 -408.751331) (xy 33.048929 -408.792868) (xy 33.006061 -408.828543)
			(xy 32.958455 -408.857597) (xy 32.907126 -408.879409) (xy 32.853169 -408.893515) (xy 32.797732 -408.899615)
			(xy 32.741998 -408.897578) (xy 32.687155 -408.887448) (xy 32.634371 -408.869441) (xy 32.584771 -408.84394)
			(xy 32.539413 -408.811489) (xy 32.499264 -408.77278) (xy 32.465178 -408.728637) (xy 32.437882 -408.680002)
			(xy 32.417959 -408.627911) (xy 32.405833 -408.573474) (xy 32.401762 -408.517852) (xy 21.147278 -408.517852)
			(xy 21.702014 -409.072588) (xy 21.710142 -409.076398) (xy 21.73434 -409.088322) (xy 21.779416 -409.117958)
			(xy 21.819868 -409.153647) (xy 21.854891 -409.194677) (xy 21.883786 -409.240231) (xy 21.905978 -409.2894)
			(xy 21.921023 -409.341204) (xy 21.928623 -409.394611) (xy 21.92909 -409.421584) (xy 21.92863 -409.448837)
			(xy 21.920874 -409.502789) (xy 21.90552 -409.555088) (xy 21.882878 -409.60467) (xy 21.85341 -409.650524)
			(xy 21.817715 -409.691717) (xy 21.776522 -409.727411) (xy 21.730668 -409.756879) (xy 21.681086 -409.77952)
			(xy 21.628787 -409.794875) (xy 21.574835 -409.80263) (xy 21.547582 -409.803092) (xy 21.520606 -409.802664)
			(xy 21.467192 -409.795073) (xy 21.41538 -409.780031) (xy 21.366205 -409.757838) (xy 21.320648 -409.728937)
			(xy 21.279618 -409.693905) (xy 21.243933 -409.653441) (xy 21.214307 -409.608352) (xy 21.202396 -409.584144)
			(xy 21.198586 -409.576016) (xy 19.133312 -407.510742) (xy 19.113871 -407.490622) (xy 19.080999 -407.44535)
			(xy 19.055623 -407.395489) (xy 19.038369 -407.342268) (xy 19.029665 -407.287002) (xy 19.029172 -407.259028)
			(xy 19.029172 -406.595072) (xy 19.028703 -406.585068) (xy 19.020989 -406.566606) (xy 19.014186 -406.559258)
			(xy 17.054068 -404.59914) (xy 17.034636 -404.579011) (xy 17.001761 -404.533743) (xy 16.976382 -404.483884)
			(xy 16.959127 -404.430665) (xy 16.950421 -404.3754) (xy 16.949928 -404.347426) (xy 16.949928 -404.292054)
			(xy 16.93291 -404.266654) (xy 16.918432 -404.260558) (xy 16.908999 -404.257121) (xy 16.888936 -404.257174)
			(xy 16.870426 -404.264911) (xy 16.86306 -404.271734) (xy 16.667988 -404.466806) (xy 16.647833 -404.486217)
			(xy 16.602569 -404.519112) (xy 16.55272 -404.54453) (xy 16.499512 -404.561845) (xy 16.444251 -404.570631)
			(xy 16.416274 -404.5712) (xy 14.170406 -404.5712) (xy 14.142424 -404.570698) (xy 14.087152 -404.561922)
			(xy 14.033935 -404.544603) (xy 13.984085 -404.519166) (xy 13.938831 -404.48624) (xy 13.918692 -404.466806)
			(xy 13.476478 -404.024592) (xy 13.457066 -404.004438) (xy 13.424171 -403.959173) (xy 13.398755 -403.909324)
			(xy 13.38144 -403.856116) (xy 13.372653 -403.800855) (xy 13.372084 -403.772878) (xy 13.372084 -402.521166)
			(xy 13.371629 -402.511197) (xy 13.364038 -402.492762) (xy 13.357352 -402.485352) (xy 12.132818 -401.260818)
			(xy 12.113408 -401.240663) (xy 12.080515 -401.195397) (xy 12.0551 -401.145548) (xy 12.037784 -401.09234)
			(xy 12.028995 -401.037081) (xy 12.028424 -401.009104) (xy 12.028424 -396.198344) (xy 12.02563 -396.189962)
			(xy 12.015092 -396.15875) (xy 12.003733 -396.093865) (xy 12.003024 -396.06093) (xy 11.120628 -396.06093)
			(xy 11.120628 -401.703794) (xy 11.121165 -401.713781) (xy 11.12888 -401.732212) (xy 11.135614 -401.739608)
			(xy 11.578082 -402.18233) (xy 11.585482 -402.189171) (xy 11.604081 -402.196887) (xy 11.61415 -402.197316)
			(xy 12.008866 -402.197316) (xy 12.015978 -402.19503) (xy 12.042549 -402.187659) (xy 12.09712 -402.179754)
			(xy 12.12469 -402.179282) (xy 12.151944 -402.179744) (xy 12.205898 -402.1875) (xy 12.258198 -402.202856)
			(xy 12.307781 -402.225498) (xy 12.353636 -402.254967) (xy 12.394831 -402.290662) (xy 12.430527 -402.331856)
			(xy 12.459997 -402.37771) (xy 12.482641 -402.427293) (xy 12.497998 -402.479593) (xy 12.505755 -402.533546)
			(xy 12.505755 -402.588054) (xy 12.497998 -402.642007) (xy 12.482641 -402.694307) (xy 12.459997 -402.74389)
			(xy 12.430527 -402.789744) (xy 12.394831 -402.830938) (xy 12.353636 -402.866633) (xy 12.307781 -402.896102)
			(xy 12.258198 -402.918744) (xy 12.205898 -402.9341) (xy 12.151944 -402.941856) (xy 12.12469 -402.942298)
			(xy 12.097119 -402.941832) (xy 12.042547 -402.933929) (xy 12.015978 -402.92655) (xy 12.008866 -402.924264)
			(xy 11.766296 -402.924264) (xy 11.756249 -402.924688) (xy 11.737691 -402.932393) (xy 11.723505 -402.946623)
			(xy 11.719306 -402.95576) (xy 11.71321 -402.970238) (xy 11.719306 -402.999956) (xy 12.18565 -403.466554)
			(xy 12.20216 -403.47392) (xy 12.211558 -403.474682) (xy 12.240107 -403.477181) (xy 12.29604 -403.489658)
			(xy 12.349478 -403.510357) (xy 12.399221 -403.538813) (xy 12.44415 -403.574387) (xy 12.483255 -403.616279)
			(xy 12.515656 -403.663547) (xy 12.540626 -403.715128) (xy 12.557603 -403.769863) (xy 12.566205 -403.826521)
			(xy 12.56665 -403.855174) (xy 12.566166 -403.882428) (xy 12.558413 -403.93638) (xy 12.54306 -403.988681)
			(xy 12.520421 -404.038264) (xy 12.490956 -404.08412) (xy 12.455265 -404.125317) (xy 12.414075 -404.161015)
			(xy 12.368224 -404.190489) (xy 12.318644 -404.213137) (xy 12.266347 -404.228498) (xy 12.212395 -404.236261)
			(xy 12.185142 -404.236682) (xy 12.157572 -404.236213) (xy 12.103001 -404.228305) (xy 12.07643 -404.220934)
			(xy 12.069318 -404.218648) (xy 12.060174 -404.218648) (xy 12.031609 -404.218094) (xy 11.975181 -404.209169)
			(xy 11.920844 -404.191528) (xy 11.869935 -404.165605) (xy 11.823707 -404.132037) (xy 11.803126 -404.112222)
			(xy 11.207242 -403.516592) (xy 11.199879 -403.509763) (xy 11.181367 -403.502016) (xy 11.161299 -403.501962)
			(xy 11.15187 -403.505416) (xy 11.137646 -403.511512) (xy 11.120628 -403.536658) (xy 11.120628 -405.934751)
			(xy 14.302972 -405.934751) (xy 14.302972 -405.880249) (xy 14.310728 -405.826301) (xy 14.326083 -405.774005)
			(xy 14.348724 -405.724428) (xy 14.378191 -405.678577) (xy 14.413882 -405.637386) (xy 14.455072 -405.601694)
			(xy 14.500923 -405.572227) (xy 14.5505 -405.549585) (xy 14.602795 -405.53423) (xy 14.656743 -405.526472)
			(xy 14.683994 -405.525986) (xy 14.713337 -405.526528) (xy 14.771331 -405.535514) (xy 14.827264 -405.553275)
			(xy 14.879819 -405.579391) (xy 14.927754 -405.613248) (xy 14.969939 -405.654045) (xy 15.005379 -405.700822)
			(xy 15.019782 -405.726392) (xy 15.027447 -405.739632) (xy 15.049269 -405.76106) (xy 15.076451 -405.775076)
			(xy 15.106563 -405.780428) (xy 15.136911 -405.776636) (xy 15.16478 -405.764039) (xy 15.187677 -405.743765)
			(xy 15.196058 -405.730964) (xy 15.21095 -405.707329) (xy 15.2466 -405.66432) (xy 15.288146 -405.626974)
			(xy 15.334697 -405.596092) (xy 15.385257 -405.572334) (xy 15.438742 -405.556209) (xy 15.494008 -405.548062)
			(xy 15.52194 -405.547576) (xy 15.549192 -405.548054) (xy 15.60314 -405.55581) (xy 15.655435 -405.571166)
			(xy 15.705013 -405.593807) (xy 15.750864 -405.623274) (xy 15.792054 -405.658966) (xy 15.827746 -405.700156)
			(xy 15.857213 -405.746007) (xy 15.879854 -405.795585) (xy 15.89521 -405.84788) (xy 15.902966 -405.901828)
			(xy 15.902966 -405.956332) (xy 15.89521 -406.01028) (xy 15.879854 -406.062575) (xy 15.857213 -406.112153)
			(xy 15.827746 -406.158004) (xy 15.792054 -406.199194) (xy 15.750864 -406.234886) (xy 15.705013 -406.264353)
			(xy 15.655435 -406.286994) (xy 15.60314 -406.30235) (xy 15.549192 -406.310106) (xy 15.52194 -406.310592)
			(xy 15.492597 -406.310034) (xy 15.434604 -406.301053) (xy 15.37867 -406.283296) (xy 15.326115 -406.257182)
			(xy 15.27818 -406.223328) (xy 15.235995 -406.182531) (xy 15.200555 -406.135756) (xy 15.186152 -406.110186)
			(xy 15.178439 -406.096978) (xy 15.156625 -406.075557) (xy 15.129453 -406.061544) (xy 15.099353 -406.05619)
			(xy 15.069016 -406.059975) (xy 15.041153 -406.07256) (xy 15.018258 -406.09282) (xy 15.009876 -406.105614)
			(xy 14.994953 -406.129229) (xy 14.959309 -406.172239) (xy 14.917769 -406.209586) (xy 14.871223 -406.240472)
			(xy 14.820668 -406.264233) (xy 14.767187 -406.280362) (xy 14.711924 -406.288514) (xy 14.683994 -406.289002)
			(xy 14.656743 -406.288528) (xy 14.602795 -406.28077) (xy 14.5505 -406.265415) (xy 14.500923 -406.242773)
			(xy 14.455072 -406.213306) (xy 14.413882 -406.177614) (xy 14.378191 -406.136423) (xy 14.348724 -406.090572)
			(xy 14.326083 -406.040995) (xy 14.310728 -405.988699) (xy 14.302972 -405.934751) (xy 11.120628 -405.934751)
			(xy 11.120628 -406.627584) (xy 11.716764 -406.627584) (xy 11.720835 -406.571962) (xy 11.732961 -406.517525)
			(xy 11.752884 -406.465434) (xy 11.78018 -406.416799) (xy 11.814266 -406.372656) (xy 11.854415 -406.333947)
			(xy 11.899773 -406.301496) (xy 11.949373 -406.275995) (xy 12.002157 -406.257988) (xy 12.057 -406.247858)
			(xy 12.112734 -406.245821) (xy 12.168171 -406.251921) (xy 12.222128 -406.266027) (xy 12.273457 -406.287839)
			(xy 12.321063 -406.316893) (xy 12.363931 -406.352568) (xy 12.401148 -406.394105) (xy 12.431921 -406.440618)
			(xy 12.455593 -406.491115) (xy 12.471661 -406.544522) (xy 12.479781 -406.599698) (xy 12.48029 -406.627584)
			(xy 12.479781 -406.65547) (xy 12.471661 -406.710646) (xy 12.455593 -406.764053) (xy 12.431921 -406.81455)
			(xy 12.401148 -406.861063) (xy 12.363931 -406.9026) (xy 12.321063 -406.938275) (xy 12.273457 -406.967329)
			(xy 12.222128 -406.989141) (xy 12.168171 -407.003247) (xy 12.112734 -407.009347) (xy 12.057 -407.00731)
			(xy 12.002157 -406.99718) (xy 11.949373 -406.979173) (xy 11.899773 -406.953672) (xy 11.854415 -406.921221)
			(xy 11.814266 -406.882512) (xy 11.78018 -406.838369) (xy 11.752884 -406.789734) (xy 11.732961 -406.737643)
			(xy 11.720835 -406.683206) (xy 11.716764 -406.627584) (xy 11.120628 -406.627584) (xy 11.120628 -407.50871)
			(xy 18.001232 -407.50871) (xy 18.005303 -407.453088) (xy 18.017429 -407.398651) (xy 18.037352 -407.34656)
			(xy 18.064648 -407.297925) (xy 18.098734 -407.253782) (xy 18.138883 -407.215073) (xy 18.184241 -407.182622)
			(xy 18.233841 -407.157121) (xy 18.286625 -407.139114) (xy 18.341468 -407.128984) (xy 18.397202 -407.126947)
			(xy 18.452639 -407.133047) (xy 18.506596 -407.147153) (xy 18.557925 -407.168965) (xy 18.605531 -407.198019)
			(xy 18.648399 -407.233694) (xy 18.685616 -407.275231) (xy 18.716389 -407.321744) (xy 18.740061 -407.372241)
			(xy 18.756129 -407.425648) (xy 18.764249 -407.480824) (xy 18.764758 -407.50871) (xy 18.764249 -407.536596)
			(xy 18.756129 -407.591772) (xy 18.740061 -407.645179) (xy 18.716389 -407.695676) (xy 18.685616 -407.742189)
			(xy 18.648399 -407.783726) (xy 18.605531 -407.819401) (xy 18.557925 -407.848455) (xy 18.506596 -407.870267)
			(xy 18.452639 -407.884373) (xy 18.397202 -407.890473) (xy 18.341468 -407.888436) (xy 18.286625 -407.878306)
			(xy 18.233841 -407.860299) (xy 18.184241 -407.834798) (xy 18.138883 -407.802347) (xy 18.098734 -407.763638)
			(xy 18.064648 -407.719495) (xy 18.037352 -407.67086) (xy 18.017429 -407.618769) (xy 18.005303 -407.564332)
			(xy 18.001232 -407.50871) (xy 11.120628 -407.50871) (xy 11.120628 -407.746708) (xy 11.143234 -407.774394)
			(xy 11.161014 -407.778204) (xy 11.187741 -407.784287) (xy 11.23923 -407.803087) (xy 11.287498 -407.829063)
			(xy 11.331552 -407.86168) (xy 11.370484 -407.900265) (xy 11.403493 -407.944025) (xy 11.429899 -407.992059)
			(xy 11.44916 -408.043378) (xy 11.460877 -408.096924) (xy 11.46481 -408.151597) (xy 11.460878 -408.206269)
			(xy 11.449161 -408.259816) (xy 11.429902 -408.311135) (xy 11.403497 -408.359169) (xy 11.370488 -408.40293)
			(xy 11.331557 -408.441516) (xy 11.287504 -408.474133) (xy 11.239236 -408.50011) (xy 11.187748 -408.518911)
			(xy 11.161014 -408.524964) (xy 11.143234 -408.528774) (xy 11.120628 -408.55646) (xy 11.120628 -409.167584)
			(xy 18.447764 -409.167584) (xy 18.451835 -409.111962) (xy 18.463961 -409.057525) (xy 18.483884 -409.005434)
			(xy 18.51118 -408.956799) (xy 18.545266 -408.912656) (xy 18.585415 -408.873947) (xy 18.630773 -408.841496)
			(xy 18.680373 -408.815995) (xy 18.733157 -408.797988) (xy 18.788 -408.787858) (xy 18.843734 -408.785821)
			(xy 18.899171 -408.791921) (xy 18.953128 -408.806027) (xy 19.004457 -408.827839) (xy 19.052063 -408.856893)
			(xy 19.094931 -408.892568) (xy 19.132148 -408.934105) (xy 19.162921 -408.980618) (xy 19.186593 -409.031115)
			(xy 19.202661 -409.084522) (xy 19.210781 -409.139698) (xy 19.21129 -409.167584) (xy 19.210781 -409.19547)
			(xy 19.202661 -409.250646) (xy 19.186593 -409.304053) (xy 19.162921 -409.35455) (xy 19.132148 -409.401063)
			(xy 19.094931 -409.4426) (xy 19.052063 -409.478275) (xy 19.004457 -409.507329) (xy 18.953128 -409.529141)
			(xy 18.899171 -409.543247) (xy 18.843734 -409.549347) (xy 18.788 -409.54731) (xy 18.733157 -409.53718)
			(xy 18.680373 -409.519173) (xy 18.630773 -409.493672) (xy 18.585415 -409.461221) (xy 18.545266 -409.422512)
			(xy 18.51118 -409.378369) (xy 18.483884 -409.329734) (xy 18.463961 -409.277643) (xy 18.451835 -409.223206)
			(xy 18.447764 -409.167584) (xy 11.120628 -409.167584) (xy 11.120628 -409.457144) (xy 11.121138 -409.46695)
			(xy 11.1286 -409.485093) (xy 11.135106 -409.49245) (xy 11.156188 -409.514294) (xy 11.162908 -409.520583)
			(xy 11.179567 -409.528383) (xy 11.1887 -409.529534) (xy 11.220186 -409.532619) (xy 11.28158 -409.54788)
			(xy 11.33962 -409.573048) (xy 11.3665 -409.589732) (xy 11.377168 -409.59659) (xy 11.402314 -409.598876)
			(xy 11.503152 -409.556458) (xy 11.5189 -409.5369) (xy 11.52144 -409.524454) (xy 11.527694 -409.496004)
			(xy 11.547672 -409.44129) (xy 11.575736 -409.390249) (xy 11.611233 -409.344067) (xy 11.653338 -409.303819)
			(xy 11.701073 -409.270439) (xy 11.753327 -409.244704) (xy 11.808886 -409.227212) (xy 11.866458 -409.218369)
			(xy 11.895582 -409.217876) (xy 11.922837 -409.218338) (xy 11.976792 -409.226093) (xy 12.029094 -409.241448)
			(xy 12.078679 -409.26409) (xy 12.124536 -409.293559) (xy 12.165733 -409.329254) (xy 12.20143 -409.370449)
			(xy 12.230901 -409.416305) (xy 12.253546 -409.465889) (xy 12.268903 -409.51819) (xy 12.276661 -409.572145)
			(xy 12.276661 -409.626655) (xy 12.268903 -409.68061) (xy 12.253546 -409.732911) (xy 12.230901 -409.782495)
			(xy 12.20143 -409.828351) (xy 12.165733 -409.869546) (xy 12.124536 -409.905241) (xy 12.078679 -409.93471)
			(xy 12.029094 -409.957352) (xy 11.976792 -409.972707) (xy 11.922837 -409.980462) (xy 11.895582 -409.980892)
			(xy 11.868139 -409.980396) (xy 11.813824 -409.972501) (xy 11.761196 -409.95692) (xy 11.711337 -409.933973)
			(xy 11.688064 -409.919424) (xy 11.677396 -409.912566) (xy 11.65225 -409.91028) (xy 11.551412 -409.952698)
			(xy 11.535664 -409.972256) (xy 11.533124 -409.984702) (xy 11.52727 -410.01154) (xy 11.508881 -410.063301)
			(xy 11.483253 -410.111887) (xy 11.450914 -410.156289) (xy 11.412536 -410.195589) (xy 11.368913 -410.228972)
			(xy 11.32095 -410.255746) (xy 11.26964 -410.275357) (xy 11.216045 -410.287399) (xy 11.1887 -410.29001)
			(xy 11.179545 -410.291082) (xy 11.162868 -410.298898) (xy 11.156188 -410.30525) (xy 11.135106 -410.327094)
			(xy 11.12857 -410.334426) (xy 11.121142 -410.352589) (xy 11.120628 -410.3624) (xy 11.120628 -410.64942)
			(xy 17.970752 -410.64942) (xy 17.974823 -410.593798) (xy 17.986949 -410.539361) (xy 18.006872 -410.48727)
			(xy 18.034168 -410.438635) (xy 18.068254 -410.394492) (xy 18.108403 -410.355783) (xy 18.153761 -410.323332)
			(xy 18.203361 -410.297831) (xy 18.256145 -410.279824) (xy 18.310988 -410.269694) (xy 18.366722 -410.267657)
			(xy 18.422159 -410.273757) (xy 18.476116 -410.287863) (xy 18.527445 -410.309675) (xy 18.575051 -410.338729)
			(xy 18.617919 -410.374404) (xy 18.655136 -410.415941) (xy 18.685909 -410.462454) (xy 18.709581 -410.512951)
			(xy 18.725649 -410.566358) (xy 18.733769 -410.621534) (xy 18.734278 -410.64942) (xy 18.733769 -410.677306)
			(xy 18.725649 -410.732482) (xy 18.709581 -410.785889) (xy 18.685909 -410.836386) (xy 18.655136 -410.882899)
			(xy 18.617919 -410.924436) (xy 18.575051 -410.960111) (xy 18.527445 -410.989165) (xy 18.476116 -411.010977)
			(xy 18.422159 -411.025083) (xy 18.366722 -411.031183) (xy 18.310988 -411.029146) (xy 18.256145 -411.019016)
			(xy 18.203361 -411.001009) (xy 18.153761 -410.975508) (xy 18.108403 -410.943057) (xy 18.068254 -410.904348)
			(xy 18.034168 -410.860205) (xy 18.006872 -410.81157) (xy 17.986949 -410.759479) (xy 17.974823 -410.705042)
			(xy 17.970752 -410.64942) (xy 11.120628 -410.64942) (xy 11.120628 -411.34284) (xy 30.531052 -411.34284)
			(xy 30.535123 -411.287218) (xy 30.547249 -411.232781) (xy 30.567172 -411.18069) (xy 30.594468 -411.132055)
			(xy 30.628554 -411.087912) (xy 30.668703 -411.049203) (xy 30.714061 -411.016752) (xy 30.763661 -410.991251)
			(xy 30.816445 -410.973244) (xy 30.871288 -410.963114) (xy 30.927022 -410.961077) (xy 30.982459 -410.967177)
			(xy 31.036416 -410.981283) (xy 31.087745 -411.003095) (xy 31.135351 -411.032149) (xy 31.178219 -411.067824)
			(xy 31.215436 -411.109361) (xy 31.246209 -411.155874) (xy 31.269881 -411.206371) (xy 31.285949 -411.259778)
			(xy 31.294069 -411.314954) (xy 31.294578 -411.34284) (xy 31.294069 -411.370726) (xy 31.285949 -411.425902)
			(xy 31.269881 -411.479309) (xy 31.246209 -411.529806) (xy 31.215436 -411.576319) (xy 31.178219 -411.617856)
			(xy 31.135351 -411.653531) (xy 31.087745 -411.682585) (xy 31.036416 -411.704397) (xy 30.982459 -411.718503)
			(xy 30.927022 -411.724603) (xy 30.871288 -411.722566) (xy 30.816445 -411.712436) (xy 30.763661 -411.694429)
			(xy 30.714061 -411.668928) (xy 30.668703 -411.636477) (xy 30.628554 -411.597768) (xy 30.594468 -411.553625)
			(xy 30.567172 -411.50499) (xy 30.547249 -411.452899) (xy 30.535123 -411.398462) (xy 30.531052 -411.34284)
			(xy 11.120628 -411.34284) (xy 11.120628 -411.834584) (xy 18.448018 -411.834584) (xy 18.452089 -411.778962)
			(xy 18.464215 -411.724525) (xy 18.484138 -411.672434) (xy 18.511434 -411.623799) (xy 18.54552 -411.579656)
			(xy 18.585669 -411.540947) (xy 18.631027 -411.508496) (xy 18.680627 -411.482995) (xy 18.733411 -411.464988)
			(xy 18.788254 -411.454858) (xy 18.843988 -411.452821) (xy 18.899425 -411.458921) (xy 18.953382 -411.473027)
			(xy 19.004711 -411.494839) (xy 19.052317 -411.523893) (xy 19.095185 -411.559568) (xy 19.132402 -411.601105)
			(xy 19.163175 -411.647618) (xy 19.186847 -411.698115) (xy 19.202915 -411.751522) (xy 19.211035 -411.806698)
			(xy 19.211544 -411.834584) (xy 19.211035 -411.86247) (xy 19.202915 -411.917646) (xy 19.19963 -411.928564)
			(xy 29.502352 -411.928564) (xy 29.506423 -411.872942) (xy 29.518549 -411.818505) (xy 29.538472 -411.766414)
			(xy 29.565768 -411.717779) (xy 29.599854 -411.673636) (xy 29.640003 -411.634927) (xy 29.685361 -411.602476)
			(xy 29.734961 -411.576975) (xy 29.787745 -411.558968) (xy 29.842588 -411.548838) (xy 29.898322 -411.546801)
			(xy 29.953759 -411.552901) (xy 30.007716 -411.567007) (xy 30.059045 -411.588819) (xy 30.106651 -411.617873)
			(xy 30.149519 -411.653548) (xy 30.186736 -411.695085) (xy 30.217509 -411.741598) (xy 30.241181 -411.792095)
			(xy 30.257249 -411.845502) (xy 30.265369 -411.900678) (xy 30.265878 -411.928564) (xy 30.265369 -411.95645)
			(xy 30.257249 -412.011626) (xy 30.241181 -412.065033) (xy 30.217509 -412.11553) (xy 30.186736 -412.162043)
			(xy 30.149519 -412.20358) (xy 30.106651 -412.239255) (xy 30.059045 -412.268309) (xy 30.007716 -412.290121)
			(xy 29.953759 -412.304227) (xy 29.898322 -412.310327) (xy 29.842588 -412.30829) (xy 29.787745 -412.29816)
			(xy 29.734961 -412.280153) (xy 29.685361 -412.254652) (xy 29.640003 -412.222201) (xy 29.599854 -412.183492)
			(xy 29.565768 -412.139349) (xy 29.538472 -412.090714) (xy 29.518549 -412.038623) (xy 29.506423 -411.984186)
			(xy 29.502352 -411.928564) (xy 19.19963 -411.928564) (xy 19.186847 -411.971053) (xy 19.163175 -412.02155)
			(xy 19.132402 -412.068063) (xy 19.095185 -412.1096) (xy 19.052317 -412.145275) (xy 19.004711 -412.174329)
			(xy 18.953382 -412.196141) (xy 18.899425 -412.210247) (xy 18.843988 -412.216347) (xy 18.788254 -412.21431)
			(xy 18.733411 -412.20418) (xy 18.680627 -412.186173) (xy 18.631027 -412.160672) (xy 18.585669 -412.128221)
			(xy 18.54552 -412.089512) (xy 18.511434 -412.045369) (xy 18.484138 -411.996734) (xy 18.464215 -411.944643)
			(xy 18.452089 -411.890206) (xy 18.448018 -411.834584) (xy 11.120628 -411.834584) (xy 11.120628 -412.903162)
			(xy 17.542 -412.903162) (xy 17.546071 -412.84754) (xy 17.558197 -412.793103) (xy 17.57812 -412.741012)
			(xy 17.605416 -412.692377) (xy 17.639502 -412.648234) (xy 17.679651 -412.609525) (xy 17.725009 -412.577074)
			(xy 17.774609 -412.551573) (xy 17.827393 -412.533566) (xy 17.882236 -412.523436) (xy 17.93797 -412.521399)
			(xy 17.993407 -412.527499) (xy 18.047364 -412.541605) (xy 18.098693 -412.563417) (xy 18.146299 -412.592471)
			(xy 18.189167 -412.628146) (xy 18.193887 -412.633414) (xy 28.730954 -412.633414) (xy 28.735025 -412.577792)
			(xy 28.747151 -412.523355) (xy 28.767074 -412.471264) (xy 28.79437 -412.422629) (xy 28.828456 -412.378486)
			(xy 28.868605 -412.339777) (xy 28.913963 -412.307326) (xy 28.963563 -412.281825) (xy 29.016347 -412.263818)
			(xy 29.07119 -412.253688) (xy 29.126924 -412.251651) (xy 29.182361 -412.257751) (xy 29.236318 -412.271857)
			(xy 29.287647 -412.293669) (xy 29.335253 -412.322723) (xy 29.378121 -412.358398) (xy 29.415338 -412.399935)
			(xy 29.446111 -412.446448) (xy 29.469783 -412.496945) (xy 29.485851 -412.550352) (xy 29.493971 -412.605528)
			(xy 29.49448 -412.633414) (xy 29.493971 -412.6613) (xy 29.485851 -412.716476) (xy 29.469783 -412.769883)
			(xy 29.446111 -412.82038) (xy 29.415338 -412.866893) (xy 29.378121 -412.90843) (xy 29.335253 -412.944105)
			(xy 29.287647 -412.973159) (xy 29.236318 -412.994971) (xy 29.182361 -413.009077) (xy 29.126924 -413.015177)
			(xy 29.07119 -413.01314) (xy 29.016347 -413.00301) (xy 28.963563 -412.985003) (xy 28.913963 -412.959502)
			(xy 28.868605 -412.927051) (xy 28.828456 -412.888342) (xy 28.79437 -412.844199) (xy 28.767074 -412.795564)
			(xy 28.747151 -412.743473) (xy 28.735025 -412.689036) (xy 28.730954 -412.633414) (xy 18.193887 -412.633414)
			(xy 18.226384 -412.669683) (xy 18.257157 -412.716196) (xy 18.280829 -412.766693) (xy 18.296897 -412.8201)
			(xy 18.305017 -412.875276) (xy 18.305526 -412.903162) (xy 18.305017 -412.931048) (xy 18.296897 -412.986224)
			(xy 18.280829 -413.039631) (xy 18.257157 -413.090128) (xy 18.226384 -413.136641) (xy 18.189167 -413.178178)
			(xy 18.146299 -413.213853) (xy 18.098693 -413.242907) (xy 18.047364 -413.264719) (xy 17.993407 -413.278825)
			(xy 17.93797 -413.284925) (xy 17.882236 -413.282888) (xy 17.827393 -413.272758) (xy 17.774609 -413.254751)
			(xy 17.725009 -413.22925) (xy 17.679651 -413.196799) (xy 17.639502 -413.15809) (xy 17.605416 -413.113947)
			(xy 17.57812 -413.065312) (xy 17.558197 -413.013221) (xy 17.546071 -412.958784) (xy 17.542 -412.903162)
			(xy 11.120628 -412.903162) (xy 11.120628 -413.485584) (xy 15.907764 -413.485584) (xy 15.911835 -413.429962)
			(xy 15.923961 -413.375525) (xy 15.943884 -413.323434) (xy 15.97118 -413.274799) (xy 16.005266 -413.230656)
			(xy 16.045415 -413.191947) (xy 16.090773 -413.159496) (xy 16.140373 -413.133995) (xy 16.193157 -413.115988)
			(xy 16.248 -413.105858) (xy 16.303734 -413.103821) (xy 16.359171 -413.109921) (xy 16.413128 -413.124027)
			(xy 16.464457 -413.145839) (xy 16.512063 -413.174893) (xy 16.554931 -413.210568) (xy 16.592148 -413.252105)
			(xy 16.622921 -413.298618) (xy 16.646593 -413.349115) (xy 16.662661 -413.402522) (xy 16.664643 -413.415988)
			(xy 18.764502 -413.415988) (xy 18.768573 -413.360366) (xy 18.780699 -413.305929) (xy 18.800622 -413.253838)
			(xy 18.827918 -413.205203) (xy 18.862004 -413.16106) (xy 18.902153 -413.122351) (xy 18.947511 -413.0899)
			(xy 18.997111 -413.064399) (xy 19.049895 -413.046392) (xy 19.104738 -413.036262) (xy 19.160472 -413.034225)
			(xy 19.215909 -413.040325) (xy 19.269866 -413.054431) (xy 19.321195 -413.076243) (xy 19.368801 -413.105297)
			(xy 19.411669 -413.140972) (xy 19.448886 -413.182509) (xy 19.479659 -413.229022) (xy 19.503331 -413.279519)
			(xy 19.519399 -413.332926) (xy 19.527519 -413.388102) (xy 19.528028 -413.415988) (xy 19.527519 -413.443874)
			(xy 19.519399 -413.49905) (xy 19.503331 -413.552457) (xy 19.479659 -413.602954) (xy 19.448886 -413.649467)
			(xy 19.411669 -413.691004) (xy 19.368801 -413.726679) (xy 19.321195 -413.755733) (xy 19.269866 -413.777545)
			(xy 19.215909 -413.791651) (xy 19.160472 -413.797751) (xy 19.104738 -413.795714) (xy 19.049895 -413.785584)
			(xy 18.997111 -413.767577) (xy 18.947511 -413.742076) (xy 18.902153 -413.709625) (xy 18.862004 -413.670916)
			(xy 18.827918 -413.626773) (xy 18.800622 -413.578138) (xy 18.780699 -413.526047) (xy 18.768573 -413.47161)
			(xy 18.764502 -413.415988) (xy 16.664643 -413.415988) (xy 16.670781 -413.457698) (xy 16.67129 -413.485584)
			(xy 16.670781 -413.51347) (xy 16.662661 -413.568646) (xy 16.646593 -413.622053) (xy 16.622921 -413.67255)
			(xy 16.592148 -413.719063) (xy 16.554931 -413.7606) (xy 16.512063 -413.796275) (xy 16.464457 -413.825329)
			(xy 16.413128 -413.847141) (xy 16.359171 -413.861247) (xy 16.303734 -413.867347) (xy 16.248 -413.86531)
			(xy 16.193157 -413.85518) (xy 16.140373 -413.837173) (xy 16.090773 -413.811672) (xy 16.045415 -413.779221)
			(xy 16.005266 -413.740512) (xy 15.97118 -413.696369) (xy 15.943884 -413.647734) (xy 15.923961 -413.595643)
			(xy 15.911835 -413.541206) (xy 15.907764 -413.485584) (xy 11.120628 -413.485584) (xy 11.120628 -413.993584)
			(xy 13.240764 -413.993584) (xy 13.244835 -413.937962) (xy 13.256961 -413.883525) (xy 13.276884 -413.831434)
			(xy 13.30418 -413.782799) (xy 13.338266 -413.738656) (xy 13.378415 -413.699947) (xy 13.423773 -413.667496)
			(xy 13.473373 -413.641995) (xy 13.526157 -413.623988) (xy 13.581 -413.613858) (xy 13.636734 -413.611821)
			(xy 13.692171 -413.617921) (xy 13.746128 -413.632027) (xy 13.797457 -413.653839) (xy 13.845063 -413.682893)
			(xy 13.887931 -413.718568) (xy 13.925148 -413.760105) (xy 13.955921 -413.806618) (xy 13.979593 -413.857115)
			(xy 13.995661 -413.910522) (xy 14.003781 -413.965698) (xy 14.00429 -413.993584) (xy 14.510764 -413.993584)
			(xy 14.514835 -413.937962) (xy 14.526961 -413.883525) (xy 14.546884 -413.831434) (xy 14.57418 -413.782799)
			(xy 14.608266 -413.738656) (xy 14.648415 -413.699947) (xy 14.693773 -413.667496) (xy 14.743373 -413.641995)
			(xy 14.796157 -413.623988) (xy 14.851 -413.613858) (xy 14.906734 -413.611821) (xy 14.962171 -413.617921)
			(xy 15.016128 -413.632027) (xy 15.067457 -413.653839) (xy 15.115063 -413.682893) (xy 15.157931 -413.718568)
			(xy 15.195148 -413.760105) (xy 15.225921 -413.806618) (xy 15.249593 -413.857115) (xy 15.265661 -413.910522)
			(xy 15.273781 -413.965698) (xy 15.27429 -413.993584) (xy 15.273781 -414.02147) (xy 15.265661 -414.076646)
			(xy 15.249593 -414.130053) (xy 15.225921 -414.18055) (xy 15.195148 -414.227063) (xy 15.157931 -414.2686)
			(xy 15.115063 -414.304275) (xy 15.067457 -414.333329) (xy 15.016128 -414.355141) (xy 14.962171 -414.369247)
			(xy 14.906734 -414.375347) (xy 14.851 -414.37331) (xy 14.796157 -414.36318) (xy 14.743373 -414.345173)
			(xy 14.693773 -414.319672) (xy 14.648415 -414.287221) (xy 14.608266 -414.248512) (xy 14.57418 -414.204369)
			(xy 14.546884 -414.155734) (xy 14.526961 -414.103643) (xy 14.514835 -414.049206) (xy 14.510764 -413.993584)
			(xy 14.00429 -413.993584) (xy 14.003781 -414.02147) (xy 13.995661 -414.076646) (xy 13.979593 -414.130053)
			(xy 13.955921 -414.18055) (xy 13.925148 -414.227063) (xy 13.887931 -414.2686) (xy 13.845063 -414.304275)
			(xy 13.797457 -414.333329) (xy 13.746128 -414.355141) (xy 13.692171 -414.369247) (xy 13.636734 -414.375347)
			(xy 13.581 -414.37331) (xy 13.526157 -414.36318) (xy 13.473373 -414.345173) (xy 13.423773 -414.319672)
			(xy 13.378415 -414.287221) (xy 13.338266 -414.248512) (xy 13.30418 -414.204369) (xy 13.276884 -414.155734)
			(xy 13.256961 -414.103643) (xy 13.244835 -414.049206) (xy 13.240764 -413.993584) (xy 11.120628 -413.993584)
			(xy 11.120628 -414.755584) (xy 16.034764 -414.755584) (xy 16.038835 -414.699962) (xy 16.050961 -414.645525)
			(xy 16.070884 -414.593434) (xy 16.09818 -414.544799) (xy 16.132266 -414.500656) (xy 16.172415 -414.461947)
			(xy 16.217773 -414.429496) (xy 16.267373 -414.403995) (xy 16.320157 -414.385988) (xy 16.375 -414.375858)
			(xy 16.430734 -414.373821) (xy 16.486171 -414.379921) (xy 16.540128 -414.394027) (xy 16.591457 -414.415839)
			(xy 16.639063 -414.444893) (xy 16.681931 -414.480568) (xy 16.719148 -414.522105) (xy 16.749921 -414.568618)
			(xy 16.773593 -414.619115) (xy 16.789661 -414.672522) (xy 16.797781 -414.727698) (xy 16.79829 -414.755584)
			(xy 16.797781 -414.78347) (xy 16.789661 -414.838646) (xy 16.777583 -414.878792) (xy 31.194104 -414.878792)
			(xy 31.201855 -414.824833) (xy 31.217206 -414.772526) (xy 31.239845 -414.722937) (xy 31.269311 -414.677075)
			(xy 31.305004 -414.635872) (xy 31.346198 -414.600169) (xy 31.392053 -414.570691) (xy 31.441636 -414.54804)
			(xy 31.493939 -414.532675) (xy 31.547896 -414.52491) (xy 31.602408 -414.524904) (xy 31.656367 -414.532655)
			(xy 31.708674 -414.548006) (xy 31.758263 -414.570645) (xy 31.804125 -414.600111) (xy 31.845328 -414.635804)
			(xy 31.881031 -414.676998) (xy 31.910509 -414.722853) (xy 31.93316 -414.772436) (xy 31.948525 -414.824739)
			(xy 31.95629 -414.878696) (xy 31.956756 -414.905952) (xy 31.956134 -414.936594) (xy 31.946309 -414.997085)
			(xy 31.937198 -415.026348) (xy 31.933225 -415.039865) (xy 31.931982 -415.067997) (xy 31.938465 -415.0954)
			(xy 31.952182 -415.119992) (xy 31.972092 -415.139906) (xy 31.996682 -415.153628) (xy 32.024084 -415.160117)
			(xy 32.052217 -415.158878) (xy 32.065722 -415.154872) (xy 32.094984 -415.145761) (xy 32.155476 -415.135942)
			(xy 32.186118 -415.135314) (xy 32.213367 -415.135797) (xy 32.267311 -415.143556) (xy 32.319601 -415.158912)
			(xy 32.369174 -415.181553) (xy 32.41502 -415.211019) (xy 32.456207 -415.246709) (xy 32.491894 -415.287898)
			(xy 32.521357 -415.333746) (xy 32.543996 -415.38332) (xy 32.559349 -415.435611) (xy 32.567104 -415.489555)
			(xy 32.567103 -415.544054) (xy 32.559347 -415.597998) (xy 32.543993 -415.650289) (xy 32.521353 -415.699862)
			(xy 32.491889 -415.74571) (xy 32.4562 -415.786897) (xy 32.415013 -415.822586) (xy 32.369166 -415.852051)
			(xy 32.319593 -415.874691) (xy 32.267302 -415.890046) (xy 32.213358 -415.897803) (xy 32.158859 -415.897804)
			(xy 32.104915 -415.89005) (xy 32.052624 -415.874697) (xy 32.003049 -415.852059) (xy 31.957201 -415.822597)
			(xy 31.916012 -415.786909) (xy 31.880322 -415.745724) (xy 31.850855 -415.699878) (xy 31.828213 -415.650305)
			(xy 31.812857 -415.598015) (xy 31.805098 -415.544071) (xy 31.80461 -415.516822) (xy 31.805223 -415.48618)
			(xy 31.815054 -415.425688) (xy 31.824168 -415.396426) (xy 31.828086 -415.382898) (xy 31.82932 -415.354779)
			(xy 31.822836 -415.32739) (xy 31.809124 -415.30281) (xy 31.789226 -415.282903) (xy 31.764651 -415.269181)
			(xy 31.737265 -415.262684) (xy 31.709146 -415.263906) (xy 31.695644 -415.267902) (xy 31.666377 -415.276997)
			(xy 31.605889 -415.286826) (xy 31.575248 -415.28746) (xy 31.547992 -415.287096) (xy 31.494033 -415.279345)
			(xy 31.441726 -415.263994) (xy 31.392137 -415.241355) (xy 31.346275 -415.211889) (xy 31.305072 -415.176196)
			(xy 31.269369 -415.135002) (xy 31.239891 -415.089147) (xy 31.21724 -415.039564) (xy 31.201875 -414.987261)
			(xy 31.19411 -414.933304) (xy 31.194104 -414.878792) (xy 16.777583 -414.878792) (xy 16.773593 -414.892053)
			(xy 16.749921 -414.94255) (xy 16.719148 -414.989063) (xy 16.681931 -415.0306) (xy 16.639063 -415.066275)
			(xy 16.591457 -415.095329) (xy 16.540128 -415.117141) (xy 16.486171 -415.131247) (xy 16.430734 -415.137347)
			(xy 16.375 -415.13531) (xy 16.320157 -415.12518) (xy 16.267373 -415.107173) (xy 16.217773 -415.081672)
			(xy 16.172415 -415.049221) (xy 16.132266 -415.010512) (xy 16.09818 -414.966369) (xy 16.070884 -414.917734)
			(xy 16.050961 -414.865643) (xy 16.038835 -414.811206) (xy 16.034764 -414.755584) (xy 11.120628 -414.755584)
			(xy 11.120628 -415.351976) (xy 29.832806 -415.351976) (xy 29.836877 -415.296354) (xy 29.849003 -415.241917)
			(xy 29.868926 -415.189826) (xy 29.896222 -415.141191) (xy 29.930308 -415.097048) (xy 29.970457 -415.058339)
			(xy 30.015815 -415.025888) (xy 30.065415 -415.000387) (xy 30.118199 -414.98238) (xy 30.173042 -414.97225)
			(xy 30.228776 -414.970213) (xy 30.284213 -414.976313) (xy 30.33817 -414.990419) (xy 30.389499 -415.012231)
			(xy 30.437105 -415.041285) (xy 30.479973 -415.07696) (xy 30.51719 -415.118497) (xy 30.547963 -415.16501)
			(xy 30.571635 -415.215507) (xy 30.587703 -415.268914) (xy 30.595823 -415.32409) (xy 30.596332 -415.351976)
			(xy 30.595823 -415.379862) (xy 30.587703 -415.435038) (xy 30.571635 -415.488445) (xy 30.547963 -415.538942)
			(xy 30.51719 -415.585455) (xy 30.479973 -415.626992) (xy 30.437105 -415.662667) (xy 30.389499 -415.691721)
			(xy 30.33817 -415.713533) (xy 30.284213 -415.727639) (xy 30.228776 -415.733739) (xy 30.173042 -415.731702)
			(xy 30.118199 -415.721572) (xy 30.065415 -415.703565) (xy 30.015815 -415.678064) (xy 29.970457 -415.645613)
			(xy 29.930308 -415.606904) (xy 29.896222 -415.562761) (xy 29.868926 -415.514126) (xy 29.849003 -415.462035)
			(xy 29.836877 -415.407598) (xy 29.832806 -415.351976) (xy 11.120628 -415.351976) (xy 11.120628 -415.48431)
			(xy 11.121054 -415.494379) (xy 11.128774 -415.512978) (xy 11.135614 -415.520378) (xy 11.438707 -415.823471)
			(xy 18.86304 -415.823471) (xy 18.86304 -415.768969) (xy 18.870796 -415.715022) (xy 18.886151 -415.662728)
			(xy 18.908792 -415.613151) (xy 18.938257 -415.567301) (xy 18.973948 -415.526111) (xy 19.015138 -415.49042)
			(xy 19.060988 -415.460954) (xy 19.110564 -415.438312) (xy 19.162858 -415.422957) (xy 19.216805 -415.4152)
			(xy 19.244056 -415.414714) (xy 19.270419 -415.415193) (xy 19.32264 -415.422472) (xy 19.373363 -415.43687)
			(xy 19.42162 -415.458113) (xy 19.466494 -415.485797) (xy 19.50713 -415.519394) (xy 19.542755 -415.558265)
			(xy 19.572689 -415.60167) (xy 19.584924 -415.625026) (xy 19.591646 -415.637388) (xy 19.610658 -415.658118)
			(xy 19.634603 -415.672877) (xy 19.661665 -415.680548) (xy 19.689793 -415.680548) (xy 19.716855 -415.672877)
			(xy 19.7408 -415.658118) (xy 19.759812 -415.637388) (xy 19.766534 -415.625026) (xy 19.778775 -415.601643)
			(xy 19.808708 -415.558174) (xy 19.844346 -415.519244) (xy 19.885007 -415.485596) (xy 19.929918 -415.457872)
			(xy 19.97822 -415.4366) (xy 20.028993 -415.422188) (xy 20.081267 -415.414909) (xy 20.107656 -415.41446)
			(xy 20.134909 -415.414927) (xy 20.18886 -415.422684) (xy 20.241158 -415.438039) (xy 20.290738 -415.460681)
			(xy 20.336592 -415.490149) (xy 20.377785 -415.525842) (xy 20.413479 -415.567035) (xy 20.442947 -415.612888)
			(xy 20.465589 -415.662468) (xy 20.480946 -415.714766) (xy 20.488703 -415.768717) (xy 20.488703 -415.823223)
			(xy 20.480946 -415.877174) (xy 20.465589 -415.929472) (xy 20.442947 -415.979052) (xy 20.413479 -416.024905)
			(xy 20.377785 -416.066098) (xy 20.336592 -416.101791) (xy 20.290738 -416.131259) (xy 20.241158 -416.153901)
			(xy 20.18886 -416.169256) (xy 20.134909 -416.177013) (xy 20.107656 -416.177476) (xy 20.081293 -416.176993)
			(xy 20.029072 -416.169715) (xy 19.978349 -416.155318) (xy 19.930092 -416.134076) (xy 19.885218 -416.106393)
			(xy 19.844581 -416.072796) (xy 19.808957 -416.033925) (xy 19.779022 -415.99052) (xy 19.766788 -415.967164)
			(xy 19.760097 -415.954762) (xy 19.741114 -415.933951) (xy 19.717161 -415.919127) (xy 19.690067 -415.911421)
			(xy 19.661899 -415.911421) (xy 19.634805 -415.919127) (xy 19.610852 -415.933951) (xy 19.591869 -415.954762)
			(xy 19.585178 -415.967164) (xy 19.572923 -415.99054) (xy 19.542993 -416.034009) (xy 19.507357 -416.07294)
			(xy 19.466698 -416.106588) (xy 19.421789 -416.134314) (xy 19.373489 -416.155586) (xy 19.322718 -416.17)
			(xy 19.270445 -416.17728) (xy 19.244056 -416.17773) (xy 19.216805 -416.17724) (xy 19.162858 -416.169483)
			(xy 19.110564 -416.154128) (xy 19.060988 -416.131486) (xy 19.015138 -416.10202) (xy 18.973948 -416.066329)
			(xy 18.938257 -416.025139) (xy 18.908792 -415.979289) (xy 18.886151 -415.929712) (xy 18.870796 -415.877418)
			(xy 18.86304 -415.823471) (xy 11.438707 -415.823471) (xy 13.04671 -417.431474) (xy 14.048992 -417.431474)
			(xy 14.053063 -417.375852) (xy 14.065189 -417.321415) (xy 14.085112 -417.269324) (xy 14.112408 -417.220689)
			(xy 14.146494 -417.176546) (xy 14.186643 -417.137837) (xy 14.232001 -417.105386) (xy 14.281601 -417.079885)
			(xy 14.334385 -417.061878) (xy 14.389228 -417.051748) (xy 14.444962 -417.049711) (xy 14.500399 -417.055811)
			(xy 14.554356 -417.069917) (xy 14.605685 -417.091729) (xy 14.653291 -417.120783) (xy 14.696159 -417.156458)
			(xy 14.733376 -417.197995) (xy 14.764149 -417.244508) (xy 14.787821 -417.295005) (xy 14.803889 -417.348412)
			(xy 14.812009 -417.403588) (xy 14.812518 -417.431474) (xy 14.812009 -417.45936) (xy 14.809673 -417.475231)
			(xy 15.348442 -417.475231) (xy 15.348442 -417.420729) (xy 15.356198 -417.366782) (xy 15.371553 -417.314488)
			(xy 15.394194 -417.264912) (xy 15.42366 -417.219062) (xy 15.459351 -417.177872) (xy 15.50054 -417.142181)
			(xy 15.54639 -417.112715) (xy 15.595966 -417.090074) (xy 15.64826 -417.074719) (xy 15.702207 -417.066962)
			(xy 15.729458 -417.066476) (xy 15.756828 -417.066948) (xy 15.811008 -417.074762) (xy 15.863512 -417.090248)
			(xy 15.913259 -417.113089) (xy 15.959225 -417.142814) (xy 15.980156 -417.160456) (xy 15.987268 -417.166552)
			(xy 16.004286 -417.172902) (xy 16.08963 -417.172902) (xy 16.106648 -417.166552) (xy 16.11376 -417.160456)
			(xy 16.13469 -417.142815) (xy 16.180664 -417.113105) (xy 16.230412 -417.09027) (xy 16.282913 -417.074779)
			(xy 16.337089 -417.06695) (xy 16.364458 -417.066476) (xy 16.391711 -417.066931) (xy 16.445663 -417.074688)
			(xy 16.497962 -417.090044) (xy 16.547542 -417.112687) (xy 16.593396 -417.142155) (xy 16.63459 -417.177849)
			(xy 16.670284 -417.219042) (xy 16.699752 -417.264896) (xy 16.722395 -417.314477) (xy 16.737752 -417.366775)
			(xy 16.745509 -417.420727) (xy 16.745509 -417.475233) (xy 16.737752 -417.529185) (xy 16.722395 -417.581483)
			(xy 16.699752 -417.631064) (xy 16.670284 -417.676918) (xy 16.667492 -417.68014) (xy 19.28444 -417.68014)
			(xy 19.288511 -417.624518) (xy 19.300637 -417.570081) (xy 19.32056 -417.51799) (xy 19.347856 -417.469355)
			(xy 19.381942 -417.425212) (xy 19.422091 -417.386503) (xy 19.467449 -417.354052) (xy 19.517049 -417.328551)
			(xy 19.569833 -417.310544) (xy 19.624676 -417.300414) (xy 19.68041 -417.298377) (xy 19.735847 -417.304477)
			(xy 19.789804 -417.318583) (xy 19.841133 -417.340395) (xy 19.888739 -417.369449) (xy 19.931607 -417.405124)
			(xy 19.968824 -417.446661) (xy 19.999597 -417.493174) (xy 20.023269 -417.543671) (xy 20.039337 -417.597078)
			(xy 20.047457 -417.652254) (xy 20.047966 -417.68014) (xy 20.047457 -417.708026) (xy 20.039337 -417.763202)
			(xy 20.023269 -417.816609) (xy 19.999597 -417.867106) (xy 19.968824 -417.913619) (xy 19.931607 -417.955156)
			(xy 19.888739 -417.990831) (xy 19.841133 -418.019885) (xy 19.789804 -418.041697) (xy 19.735847 -418.055803)
			(xy 19.68041 -418.061903) (xy 19.624676 -418.059866) (xy 19.569833 -418.049736) (xy 19.517049 -418.031729)
			(xy 19.467449 -418.006228) (xy 19.422091 -417.973777) (xy 19.381942 -417.935068) (xy 19.347856 -417.890925)
			(xy 19.32056 -417.84229) (xy 19.300637 -417.790199) (xy 19.288511 -417.735762) (xy 19.28444 -417.68014)
			(xy 16.667492 -417.68014) (xy 16.63459 -417.718111) (xy 16.593396 -417.753805) (xy 16.547542 -417.783273)
			(xy 16.497962 -417.805916) (xy 16.445663 -417.821272) (xy 16.391711 -417.829029) (xy 16.364458 -417.829492)
			(xy 16.337089 -417.828994) (xy 16.282911 -417.821184) (xy 16.230408 -417.805703) (xy 16.180661 -417.782868)
			(xy 16.134693 -417.75315) (xy 16.11376 -417.735512) (xy 16.106648 -417.729416) (xy 16.08963 -417.723066)
			(xy 16.004286 -417.723066) (xy 15.987268 -417.729416) (xy 15.980156 -417.735512) (xy 15.959215 -417.75314)
			(xy 15.913245 -417.782853) (xy 15.863499 -417.805691) (xy 15.811001 -417.821185) (xy 15.756827 -417.829016)
			(xy 15.729458 -417.829492) (xy 15.702207 -417.828998) (xy 15.64826 -417.821241) (xy 15.595966 -417.805886)
			(xy 15.54639 -417.783245) (xy 15.50054 -417.753779) (xy 15.459351 -417.718088) (xy 15.42366 -417.676898)
			(xy 15.394194 -417.631048) (xy 15.371553 -417.581472) (xy 15.356198 -417.529178) (xy 15.348442 -417.475231)
			(xy 14.809673 -417.475231) (xy 14.803889 -417.514536) (xy 14.787821 -417.567943) (xy 14.764149 -417.61844)
			(xy 14.733376 -417.664953) (xy 14.696159 -417.70649) (xy 14.653291 -417.742165) (xy 14.605685 -417.771219)
			(xy 14.554356 -417.793031) (xy 14.500399 -417.807137) (xy 14.444962 -417.813237) (xy 14.389228 -417.8112)
			(xy 14.334385 -417.80107) (xy 14.281601 -417.783063) (xy 14.232001 -417.757562) (xy 14.186643 -417.725111)
			(xy 14.146494 -417.686402) (xy 14.112408 -417.642259) (xy 14.085112 -417.593624) (xy 14.065189 -417.541533)
			(xy 14.053063 -417.487096) (xy 14.048992 -417.431474) (xy 13.04671 -417.431474) (xy 13.854684 -418.239448)
			(xy 28.155644 -418.239448) (xy 28.159715 -418.183826) (xy 28.171841 -418.129389) (xy 28.191764 -418.077298)
			(xy 28.21906 -418.028663) (xy 28.253146 -417.98452) (xy 28.293295 -417.945811) (xy 28.338653 -417.91336)
			(xy 28.388253 -417.887859) (xy 28.441037 -417.869852) (xy 28.49588 -417.859722) (xy 28.551614 -417.857685)
			(xy 28.607051 -417.863785) (xy 28.661008 -417.877891) (xy 28.712337 -417.899703) (xy 28.759943 -417.928757)
			(xy 28.802811 -417.964432) (xy 28.840028 -418.005969) (xy 28.870801 -418.052482) (xy 28.894473 -418.102979)
			(xy 28.910541 -418.156386) (xy 28.918661 -418.211562) (xy 28.91917 -418.239448) (xy 28.918661 -418.267334)
			(xy 28.910541 -418.32251) (xy 28.894473 -418.375917) (xy 28.870801 -418.426414) (xy 28.840028 -418.472927)
			(xy 28.802811 -418.514464) (xy 28.759943 -418.550139) (xy 28.712337 -418.579193) (xy 28.661008 -418.601005)
			(xy 28.607051 -418.615111) (xy 28.551614 -418.621211) (xy 28.49588 -418.619174) (xy 28.441037 -418.609044)
			(xy 28.388253 -418.591037) (xy 28.338653 -418.565536) (xy 28.293295 -418.533085) (xy 28.253146 -418.494376)
			(xy 28.21906 -418.450233) (xy 28.191764 -418.401598) (xy 28.171841 -418.349507) (xy 28.159715 -418.29507)
			(xy 28.155644 -418.239448) (xy 13.854684 -418.239448) (xy 14.44752 -418.832284) (xy 14.454919 -418.839129)
			(xy 14.473517 -418.846859) (xy 14.483588 -418.84727)
		)
		(stroke
			(width 0)
			(type solid)
		)
		(fill yes)
		(layer "In11.Cu")
		(net "GND")
	)
	(gr_poly
		(pts
			(xy 419.828218 -407.39568) (xy 419.838286 -407.395253) (xy 419.856884 -407.387532) (xy 419.864286 -407.380694)
			(xy 420.738554 -406.506426) (xy 420.745394 -406.499026) (xy 420.753109 -406.480427) (xy 420.75354 -406.470358)
			(xy 420.75354 -398.699482) (xy 420.750746 -398.688052) (xy 420.747952 -398.682464) (xy 420.73718 -398.660632)
			(xy 420.721924 -398.614403) (xy 420.714174 -398.566342) (xy 420.713662 -398.542002) (xy 420.714132 -398.517658)
			(xy 420.721868 -398.469589) (xy 420.737157 -398.423365) (xy 420.747952 -398.40154) (xy 420.750746 -398.395952)
			(xy 420.75354 -398.384522) (xy 420.75354 -398.265142) (xy 420.753022 -398.254626) (xy 420.74464 -398.235335)
			(xy 420.737284 -398.227804) (xy 420.674546 -398.169892) (xy 420.654734 -398.163034) (xy 420.643812 -398.16405)
			(xy 420.61892 -398.164812) (xy 420.593525 -398.164306) (xy 420.543391 -398.156178) (xy 420.495204 -398.140129)
			(xy 420.450208 -398.116572) (xy 420.409563 -398.086116) (xy 420.374319 -398.049546) (xy 420.345383 -398.007805)
			(xy 420.323504 -397.96197) (xy 420.315898 -397.937736) (xy 420.314374 -397.931894) (xy 419.993826 -397.377412)
			(xy 419.989762 -397.373094) (xy 419.973683 -397.355416) (xy 419.946496 -397.316118) (xy 419.925538 -397.273173)
			(xy 419.911288 -397.227562) (xy 419.90407 -397.180325) (xy 419.903656 -397.156432) (xy 419.903742 -397.144384)
			(xy 419.905525 -397.120355) (xy 419.907212 -397.108426) (xy 419.908482 -397.099536) (xy 419.905434 -397.082518)
			(xy 419.86327 -397.011652) (xy 419.850062 -397.000476) (xy 419.84168 -396.997428) (xy 419.81994 -396.989022)
			(xy 419.779095 -396.96657) (xy 419.742138 -396.93817) (xy 419.709925 -396.904484) (xy 419.683206 -396.866293)
			(xy 419.662602 -396.824486) (xy 419.648591 -396.780033) (xy 419.641498 -396.733966) (xy 419.64102 -396.710662)
			(xy 419.64152 -396.685264) (xy 419.64992 -396.635168) (xy 419.666499 -396.587154) (xy 419.690798 -396.542548)
			(xy 419.722147 -396.50258) (xy 419.740588 -396.48511) (xy 419.74897 -396.47749) (xy 419.757606 -396.457424)
			(xy 419.754812 -396.35811) (xy 419.745414 -396.338552) (xy 419.736524 -396.33144) (xy 419.717962 -396.315638)
			(xy 419.685233 -396.279513) (xy 419.658158 -396.238976) (xy 419.637323 -396.194906) (xy 419.62318 -396.148256)
			(xy 419.616034 -396.100035) (xy 419.61562 -396.075662) (xy 419.616059 -396.051546) (xy 419.623065 -396.003826)
			(xy 419.636923 -395.957628) (xy 419.65734 -395.913931) (xy 419.67023 -395.893544) (xy 419.676072 -395.884654)
			(xy 419.679628 -395.864588) (xy 419.658546 -395.772386) (xy 419.646354 -395.755622) (xy 419.637464 -395.750288)
			(xy 419.616661 -395.737433) (xy 419.578743 -395.706555) (xy 419.545791 -395.670425) (xy 419.518526 -395.629831)
			(xy 419.497544 -395.585662) (xy 419.483302 -395.538881) (xy 419.476113 -395.490512) (xy 419.475666 -395.466062)
			(xy 419.476227 -395.438779) (xy 419.485187 -395.384954) (xy 419.502858 -395.333329) (xy 419.528761 -395.285303)
			(xy 419.562193 -395.242179) (xy 419.581838 -395.223238) (xy 419.589282 -395.215744) (xy 419.597818 -395.196449)
			(xy 419.598348 -395.1859) (xy 419.598348 -395.111224) (xy 419.59776 -395.10069) (xy 419.589226 -395.081419)
			(xy 419.581838 -395.073886) (xy 419.562183 -395.054953) (xy 419.528741 -395.011832) (xy 419.502833 -394.963805)
			(xy 419.485162 -394.912176) (xy 419.476208 -394.858347) (xy 419.475666 -394.831062) (xy 419.47592 -394.81887)
			(xy 419.476174 -394.809218) (xy 419.470078 -394.791184) (xy 419.411404 -394.723874) (xy 419.39464 -394.715238)
			(xy 419.384734 -394.714222) (xy 419.357822 -394.710869) (xy 419.305525 -394.696521) (xy 419.256272 -394.673831)
			(xy 419.211381 -394.643407) (xy 419.172058 -394.606064) (xy 419.139356 -394.562804) (xy 419.114153 -394.514788)
			(xy 419.097124 -394.463302) (xy 419.09238 -394.4366) (xy 419.090856 -394.427202) (xy 418.81806 -393.95527)
			(xy 418.810694 -393.949428) (xy 418.791918 -393.933623) (xy 418.758788 -393.897415) (xy 418.731372 -393.85671)
			(xy 418.71027 -393.812401) (xy 418.695945 -393.76546) (xy 418.688712 -393.716919) (xy 418.688266 -393.69238)
			(xy 418.688777 -393.666393) (xy 418.69691 -393.61506) (xy 418.712972 -393.56563) (xy 418.736569 -393.519321)
			(xy 418.767118 -393.477274) (xy 418.803869 -393.440522) (xy 418.845916 -393.409972) (xy 418.892224 -393.386375)
			(xy 418.941654 -393.370311) (xy 418.992987 -393.362177) (xy 419.018974 -393.361672) (xy 419.044986 -393.362155)
			(xy 419.096369 -393.370298) (xy 419.145842 -393.386388) (xy 419.192185 -393.410027) (xy 419.234254 -393.440633)
			(xy 419.271012 -393.477449) (xy 419.301549 -393.519567) (xy 419.325114 -393.565948) (xy 419.341125 -393.615447)
			(xy 419.345618 -393.641072) (xy 419.347142 -393.65047) (xy 419.619938 -394.122402) (xy 419.627304 -394.128244)
			(xy 419.646082 -394.144048) (xy 419.679214 -394.180256) (xy 419.706635 -394.22096) (xy 419.727741 -394.265269)
			(xy 419.742069 -394.31221) (xy 419.749306 -394.360752) (xy 419.749732 -394.385292) (xy 419.749478 -394.397484)
			(xy 419.749224 -394.407136) (xy 419.75532 -394.42517) (xy 419.813994 -394.49248) (xy 419.830758 -394.501116)
			(xy 419.840664 -394.502132) (xy 419.867434 -394.505456) (xy 419.919467 -394.519675) (xy 419.968503 -394.54215)
			(xy 420.013242 -394.572284) (xy 420.052498 -394.609278) (xy 420.085231 -394.652151) (xy 420.110573 -394.699768)
			(xy 420.127853 -394.750867) (xy 420.136612 -394.804092) (xy 420.137082 -394.831062) (xy 420.136519 -394.858344)
			(xy 420.127554 -394.912165) (xy 420.109879 -394.963786) (xy 420.083971 -395.011807) (xy 420.050534 -395.054924)
			(xy 420.03091 -395.073886) (xy 420.023464 -395.081379) (xy 420.014929 -395.100674) (xy 420.0144 -395.111224)
			(xy 420.0144 -395.1859) (xy 420.014991 -395.196433) (xy 420.023525 -395.215703) (xy 420.03091 -395.223238)
			(xy 420.050566 -395.24217) (xy 420.08401 -395.28529) (xy 420.109919 -395.333317) (xy 420.127589 -395.384946)
			(xy 420.136541 -395.438777) (xy 420.137082 -395.466062) (xy 420.136649 -395.490179) (xy 420.129653 -395.537904)
			(xy 420.115804 -395.584108) (xy 420.095394 -395.627813) (xy 420.082472 -395.64818) (xy 420.07663 -395.65707)
			(xy 420.073074 -395.677136) (xy 420.094156 -395.769338) (xy 420.106348 -395.786102) (xy 420.115238 -395.791436)
			(xy 420.136039 -395.804292) (xy 420.173955 -395.83517) (xy 420.206904 -395.871301) (xy 420.234166 -395.911895)
			(xy 420.255146 -395.956065) (xy 420.269384 -396.002845) (xy 420.276569 -396.051212) (xy 420.277036 -396.075662)
			(xy 420.276598 -396.100033) (xy 420.269442 -396.148245) (xy 420.255294 -396.194888) (xy 420.234459 -396.238952)
			(xy 420.207388 -396.279484) (xy 420.174666 -396.315609) (xy 420.156132 -396.33144) (xy 420.147242 -396.338552)
			(xy 420.137844 -396.35811) (xy 420.13505 -396.457424) (xy 420.143686 -396.47749) (xy 420.152068 -396.48511)
			(xy 420.170486 -396.5026) (xy 420.201821 -396.54257) (xy 420.226113 -396.587173) (xy 420.242691 -396.63518)
			(xy 420.251099 -396.685268) (xy 420.251636 -396.710662) (xy 420.251564 -396.72002) (xy 420.250418 -396.738702)
			(xy 420.24935 -396.748) (xy 420.248334 -396.75689) (xy 420.252144 -396.773654) (xy 420.296086 -396.843504)
			(xy 420.309802 -396.853918) (xy 420.318184 -396.856712) (xy 420.34228 -396.865194) (xy 420.387569 -396.888824)
			(xy 420.428463 -396.919435) (xy 420.463895 -396.956231) (xy 420.492942 -396.998251) (xy 420.514846 -397.044399)
			(xy 420.5224 -397.068802) (xy 420.523924 -397.074644) (xy 420.658798 -397.307816) (xy 420.66486 -397.317179)
			(xy 420.683112 -397.329954) (xy 420.705053 -397.333819) (xy 420.715948 -397.331438) (xy 420.732712 -397.32712)
			(xy 420.75354 -397.299942) (xy 420.75354 -395.697202) (xy 420.753224 -395.68892) (xy 420.747916 -395.673231)
			(xy 420.743126 -395.666468) (xy 420.727245 -395.644721) (xy 420.702011 -395.597154) (xy 420.684811 -395.546129)
			(xy 420.676098 -395.492993) (xy 420.676103 -395.439147) (xy 420.684825 -395.386012) (xy 420.702035 -395.33499)
			(xy 420.727278 -395.287428) (xy 420.743126 -395.265656) (xy 420.747876 -395.258872) (xy 420.753185 -395.243196)
			(xy 420.75354 -395.234922) (xy 420.75354 -395.062202) (xy 420.753224 -395.05392) (xy 420.747916 -395.038231)
			(xy 420.743126 -395.031468) (xy 420.727245 -395.00972) (xy 420.70201 -394.962151) (xy 420.684809 -394.911125)
			(xy 420.676097 -394.857986) (xy 420.675562 -394.831062) (xy 420.675816 -394.81887) (xy 420.67607 -394.809218)
			(xy 420.669974 -394.791184) (xy 420.6113 -394.723874) (xy 420.594536 -394.715238) (xy 420.58463 -394.714222)
			(xy 420.557718 -394.710869) (xy 420.505422 -394.696521) (xy 420.456169 -394.67383) (xy 420.411279 -394.643405)
			(xy 420.371956 -394.606063) (xy 420.339255 -394.562803) (xy 420.314052 -394.514787) (xy 420.297023 -394.463301)
			(xy 420.292276 -394.4366) (xy 420.290752 -394.427202) (xy 420.017702 -393.954762) (xy 420.01059 -393.94892)
			(xy 419.991856 -393.933141) (xy 419.9588 -393.896998) (xy 419.931439 -393.856373) (xy 419.910374 -393.812154)
			(xy 419.896064 -393.765311) (xy 419.888825 -393.71687) (xy 419.888416 -393.69238) (xy 419.888901 -393.666392)
			(xy 419.897035 -393.615058) (xy 419.913099 -393.565627) (xy 419.936698 -393.519319) (xy 419.967251 -393.477272)
			(xy 420.004005 -393.440522) (xy 420.046056 -393.409975) (xy 420.092368 -393.386382) (xy 420.141801 -393.370324)
			(xy 420.193136 -393.362197) (xy 420.219124 -393.361672) (xy 420.245171 -393.362154) (xy 420.296622 -393.370308)
			(xy 420.346159 -393.386428) (xy 420.392556 -393.410115) (xy 420.434666 -393.440782) (xy 420.471448 -393.477671)
			(xy 420.501991 -393.519871) (xy 420.525542 -393.566337) (xy 420.541517 -393.615921) (xy 420.546022 -393.64158)
			(xy 420.547292 -393.650978) (xy 420.658798 -393.843764) (xy 420.664865 -393.853119) (xy 420.683117 -393.865882)
			(xy 420.705051 -393.869743) (xy 420.715948 -393.867386) (xy 420.732712 -393.863068) (xy 420.75354 -393.83589)
			(xy 420.75354 -392.786362) (xy 420.753108 -392.776296) (xy 420.745378 -392.757707) (xy 420.738554 -392.750294)
			(xy 420.105586 -392.117326) (xy 420.098188 -392.110479) (xy 420.07959 -392.102746) (xy 420.069518 -392.10234)
			(xy 402.369782 -392.10234) (xy 402.359714 -392.102768) (xy 402.341118 -392.110491) (xy 402.333714 -392.117326)
			(xy 401.425331 -393.025709) (xy 402.759928 -393.025709) (xy 402.759928 -392.973735) (xy 402.768058 -392.9224)
			(xy 402.784119 -392.87297) (xy 402.807715 -392.82666) (xy 402.838265 -392.784612) (xy 402.875016 -392.747861)
			(xy 402.917064 -392.717311) (xy 402.963374 -392.693715) (xy 403.012804 -392.677654) (xy 403.064139 -392.669524)
			(xy 403.116113 -392.669524) (xy 403.167448 -392.677654) (xy 403.216878 -392.693715) (xy 403.263188 -392.717311)
			(xy 403.305236 -392.747861) (xy 403.341987 -392.784612) (xy 403.372537 -392.82666) (xy 403.396133 -392.87297)
			(xy 403.412194 -392.9224) (xy 403.420324 -392.973735) (xy 403.420834 -392.999722) (xy 403.420324 -393.025709)
			(xy 403.959824 -393.025709) (xy 403.959824 -392.973735) (xy 403.967954 -392.9224) (xy 403.984015 -392.87297)
			(xy 404.007611 -392.82666) (xy 404.038161 -392.784612) (xy 404.074912 -392.747861) (xy 404.11696 -392.717311)
			(xy 404.16327 -392.693715) (xy 404.2127 -392.677654) (xy 404.264035 -392.669524) (xy 404.316009 -392.669524)
			(xy 404.367344 -392.677654) (xy 404.416774 -392.693715) (xy 404.463084 -392.717311) (xy 404.505132 -392.747861)
			(xy 404.541883 -392.784612) (xy 404.572433 -392.82666) (xy 404.596029 -392.87297) (xy 404.61209 -392.9224)
			(xy 404.62022 -392.973735) (xy 404.62073 -392.999722) (xy 404.62022 -393.025709) (xy 405.159974 -393.025709)
			(xy 405.159974 -392.973735) (xy 405.168104 -392.9224) (xy 405.184165 -392.87297) (xy 405.207761 -392.82666)
			(xy 405.238311 -392.784612) (xy 405.275062 -392.747861) (xy 405.31711 -392.717311) (xy 405.36342 -392.693715)
			(xy 405.41285 -392.677654) (xy 405.464185 -392.669524) (xy 405.516159 -392.669524) (xy 405.567494 -392.677654)
			(xy 405.616924 -392.693715) (xy 405.663234 -392.717311) (xy 405.705282 -392.747861) (xy 405.742033 -392.784612)
			(xy 405.772583 -392.82666) (xy 405.796179 -392.87297) (xy 405.81224 -392.9224) (xy 405.82037 -392.973735)
			(xy 405.82088 -392.999722) (xy 405.82037 -393.025709) (xy 406.35987 -393.025709) (xy 406.35987 -392.973735)
			(xy 406.368 -392.9224) (xy 406.384061 -392.87297) (xy 406.407657 -392.82666) (xy 406.438207 -392.784612)
			(xy 406.474958 -392.747861) (xy 406.517006 -392.717311) (xy 406.563316 -392.693715) (xy 406.612746 -392.677654)
			(xy 406.664081 -392.669524) (xy 406.716055 -392.669524) (xy 406.76739 -392.677654) (xy 406.81682 -392.693715)
			(xy 406.86313 -392.717311) (xy 406.905178 -392.747861) (xy 406.941929 -392.784612) (xy 406.972479 -392.82666)
			(xy 406.996075 -392.87297) (xy 407.012136 -392.9224) (xy 407.020266 -392.973735) (xy 407.020776 -392.999722)
			(xy 407.020266 -393.025709) (xy 407.56002 -393.025709) (xy 407.56002 -392.973735) (xy 407.56815 -392.9224)
			(xy 407.584211 -392.87297) (xy 407.607807 -392.82666) (xy 407.638357 -392.784612) (xy 407.675108 -392.747861)
			(xy 407.717156 -392.717311) (xy 407.763466 -392.693715) (xy 407.812896 -392.677654) (xy 407.864231 -392.669524)
			(xy 407.916205 -392.669524) (xy 407.96754 -392.677654) (xy 408.01697 -392.693715) (xy 408.06328 -392.717311)
			(xy 408.105328 -392.747861) (xy 408.142079 -392.784612) (xy 408.172629 -392.82666) (xy 408.196225 -392.87297)
			(xy 408.212286 -392.9224) (xy 408.220416 -392.973735) (xy 408.220926 -392.999722) (xy 408.220416 -393.025709)
			(xy 408.759916 -393.025709) (xy 408.759916 -392.973735) (xy 408.768046 -392.9224) (xy 408.784107 -392.87297)
			(xy 408.807703 -392.82666) (xy 408.838253 -392.784612) (xy 408.875004 -392.747861) (xy 408.917052 -392.717311)
			(xy 408.963362 -392.693715) (xy 409.012792 -392.677654) (xy 409.064127 -392.669524) (xy 409.116101 -392.669524)
			(xy 409.167436 -392.677654) (xy 409.216866 -392.693715) (xy 409.263176 -392.717311) (xy 409.305224 -392.747861)
			(xy 409.341975 -392.784612) (xy 409.372525 -392.82666) (xy 409.396121 -392.87297) (xy 409.412182 -392.9224)
			(xy 409.420312 -392.973735) (xy 409.420822 -392.999722) (xy 409.420312 -393.025709) (xy 409.959812 -393.025709)
			(xy 409.959812 -392.973735) (xy 409.967942 -392.9224) (xy 409.984003 -392.87297) (xy 410.007599 -392.82666)
			(xy 410.038149 -392.784612) (xy 410.0749 -392.747861) (xy 410.116948 -392.717311) (xy 410.163258 -392.693715)
			(xy 410.212688 -392.677654) (xy 410.264023 -392.669524) (xy 410.315997 -392.669524) (xy 410.367332 -392.677654)
			(xy 410.416762 -392.693715) (xy 410.463072 -392.717311) (xy 410.50512 -392.747861) (xy 410.541871 -392.784612)
			(xy 410.572421 -392.82666) (xy 410.596017 -392.87297) (xy 410.612078 -392.9224) (xy 410.620208 -392.973735)
			(xy 410.620718 -392.999722) (xy 410.620208 -393.025709) (xy 411.159962 -393.025709) (xy 411.159962 -392.973735)
			(xy 411.168092 -392.9224) (xy 411.184153 -392.87297) (xy 411.207749 -392.82666) (xy 411.238299 -392.784612)
			(xy 411.27505 -392.747861) (xy 411.317098 -392.717311) (xy 411.363408 -392.693715) (xy 411.412838 -392.677654)
			(xy 411.464173 -392.669524) (xy 411.516147 -392.669524) (xy 411.567482 -392.677654) (xy 411.616912 -392.693715)
			(xy 411.663222 -392.717311) (xy 411.70527 -392.747861) (xy 411.742021 -392.784612) (xy 411.772571 -392.82666)
			(xy 411.796167 -392.87297) (xy 411.812228 -392.9224) (xy 411.820358 -392.973735) (xy 411.820868 -392.999722)
			(xy 411.820358 -393.025709) (xy 412.359858 -393.025709) (xy 412.359858 -392.973735) (xy 412.367988 -392.9224)
			(xy 412.384049 -392.87297) (xy 412.407645 -392.82666) (xy 412.438195 -392.784612) (xy 412.474946 -392.747861)
			(xy 412.516994 -392.717311) (xy 412.563304 -392.693715) (xy 412.612734 -392.677654) (xy 412.664069 -392.669524)
			(xy 412.716043 -392.669524) (xy 412.767378 -392.677654) (xy 412.816808 -392.693715) (xy 412.863118 -392.717311)
			(xy 412.905166 -392.747861) (xy 412.941917 -392.784612) (xy 412.972467 -392.82666) (xy 412.996063 -392.87297)
			(xy 413.012124 -392.9224) (xy 413.020254 -392.973735) (xy 413.020764 -392.999722) (xy 413.020254 -393.025709)
			(xy 413.560008 -393.025709) (xy 413.560008 -392.973735) (xy 413.568138 -392.9224) (xy 413.584199 -392.87297)
			(xy 413.607795 -392.82666) (xy 413.638345 -392.784612) (xy 413.675096 -392.747861) (xy 413.717144 -392.717311)
			(xy 413.763454 -392.693715) (xy 413.812884 -392.677654) (xy 413.864219 -392.669524) (xy 413.916193 -392.669524)
			(xy 413.967528 -392.677654) (xy 414.016958 -392.693715) (xy 414.063268 -392.717311) (xy 414.105316 -392.747861)
			(xy 414.142067 -392.784612) (xy 414.172617 -392.82666) (xy 414.196213 -392.87297) (xy 414.212274 -392.9224)
			(xy 414.220404 -392.973735) (xy 414.220914 -392.999722) (xy 414.220404 -393.025709) (xy 414.759904 -393.025709)
			(xy 414.759904 -392.973735) (xy 414.768034 -392.9224) (xy 414.784095 -392.87297) (xy 414.807691 -392.82666)
			(xy 414.838241 -392.784612) (xy 414.874992 -392.747861) (xy 414.91704 -392.717311) (xy 414.96335 -392.693715)
			(xy 415.01278 -392.677654) (xy 415.064115 -392.669524) (xy 415.116089 -392.669524) (xy 415.167424 -392.677654)
			(xy 415.216854 -392.693715) (xy 415.263164 -392.717311) (xy 415.305212 -392.747861) (xy 415.341963 -392.784612)
			(xy 415.372513 -392.82666) (xy 415.396109 -392.87297) (xy 415.41217 -392.9224) (xy 415.4203 -392.973735)
			(xy 415.42081 -392.999722) (xy 415.4203 -393.025709) (xy 415.9598 -393.025709) (xy 415.9598 -392.973735)
			(xy 415.96793 -392.9224) (xy 415.983991 -392.87297) (xy 416.007587 -392.82666) (xy 416.038137 -392.784612)
			(xy 416.074888 -392.747861) (xy 416.116936 -392.717311) (xy 416.163246 -392.693715) (xy 416.212676 -392.677654)
			(xy 416.264011 -392.669524) (xy 416.315985 -392.669524) (xy 416.36732 -392.677654) (xy 416.41675 -392.693715)
			(xy 416.46306 -392.717311) (xy 416.505108 -392.747861) (xy 416.541859 -392.784612) (xy 416.572409 -392.82666)
			(xy 416.596005 -392.87297) (xy 416.612066 -392.9224) (xy 416.620196 -392.973735) (xy 416.620706 -392.999722)
			(xy 416.620196 -393.025709) (xy 417.15995 -393.025709) (xy 417.15995 -392.973735) (xy 417.16808 -392.9224)
			(xy 417.184141 -392.87297) (xy 417.207737 -392.82666) (xy 417.238287 -392.784612) (xy 417.275038 -392.747861)
			(xy 417.317086 -392.717311) (xy 417.363396 -392.693715) (xy 417.412826 -392.677654) (xy 417.464161 -392.669524)
			(xy 417.516135 -392.669524) (xy 417.56747 -392.677654) (xy 417.6169 -392.693715) (xy 417.66321 -392.717311)
			(xy 417.705258 -392.747861) (xy 417.742009 -392.784612) (xy 417.772559 -392.82666) (xy 417.796155 -392.87297)
			(xy 417.812216 -392.9224) (xy 417.820346 -392.973735) (xy 417.820856 -392.999722) (xy 417.820346 -393.025709)
			(xy 418.359846 -393.025709) (xy 418.359846 -392.973735) (xy 418.367976 -392.9224) (xy 418.384037 -392.87297)
			(xy 418.407633 -392.82666) (xy 418.438183 -392.784612) (xy 418.474934 -392.747861) (xy 418.516982 -392.717311)
			(xy 418.563292 -392.693715) (xy 418.612722 -392.677654) (xy 418.664057 -392.669524) (xy 418.716031 -392.669524)
			(xy 418.767366 -392.677654) (xy 418.816796 -392.693715) (xy 418.863106 -392.717311) (xy 418.905154 -392.747861)
			(xy 418.941905 -392.784612) (xy 418.972455 -392.82666) (xy 418.996051 -392.87297) (xy 419.012112 -392.9224)
			(xy 419.020242 -392.973735) (xy 419.020752 -392.999722) (xy 419.020242 -393.025709) (xy 419.559996 -393.025709)
			(xy 419.559996 -392.973735) (xy 419.568126 -392.9224) (xy 419.584187 -392.87297) (xy 419.607783 -392.82666)
			(xy 419.638333 -392.784612) (xy 419.675084 -392.747861) (xy 419.717132 -392.717311) (xy 419.763442 -392.693715)
			(xy 419.812872 -392.677654) (xy 419.864207 -392.669524) (xy 419.916181 -392.669524) (xy 419.967516 -392.677654)
			(xy 420.016946 -392.693715) (xy 420.063256 -392.717311) (xy 420.105304 -392.747861) (xy 420.142055 -392.784612)
			(xy 420.172605 -392.82666) (xy 420.196201 -392.87297) (xy 420.212262 -392.9224) (xy 420.220392 -392.973735)
			(xy 420.220902 -392.999722) (xy 420.220392 -393.025709) (xy 420.212262 -393.077044) (xy 420.196201 -393.126474)
			(xy 420.172605 -393.172784) (xy 420.142055 -393.214832) (xy 420.105304 -393.251583) (xy 420.063256 -393.282133)
			(xy 420.016946 -393.305729) (xy 419.967516 -393.32179) (xy 419.916181 -393.32992) (xy 419.864207 -393.32992)
			(xy 419.812872 -393.32179) (xy 419.763442 -393.305729) (xy 419.717132 -393.282133) (xy 419.675084 -393.251583)
			(xy 419.638333 -393.214832) (xy 419.607783 -393.172784) (xy 419.584187 -393.126474) (xy 419.568126 -393.077044)
			(xy 419.559996 -393.025709) (xy 419.020242 -393.025709) (xy 419.012112 -393.077044) (xy 418.996051 -393.126474)
			(xy 418.972455 -393.172784) (xy 418.941905 -393.214832) (xy 418.905154 -393.251583) (xy 418.863106 -393.282133)
			(xy 418.816796 -393.305729) (xy 418.767366 -393.32179) (xy 418.716031 -393.32992) (xy 418.664057 -393.32992)
			(xy 418.612722 -393.32179) (xy 418.563292 -393.305729) (xy 418.516982 -393.282133) (xy 418.474934 -393.251583)
			(xy 418.438183 -393.214832) (xy 418.407633 -393.172784) (xy 418.384037 -393.126474) (xy 418.367976 -393.077044)
			(xy 418.359846 -393.025709) (xy 417.820346 -393.025709) (xy 417.812216 -393.077044) (xy 417.796155 -393.126474)
			(xy 417.772559 -393.172784) (xy 417.742009 -393.214832) (xy 417.705258 -393.251583) (xy 417.66321 -393.282133)
			(xy 417.6169 -393.305729) (xy 417.56747 -393.32179) (xy 417.516135 -393.32992) (xy 417.464161 -393.32992)
			(xy 417.412826 -393.32179) (xy 417.363396 -393.305729) (xy 417.317086 -393.282133) (xy 417.275038 -393.251583)
			(xy 417.238287 -393.214832) (xy 417.207737 -393.172784) (xy 417.184141 -393.126474) (xy 417.16808 -393.077044)
			(xy 417.15995 -393.025709) (xy 416.620196 -393.025709) (xy 416.612066 -393.077044) (xy 416.596005 -393.126474)
			(xy 416.572409 -393.172784) (xy 416.541859 -393.214832) (xy 416.505108 -393.251583) (xy 416.46306 -393.282133)
			(xy 416.41675 -393.305729) (xy 416.36732 -393.32179) (xy 416.315985 -393.32992) (xy 416.264011 -393.32992)
			(xy 416.212676 -393.32179) (xy 416.163246 -393.305729) (xy 416.116936 -393.282133) (xy 416.074888 -393.251583)
			(xy 416.038137 -393.214832) (xy 416.007587 -393.172784) (xy 415.983991 -393.126474) (xy 415.96793 -393.077044)
			(xy 415.9598 -393.025709) (xy 415.4203 -393.025709) (xy 415.41217 -393.077044) (xy 415.396109 -393.126474)
			(xy 415.372513 -393.172784) (xy 415.341963 -393.214832) (xy 415.305212 -393.251583) (xy 415.263164 -393.282133)
			(xy 415.216854 -393.305729) (xy 415.167424 -393.32179) (xy 415.116089 -393.32992) (xy 415.064115 -393.32992)
			(xy 415.01278 -393.32179) (xy 414.96335 -393.305729) (xy 414.91704 -393.282133) (xy 414.874992 -393.251583)
			(xy 414.838241 -393.214832) (xy 414.807691 -393.172784) (xy 414.784095 -393.126474) (xy 414.768034 -393.077044)
			(xy 414.759904 -393.025709) (xy 414.220404 -393.025709) (xy 414.212274 -393.077044) (xy 414.196213 -393.126474)
			(xy 414.172617 -393.172784) (xy 414.142067 -393.214832) (xy 414.105316 -393.251583) (xy 414.063268 -393.282133)
			(xy 414.016958 -393.305729) (xy 413.967528 -393.32179) (xy 413.916193 -393.32992) (xy 413.864219 -393.32992)
			(xy 413.812884 -393.32179) (xy 413.763454 -393.305729) (xy 413.717144 -393.282133) (xy 413.675096 -393.251583)
			(xy 413.638345 -393.214832) (xy 413.607795 -393.172784) (xy 413.584199 -393.126474) (xy 413.568138 -393.077044)
			(xy 413.560008 -393.025709) (xy 413.020254 -393.025709) (xy 413.012124 -393.077044) (xy 412.996063 -393.126474)
			(xy 412.972467 -393.172784) (xy 412.941917 -393.214832) (xy 412.905166 -393.251583) (xy 412.863118 -393.282133)
			(xy 412.816808 -393.305729) (xy 412.767378 -393.32179) (xy 412.716043 -393.32992) (xy 412.664069 -393.32992)
			(xy 412.612734 -393.32179) (xy 412.563304 -393.305729) (xy 412.516994 -393.282133) (xy 412.474946 -393.251583)
			(xy 412.438195 -393.214832) (xy 412.407645 -393.172784) (xy 412.384049 -393.126474) (xy 412.367988 -393.077044)
			(xy 412.359858 -393.025709) (xy 411.820358 -393.025709) (xy 411.812228 -393.077044) (xy 411.796167 -393.126474)
			(xy 411.772571 -393.172784) (xy 411.742021 -393.214832) (xy 411.70527 -393.251583) (xy 411.663222 -393.282133)
			(xy 411.616912 -393.305729) (xy 411.567482 -393.32179) (xy 411.516147 -393.32992) (xy 411.464173 -393.32992)
			(xy 411.412838 -393.32179) (xy 411.363408 -393.305729) (xy 411.317098 -393.282133) (xy 411.27505 -393.251583)
			(xy 411.238299 -393.214832) (xy 411.207749 -393.172784) (xy 411.184153 -393.126474) (xy 411.168092 -393.077044)
			(xy 411.159962 -393.025709) (xy 410.620208 -393.025709) (xy 410.612078 -393.077044) (xy 410.596017 -393.126474)
			(xy 410.572421 -393.172784) (xy 410.541871 -393.214832) (xy 410.50512 -393.251583) (xy 410.463072 -393.282133)
			(xy 410.416762 -393.305729) (xy 410.367332 -393.32179) (xy 410.315997 -393.32992) (xy 410.264023 -393.32992)
			(xy 410.212688 -393.32179) (xy 410.163258 -393.305729) (xy 410.116948 -393.282133) (xy 410.0749 -393.251583)
			(xy 410.038149 -393.214832) (xy 410.007599 -393.172784) (xy 409.984003 -393.126474) (xy 409.967942 -393.077044)
			(xy 409.959812 -393.025709) (xy 409.420312 -393.025709) (xy 409.412182 -393.077044) (xy 409.396121 -393.126474)
			(xy 409.372525 -393.172784) (xy 409.341975 -393.214832) (xy 409.305224 -393.251583) (xy 409.263176 -393.282133)
			(xy 409.216866 -393.305729) (xy 409.167436 -393.32179) (xy 409.116101 -393.32992) (xy 409.064127 -393.32992)
			(xy 409.012792 -393.32179) (xy 408.963362 -393.305729) (xy 408.917052 -393.282133) (xy 408.875004 -393.251583)
			(xy 408.838253 -393.214832) (xy 408.807703 -393.172784) (xy 408.784107 -393.126474) (xy 408.768046 -393.077044)
			(xy 408.759916 -393.025709) (xy 408.220416 -393.025709) (xy 408.212286 -393.077044) (xy 408.196225 -393.126474)
			(xy 408.172629 -393.172784) (xy 408.142079 -393.214832) (xy 408.105328 -393.251583) (xy 408.06328 -393.282133)
			(xy 408.01697 -393.305729) (xy 407.96754 -393.32179) (xy 407.916205 -393.32992) (xy 407.864231 -393.32992)
			(xy 407.812896 -393.32179) (xy 407.763466 -393.305729) (xy 407.717156 -393.282133) (xy 407.675108 -393.251583)
			(xy 407.638357 -393.214832) (xy 407.607807 -393.172784) (xy 407.584211 -393.126474) (xy 407.56815 -393.077044)
			(xy 407.56002 -393.025709) (xy 407.020266 -393.025709) (xy 407.012136 -393.077044) (xy 406.996075 -393.126474)
			(xy 406.972479 -393.172784) (xy 406.941929 -393.214832) (xy 406.905178 -393.251583) (xy 406.86313 -393.282133)
			(xy 406.81682 -393.305729) (xy 406.76739 -393.32179) (xy 406.716055 -393.32992) (xy 406.664081 -393.32992)
			(xy 406.612746 -393.32179) (xy 406.563316 -393.305729) (xy 406.517006 -393.282133) (xy 406.474958 -393.251583)
			(xy 406.438207 -393.214832) (xy 406.407657 -393.172784) (xy 406.384061 -393.126474) (xy 406.368 -393.077044)
			(xy 406.35987 -393.025709) (xy 405.82037 -393.025709) (xy 405.81224 -393.077044) (xy 405.796179 -393.126474)
			(xy 405.772583 -393.172784) (xy 405.742033 -393.214832) (xy 405.705282 -393.251583) (xy 405.663234 -393.282133)
			(xy 405.616924 -393.305729) (xy 405.567494 -393.32179) (xy 405.516159 -393.32992) (xy 405.464185 -393.32992)
			(xy 405.41285 -393.32179) (xy 405.36342 -393.305729) (xy 405.31711 -393.282133) (xy 405.275062 -393.251583)
			(xy 405.238311 -393.214832) (xy 405.207761 -393.172784) (xy 405.184165 -393.126474) (xy 405.168104 -393.077044)
			(xy 405.159974 -393.025709) (xy 404.62022 -393.025709) (xy 404.61209 -393.077044) (xy 404.596029 -393.126474)
			(xy 404.572433 -393.172784) (xy 404.541883 -393.214832) (xy 404.505132 -393.251583) (xy 404.463084 -393.282133)
			(xy 404.416774 -393.305729) (xy 404.367344 -393.32179) (xy 404.316009 -393.32992) (xy 404.264035 -393.32992)
			(xy 404.2127 -393.32179) (xy 404.16327 -393.305729) (xy 404.11696 -393.282133) (xy 404.074912 -393.251583)
			(xy 404.038161 -393.214832) (xy 404.007611 -393.172784) (xy 403.984015 -393.126474) (xy 403.967954 -393.077044)
			(xy 403.959824 -393.025709) (xy 403.420324 -393.025709) (xy 403.412194 -393.077044) (xy 403.396133 -393.126474)
			(xy 403.372537 -393.172784) (xy 403.341987 -393.214832) (xy 403.305236 -393.251583) (xy 403.263188 -393.282133)
			(xy 403.216878 -393.305729) (xy 403.167448 -393.32179) (xy 403.116113 -393.32992) (xy 403.064139 -393.32992)
			(xy 403.012804 -393.32179) (xy 402.963374 -393.305729) (xy 402.917064 -393.282133) (xy 402.875016 -393.251583)
			(xy 402.838265 -393.214832) (xy 402.807715 -393.172784) (xy 402.784119 -393.126474) (xy 402.768058 -393.077044)
			(xy 402.759928 -393.025709) (xy 401.425331 -393.025709) (xy 400.84248 -393.60856) (xy 400.835792 -393.615968)
			(xy 400.828198 -393.634404) (xy 400.827748 -393.644374) (xy 400.827599 -393.69238) (xy 403.088348 -393.69238)
			(xy 403.088883 -393.666394) (xy 403.097015 -393.615064) (xy 403.113076 -393.565636) (xy 403.136671 -393.51933)
			(xy 403.167218 -393.477284) (xy 403.203966 -393.440533) (xy 403.246009 -393.409983) (xy 403.292314 -393.386385)
			(xy 403.34174 -393.370321) (xy 403.393071 -393.362185) (xy 403.419056 -393.361672) (xy 403.445068 -393.362091)
			(xy 403.496447 -393.370258) (xy 403.545914 -393.386366) (xy 403.59225 -393.410019) (xy 403.634313 -393.440633)
			(xy 403.671065 -393.477454) (xy 403.701601 -393.519573) (xy 403.725168 -393.565953) (xy 403.741185 -393.61545)
			(xy 403.7457 -393.641072) (xy 403.747224 -393.65047) (xy 403.77145 -393.69238) (xy 404.288244 -393.69238)
			(xy 404.288783 -393.666395) (xy 404.296915 -393.615064) (xy 404.312976 -393.565637) (xy 404.33657 -393.519331)
			(xy 404.367117 -393.477285) (xy 404.403864 -393.440535) (xy 404.445907 -393.409985) (xy 404.492211 -393.386386)
			(xy 404.541637 -393.370322) (xy 404.592967 -393.362185) (xy 404.618952 -393.361672) (xy 404.644964 -393.362094)
			(xy 404.696342 -393.370261) (xy 404.74581 -393.386369) (xy 404.792146 -393.410021) (xy 404.834208 -393.440635)
			(xy 404.870961 -393.477455) (xy 404.901497 -393.519574) (xy 404.925064 -393.565954) (xy 404.941081 -393.61545)
			(xy 404.945596 -393.641072) (xy 404.94712 -393.65047) (xy 404.971346 -393.69238) (xy 405.488394 -393.69238)
			(xy 405.488883 -393.666392) (xy 405.497017 -393.615057) (xy 405.513081 -393.565626) (xy 405.536679 -393.519316)
			(xy 405.567231 -393.477268) (xy 405.603985 -393.440517) (xy 405.646035 -393.409968) (xy 405.692346 -393.386372)
			(xy 405.741778 -393.370312) (xy 405.793114 -393.362181) (xy 405.819102 -393.361672) (xy 405.845146 -393.362131)
			(xy 405.896587 -393.370319) (xy 405.946111 -393.386462) (xy 405.992496 -393.41016) (xy 406.034598 -393.440829)
			(xy 406.071378 -393.477713) (xy 406.101929 -393.519902) (xy 406.125496 -393.566354) (xy 406.141499 -393.615923)
			(xy 406.146 -393.64158) (xy 406.14727 -393.650978) (xy 406.171206 -393.69238) (xy 406.68829 -393.69238)
			(xy 406.688783 -393.666392) (xy 406.696917 -393.615057) (xy 406.71298 -393.565627) (xy 406.736578 -393.519317)
			(xy 406.76713 -393.477269) (xy 406.803883 -393.440518) (xy 406.845933 -393.409969) (xy 406.892243 -393.386373)
			(xy 406.941675 -393.370312) (xy 406.99301 -393.362182) (xy 407.018998 -393.361672) (xy 407.045008 -393.362143)
			(xy 407.096385 -393.370302) (xy 407.145851 -393.386402) (xy 407.192187 -393.410048) (xy 407.23425 -393.440655)
			(xy 407.271003 -393.47747) (xy 407.301541 -393.519584) (xy 407.325109 -393.565959) (xy 407.341127 -393.615452)
			(xy 407.345642 -393.641072) (xy 407.347166 -393.65047) (xy 407.371392 -393.69238) (xy 407.888186 -393.69238)
			(xy 407.888683 -393.666393) (xy 407.896816 -393.615058) (xy 407.91288 -393.565628) (xy 407.936478 -393.519319)
			(xy 407.967029 -393.477271) (xy 408.003781 -393.44052) (xy 408.04583 -393.40997) (xy 408.092141 -393.386374)
			(xy 408.141572 -393.370313) (xy 408.192907 -393.362182) (xy 408.218894 -393.361672) (xy 408.244904 -393.362147)
			(xy 408.29628 -393.370305) (xy 408.345747 -393.386405) (xy 408.392082 -393.41005) (xy 408.434146 -393.440657)
			(xy 408.470899 -393.477471) (xy 408.501436 -393.519585) (xy 408.525005 -393.56596) (xy 408.541023 -393.615452)
			(xy 408.545538 -393.641072) (xy 408.547062 -393.65047) (xy 408.571288 -393.69238) (xy 409.088336 -393.69238)
			(xy 409.088757 -393.666388) (xy 409.096892 -393.615044) (xy 409.11296 -393.565606) (xy 409.136564 -393.51929)
			(xy 409.167123 -393.477236) (xy 409.203885 -393.440482) (xy 409.245944 -393.409931) (xy 409.292265 -393.386336)
			(xy 409.341707 -393.370277) (xy 409.393052 -393.362152) (xy 409.419044 -393.361672) (xy 409.445055 -393.362102)
			(xy 409.496434 -393.370267) (xy 409.545901 -393.386374) (xy 409.592237 -393.410025) (xy 409.6343 -393.440638)
			(xy 409.671052 -393.477457) (xy 409.701589 -393.519576) (xy 409.725156 -393.565954) (xy 409.741173 -393.615451)
			(xy 409.745688 -393.641072) (xy 409.747212 -393.65047) (xy 409.771438 -393.69238) (xy 410.288232 -393.69238)
			(xy 410.288657 -393.666388) (xy 410.296792 -393.615045) (xy 410.31286 -393.565607) (xy 410.336463 -393.519291)
			(xy 410.367022 -393.477238) (xy 410.403784 -393.440483) (xy 410.445842 -393.409932) (xy 410.492162 -393.386337)
			(xy 410.541604 -393.370278) (xy 410.592948 -393.362152) (xy 410.61894 -393.361672) (xy 410.644951 -393.362105)
			(xy 410.69633 -393.37027) (xy 410.745797 -393.386376) (xy 410.792133 -393.410027) (xy 410.834195 -393.440639)
			(xy 410.870948 -393.477458) (xy 410.901485 -393.519576) (xy 410.925052 -393.565955) (xy 410.941069 -393.615451)
			(xy 410.945584 -393.641072) (xy 410.947108 -393.65047) (xy 410.971334 -393.69238) (xy 411.488382 -393.69238)
			(xy 411.488883 -393.666393) (xy 411.497016 -393.615059) (xy 411.513079 -393.565629) (xy 411.536677 -393.51932)
			(xy 411.567228 -393.477272) (xy 411.60398 -393.440521) (xy 411.646028 -393.409972) (xy 411.692338 -393.386376)
			(xy 411.741768 -393.370314) (xy 411.793103 -393.362182) (xy 411.81909 -393.361672) (xy 411.845134 -393.362142)
			(xy 411.896574 -393.370328) (xy 411.946098 -393.386469) (xy 411.992483 -393.410166) (xy 412.034585 -393.440834)
			(xy 412.071365 -393.477717) (xy 412.101916 -393.519904) (xy 412.125484 -393.566355) (xy 412.141486 -393.615924)
			(xy 412.145988 -393.64158) (xy 412.147258 -393.650978) (xy 412.171194 -393.69238) (xy 412.688278 -393.69238)
			(xy 412.688783 -393.666393) (xy 412.696916 -393.615059) (xy 412.712979 -393.565629) (xy 412.736576 -393.519321)
			(xy 412.767127 -393.477274) (xy 412.803878 -393.440523) (xy 412.845926 -393.409973) (xy 412.892235 -393.386377)
			(xy 412.941665 -393.370315) (xy 412.992999 -393.362183) (xy 413.018986 -393.361672) (xy 413.044996 -393.362154)
			(xy 413.096372 -393.370311) (xy 413.145838 -393.38641) (xy 413.192174 -393.410054) (xy 413.234237 -393.44066)
			(xy 413.270991 -393.477473) (xy 413.301528 -393.519586) (xy 413.325096 -393.56596) (xy 413.341115 -393.615453)
			(xy 413.34563 -393.641072) (xy 413.347154 -393.65047) (xy 413.37138 -393.69238) (xy 413.888174 -393.69238)
			(xy 413.888683 -393.666393) (xy 413.896816 -393.61506) (xy 413.912879 -393.56563) (xy 413.936475 -393.519322)
			(xy 413.967025 -393.477275) (xy 414.003776 -393.440524) (xy 414.045824 -393.409974) (xy 414.092132 -393.386378)
			(xy 414.141562 -393.370316) (xy 414.192895 -393.362183) (xy 414.218882 -393.361672) (xy 414.244892 -393.362158)
			(xy 414.296268 -393.370314) (xy 414.345733 -393.386412) (xy 414.392069 -393.410056) (xy 414.434133 -393.440661)
			(xy 414.470886 -393.477474) (xy 414.501424 -393.519587) (xy 414.524992 -393.565961) (xy 414.541011 -393.615453)
			(xy 414.545526 -393.641072) (xy 414.54705 -393.65047) (xy 414.571276 -393.69238) (xy 415.088324 -393.69238)
			(xy 415.088757 -393.666389) (xy 415.096892 -393.615046) (xy 415.112959 -393.565609) (xy 415.136562 -393.519293)
			(xy 415.16712 -393.477241) (xy 415.20388 -393.440486) (xy 415.245938 -393.409935) (xy 415.292257 -393.386339)
			(xy 415.341697 -393.37028) (xy 415.393041 -393.362153) (xy 415.419032 -393.361672) (xy 415.445043 -393.362112)
			(xy 415.496421 -393.370276) (xy 415.545888 -393.386381) (xy 415.592224 -393.410031) (xy 415.634287 -393.440642)
			(xy 415.67104 -393.477461) (xy 415.701576 -393.519578) (xy 415.725144 -393.565956) (xy 415.741161 -393.615451)
			(xy 415.745676 -393.641072) (xy 415.7472 -393.65047) (xy 415.771426 -393.69238) (xy 416.28822 -393.69238)
			(xy 416.288657 -393.666389) (xy 416.296792 -393.615047) (xy 416.312859 -393.56561) (xy 416.336461 -393.519295)
			(xy 416.367019 -393.477242) (xy 416.403779 -393.440487) (xy 416.445836 -393.409936) (xy 416.492154 -393.38634)
			(xy 416.541594 -393.370281) (xy 416.592937 -393.362153) (xy 416.618928 -393.361672) (xy 416.644939 -393.362116)
			(xy 416.696317 -393.370279) (xy 416.745783 -393.386384) (xy 416.792119 -393.410033) (xy 416.834182 -393.440644)
			(xy 416.870935 -393.477462) (xy 416.901472 -393.519578) (xy 416.92504 -393.565956) (xy 416.941057 -393.615451)
			(xy 416.945572 -393.641072) (xy 416.947096 -393.65047) (xy 416.971322 -393.69238) (xy 417.48837 -393.69238)
			(xy 417.488883 -393.666393) (xy 417.497016 -393.61506) (xy 417.513078 -393.565631) (xy 417.536675 -393.519323)
			(xy 417.567224 -393.477276) (xy 417.603975 -393.440526) (xy 417.646022 -393.409976) (xy 417.692329 -393.386379)
			(xy 417.741758 -393.370316) (xy 417.793091 -393.362183) (xy 417.819078 -393.361672) (xy 417.845121 -393.362153)
			(xy 417.896561 -393.370338) (xy 417.946085 -393.386476) (xy 417.99247 -393.410172) (xy 418.034572 -393.440838)
			(xy 418.071353 -393.47772) (xy 418.101904 -393.519906) (xy 418.125471 -393.566356) (xy 418.141474 -393.615924)
			(xy 418.145976 -393.64158) (xy 418.147246 -393.650978) (xy 418.419788 -394.122402) (xy 418.427154 -394.128244)
			(xy 418.445947 -394.144029) (xy 418.479061 -394.180251) (xy 418.506467 -394.220963) (xy 418.527565 -394.265274)
			(xy 418.541893 -394.312213) (xy 418.549137 -394.360753) (xy 418.549582 -394.385292) (xy 418.549328 -394.397484)
			(xy 418.549074 -394.407136) (xy 418.55517 -394.42517) (xy 418.613844 -394.49248) (xy 418.630608 -394.501116)
			(xy 418.640514 -394.502132) (xy 418.667277 -394.50548) (xy 418.7193 -394.519705) (xy 418.768326 -394.542182)
			(xy 418.813055 -394.572315) (xy 418.852303 -394.609307) (xy 418.885028 -394.652176) (xy 418.910364 -394.699788)
			(xy 418.927639 -394.750879) (xy 418.936396 -394.804096) (xy 418.936932 -394.831062) (xy 418.936391 -394.858347)
			(xy 418.927437 -394.912177) (xy 418.909766 -394.963805) (xy 418.883857 -395.011832) (xy 418.850415 -395.054953)
			(xy 418.83076 -395.073886) (xy 418.823371 -395.081419) (xy 418.814838 -395.10069) (xy 418.81425 -395.111224)
			(xy 418.81425 -395.1859) (xy 418.814781 -395.196449) (xy 418.823316 -395.215744) (xy 418.83076 -395.223238)
			(xy 418.850405 -395.242179) (xy 418.883837 -395.285303) (xy 418.90974 -395.333329) (xy 418.927411 -395.384954)
			(xy 418.936371 -395.438779) (xy 418.936932 -395.466062) (xy 418.936485 -395.490178) (xy 418.929488 -395.537901)
			(xy 418.915638 -395.584102) (xy 418.895227 -395.627803) (xy 418.882322 -395.64818) (xy 418.87648 -395.65707)
			(xy 418.872924 -395.677136) (xy 418.894006 -395.769338) (xy 418.906198 -395.786102) (xy 418.915088 -395.791436)
			(xy 418.935878 -395.804308) (xy 418.973786 -395.835193) (xy 419.006731 -395.871324) (xy 419.033995 -395.911915)
			(xy 419.054982 -395.956078) (xy 419.069235 -396.002851) (xy 419.076443 -396.051214) (xy 419.076886 -396.075662)
			(xy 419.07647 -396.100035) (xy 419.069324 -396.148255) (xy 419.055181 -396.194905) (xy 419.034347 -396.238975)
			(xy 419.007272 -396.279512) (xy 418.974544 -396.315638) (xy 418.955982 -396.33144) (xy 418.947092 -396.338552)
			(xy 418.937694 -396.35811) (xy 418.9349 -396.457424) (xy 418.943536 -396.47749) (xy 418.951918 -396.48511)
			(xy 418.97036 -396.502579) (xy 419.001709 -396.542547) (xy 419.026008 -396.587154) (xy 419.042586 -396.635168)
			(xy 419.050986 -396.685264) (xy 419.051486 -396.710662) (xy 419.051418 -396.720021) (xy 419.050274 -396.738703)
			(xy 419.0492 -396.748) (xy 419.048184 -396.75689) (xy 419.051994 -396.773654) (xy 419.095936 -396.843504)
			(xy 419.109652 -396.853918) (xy 419.118034 -396.856712) (xy 419.142061 -396.865183) (xy 419.187234 -396.888735)
			(xy 419.228039 -396.919234) (xy 419.263418 -396.955888) (xy 419.292454 -396.997747) (xy 419.314393 -397.043725)
			(xy 419.321996 -397.06804) (xy 419.32352 -397.073882) (xy 419.643814 -397.627602) (xy 419.647878 -397.63192)
			(xy 419.664079 -397.649618) (xy 419.69144 -397.68903) (xy 419.712522 -397.732129) (xy 419.72684 -397.777922)
			(xy 419.734064 -397.825354) (xy 419.734492 -397.849344) (xy 419.734023 -397.874134) (xy 419.726261 -397.923102)
			(xy 419.710936 -397.970253) (xy 419.688424 -398.014427) (xy 419.65928 -398.054536) (xy 419.624221 -398.089593)
			(xy 419.58411 -398.118734) (xy 419.539934 -398.141243) (xy 419.492782 -398.156566) (xy 419.443814 -398.164324)
			(xy 419.419024 -398.164812) (xy 419.39363 -398.16429) (xy 419.343498 -398.156164) (xy 419.295313 -398.140116)
			(xy 419.250318 -398.11656) (xy 419.209675 -398.086106) (xy 419.174432 -398.049537) (xy 419.145498 -398.007798)
			(xy 419.123619 -397.961966) (xy 419.116002 -397.937736) (xy 419.114478 -397.931894) (xy 418.794184 -397.378174)
			(xy 418.79012 -397.373856) (xy 418.77392 -397.356144) (xy 418.746495 -397.316755) (xy 418.725351 -397.273666)
			(xy 418.710976 -397.227873) (xy 418.703702 -397.18043) (xy 418.703252 -397.156432) (xy 418.703393 -397.14438)
			(xy 418.7053 -397.12035) (xy 418.707062 -397.108426) (xy 418.708332 -397.099536) (xy 418.705284 -397.082518)
			(xy 418.66312 -397.011652) (xy 418.649912 -397.000476) (xy 418.64153 -396.997428) (xy 418.619774 -396.989055)
			(xy 418.578916 -396.966609) (xy 418.541947 -396.938211) (xy 418.509726 -396.904522) (xy 418.483002 -396.866325)
			(xy 418.462398 -396.824509) (xy 418.448391 -396.780046) (xy 418.441308 -396.733971) (xy 418.44087 -396.710662)
			(xy 418.441405 -396.685268) (xy 418.449814 -396.63518) (xy 418.466392 -396.587173) (xy 418.490684 -396.54257)
			(xy 418.522019 -396.5026) (xy 418.540438 -396.48511) (xy 418.54882 -396.47749) (xy 418.557456 -396.457424)
			(xy 418.554662 -396.35811) (xy 418.545264 -396.338552) (xy 418.536374 -396.33144) (xy 418.517841 -396.315607)
			(xy 418.485119 -396.279483) (xy 418.458048 -396.238951) (xy 418.437213 -396.194888) (xy 418.423064 -396.148245)
			(xy 418.415908 -396.100032) (xy 418.41547 -396.075662) (xy 418.41588 -396.051544) (xy 418.422888 -396.003821)
			(xy 418.436749 -395.95762) (xy 418.45717 -395.91392) (xy 418.47008 -395.893544) (xy 418.475922 -395.884654)
			(xy 418.479478 -395.864588) (xy 418.458396 -395.772386) (xy 418.446204 -395.755622) (xy 418.437314 -395.750288)
			(xy 418.416535 -395.737399) (xy 418.378627 -395.706517) (xy 418.345681 -395.670388) (xy 418.318417 -395.629801)
			(xy 418.297428 -395.58564) (xy 418.283172 -395.53887) (xy 418.275961 -395.490509) (xy 418.275516 -395.466062)
			(xy 418.276058 -395.438777) (xy 418.285009 -395.384947) (xy 418.302679 -395.333317) (xy 418.328588 -395.28529)
			(xy 418.362032 -395.24217) (xy 418.381688 -395.223238) (xy 418.389073 -395.215703) (xy 418.397607 -395.196433)
			(xy 418.398198 -395.1859) (xy 418.398198 -395.111224) (xy 418.39767 -395.100674) (xy 418.389134 -395.081379)
			(xy 418.381688 -395.073886) (xy 418.362064 -395.054924) (xy 418.328627 -395.011807) (xy 418.302719 -394.963786)
			(xy 418.285044 -394.912165) (xy 418.276079 -394.858344) (xy 418.275516 -394.831062) (xy 418.27577 -394.81887)
			(xy 418.276024 -394.809218) (xy 418.269928 -394.791184) (xy 418.211254 -394.723874) (xy 418.19449 -394.715238)
			(xy 418.184584 -394.714222) (xy 418.15768 -394.710831) (xy 418.105394 -394.696471) (xy 418.056151 -394.673776)
			(xy 418.011268 -394.643354) (xy 417.971947 -394.606019) (xy 417.939242 -394.562771) (xy 417.914028 -394.514769)
			(xy 417.89698 -394.463297) (xy 417.89223 -394.4366) (xy 417.890706 -394.427202) (xy 417.617656 -393.954762)
			(xy 417.610544 -393.94892) (xy 417.591801 -393.933153) (xy 417.558749 -393.897007) (xy 417.531395 -393.856379)
			(xy 417.510338 -393.812157) (xy 417.49604 -393.765312) (xy 417.488812 -393.716869) (xy 417.48837 -393.69238)
			(xy 416.971322 -393.69238) (xy 417.219892 -394.122402) (xy 417.227258 -394.128244) (xy 417.246051 -394.144028)
			(xy 417.279166 -394.18025) (xy 417.306572 -394.220962) (xy 417.327669 -394.265274) (xy 417.341997 -394.312213)
			(xy 417.349241 -394.360753) (xy 417.349686 -394.385292) (xy 417.349432 -394.397484) (xy 417.349178 -394.407136)
			(xy 417.355274 -394.42517) (xy 417.413948 -394.49248) (xy 417.430712 -394.501116) (xy 417.440618 -394.502132)
			(xy 417.467382 -394.505476) (xy 417.519405 -394.519702) (xy 417.568431 -394.542179) (xy 417.61316 -394.572313)
			(xy 417.652407 -394.609305) (xy 417.685133 -394.652175) (xy 417.710469 -394.699787) (xy 417.727744 -394.750878)
			(xy 417.736501 -394.804096) (xy 417.737036 -394.831062) (xy 417.736493 -394.858347) (xy 417.72754 -394.912176)
			(xy 417.709869 -394.963805) (xy 417.683961 -395.011832) (xy 417.650519 -395.054953) (xy 417.630864 -395.073886)
			(xy 417.623476 -395.081419) (xy 417.614942 -395.10069) (xy 417.614354 -395.111224) (xy 417.614354 -395.1859)
			(xy 417.614883 -395.196449) (xy 417.62342 -395.215744) (xy 417.630864 -395.223238) (xy 417.650509 -395.242178)
			(xy 417.683941 -395.285303) (xy 417.709844 -395.333329) (xy 417.727515 -395.384954) (xy 417.736475 -395.438779)
			(xy 417.737036 -395.466062) (xy 417.736588 -395.490178) (xy 417.729592 -395.537901) (xy 417.715742 -395.584102)
			(xy 417.695331 -395.627802) (xy 417.682426 -395.64818) (xy 417.676584 -395.65707) (xy 417.673028 -395.677136)
			(xy 417.69411 -395.769338) (xy 417.706302 -395.786102) (xy 417.715192 -395.791436) (xy 417.735983 -395.804306)
			(xy 417.773891 -395.835192) (xy 417.806836 -395.871324) (xy 417.834099 -395.911914) (xy 417.855086 -395.956078)
			(xy 417.869339 -396.002851) (xy 417.876547 -396.051214) (xy 417.87699 -396.075662) (xy 417.876573 -396.100035)
			(xy 417.869427 -396.148255) (xy 417.855284 -396.194905) (xy 417.83445 -396.238975) (xy 417.807376 -396.279512)
			(xy 417.774648 -396.315638) (xy 417.756086 -396.33144) (xy 417.747196 -396.338552) (xy 417.737798 -396.35811)
			(xy 417.735004 -396.457424) (xy 417.74364 -396.47749) (xy 417.752022 -396.48511) (xy 417.770465 -396.502579)
			(xy 417.801813 -396.542547) (xy 417.826112 -396.587154) (xy 417.84269 -396.635168) (xy 417.85109 -396.685264)
			(xy 417.85159 -396.710662) (xy 417.851522 -396.720021) (xy 417.850378 -396.738703) (xy 417.849304 -396.748)
			(xy 417.848288 -396.75689) (xy 417.852098 -396.773654) (xy 417.89604 -396.843504) (xy 417.909756 -396.853918)
			(xy 417.918138 -396.856712) (xy 417.942243 -396.865172) (xy 417.987533 -396.888802) (xy 418.028427 -396.919418)
			(xy 418.063857 -396.956219) (xy 418.092898 -396.998245) (xy 418.114793 -397.0444) (xy 418.122354 -397.068802)
			(xy 418.123878 -397.074644) (xy 418.443664 -397.627602) (xy 418.447728 -397.63192) (xy 418.463924 -397.649634)
			(xy 418.491349 -397.689024) (xy 418.512492 -397.732112) (xy 418.526868 -397.777905) (xy 418.534144 -397.825346)
			(xy 418.534596 -397.849344) (xy 418.534147 -397.874148) (xy 418.526377 -397.923144) (xy 418.511035 -397.97032)
			(xy 418.488499 -398.014515) (xy 418.459325 -398.054638) (xy 418.424232 -398.089701) (xy 418.384084 -398.118841)
			(xy 418.339871 -398.141338) (xy 418.292681 -398.15664) (xy 418.243678 -398.164368) (xy 418.218874 -398.164812)
			(xy 418.193479 -398.164334) (xy 418.143344 -398.1562) (xy 418.095158 -398.140145) (xy 418.050164 -398.116583)
			(xy 418.009521 -398.086122) (xy 417.974279 -398.049548) (xy 417.945346 -398.007805) (xy 417.923468 -397.961967)
			(xy 417.915852 -397.937736) (xy 417.914328 -397.931894) (xy 417.59378 -397.377412) (xy 417.589716 -397.373094)
			(xy 417.573624 -397.355415) (xy 417.546371 -397.316139) (xy 417.525358 -397.273202) (xy 417.511063 -397.227585)
			(xy 417.503815 -397.180334) (xy 417.503356 -397.156432) (xy 417.503497 -397.14438) (xy 417.505404 -397.12035)
			(xy 417.507166 -397.108426) (xy 417.508436 -397.099536) (xy 417.505388 -397.082518) (xy 417.463224 -397.011652)
			(xy 417.450016 -397.000476) (xy 417.441634 -396.997428) (xy 417.419878 -396.989052) (xy 417.379021 -396.966607)
			(xy 417.342052 -396.93821) (xy 417.30983 -396.904521) (xy 417.283107 -396.866325) (xy 417.262502 -396.824509)
			(xy 417.248495 -396.780046) (xy 417.241412 -396.73397) (xy 417.240974 -396.710662) (xy 417.241508 -396.685268)
			(xy 417.249917 -396.635179) (xy 417.266495 -396.587172) (xy 417.290787 -396.542569) (xy 417.322123 -396.5026)
			(xy 417.340542 -396.48511) (xy 417.348924 -396.47749) (xy 417.35756 -396.457424) (xy 417.354766 -396.35811)
			(xy 417.345368 -396.338552) (xy 417.336478 -396.33144) (xy 417.317946 -396.315606) (xy 417.285224 -396.279482)
			(xy 417.258152 -396.238951) (xy 417.237317 -396.194887) (xy 417.223168 -396.148245) (xy 417.216012 -396.100032)
			(xy 417.215574 -396.075662) (xy 417.215984 -396.051544) (xy 417.222991 -396.003821) (xy 417.236853 -395.95762)
			(xy 417.257274 -395.91392) (xy 417.270184 -395.893544) (xy 417.276026 -395.884654) (xy 417.279582 -395.864588)
			(xy 417.2585 -395.772386) (xy 417.246308 -395.755622) (xy 417.237418 -395.750288) (xy 417.21664 -395.737398)
			(xy 417.178732 -395.706516) (xy 417.145786 -395.670387) (xy 417.118521 -395.6298) (xy 417.097532 -395.58564)
			(xy 417.083276 -395.538869) (xy 417.076065 -395.490509) (xy 417.07562 -395.466062) (xy 417.07616 -395.438777)
			(xy 417.085112 -395.384946) (xy 417.102782 -395.333317) (xy 417.128691 -395.28529) (xy 417.162136 -395.24217)
			(xy 417.181792 -395.223238) (xy 417.189178 -395.215703) (xy 417.197711 -395.196433) (xy 417.198302 -395.1859)
			(xy 417.198302 -395.111224) (xy 417.197773 -395.100674) (xy 417.189238 -395.081379) (xy 417.181792 -395.073886)
			(xy 417.162169 -395.054924) (xy 417.128731 -395.011806) (xy 417.102824 -394.963786) (xy 417.085148 -394.912165)
			(xy 417.076183 -394.858344) (xy 417.07562 -394.831062) (xy 417.075874 -394.81887) (xy 417.076128 -394.809218)
			(xy 417.070032 -394.791184) (xy 417.011358 -394.723874) (xy 416.994594 -394.715238) (xy 416.984688 -394.714222)
			(xy 416.957784 -394.710828) (xy 416.905499 -394.696469) (xy 416.856255 -394.673774) (xy 416.811372 -394.643352)
			(xy 416.772052 -394.606018) (xy 416.739346 -394.562771) (xy 416.714132 -394.514769) (xy 416.697084 -394.463297)
			(xy 416.692334 -394.4366) (xy 416.69081 -394.427202) (xy 416.418014 -393.95527) (xy 416.410648 -393.949428)
			(xy 416.39189 -393.933604) (xy 416.358774 -393.89739) (xy 416.331363 -393.856686) (xy 416.310259 -393.812383)
			(xy 416.295923 -393.76545) (xy 416.28867 -393.716916) (xy 416.28822 -393.69238) (xy 415.771426 -393.69238)
			(xy 416.019996 -394.122402) (xy 416.027362 -394.128244) (xy 416.046156 -394.144027) (xy 416.07927 -394.180249)
			(xy 416.106676 -394.220962) (xy 416.127774 -394.265273) (xy 416.142101 -394.312213) (xy 416.149345 -394.360753)
			(xy 416.14979 -394.385292) (xy 416.149536 -394.397484) (xy 416.149282 -394.407136) (xy 416.155378 -394.42517)
			(xy 416.214052 -394.49248) (xy 416.230816 -394.501116) (xy 416.240468 -394.502132) (xy 416.267226 -394.505517)
			(xy 416.319249 -394.519735) (xy 416.368275 -394.542206) (xy 416.413005 -394.572334) (xy 416.452253 -394.609321)
			(xy 416.48498 -394.652186) (xy 416.510317 -394.699794) (xy 416.527593 -394.750882) (xy 416.53635 -394.804097)
			(xy 416.536886 -394.831062) (xy 416.536376 -394.857049) (xy 416.528246 -394.908384) (xy 416.512185 -394.957814)
			(xy 416.488589 -395.004124) (xy 416.458039 -395.046172) (xy 416.421288 -395.082923) (xy 416.37924 -395.113473)
			(xy 416.33293 -395.137069) (xy 416.2835 -395.15313) (xy 416.232165 -395.16126) (xy 416.180191 -395.16126)
			(xy 416.128856 -395.15313) (xy 416.079426 -395.137069) (xy 416.033116 -395.113473) (xy 415.991068 -395.082923)
			(xy 415.954317 -395.046172) (xy 415.923767 -395.004124) (xy 415.900171 -394.957814) (xy 415.88411 -394.908384)
			(xy 415.87598 -394.857049) (xy 415.87547 -394.831062) (xy 415.875724 -394.81887) (xy 415.875978 -394.809218)
			(xy 415.869882 -394.791184) (xy 415.811208 -394.723874) (xy 415.794444 -394.715238) (xy 415.784792 -394.714222)
			(xy 415.757889 -394.710825) (xy 415.705603 -394.696466) (xy 415.65636 -394.673772) (xy 415.611477 -394.643351)
			(xy 415.572156 -394.606017) (xy 415.539451 -394.56277) (xy 415.514236 -394.514768) (xy 415.497188 -394.463297)
			(xy 415.492438 -394.4366) (xy 415.490914 -394.427202) (xy 415.218118 -393.95527) (xy 415.210752 -393.949428)
			(xy 415.191995 -393.933603) (xy 415.158878 -393.897389) (xy 415.131467 -393.856686) (xy 415.110363 -393.812383)
			(xy 415.096027 -393.76545) (xy 415.088774 -393.716916) (xy 415.088324 -393.69238) (xy 414.571276 -393.69238)
			(xy 414.819846 -394.122402) (xy 414.827212 -394.128244) (xy 414.845996 -394.144039) (xy 414.879113 -394.180257)
			(xy 414.906521 -394.220967) (xy 414.927621 -394.265276) (xy 414.94195 -394.312215) (xy 414.949195 -394.360754)
			(xy 414.94964 -394.385292) (xy 414.949386 -394.397484) (xy 414.949132 -394.407136) (xy 414.955228 -394.42517)
			(xy 415.013902 -394.49248) (xy 415.030666 -394.501116) (xy 415.040572 -394.502132) (xy 415.067331 -394.505514)
			(xy 415.119353 -394.519732) (xy 415.168379 -394.542204) (xy 415.213109 -394.572332) (xy 415.252358 -394.60932)
			(xy 415.285084 -394.652185) (xy 415.310421 -394.699794) (xy 415.327697 -394.750882) (xy 415.336454 -394.804097)
			(xy 415.33699 -394.831062) (xy 415.336566 -394.855264) (xy 415.329493 -394.903149) (xy 415.315506 -394.949489)
			(xy 415.294905 -394.993291) (xy 415.281872 -395.013688) (xy 415.277084 -395.021645) (xy 415.27305 -395.039756)
			(xy 415.273998 -395.048994) (xy 415.278316 -395.079982) (xy 415.279993 -395.089279) (xy 415.289277 -395.105721)
			(xy 415.29635 -395.111986) (xy 415.318436 -395.130671) (xy 415.358208 -395.172682) (xy 415.39237 -395.219369)
			(xy 415.420379 -395.269989) (xy 415.441786 -395.323733) (xy 415.456252 -395.379747) (xy 415.463545 -395.437136)
			(xy 415.46399 -395.466062) (xy 415.463396 -395.499383) (xy 415.453734 -395.565321) (xy 415.43461 -395.629161)
			(xy 415.421064 -395.65961) (xy 415.416821 -395.670076) (xy 415.416935 -395.692633) (xy 415.426666 -395.712984)
			(xy 415.435034 -395.72057) (xy 415.457271 -395.739254) (xy 415.497334 -395.781309) (xy 415.531754 -395.828094)
			(xy 415.55998 -395.878857) (xy 415.581557 -395.932783) (xy 415.596139 -395.989005) (xy 415.603491 -396.046621)
			(xy 415.603944 -396.075662) (xy 415.60347 -396.104667) (xy 415.596159 -396.162214) (xy 415.581637 -396.218377)
			(xy 415.560136 -396.272255) (xy 415.532001 -396.322986) (xy 415.497683 -396.369756) (xy 415.457732 -396.411816)
			(xy 415.435542 -396.4305) (xy 415.42843 -396.436088) (xy 415.419286 -396.451328) (xy 415.404046 -396.534132)
			(xy 415.40684 -396.551404) (xy 415.411412 -396.559532) (xy 415.423985 -396.58272) (xy 415.44186 -396.632341)
			(xy 415.450962 -396.684291) (xy 415.451544 -396.710662) (xy 416.040824 -396.710662) (xy 416.041346 -396.685407)
			(xy 416.049659 -396.635585) (xy 416.06606 -396.587811) (xy 416.090101 -396.543388) (xy 416.121125 -396.503528)
			(xy 416.158287 -396.469318) (xy 416.200573 -396.441692) (xy 416.246829 -396.421402) (xy 416.295794 -396.409002)
			(xy 416.346132 -396.404831) (xy 416.39647 -396.409002) (xy 416.445435 -396.421402) (xy 416.491691 -396.441692)
			(xy 416.533977 -396.469318) (xy 416.571139 -396.503528) (xy 416.602163 -396.543388) (xy 416.626204 -396.587811)
			(xy 416.642605 -396.635585) (xy 416.650918 -396.685407) (xy 416.65144 -396.710662) (xy 416.651371 -396.720021)
			(xy 416.650228 -396.738703) (xy 416.649154 -396.748) (xy 416.648138 -396.75689) (xy 416.651948 -396.773654)
			(xy 416.69589 -396.843504) (xy 416.709606 -396.853918) (xy 416.717988 -396.856712) (xy 416.742006 -396.865208)
			(xy 416.78718 -396.888753) (xy 416.827986 -396.919246) (xy 416.863368 -396.955896) (xy 416.892405 -396.997751)
			(xy 416.914346 -397.043726) (xy 416.92195 -397.06804) (xy 416.923474 -397.073882) (xy 417.243768 -397.627602)
			(xy 417.247832 -397.63192) (xy 417.264029 -397.649634) (xy 417.291453 -397.689024) (xy 417.312597 -397.732112)
			(xy 417.326972 -397.777905) (xy 417.334248 -397.825346) (xy 417.3347 -397.849344) (xy 417.334247 -397.874148)
			(xy 417.326477 -397.923143) (xy 417.311135 -397.970319) (xy 417.2886 -398.014513) (xy 417.259427 -398.054636)
			(xy 417.224334 -398.0897) (xy 417.184186 -398.118839) (xy 417.139973 -398.141337) (xy 417.092784 -398.156639)
			(xy 417.043782 -398.164368) (xy 417.018978 -398.164812) (xy 416.993583 -398.164331) (xy 416.943448 -398.156197)
			(xy 416.895263 -398.140142) (xy 416.850268 -398.116581) (xy 416.809626 -398.086121) (xy 416.774383 -398.049547)
			(xy 416.74545 -398.007804) (xy 416.723572 -397.961967) (xy 416.715956 -397.937736) (xy 416.714432 -397.931894)
			(xy 416.394138 -397.378174) (xy 416.390074 -397.373856) (xy 416.373918 -397.356119) (xy 416.346549 -397.316718)
			(xy 416.325457 -397.273629) (xy 416.311129 -397.227845) (xy 416.303894 -397.180419) (xy 416.30346 -397.156432)
			(xy 416.303541 -397.144384) (xy 416.305323 -397.120355) (xy 416.307016 -397.108426) (xy 416.308286 -397.099536)
			(xy 416.305238 -397.082518) (xy 416.263074 -397.011652) (xy 416.249866 -397.000476) (xy 416.241484 -396.997428)
			(xy 416.219739 -396.989025) (xy 416.17888 -396.966586) (xy 416.141909 -396.938194) (xy 416.109686 -396.90451)
			(xy 416.08296 -396.866317) (xy 416.062354 -396.824504) (xy 416.048346 -396.780043) (xy 416.041262 -396.73397)
			(xy 416.040824 -396.710662) (xy 415.451544 -396.710662) (xy 415.451475 -396.720021) (xy 415.450332 -396.738703)
			(xy 415.449258 -396.748) (xy 415.448242 -396.75689) (xy 415.452052 -396.773654) (xy 415.495994 -396.843504)
			(xy 415.50971 -396.853918) (xy 415.518092 -396.856712) (xy 415.542111 -396.865205) (xy 415.587284 -396.888752)
			(xy 415.628091 -396.919245) (xy 415.663472 -396.955896) (xy 415.69251 -396.997751) (xy 415.71445 -397.043726)
			(xy 415.722054 -397.06804) (xy 415.723578 -397.073882) (xy 416.043872 -397.627602) (xy 416.047936 -397.63192)
			(xy 416.064134 -397.649633) (xy 416.091558 -397.689023) (xy 416.112701 -397.732112) (xy 416.127076 -397.777904)
			(xy 416.134352 -397.825346) (xy 416.134804 -397.849344) (xy 416.134347 -397.874148) (xy 416.126577 -397.923143)
			(xy 416.111236 -397.970319) (xy 416.088701 -398.014512) (xy 416.059528 -398.054635) (xy 416.024435 -398.089698)
			(xy 415.984288 -398.118838) (xy 415.940076 -398.141336) (xy 415.892888 -398.156638) (xy 415.843886 -398.164367)
			(xy 415.819082 -398.164812) (xy 415.793687 -398.164327) (xy 415.743553 -398.156194) (xy 415.695367 -398.14014)
			(xy 415.650372 -398.116579) (xy 415.60973 -398.08612) (xy 415.574487 -398.049547) (xy 415.545554 -398.007804)
			(xy 415.523676 -397.961967) (xy 415.51606 -397.937736) (xy 415.514536 -397.931894) (xy 415.194242 -397.378174)
			(xy 415.190178 -397.373856) (xy 415.174023 -397.356118) (xy 415.146653 -397.316718) (xy 415.125561 -397.273629)
			(xy 415.111233 -397.227845) (xy 415.103998 -397.180419) (xy 415.103564 -397.156432) (xy 415.103644 -397.144384)
			(xy 415.105427 -397.120355) (xy 415.10712 -397.108426) (xy 415.10839 -397.099536) (xy 415.105342 -397.082518)
			(xy 415.063178 -397.011652) (xy 415.04997 -397.000476) (xy 415.041588 -396.997428) (xy 415.019844 -396.989023)
			(xy 414.978985 -396.966584) (xy 414.942014 -396.938193) (xy 414.90979 -396.904509) (xy 414.883064 -396.866316)
			(xy 414.862458 -396.824504) (xy 414.84845 -396.780043) (xy 414.841366 -396.73397) (xy 414.840928 -396.710662)
			(xy 414.84149 -396.684289) (xy 414.850574 -396.63233) (xy 414.868464 -396.58271) (xy 414.88106 -396.559532)
			(xy 414.885632 -396.551404) (xy 414.888426 -396.534132) (xy 414.873186 -396.451328) (xy 414.864042 -396.436088)
			(xy 414.85693 -396.4305) (xy 414.834766 -396.411787) (xy 414.794817 -396.369727) (xy 414.760498 -396.322961)
			(xy 414.732358 -396.272236) (xy 414.710847 -396.218364) (xy 414.69631 -396.162208) (xy 414.688979 -396.104666)
			(xy 414.688528 -396.075662) (xy 414.689129 -396.042341) (xy 414.698787 -395.976403) (xy 414.717909 -395.912563)
			(xy 414.731454 -395.882114) (xy 414.735702 -395.871647) (xy 414.735597 -395.849086) (xy 414.725859 -395.828735)
			(xy 414.717484 -395.821154) (xy 414.695214 -395.802507) (xy 414.655152 -395.760446) (xy 414.620734 -395.713655)
			(xy 414.592513 -395.662886) (xy 414.570941 -395.608953) (xy 414.556366 -395.552725) (xy 414.549022 -395.495105)
			(xy 414.548574 -395.466062) (xy 414.549017 -395.437135) (xy 414.556301 -395.379742) (xy 414.570761 -395.323725)
			(xy 414.592166 -395.269977) (xy 414.620174 -395.219356) (xy 414.65434 -395.172668) (xy 414.694117 -395.130659)
			(xy 414.716214 -395.111986) (xy 414.723178 -395.105631) (xy 414.732442 -395.089233) (xy 414.734248 -395.079982)
			(xy 414.738566 -395.048994) (xy 414.739467 -395.039757) (xy 414.735444 -395.021658) (xy 414.730692 -395.013688)
			(xy 414.717704 -394.993266) (xy 414.697123 -394.949464) (xy 414.683137 -394.903133) (xy 414.676041 -394.85526)
			(xy 414.675574 -394.831062) (xy 414.675828 -394.81887) (xy 414.676082 -394.809218) (xy 414.669986 -394.791184)
			(xy 414.611312 -394.723874) (xy 414.594548 -394.715238) (xy 414.584642 -394.714222) (xy 414.557733 -394.710865)
			(xy 414.505447 -394.696498) (xy 414.456204 -394.673797) (xy 414.411321 -394.64337) (xy 414.372002 -394.60603)
			(xy 414.339298 -394.562779) (xy 414.314085 -394.514773) (xy 414.297038 -394.463298) (xy 414.292288 -394.4366)
			(xy 414.290764 -394.427202) (xy 414.017968 -393.95527) (xy 414.010602 -393.949428) (xy 413.991856 -393.93359)
			(xy 413.958736 -393.897381) (xy 413.931322 -393.85668) (xy 413.910216 -393.812379) (xy 413.895879 -393.765449)
			(xy 413.888625 -393.716916) (xy 413.888174 -393.69238) (xy 413.37138 -393.69238) (xy 413.61995 -394.122402)
			(xy 413.627316 -394.128244) (xy 413.646101 -394.144038) (xy 413.679217 -394.180257) (xy 413.706626 -394.220967)
			(xy 413.727725 -394.265276) (xy 413.742054 -394.312215) (xy 413.749299 -394.360754) (xy 413.749744 -394.385292)
			(xy 413.74949 -394.397484) (xy 413.749236 -394.407136) (xy 413.755332 -394.42517) (xy 413.814006 -394.49248)
			(xy 413.83077 -394.501116) (xy 413.840422 -394.502132) (xy 413.867186 -394.505473) (xy 413.91921 -394.519699)
			(xy 413.968235 -394.542177) (xy 414.012965 -394.572312) (xy 414.052212 -394.609304) (xy 414.084937 -394.652174)
			(xy 414.110273 -394.699786) (xy 414.127548 -394.750878) (xy 414.136305 -394.804095) (xy 414.13684 -394.831062)
			(xy 414.136296 -394.858347) (xy 414.127343 -394.912176) (xy 414.109672 -394.963805) (xy 414.083764 -395.011832)
			(xy 414.050322 -395.054953) (xy 414.030668 -395.073886) (xy 414.023281 -395.08142) (xy 414.014746 -395.10069)
			(xy 414.014158 -395.111224) (xy 414.014158 -395.1859) (xy 414.014686 -395.196449) (xy 414.023223 -395.215744)
			(xy 414.030668 -395.223238) (xy 414.050314 -395.242178) (xy 414.083746 -395.285302) (xy 414.109648 -395.333328)
			(xy 414.127319 -395.384954) (xy 414.136279 -395.438779) (xy 414.13684 -395.466062) (xy 414.136392 -395.490178)
			(xy 414.129395 -395.5379) (xy 414.115545 -395.584101) (xy 414.095135 -395.627802) (xy 414.08223 -395.64818)
			(xy 414.076388 -395.65707) (xy 414.072832 -395.677136) (xy 414.093914 -395.769338) (xy 414.106106 -395.786102)
			(xy 414.114996 -395.791436) (xy 414.135788 -395.804305) (xy 414.173696 -395.835191) (xy 414.20664 -395.871323)
			(xy 414.233903 -395.911914) (xy 414.25489 -395.956078) (xy 414.269143 -396.002851) (xy 414.276351 -396.051214)
			(xy 414.276794 -396.075662) (xy 414.276375 -396.100035) (xy 414.269229 -396.148255) (xy 414.255086 -396.194905)
			(xy 414.234253 -396.238975) (xy 414.207179 -396.279512) (xy 414.174452 -396.315638) (xy 414.15589 -396.33144)
			(xy 414.147 -396.338552) (xy 414.137602 -396.35811) (xy 414.134808 -396.457424) (xy 414.143444 -396.47749)
			(xy 414.151826 -396.48511) (xy 414.170269 -396.502578) (xy 414.201618 -396.542546) (xy 414.225916 -396.587153)
			(xy 414.242494 -396.635168) (xy 414.250894 -396.685264) (xy 414.251394 -396.710662) (xy 414.251326 -396.720021)
			(xy 414.250182 -396.738703) (xy 414.249108 -396.748) (xy 414.248092 -396.75689) (xy 414.251902 -396.773654)
			(xy 414.295844 -396.843504) (xy 414.30956 -396.853918) (xy 414.317942 -396.856712) (xy 414.341971 -396.865179)
			(xy 414.387143 -396.888732) (xy 414.427948 -396.919232) (xy 414.463327 -396.955887) (xy 414.492362 -396.997746)
			(xy 414.514301 -397.043724) (xy 414.521904 -397.06804) (xy 414.523428 -397.073882) (xy 414.843722 -397.627602)
			(xy 414.847786 -397.63192) (xy 414.863988 -397.649616) (xy 414.891349 -397.689029) (xy 414.912431 -397.732129)
			(xy 414.926748 -397.777922) (xy 414.933972 -397.825354) (xy 414.9344 -397.849344) (xy 414.933923 -397.874133)
			(xy 414.926161 -397.9231) (xy 414.910836 -397.970251) (xy 414.888325 -398.014424) (xy 414.859182 -398.054533)
			(xy 414.824124 -398.08959) (xy 414.784014 -398.118731) (xy 414.73984 -398.141241) (xy 414.692689 -398.156564)
			(xy 414.643721 -398.164324) (xy 414.618932 -398.164812) (xy 414.593539 -398.164283) (xy 414.543406 -398.156158)
			(xy 414.495221 -398.140111) (xy 414.450227 -398.116557) (xy 414.409584 -398.086103) (xy 414.374341 -398.049536)
			(xy 414.345406 -398.007797) (xy 414.323527 -397.961965) (xy 414.31591 -397.937736) (xy 414.314386 -397.931894)
			(xy 413.994092 -397.378174) (xy 413.990028 -397.373856) (xy 413.97383 -397.356143) (xy 413.946403 -397.316754)
			(xy 413.925259 -397.273666) (xy 413.910884 -397.227873) (xy 413.903611 -397.18043) (xy 413.90316 -397.156432)
			(xy 413.903301 -397.14438) (xy 413.905208 -397.12035) (xy 413.90697 -397.108426) (xy 413.90824 -397.099536)
			(xy 413.905192 -397.082518) (xy 413.863028 -397.011652) (xy 413.84982 -397.000476) (xy 413.841438 -396.997428)
			(xy 413.819683 -396.98905) (xy 413.778826 -396.966605) (xy 413.741856 -396.938208) (xy 413.709635 -396.90452)
			(xy 413.682911 -396.866324) (xy 413.662306 -396.824508) (xy 413.648299 -396.780046) (xy 413.641216 -396.73397)
			(xy 413.640778 -396.710662) (xy 413.641311 -396.685267) (xy 413.649719 -396.635179) (xy 413.666298 -396.587172)
			(xy 413.690591 -396.542569) (xy 413.721927 -396.502599) (xy 413.740346 -396.48511) (xy 413.748728 -396.47749)
			(xy 413.757364 -396.457424) (xy 413.75457 -396.35811) (xy 413.745172 -396.338552) (xy 413.736282 -396.33144)
			(xy 413.717751 -396.315605) (xy 413.685028 -396.279482) (xy 413.657956 -396.23895) (xy 413.637121 -396.194887)
			(xy 413.622972 -396.148245) (xy 413.615816 -396.100032) (xy 413.615378 -396.075662) (xy 413.615787 -396.051544)
			(xy 413.622795 -396.00382) (xy 413.636656 -395.957619) (xy 413.657078 -395.91392) (xy 413.669988 -395.893544)
			(xy 413.67583 -395.884654) (xy 413.679386 -395.864588) (xy 413.658304 -395.772386) (xy 413.646112 -395.755622)
			(xy 413.637222 -395.750288) (xy 413.616445 -395.737396) (xy 413.578536 -395.706515) (xy 413.54559 -395.670387)
			(xy 413.518325 -395.6298) (xy 413.497336 -395.585639) (xy 413.48308 -395.538869) (xy 413.475869 -395.490509)
			(xy 413.475424 -395.466062) (xy 413.475963 -395.438777) (xy 413.484915 -395.384946) (xy 413.502585 -395.333316)
			(xy 413.528495 -395.28529) (xy 413.56194 -395.24217) (xy 413.581596 -395.223238) (xy 413.588982 -395.215704)
			(xy 413.597515 -395.196433) (xy 413.598106 -395.1859) (xy 413.598106 -395.111224) (xy 413.597576 -395.100675)
			(xy 413.589041 -395.081379) (xy 413.581596 -395.073886) (xy 413.561973 -395.054923) (xy 413.528536 -395.011806)
			(xy 413.502628 -394.963786) (xy 413.484952 -394.912165) (xy 413.475987 -394.858343) (xy 413.475424 -394.831062)
			(xy 413.475678 -394.81887) (xy 413.475932 -394.809218) (xy 413.469836 -394.791184) (xy 413.411162 -394.723874)
			(xy 413.394398 -394.715238) (xy 413.384746 -394.714222) (xy 413.357838 -394.710862) (xy 413.305552 -394.696496)
			(xy 413.256308 -394.673795) (xy 413.211426 -394.643368) (xy 413.172106 -394.606029) (xy 413.139402 -394.562778)
			(xy 413.114189 -394.514773) (xy 413.097142 -394.463298) (xy 413.092392 -394.4366) (xy 413.090868 -394.427202)
			(xy 412.818072 -393.95527) (xy 412.810706 -393.949428) (xy 412.791961 -393.93359) (xy 412.75884 -393.89738)
			(xy 412.731427 -393.85668) (xy 412.71032 -393.812379) (xy 412.695983 -393.765448) (xy 412.688729 -393.716916)
			(xy 412.688278 -393.69238) (xy 412.171194 -393.69238) (xy 412.4198 -394.122402) (xy 412.427166 -394.128244)
			(xy 412.445961 -394.144026) (xy 412.479075 -394.180249) (xy 412.50648 -394.220962) (xy 412.527578 -394.265273)
			(xy 412.541905 -394.312213) (xy 412.549149 -394.360753) (xy 412.549594 -394.385292) (xy 412.54934 -394.397484)
			(xy 412.549086 -394.407136) (xy 412.555182 -394.42517) (xy 412.613856 -394.49248) (xy 412.63062 -394.501116)
			(xy 412.640526 -394.502132) (xy 412.667291 -394.50547) (xy 412.719314 -394.519696) (xy 412.76834 -394.542175)
			(xy 412.813069 -394.57231) (xy 412.852316 -394.609303) (xy 412.885041 -394.652174) (xy 412.910377 -394.699786)
			(xy 412.927652 -394.750878) (xy 412.936409 -394.804095) (xy 412.936944 -394.831062) (xy 412.936399 -394.858347)
			(xy 412.927445 -394.912176) (xy 412.909775 -394.963805) (xy 412.883868 -395.011832) (xy 412.850426 -395.054953)
			(xy 412.830772 -395.073886) (xy 412.823385 -395.08142) (xy 412.81485 -395.10069) (xy 412.814262 -395.111224)
			(xy 412.814262 -395.1859) (xy 412.814789 -395.19645) (xy 412.823327 -395.215744) (xy 412.830772 -395.223238)
			(xy 412.850419 -395.242177) (xy 412.88385 -395.285302) (xy 412.909753 -395.333328) (xy 412.927423 -395.384954)
			(xy 412.936383 -395.438779) (xy 412.936944 -395.466062) (xy 412.936495 -395.490178) (xy 412.929499 -395.5379)
			(xy 412.915649 -395.584101) (xy 412.895239 -395.627802) (xy 412.882334 -395.64818) (xy 412.876492 -395.65707)
			(xy 412.872936 -395.677136) (xy 412.894018 -395.769338) (xy 412.90621 -395.786102) (xy 412.9151 -395.791436)
			(xy 412.935893 -395.804303) (xy 412.9738 -395.835189) (xy 413.006745 -395.871322) (xy 413.034008 -395.911913)
			(xy 413.054994 -395.956077) (xy 413.069247 -396.002851) (xy 413.076455 -396.051214) (xy 413.076898 -396.075662)
			(xy 413.076478 -396.100035) (xy 413.069332 -396.148255) (xy 413.055189 -396.194904) (xy 413.034356 -396.238974)
			(xy 413.007283 -396.279511) (xy 412.974555 -396.315638) (xy 412.955994 -396.33144) (xy 412.947104 -396.338552)
			(xy 412.937706 -396.35811) (xy 412.934912 -396.457424) (xy 412.943548 -396.47749) (xy 412.95193 -396.48511)
			(xy 412.970374 -396.502577) (xy 413.001722 -396.542546) (xy 413.026021 -396.587153) (xy 413.042598 -396.635168)
			(xy 413.050998 -396.685264) (xy 413.051498 -396.710662) (xy 413.05143 -396.720021) (xy 413.050286 -396.738703)
			(xy 413.049212 -396.748) (xy 413.048196 -396.75689) (xy 413.052006 -396.773654) (xy 413.095948 -396.843504)
			(xy 413.109664 -396.853918) (xy 413.118046 -396.856712) (xy 413.142076 -396.865177) (xy 413.187248 -396.88873)
			(xy 413.228052 -396.91923) (xy 413.263431 -396.955886) (xy 413.292467 -396.997746) (xy 413.314405 -397.043724)
			(xy 413.322008 -397.06804) (xy 413.323532 -397.073882) (xy 413.643826 -397.627602) (xy 413.64789 -397.63192)
			(xy 413.664093 -397.649616) (xy 413.691453 -397.689029) (xy 413.712535 -397.732129) (xy 413.726852 -397.777922)
			(xy 413.734076 -397.825354) (xy 413.734504 -397.849344) (xy 413.734023 -397.874133) (xy 413.726261 -397.9231)
			(xy 413.710937 -397.97025) (xy 413.688426 -398.014423) (xy 413.659283 -398.054532) (xy 413.624226 -398.089588)
			(xy 413.584116 -398.11873) (xy 413.539943 -398.14124) (xy 413.492792 -398.156563) (xy 413.443825 -398.164323)
			(xy 413.419036 -398.164812) (xy 413.393643 -398.16428) (xy 413.343511 -398.156155) (xy 413.295326 -398.140109)
			(xy 413.250331 -398.116555) (xy 413.209688 -398.086102) (xy 413.174445 -398.049535) (xy 413.14551 -398.007797)
			(xy 413.123631 -397.961965) (xy 413.116014 -397.937736) (xy 413.11449 -397.931894) (xy 412.794196 -397.378174)
			(xy 412.790132 -397.373856) (xy 412.773917 -397.356158) (xy 412.746497 -397.316763) (xy 412.725358 -397.273671)
			(xy 412.710986 -397.227875) (xy 412.703714 -397.180431) (xy 412.703264 -397.156432) (xy 412.703405 -397.14438)
			(xy 412.705312 -397.12035) (xy 412.707074 -397.108426) (xy 412.708344 -397.099536) (xy 412.705296 -397.082518)
			(xy 412.663132 -397.011652) (xy 412.649924 -397.000476) (xy 412.641542 -396.997428) (xy 412.619788 -396.989048)
			(xy 412.57893 -396.966604) (xy 412.541961 -396.938207) (xy 412.509739 -396.904519) (xy 412.483015 -396.866324)
			(xy 412.46241 -396.824508) (xy 412.448403 -396.780046) (xy 412.44132 -396.73397) (xy 412.440882 -396.710662)
			(xy 412.441414 -396.685267) (xy 412.449822 -396.635179) (xy 412.466401 -396.587172) (xy 412.490694 -396.542569)
			(xy 412.522031 -396.502599) (xy 412.54045 -396.48511) (xy 412.548832 -396.47749) (xy 412.557468 -396.457424)
			(xy 412.554674 -396.35811) (xy 412.545276 -396.338552) (xy 412.536386 -396.33144) (xy 412.517856 -396.315604)
			(xy 412.485133 -396.279481) (xy 412.458061 -396.23895) (xy 412.437225 -396.194887) (xy 412.423076 -396.148245)
			(xy 412.41592 -396.100032) (xy 412.415482 -396.075662) (xy 412.415891 -396.051544) (xy 412.422898 -396.00382)
			(xy 412.43676 -395.957619) (xy 412.457182 -395.91392) (xy 412.470092 -395.893544) (xy 412.475934 -395.884654)
			(xy 412.47949 -395.864588) (xy 412.458408 -395.772386) (xy 412.446216 -395.755622) (xy 412.437326 -395.750288)
			(xy 412.416527 -395.737431) (xy 412.378623 -395.70654) (xy 412.345682 -395.670404) (xy 412.318421 -395.629811)
			(xy 412.297436 -395.585647) (xy 412.283183 -395.538873) (xy 412.275973 -395.49051) (xy 412.275528 -395.466062)
			(xy 412.276066 -395.438777) (xy 412.285018 -395.384946) (xy 412.302688 -395.333316) (xy 412.328598 -395.285289)
			(xy 412.362043 -395.24217) (xy 412.3817 -395.223238) (xy 412.389087 -395.215704) (xy 412.39762 -395.196433)
			(xy 412.39821 -395.1859) (xy 412.39821 -395.111224) (xy 412.397678 -395.100675) (xy 412.389145 -395.08138)
			(xy 412.3817 -395.073886) (xy 412.362078 -395.054922) (xy 412.32864 -395.011806) (xy 412.302732 -394.963786)
			(xy 412.285056 -394.912165) (xy 412.276091 -394.858343) (xy 412.275528 -394.831062) (xy 412.275782 -394.81887)
			(xy 412.276036 -394.809218) (xy 412.26994 -394.791184) (xy 412.211266 -394.723874) (xy 412.194502 -394.715238)
			(xy 412.184596 -394.714222) (xy 412.157693 -394.710822) (xy 412.105408 -394.696464) (xy 412.056164 -394.67377)
			(xy 412.011281 -394.643349) (xy 411.97196 -394.606016) (xy 411.939255 -394.562769) (xy 411.91404 -394.514768)
			(xy 411.896992 -394.463297) (xy 411.892242 -394.4366) (xy 411.890718 -394.427202) (xy 411.617668 -393.954762)
			(xy 411.610556 -393.94892) (xy 411.591815 -393.93315) (xy 411.558763 -393.897005) (xy 411.531408 -393.856377)
			(xy 411.510351 -393.812157) (xy 411.496052 -393.765312) (xy 411.488825 -393.716869) (xy 411.488382 -393.69238)
			(xy 410.971334 -393.69238) (xy 411.219904 -394.122402) (xy 411.22727 -394.128244) (xy 411.246066 -394.144025)
			(xy 411.279179 -394.180248) (xy 411.306585 -394.220961) (xy 411.327682 -394.265273) (xy 411.342009 -394.312213)
			(xy 411.349253 -394.360753) (xy 411.349698 -394.385292) (xy 411.349444 -394.397484) (xy 411.34919 -394.407136)
			(xy 411.355286 -394.42517) (xy 411.41396 -394.49248) (xy 411.430724 -394.501116) (xy 411.44063 -394.502132)
			(xy 411.467395 -394.505467) (xy 411.519419 -394.519694) (xy 411.568444 -394.542173) (xy 411.613173 -394.572308)
			(xy 411.65242 -394.609302) (xy 411.685145 -394.652173) (xy 411.710481 -394.699785) (xy 411.727756 -394.750877)
			(xy 411.736513 -394.804095) (xy 411.737048 -394.831062) (xy 411.736502 -394.858346) (xy 411.727548 -394.912176)
			(xy 411.709878 -394.963804) (xy 411.683971 -395.011831) (xy 411.65053 -395.054953) (xy 411.630876 -395.073886)
			(xy 411.62349 -395.081421) (xy 411.614954 -395.10069) (xy 411.614366 -395.111224) (xy 411.614366 -395.1859)
			(xy 411.614892 -395.19645) (xy 411.62343 -395.215744) (xy 411.630876 -395.223238) (xy 411.650524 -395.242176)
			(xy 411.683955 -395.285301) (xy 411.709857 -395.333328) (xy 411.727527 -395.384954) (xy 411.736487 -395.438779)
			(xy 411.737048 -395.466062) (xy 411.736598 -395.490178) (xy 411.729602 -395.5379) (xy 411.715752 -395.584101)
			(xy 411.695343 -395.627802) (xy 411.682438 -395.64818) (xy 411.676596 -395.65707) (xy 411.67304 -395.677136)
			(xy 411.694122 -395.769338) (xy 411.706314 -395.786102) (xy 411.715204 -395.791436) (xy 411.735998 -395.804302)
			(xy 411.773905 -395.835188) (xy 411.806849 -395.871321) (xy 411.834112 -395.911913) (xy 411.855098 -395.956077)
			(xy 411.869351 -396.002851) (xy 411.876559 -396.051214) (xy 411.877002 -396.075662) (xy 411.87658 -396.100035)
			(xy 411.869435 -396.148255) (xy 411.855292 -396.194904) (xy 411.834459 -396.238974) (xy 411.807386 -396.279511)
			(xy 411.774659 -396.315638) (xy 411.756098 -396.33144) (xy 411.747208 -396.338552) (xy 411.73781 -396.35811)
			(xy 411.735016 -396.457424) (xy 411.743652 -396.47749) (xy 411.752034 -396.48511) (xy 411.770479 -396.502576)
			(xy 411.801827 -396.542545) (xy 411.826125 -396.587153) (xy 411.842702 -396.635167) (xy 411.851102 -396.685264)
			(xy 411.851602 -396.710662) (xy 411.851534 -396.720021) (xy 411.85039 -396.738703) (xy 411.849316 -396.748)
			(xy 411.8483 -396.75689) (xy 411.85211 -396.773654) (xy 411.896052 -396.843504) (xy 411.909768 -396.853918)
			(xy 411.91815 -396.856712) (xy 411.942238 -396.865219) (xy 411.98753 -396.888837) (xy 412.028427 -396.919442)
			(xy 412.06386 -396.956235) (xy 412.092905 -396.998254) (xy 412.114803 -397.044402) (xy 412.122366 -397.068802)
			(xy 412.12389 -397.074644) (xy 412.443676 -397.627602) (xy 412.44774 -397.63192) (xy 412.463938 -397.649633)
			(xy 412.491362 -397.689023) (xy 412.512505 -397.732111) (xy 412.52688 -397.777904) (xy 412.534156 -397.825346)
			(xy 412.534608 -397.849344) (xy 412.534147 -397.874147) (xy 412.526377 -397.923142) (xy 412.511036 -397.970318)
			(xy 412.488501 -398.014511) (xy 412.459329 -398.054634) (xy 412.424237 -398.089697) (xy 412.384091 -398.118836)
			(xy 412.339879 -398.141335) (xy 412.292691 -398.156637) (xy 412.24369 -398.164367) (xy 412.218886 -398.164812)
			(xy 412.193491 -398.164324) (xy 412.143357 -398.156191) (xy 412.095171 -398.140138) (xy 412.050177 -398.116577)
			(xy 412.009534 -398.086118) (xy 411.974292 -398.049546) (xy 411.945358 -398.007803) (xy 411.92348 -397.961967)
			(xy 411.915864 -397.937736) (xy 411.91434 -397.931894) (xy 411.593792 -397.377412) (xy 411.589728 -397.373094)
			(xy 411.573621 -397.355428) (xy 411.546374 -397.316148) (xy 411.525364 -397.273206) (xy 411.511073 -397.227587)
			(xy 411.503826 -397.180334) (xy 411.503368 -397.156432) (xy 411.50351 -397.14438) (xy 411.505416 -397.12035)
			(xy 411.507178 -397.108426) (xy 411.508448 -397.099536) (xy 411.5054 -397.082518) (xy 411.463236 -397.011652)
			(xy 411.450028 -397.000476) (xy 411.441646 -396.997428) (xy 411.419893 -396.989046) (xy 411.379035 -396.966602)
			(xy 411.342066 -396.938206) (xy 411.309844 -396.904518) (xy 411.283119 -396.866323) (xy 411.262514 -396.824508)
			(xy 411.248507 -396.780045) (xy 411.241424 -396.73397) (xy 411.240986 -396.710662) (xy 411.241516 -396.685267)
			(xy 411.249925 -396.635179) (xy 411.266504 -396.587171) (xy 411.290797 -396.542569) (xy 411.322135 -396.502599)
			(xy 411.340554 -396.48511) (xy 411.348936 -396.47749) (xy 411.357572 -396.457424) (xy 411.354778 -396.35811)
			(xy 411.34538 -396.338552) (xy 411.33649 -396.33144) (xy 411.31796 -396.315603) (xy 411.285237 -396.27948)
			(xy 411.258165 -396.238949) (xy 411.237329 -396.194887) (xy 411.22318 -396.148245) (xy 411.216024 -396.100032)
			(xy 411.215586 -396.075662) (xy 411.215994 -396.051544) (xy 411.223002 -396.00382) (xy 411.236864 -395.957619)
			(xy 411.257286 -395.91392) (xy 411.270196 -395.893544) (xy 411.276038 -395.884654) (xy 411.279594 -395.864588)
			(xy 411.258512 -395.772386) (xy 411.24632 -395.755622) (xy 411.23743 -395.750288) (xy 411.216632 -395.737429)
			(xy 411.178728 -395.706539) (xy 411.145786 -395.670403) (xy 411.118526 -395.629811) (xy 411.09754 -395.585646)
			(xy 411.083287 -395.538873) (xy 411.076077 -395.49051) (xy 411.075632 -395.466062) (xy 411.076169 -395.438777)
			(xy 411.08512 -395.384946) (xy 411.102791 -395.333316) (xy 411.128702 -395.285289) (xy 411.162147 -395.24217)
			(xy 411.181804 -395.223238) (xy 411.189191 -395.215705) (xy 411.197724 -395.196433) (xy 411.198314 -395.1859)
			(xy 411.198314 -395.111224) (xy 411.197781 -395.100675) (xy 411.189248 -395.08138) (xy 411.181804 -395.073886)
			(xy 411.162164 -395.05494) (xy 411.128733 -395.011816) (xy 411.10283 -394.963792) (xy 411.085158 -394.912168)
			(xy 411.076195 -394.858344) (xy 411.075632 -394.831062) (xy 411.075886 -394.81887) (xy 411.07614 -394.809218)
			(xy 411.070044 -394.791184) (xy 411.01137 -394.723874) (xy 410.994606 -394.715238) (xy 410.9847 -394.714222)
			(xy 410.957798 -394.710819) (xy 410.905512 -394.696461) (xy 410.856269 -394.673768) (xy 410.811386 -394.643348)
			(xy 410.772065 -394.606015) (xy 410.739359 -394.562769) (xy 410.714145 -394.514767) (xy 410.697096 -394.463297)
			(xy 410.692346 -394.4366) (xy 410.690822 -394.427202) (xy 410.418026 -393.95527) (xy 410.41066 -393.949428)
			(xy 410.391905 -393.933601) (xy 410.358787 -393.897388) (xy 410.331376 -393.856685) (xy 410.310272 -393.812382)
			(xy 410.295936 -393.76545) (xy 410.288682 -393.716916) (xy 410.288232 -393.69238) (xy 409.771438 -393.69238)
			(xy 410.020008 -394.122402) (xy 410.027374 -394.128244) (xy 410.046171 -394.144024) (xy 410.079284 -394.180247)
			(xy 410.106689 -394.220961) (xy 410.127786 -394.265273) (xy 410.142113 -394.312213) (xy 410.149357 -394.360753)
			(xy 410.149802 -394.385292) (xy 410.149548 -394.397484) (xy 410.149294 -394.407136) (xy 410.15539 -394.42517)
			(xy 410.214064 -394.49248) (xy 410.230828 -394.501116) (xy 410.24048 -394.502132) (xy 410.26724 -394.505508)
			(xy 410.319262 -394.519727) (xy 410.368288 -394.542199) (xy 410.413018 -394.572329) (xy 410.452266 -394.609317)
			(xy 410.484992 -394.652184) (xy 410.510329 -394.699792) (xy 410.527605 -394.750881) (xy 410.536362 -394.804097)
			(xy 410.536898 -394.831062) (xy 410.536368 -394.858347) (xy 410.527413 -394.912178) (xy 410.50974 -394.963808)
			(xy 410.483829 -395.011834) (xy 410.450383 -395.054954) (xy 410.430726 -395.073886) (xy 410.423332 -395.081414)
			(xy 410.414802 -395.100689) (xy 410.414216 -395.111224) (xy 410.414216 -395.1859) (xy 410.414727 -395.196452)
			(xy 410.423275 -395.215747) (xy 410.430726 -395.223238) (xy 410.450364 -395.242185) (xy 410.483799 -395.285307)
			(xy 410.509704 -395.333331) (xy 410.527376 -395.384955) (xy 410.536337 -395.438779) (xy 410.536898 -395.466062)
			(xy 410.536456 -395.490179) (xy 410.529459 -395.537901) (xy 410.515607 -395.584102) (xy 410.495194 -395.627803)
			(xy 410.482288 -395.64818) (xy 410.476446 -395.65707) (xy 410.47289 -395.677136) (xy 410.493972 -395.769338)
			(xy 410.506164 -395.786102) (xy 410.515054 -395.791436) (xy 410.53586 -395.804284) (xy 410.573764 -395.835175)
			(xy 410.606706 -395.871312) (xy 410.633966 -395.911907) (xy 410.654951 -395.956073) (xy 410.669202 -396.002849)
			(xy 410.676409 -396.051213) (xy 410.676852 -396.075662) (xy 410.676448 -396.100036) (xy 410.669301 -396.148257)
			(xy 410.655157 -396.194908) (xy 410.63432 -396.238978) (xy 410.607243 -396.279514) (xy 410.574512 -396.315639)
			(xy 410.555948 -396.33144) (xy 410.547058 -396.338552) (xy 410.53766 -396.35811) (xy 410.534866 -396.457424)
			(xy 410.543502 -396.47749) (xy 410.551884 -396.48511) (xy 410.570339 -396.502566) (xy 410.601683 -396.542539)
			(xy 410.625979 -396.587149) (xy 410.642554 -396.635166) (xy 410.650953 -396.685263) (xy 410.651452 -396.710662)
			(xy 410.651383 -396.720021) (xy 410.65024 -396.738703) (xy 410.649166 -396.748) (xy 410.64815 -396.75689)
			(xy 410.65196 -396.773654) (xy 410.695902 -396.843504) (xy 410.709618 -396.853918) (xy 410.718 -396.856712)
			(xy 410.74202 -396.865201) (xy 410.787194 -396.888748) (xy 410.828 -396.919243) (xy 410.863381 -396.955894)
			(xy 410.892418 -396.99775) (xy 410.914358 -397.043726) (xy 410.921962 -397.06804) (xy 410.923486 -397.073882)
			(xy 411.24378 -397.627602) (xy 411.247844 -397.63192) (xy 411.264043 -397.649632) (xy 411.291466 -397.689023)
			(xy 411.312609 -397.732111) (xy 411.326984 -397.777904) (xy 411.33426 -397.825346) (xy 411.334712 -397.849344)
			(xy 411.334247 -397.874147) (xy 411.326477 -397.923142) (xy 411.311136 -397.970317) (xy 411.288602 -398.01451)
			(xy 411.25943 -398.054632) (xy 411.224339 -398.089695) (xy 411.184193 -398.118835) (xy 411.139982 -398.141334)
			(xy 411.092794 -398.156637) (xy 411.043794 -398.164367) (xy 411.01899 -398.164812) (xy 410.993595 -398.16432)
			(xy 410.943461 -398.156188) (xy 410.895276 -398.140135) (xy 410.850281 -398.116576) (xy 410.809639 -398.086117)
			(xy 410.774396 -398.049545) (xy 410.745463 -398.007803) (xy 410.723585 -397.961967) (xy 410.715968 -397.937736)
			(xy 410.714444 -397.931894) (xy 410.39415 -397.378174) (xy 410.390086 -397.373856) (xy 410.373932 -397.356117)
			(xy 410.346562 -397.316717) (xy 410.32547 -397.273629) (xy 410.311141 -397.227844) (xy 410.303906 -397.180419)
			(xy 410.303472 -397.156432) (xy 410.303552 -397.144384) (xy 410.305335 -397.120355) (xy 410.307028 -397.108426)
			(xy 410.308298 -397.099536) (xy 410.30525 -397.082518) (xy 410.263086 -397.011652) (xy 410.249878 -397.000476)
			(xy 410.241496 -396.997428) (xy 410.219754 -396.989019) (xy 410.178895 -396.966581) (xy 410.141923 -396.93819)
			(xy 410.109699 -396.904507) (xy 410.082973 -396.866315) (xy 410.062366 -396.824503) (xy 410.048358 -396.780043)
			(xy 410.041274 -396.733969) (xy 410.040836 -396.710662) (xy 410.04135 -396.685266) (xy 410.04976 -396.635176)
			(xy 410.066343 -396.587168) (xy 410.09064 -396.542565) (xy 410.121982 -396.502598) (xy 410.140404 -396.48511)
			(xy 410.148786 -396.47749) (xy 410.157422 -396.457424) (xy 410.154628 -396.35811) (xy 410.14523 -396.338552)
			(xy 410.13634 -396.33144) (xy 410.1178 -396.315615) (xy 410.08508 -396.279488) (xy 410.058011 -396.238954)
			(xy 410.037177 -396.19489) (xy 410.023029 -396.148246) (xy 410.015874 -396.100033) (xy 410.015436 -396.075662)
			(xy 410.015852 -396.051545) (xy 410.022859 -396.003821) (xy 410.036718 -395.95762) (xy 410.057137 -395.913921)
			(xy 410.070046 -395.893544) (xy 410.075888 -395.884654) (xy 410.079444 -395.864588) (xy 410.058362 -395.772386)
			(xy 410.04617 -395.755622) (xy 410.03728 -395.750288) (xy 410.016493 -395.737411) (xy 409.978587 -395.706526)
			(xy 409.945643 -395.670394) (xy 409.91838 -395.629805) (xy 409.897392 -395.585643) (xy 409.883137 -395.538871)
			(xy 409.875927 -395.49051) (xy 409.875482 -395.466062) (xy 409.876034 -395.438778) (xy 409.884985 -395.384948)
			(xy 409.902653 -395.333319) (xy 409.928559 -395.285292) (xy 409.962 -395.242171) (xy 409.981654 -395.223238)
			(xy 409.989034 -395.215698) (xy 409.997572 -395.196432) (xy 409.998164 -395.1859) (xy 409.998164 -395.111224)
			(xy 409.997646 -395.100673) (xy 409.989104 -395.081377) (xy 409.981654 -395.073886) (xy 409.962024 -395.054931)
			(xy 409.928589 -395.011811) (xy 409.902683 -394.963789) (xy 409.885009 -394.912167) (xy 409.876045 -394.858344)
			(xy 409.875482 -394.831062) (xy 409.875736 -394.81887) (xy 409.87599 -394.809218) (xy 409.869894 -394.791184)
			(xy 409.81122 -394.723874) (xy 409.794456 -394.715238) (xy 409.784804 -394.714222) (xy 409.757902 -394.710816)
			(xy 409.705617 -394.696458) (xy 409.656373 -394.673766) (xy 409.61149 -394.643346) (xy 409.572169 -394.606014)
			(xy 409.539463 -394.562768) (xy 409.514249 -394.514767) (xy 409.4972 -394.463296) (xy 409.49245 -394.4366)
			(xy 409.490926 -394.427202) (xy 409.21813 -393.95527) (xy 409.210764 -393.949428) (xy 409.19201 -393.9336)
			(xy 409.158892 -393.897388) (xy 409.13148 -393.856684) (xy 409.110376 -393.812382) (xy 409.09604 -393.76545)
			(xy 409.088786 -393.716916) (xy 409.088336 -393.69238) (xy 408.571288 -393.69238) (xy 408.819858 -394.122402)
			(xy 408.827224 -394.128244) (xy 408.84601 -394.144036) (xy 408.879127 -394.180255) (xy 408.906534 -394.220966)
			(xy 408.927634 -394.265276) (xy 408.941962 -394.312214) (xy 408.949207 -394.360754) (xy 408.949652 -394.385292)
			(xy 408.949398 -394.397484) (xy 408.949144 -394.407136) (xy 408.95524 -394.42517) (xy 409.013914 -394.49248)
			(xy 409.030678 -394.501116) (xy 409.040584 -394.502132) (xy 409.067344 -394.505504) (xy 409.119367 -394.519724)
			(xy 409.168393 -394.542197) (xy 409.213122 -394.572327) (xy 409.25237 -394.609316) (xy 409.285096 -394.652183)
			(xy 409.310433 -394.699792) (xy 409.327709 -394.750881) (xy 409.336466 -394.804097) (xy 409.337002 -394.831062)
			(xy 409.336576 -394.855264) (xy 409.329503 -394.903149) (xy 409.315517 -394.949488) (xy 409.294917 -394.99329)
			(xy 409.281884 -395.013688) (xy 409.277097 -395.021645) (xy 409.273062 -395.039756) (xy 409.27401 -395.048994)
			(xy 409.278328 -395.079982) (xy 409.280001 -395.08928) (xy 409.289288 -395.105722) (xy 409.296362 -395.111986)
			(xy 409.31845 -395.130668) (xy 409.358222 -395.17268) (xy 409.392384 -395.219368) (xy 409.420391 -395.269988)
			(xy 409.441799 -395.323733) (xy 409.456264 -395.379746) (xy 409.463557 -395.437136) (xy 409.464002 -395.466062)
			(xy 409.463416 -395.499384) (xy 409.453752 -395.565322) (xy 409.434625 -395.629161) (xy 409.421076 -395.65961)
			(xy 409.416829 -395.670075) (xy 409.416943 -395.692634) (xy 409.426676 -395.712985) (xy 409.435046 -395.72057)
			(xy 409.457265 -395.739276) (xy 409.497332 -395.781324) (xy 409.531757 -395.828104) (xy 409.559986 -395.878864)
			(xy 409.581566 -395.932787) (xy 409.59615 -395.989008) (xy 409.603503 -396.046621) (xy 409.603956 -396.075662)
			(xy 409.603478 -396.104667) (xy 409.596167 -396.162214) (xy 409.581645 -396.218376) (xy 409.560145 -396.272255)
			(xy 409.532011 -396.322985) (xy 409.497694 -396.369755) (xy 409.457743 -396.411815) (xy 409.435554 -396.4305)
			(xy 409.428442 -396.436088) (xy 409.419298 -396.451328) (xy 409.404058 -396.534132) (xy 409.406852 -396.551404)
			(xy 409.411424 -396.559532) (xy 409.423998 -396.582719) (xy 409.441873 -396.63234) (xy 409.450974 -396.684291)
			(xy 409.451556 -396.710662) (xy 409.451487 -396.720021) (xy 409.450344 -396.738703) (xy 409.44927 -396.748)
			(xy 409.448254 -396.75689) (xy 409.452064 -396.773654) (xy 409.496006 -396.843504) (xy 409.509722 -396.853918)
			(xy 409.518104 -396.856712) (xy 409.542125 -396.865199) (xy 409.587298 -396.888747) (xy 409.628105 -396.919242)
			(xy 409.663485 -396.955893) (xy 409.692522 -396.99775) (xy 409.714462 -397.043725) (xy 409.722066 -397.06804)
			(xy 409.72359 -397.073882) (xy 410.043884 -397.627602) (xy 410.047948 -397.63192) (xy 410.064148 -397.649631)
			(xy 410.091571 -397.689022) (xy 410.112713 -397.732111) (xy 410.127088 -397.777904) (xy 410.134364 -397.825346)
			(xy 410.134816 -397.849344) (xy 410.134347 -397.874147) (xy 410.126577 -397.923141) (xy 410.111237 -397.970316)
			(xy 410.088703 -398.014509) (xy 410.059531 -398.054631) (xy 410.02444 -398.089694) (xy 409.984295 -398.118834)
			(xy 409.940084 -398.141332) (xy 409.892898 -398.156636) (xy 409.843897 -398.164366) (xy 409.819094 -398.164812)
			(xy 409.793699 -398.164317) (xy 409.743566 -398.156185) (xy 409.69538 -398.140133) (xy 409.650386 -398.116574)
			(xy 409.609743 -398.086116) (xy 409.5745 -398.049544) (xy 409.545567 -398.007802) (xy 409.523689 -397.961967)
			(xy 409.516072 -397.937736) (xy 409.514548 -397.931894) (xy 409.194254 -397.378174) (xy 409.19019 -397.373856)
			(xy 409.174037 -397.356117) (xy 409.146666 -397.316717) (xy 409.125574 -397.273628) (xy 409.111245 -397.227844)
			(xy 409.10401 -397.180419) (xy 409.103576 -397.156432) (xy 409.103656 -397.144384) (xy 409.105439 -397.120355)
			(xy 409.107132 -397.108426) (xy 409.108402 -397.099536) (xy 409.105354 -397.082518) (xy 409.06319 -397.011652)
			(xy 409.049982 -397.000476) (xy 409.0416 -396.997428) (xy 409.019859 -396.989016) (xy 408.978999 -396.966579)
			(xy 408.942028 -396.938189) (xy 408.909804 -396.904506) (xy 408.883077 -396.866315) (xy 408.86247 -396.824502)
			(xy 408.848462 -396.780042) (xy 408.841378 -396.733969) (xy 408.84094 -396.710662) (xy 408.841501 -396.684289)
			(xy 408.850585 -396.63233) (xy 408.868476 -396.58271) (xy 408.881072 -396.559532) (xy 408.885644 -396.551404)
			(xy 408.888438 -396.534132) (xy 408.873198 -396.451328) (xy 408.864054 -396.436088) (xy 408.856942 -396.4305)
			(xy 408.83478 -396.411784) (xy 408.794831 -396.369725) (xy 408.760511 -396.32296) (xy 408.732371 -396.272235)
			(xy 408.71086 -396.218364) (xy 408.696322 -396.162208) (xy 408.688991 -396.104666) (xy 408.68854 -396.075662)
			(xy 408.68914 -396.042341) (xy 408.698799 -395.976403) (xy 408.717921 -395.912563) (xy 408.731466 -395.882114)
			(xy 408.73571 -395.871646) (xy 408.735605 -395.849087) (xy 408.725869 -395.828736) (xy 408.717496 -395.821154)
			(xy 408.695228 -395.802504) (xy 408.655166 -395.760444) (xy 408.620748 -395.713654) (xy 408.592526 -395.662885)
			(xy 408.570953 -395.608953) (xy 408.556378 -395.552725) (xy 408.549034 -395.495105) (xy 408.548586 -395.466062)
			(xy 408.549025 -395.437135) (xy 408.556309 -395.379742) (xy 408.570769 -395.323724) (xy 408.592175 -395.269976)
			(xy 408.620184 -395.219355) (xy 408.65435 -395.172667) (xy 408.694129 -395.130659) (xy 408.716226 -395.111986)
			(xy 408.723192 -395.105633) (xy 408.732454 -395.089234) (xy 408.73426 -395.079982) (xy 408.738578 -395.048994)
			(xy 408.739477 -395.039757) (xy 408.735455 -395.021658) (xy 408.730704 -395.013688) (xy 408.717717 -394.993265)
			(xy 408.697136 -394.949463) (xy 408.683149 -394.903133) (xy 408.676053 -394.85526) (xy 408.675586 -394.831062)
			(xy 408.67584 -394.81887) (xy 408.676094 -394.809218) (xy 408.669998 -394.791184) (xy 408.611324 -394.723874)
			(xy 408.59456 -394.715238) (xy 408.584654 -394.714222) (xy 408.557747 -394.710855) (xy 408.505461 -394.69649)
			(xy 408.456217 -394.673791) (xy 408.411335 -394.643365) (xy 408.372015 -394.606027) (xy 408.33931 -394.562777)
			(xy 408.314097 -394.514772) (xy 408.29705 -394.463298) (xy 408.2923 -394.4366) (xy 408.290776 -394.427202)
			(xy 408.01798 -393.95527) (xy 408.010614 -393.949428) (xy 407.99187 -393.933588) (xy 407.95875 -393.897379)
			(xy 407.931336 -393.856679) (xy 407.910229 -393.812379) (xy 407.895891 -393.765448) (xy 407.888637 -393.716916)
			(xy 407.888186 -393.69238) (xy 407.371392 -393.69238) (xy 407.619962 -394.122402) (xy 407.627328 -394.128244)
			(xy 407.646115 -394.144035) (xy 407.679231 -394.180255) (xy 407.706639 -394.220966) (xy 407.727738 -394.265276)
			(xy 407.742067 -394.312214) (xy 407.749311 -394.360754) (xy 407.749756 -394.385292) (xy 407.749502 -394.397484)
			(xy 407.749248 -394.407136) (xy 407.755344 -394.42517) (xy 407.814018 -394.49248) (xy 407.830782 -394.501116)
			(xy 407.840434 -394.502132) (xy 407.8672 -394.505464) (xy 407.919223 -394.519691) (xy 407.968249 -394.542171)
			(xy 408.012978 -394.572307) (xy 408.052225 -394.609301) (xy 408.084949 -394.652172) (xy 408.110285 -394.699785)
			(xy 408.12756 -394.750877) (xy 408.136317 -394.804095) (xy 408.136852 -394.831062) (xy 408.136342 -394.857049)
			(xy 408.128212 -394.908384) (xy 408.112151 -394.957814) (xy 408.088555 -395.004124) (xy 408.058005 -395.046172)
			(xy 408.021254 -395.082923) (xy 407.979206 -395.113473) (xy 407.932896 -395.137069) (xy 407.883466 -395.15313)
			(xy 407.832131 -395.16126) (xy 407.780157 -395.16126) (xy 407.728822 -395.15313) (xy 407.679392 -395.137069)
			(xy 407.633082 -395.113473) (xy 407.591034 -395.082923) (xy 407.554283 -395.046172) (xy 407.523733 -395.004124)
			(xy 407.500137 -394.957814) (xy 407.484076 -394.908384) (xy 407.475946 -394.857049) (xy 407.475436 -394.831062)
			(xy 407.47569 -394.81887) (xy 407.475944 -394.809218) (xy 407.469848 -394.791184) (xy 407.411174 -394.723874)
			(xy 407.39441 -394.715238) (xy 407.384758 -394.714222) (xy 407.357851 -394.710852) (xy 407.305565 -394.696488)
			(xy 407.256322 -394.673789) (xy 407.211439 -394.643364) (xy 407.172119 -394.606026) (xy 407.139415 -394.562776)
			(xy 407.114201 -394.514771) (xy 407.097154 -394.463298) (xy 407.092404 -394.4366) (xy 407.09088 -394.427202)
			(xy 406.818084 -393.95527) (xy 406.810718 -393.949428) (xy 406.791975 -393.933587) (xy 406.758854 -393.897379)
			(xy 406.73144 -393.856679) (xy 406.710333 -393.812378) (xy 406.695995 -393.765448) (xy 406.688741 -393.716916)
			(xy 406.68829 -393.69238) (xy 406.171206 -393.69238) (xy 406.419812 -394.122402) (xy 406.427178 -394.128244)
			(xy 406.445955 -394.144047) (xy 406.479073 -394.180263) (xy 406.506484 -394.220971) (xy 406.527585 -394.265279)
			(xy 406.541915 -394.312216) (xy 406.54916 -394.360754) (xy 406.549606 -394.385292) (xy 406.549352 -394.397484)
			(xy 406.549098 -394.407136) (xy 406.555194 -394.42517) (xy 406.613868 -394.49248) (xy 406.630632 -394.501116)
			(xy 406.640538 -394.502132) (xy 406.667304 -394.50546) (xy 406.719328 -394.519689) (xy 406.768353 -394.542169)
			(xy 406.813082 -394.572305) (xy 406.852329 -394.609299) (xy 406.885054 -394.652171) (xy 406.910389 -394.699784)
			(xy 406.927664 -394.750877) (xy 406.936421 -394.804095) (xy 406.936956 -394.831062) (xy 406.936407 -394.858346)
			(xy 406.927454 -394.912175) (xy 406.909784 -394.963804) (xy 406.883878 -395.011831) (xy 406.850438 -395.054952)
			(xy 406.830784 -395.073886) (xy 406.823384 -395.081409) (xy 406.814859 -395.100688) (xy 406.814274 -395.111224)
			(xy 406.814274 -395.1859) (xy 406.814797 -395.19645) (xy 406.823337 -395.215745) (xy 406.830784 -395.223238)
			(xy 406.850433 -395.242175) (xy 406.883864 -395.285301) (xy 406.909765 -395.333327) (xy 406.927435 -395.384953)
			(xy 406.936395 -395.438779) (xy 406.936956 -395.466062) (xy 406.936505 -395.490178) (xy 406.929509 -395.5379)
			(xy 406.91566 -395.584101) (xy 406.89525 -395.627802) (xy 406.882346 -395.64818) (xy 406.876504 -395.65707)
			(xy 406.872948 -395.677136) (xy 406.89403 -395.769338) (xy 406.906222 -395.786102) (xy 406.915112 -395.791436)
			(xy 406.935908 -395.804299) (xy 406.973814 -395.835186) (xy 407.006758 -395.87132) (xy 407.034021 -395.911912)
			(xy 407.055007 -395.956076) (xy 407.069259 -396.00285) (xy 407.076467 -396.051213) (xy 407.07691 -396.075662)
			(xy 407.076485 -396.100035) (xy 407.06934 -396.148254) (xy 407.055198 -396.194904) (xy 407.034365 -396.238974)
			(xy 407.007293 -396.279511) (xy 406.974567 -396.315637) (xy 406.956006 -396.33144) (xy 406.947116 -396.338552)
			(xy 406.937718 -396.35811) (xy 406.934924 -396.457424) (xy 406.94356 -396.47749) (xy 406.951942 -396.48511)
			(xy 406.970388 -396.502575) (xy 407.001736 -396.542544) (xy 407.026033 -396.587152) (xy 407.042611 -396.635167)
			(xy 407.05101 -396.685264) (xy 407.05151 -396.710662) (xy 407.64079 -396.710662) (xy 407.641312 -396.685407)
			(xy 407.649625 -396.635585) (xy 407.666026 -396.587811) (xy 407.690067 -396.543388) (xy 407.721091 -396.503528)
			(xy 407.758253 -396.469318) (xy 407.800539 -396.441692) (xy 407.846795 -396.421402) (xy 407.89576 -396.409002)
			(xy 407.946098 -396.404831) (xy 407.996436 -396.409002) (xy 408.045401 -396.421402) (xy 408.091657 -396.441692)
			(xy 408.133943 -396.469318) (xy 408.171105 -396.503528) (xy 408.202129 -396.543388) (xy 408.22617 -396.587811)
			(xy 408.242571 -396.635585) (xy 408.250884 -396.685407) (xy 408.251406 -396.710662) (xy 408.251337 -396.720021)
			(xy 408.250194 -396.738703) (xy 408.24912 -396.748) (xy 408.248104 -396.75689) (xy 408.251914 -396.773654)
			(xy 408.295856 -396.843504) (xy 408.309572 -396.853918) (xy 408.317954 -396.856712) (xy 408.341985 -396.865172)
			(xy 408.387157 -396.888727) (xy 408.427962 -396.919228) (xy 408.46334 -396.955885) (xy 408.492375 -396.997745)
			(xy 408.514313 -397.043724) (xy 408.521916 -397.06804) (xy 408.52344 -397.073882) (xy 408.843734 -397.627602)
			(xy 408.847798 -397.63192) (xy 408.863986 -397.64963) (xy 408.891352 -397.689037) (xy 408.912438 -397.732133)
			(xy 408.926758 -397.777924) (xy 408.933983 -397.825355) (xy 408.934412 -397.849344) (xy 408.933923 -397.874133)
			(xy 408.926162 -397.923099) (xy 408.910838 -397.970248) (xy 408.888327 -398.014421) (xy 408.859185 -398.054529)
			(xy 408.824129 -398.089585) (xy 408.784021 -398.118727) (xy 408.739848 -398.141238) (xy 408.692699 -398.156562)
			(xy 408.643733 -398.164323) (xy 408.618944 -398.164812) (xy 408.593551 -398.164273) (xy 408.543419 -398.156149)
			(xy 408.495234 -398.140104) (xy 408.45024 -398.116552) (xy 408.409597 -398.086099) (xy 408.374353 -398.049533)
			(xy 408.345419 -398.007796) (xy 408.323539 -397.961965) (xy 408.315922 -397.937736) (xy 408.314398 -397.931894)
			(xy 407.994104 -397.378174) (xy 407.99004 -397.373856) (xy 407.973827 -397.356156) (xy 407.946406 -397.316762)
			(xy 407.925266 -397.27367) (xy 407.910894 -397.227875) (xy 407.903622 -397.180431) (xy 407.903172 -397.156432)
			(xy 407.903314 -397.14438) (xy 407.90522 -397.12035) (xy 407.906982 -397.108426) (xy 407.908252 -397.099536)
			(xy 407.905204 -397.082518) (xy 407.86304 -397.011652) (xy 407.849832 -397.000476) (xy 407.84145 -396.997428)
			(xy 407.819698 -396.989044) (xy 407.77884 -396.9666) (xy 407.74187 -396.938205) (xy 407.709648 -396.904518)
			(xy 407.682924 -396.866322) (xy 407.662318 -396.824507) (xy 407.648311 -396.780045) (xy 407.641228 -396.73397)
			(xy 407.64079 -396.710662) (xy 407.05151 -396.710662) (xy 407.051441 -396.720021) (xy 407.050298 -396.738703)
			(xy 407.049224 -396.748) (xy 407.048208 -396.75689) (xy 407.052018 -396.773654) (xy 407.09596 -396.843504)
			(xy 407.109676 -396.853918) (xy 407.118058 -396.856712) (xy 407.14209 -396.86517) (xy 407.187262 -396.888725)
			(xy 407.228066 -396.919227) (xy 407.263445 -396.955884) (xy 407.292479 -396.997745) (xy 407.314417 -397.043724)
			(xy 407.32202 -397.06804) (xy 407.323544 -397.073882) (xy 407.643838 -397.627602) (xy 407.647902 -397.63192)
			(xy 407.66409 -397.649629) (xy 407.691456 -397.689037) (xy 407.712542 -397.732133) (xy 407.726862 -397.777924)
			(xy 407.734087 -397.825355) (xy 407.734516 -397.849344) (xy 407.734023 -397.874132) (xy 407.726262 -397.923098)
			(xy 407.710938 -397.970247) (xy 407.688428 -398.01442) (xy 407.659287 -398.054528) (xy 407.624231 -398.089584)
			(xy 407.584123 -398.118726) (xy 407.539951 -398.141236) (xy 407.492802 -398.156561) (xy 407.443836 -398.164322)
			(xy 407.419048 -398.164812) (xy 407.393655 -398.164269) (xy 407.343523 -398.156146) (xy 407.295339 -398.140102)
			(xy 407.250345 -398.11655) (xy 407.209701 -398.086098) (xy 407.174458 -398.049532) (xy 407.145523 -398.007796)
			(xy 407.123643 -397.961965) (xy 407.116026 -397.937736) (xy 407.114502 -397.931894) (xy 406.794208 -397.378174)
			(xy 406.790144 -397.373856) (xy 406.773931 -397.356156) (xy 406.746511 -397.316762) (xy 406.72537 -397.27367)
			(xy 406.710999 -397.227875) (xy 406.703726 -397.180431) (xy 406.703276 -397.156432) (xy 406.703418 -397.14438)
			(xy 406.705324 -397.12035) (xy 406.707086 -397.108426) (xy 406.708356 -397.099536) (xy 406.705308 -397.082518)
			(xy 406.663144 -397.011652) (xy 406.649936 -397.000476) (xy 406.641554 -396.997428) (xy 406.619803 -396.989042)
			(xy 406.578945 -396.966599) (xy 406.541975 -396.938203) (xy 406.509753 -396.904517) (xy 406.483028 -396.866322)
			(xy 406.462422 -396.824507) (xy 406.448415 -396.780045) (xy 406.441332 -396.73397) (xy 406.440894 -396.710662)
			(xy 406.441422 -396.685267) (xy 406.449831 -396.635178) (xy 406.46641 -396.587171) (xy 406.490704 -396.542568)
			(xy 406.522042 -396.502599) (xy 406.540462 -396.48511) (xy 406.548844 -396.47749) (xy 406.55748 -396.457424)
			(xy 406.554686 -396.35811) (xy 406.545288 -396.338552) (xy 406.536398 -396.33144) (xy 406.51787 -396.315601)
			(xy 406.485147 -396.279479) (xy 406.458074 -396.238949) (xy 406.437238 -396.194886) (xy 406.423088 -396.148245)
			(xy 406.415932 -396.100032) (xy 406.415494 -396.075662) (xy 406.415901 -396.051544) (xy 406.422909 -396.00382)
			(xy 406.436771 -395.957619) (xy 406.457193 -395.91392) (xy 406.470104 -395.893544) (xy 406.475946 -395.884654)
			(xy 406.479502 -395.864588) (xy 406.45842 -395.772386) (xy 406.446228 -395.755622) (xy 406.437338 -395.750288)
			(xy 406.416541 -395.737427) (xy 406.378637 -395.706537) (xy 406.345696 -395.670402) (xy 406.318434 -395.62981)
			(xy 406.297448 -395.585646) (xy 406.283195 -395.538873) (xy 406.275985 -395.49051) (xy 406.27554 -395.466062)
			(xy 406.276106 -395.438778) (xy 406.285055 -395.38495) (xy 406.302721 -395.333322) (xy 406.328623 -395.285295)
			(xy 406.36206 -395.242172) (xy 406.381712 -395.223238) (xy 406.389101 -395.215706) (xy 406.397632 -395.196434)
			(xy 406.398222 -395.1859) (xy 406.398222 -395.111224) (xy 406.397687 -395.100675) (xy 406.389155 -395.08138)
			(xy 406.381712 -395.073886) (xy 406.362074 -395.054939) (xy 406.328642 -395.011816) (xy 406.302738 -394.963791)
			(xy 406.285066 -394.912168) (xy 406.276103 -394.858344) (xy 406.27554 -394.831062) (xy 406.275794 -394.81887)
			(xy 406.276048 -394.809218) (xy 406.269952 -394.791184) (xy 406.211278 -394.723874) (xy 406.194514 -394.715238)
			(xy 406.184608 -394.714222) (xy 406.157707 -394.710812) (xy 406.105421 -394.696456) (xy 406.056178 -394.673764)
			(xy 406.011295 -394.643345) (xy 405.971973 -394.606013) (xy 405.939268 -394.562767) (xy 405.914053 -394.514767)
			(xy 405.897004 -394.463296) (xy 405.892254 -394.4366) (xy 405.89073 -394.427202) (xy 405.61768 -393.954762)
			(xy 405.610568 -393.94892) (xy 405.59183 -393.933147) (xy 405.558777 -393.897003) (xy 405.531422 -393.856376)
			(xy 405.510364 -393.812156) (xy 405.496064 -393.765311) (xy 405.488837 -393.716869) (xy 405.488394 -393.69238)
			(xy 404.971346 -393.69238) (xy 405.219916 -394.122402) (xy 405.227282 -394.128244) (xy 405.24606 -394.144046)
			(xy 405.279178 -394.180262) (xy 405.306588 -394.22097) (xy 405.327689 -394.265278) (xy 405.342019 -394.312216)
			(xy 405.349264 -394.360754) (xy 405.34971 -394.385292) (xy 405.349456 -394.397484) (xy 405.349202 -394.407136)
			(xy 405.355298 -394.42517) (xy 405.413972 -394.49248) (xy 405.430736 -394.501116) (xy 405.440642 -394.502132)
			(xy 405.467409 -394.505457) (xy 405.519432 -394.519686) (xy 405.568458 -394.542167) (xy 405.613187 -394.572304)
			(xy 405.652433 -394.609298) (xy 405.685158 -394.65217) (xy 405.710493 -394.699783) (xy 405.727768 -394.750876)
			(xy 405.736525 -394.804095) (xy 405.73706 -394.831062) (xy 405.73651 -394.858346) (xy 405.727557 -394.912175)
			(xy 405.709887 -394.963804) (xy 405.683981 -395.011831) (xy 405.650541 -395.054952) (xy 405.630888 -395.073886)
			(xy 405.623489 -395.081409) (xy 405.614963 -395.100688) (xy 405.614378 -395.111224) (xy 405.614378 -395.1859)
			(xy 405.6149 -395.19645) (xy 405.623441 -395.215745) (xy 405.630888 -395.223238) (xy 405.650538 -395.242174)
			(xy 405.683968 -395.2853) (xy 405.70987 -395.333327) (xy 405.727539 -395.384953) (xy 405.736499 -395.438779)
			(xy 405.73706 -395.466062) (xy 405.736608 -395.490178) (xy 405.729612 -395.5379) (xy 405.715763 -395.584101)
			(xy 405.695354 -395.627802) (xy 405.68245 -395.64818) (xy 405.676608 -395.65707) (xy 405.673052 -395.677136)
			(xy 405.694134 -395.769338) (xy 405.706326 -395.786102) (xy 405.715216 -395.791436) (xy 405.736013 -395.804298)
			(xy 405.773919 -395.835185) (xy 405.806863 -395.871319) (xy 405.834125 -395.911911) (xy 405.855111 -395.956076)
			(xy 405.869363 -396.00285) (xy 405.876571 -396.051213) (xy 405.877014 -396.075662) (xy 405.876588 -396.100035)
			(xy 405.869442 -396.148254) (xy 405.855301 -396.194903) (xy 405.834468 -396.238973) (xy 405.807396 -396.27951)
			(xy 405.774671 -396.315637) (xy 405.75611 -396.33144) (xy 405.74722 -396.338552) (xy 405.737822 -396.35811)
			(xy 405.735028 -396.457424) (xy 405.743664 -396.47749) (xy 405.752046 -396.48511) (xy 405.770493 -396.502574)
			(xy 405.801841 -396.542544) (xy 405.826138 -396.587152) (xy 405.842715 -396.635167) (xy 405.851115 -396.685264)
			(xy 405.851614 -396.710662) (xy 405.851545 -396.720021) (xy 405.850402 -396.738703) (xy 405.849328 -396.748)
			(xy 405.848312 -396.75689) (xy 405.852122 -396.773654) (xy 405.896064 -396.843504) (xy 405.90978 -396.853918)
			(xy 405.918162 -396.856712) (xy 405.942252 -396.865212) (xy 405.987544 -396.888832) (xy 406.02844 -396.919439)
			(xy 406.063873 -396.956232) (xy 406.092918 -396.998253) (xy 406.114815 -397.044402) (xy 406.122378 -397.068802)
			(xy 406.123902 -397.074644) (xy 406.443688 -397.627602) (xy 406.447752 -397.63192) (xy 406.463952 -397.649631)
			(xy 406.491375 -397.689022) (xy 406.512518 -397.732111) (xy 406.526892 -397.777904) (xy 406.534168 -397.825346)
			(xy 406.53462 -397.849344) (xy 406.534246 -397.874152) (xy 406.526474 -397.923155) (xy 406.511128 -397.970338)
			(xy 406.488585 -398.014537) (xy 406.459403 -398.054664) (xy 406.4243 -398.089728) (xy 406.384142 -398.118866)
			(xy 406.339918 -398.14136) (xy 406.292718 -398.156655) (xy 406.243706 -398.164374) (xy 406.218898 -398.164812)
			(xy 406.193504 -398.164313) (xy 406.14337 -398.156182) (xy 406.095184 -398.140131) (xy 406.05019 -398.116572)
			(xy 406.009547 -398.086114) (xy 405.974304 -398.049543) (xy 405.945371 -398.007802) (xy 405.923493 -397.961967)
			(xy 405.915876 -397.937736) (xy 405.914352 -397.931894) (xy 405.593804 -397.377412) (xy 405.58974 -397.373094)
			(xy 405.573635 -397.355426) (xy 405.546387 -397.316147) (xy 405.525377 -397.273206) (xy 405.511085 -397.227587)
			(xy 405.503838 -397.180334) (xy 405.50338 -397.156432) (xy 405.503522 -397.14438) (xy 405.505428 -397.12035)
			(xy 405.50719 -397.108426) (xy 405.50846 -397.099536) (xy 405.505412 -397.082518) (xy 405.463248 -397.011652)
			(xy 405.45004 -397.000476) (xy 405.441658 -396.997428) (xy 405.419908 -396.989039) (xy 405.379049 -396.966597)
			(xy 405.342079 -396.938202) (xy 405.309857 -396.904516) (xy 405.283132 -396.866321) (xy 405.262527 -396.824507)
			(xy 405.248519 -396.780045) (xy 405.241436 -396.73397) (xy 405.240998 -396.710662) (xy 405.241524 -396.685267)
			(xy 405.249934 -396.635178) (xy 405.266514 -396.587171) (xy 405.290808 -396.542568) (xy 405.322146 -396.502599)
			(xy 405.340566 -396.48511) (xy 405.348948 -396.47749) (xy 405.357584 -396.457424) (xy 405.35479 -396.35811)
			(xy 405.345392 -396.338552) (xy 405.336502 -396.33144) (xy 405.317975 -396.315601) (xy 405.285251 -396.279479)
			(xy 405.258178 -396.238948) (xy 405.237342 -396.194886) (xy 405.223192 -396.148244) (xy 405.216036 -396.100032)
			(xy 405.215598 -396.075662) (xy 405.216004 -396.051544) (xy 405.223012 -396.00382) (xy 405.236874 -395.957619)
			(xy 405.257297 -395.91392) (xy 405.270208 -395.893544) (xy 405.27605 -395.884654) (xy 405.279606 -395.864588)
			(xy 405.258524 -395.772386) (xy 405.246332 -395.755622) (xy 405.237442 -395.750288) (xy 405.216646 -395.737425)
			(xy 405.178742 -395.706536) (xy 405.1458 -395.670401) (xy 405.118539 -395.629809) (xy 405.097552 -395.585645)
			(xy 405.083299 -395.538872) (xy 405.076089 -395.49051) (xy 405.075644 -395.466062) (xy 405.076209 -395.438778)
			(xy 405.085158 -395.38495) (xy 405.102824 -395.333322) (xy 405.128727 -395.285294) (xy 405.162164 -395.242172)
			(xy 405.181816 -395.223238) (xy 405.189205 -395.215706) (xy 405.197736 -395.196434) (xy 405.198326 -395.1859)
			(xy 405.198326 -395.111224) (xy 405.19779 -395.100675) (xy 405.189259 -395.08138) (xy 405.181816 -395.073886)
			(xy 405.162179 -395.054938) (xy 405.128746 -395.011815) (xy 405.102843 -394.963791) (xy 405.08517 -394.912168)
			(xy 405.076207 -394.858344) (xy 405.075644 -394.831062) (xy 405.075898 -394.81887) (xy 405.076152 -394.809218)
			(xy 405.070056 -394.791184) (xy 405.011382 -394.723874) (xy 404.994618 -394.715238) (xy 404.984712 -394.714222)
			(xy 404.957811 -394.710809) (xy 404.905526 -394.696453) (xy 404.856282 -394.673762) (xy 404.811399 -394.643343)
			(xy 404.772078 -394.606012) (xy 404.739372 -394.562766) (xy 404.714157 -394.514766) (xy 404.697108 -394.463296)
			(xy 404.692358 -394.4366) (xy 404.690834 -394.427202) (xy 404.418038 -393.95527) (xy 404.410672 -393.949428)
			(xy 404.391919 -393.933598) (xy 404.358801 -393.897386) (xy 404.331389 -393.856684) (xy 404.310284 -393.812381)
			(xy 404.295948 -393.76545) (xy 404.288694 -393.716916) (xy 404.288244 -393.69238) (xy 403.77145 -393.69238)
			(xy 404.02002 -394.122402) (xy 404.027386 -394.128244) (xy 404.046164 -394.144045) (xy 404.079283 -394.180262)
			(xy 404.106692 -394.22097) (xy 404.127793 -394.265278) (xy 404.142123 -394.312216) (xy 404.149368 -394.360754)
			(xy 404.149814 -394.385292) (xy 404.14956 -394.397484) (xy 404.149306 -394.407136) (xy 404.155402 -394.42517)
			(xy 404.214076 -394.49248) (xy 404.23084 -394.501116) (xy 404.240492 -394.502132) (xy 404.267253 -394.505498)
			(xy 404.319276 -394.519719) (xy 404.368302 -394.542193) (xy 404.413031 -394.572324) (xy 404.452279 -394.609314)
			(xy 404.485005 -394.652181) (xy 404.510341 -394.699791) (xy 404.527617 -394.75088) (xy 404.536374 -394.804096)
			(xy 404.53691 -394.831062) (xy 404.536376 -394.858347) (xy 404.527421 -394.912178) (xy 404.509749 -394.963807)
			(xy 404.483839 -395.011834) (xy 404.450394 -395.054954) (xy 404.430738 -395.073886) (xy 404.423346 -395.081416)
			(xy 404.414815 -395.100689) (xy 404.414228 -395.111224) (xy 404.414228 -395.1859) (xy 404.414735 -395.196452)
			(xy 404.423285 -395.215748) (xy 404.430738 -395.223238) (xy 404.450379 -395.242183) (xy 404.483812 -395.285306)
			(xy 404.509716 -395.33333) (xy 404.527388 -395.384955) (xy 404.536349 -395.438779) (xy 404.53691 -395.466062)
			(xy 404.536466 -395.490178) (xy 404.529469 -395.537901) (xy 404.515618 -395.584102) (xy 404.495206 -395.627803)
			(xy 404.4823 -395.64818) (xy 404.476458 -395.65707) (xy 404.472902 -395.677136) (xy 404.493984 -395.769338)
			(xy 404.506176 -395.786102) (xy 404.515066 -395.791436) (xy 404.535874 -395.804279) (xy 404.573778 -395.835172)
			(xy 404.606719 -395.87131) (xy 404.633979 -395.911905) (xy 404.654963 -395.956072) (xy 404.669214 -396.002848)
			(xy 404.676421 -396.051213) (xy 404.676864 -396.075662) (xy 404.676456 -396.100036) (xy 404.669309 -396.148257)
			(xy 404.655165 -396.194907) (xy 404.63433 -396.238977) (xy 404.607254 -396.279514) (xy 404.574523 -396.315639)
			(xy 404.55596 -396.33144) (xy 404.54707 -396.338552) (xy 404.537672 -396.35811) (xy 404.534878 -396.457424)
			(xy 404.543514 -396.47749) (xy 404.551896 -396.48511) (xy 404.570334 -396.502584) (xy 404.601684 -396.54255)
			(xy 404.625984 -396.587155) (xy 404.642564 -396.635169) (xy 404.650964 -396.685264) (xy 404.651464 -396.710662)
			(xy 404.651395 -396.720021) (xy 404.650252 -396.738703) (xy 404.649178 -396.748) (xy 404.648162 -396.75689)
			(xy 404.651972 -396.773654) (xy 404.695914 -396.843504) (xy 404.70963 -396.853918) (xy 404.718012 -396.856712)
			(xy 404.742035 -396.865195) (xy 404.787208 -396.888744) (xy 404.828014 -396.91924) (xy 404.863394 -396.955892)
			(xy 404.892431 -396.997749) (xy 404.91437 -397.043725) (xy 404.921974 -397.06804) (xy 404.923498 -397.073882)
			(xy 405.243792 -397.627602) (xy 405.247856 -397.63192) (xy 405.264057 -397.64963) (xy 405.29148 -397.689021)
			(xy 405.312622 -397.732111) (xy 405.326997 -397.777904) (xy 405.334272 -397.825346) (xy 405.334724 -397.849344)
			(xy 405.334346 -397.874152) (xy 405.326574 -397.923155) (xy 405.311228 -397.970337) (xy 405.288686 -398.014536)
			(xy 405.259504 -398.054662) (xy 405.224402 -398.089727) (xy 405.184244 -398.118865) (xy 405.140021 -398.141359)
			(xy 405.092821 -398.156654) (xy 405.04381 -398.164373) (xy 405.019002 -398.164812) (xy 404.993608 -398.16431)
			(xy 404.943474 -398.156179) (xy 404.895289 -398.140128) (xy 404.850294 -398.11657) (xy 404.809651 -398.086113)
			(xy 404.774409 -398.049542) (xy 404.745475 -398.007801) (xy 404.723597 -397.961966) (xy 404.71598 -397.937736)
			(xy 404.714456 -397.931894) (xy 404.394162 -397.378174) (xy 404.390098 -397.373856) (xy 404.373946 -397.356115)
			(xy 404.346575 -397.316716) (xy 404.325482 -397.273628) (xy 404.311153 -397.227844) (xy 404.303918 -397.180419)
			(xy 404.303484 -397.156432) (xy 404.303564 -397.144384) (xy 404.305347 -397.120355) (xy 404.30704 -397.108426)
			(xy 404.30831 -397.099536) (xy 404.305262 -397.082518) (xy 404.263098 -397.011652) (xy 404.24989 -397.000476)
			(xy 404.241508 -396.997428) (xy 404.219768 -396.989012) (xy 404.178909 -396.966576) (xy 404.141937 -396.938187)
			(xy 404.109713 -396.904505) (xy 404.082986 -396.866313) (xy 404.062378 -396.824502) (xy 404.04837 -396.780042)
			(xy 404.041286 -396.733969) (xy 404.040848 -396.710662) (xy 404.041358 -396.685266) (xy 404.049769 -396.635176)
			(xy 404.066352 -396.587167) (xy 404.09065 -396.542565) (xy 404.121993 -396.502597) (xy 404.140416 -396.48511)
			(xy 404.148798 -396.47749) (xy 404.157434 -396.457424) (xy 404.15464 -396.35811) (xy 404.145242 -396.338552)
			(xy 404.136352 -396.33144) (xy 404.117815 -396.315612) (xy 404.085094 -396.279486) (xy 404.058024 -396.238953)
			(xy 404.037189 -396.194889) (xy 404.023041 -396.148246) (xy 404.015886 -396.100033) (xy 404.015448 -396.075662)
			(xy 404.015862 -396.051544) (xy 404.022869 -396.003821) (xy 404.036729 -395.95762) (xy 404.057149 -395.91392)
			(xy 404.070058 -395.893544) (xy 404.0759 -395.884654) (xy 404.079456 -395.864588) (xy 404.058374 -395.772386)
			(xy 404.046182 -395.755622) (xy 404.037292 -395.750288) (xy 404.016508 -395.737407) (xy 403.978601 -395.706523)
			(xy 403.945656 -395.670392) (xy 403.918393 -395.629803) (xy 403.897405 -395.585642) (xy 403.88315 -395.53887)
			(xy 403.875939 -395.49051) (xy 403.875494 -395.466062) (xy 403.876043 -395.438777) (xy 403.884993 -395.384948)
			(xy 403.902662 -395.333318) (xy 403.928569 -395.285291) (xy 403.962011 -395.242171) (xy 403.981666 -395.223238)
			(xy 403.989048 -395.2157) (xy 403.997585 -395.196433) (xy 403.998176 -395.1859) (xy 403.998176 -395.111224)
			(xy 403.997655 -395.100673) (xy 403.989115 -395.081377) (xy 403.981666 -395.073886) (xy 403.962038 -395.054929)
			(xy 403.928602 -395.011809) (xy 403.902696 -394.963788) (xy 403.885021 -394.912166) (xy 403.876057 -394.858344)
			(xy 403.875494 -394.831062) (xy 403.875748 -394.81887) (xy 403.876002 -394.809218) (xy 403.869906 -394.791184)
			(xy 403.811232 -394.723874) (xy 403.794468 -394.715238) (xy 403.784816 -394.714222) (xy 403.757915 -394.710806)
			(xy 403.70563 -394.696451) (xy 403.656387 -394.67376) (xy 403.611503 -394.643342) (xy 403.572182 -394.60601)
			(xy 403.539476 -394.562766) (xy 403.514261 -394.514766) (xy 403.497212 -394.463296) (xy 403.492462 -394.4366)
			(xy 403.490938 -394.427202) (xy 403.218142 -393.95527) (xy 403.210776 -393.949428) (xy 403.192024 -393.933597)
			(xy 403.158906 -393.897386) (xy 403.131494 -393.856683) (xy 403.110388 -393.812381) (xy 403.096052 -393.76545)
			(xy 403.088798 -393.716916) (xy 403.088348 -393.69238) (xy 400.827599 -393.69238) (xy 400.827494 -393.726162)
			(xy 400.835114 -393.74445) (xy 400.842226 -393.751816) (xy 400.860101 -393.770513) (xy 400.8904 -393.812434)
			(xy 400.913795 -393.858565) (xy 400.929715 -393.907779) (xy 400.93777 -393.958872) (xy 400.938238 -393.984734)
			(xy 400.937797 -394.008864) (xy 400.930776 -394.056612) (xy 400.916888 -394.102832) (xy 400.896428 -394.146541)
			(xy 400.86983 -394.186812) (xy 400.837661 -394.222788) (xy 400.800604 -394.253705) (xy 400.794601 -394.25753)
			(xy 402.46173 -394.25753) (xy 402.46224 -394.231543) (xy 402.47037 -394.180208) (xy 402.486431 -394.130778)
			(xy 402.510027 -394.084468) (xy 402.540577 -394.04242) (xy 402.577328 -394.005669) (xy 402.619376 -393.975119)
			(xy 402.665686 -393.951523) (xy 402.715116 -393.935462) (xy 402.766451 -393.927332) (xy 402.818425 -393.927332)
			(xy 402.86976 -393.935462) (xy 402.91919 -393.951523) (xy 402.9655 -393.975119) (xy 403.007548 -394.005669)
			(xy 403.044299 -394.04242) (xy 403.074849 -394.084468) (xy 403.098445 -394.130778) (xy 403.114506 -394.180208)
			(xy 403.122636 -394.231543) (xy 403.123146 -394.25753) (xy 403.122763 -394.281206) (xy 403.11603 -394.328077)
			(xy 403.102665 -394.373504) (xy 403.093174 -394.395198) (xy 403.088856 -394.404596) (xy 403.088094 -394.424662)
			(xy 403.120352 -394.511022) (xy 403.134068 -394.525754) (xy 403.143466 -394.530072) (xy 403.167838 -394.541755)
			(xy 403.212708 -394.571884) (xy 403.252085 -394.608904) (xy 403.284922 -394.65183) (xy 403.310348 -394.699522)
			(xy 403.327686 -394.750712) (xy 403.336475 -394.804039) (xy 403.337014 -394.831062) (xy 403.336478 -394.858347)
			(xy 403.327524 -394.912177) (xy 403.309852 -394.963807) (xy 403.283942 -395.011833) (xy 403.250498 -395.054954)
			(xy 403.230842 -395.073886) (xy 403.223451 -395.081417) (xy 403.214919 -395.10069) (xy 403.214332 -395.111224)
			(xy 403.214332 -395.1859) (xy 403.214838 -395.196453) (xy 403.223388 -395.215748) (xy 403.230842 -395.223238)
			(xy 403.250483 -395.242182) (xy 403.283917 -395.285305) (xy 403.309821 -395.33333) (xy 403.327492 -395.384955)
			(xy 403.336453 -395.438779) (xy 403.337014 -395.466062) (xy 403.33657 -395.490178) (xy 403.329573 -395.537901)
			(xy 403.315722 -395.584102) (xy 403.29531 -395.627803) (xy 403.282404 -395.64818) (xy 403.276562 -395.65707)
			(xy 403.273006 -395.677136) (xy 403.294088 -395.769338) (xy 403.30628 -395.786102) (xy 403.31517 -395.791436)
			(xy 403.335979 -395.804278) (xy 403.373883 -395.835171) (xy 403.406824 -395.871309) (xy 403.434083 -395.911905)
			(xy 403.455067 -395.956072) (xy 403.469318 -396.002848) (xy 403.476525 -396.051213) (xy 403.476968 -396.075662)
			(xy 403.476559 -396.100036) (xy 403.469412 -396.148256) (xy 403.455268 -396.194907) (xy 403.434433 -396.238977)
			(xy 403.407357 -396.279513) (xy 403.374627 -396.315639) (xy 403.356064 -396.33144) (xy 403.347174 -396.338552)
			(xy 403.337776 -396.35811) (xy 403.334982 -396.457424) (xy 403.343618 -396.47749) (xy 403.352 -396.48511)
			(xy 403.370439 -396.502583) (xy 403.401789 -396.542549) (xy 403.426089 -396.587155) (xy 403.442668 -396.635168)
			(xy 403.451068 -396.685264) (xy 403.451568 -396.710662) (xy 403.451499 -396.720021) (xy 403.450356 -396.738703)
			(xy 403.449282 -396.748) (xy 403.448266 -396.75689) (xy 403.452076 -396.773654) (xy 403.496018 -396.843504)
			(xy 403.509734 -396.853918) (xy 403.518116 -396.856712) (xy 403.54214 -396.865193) (xy 403.587312 -396.888742)
			(xy 403.628118 -396.919239) (xy 403.663498 -396.955891) (xy 403.692535 -396.997749) (xy 403.714474 -397.043725)
			(xy 403.722078 -397.06804) (xy 403.723602 -397.073882) (xy 404.043896 -397.627602) (xy 404.04796 -397.63192)
			(xy 404.064162 -397.64963) (xy 404.091584 -397.689021) (xy 404.112726 -397.73211) (xy 404.127101 -397.777904)
			(xy 404.134376 -397.825346) (xy 404.134828 -397.849344) (xy 404.134446 -397.874151) (xy 404.126674 -397.923154)
			(xy 404.111328 -397.970336) (xy 404.088787 -398.014535) (xy 404.059606 -398.054661) (xy 404.024504 -398.089725)
			(xy 403.984346 -398.118864) (xy 403.940123 -398.141358) (xy 403.892925 -398.156653) (xy 403.843914 -398.164373)
			(xy 403.819106 -398.164812) (xy 403.793712 -398.164306) (xy 403.743578 -398.156177) (xy 403.695393 -398.140126)
			(xy 403.650399 -398.116568) (xy 403.609756 -398.086112) (xy 403.574513 -398.049541) (xy 403.545579 -398.007801)
			(xy 403.523701 -397.961966) (xy 403.516084 -397.937736) (xy 403.51456 -397.931894) (xy 403.194266 -397.378174)
			(xy 403.190202 -397.373856) (xy 403.174051 -397.356115) (xy 403.14668 -397.316716) (xy 403.125587 -397.273628)
			(xy 403.111257 -397.227844) (xy 403.104022 -397.180419) (xy 403.103588 -397.156432) (xy 403.103669 -397.144384)
			(xy 403.105452 -397.120355) (xy 403.107144 -397.108426) (xy 403.108414 -397.099536) (xy 403.105366 -397.082518)
			(xy 403.063202 -397.011652) (xy 403.049994 -397.000476) (xy 403.041612 -396.997428) (xy 403.019873 -396.98901)
			(xy 402.979014 -396.966574) (xy 402.942041 -396.938185) (xy 402.909817 -396.904504) (xy 402.88309 -396.866313)
			(xy 402.862483 -396.824501) (xy 402.848474 -396.780042) (xy 402.84139 -396.733969) (xy 402.840952 -396.710662)
			(xy 402.841461 -396.685266) (xy 402.849872 -396.635176) (xy 402.866455 -396.587167) (xy 402.890753 -396.542564)
			(xy 402.922097 -396.502597) (xy 402.94052 -396.48511) (xy 402.948902 -396.47749) (xy 402.957538 -396.457424)
			(xy 402.954744 -396.35811) (xy 402.945346 -396.338552) (xy 402.936456 -396.33144) (xy 402.91792 -396.315611)
			(xy 402.885198 -396.279486) (xy 402.858128 -396.238953) (xy 402.837294 -396.194889) (xy 402.823146 -396.148246)
			(xy 402.81599 -396.100033) (xy 402.815552 -396.075662) (xy 402.815965 -396.051544) (xy 402.822973 -396.003821)
			(xy 402.836833 -395.95762) (xy 402.857253 -395.91392) (xy 402.870162 -395.893544) (xy 402.876004 -395.884654)
			(xy 402.87956 -395.864588) (xy 402.858478 -395.772386) (xy 402.846286 -395.755622) (xy 402.837396 -395.750288)
			(xy 402.816613 -395.737406) (xy 402.778706 -395.706522) (xy 402.745761 -395.670391) (xy 402.718497 -395.629803)
			(xy 402.697509 -395.585641) (xy 402.683254 -395.53887) (xy 402.676043 -395.49051) (xy 402.675598 -395.466062)
			(xy 402.676145 -395.438777) (xy 402.685096 -395.384947) (xy 402.702765 -395.333318) (xy 402.728673 -395.285291)
			(xy 402.762115 -395.242171) (xy 402.78177 -395.223238) (xy 402.789153 -395.2157) (xy 402.797689 -395.196433)
			(xy 402.79828 -395.1859) (xy 402.79828 -395.111224) (xy 402.797757 -395.100673) (xy 402.789218 -395.081378)
			(xy 402.78177 -395.073886) (xy 402.762143 -395.054928) (xy 402.728707 -395.011809) (xy 402.7028 -394.963788)
			(xy 402.685125 -394.912166) (xy 402.676161 -394.858344) (xy 402.675598 -394.831062) (xy 402.675983 -394.807386)
			(xy 402.682716 -394.760515) (xy 402.69608 -394.715089) (xy 402.70557 -394.693394) (xy 402.709888 -394.683996)
			(xy 402.71065 -394.66393) (xy 402.678392 -394.57757) (xy 402.664676 -394.562838) (xy 402.655278 -394.55852)
			(xy 402.630912 -394.546823) (xy 402.586041 -394.516698) (xy 402.546662 -394.479682) (xy 402.513822 -394.436758)
			(xy 402.488395 -394.389068) (xy 402.471057 -394.337879) (xy 402.462269 -394.284553) (xy 402.46173 -394.25753)
			(xy 400.794601 -394.25753) (xy 400.78025 -394.266674) (xy 400.773059 -394.271536) (xy 400.762196 -394.285062)
			(xy 400.756455 -394.301433) (xy 400.75612 -394.310108) (xy 400.75612 -394.520166) (xy 400.776948 -394.547344)
			(xy 400.793966 -394.551662) (xy 400.82007 -394.559127) (xy 400.869586 -394.581386) (xy 400.9148 -394.611435)
			(xy 400.954497 -394.648468) (xy 400.987611 -394.691488) (xy 401.013251 -394.739341) (xy 401.030729 -394.79074)
			(xy 401.039574 -394.844303) (xy 401.040092 -394.871448) (xy 401.039533 -394.898778) (xy 401.030554 -394.952694)
			(xy 401.01283 -395.0044) (xy 400.986845 -395.052487) (xy 400.970496 -395.074394) (xy 400.964908 -395.08176)
			(xy 400.95932 -395.098524) (xy 400.962876 -395.182598) (xy 400.969734 -395.198854) (xy 400.97583 -395.205712)
			(xy 400.992206 -395.22412) (xy 401.019883 -395.26488) (xy 401.041202 -395.309297) (xy 401.05569 -395.356387)
			(xy 401.063028 -395.405106) (xy 401.06346 -395.42974) (xy 401.062974 -395.455726) (xy 401.054837 -395.507057)
			(xy 401.038771 -395.556483) (xy 401.01517 -395.602787) (xy 400.984617 -395.644829) (xy 400.947862 -395.681574)
			(xy 400.905812 -395.712116) (xy 400.859501 -395.735705) (xy 400.810071 -395.751758) (xy 400.758738 -395.759881)
			(xy 400.732752 -395.760448) (xy 400.706719 -395.759988) (xy 400.65529 -395.751875) (xy 400.60577 -395.735796)
			(xy 400.559385 -395.712148) (xy 400.517284 -395.681517) (xy 400.498564 -395.66342) (xy 400.491452 -395.656308)
			(xy 400.47291 -395.648434) (xy 400.390868 -395.648434) (xy 400.380904 -395.648915) (xy 400.362474 -395.656498)
			(xy 400.355054 -395.663166) (xy 399.87601 -396.14221) (xy 399.86993 -396.148714) (xy 399.862372 -396.164821)
			(xy 399.860835 -396.182547) (xy 399.862802 -396.191232) (xy 399.888456 -396.289276) (xy 399.907506 -396.308326)
			(xy 399.92046 -396.312136) (xy 399.946911 -396.319948) (xy 399.997401 -396.342139) (xy 400.044164 -396.371377)
			(xy 400.086226 -396.407049) (xy 400.122706 -396.448412) (xy 400.152843 -396.494601) (xy 400.176008 -396.544652)
			(xy 400.191717 -396.597519) (xy 400.199642 -396.652098) (xy 400.200114 -396.679674) (xy 400.199699 -396.704137)
			(xy 400.402554 -396.704137) (xy 400.402554 -396.652163) (xy 400.410684 -396.600828) (xy 400.426745 -396.551398)
			(xy 400.450341 -396.505088) (xy 400.480891 -396.46304) (xy 400.517642 -396.426289) (xy 400.55969 -396.395739)
			(xy 400.606 -396.372143) (xy 400.65543 -396.356082) (xy 400.706765 -396.347952) (xy 400.758739 -396.347952)
			(xy 400.810074 -396.356082) (xy 400.859504 -396.372143) (xy 400.905814 -396.395739) (xy 400.947862 -396.426289)
			(xy 400.984613 -396.46304) (xy 401.015163 -396.505088) (xy 401.038759 -396.551398) (xy 401.05482 -396.600828)
			(xy 401.06295 -396.652163) (xy 401.06346 -396.67815) (xy 401.06295 -396.704137) (xy 401.05482 -396.755472)
			(xy 401.038759 -396.804902) (xy 401.015163 -396.851212) (xy 400.984613 -396.89326) (xy 400.947862 -396.930011)
			(xy 400.905814 -396.960561) (xy 400.859504 -396.984157) (xy 400.810074 -397.000218) (xy 400.758739 -397.008348)
			(xy 400.706765 -397.008348) (xy 400.65543 -397.000218) (xy 400.606 -396.984157) (xy 400.55969 -396.960561)
			(xy 400.517642 -396.930011) (xy 400.480891 -396.89326) (xy 400.450341 -396.851212) (xy 400.426745 -396.804902)
			(xy 400.410684 -396.755472) (xy 400.402554 -396.704137) (xy 400.199699 -396.704137) (xy 400.199652 -396.706928)
			(xy 400.191899 -396.760882) (xy 400.176545 -396.813184) (xy 400.153904 -396.862767) (xy 400.124437 -396.908624)
			(xy 400.088743 -396.94982) (xy 400.04755 -396.985517) (xy 400.001695 -397.014989) (xy 399.952114 -397.037634)
			(xy 399.899814 -397.052992) (xy 399.84586 -397.06075) (xy 399.818606 -397.061182) (xy 399.791036 -397.060689)
			(xy 399.736474 -397.052735) (xy 399.683625 -397.037006) (xy 399.633593 -397.013831) (xy 399.587419 -396.983692)
			(xy 399.546067 -396.947219) (xy 399.510398 -396.90517) (xy 399.481157 -396.858423) (xy 399.458952 -396.807952)
			(xy 399.451068 -396.781528) (xy 399.447258 -396.768574) (xy 399.428208 -396.749524) (xy 399.330164 -396.72387)
			(xy 399.321479 -396.721984) (xy 399.303793 -396.723579) (xy 399.287695 -396.731076) (xy 399.281142 -396.737078)
			(xy 397.294354 -398.723866) (xy 397.286734 -398.740376) (xy 397.285972 -398.749266) (xy 397.28392 -398.771561)
			(xy 397.275261 -398.815489) (xy 397.2687 -398.836896) (xy 397.265144 -398.847564) (xy 397.267938 -398.869408)
			(xy 397.319754 -398.954498) (xy 397.338042 -398.96669) (xy 397.349218 -398.968468) (xy 397.375729 -398.973211)
			(xy 397.427165 -398.989176) (xy 397.467133 -399.008092) (xy 400.39036 -399.008092) (xy 400.39078 -398.984859)
			(xy 400.397273 -398.938849) (xy 400.410145 -398.894202) (xy 400.429141 -398.851797) (xy 400.453888 -398.81247)
			(xy 400.468592 -398.794478) (xy 400.474688 -398.787366) (xy 400.480784 -398.770856) (xy 400.480784 -398.686528)
			(xy 400.474688 -398.670018) (xy 400.468592 -398.662906) (xy 400.453871 -398.644927) (xy 400.429127 -398.605594)
			(xy 400.41013 -398.563187) (xy 400.397254 -398.518538) (xy 400.390753 -398.472526) (xy 400.39036 -398.449292)
			(xy 400.39087 -398.423305) (xy 400.399 -398.37197) (xy 400.415061 -398.32254) (xy 400.438657 -398.27623)
			(xy 400.469207 -398.234182) (xy 400.505958 -398.197431) (xy 400.548006 -398.166881) (xy 400.594316 -398.143285)
			(xy 400.643746 -398.127224) (xy 400.695081 -398.119094) (xy 400.747055 -398.119094) (xy 400.79839 -398.127224)
			(xy 400.84782 -398.143285) (xy 400.89413 -398.166881) (xy 400.936178 -398.197431) (xy 400.972929 -398.234182)
			(xy 401.003479 -398.27623) (xy 401.027075 -398.32254) (xy 401.043136 -398.37197) (xy 401.051266 -398.423305)
			(xy 401.051776 -398.449292) (xy 401.051396 -398.472526) (xy 401.044892 -398.518537) (xy 401.038122 -398.542002)
			(xy 402.712948 -398.542002) (xy 402.716908 -398.492948) (xy 402.728685 -398.445164) (xy 402.747976 -398.399888)
			(xy 402.774279 -398.358292) (xy 402.806914 -398.321455) (xy 402.845035 -398.29033) (xy 402.887656 -398.265723)
			(xy 402.933672 -398.248271) (xy 402.981891 -398.238427) (xy 403.031066 -398.236446) (xy 403.079921 -398.242378)
			(xy 403.127192 -398.25607) (xy 403.171654 -398.277168) (xy 403.212157 -398.305124) (xy 403.24765 -398.339216)
			(xy 403.277215 -398.37856) (xy 403.300086 -398.422137) (xy 403.31567 -398.468818) (xy 403.323565 -398.517395)
			(xy 403.32406 -398.542002) (xy 403.913098 -398.542002) (xy 403.917058 -398.492948) (xy 403.928835 -398.445164)
			(xy 403.948126 -398.399888) (xy 403.974429 -398.358292) (xy 404.007064 -398.321455) (xy 404.045185 -398.29033)
			(xy 404.087806 -398.265723) (xy 404.133822 -398.248271) (xy 404.182041 -398.238427) (xy 404.231216 -398.236446)
			(xy 404.280071 -398.242378) (xy 404.327342 -398.25607) (xy 404.371804 -398.277168) (xy 404.412307 -398.305124)
			(xy 404.4478 -398.339216) (xy 404.477365 -398.37856) (xy 404.500236 -398.422137) (xy 404.51582 -398.468818)
			(xy 404.523715 -398.517395) (xy 404.52421 -398.542002) (xy 405.113248 -398.542002) (xy 405.117208 -398.492948)
			(xy 405.128985 -398.445164) (xy 405.148276 -398.399888) (xy 405.174579 -398.358292) (xy 405.207214 -398.321455)
			(xy 405.245335 -398.29033) (xy 405.287956 -398.265723) (xy 405.333972 -398.248271) (xy 405.382191 -398.238427)
			(xy 405.431366 -398.236446) (xy 405.480221 -398.242378) (xy 405.527492 -398.25607) (xy 405.571954 -398.277168)
			(xy 405.612457 -398.305124) (xy 405.64795 -398.339216) (xy 405.677515 -398.37856) (xy 405.700386 -398.422137)
			(xy 405.71597 -398.468818) (xy 405.723865 -398.517395) (xy 405.72436 -398.542002) (xy 406.313144 -398.542002)
			(xy 406.317104 -398.492948) (xy 406.328881 -398.445164) (xy 406.348172 -398.399888) (xy 406.374475 -398.358292)
			(xy 406.40711 -398.321455) (xy 406.445231 -398.29033) (xy 406.487852 -398.265723) (xy 406.533868 -398.248271)
			(xy 406.582087 -398.238427) (xy 406.631262 -398.236446) (xy 406.680117 -398.242378) (xy 406.727388 -398.25607)
			(xy 406.77185 -398.277168) (xy 406.812353 -398.305124) (xy 406.847846 -398.339216) (xy 406.877411 -398.37856)
			(xy 406.900282 -398.422137) (xy 406.915866 -398.468818) (xy 406.923761 -398.517395) (xy 406.924256 -398.542002)
			(xy 407.513294 -398.542002) (xy 407.517254 -398.492948) (xy 407.529031 -398.445164) (xy 407.548322 -398.399888)
			(xy 407.574625 -398.358292) (xy 407.60726 -398.321455) (xy 407.645381 -398.29033) (xy 407.688002 -398.265723)
			(xy 407.734018 -398.248271) (xy 407.782237 -398.238427) (xy 407.831412 -398.236446) (xy 407.880267 -398.242378)
			(xy 407.927538 -398.25607) (xy 407.972 -398.277168) (xy 408.012503 -398.305124) (xy 408.047996 -398.339216)
			(xy 408.077561 -398.37856) (xy 408.100432 -398.422137) (xy 408.116016 -398.468818) (xy 408.123911 -398.517395)
			(xy 408.124406 -398.542002) (xy 408.71319 -398.542002) (xy 408.71715 -398.492948) (xy 408.728927 -398.445164)
			(xy 408.748218 -398.399888) (xy 408.774521 -398.358292) (xy 408.807156 -398.321455) (xy 408.845277 -398.29033)
			(xy 408.887898 -398.265723) (xy 408.933914 -398.248271) (xy 408.982133 -398.238427) (xy 409.031308 -398.236446)
			(xy 409.080163 -398.242378) (xy 409.127434 -398.25607) (xy 409.171896 -398.277168) (xy 409.212399 -398.305124)
			(xy 409.247892 -398.339216) (xy 409.277457 -398.37856) (xy 409.300328 -398.422137) (xy 409.315912 -398.468818)
			(xy 409.323807 -398.517395) (xy 409.324302 -398.542002) (xy 409.913086 -398.542002) (xy 409.917046 -398.492948)
			(xy 409.928823 -398.445164) (xy 409.948114 -398.399888) (xy 409.974417 -398.358292) (xy 410.007052 -398.321455)
			(xy 410.045173 -398.29033) (xy 410.087794 -398.265723) (xy 410.13381 -398.248271) (xy 410.182029 -398.238427)
			(xy 410.231204 -398.236446) (xy 410.280059 -398.242378) (xy 410.32733 -398.25607) (xy 410.371792 -398.277168)
			(xy 410.412295 -398.305124) (xy 410.447788 -398.339216) (xy 410.477353 -398.37856) (xy 410.500224 -398.422137)
			(xy 410.515808 -398.468818) (xy 410.523703 -398.517395) (xy 410.524198 -398.542002) (xy 411.113236 -398.542002)
			(xy 411.117196 -398.492948) (xy 411.128973 -398.445164) (xy 411.148264 -398.399888) (xy 411.174567 -398.358292)
			(xy 411.207202 -398.321455) (xy 411.245323 -398.29033) (xy 411.287944 -398.265723) (xy 411.33396 -398.248271)
			(xy 411.382179 -398.238427) (xy 411.431354 -398.236446) (xy 411.480209 -398.242378) (xy 411.52748 -398.25607)
			(xy 411.571942 -398.277168) (xy 411.612445 -398.305124) (xy 411.647938 -398.339216) (xy 411.677503 -398.37856)
			(xy 411.700374 -398.422137) (xy 411.715958 -398.468818) (xy 411.723853 -398.517395) (xy 411.724348 -398.542002)
			(xy 412.313132 -398.542002) (xy 412.317092 -398.492948) (xy 412.328869 -398.445164) (xy 412.34816 -398.399888)
			(xy 412.374463 -398.358292) (xy 412.407098 -398.321455) (xy 412.445219 -398.29033) (xy 412.48784 -398.265723)
			(xy 412.533856 -398.248271) (xy 412.582075 -398.238427) (xy 412.63125 -398.236446) (xy 412.680105 -398.242378)
			(xy 412.727376 -398.25607) (xy 412.771838 -398.277168) (xy 412.812341 -398.305124) (xy 412.847834 -398.339216)
			(xy 412.877399 -398.37856) (xy 412.90027 -398.422137) (xy 412.915854 -398.468818) (xy 412.923749 -398.517395)
			(xy 412.924244 -398.542002) (xy 413.513282 -398.542002) (xy 413.517242 -398.492948) (xy 413.529019 -398.445164)
			(xy 413.54831 -398.399888) (xy 413.574613 -398.358292) (xy 413.607248 -398.321455) (xy 413.645369 -398.29033)
			(xy 413.68799 -398.265723) (xy 413.734006 -398.248271) (xy 413.782225 -398.238427) (xy 413.8314 -398.236446)
			(xy 413.880255 -398.242378) (xy 413.927526 -398.25607) (xy 413.971988 -398.277168) (xy 414.012491 -398.305124)
			(xy 414.047984 -398.339216) (xy 414.077549 -398.37856) (xy 414.10042 -398.422137) (xy 414.116004 -398.468818)
			(xy 414.123899 -398.517395) (xy 414.124394 -398.542002) (xy 414.713178 -398.542002) (xy 414.717138 -398.492948)
			(xy 414.728915 -398.445164) (xy 414.748206 -398.399888) (xy 414.774509 -398.358292) (xy 414.807144 -398.321455)
			(xy 414.845265 -398.29033) (xy 414.887886 -398.265723) (xy 414.933902 -398.248271) (xy 414.982121 -398.238427)
			(xy 415.031296 -398.236446) (xy 415.080151 -398.242378) (xy 415.127422 -398.25607) (xy 415.171884 -398.277168)
			(xy 415.212387 -398.305124) (xy 415.24788 -398.339216) (xy 415.277445 -398.37856) (xy 415.300316 -398.422137)
			(xy 415.3159 -398.468818) (xy 415.323795 -398.517395) (xy 415.32429 -398.542002) (xy 415.913074 -398.542002)
			(xy 415.917034 -398.492948) (xy 415.928811 -398.445164) (xy 415.948102 -398.399888) (xy 415.974405 -398.358292)
			(xy 416.00704 -398.321455) (xy 416.045161 -398.29033) (xy 416.087782 -398.265723) (xy 416.133798 -398.248271)
			(xy 416.182017 -398.238427) (xy 416.231192 -398.236446) (xy 416.280047 -398.242378) (xy 416.327318 -398.25607)
			(xy 416.37178 -398.277168) (xy 416.412283 -398.305124) (xy 416.447776 -398.339216) (xy 416.477341 -398.37856)
			(xy 416.500212 -398.422137) (xy 416.515796 -398.468818) (xy 416.523691 -398.517395) (xy 416.524186 -398.542002)
			(xy 417.113224 -398.542002) (xy 417.117184 -398.492948) (xy 417.128961 -398.445164) (xy 417.148252 -398.399888)
			(xy 417.174555 -398.358292) (xy 417.20719 -398.321455) (xy 417.245311 -398.29033) (xy 417.287932 -398.265723)
			(xy 417.333948 -398.248271) (xy 417.382167 -398.238427) (xy 417.431342 -398.236446) (xy 417.480197 -398.242378)
			(xy 417.527468 -398.25607) (xy 417.57193 -398.277168) (xy 417.612433 -398.305124) (xy 417.647926 -398.339216)
			(xy 417.677491 -398.37856) (xy 417.700362 -398.422137) (xy 417.715946 -398.468818) (xy 417.723841 -398.517395)
			(xy 417.724336 -398.542002) (xy 418.31312 -398.542002) (xy 418.31708 -398.492948) (xy 418.328857 -398.445164)
			(xy 418.348148 -398.399888) (xy 418.374451 -398.358292) (xy 418.407086 -398.321455) (xy 418.445207 -398.29033)
			(xy 418.487828 -398.265723) (xy 418.533844 -398.248271) (xy 418.582063 -398.238427) (xy 418.631238 -398.236446)
			(xy 418.680093 -398.242378) (xy 418.727364 -398.25607) (xy 418.771826 -398.277168) (xy 418.812329 -398.305124)
			(xy 418.847822 -398.339216) (xy 418.877387 -398.37856) (xy 418.900258 -398.422137) (xy 418.915842 -398.468818)
			(xy 418.923737 -398.517395) (xy 418.924232 -398.542002) (xy 419.51327 -398.542002) (xy 419.51723 -398.492948)
			(xy 419.529007 -398.445164) (xy 419.548298 -398.399888) (xy 419.574601 -398.358292) (xy 419.607236 -398.321455)
			(xy 419.645357 -398.29033) (xy 419.687978 -398.265723) (xy 419.733994 -398.248271) (xy 419.782213 -398.238427)
			(xy 419.831388 -398.236446) (xy 419.880243 -398.242378) (xy 419.927514 -398.25607) (xy 419.971976 -398.277168)
			(xy 420.012479 -398.305124) (xy 420.047972 -398.339216) (xy 420.077537 -398.37856) (xy 420.100408 -398.422137)
			(xy 420.115992 -398.468818) (xy 420.123887 -398.517395) (xy 420.124382 -398.542002) (xy 420.123887 -398.566609)
			(xy 420.115992 -398.615186) (xy 420.100408 -398.661867) (xy 420.077537 -398.705444) (xy 420.047972 -398.744788)
			(xy 420.012479 -398.77888) (xy 419.971976 -398.806836) (xy 419.927514 -398.827934) (xy 419.880243 -398.841626)
			(xy 419.831388 -398.847558) (xy 419.782213 -398.845577) (xy 419.733994 -398.835733) (xy 419.687978 -398.818281)
			(xy 419.645357 -398.793674) (xy 419.607236 -398.762549) (xy 419.574601 -398.725712) (xy 419.548298 -398.684116)
			(xy 419.529007 -398.63884) (xy 419.51723 -398.591056) (xy 419.51327 -398.542002) (xy 418.924232 -398.542002)
			(xy 418.923737 -398.566609) (xy 418.915842 -398.615186) (xy 418.900258 -398.661867) (xy 418.877387 -398.705444)
			(xy 418.847822 -398.744788) (xy 418.812329 -398.77888) (xy 418.771826 -398.806836) (xy 418.727364 -398.827934)
			(xy 418.680093 -398.841626) (xy 418.631238 -398.847558) (xy 418.582063 -398.845577) (xy 418.533844 -398.835733)
			(xy 418.487828 -398.818281) (xy 418.445207 -398.793674) (xy 418.407086 -398.762549) (xy 418.374451 -398.725712)
			(xy 418.348148 -398.684116) (xy 418.328857 -398.63884) (xy 418.31708 -398.591056) (xy 418.31312 -398.542002)
			(xy 417.724336 -398.542002) (xy 417.723841 -398.566609) (xy 417.715946 -398.615186) (xy 417.700362 -398.661867)
			(xy 417.677491 -398.705444) (xy 417.647926 -398.744788) (xy 417.612433 -398.77888) (xy 417.57193 -398.806836)
			(xy 417.527468 -398.827934) (xy 417.480197 -398.841626) (xy 417.431342 -398.847558) (xy 417.382167 -398.845577)
			(xy 417.333948 -398.835733) (xy 417.287932 -398.818281) (xy 417.245311 -398.793674) (xy 417.20719 -398.762549)
			(xy 417.174555 -398.725712) (xy 417.148252 -398.684116) (xy 417.128961 -398.63884) (xy 417.117184 -398.591056)
			(xy 417.113224 -398.542002) (xy 416.524186 -398.542002) (xy 416.523691 -398.566609) (xy 416.515796 -398.615186)
			(xy 416.500212 -398.661867) (xy 416.477341 -398.705444) (xy 416.447776 -398.744788) (xy 416.412283 -398.77888)
			(xy 416.37178 -398.806836) (xy 416.327318 -398.827934) (xy 416.280047 -398.841626) (xy 416.231192 -398.847558)
			(xy 416.182017 -398.845577) (xy 416.133798 -398.835733) (xy 416.087782 -398.818281) (xy 416.045161 -398.793674)
			(xy 416.00704 -398.762549) (xy 415.974405 -398.725712) (xy 415.948102 -398.684116) (xy 415.928811 -398.63884)
			(xy 415.917034 -398.591056) (xy 415.913074 -398.542002) (xy 415.32429 -398.542002) (xy 415.323795 -398.566609)
			(xy 415.3159 -398.615186) (xy 415.300316 -398.661867) (xy 415.277445 -398.705444) (xy 415.24788 -398.744788)
			(xy 415.212387 -398.77888) (xy 415.171884 -398.806836) (xy 415.127422 -398.827934) (xy 415.080151 -398.841626)
			(xy 415.031296 -398.847558) (xy 414.982121 -398.845577) (xy 414.933902 -398.835733) (xy 414.887886 -398.818281)
			(xy 414.845265 -398.793674) (xy 414.807144 -398.762549) (xy 414.774509 -398.725712) (xy 414.748206 -398.684116)
			(xy 414.728915 -398.63884) (xy 414.717138 -398.591056) (xy 414.713178 -398.542002) (xy 414.124394 -398.542002)
			(xy 414.123899 -398.566609) (xy 414.116004 -398.615186) (xy 414.10042 -398.661867) (xy 414.077549 -398.705444)
			(xy 414.047984 -398.744788) (xy 414.012491 -398.77888) (xy 413.971988 -398.806836) (xy 413.927526 -398.827934)
			(xy 413.880255 -398.841626) (xy 413.8314 -398.847558) (xy 413.782225 -398.845577) (xy 413.734006 -398.835733)
			(xy 413.68799 -398.818281) (xy 413.645369 -398.793674) (xy 413.607248 -398.762549) (xy 413.574613 -398.725712)
			(xy 413.54831 -398.684116) (xy 413.529019 -398.63884) (xy 413.517242 -398.591056) (xy 413.513282 -398.542002)
			(xy 412.924244 -398.542002) (xy 412.923749 -398.566609) (xy 412.915854 -398.615186) (xy 412.90027 -398.661867)
			(xy 412.877399 -398.705444) (xy 412.847834 -398.744788) (xy 412.812341 -398.77888) (xy 412.771838 -398.806836)
			(xy 412.727376 -398.827934) (xy 412.680105 -398.841626) (xy 412.63125 -398.847558) (xy 412.582075 -398.845577)
			(xy 412.533856 -398.835733) (xy 412.48784 -398.818281) (xy 412.445219 -398.793674) (xy 412.407098 -398.762549)
			(xy 412.374463 -398.725712) (xy 412.34816 -398.684116) (xy 412.328869 -398.63884) (xy 412.317092 -398.591056)
			(xy 412.313132 -398.542002) (xy 411.724348 -398.542002) (xy 411.723853 -398.566609) (xy 411.715958 -398.615186)
			(xy 411.700374 -398.661867) (xy 411.677503 -398.705444) (xy 411.647938 -398.744788) (xy 411.612445 -398.77888)
			(xy 411.571942 -398.806836) (xy 411.52748 -398.827934) (xy 411.480209 -398.841626) (xy 411.431354 -398.847558)
			(xy 411.382179 -398.845577) (xy 411.33396 -398.835733) (xy 411.287944 -398.818281) (xy 411.245323 -398.793674)
			(xy 411.207202 -398.762549) (xy 411.174567 -398.725712) (xy 411.148264 -398.684116) (xy 411.128973 -398.63884)
			(xy 411.117196 -398.591056) (xy 411.113236 -398.542002) (xy 410.524198 -398.542002) (xy 410.523703 -398.566609)
			(xy 410.515808 -398.615186) (xy 410.500224 -398.661867) (xy 410.477353 -398.705444) (xy 410.447788 -398.744788)
			(xy 410.412295 -398.77888) (xy 410.371792 -398.806836) (xy 410.32733 -398.827934) (xy 410.280059 -398.841626)
			(xy 410.231204 -398.847558) (xy 410.182029 -398.845577) (xy 410.13381 -398.835733) (xy 410.087794 -398.818281)
			(xy 410.045173 -398.793674) (xy 410.007052 -398.762549) (xy 409.974417 -398.725712) (xy 409.948114 -398.684116)
			(xy 409.928823 -398.63884) (xy 409.917046 -398.591056) (xy 409.913086 -398.542002) (xy 409.324302 -398.542002)
			(xy 409.323807 -398.566609) (xy 409.315912 -398.615186) (xy 409.300328 -398.661867) (xy 409.277457 -398.705444)
			(xy 409.247892 -398.744788) (xy 409.212399 -398.77888) (xy 409.171896 -398.806836) (xy 409.127434 -398.827934)
			(xy 409.080163 -398.841626) (xy 409.031308 -398.847558) (xy 408.982133 -398.845577) (xy 408.933914 -398.835733)
			(xy 408.887898 -398.818281) (xy 408.845277 -398.793674) (xy 408.807156 -398.762549) (xy 408.774521 -398.725712)
			(xy 408.748218 -398.684116) (xy 408.728927 -398.63884) (xy 408.71715 -398.591056) (xy 408.71319 -398.542002)
			(xy 408.124406 -398.542002) (xy 408.123911 -398.566609) (xy 408.116016 -398.615186) (xy 408.100432 -398.661867)
			(xy 408.077561 -398.705444) (xy 408.047996 -398.744788) (xy 408.012503 -398.77888) (xy 407.972 -398.806836)
			(xy 407.927538 -398.827934) (xy 407.880267 -398.841626) (xy 407.831412 -398.847558) (xy 407.782237 -398.845577)
			(xy 407.734018 -398.835733) (xy 407.688002 -398.818281) (xy 407.645381 -398.793674) (xy 407.60726 -398.762549)
			(xy 407.574625 -398.725712) (xy 407.548322 -398.684116) (xy 407.529031 -398.63884) (xy 407.517254 -398.591056)
			(xy 407.513294 -398.542002) (xy 406.924256 -398.542002) (xy 406.923761 -398.566609) (xy 406.915866 -398.615186)
			(xy 406.900282 -398.661867) (xy 406.877411 -398.705444) (xy 406.847846 -398.744788) (xy 406.812353 -398.77888)
			(xy 406.77185 -398.806836) (xy 406.727388 -398.827934) (xy 406.680117 -398.841626) (xy 406.631262 -398.847558)
			(xy 406.582087 -398.845577) (xy 406.533868 -398.835733) (xy 406.487852 -398.818281) (xy 406.445231 -398.793674)
			(xy 406.40711 -398.762549) (xy 406.374475 -398.725712) (xy 406.348172 -398.684116) (xy 406.328881 -398.63884)
			(xy 406.317104 -398.591056) (xy 406.313144 -398.542002) (xy 405.72436 -398.542002) (xy 405.723865 -398.566609)
			(xy 405.71597 -398.615186) (xy 405.700386 -398.661867) (xy 405.677515 -398.705444) (xy 405.64795 -398.744788)
			(xy 405.612457 -398.77888) (xy 405.571954 -398.806836) (xy 405.527492 -398.827934) (xy 405.480221 -398.841626)
			(xy 405.431366 -398.847558) (xy 405.382191 -398.845577) (xy 405.333972 -398.835733) (xy 405.287956 -398.818281)
			(xy 405.245335 -398.793674) (xy 405.207214 -398.762549) (xy 405.174579 -398.725712) (xy 405.148276 -398.684116)
			(xy 405.128985 -398.63884) (xy 405.117208 -398.591056) (xy 405.113248 -398.542002) (xy 404.52421 -398.542002)
			(xy 404.523715 -398.566609) (xy 404.51582 -398.615186) (xy 404.500236 -398.661867) (xy 404.477365 -398.705444)
			(xy 404.4478 -398.744788) (xy 404.412307 -398.77888) (xy 404.371804 -398.806836) (xy 404.327342 -398.827934)
			(xy 404.280071 -398.841626) (xy 404.231216 -398.847558) (xy 404.182041 -398.845577) (xy 404.133822 -398.835733)
			(xy 404.087806 -398.818281) (xy 404.045185 -398.793674) (xy 404.007064 -398.762549) (xy 403.974429 -398.725712)
			(xy 403.948126 -398.684116) (xy 403.928835 -398.63884) (xy 403.917058 -398.591056) (xy 403.913098 -398.542002)
			(xy 403.32406 -398.542002) (xy 403.323565 -398.566609) (xy 403.31567 -398.615186) (xy 403.300086 -398.661867)
			(xy 403.277215 -398.705444) (xy 403.24765 -398.744788) (xy 403.212157 -398.77888) (xy 403.171654 -398.806836)
			(xy 403.127192 -398.827934) (xy 403.079921 -398.841626) (xy 403.031066 -398.847558) (xy 402.981891 -398.845577)
			(xy 402.933672 -398.835733) (xy 402.887656 -398.818281) (xy 402.845035 -398.793674) (xy 402.806914 -398.762549)
			(xy 402.774279 -398.725712) (xy 402.747976 -398.684116) (xy 402.728685 -398.63884) (xy 402.716908 -398.591056)
			(xy 402.712948 -398.542002) (xy 401.038122 -398.542002) (xy 401.032011 -398.563185) (xy 401.013006 -398.605589)
			(xy 400.988251 -398.644915) (xy 400.973544 -398.662906) (xy 400.967448 -398.670018) (xy 400.961352 -398.686528)
			(xy 400.961352 -398.770856) (xy 400.967448 -398.787366) (xy 400.973544 -398.794478) (xy 400.988248 -398.812471)
			(xy 401.012997 -398.851798) (xy 401.031998 -398.894203) (xy 401.044878 -398.938849) (xy 401.051382 -398.984859)
			(xy 401.051776 -399.008092) (xy 401.051365 -399.032185) (xy 401.044385 -399.079862) (xy 401.030573 -399.126025)
			(xy 401.020788 -399.148046) (xy 401.015454 -399.159476) (xy 401.016724 -399.184622) (xy 401.072858 -399.278602)
			(xy 401.094448 -399.291556) (xy 401.107148 -399.292318) (xy 401.132143 -399.294174) (xy 401.181187 -399.304504)
			(xy 401.228111 -399.322116) (xy 401.27184 -399.346607) (xy 401.311373 -399.377416) (xy 401.345804 -399.413838)
			(xy 401.374345 -399.455038) (xy 401.396342 -399.500073) (xy 401.411292 -399.547911) (xy 401.418852 -399.597458)
			(xy 401.419314 -399.622518) (xy 401.418804 -399.648505) (xy 401.410674 -399.69984) (xy 401.394613 -399.74927)
			(xy 401.371017 -399.79558) (xy 401.340467 -399.837628) (xy 401.303716 -399.874379) (xy 401.261668 -399.904929)
			(xy 401.215358 -399.928525) (xy 401.165928 -399.944586) (xy 401.114593 -399.952716) (xy 401.062619 -399.952716)
			(xy 401.011284 -399.944586) (xy 400.961854 -399.928525) (xy 400.915544 -399.904929) (xy 400.873496 -399.874379)
			(xy 400.836745 -399.837628) (xy 400.806195 -399.79558) (xy 400.782599 -399.74927) (xy 400.766538 -399.69984)
			(xy 400.758408 -399.648505) (xy 400.757898 -399.622518) (xy 400.758315 -399.598426) (xy 400.765293 -399.550748)
			(xy 400.779103 -399.504585) (xy 400.788886 -399.482564) (xy 400.79422 -399.471134) (xy 400.79295 -399.445988)
			(xy 400.736816 -399.352008) (xy 400.715226 -399.339054) (xy 400.702526 -399.338292) (xy 400.67753 -399.336448)
			(xy 400.628486 -399.326115) (xy 400.581563 -399.3085) (xy 400.537835 -399.284007) (xy 400.498303 -399.253197)
			(xy 400.463872 -399.216774) (xy 400.435331 -399.175573) (xy 400.413334 -399.130538) (xy 400.398383 -399.082699)
			(xy 400.390822 -399.033152) (xy 400.39036 -399.008092) (xy 397.467133 -399.008092) (xy 397.475844 -399.012215)
			(xy 397.5208 -399.041872) (xy 397.561137 -399.077557) (xy 397.596055 -399.11856) (xy 397.624859 -399.164067)
			(xy 397.646976 -399.213172) (xy 397.661968 -399.2649) (xy 397.669535 -399.318222) (xy 397.67002 -399.34515)
			(xy 397.669295 -399.379439) (xy 397.657021 -399.44691) (xy 397.645636 -399.479262) (xy 397.641064 -399.491454)
			(xy 397.644366 -399.516346) (xy 397.708374 -399.605754) (xy 397.730726 -399.61693) (xy 397.74368 -399.616676)
			(xy 397.754602 -399.616422) (xy 397.781972 -399.616894) (xy 397.83615 -399.624718) (xy 397.888653 -399.640206)
			(xy 397.938403 -399.66304) (xy 397.984379 -399.69275) (xy 398.0053 -399.710402) (xy 398.012412 -399.716498)
			(xy 398.02943 -399.722848) (xy 398.114774 -399.722848) (xy 398.131792 -399.716498) (xy 398.138904 -399.710402)
			(xy 398.159837 -399.692761) (xy 398.205805 -399.663037) (xy 398.255551 -399.640191) (xy 398.308053 -399.624695)
			(xy 398.362231 -399.616866) (xy 398.416973 -399.616866) (xy 398.471151 -399.624695) (xy 398.523653 -399.640191)
			(xy 398.573399 -399.663037) (xy 398.619367 -399.692761) (xy 398.6403 -399.710402) (xy 398.647412 -399.716498)
			(xy 398.66443 -399.722848) (xy 398.749774 -399.722848) (xy 398.766792 -399.716498) (xy 398.773904 -399.710402)
			(xy 398.794835 -399.69276) (xy 398.840802 -399.663034) (xy 398.890549 -399.640192) (xy 398.943052 -399.624702)
			(xy 398.997232 -399.616884) (xy 399.024602 -399.616422) (xy 399.051854 -399.616885) (xy 399.105803 -399.624643)
			(xy 399.158099 -399.639999) (xy 399.207677 -399.662642) (xy 399.253528 -399.692111) (xy 399.294718 -399.727805)
			(xy 399.330408 -399.768998) (xy 399.359873 -399.814851) (xy 399.382512 -399.864431) (xy 399.397864 -399.916728)
			(xy 399.405617 -399.970678) (xy 399.40611 -399.99793) (xy 399.405636 -400.025299) (xy 399.397809 -400.079476)
			(xy 399.382319 -400.131977) (xy 399.359484 -400.181726) (xy 399.329774 -400.2277) (xy 399.31213 -400.248628)
			(xy 399.306034 -400.25574) (xy 399.299684 -400.272758) (xy 399.299684 -400.358102) (xy 399.306034 -400.37512)
			(xy 399.31213 -400.382232) (xy 399.32977 -400.403164) (xy 399.359494 -400.44913) (xy 399.382338 -400.498875)
			(xy 399.397832 -400.551376) (xy 399.400183 -400.567652) (xy 399.659856 -400.567652) (xy 399.660342 -400.540401)
			(xy 399.668098 -400.486453) (xy 399.683453 -400.434158) (xy 399.706095 -400.384581) (xy 399.735561 -400.338731)
			(xy 399.771252 -400.29754) (xy 399.812443 -400.261849) (xy 399.858293 -400.232383) (xy 399.90787 -400.209741)
			(xy 399.960165 -400.194386) (xy 400.014113 -400.18663) (xy 400.068615 -400.18663) (xy 400.122563 -400.194386)
			(xy 400.174858 -400.209741) (xy 400.224435 -400.232383) (xy 400.270285 -400.261849) (xy 400.311476 -400.29754)
			(xy 400.347167 -400.338731) (xy 400.376633 -400.384581) (xy 400.399275 -400.434158) (xy 400.41463 -400.486453)
			(xy 400.422386 -400.540401) (xy 400.422872 -400.567652) (xy 400.422599 -400.58794) (xy 400.418276 -400.628286)
			(xy 400.414236 -400.64817) (xy 400.41171 -400.662297) (xy 400.413753 -400.690909) (xy 400.423276 -400.71675)
			(xy 401.791932 -400.71675) (xy 401.792334 -400.693517) (xy 401.798833 -400.647506) (xy 401.811709 -400.602859)
			(xy 401.830709 -400.560455) (xy 401.855459 -400.521128) (xy 401.870164 -400.503136) (xy 401.87626 -400.496024)
			(xy 401.882356 -400.479514) (xy 401.882356 -400.395186) (xy 401.87626 -400.378676) (xy 401.870164 -400.371564)
			(xy 401.855481 -400.353555) (xy 401.830728 -400.314232) (xy 401.811723 -400.271832) (xy 401.798839 -400.227189)
			(xy 401.792329 -400.181182) (xy 401.791932 -400.15795) (xy 401.792442 -400.131963) (xy 401.800572 -400.080628)
			(xy 401.816633 -400.031198) (xy 401.840229 -399.984888) (xy 401.870779 -399.94284) (xy 401.90753 -399.906089)
			(xy 401.949578 -399.875539) (xy 401.995888 -399.851943) (xy 402.045318 -399.835882) (xy 402.096653 -399.827752)
			(xy 402.148627 -399.827752) (xy 402.199962 -399.835882) (xy 402.249392 -399.851943) (xy 402.295702 -399.875539)
			(xy 402.33775 -399.906089) (xy 402.374501 -399.94284) (xy 402.405051 -399.984888) (xy 402.428647 -400.031198)
			(xy 402.444708 -400.080628) (xy 402.452838 -400.131963) (xy 402.453348 -400.15795) (xy 402.452951 -400.181184)
			(xy 402.446452 -400.227194) (xy 402.433575 -400.271842) (xy 402.414573 -400.314246) (xy 402.389822 -400.353573)
			(xy 402.375116 -400.371564) (xy 402.36902 -400.378676) (xy 402.362924 -400.395186) (xy 402.362924 -400.479514)
			(xy 402.36902 -400.496024) (xy 402.375116 -400.503136) (xy 402.389812 -400.521135) (xy 402.414559 -400.560462)
			(xy 402.433561 -400.602865) (xy 402.446443 -400.647509) (xy 402.452951 -400.693517) (xy 402.453348 -400.71675)
			(xy 402.452838 -400.742737) (xy 402.444708 -400.794072) (xy 402.428647 -400.843502) (xy 402.405051 -400.889812)
			(xy 402.374501 -400.93186) (xy 402.33775 -400.968611) (xy 402.295702 -400.999161) (xy 402.249392 -401.022757)
			(xy 402.199962 -401.038818) (xy 402.148627 -401.046948) (xy 402.096653 -401.046948) (xy 402.045318 -401.038818)
			(xy 401.995888 -401.022757) (xy 401.949578 -400.999161) (xy 401.90753 -400.968611) (xy 401.870779 -400.93186)
			(xy 401.840229 -400.889812) (xy 401.816633 -400.843502) (xy 401.800572 -400.794072) (xy 401.792442 -400.742737)
			(xy 401.791932 -400.71675) (xy 400.423276 -400.71675) (xy 400.423672 -400.717825) (xy 400.440684 -400.740921)
			(xy 400.463447 -400.758376) (xy 400.490166 -400.768813) (xy 400.504406 -400.770598) (xy 400.532492 -400.773673)
			(xy 400.587385 -400.787037) (xy 400.639709 -400.80835) (xy 400.688318 -400.837145) (xy 400.732149 -400.872792)
			(xy 400.770245 -400.914513) (xy 400.801773 -400.961395) (xy 400.826043 -401.012414) (xy 400.842525 -401.066454)
			(xy 400.850858 -401.122333) (xy 400.85137 -401.150582) (xy 400.850884 -401.177833) (xy 400.843128 -401.231781)
			(xy 400.827773 -401.284076) (xy 400.805131 -401.333653) (xy 400.775665 -401.379503) (xy 400.739974 -401.420694)
			(xy 400.698783 -401.456385) (xy 400.652933 -401.485851) (xy 400.603356 -401.508493) (xy 400.551061 -401.523848)
			(xy 400.497113 -401.531604) (xy 400.442611 -401.531604) (xy 400.388663 -401.523848) (xy 400.336368 -401.508493)
			(xy 400.286791 -401.485851) (xy 400.240941 -401.456385) (xy 400.19975 -401.420694) (xy 400.164059 -401.379503)
			(xy 400.134593 -401.333653) (xy 400.111951 -401.284076) (xy 400.096596 -401.231781) (xy 400.08884 -401.177833)
			(xy 400.088354 -401.150582) (xy 400.088616 -401.130293) (xy 400.092946 -401.089947) (xy 400.09699 -401.070064)
			(xy 400.099457 -401.055929) (xy 400.097422 -401.027325) (xy 400.087514 -401.000415) (xy 400.070514 -400.977321)
			(xy 400.047762 -400.959866) (xy 400.021055 -400.949425) (xy 400.00682 -400.947636) (xy 399.978742 -400.944506)
			(xy 399.923851 -400.931147) (xy 399.87153 -400.90984) (xy 399.822923 -400.881052) (xy 399.779092 -400.84541)
			(xy 399.740995 -400.803696) (xy 399.709466 -400.75682) (xy 399.685193 -400.705807) (xy 399.668708 -400.651773)
			(xy 399.66037 -400.595898) (xy 399.659856 -400.567652) (xy 399.400183 -400.567652) (xy 399.405658 -400.605553)
			(xy 399.405655 -400.660292) (xy 399.397823 -400.714468) (xy 399.382322 -400.766967) (xy 399.359472 -400.81671)
			(xy 399.329743 -400.862672) (xy 399.31213 -400.883628) (xy 399.306034 -400.89074) (xy 399.299684 -400.907758)
			(xy 399.299684 -400.993102) (xy 399.306034 -401.01012) (xy 399.31213 -401.017232) (xy 399.32977 -401.038164)
			(xy 399.359494 -401.08413) (xy 399.382338 -401.133875) (xy 399.397832 -401.186376) (xy 399.405658 -401.240553)
			(xy 399.405655 -401.295292) (xy 399.397823 -401.349468) (xy 399.382322 -401.401967) (xy 399.359472 -401.45171)
			(xy 399.329743 -401.497672) (xy 399.31213 -401.518628) (xy 399.306034 -401.52574) (xy 399.299684 -401.542758)
			(xy 399.299684 -401.628102) (xy 399.306034 -401.64512) (xy 399.31213 -401.652232) (xy 399.329769 -401.673165)
			(xy 399.330851 -401.674838) (xy 403.06244 -401.674838) (xy 403.06244 -400.811238) (xy 403.06292 -400.784882)
			(xy 403.070183 -400.732674) (xy 403.084562 -400.681962) (xy 403.105783 -400.633711) (xy 403.133443 -400.58884)
			(xy 403.167015 -400.548202) (xy 403.186138 -400.53006) (xy 403.19325 -400.52371) (xy 403.201378 -400.506946)
			(xy 403.20976 -400.420332) (xy 403.20468 -400.402552) (xy 403.199092 -400.394678) (xy 403.184947 -400.374828)
			(xy 403.162487 -400.331571) (xy 403.147173 -400.285299) (xy 403.139393 -400.237184) (xy 403.138894 -400.212814)
			(xy 403.139416 -400.187559) (xy 403.147729 -400.137737) (xy 403.16413 -400.089963) (xy 403.188171 -400.04554)
			(xy 403.219195 -400.00568) (xy 403.256357 -399.97147) (xy 403.298643 -399.943844) (xy 403.344899 -399.923554)
			(xy 403.393864 -399.911154) (xy 403.444202 -399.906983) (xy 403.49454 -399.911154) (xy 403.543505 -399.923554)
			(xy 403.589761 -399.943844) (xy 403.632047 -399.97147) (xy 403.669209 -400.00568) (xy 403.700233 -400.04554)
			(xy 403.724274 -400.089963) (xy 403.740675 -400.137737) (xy 403.748988 -400.187559) (xy 403.74951 -400.212814)
			(xy 403.74904 -400.237187) (xy 403.74128 -400.285311) (xy 403.72596 -400.331586) (xy 403.703471 -400.374834)
			(xy 403.689312 -400.394678) (xy 403.683724 -400.402552) (xy 403.678644 -400.420332) (xy 403.687026 -400.506946)
			(xy 403.695154 -400.52371) (xy 403.702266 -400.53006) (xy 403.721403 -400.548191) (xy 403.75499 -400.588822)
			(xy 403.782661 -400.633693) (xy 403.803887 -400.681947) (xy 403.818266 -400.732665) (xy 403.825521 -400.78488)
			(xy 403.825964 -400.811238) (xy 403.825964 -401.674838) (xy 404.262336 -401.674838) (xy 404.262336 -400.811238)
			(xy 404.262817 -400.784882) (xy 404.27008 -400.732674) (xy 404.284459 -400.681962) (xy 404.30568 -400.633711)
			(xy 404.33334 -400.58884) (xy 404.366912 -400.548202) (xy 404.386034 -400.53006) (xy 404.393146 -400.523456)
			(xy 404.401528 -400.506946) (xy 404.409656 -400.420078) (xy 404.40483 -400.402298) (xy 404.398988 -400.394678)
			(xy 404.384883 -400.37481) (xy 404.36246 -400.331555) (xy 404.347202 -400.285284) (xy 404.339498 -400.237175)
			(xy 404.339044 -400.212814) (xy 404.339566 -400.187559) (xy 404.347879 -400.137737) (xy 404.36428 -400.089963)
			(xy 404.388321 -400.04554) (xy 404.419345 -400.00568) (xy 404.456507 -399.97147) (xy 404.498793 -399.943844)
			(xy 404.545049 -399.923554) (xy 404.594014 -399.911154) (xy 404.644352 -399.906983) (xy 404.69469 -399.911154)
			(xy 404.743655 -399.923554) (xy 404.789911 -399.943844) (xy 404.832197 -399.97147) (xy 404.869359 -400.00568)
			(xy 404.900383 -400.04554) (xy 404.924424 -400.089963) (xy 404.940825 -400.137737) (xy 404.949138 -400.187559)
			(xy 404.94966 -400.212814) (xy 404.949194 -400.237217) (xy 404.941434 -400.285401) (xy 404.926114 -400.331739)
			(xy 404.903624 -400.375053) (xy 404.889462 -400.394932) (xy 404.883874 -400.402552) (xy 404.878794 -400.420332)
			(xy 404.886922 -400.5072) (xy 404.895304 -400.52371) (xy 404.902416 -400.530314) (xy 404.921485 -400.548467)
			(xy 404.954975 -400.589089) (xy 404.982572 -400.633924) (xy 405.003754 -400.682122) (xy 405.018119 -400.732772)
			(xy 405.025395 -400.784915) (xy 405.02586 -400.811238) (xy 405.02586 -401.674838) (xy 405.46274 -401.674838)
			(xy 405.46274 -400.811238) (xy 405.463207 -400.784893) (xy 405.470454 -400.732705) (xy 405.484803 -400.682007)
			(xy 405.50598 -400.633761) (xy 405.533585 -400.588882) (xy 405.567094 -400.548221) (xy 405.586184 -400.53006)
			(xy 405.593296 -400.52371) (xy 405.601424 -400.506946) (xy 405.609806 -400.420332) (xy 405.604726 -400.402552)
			(xy 405.599138 -400.394678) (xy 405.584986 -400.374832) (xy 405.56253 -400.331573) (xy 405.547218 -400.2853)
			(xy 405.539438 -400.237184) (xy 405.53894 -400.212814) (xy 405.539462 -400.187559) (xy 405.547775 -400.137737)
			(xy 405.564176 -400.089963) (xy 405.588217 -400.04554) (xy 405.619241 -400.00568) (xy 405.656403 -399.97147)
			(xy 405.698689 -399.943844) (xy 405.744945 -399.923554) (xy 405.79391 -399.911154) (xy 405.844248 -399.906983)
			(xy 405.894586 -399.911154) (xy 405.943551 -399.923554) (xy 405.989807 -399.943844) (xy 406.032093 -399.97147)
			(xy 406.069255 -400.00568) (xy 406.100279 -400.04554) (xy 406.12432 -400.089963) (xy 406.140721 -400.137737)
			(xy 406.149034 -400.187559) (xy 406.149556 -400.212814) (xy 406.149077 -400.237186) (xy 406.141318 -400.285309)
			(xy 406.126001 -400.331585) (xy 406.103515 -400.374833) (xy 406.089358 -400.394678) (xy 406.08377 -400.402552)
			(xy 406.07869 -400.420332) (xy 406.087072 -400.506946) (xy 406.0952 -400.52371) (xy 406.102312 -400.53006)
			(xy 406.121407 -400.548218) (xy 406.154931 -400.588871) (xy 406.182546 -400.633748) (xy 406.203728 -400.681996)
			(xy 406.218076 -400.732698) (xy 406.225316 -400.784891) (xy 406.225756 -400.811238) (xy 406.225756 -401.674838)
			(xy 406.662636 -401.674838) (xy 406.662636 -400.811238) (xy 406.663105 -400.784893) (xy 406.670352 -400.732705)
			(xy 406.6847 -400.682007) (xy 406.705877 -400.633761) (xy 406.733482 -400.588882) (xy 406.76699 -400.548221)
			(xy 406.78608 -400.53006) (xy 406.793192 -400.52371) (xy 406.80132 -400.506946) (xy 406.809702 -400.420332)
			(xy 406.804622 -400.402552) (xy 406.799034 -400.394678) (xy 406.784882 -400.374833) (xy 406.762425 -400.331573)
			(xy 406.747114 -400.2853) (xy 406.739334 -400.237184) (xy 406.738836 -400.212814) (xy 406.739358 -400.187559)
			(xy 406.747671 -400.137737) (xy 406.764072 -400.089963) (xy 406.788113 -400.04554) (xy 406.819137 -400.00568)
			(xy 406.856299 -399.97147) (xy 406.898585 -399.943844) (xy 406.944841 -399.923554) (xy 406.993806 -399.911154)
			(xy 407.044144 -399.906983) (xy 407.094482 -399.911154) (xy 407.143447 -399.923554) (xy 407.189703 -399.943844)
			(xy 407.231989 -399.97147) (xy 407.269151 -400.00568) (xy 407.300175 -400.04554) (xy 407.324216 -400.089963)
			(xy 407.340617 -400.137737) (xy 407.34893 -400.187559) (xy 407.349452 -400.212814) (xy 407.348973 -400.237186)
			(xy 407.341215 -400.285309) (xy 407.325897 -400.331585) (xy 407.303411 -400.374833) (xy 407.289254 -400.394678)
			(xy 407.283666 -400.402552) (xy 407.278586 -400.420332) (xy 407.286968 -400.506946) (xy 407.295096 -400.52371)
			(xy 407.302208 -400.53006) (xy 407.321303 -400.548218) (xy 407.354826 -400.588872) (xy 407.382442 -400.633749)
			(xy 407.403624 -400.681996) (xy 407.417972 -400.732698) (xy 407.425212 -400.784892) (xy 407.425652 -400.811238)
			(xy 407.425652 -401.674838) (xy 407.862532 -401.674838) (xy 407.862532 -400.811238) (xy 407.863014 -400.784883)
			(xy 407.870277 -400.732674) (xy 407.884656 -400.681962) (xy 407.905877 -400.633711) (xy 407.933536 -400.58884)
			(xy 407.967108 -400.548203) (xy 407.98623 -400.53006) (xy 407.993342 -400.52371) (xy 408.00147 -400.506946)
			(xy 408.009852 -400.420332) (xy 408.004772 -400.402552) (xy 407.999184 -400.394678) (xy 407.985038 -400.374828)
			(xy 407.962579 -400.331571) (xy 407.947265 -400.285299) (xy 407.939485 -400.237184) (xy 407.938986 -400.212814)
			(xy 407.939508 -400.187559) (xy 407.947821 -400.137737) (xy 407.964222 -400.089963) (xy 407.988263 -400.04554)
			(xy 408.019287 -400.00568) (xy 408.056449 -399.97147) (xy 408.098735 -399.943844) (xy 408.144991 -399.923554)
			(xy 408.193956 -399.911154) (xy 408.244294 -399.906983) (xy 408.294632 -399.911154) (xy 408.343597 -399.923554)
			(xy 408.389853 -399.943844) (xy 408.432139 -399.97147) (xy 408.469301 -400.00568) (xy 408.500325 -400.04554)
			(xy 408.524366 -400.089963) (xy 408.540767 -400.137737) (xy 408.54908 -400.187559) (xy 408.549602 -400.212814)
			(xy 408.549133 -400.237187) (xy 408.541373 -400.285311) (xy 408.526053 -400.331586) (xy 408.503563 -400.374834)
			(xy 408.489404 -400.394678) (xy 408.483816 -400.402552) (xy 408.478736 -400.420332) (xy 408.487118 -400.506946)
			(xy 408.495246 -400.52371) (xy 408.502358 -400.53006) (xy 408.521493 -400.548192) (xy 408.555081 -400.588824)
			(xy 408.582752 -400.633694) (xy 408.603979 -400.681947) (xy 408.618358 -400.732665) (xy 408.625613 -400.78488)
			(xy 408.626056 -400.811238) (xy 408.626056 -401.674838) (xy 409.062428 -401.674838) (xy 409.062428 -400.811238)
			(xy 409.062912 -400.784883) (xy 409.070174 -400.732674) (xy 409.084553 -400.681962) (xy 409.105774 -400.633712)
			(xy 409.133433 -400.58884) (xy 409.167004 -400.548203) (xy 409.186126 -400.53006) (xy 409.193238 -400.52371)
			(xy 409.201366 -400.506946) (xy 409.209748 -400.420332) (xy 409.204668 -400.402552) (xy 409.19908 -400.394678)
			(xy 409.184933 -400.374829) (xy 409.162474 -400.331571) (xy 409.147161 -400.285299) (xy 409.13938 -400.237184)
			(xy 409.138882 -400.212814) (xy 409.139404 -400.187559) (xy 409.147717 -400.137737) (xy 409.164118 -400.089963)
			(xy 409.188159 -400.04554) (xy 409.219183 -400.00568) (xy 409.256345 -399.97147) (xy 409.298631 -399.943844)
			(xy 409.344887 -399.923554) (xy 409.393852 -399.911154) (xy 409.44419 -399.906983) (xy 409.494528 -399.911154)
			(xy 409.543493 -399.923554) (xy 409.589749 -399.943844) (xy 409.632035 -399.97147) (xy 409.669197 -400.00568)
			(xy 409.700221 -400.04554) (xy 409.724262 -400.089963) (xy 409.740663 -400.137737) (xy 409.748976 -400.187559)
			(xy 409.749498 -400.212814) (xy 409.74903 -400.237187) (xy 409.74127 -400.285311) (xy 409.725949 -400.331587)
			(xy 409.703459 -400.374834) (xy 409.6893 -400.394678) (xy 409.683712 -400.402552) (xy 409.678632 -400.420332)
			(xy 409.687014 -400.506946) (xy 409.695142 -400.52371) (xy 409.702254 -400.53006) (xy 409.721389 -400.548193)
			(xy 409.754976 -400.588824) (xy 409.782648 -400.633694) (xy 409.803875 -400.681948) (xy 409.818253 -400.732665)
			(xy 409.825509 -400.78488) (xy 409.825952 -400.811238) (xy 409.825952 -401.674838) (xy 410.262832 -401.674838)
			(xy 410.262832 -400.811238) (xy 410.263302 -400.784894) (xy 410.270549 -400.732705) (xy 410.284897 -400.682007)
			(xy 410.306074 -400.633761) (xy 410.333678 -400.588882) (xy 410.367187 -400.548221) (xy 410.386276 -400.53006)
			(xy 410.393388 -400.52371) (xy 410.401516 -400.506946) (xy 410.409898 -400.420332) (xy 410.404818 -400.402552)
			(xy 410.39923 -400.394678) (xy 410.385077 -400.374833) (xy 410.362621 -400.331573) (xy 410.34731 -400.2853)
			(xy 410.33953 -400.237184) (xy 410.339032 -400.212814) (xy 410.339554 -400.187559) (xy 410.347867 -400.137737)
			(xy 410.364268 -400.089963) (xy 410.388309 -400.04554) (xy 410.419333 -400.00568) (xy 410.456495 -399.97147)
			(xy 410.498781 -399.943844) (xy 410.545037 -399.923554) (xy 410.594002 -399.911154) (xy 410.64434 -399.906983)
			(xy 410.694678 -399.911154) (xy 410.743643 -399.923554) (xy 410.789899 -399.943844) (xy 410.832185 -399.97147)
			(xy 410.869347 -400.00568) (xy 410.900371 -400.04554) (xy 410.924412 -400.089963) (xy 410.940813 -400.137737)
			(xy 410.949126 -400.187559) (xy 410.949648 -400.212814) (xy 410.94917 -400.237186) (xy 410.941411 -400.28531)
			(xy 410.926093 -400.331585) (xy 410.903607 -400.374833) (xy 410.88945 -400.394678) (xy 410.883862 -400.402552)
			(xy 410.878782 -400.420332) (xy 410.887164 -400.506946) (xy 410.895292 -400.52371) (xy 410.902404 -400.53006)
			(xy 410.921498 -400.548219) (xy 410.955022 -400.588873) (xy 410.982637 -400.633749) (xy 411.00382 -400.681997)
			(xy 411.018168 -400.732698) (xy 411.025408 -400.784892) (xy 411.025848 -400.811238) (xy 411.025848 -401.674838)
			(xy 411.462728 -401.674838) (xy 411.462728 -400.811238) (xy 411.463167 -400.784892) (xy 411.470416 -400.732701)
			(xy 411.484768 -400.682002) (xy 411.505951 -400.633755) (xy 411.533562 -400.588877) (xy 411.567078 -400.548219)
			(xy 411.586172 -400.53006) (xy 411.593284 -400.52371) (xy 411.601412 -400.506946) (xy 411.609794 -400.420332)
			(xy 411.604714 -400.402552) (xy 411.599126 -400.394678) (xy 411.584973 -400.374833) (xy 411.562517 -400.331574)
			(xy 411.547205 -400.2853) (xy 411.539426 -400.237184) (xy 411.538928 -400.212814) (xy 411.53945 -400.187559)
			(xy 411.547763 -400.137737) (xy 411.564164 -400.089963) (xy 411.588205 -400.04554) (xy 411.619229 -400.00568)
			(xy 411.656391 -399.97147) (xy 411.698677 -399.943844) (xy 411.744933 -399.923554) (xy 411.793898 -399.911154)
			(xy 411.844236 -399.906983) (xy 411.894574 -399.911154) (xy 411.943539 -399.923554) (xy 411.989795 -399.943844)
			(xy 412.032081 -399.97147) (xy 412.069243 -400.00568) (xy 412.100267 -400.04554) (xy 412.124308 -400.089963)
			(xy 412.140709 -400.137737) (xy 412.149022 -400.187559) (xy 412.149544 -400.212814) (xy 412.149067 -400.237186)
			(xy 412.141308 -400.28531) (xy 412.12599 -400.331585) (xy 412.103503 -400.374833) (xy 412.089346 -400.394678)
			(xy 412.083758 -400.402552) (xy 412.078678 -400.420332) (xy 412.08706 -400.506946) (xy 412.095188 -400.52371)
			(xy 412.1023 -400.53006) (xy 412.121413 -400.5482) (xy 412.154931 -400.58886) (xy 412.182542 -400.633741)
			(xy 412.203721 -400.681992) (xy 412.218066 -400.732696) (xy 412.225304 -400.784891) (xy 412.225744 -400.811238)
			(xy 412.225744 -401.674838) (xy 412.662624 -401.674838) (xy 412.662624 -400.811238) (xy 412.663058 -400.784911)
			(xy 412.670308 -400.732757) (xy 412.684662 -400.682096) (xy 412.705846 -400.633891) (xy 412.733459 -400.589057)
			(xy 412.766976 -400.548447) (xy 412.786068 -400.530314) (xy 412.79318 -400.52371) (xy 412.801562 -400.5072)
			(xy 412.80969 -400.420332) (xy 412.80461 -400.402552) (xy 412.799022 -400.394932) (xy 412.784869 -400.375048)
			(xy 412.76238 -400.331735) (xy 412.747062 -400.285398) (xy 412.739302 -400.237216) (xy 412.738824 -400.212814)
			(xy 412.739346 -400.187559) (xy 412.747659 -400.137737) (xy 412.76406 -400.089963) (xy 412.788101 -400.04554)
			(xy 412.819125 -400.00568) (xy 412.856287 -399.97147) (xy 412.898573 -399.943844) (xy 412.944829 -399.923554)
			(xy 412.993794 -399.911154) (xy 413.044132 -399.906983) (xy 413.09447 -399.911154) (xy 413.143435 -399.923554)
			(xy 413.189691 -399.943844) (xy 413.231977 -399.97147) (xy 413.269139 -400.00568) (xy 413.300163 -400.04554)
			(xy 413.324204 -400.089963) (xy 413.340605 -400.137737) (xy 413.348918 -400.187559) (xy 413.34944 -400.212814)
			(xy 413.348944 -400.237172) (xy 413.341232 -400.285275) (xy 413.325988 -400.331545) (xy 413.303599 -400.374812)
			(xy 413.289496 -400.394678) (xy 413.283654 -400.402298) (xy 413.278828 -400.420078) (xy 413.286956 -400.506946)
			(xy 413.295338 -400.523456) (xy 413.30245 -400.53006) (xy 413.321584 -400.548194) (xy 413.355172 -400.588825)
			(xy 413.382843 -400.633694) (xy 413.404071 -400.681948) (xy 413.418449 -400.732665) (xy 413.425705 -400.78488)
			(xy 413.426148 -400.811238) (xy 413.426148 -401.674838) (xy 413.86252 -401.674838) (xy 413.86252 -400.811238)
			(xy 413.863006 -400.784883) (xy 413.870269 -400.732675) (xy 413.884647 -400.681963) (xy 413.905867 -400.633712)
			(xy 413.933526 -400.588841) (xy 413.967096 -400.548203) (xy 413.986218 -400.53006) (xy 413.99333 -400.52371)
			(xy 414.001458 -400.506946) (xy 414.00984 -400.420332) (xy 414.00476 -400.402552) (xy 413.999172 -400.394678)
			(xy 413.985024 -400.374829) (xy 413.962566 -400.331572) (xy 413.947253 -400.285299) (xy 413.939472 -400.237184)
			(xy 413.938974 -400.212814) (xy 413.939496 -400.187559) (xy 413.947809 -400.137737) (xy 413.96421 -400.089963)
			(xy 413.988251 -400.04554) (xy 414.019275 -400.00568) (xy 414.056437 -399.97147) (xy 414.098723 -399.943844)
			(xy 414.144979 -399.923554) (xy 414.193944 -399.911154) (xy 414.244282 -399.906983) (xy 414.29462 -399.911154)
			(xy 414.343585 -399.923554) (xy 414.389841 -399.943844) (xy 414.432127 -399.97147) (xy 414.469289 -400.00568)
			(xy 414.500313 -400.04554) (xy 414.524354 -400.089963) (xy 414.540755 -400.137737) (xy 414.549068 -400.187559)
			(xy 414.54959 -400.212814) (xy 414.549123 -400.237187) (xy 414.541363 -400.285311) (xy 414.526042 -400.331587)
			(xy 414.503552 -400.374834) (xy 414.489392 -400.394678) (xy 414.483804 -400.402552) (xy 414.478724 -400.420332)
			(xy 414.487106 -400.506946) (xy 414.495234 -400.52371) (xy 414.502346 -400.53006) (xy 414.521479 -400.548195)
			(xy 414.555067 -400.588825) (xy 414.582739 -400.633695) (xy 414.603967 -400.681948) (xy 414.618345 -400.732665)
			(xy 414.625601 -400.78488) (xy 414.626044 -400.811238) (xy 414.626044 -401.674838) (xy 415.062924 -401.674838)
			(xy 415.062924 -400.811238) (xy 415.063348 -400.784921) (xy 415.070573 -400.732785) (xy 415.084891 -400.682136)
			(xy 415.106031 -400.633934) (xy 415.133592 -400.589093) (xy 415.167051 -400.548463) (xy 415.186114 -400.530314)
			(xy 415.193226 -400.52371) (xy 415.201608 -400.5072) (xy 415.209736 -400.420332) (xy 415.204656 -400.402552)
			(xy 415.199068 -400.394932) (xy 415.184908 -400.375053) (xy 415.162423 -400.331737) (xy 415.147106 -400.285399)
			(xy 415.139348 -400.237216) (xy 415.13887 -400.212814) (xy 415.139392 -400.187559) (xy 415.147705 -400.137737)
			(xy 415.164106 -400.089963) (xy 415.188147 -400.04554) (xy 415.219171 -400.00568) (xy 415.256333 -399.97147)
			(xy 415.298619 -399.943844) (xy 415.344875 -399.923554) (xy 415.39384 -399.911154) (xy 415.444178 -399.906983)
			(xy 415.494516 -399.911154) (xy 415.543481 -399.923554) (xy 415.589737 -399.943844) (xy 415.632023 -399.97147)
			(xy 415.669185 -400.00568) (xy 415.700209 -400.04554) (xy 415.72425 -400.089963) (xy 415.740651 -400.137737)
			(xy 415.748964 -400.187559) (xy 415.749486 -400.212814) (xy 415.749 -400.237173) (xy 415.741286 -400.285276)
			(xy 415.72604 -400.331547) (xy 415.703647 -400.374813) (xy 415.689542 -400.394678) (xy 415.6837 -400.402298)
			(xy 415.678874 -400.420078) (xy 415.687002 -400.506946) (xy 415.695384 -400.523456) (xy 415.702496 -400.53006)
			(xy 415.721608 -400.548201) (xy 415.755127 -400.58886) (xy 415.782738 -400.633741) (xy 415.803917 -400.681992)
			(xy 415.818262 -400.732696) (xy 415.8255 -400.784891) (xy 415.82594 -400.811238) (xy 415.82594 -401.674838)
			(xy 416.26282 -401.674838) (xy 416.26282 -400.811238) (xy 416.263262 -400.784892) (xy 416.27051 -400.732702)
			(xy 416.284862 -400.682002) (xy 416.306044 -400.633756) (xy 416.333655 -400.588877) (xy 416.367171 -400.548219)
			(xy 416.386264 -400.53006) (xy 416.393376 -400.52371) (xy 416.401504 -400.506946) (xy 416.409886 -400.420332)
			(xy 416.404806 -400.402552) (xy 416.399218 -400.394678) (xy 416.385064 -400.374834) (xy 416.362608 -400.331574)
			(xy 416.347297 -400.2853) (xy 416.339518 -400.237184) (xy 416.33902 -400.212814) (xy 416.339542 -400.187559)
			(xy 416.347855 -400.137737) (xy 416.364256 -400.089963) (xy 416.388297 -400.04554) (xy 416.419321 -400.00568)
			(xy 416.456483 -399.97147) (xy 416.498769 -399.943844) (xy 416.545025 -399.923554) (xy 416.59399 -399.911154)
			(xy 416.644328 -399.906983) (xy 416.694666 -399.911154) (xy 416.743631 -399.923554) (xy 416.789887 -399.943844)
			(xy 416.832173 -399.97147) (xy 416.869335 -400.00568) (xy 416.900359 -400.04554) (xy 416.9244 -400.089963)
			(xy 416.940801 -400.137737) (xy 416.949114 -400.187559) (xy 416.949636 -400.212814) (xy 416.94916 -400.237186)
			(xy 416.941401 -400.28531) (xy 416.926083 -400.331585) (xy 416.903596 -400.374833) (xy 416.889438 -400.394678)
			(xy 416.88385 -400.402552) (xy 416.87877 -400.420332) (xy 416.887152 -400.506946) (xy 416.89528 -400.52371)
			(xy 416.902392 -400.53006) (xy 416.921503 -400.548201) (xy 416.955022 -400.588861) (xy 416.982633 -400.633742)
			(xy 417.003813 -400.681992) (xy 417.018158 -400.732696) (xy 417.025396 -400.784891) (xy 417.025836 -400.811238)
			(xy 417.025836 -401.674838) (xy 417.462716 -401.674838) (xy 417.462716 -400.811238) (xy 417.463159 -400.784892)
			(xy 417.470408 -400.732702) (xy 417.484759 -400.682002) (xy 417.505941 -400.633756) (xy 417.533552 -400.588878)
			(xy 417.567067 -400.548219) (xy 417.58616 -400.53006) (xy 417.593272 -400.52371) (xy 417.6014 -400.506946)
			(xy 417.609782 -400.420332) (xy 417.604702 -400.402552) (xy 417.599114 -400.394678) (xy 417.584959 -400.374834)
			(xy 417.562504 -400.331574) (xy 417.547193 -400.2853) (xy 417.539414 -400.237184) (xy 417.538916 -400.212814)
			(xy 417.539438 -400.187559) (xy 417.547751 -400.137737) (xy 417.564152 -400.089963) (xy 417.588193 -400.04554)
			(xy 417.619217 -400.00568) (xy 417.656379 -399.97147) (xy 417.698665 -399.943844) (xy 417.744921 -399.923554)
			(xy 417.793886 -399.911154) (xy 417.844224 -399.906983) (xy 417.894562 -399.911154) (xy 417.943527 -399.923554)
			(xy 417.989783 -399.943844) (xy 418.032069 -399.97147) (xy 418.069231 -400.00568) (xy 418.100255 -400.04554)
			(xy 418.124296 -400.089963) (xy 418.140697 -400.137737) (xy 418.14901 -400.187559) (xy 418.149532 -400.212814)
			(xy 418.149057 -400.237186) (xy 418.141298 -400.28531) (xy 418.125979 -400.331585) (xy 418.103492 -400.374833)
			(xy 418.089334 -400.394678) (xy 418.083746 -400.402552) (xy 418.078666 -400.420332) (xy 418.087048 -400.506946)
			(xy 418.095176 -400.52371) (xy 418.102288 -400.53006) (xy 418.121398 -400.548202) (xy 418.154917 -400.588861)
			(xy 418.182529 -400.633742) (xy 418.203708 -400.681992) (xy 418.218054 -400.732696) (xy 418.225292 -400.784891)
			(xy 418.225732 -400.811238) (xy 418.225732 -401.674838) (xy 418.662612 -401.674838) (xy 418.662612 -400.811238)
			(xy 418.663056 -400.784892) (xy 418.670305 -400.732702) (xy 418.684656 -400.682003) (xy 418.705838 -400.633756)
			(xy 418.733448 -400.588878) (xy 418.766963 -400.548219) (xy 418.786056 -400.53006) (xy 418.793168 -400.52371)
			(xy 418.801296 -400.506946) (xy 418.809678 -400.420332) (xy 418.804598 -400.402552) (xy 418.79901 -400.394678)
			(xy 418.784867 -400.374826) (xy 418.762406 -400.33157) (xy 418.747092 -400.285298) (xy 418.739311 -400.237184)
			(xy 418.738812 -400.212814) (xy 418.739334 -400.187559) (xy 418.747647 -400.137737) (xy 418.764048 -400.089963)
			(xy 418.788089 -400.04554) (xy 418.819113 -400.00568) (xy 418.856275 -399.97147) (xy 418.898561 -399.943844)
			(xy 418.944817 -399.923554) (xy 418.993782 -399.911154) (xy 419.04412 -399.906983) (xy 419.094458 -399.911154)
			(xy 419.143423 -399.923554) (xy 419.189679 -399.943844) (xy 419.231965 -399.97147) (xy 419.269127 -400.00568)
			(xy 419.300151 -400.04554) (xy 419.324192 -400.089963) (xy 419.340593 -400.137737) (xy 419.348906 -400.187559)
			(xy 419.349428 -400.212814) (xy 419.348954 -400.237187) (xy 419.341195 -400.28531) (xy 419.325876 -400.331586)
			(xy 419.303388 -400.374834) (xy 419.28923 -400.394678) (xy 419.283642 -400.402552) (xy 419.278562 -400.420332)
			(xy 419.286944 -400.506946) (xy 419.295072 -400.52371) (xy 419.302184 -400.53006) (xy 419.321294 -400.548203)
			(xy 419.354813 -400.588862) (xy 419.382425 -400.633742) (xy 419.403604 -400.681993) (xy 419.41795 -400.732696)
			(xy 419.425188 -400.784891) (xy 419.425628 -400.811238) (xy 419.425628 -401.674838) (xy 419.862508 -401.674838)
			(xy 419.862508 -400.811238) (xy 419.862966 -400.784881) (xy 419.87023 -400.732671) (xy 419.884612 -400.681957)
			(xy 419.905837 -400.633706) (xy 419.933502 -400.588836) (xy 419.96708 -400.548201) (xy 419.986206 -400.53006)
			(xy 419.993318 -400.52371) (xy 420.001446 -400.506946) (xy 420.009828 -400.420332) (xy 420.004748 -400.402552)
			(xy 419.99916 -400.394678) (xy 419.985011 -400.37483) (xy 419.962553 -400.331572) (xy 419.94724 -400.285299)
			(xy 419.93946 -400.237184) (xy 419.938962 -400.212814) (xy 419.939484 -400.187559) (xy 419.947797 -400.137737)
			(xy 419.964198 -400.089963) (xy 419.988239 -400.04554) (xy 420.019263 -400.00568) (xy 420.056425 -399.97147)
			(xy 420.098711 -399.943844) (xy 420.144967 -399.923554) (xy 420.193932 -399.911154) (xy 420.24427 -399.906983)
			(xy 420.294608 -399.911154) (xy 420.343573 -399.923554) (xy 420.389829 -399.943844) (xy 420.432115 -399.97147)
			(xy 420.469277 -400.00568) (xy 420.500301 -400.04554) (xy 420.524342 -400.089963) (xy 420.540743 -400.137737)
			(xy 420.549056 -400.187559) (xy 420.549578 -400.212814) (xy 420.549114 -400.237187) (xy 420.541353 -400.285311)
			(xy 420.526032 -400.331587) (xy 420.50354 -400.374834) (xy 420.48938 -400.394678) (xy 420.483792 -400.402552)
			(xy 420.478712 -400.420332) (xy 420.487094 -400.506946) (xy 420.495222 -400.52371) (xy 420.502334 -400.53006)
			(xy 420.521465 -400.548197) (xy 420.555054 -400.588827) (xy 420.582726 -400.633696) (xy 420.603954 -400.681949)
			(xy 420.618333 -400.732666) (xy 420.625589 -400.78488) (xy 420.626032 -400.811238) (xy 420.626032 -401.674838)
			(xy 420.625607 -401.701012) (xy 420.61841 -401.752864) (xy 420.604197 -401.803247) (xy 420.583236 -401.851216)
			(xy 420.555918 -401.895872) (xy 420.522757 -401.936378) (xy 420.503858 -401.954492) (xy 420.496492 -401.96135)
			(xy 420.488364 -401.978876) (xy 420.48303 -402.069046) (xy 420.489126 -402.087334) (xy 420.49573 -402.094954)
			(xy 420.510635 -402.112995) (xy 420.535697 -402.152514) (xy 420.554944 -402.195169) (xy 420.56799 -402.240109)
			(xy 420.574576 -402.28644) (xy 420.574978 -402.309838) (xy 420.574468 -402.335825) (xy 420.566338 -402.38716)
			(xy 420.550277 -402.43659) (xy 420.526681 -402.4829) (xy 420.496131 -402.524948) (xy 420.45938 -402.561699)
			(xy 420.417332 -402.592249) (xy 420.371022 -402.615845) (xy 420.321592 -402.631906) (xy 420.270257 -402.640036)
			(xy 420.218283 -402.640036) (xy 420.166948 -402.631906) (xy 420.117518 -402.615845) (xy 420.071208 -402.592249)
			(xy 420.02916 -402.561699) (xy 419.992409 -402.524948) (xy 419.961859 -402.4829) (xy 419.938263 -402.43659)
			(xy 419.922202 -402.38716) (xy 419.914072 -402.335825) (xy 419.913562 -402.309838) (xy 419.913984 -402.286442)
			(xy 419.92057 -402.240114) (xy 419.933617 -402.195177) (xy 419.952864 -402.152526) (xy 419.977928 -402.113012)
			(xy 419.99281 -402.094954) (xy 419.999414 -402.087334) (xy 420.00551 -402.069046) (xy 420.000176 -401.978876)
			(xy 419.992048 -401.96135) (xy 419.984682 -401.954492) (xy 419.965782 -401.936379) (xy 419.93262 -401.895875)
			(xy 419.905304 -401.851219) (xy 419.884347 -401.803249) (xy 419.870142 -401.752865) (xy 419.862956 -401.701012)
			(xy 419.862508 -401.674838) (xy 419.425628 -401.674838) (xy 419.425147 -401.701) (xy 419.417998 -401.752834)
			(xy 419.403839 -401.803207) (xy 419.382935 -401.851175) (xy 419.355677 -401.895839) (xy 419.322577 -401.936364)
			(xy 419.303708 -401.954492) (xy 419.296342 -401.96135) (xy 419.288214 -401.978876) (xy 419.28288 -402.069046)
			(xy 419.288976 -402.087334) (xy 419.29558 -402.094954) (xy 419.310477 -402.113001) (xy 419.335542 -402.152517)
			(xy 419.354791 -402.195171) (xy 419.367839 -402.24011) (xy 419.374426 -402.28644) (xy 419.374828 -402.309838)
			(xy 419.374318 -402.335825) (xy 419.366188 -402.38716) (xy 419.350127 -402.43659) (xy 419.326531 -402.4829)
			(xy 419.295981 -402.524948) (xy 419.25923 -402.561699) (xy 419.217182 -402.592249) (xy 419.170872 -402.615845)
			(xy 419.121442 -402.631906) (xy 419.070107 -402.640036) (xy 419.018133 -402.640036) (xy 418.966798 -402.631906)
			(xy 418.917368 -402.615845) (xy 418.871058 -402.592249) (xy 418.82901 -402.561699) (xy 418.792259 -402.524948)
			(xy 418.761709 -402.4829) (xy 418.738113 -402.43659) (xy 418.722052 -402.38716) (xy 418.713922 -402.335825)
			(xy 418.713412 -402.309838) (xy 418.713846 -402.286442) (xy 418.720431 -402.240116) (xy 418.733476 -402.195179)
			(xy 418.75272 -402.152528) (xy 418.77778 -402.113013) (xy 418.79266 -402.094954) (xy 418.799264 -402.087334)
			(xy 418.80536 -402.069046) (xy 418.800026 -401.978876) (xy 418.791898 -401.96135) (xy 418.784532 -401.954492)
			(xy 418.765644 -401.93638) (xy 418.732525 -401.895861) (xy 418.705254 -401.851197) (xy 418.684342 -401.803225)
			(xy 418.670182 -401.752846) (xy 418.663039 -401.701004) (xy 418.662612 -401.674838) (xy 418.225732 -401.674838)
			(xy 418.225199 -401.703743) (xy 418.216494 -401.760893) (xy 418.199273 -401.816077) (xy 418.17393 -401.868035)
			(xy 418.141044 -401.915579) (xy 418.121592 -401.936966) (xy 418.115496 -401.94357) (xy 418.108384 -401.959572)
			(xy 418.102796 -402.041868) (xy 418.107622 -402.058886) (xy 418.112702 -402.065998) (xy 418.127345 -402.087224)
			(xy 418.150595 -402.133247) (xy 418.166419 -402.182321) (xy 418.174433 -402.233257) (xy 418.174932 -402.259038)
			(xy 418.174422 -402.285025) (xy 418.166292 -402.33636) (xy 418.150231 -402.38579) (xy 418.126635 -402.4321)
			(xy 418.096085 -402.474148) (xy 418.059334 -402.510899) (xy 418.017286 -402.541449) (xy 417.970976 -402.565045)
			(xy 417.921546 -402.581106) (xy 417.870211 -402.589236) (xy 417.818237 -402.589236) (xy 417.766902 -402.581106)
			(xy 417.717472 -402.565045) (xy 417.671162 -402.541449) (xy 417.629114 -402.510899) (xy 417.592363 -402.474148)
			(xy 417.561813 -402.4321) (xy 417.538217 -402.38579) (xy 417.522156 -402.33636) (xy 417.514026 -402.285025)
			(xy 417.513516 -402.259038) (xy 417.513986 -402.233254) (xy 417.521994 -402.182313) (xy 417.537821 -402.133234)
			(xy 417.561083 -402.087212) (xy 417.575746 -402.065998) (xy 417.580826 -402.058886) (xy 417.585652 -402.041868)
			(xy 417.580064 -401.959572) (xy 417.572952 -401.94357) (xy 417.566856 -401.936966) (xy 417.547366 -401.91561)
			(xy 417.51446 -401.86807) (xy 417.489111 -401.816106) (xy 417.471901 -401.760909) (xy 417.463224 -401.703747)
			(xy 417.462716 -401.674838) (xy 417.025836 -401.674838) (xy 417.025384 -401.701002) (xy 417.018233 -401.752838)
			(xy 417.00407 -401.803212) (xy 416.983161 -401.851181) (xy 416.955897 -401.895844) (xy 416.922789 -401.936366)
			(xy 416.903916 -401.954492) (xy 416.89655 -401.96135) (xy 416.888422 -401.978876) (xy 416.883088 -402.069046)
			(xy 416.889184 -402.087334) (xy 416.895788 -402.094954) (xy 416.910686 -402.113) (xy 416.935751 -402.152517)
			(xy 416.955 -402.19517) (xy 416.968047 -402.24011) (xy 416.974634 -402.28644) (xy 416.975036 -402.309838)
			(xy 416.974526 -402.335825) (xy 416.966396 -402.38716) (xy 416.950335 -402.43659) (xy 416.926739 -402.4829)
			(xy 416.896189 -402.524948) (xy 416.859438 -402.561699) (xy 416.81739 -402.592249) (xy 416.77108 -402.615845)
			(xy 416.72165 -402.631906) (xy 416.670315 -402.640036) (xy 416.618341 -402.640036) (xy 416.567006 -402.631906)
			(xy 416.517576 -402.615845) (xy 416.471266 -402.592249) (xy 416.429218 -402.561699) (xy 416.392467 -402.524948)
			(xy 416.361917 -402.4829) (xy 416.338321 -402.43659) (xy 416.32226 -402.38716) (xy 416.31413 -402.335825)
			(xy 416.31362 -402.309838) (xy 416.314052 -402.286442) (xy 416.320637 -402.240116) (xy 416.333683 -402.195179)
			(xy 416.352927 -402.152528) (xy 416.377987 -402.113012) (xy 416.392868 -402.094954) (xy 416.399472 -402.087334)
			(xy 416.405568 -402.069046) (xy 416.400234 -401.978876) (xy 416.392106 -401.96135) (xy 416.38474 -401.954492)
			(xy 416.365853 -401.936378) (xy 416.332734 -401.89586) (xy 416.305462 -401.851196) (xy 416.28455 -401.803225)
			(xy 416.27039 -401.752846) (xy 416.263247 -401.701004) (xy 416.26282 -401.674838) (xy 415.82594 -401.674838)
			(xy 415.825486 -401.701002) (xy 415.818335 -401.752838) (xy 415.804173 -401.803212) (xy 415.783264 -401.85118)
			(xy 415.756 -401.895844) (xy 415.722893 -401.936366) (xy 415.70402 -401.954492) (xy 415.696654 -401.96135)
			(xy 415.688526 -401.978876) (xy 415.683192 -402.069046) (xy 415.689288 -402.087334) (xy 415.695892 -402.094954)
			(xy 415.710791 -402.112999) (xy 415.735856 -402.152516) (xy 415.755104 -402.19517) (xy 415.768151 -402.24011)
			(xy 415.774738 -402.28644) (xy 415.77514 -402.309838) (xy 415.77463 -402.335825) (xy 415.7665 -402.38716)
			(xy 415.750439 -402.43659) (xy 415.726843 -402.4829) (xy 415.696293 -402.524948) (xy 415.659542 -402.561699)
			(xy 415.617494 -402.592249) (xy 415.571184 -402.615845) (xy 415.521754 -402.631906) (xy 415.470419 -402.640036)
			(xy 415.418445 -402.640036) (xy 415.36711 -402.631906) (xy 415.31768 -402.615845) (xy 415.27137 -402.592249)
			(xy 415.229322 -402.561699) (xy 415.192571 -402.524948) (xy 415.162021 -402.4829) (xy 415.138425 -402.43659)
			(xy 415.122364 -402.38716) (xy 415.114234 -402.335825) (xy 415.113724 -402.309838) (xy 415.114155 -402.286442)
			(xy 415.120741 -402.240116) (xy 415.133786 -402.195179) (xy 415.153031 -402.152528) (xy 415.178091 -402.113012)
			(xy 415.192972 -402.094954) (xy 415.199576 -402.087334) (xy 415.205672 -402.069046) (xy 415.200338 -401.978876)
			(xy 415.19221 -401.96135) (xy 415.184844 -401.954492) (xy 415.165958 -401.936377) (xy 415.132838 -401.89586)
			(xy 415.105567 -401.851196) (xy 415.084654 -401.803225) (xy 415.070494 -401.752845) (xy 415.063351 -401.701004)
			(xy 415.062924 -401.674838) (xy 414.626044 -401.674838) (xy 414.625615 -401.701012) (xy 414.618418 -401.752864)
			(xy 414.604206 -401.803246) (xy 414.583246 -401.851215) (xy 414.555929 -401.895871) (xy 414.522768 -401.936378)
			(xy 414.50387 -401.954492) (xy 414.496504 -401.96135) (xy 414.488376 -401.978876) (xy 414.483042 -402.069046)
			(xy 414.489138 -402.087334) (xy 414.495742 -402.094954) (xy 414.510648 -402.112993) (xy 414.53571 -402.152513)
			(xy 414.554956 -402.195168) (xy 414.568002 -402.240109) (xy 414.574588 -402.28644) (xy 414.57499 -402.309838)
			(xy 414.57448 -402.335825) (xy 414.56635 -402.38716) (xy 414.550289 -402.43659) (xy 414.526693 -402.4829)
			(xy 414.496143 -402.524948) (xy 414.459392 -402.561699) (xy 414.417344 -402.592249) (xy 414.371034 -402.615845)
			(xy 414.321604 -402.631906) (xy 414.270269 -402.640036) (xy 414.218295 -402.640036) (xy 414.16696 -402.631906)
			(xy 414.11753 -402.615845) (xy 414.07122 -402.592249) (xy 414.029172 -402.561699) (xy 413.992421 -402.524948)
			(xy 413.961871 -402.4829) (xy 413.938275 -402.43659) (xy 413.922214 -402.38716) (xy 413.914084 -402.335825)
			(xy 413.913574 -402.309838) (xy 413.913993 -402.286441) (xy 413.92058 -402.240114) (xy 413.933627 -402.195177)
			(xy 413.952875 -402.152526) (xy 413.977939 -402.113011) (xy 413.992822 -402.094954) (xy 413.999426 -402.087334)
			(xy 414.005522 -402.069046) (xy 414.000188 -401.978876) (xy 413.99206 -401.96135) (xy 413.984694 -401.954492)
			(xy 413.965797 -401.936377) (xy 413.932633 -401.895873) (xy 413.905317 -401.851218) (xy 413.884359 -401.803248)
			(xy 413.870154 -401.752864) (xy 413.862968 -401.701012) (xy 413.86252 -401.674838) (xy 413.426148 -401.674838)
			(xy 413.425718 -401.701012) (xy 413.418521 -401.752863) (xy 413.404309 -401.803246) (xy 413.383349 -401.851215)
			(xy 413.356032 -401.895871) (xy 413.322872 -401.936377) (xy 413.303974 -401.954492) (xy 413.296608 -401.96135)
			(xy 413.28848 -401.978876) (xy 413.283146 -402.069046) (xy 413.289242 -402.087334) (xy 413.295846 -402.094954)
			(xy 413.310753 -402.112993) (xy 413.335815 -402.152512) (xy 413.35506 -402.195168) (xy 413.368106 -402.240109)
			(xy 413.374692 -402.28644) (xy 413.375094 -402.309838) (xy 413.374584 -402.335825) (xy 413.366454 -402.38716)
			(xy 413.350393 -402.43659) (xy 413.326797 -402.4829) (xy 413.296247 -402.524948) (xy 413.259496 -402.561699)
			(xy 413.217448 -402.592249) (xy 413.171138 -402.615845) (xy 413.121708 -402.631906) (xy 413.070373 -402.640036)
			(xy 413.018399 -402.640036) (xy 412.967064 -402.631906) (xy 412.917634 -402.615845) (xy 412.871324 -402.592249)
			(xy 412.829276 -402.561699) (xy 412.792525 -402.524948) (xy 412.761975 -402.4829) (xy 412.738379 -402.43659)
			(xy 412.722318 -402.38716) (xy 412.714188 -402.335825) (xy 412.713678 -402.309838) (xy 412.714096 -402.286441)
			(xy 412.720683 -402.240114) (xy 412.73373 -402.195177) (xy 412.752978 -402.152525) (xy 412.778043 -402.113011)
			(xy 412.792926 -402.094954) (xy 412.79953 -402.087334) (xy 412.805626 -402.069046) (xy 412.800292 -401.978876)
			(xy 412.792164 -401.96135) (xy 412.784798 -401.954492) (xy 412.765901 -401.936376) (xy 412.732738 -401.895873)
			(xy 412.705421 -401.851218) (xy 412.684464 -401.803248) (xy 412.670258 -401.752864) (xy 412.663072 -401.701012)
			(xy 412.662624 -401.674838) (xy 412.225744 -401.674838) (xy 412.225188 -401.704987) (xy 412.215732 -401.764539)
			(xy 412.197029 -401.821862) (xy 412.169545 -401.875532) (xy 412.133963 -401.924212) (xy 412.112968 -401.945856)
			(xy 412.106364 -401.95246) (xy 412.098744 -401.969224) (xy 412.09341 -402.05533) (xy 412.098744 -402.07311)
			(xy 412.104586 -402.080476) (xy 412.121096 -402.102462) (xy 412.147369 -402.150756) (xy 412.1653 -402.202728)
			(xy 412.174396 -402.256949) (xy 412.174944 -402.284438) (xy 412.174434 -402.310425) (xy 412.166304 -402.36176)
			(xy 412.150243 -402.41119) (xy 412.126647 -402.4575) (xy 412.096097 -402.499548) (xy 412.059346 -402.536299)
			(xy 412.017298 -402.566849) (xy 411.970988 -402.590445) (xy 411.921558 -402.606506) (xy 411.870223 -402.614636)
			(xy 411.818249 -402.614636) (xy 411.766914 -402.606506) (xy 411.717484 -402.590445) (xy 411.671174 -402.566849)
			(xy 411.629126 -402.536299) (xy 411.592375 -402.499548) (xy 411.561825 -402.4575) (xy 411.538229 -402.41119)
			(xy 411.522168 -402.36176) (xy 411.514038 -402.310425) (xy 411.513528 -402.284438) (xy 411.514075 -402.256947)
			(xy 411.523152 -402.202721) (xy 411.541078 -402.150744) (xy 411.56736 -402.102451) (xy 411.583886 -402.080476)
			(xy 411.589728 -402.07311) (xy 411.595062 -402.05533) (xy 411.589728 -401.969224) (xy 411.582108 -401.95246)
			(xy 411.575504 -401.945856) (xy 411.554509 -401.92421) (xy 411.518917 -401.875536) (xy 411.491428 -401.821867)
			(xy 411.472726 -401.764542) (xy 411.463278 -401.704988) (xy 411.462728 -401.674838) (xy 411.025848 -401.674838)
			(xy 411.025311 -401.703742) (xy 411.016606 -401.760892) (xy 410.999386 -401.816077) (xy 410.974044 -401.868035)
			(xy 410.941159 -401.915579) (xy 410.921708 -401.936966) (xy 410.915612 -401.94357) (xy 410.9085 -401.959572)
			(xy 410.902912 -402.041868) (xy 410.907738 -402.058886) (xy 410.912818 -402.065998) (xy 410.92745 -402.087231)
			(xy 410.950706 -402.13325) (xy 410.966533 -402.182322) (xy 410.974549 -402.233257) (xy 410.975048 -402.259038)
			(xy 410.974538 -402.285025) (xy 410.966408 -402.33636) (xy 410.950347 -402.38579) (xy 410.926751 -402.4321)
			(xy 410.896201 -402.474148) (xy 410.85945 -402.510899) (xy 410.817402 -402.541449) (xy 410.771092 -402.565045)
			(xy 410.721662 -402.581106) (xy 410.670327 -402.589236) (xy 410.618353 -402.589236) (xy 410.567018 -402.581106)
			(xy 410.517588 -402.565045) (xy 410.471278 -402.541449) (xy 410.42923 -402.510899) (xy 410.392479 -402.474148)
			(xy 410.361929 -402.4321) (xy 410.338333 -402.38579) (xy 410.322272 -402.33636) (xy 410.314142 -402.285025)
			(xy 410.313632 -402.259038) (xy 410.314117 -402.233255) (xy 410.322123 -402.182315) (xy 410.337946 -402.133237)
			(xy 410.361202 -402.087213) (xy 410.375862 -402.065998) (xy 410.380942 -402.058886) (xy 410.385768 -402.041868)
			(xy 410.38018 -401.959572) (xy 410.373068 -401.94357) (xy 410.366972 -401.936966) (xy 410.347484 -401.915607)
			(xy 410.314578 -401.868068) (xy 410.289228 -401.816105) (xy 410.272017 -401.760909) (xy 410.26334 -401.703747)
			(xy 410.262832 -401.674838) (xy 409.825952 -401.674838) (xy 409.82552 -401.701012) (xy 409.818324 -401.752863)
			(xy 409.804112 -401.803246) (xy 409.783152 -401.851215) (xy 409.755836 -401.895871) (xy 409.722676 -401.936377)
			(xy 409.703778 -401.954492) (xy 409.696412 -401.96135) (xy 409.688284 -401.978876) (xy 409.68295 -402.069046)
			(xy 409.689046 -402.087334) (xy 409.69565 -402.094954) (xy 409.710558 -402.112992) (xy 409.735619 -402.152512)
			(xy 409.754865 -402.195168) (xy 409.76791 -402.240109) (xy 409.774496 -402.28644) (xy 409.774898 -402.309838)
			(xy 409.774388 -402.335825) (xy 409.766258 -402.38716) (xy 409.750197 -402.43659) (xy 409.726601 -402.4829)
			(xy 409.696051 -402.524948) (xy 409.6593 -402.561699) (xy 409.617252 -402.592249) (xy 409.570942 -402.615845)
			(xy 409.521512 -402.631906) (xy 409.470177 -402.640036) (xy 409.418203 -402.640036) (xy 409.366868 -402.631906)
			(xy 409.317438 -402.615845) (xy 409.271128 -402.592249) (xy 409.22908 -402.561699) (xy 409.192329 -402.524948)
			(xy 409.161779 -402.4829) (xy 409.138183 -402.43659) (xy 409.122122 -402.38716) (xy 409.113992 -402.335825)
			(xy 409.113482 -402.309838) (xy 409.113923 -402.286442) (xy 409.120508 -402.240117) (xy 409.133551 -402.195181)
			(xy 409.152793 -402.152529) (xy 409.177851 -402.113013) (xy 409.19273 -402.094954) (xy 409.199334 -402.087334)
			(xy 409.20543 -402.069046) (xy 409.200096 -401.978876) (xy 409.191968 -401.96135) (xy 409.184602 -401.954492)
			(xy 409.165706 -401.936375) (xy 409.132543 -401.895872) (xy 409.105226 -401.851217) (xy 409.084268 -401.803248)
			(xy 409.070062 -401.752864) (xy 409.062876 -401.701012) (xy 409.062428 -401.674838) (xy 408.626056 -401.674838)
			(xy 408.625624 -401.701012) (xy 408.618427 -401.752863) (xy 408.604216 -401.803246) (xy 408.583256 -401.851215)
			(xy 408.55594 -401.895871) (xy 408.52278 -401.936378) (xy 408.503882 -401.954492) (xy 408.496516 -401.96135)
			(xy 408.488388 -401.978876) (xy 408.483054 -402.069046) (xy 408.48915 -402.087334) (xy 408.495754 -402.094954)
			(xy 408.510647 -402.113004) (xy 408.535714 -402.152519) (xy 408.554964 -402.195172) (xy 408.568013 -402.240111)
			(xy 408.5746 -402.28644) (xy 408.575002 -402.309838) (xy 408.574492 -402.335825) (xy 408.566362 -402.38716)
			(xy 408.550301 -402.43659) (xy 408.526705 -402.4829) (xy 408.496155 -402.524948) (xy 408.459404 -402.561699)
			(xy 408.417356 -402.592249) (xy 408.371046 -402.615845) (xy 408.321616 -402.631906) (xy 408.270281 -402.640036)
			(xy 408.218307 -402.640036) (xy 408.166972 -402.631906) (xy 408.117542 -402.615845) (xy 408.071232 -402.592249)
			(xy 408.029184 -402.561699) (xy 407.992433 -402.524948) (xy 407.961883 -402.4829) (xy 407.938287 -402.43659)
			(xy 407.922226 -402.38716) (xy 407.914096 -402.335825) (xy 407.913586 -402.309838) (xy 407.914026 -402.286442)
			(xy 407.920611 -402.240117) (xy 407.933654 -402.19518) (xy 407.952897 -402.152529) (xy 407.977955 -402.113013)
			(xy 407.992834 -402.094954) (xy 407.999438 -402.087334) (xy 408.005534 -402.069046) (xy 408.0002 -401.978876)
			(xy 407.992072 -401.96135) (xy 407.984706 -401.954492) (xy 407.965811 -401.936375) (xy 407.932647 -401.895872)
			(xy 407.90533 -401.851217) (xy 407.884372 -401.803247) (xy 407.870166 -401.752864) (xy 407.86298 -401.701012)
			(xy 407.862532 -401.674838) (xy 407.425652 -401.674838) (xy 407.425114 -401.703742) (xy 407.416409 -401.760892)
			(xy 407.399189 -401.816076) (xy 407.373847 -401.868034) (xy 407.340963 -401.915579) (xy 407.321512 -401.936966)
			(xy 407.315416 -401.94357) (xy 407.308304 -401.959572) (xy 407.302716 -402.041868) (xy 407.307542 -402.058886)
			(xy 407.312622 -402.065998) (xy 407.327255 -402.08723) (xy 407.35051 -402.13325) (xy 407.366337 -402.182322)
			(xy 407.374353 -402.233257) (xy 407.374852 -402.259038) (xy 407.374342 -402.285025) (xy 407.366212 -402.33636)
			(xy 407.350151 -402.38579) (xy 407.326555 -402.4321) (xy 407.296005 -402.474148) (xy 407.259254 -402.510899)
			(xy 407.217206 -402.541449) (xy 407.170896 -402.565045) (xy 407.121466 -402.581106) (xy 407.070131 -402.589236)
			(xy 407.018157 -402.589236) (xy 406.966822 -402.581106) (xy 406.917392 -402.565045) (xy 406.871082 -402.541449)
			(xy 406.829034 -402.510899) (xy 406.792283 -402.474148) (xy 406.761733 -402.4321) (xy 406.738137 -402.38579)
			(xy 406.722076 -402.33636) (xy 406.713946 -402.285025) (xy 406.713436 -402.259038) (xy 406.71392 -402.233255)
			(xy 406.721926 -402.182315) (xy 406.737749 -402.133237) (xy 406.761006 -402.087213) (xy 406.775666 -402.065998)
			(xy 406.780746 -402.058886) (xy 406.785572 -402.041868) (xy 406.779984 -401.959572) (xy 406.772872 -401.94357)
			(xy 406.766776 -401.936966) (xy 406.747289 -401.915607) (xy 406.714382 -401.868068) (xy 406.689033 -401.816105)
			(xy 406.671821 -401.760909) (xy 406.663144 -401.703747) (xy 406.662636 -401.674838) (xy 406.225756 -401.674838)
			(xy 406.225297 -401.701001) (xy 406.218147 -401.752837) (xy 406.203985 -401.803211) (xy 406.183077 -401.851179)
			(xy 406.155814 -401.895843) (xy 406.122708 -401.936366) (xy 406.103836 -401.954492) (xy 406.09647 -401.96135)
			(xy 406.088342 -401.978876) (xy 406.083008 -402.069046) (xy 406.089104 -402.087334) (xy 406.095708 -402.094954)
			(xy 406.110609 -402.112997) (xy 406.135673 -402.152515) (xy 406.154921 -402.19517) (xy 406.167968 -402.24011)
			(xy 406.174554 -402.28644) (xy 406.174956 -402.309838) (xy 406.174446 -402.335825) (xy 406.166316 -402.38716)
			(xy 406.150255 -402.43659) (xy 406.126659 -402.4829) (xy 406.096109 -402.524948) (xy 406.059358 -402.561699)
			(xy 406.01731 -402.592249) (xy 405.971 -402.615845) (xy 405.92157 -402.631906) (xy 405.870235 -402.640036)
			(xy 405.818261 -402.640036) (xy 405.766926 -402.631906) (xy 405.717496 -402.615845) (xy 405.671186 -402.592249)
			(xy 405.629138 -402.561699) (xy 405.592387 -402.524948) (xy 405.561837 -402.4829) (xy 405.538241 -402.43659)
			(xy 405.52218 -402.38716) (xy 405.51405 -402.335825) (xy 405.51354 -402.309838) (xy 405.513967 -402.286442)
			(xy 405.520553 -402.240115) (xy 405.533599 -402.195178) (xy 405.552845 -402.152527) (xy 405.577907 -402.113012)
			(xy 405.592788 -402.094954) (xy 405.599392 -402.087334) (xy 405.605488 -402.069046) (xy 405.600154 -401.978876)
			(xy 405.592026 -401.96135) (xy 405.58466 -401.954492) (xy 405.565758 -401.936394) (xy 405.532643 -401.895871)
			(xy 405.505376 -401.851203) (xy 405.484467 -401.803229) (xy 405.470308 -401.752848) (xy 405.463167 -401.701004)
			(xy 405.46274 -401.674838) (xy 405.02586 -401.674838) (xy 405.025245 -401.704996) (xy 405.015752 -401.764559)
			(xy 404.997007 -401.821888) (xy 404.969477 -401.875554) (xy 404.933848 -401.924222) (xy 404.91283 -401.945856)
			(xy 404.906226 -401.95246) (xy 404.898606 -401.969224) (xy 404.893272 -402.05533) (xy 404.898606 -402.07311)
			(xy 404.904448 -402.080476) (xy 404.920953 -402.102466) (xy 404.947228 -402.150758) (xy 404.965161 -402.202729)
			(xy 404.974257 -402.256949) (xy 404.974806 -402.284438) (xy 404.974296 -402.310425) (xy 404.966166 -402.36176)
			(xy 404.950105 -402.41119) (xy 404.926509 -402.4575) (xy 404.895959 -402.499548) (xy 404.859208 -402.536299)
			(xy 404.81716 -402.566849) (xy 404.77085 -402.590445) (xy 404.72142 -402.606506) (xy 404.670085 -402.614636)
			(xy 404.618111 -402.614636) (xy 404.566776 -402.606506) (xy 404.517346 -402.590445) (xy 404.471036 -402.566849)
			(xy 404.428988 -402.536299) (xy 404.392237 -402.499548) (xy 404.361687 -402.4575) (xy 404.338091 -402.41119)
			(xy 404.32203 -402.36176) (xy 404.3139 -402.310425) (xy 404.31339 -402.284438) (xy 404.313945 -402.256948)
			(xy 404.323021 -402.202722) (xy 404.340945 -402.150745) (xy 404.367224 -402.102452) (xy 404.383748 -402.080476)
			(xy 404.38959 -402.07311) (xy 404.394924 -402.05533) (xy 404.38959 -401.969224) (xy 404.38197 -401.95246)
			(xy 404.375366 -401.945856) (xy 404.354321 -401.924243) (xy 404.318676 -401.875578) (xy 404.291137 -401.821908)
			(xy 404.27239 -401.764572) (xy 404.262903 -401.705) (xy 404.262336 -401.674838) (xy 403.825964 -401.674838)
			(xy 403.825349 -401.704996) (xy 403.815855 -401.764559) (xy 403.79711 -401.821888) (xy 403.769581 -401.875554)
			(xy 403.733953 -401.924222) (xy 403.712934 -401.945856) (xy 403.70633 -401.95246) (xy 403.69871 -401.969224)
			(xy 403.693376 -402.05533) (xy 403.69871 -402.07311) (xy 403.704552 -402.080476) (xy 403.721058 -402.102465)
			(xy 403.747333 -402.150758) (xy 403.765265 -402.202729) (xy 403.774361 -402.256949) (xy 403.77491 -402.284438)
			(xy 403.7744 -402.310425) (xy 403.76627 -402.36176) (xy 403.750209 -402.41119) (xy 403.726613 -402.4575)
			(xy 403.696063 -402.499548) (xy 403.659312 -402.536299) (xy 403.617264 -402.566849) (xy 403.570954 -402.590445)
			(xy 403.521524 -402.606506) (xy 403.470189 -402.614636) (xy 403.418215 -402.614636) (xy 403.36688 -402.606506)
			(xy 403.31745 -402.590445) (xy 403.27114 -402.566849) (xy 403.229092 -402.536299) (xy 403.192341 -402.499548)
			(xy 403.161791 -402.4575) (xy 403.138195 -402.41119) (xy 403.122134 -402.36176) (xy 403.114004 -402.310425)
			(xy 403.113494 -402.284438) (xy 403.114048 -402.256948) (xy 403.123124 -402.202722) (xy 403.141048 -402.150745)
			(xy 403.167327 -402.102452) (xy 403.183852 -402.080476) (xy 403.189694 -402.07311) (xy 403.195028 -402.05533)
			(xy 403.189694 -401.969224) (xy 403.182074 -401.95246) (xy 403.17547 -401.945856) (xy 403.154426 -401.924242)
			(xy 403.11878 -401.875577) (xy 403.091241 -401.821908) (xy 403.072494 -401.764572) (xy 403.063007 -401.705)
			(xy 403.06244 -401.674838) (xy 399.330851 -401.674838) (xy 399.359489 -401.719132) (xy 399.382326 -401.76888)
			(xy 399.397811 -401.821382) (xy 399.405624 -401.875561) (xy 399.40611 -401.90293) (xy 399.405622 -401.93018)
			(xy 399.397862 -401.984124) (xy 399.382505 -402.036416) (xy 399.359862 -402.085989) (xy 399.330395 -402.131836)
			(xy 399.294703 -402.173023) (xy 399.253514 -402.208711) (xy 399.207665 -402.238175) (xy 399.158089 -402.260814)
			(xy 399.105797 -402.276168) (xy 399.051852 -402.283924) (xy 399.024602 -402.284438) (xy 398.997232 -402.283966)
			(xy 398.943055 -402.276142) (xy 398.890552 -402.260653) (xy 398.840803 -402.237818) (xy 398.794829 -402.208106)
			(xy 398.773904 -402.190458) (xy 398.766792 -402.184362) (xy 398.749774 -402.178012) (xy 398.66443 -402.178012)
			(xy 398.647412 -402.184362) (xy 398.6403 -402.190458) (xy 398.619367 -402.208099) (xy 398.573399 -402.237823)
			(xy 398.523653 -402.260669) (xy 398.471151 -402.276165) (xy 398.416973 -402.283994) (xy 398.362231 -402.283994)
			(xy 398.308053 -402.276165) (xy 398.255551 -402.260669) (xy 398.205805 -402.237823) (xy 398.159837 -402.208099)
			(xy 398.138904 -402.190458) (xy 398.131792 -402.184362) (xy 398.114774 -402.178012) (xy 398.02943 -402.178012)
			(xy 398.012412 -402.184362) (xy 398.0053 -402.190458) (xy 397.984367 -402.208099) (xy 397.938399 -402.237823)
			(xy 397.888653 -402.260669) (xy 397.836151 -402.276165) (xy 397.781973 -402.283994) (xy 397.727231 -402.283994)
			(xy 397.673053 -402.276165) (xy 397.620551 -402.260669) (xy 397.570805 -402.237823) (xy 397.524837 -402.208099)
			(xy 397.503904 -402.190458) (xy 397.496792 -402.184362) (xy 397.479774 -402.178012) (xy 397.39443 -402.178012)
			(xy 397.377412 -402.184362) (xy 397.3703 -402.190458) (xy 397.349369 -402.208102) (xy 397.303404 -402.237831)
			(xy 397.253657 -402.260677) (xy 397.201153 -402.276169) (xy 397.146973 -402.283988) (xy 397.119602 -402.284438)
			(xy 397.09235 -402.283952) (xy 397.0384 -402.276196) (xy 396.986104 -402.260842) (xy 396.936524 -402.238201)
			(xy 396.890671 -402.208735) (xy 396.849479 -402.173044) (xy 396.813784 -402.131854) (xy 396.784314 -402.086004)
			(xy 396.76167 -402.036426) (xy 396.746311 -401.984131) (xy 396.73855 -401.930182) (xy 396.738094 -401.90293)
			(xy 396.738571 -401.875562) (xy 396.746403 -401.821388) (xy 396.761898 -401.76889) (xy 396.784736 -401.719146)
			(xy 396.814449 -401.673176) (xy 396.832074 -401.652232) (xy 396.83817 -401.64512) (xy 396.84452 -401.628102)
			(xy 396.84452 -401.542758) (xy 396.83817 -401.52574) (xy 396.832074 -401.518628) (xy 396.814429 -401.497696)
			(xy 396.784697 -401.451729) (xy 396.761844 -401.401981) (xy 396.746342 -401.349477) (xy 396.738509 -401.295295)
			(xy 396.738506 -401.24055) (xy 396.746332 -401.186367) (xy 396.761828 -401.133861) (xy 396.784675 -401.084111)
			(xy 396.814402 -401.03814) (xy 396.832074 -401.017232) (xy 396.83817 -401.01012) (xy 396.84452 -400.993102)
			(xy 396.84452 -400.907758) (xy 396.83817 -400.89074) (xy 396.832074 -400.883628) (xy 396.814429 -400.862696)
			(xy 396.784697 -400.816729) (xy 396.761844 -400.766981) (xy 396.746342 -400.714477) (xy 396.738509 -400.660295)
			(xy 396.738506 -400.60555) (xy 396.746332 -400.551367) (xy 396.761828 -400.498861) (xy 396.784675 -400.449111)
			(xy 396.814402 -400.40314) (xy 396.832074 -400.382232) (xy 396.83817 -400.37512) (xy 396.84452 -400.358102)
			(xy 396.84452 -400.272758) (xy 396.83817 -400.25574) (xy 396.832074 -400.248628) (xy 396.814432 -400.227697)
			(xy 396.784704 -400.18173) (xy 396.761859 -400.131984) (xy 396.746366 -400.079481) (xy 396.738544 -400.025301)
			(xy 396.738094 -399.99793) (xy 396.738582 -399.969973) (xy 396.746744 -399.914657) (xy 396.762896 -399.861126)
			(xy 396.786693 -399.810529) (xy 396.817624 -399.763948) (xy 396.855026 -399.722385) (xy 396.898097 -399.686729)
			(xy 396.921736 -399.671794) (xy 396.930372 -399.66646) (xy 396.942056 -399.650712) (xy 396.964916 -399.562828)
			(xy 396.962122 -399.543016) (xy 396.957296 -399.53438) (xy 396.9422 -399.506677) (xy 396.920304 -399.447514)
			(xy 396.908424 -399.385557) (xy 396.907004 -399.35404) (xy 396.90675 -399.338546) (xy 396.889478 -399.313654)
			(xy 396.78864 -399.273268) (xy 396.779264 -399.269978) (xy 396.759416 -399.270081) (xy 396.741101 -399.277733)
			(xy 396.733776 -399.284444) (xy 396.394432 -399.623788) (xy 396.3924 -399.66265) (xy 396.404846 -399.67789)
			(xy 396.426176 -399.705174) (xy 396.46204 -399.764421) (xy 396.489536 -399.827983) (xy 396.508158 -399.894688)
			(xy 396.51756 -399.963302) (xy 396.51813 -399.99793) (xy 396.517649 -400.028624) (xy 396.510225 -400.089563)
			(xy 396.495524 -400.149166) (xy 396.47376 -400.206568) (xy 396.445248 -400.260935) (xy 396.428214 -400.286474)
			(xy 396.422747 -400.295225) (xy 396.418628 -400.315425) (xy 396.422766 -400.335621) (xy 396.428214 -400.344386)
			(xy 396.445268 -400.369913) (xy 396.473797 -400.424276) (xy 396.495567 -400.48168) (xy 396.510262 -400.541288)
			(xy 396.517668 -400.602233) (xy 396.51813 -400.63293) (xy 396.517664 -400.66366) (xy 396.510253 -400.724672)
			(xy 396.495542 -400.784347) (xy 396.473745 -400.841812) (xy 396.445182 -400.896232) (xy 396.410267 -400.946813)
			(xy 396.369511 -400.992816) (xy 396.323507 -401.033572) (xy 396.272926 -401.068486) (xy 396.218505 -401.097049)
			(xy 396.161039 -401.118844) (xy 396.101365 -401.133554) (xy 396.040352 -401.140965) (xy 396.009622 -401.141438)
			(xy 395.98854 -401.14093) (xy 395.977618 -401.140422) (xy 395.95806 -401.148042) (xy 395.889734 -401.216368)
			(xy 395.882114 -401.235926) (xy 395.882622 -401.246848) (xy 395.88313 -401.26793) (xy 395.882649 -401.298624)
			(xy 395.875225 -401.359563) (xy 395.860524 -401.419166) (xy 395.83876 -401.476568) (xy 395.810248 -401.530935)
			(xy 395.793214 -401.556474) (xy 395.787747 -401.565225) (xy 395.783628 -401.585425) (xy 395.787766 -401.605621)
			(xy 395.793214 -401.614386) (xy 395.810268 -401.639913) (xy 395.838797 -401.694276) (xy 395.860567 -401.75168)
			(xy 395.875262 -401.811288) (xy 395.882668 -401.872233) (xy 395.88313 -401.90293) (xy 395.882664 -401.93366)
			(xy 395.875253 -401.994672) (xy 395.860542 -402.054347) (xy 395.838745 -402.111812) (xy 395.810182 -402.166232)
			(xy 395.775267 -402.216813) (xy 395.734511 -402.262816) (xy 395.688507 -402.303572) (xy 395.637926 -402.338486)
			(xy 395.583505 -402.367049) (xy 395.526039 -402.388844) (xy 395.466365 -402.403554) (xy 395.405352 -402.410965)
			(xy 395.374622 -402.411438) (xy 395.343927 -402.410961) (xy 395.282985 -402.403542) (xy 395.223379 -402.388846)
			(xy 395.165973 -402.367087) (xy 395.111602 -402.33858) (xy 395.086078 -402.321522) (xy 395.077326 -402.316051)
			(xy 395.057122 -402.311923) (xy 395.036918 -402.316051) (xy 395.028166 -402.321522) (xy 395.002638 -402.338574)
			(xy 394.948274 -402.367097) (xy 394.89087 -402.388861) (xy 394.831262 -402.40355) (xy 394.770318 -402.41095)
			(xy 394.739622 -402.411438) (xy 394.719792 -402.411267) (xy 394.680249 -402.408216) (xy 394.660628 -402.405342)
			(xy 394.649452 -402.403564) (xy 394.62837 -402.40966) (xy 394.56106 -402.467064) (xy 394.553035 -402.474636)
			(xy 394.543809 -402.494652) (xy 394.54328 -402.505672) (xy 394.54328 -402.734018) (xy 401.832824 -402.734018)
			(xy 401.836895 -402.678396) (xy 401.849021 -402.623959) (xy 401.868944 -402.571868) (xy 401.89624 -402.523233)
			(xy 401.930326 -402.47909) (xy 401.970475 -402.440381) (xy 402.015833 -402.40793) (xy 402.065433 -402.382429)
			(xy 402.118217 -402.364422) (xy 402.17306 -402.354292) (xy 402.228794 -402.352255) (xy 402.284231 -402.358355)
			(xy 402.338188 -402.372461) (xy 402.389517 -402.394273) (xy 402.437123 -402.423327) (xy 402.479991 -402.459002)
			(xy 402.517208 -402.500539) (xy 402.547981 -402.547052) (xy 402.571653 -402.597549) (xy 402.587721 -402.650956)
			(xy 402.595841 -402.706132) (xy 402.59635 -402.734018) (xy 402.595841 -402.761904) (xy 402.587721 -402.81708)
			(xy 402.571653 -402.870487) (xy 402.547981 -402.920984) (xy 402.517208 -402.967497) (xy 402.479991 -403.009034)
			(xy 402.437123 -403.044709) (xy 402.389517 -403.073763) (xy 402.338188 -403.095575) (xy 402.284231 -403.109681)
			(xy 402.228794 -403.115781) (xy 402.17306 -403.113744) (xy 402.118217 -403.103614) (xy 402.065433 -403.085607)
			(xy 402.015833 -403.060106) (xy 401.970475 -403.027655) (xy 401.930326 -402.988946) (xy 401.89624 -402.944803)
			(xy 401.868944 -402.896168) (xy 401.849021 -402.844077) (xy 401.836895 -402.78964) (xy 401.832824 -402.734018)
			(xy 394.54328 -402.734018) (xy 394.54328 -406.526238) (xy 394.543709 -406.536306) (xy 394.551431 -406.554902)
			(xy 394.558266 -406.562306) (xy 395.376654 -407.380694) (xy 395.384055 -407.387533) (xy 395.402653 -407.395248)
			(xy 395.412722 -407.39568)
		)
		(stroke
			(width 0)
			(type solid)
		)
		(fill yes)
		(layer "In11.Cu")
		(net "P0V9_CPU0_RT2_2A_2D")
	)
	(gr_poly
		(pts
			(xy 113.229136 -275.237956) (xy 113.235232 -275.2344) (xy 113.241346 -275.230916) (xy 113.25487 -275.227044)
			(xy 113.261902 -275.22678) (xy 113.90757 -275.22678) (xy 113.917634 -275.226344) (xy 113.936218 -275.218609)
			(xy 113.943638 -275.211794) (xy 114.028728 -275.126704) (xy 114.036128 -275.119862) (xy 114.054726 -275.112137)
			(xy 114.064796 -275.111718) (xy 115.13312 -275.111718) (xy 115.143189 -275.111292) (xy 115.16179 -275.103574)
			(xy 115.169188 -275.096732) (xy 115.958874 -274.307046) (xy 115.965265 -274.301112) (xy 115.98098 -274.293583)
			(xy 115.989608 -274.292314) (xy 116.009166 -274.290282) (xy 116.035074 -274.261326) (xy 116.035074 -274.235672)
			(xy 116.032534 -274.224496) (xy 116.029994 -274.219416) (xy 116.020357 -274.198568) (xy 116.006768 -274.154698)
			(xy 115.999925 -274.109284) (xy 115.999514 -274.08632) (xy 115.999959 -274.062326) (xy 116.007463 -274.01493)
			(xy 116.02229 -273.969291) (xy 116.044075 -273.926534) (xy 116.07228 -273.887711) (xy 116.106213 -273.853779)
			(xy 116.145035 -273.825574) (xy 116.187793 -273.803789) (xy 116.233432 -273.788963) (xy 116.280828 -273.781459)
			(xy 116.304822 -273.781012) (xy 116.328659 -273.781472) (xy 116.375754 -273.788887) (xy 116.421124 -273.803532)
			(xy 116.463666 -273.825051) (xy 116.502345 -273.852922) (xy 116.536222 -273.886467) (xy 116.564472 -273.92487)
			(xy 116.586409 -273.967198) (xy 116.6015 -274.012421) (xy 116.609378 -274.059441) (xy 116.61013 -274.083272)
			(xy 116.61013 -274.08632) (xy 116.60982 -274.106042) (xy 116.604719 -274.145154) (xy 116.59997 -274.164298)
			(xy 116.59997 -274.164552) (xy 116.597552 -274.175994) (xy 116.602186 -274.198891) (xy 116.60886 -274.208494)
			(xy 116.657882 -274.272248) (xy 116.665465 -274.281113) (xy 116.686365 -274.291425) (xy 116.698014 -274.29206)
			(xy 116.85143 -274.29206) (xy 116.863093 -274.291482) (xy 116.884002 -274.281149) (xy 116.891562 -274.272248)
			(xy 116.940584 -274.208494) (xy 116.947256 -274.19889) (xy 116.951886 -274.175995) (xy 116.949474 -274.164552)
			(xy 116.949474 -274.164298) (xy 116.944729 -274.145218) (xy 116.939629 -274.106233) (xy 116.939314 -274.086574)
			(xy 116.939314 -274.083272) (xy 116.940073 -274.058182) (xy 116.948776 -274.008749) (xy 116.965447 -273.961406)
			(xy 116.989638 -273.917427) (xy 117.020695 -273.877997) (xy 117.057784 -273.844177) (xy 117.099904 -273.816879)
			(xy 117.145922 -273.796837) (xy 117.194598 -273.784592) (xy 117.244622 -273.780474) (xy 117.294646 -273.784592)
			(xy 117.343322 -273.796837) (xy 117.38934 -273.816879) (xy 117.43146 -273.844177) (xy 117.468549 -273.877997)
			(xy 117.499606 -273.917427) (xy 117.523797 -273.961406) (xy 117.540468 -274.008749) (xy 117.549171 -274.058182)
			(xy 117.54993 -274.083272) (xy 117.54993 -274.08632) (xy 117.54962 -274.106042) (xy 117.544519 -274.145154)
			(xy 117.53977 -274.164298) (xy 117.53977 -274.164552) (xy 117.537352 -274.175994) (xy 117.541986 -274.198891)
			(xy 117.54866 -274.208494) (xy 117.597682 -274.272248) (xy 117.605265 -274.281113) (xy 117.626165 -274.291425)
			(xy 117.637814 -274.29206) (xy 117.791484 -274.29206) (xy 117.803152 -274.291491) (xy 117.824077 -274.28117)
			(xy 117.831616 -274.272248) (xy 117.880638 -274.208494) (xy 117.887315 -274.198892) (xy 117.891949 -274.175994)
			(xy 117.889528 -274.164552) (xy 117.889528 -274.164298) (xy 117.884784 -274.145218) (xy 117.879685 -274.106233)
			(xy 117.879368 -274.086574) (xy 117.879368 -274.083272) (xy 117.880127 -274.058182) (xy 117.88883 -274.008749)
			(xy 117.905501 -273.961406) (xy 117.929692 -273.917427) (xy 117.960749 -273.877997) (xy 117.997838 -273.844177)
			(xy 118.039958 -273.816879) (xy 118.085976 -273.796837) (xy 118.134652 -273.784592) (xy 118.184676 -273.780474)
			(xy 118.2347 -273.784592) (xy 118.283376 -273.796837) (xy 118.329394 -273.816879) (xy 118.371514 -273.844177)
			(xy 118.408603 -273.877997) (xy 118.43966 -273.917427) (xy 118.463851 -273.961406) (xy 118.480522 -274.008749)
			(xy 118.489225 -274.058182) (xy 118.489984 -274.083272) (xy 118.489984 -274.08632) (xy 118.489674 -274.106042)
			(xy 118.484572 -274.145154) (xy 118.479824 -274.164298) (xy 118.479824 -274.164552) (xy 118.477405 -274.175994)
			(xy 118.482043 -274.198888) (xy 118.488714 -274.208494) (xy 118.537736 -274.272248) (xy 118.545316 -274.281121)
			(xy 118.566215 -274.291451) (xy 118.577868 -274.29206) (xy 118.731538 -274.29206) (xy 118.7432 -274.29148)
			(xy 118.764107 -274.281145) (xy 118.77167 -274.272248) (xy 118.820692 -274.208494) (xy 118.827374 -274.198893)
			(xy 118.832012 -274.175993) (xy 118.829582 -274.164552) (xy 118.829582 -274.164298) (xy 118.824837 -274.145218)
			(xy 118.819737 -274.106233) (xy 118.819422 -274.086574) (xy 118.819422 -274.083272) (xy 118.820181 -274.058182)
			(xy 118.828884 -274.008749) (xy 118.845555 -273.961406) (xy 118.869746 -273.917427) (xy 118.900803 -273.877997)
			(xy 118.937892 -273.844177) (xy 118.980012 -273.816879) (xy 119.02603 -273.796837) (xy 119.074706 -273.784592)
			(xy 119.12473 -273.780474) (xy 119.174754 -273.784592) (xy 119.22343 -273.796837) (xy 119.269448 -273.816879)
			(xy 119.311568 -273.844177) (xy 119.348657 -273.877997) (xy 119.379714 -273.917427) (xy 119.403905 -273.961406)
			(xy 119.420576 -274.008749) (xy 119.429279 -274.058182) (xy 119.430038 -274.083272) (xy 119.430038 -274.08632)
			(xy 119.429728 -274.106042) (xy 119.424625 -274.145154) (xy 119.419878 -274.164298) (xy 119.419878 -274.164552)
			(xy 119.41746 -274.175994) (xy 119.422094 -274.19889) (xy 119.428768 -274.208494) (xy 119.47779 -274.272248)
			(xy 119.485374 -274.281112) (xy 119.506273 -274.29142) (xy 119.517922 -274.29206) (xy 119.671592 -274.29206)
			(xy 119.683259 -274.29149) (xy 119.704181 -274.281166) (xy 119.711724 -274.272248) (xy 119.760746 -274.208494)
			(xy 119.767422 -274.198891) (xy 119.772055 -274.175994) (xy 119.769636 -274.164552) (xy 119.769636 -274.164298)
			(xy 119.764891 -274.145218) (xy 119.759792 -274.106233) (xy 119.759476 -274.086574) (xy 119.759476 -274.083272)
			(xy 119.760235 -274.058182) (xy 119.768938 -274.008749) (xy 119.785609 -273.961406) (xy 119.8098 -273.917427)
			(xy 119.840857 -273.877997) (xy 119.877946 -273.844177) (xy 119.920066 -273.816879) (xy 119.966084 -273.796837)
			(xy 120.01476 -273.784592) (xy 120.064784 -273.780474) (xy 120.114808 -273.784592) (xy 120.163484 -273.796837)
			(xy 120.209502 -273.816879) (xy 120.251622 -273.844177) (xy 120.288711 -273.877997) (xy 120.319768 -273.917427)
			(xy 120.343959 -273.961406) (xy 120.36063 -274.008749) (xy 120.369333 -274.058182) (xy 120.370092 -274.083272)
			(xy 120.370092 -274.08632) (xy 120.369782 -274.106042) (xy 120.36468 -274.145154) (xy 120.359932 -274.164298)
			(xy 120.359932 -274.164552) (xy 120.357513 -274.175994) (xy 120.362151 -274.198888) (xy 120.368822 -274.208494)
			(xy 120.417844 -274.272248) (xy 120.425425 -274.281119) (xy 120.446324 -274.291447) (xy 120.457976 -274.29206)
			(xy 120.611646 -274.29206) (xy 120.623318 -274.291499) (xy 120.644256 -274.281187) (xy 120.651778 -274.272248)
			(xy 120.7008 -274.208494) (xy 120.707481 -274.198893) (xy 120.712118 -274.175993) (xy 120.70969 -274.164552)
			(xy 120.70969 -274.164298) (xy 120.704945 -274.145218) (xy 120.699845 -274.106233) (xy 120.69953 -274.086574)
			(xy 120.69953 -274.083272) (xy 120.700289 -274.058182) (xy 120.708992 -274.008749) (xy 120.725663 -273.961406)
			(xy 120.749854 -273.917427) (xy 120.780911 -273.877997) (xy 120.818 -273.844177) (xy 120.86012 -273.816879)
			(xy 120.906138 -273.796837) (xy 120.954814 -273.784592) (xy 121.004838 -273.780474) (xy 121.054862 -273.784592)
			(xy 121.103538 -273.796837) (xy 121.149556 -273.816879) (xy 121.191676 -273.844177) (xy 121.228765 -273.877997)
			(xy 121.259822 -273.917427) (xy 121.284013 -273.961406) (xy 121.300684 -274.008749) (xy 121.309387 -274.058182)
			(xy 121.310146 -274.083272) (xy 121.310146 -274.08632) (xy 121.309836 -274.106042) (xy 121.304734 -274.145154)
			(xy 121.299986 -274.164298) (xy 121.299986 -274.164552) (xy 121.297568 -274.175994) (xy 121.302203 -274.19889)
			(xy 121.308876 -274.208494) (xy 121.357898 -274.272248) (xy 121.365482 -274.28111) (xy 121.386382 -274.291415)
			(xy 121.39803 -274.29206) (xy 121.551446 -274.29206) (xy 121.563118 -274.291499) (xy 121.584056 -274.281187)
			(xy 121.591578 -274.272248) (xy 121.6406 -274.208494) (xy 121.647281 -274.198893) (xy 121.651918 -274.175993)
			(xy 121.64949 -274.164552) (xy 121.64949 -274.164298) (xy 121.644745 -274.145218) (xy 121.639645 -274.106233)
			(xy 121.63933 -274.086574) (xy 121.63933 -274.083272) (xy 121.640089 -274.058182) (xy 121.648792 -274.008749)
			(xy 121.665463 -273.961406) (xy 121.689654 -273.917427) (xy 121.720711 -273.877997) (xy 121.7578 -273.844177)
			(xy 121.79992 -273.816879) (xy 121.845938 -273.796837) (xy 121.894614 -273.784592) (xy 121.944638 -273.780474)
			(xy 121.994662 -273.784592) (xy 122.043338 -273.796837) (xy 122.089356 -273.816879) (xy 122.131476 -273.844177)
			(xy 122.168565 -273.877997) (xy 122.199622 -273.917427) (xy 122.223813 -273.961406) (xy 122.240484 -274.008749)
			(xy 122.249187 -274.058182) (xy 122.249946 -274.083272) (xy 122.249946 -274.08632) (xy 122.249636 -274.106042)
			(xy 122.244534 -274.145154) (xy 122.239786 -274.164298) (xy 122.239786 -274.164552) (xy 122.237368 -274.175994)
			(xy 122.242003 -274.19889) (xy 122.248676 -274.208494) (xy 122.297698 -274.272248) (xy 122.305282 -274.28111)
			(xy 122.326182 -274.291415) (xy 122.33783 -274.29206) (xy 122.4915 -274.29206) (xy 122.503166 -274.291488)
			(xy 122.524086 -274.281162) (xy 122.531632 -274.272248) (xy 122.580654 -274.208494) (xy 122.587329 -274.198891)
			(xy 122.591961 -274.175994) (xy 122.589544 -274.164552) (xy 122.589544 -274.164298) (xy 122.584799 -274.145218)
			(xy 122.5797 -274.106233) (xy 122.579384 -274.086574) (xy 122.579384 -274.083272) (xy 122.580143 -274.058182)
			(xy 122.588846 -274.008749) (xy 122.605517 -273.961406) (xy 122.629708 -273.917427) (xy 122.660765 -273.877997)
			(xy 122.697854 -273.844177) (xy 122.739974 -273.816879) (xy 122.785992 -273.796837) (xy 122.834668 -273.784592)
			(xy 122.884692 -273.780474) (xy 122.934716 -273.784592) (xy 122.983392 -273.796837) (xy 123.02941 -273.816879)
			(xy 123.07153 -273.844177) (xy 123.108619 -273.877997) (xy 123.139676 -273.917427) (xy 123.163867 -273.961406)
			(xy 123.180538 -274.008749) (xy 123.189241 -274.058182) (xy 123.19 -274.083272) (xy 123.19 -274.08632)
			(xy 123.18969 -274.106042) (xy 123.184589 -274.145154) (xy 123.17984 -274.164298) (xy 123.17984 -274.164552)
			(xy 123.177423 -274.175995) (xy 123.182054 -274.198892) (xy 123.18873 -274.208494) (xy 123.237752 -274.272248)
			(xy 123.245334 -274.281118) (xy 123.266233 -274.291442) (xy 123.277884 -274.29206) (xy 123.431554 -274.29206)
			(xy 123.443225 -274.291497) (xy 123.46416 -274.281183) (xy 123.471686 -274.272248) (xy 123.520708 -274.208494)
			(xy 123.527388 -274.198893) (xy 123.532025 -274.175994) (xy 123.529598 -274.164552) (xy 123.529598 -274.164298)
			(xy 123.524853 -274.145218) (xy 123.519752 -274.106233) (xy 123.519438 -274.086574) (xy 123.519438 -274.083272)
			(xy 123.520197 -274.058182) (xy 123.5289 -274.008749) (xy 123.545571 -273.961406) (xy 123.569762 -273.917427)
			(xy 123.600819 -273.877997) (xy 123.637908 -273.844177) (xy 123.680028 -273.816879) (xy 123.726046 -273.796837)
			(xy 123.774722 -273.784592) (xy 123.824746 -273.780474) (xy 123.87477 -273.784592) (xy 123.923446 -273.796837)
			(xy 123.969464 -273.816879) (xy 124.011584 -273.844177) (xy 124.048673 -273.877997) (xy 124.07973 -273.917427)
			(xy 124.103921 -273.961406) (xy 124.120592 -274.008749) (xy 124.129295 -274.058182) (xy 124.130054 -274.083272)
			(xy 124.130054 -274.08632) (xy 124.129744 -274.106042) (xy 124.124642 -274.145154) (xy 124.119894 -274.164298)
			(xy 124.119894 -274.164552) (xy 124.117476 -274.175994) (xy 124.122111 -274.19889) (xy 124.128784 -274.208494)
			(xy 124.177806 -274.272248) (xy 124.185391 -274.281109) (xy 124.206291 -274.291411) (xy 124.217938 -274.29206)
			(xy 124.371608 -274.29206) (xy 124.383273 -274.291486) (xy 124.40419 -274.281159) (xy 124.41174 -274.272248)
			(xy 124.460762 -274.208494) (xy 124.467436 -274.198891) (xy 124.472068 -274.175994) (xy 124.469652 -274.164552)
			(xy 124.469652 -274.164298) (xy 124.464907 -274.145218) (xy 124.459808 -274.106233) (xy 124.459492 -274.086574)
			(xy 124.459492 -274.083272) (xy 124.460251 -274.058182) (xy 124.468954 -274.008749) (xy 124.485625 -273.961406)
			(xy 124.509816 -273.917427) (xy 124.540873 -273.877997) (xy 124.577962 -273.844177) (xy 124.620082 -273.816879)
			(xy 124.6661 -273.796837) (xy 124.714776 -273.784592) (xy 124.7648 -273.780474) (xy 124.814824 -273.784592)
			(xy 124.8635 -273.796837) (xy 124.909518 -273.816879) (xy 124.951638 -273.844177) (xy 124.988727 -273.877997)
			(xy 125.019784 -273.917427) (xy 125.043975 -273.961406) (xy 125.060646 -274.008749) (xy 125.069349 -274.058182)
			(xy 125.070108 -274.083272) (xy 125.070108 -274.08632) (xy 125.069798 -274.106042) (xy 125.064697 -274.145154)
			(xy 125.059948 -274.164298) (xy 125.059948 -274.164552) (xy 125.057531 -274.175994) (xy 125.062163 -274.198891)
			(xy 125.068838 -274.208494) (xy 125.11786 -274.272248) (xy 125.125442 -274.281116) (xy 125.146341 -274.291437)
			(xy 125.157992 -274.29206) (xy 125.311662 -274.29206) (xy 125.323332 -274.291496) (xy 125.344265 -274.28118)
			(xy 125.351794 -274.272248) (xy 125.400816 -274.208494) (xy 125.407495 -274.198892) (xy 125.412131 -274.175994)
			(xy 125.409706 -274.164552) (xy 125.409706 -274.164298) (xy 125.40496 -274.145218) (xy 125.39986 -274.106233)
			(xy 125.399546 -274.086574) (xy 125.399546 -274.083272) (xy 125.400305 -274.058182) (xy 125.409008 -274.008749)
			(xy 125.425679 -273.961406) (xy 125.44987 -273.917427) (xy 125.480927 -273.877997) (xy 125.518016 -273.844177)
			(xy 125.560136 -273.816879) (xy 125.606154 -273.796837) (xy 125.65483 -273.784592) (xy 125.704854 -273.780474)
			(xy 125.754878 -273.784592) (xy 125.803554 -273.796837) (xy 125.849572 -273.816879) (xy 125.891692 -273.844177)
			(xy 125.928781 -273.877997) (xy 125.959838 -273.917427) (xy 125.984029 -273.961406) (xy 126.0007 -274.008749)
			(xy 126.009403 -274.058182) (xy 126.010162 -274.083272) (xy 126.010162 -274.08632) (xy 126.009852 -274.106042)
			(xy 126.00475 -274.145154) (xy 126.000002 -274.164298) (xy 126.000002 -274.164552) (xy 125.997584 -274.175994)
			(xy 126.00222 -274.198889) (xy 126.008892 -274.208494) (xy 126.057914 -274.272248) (xy 126.065493 -274.281124)
			(xy 126.086392 -274.291463) (xy 126.098046 -274.29206) (xy 126.251462 -274.29206) (xy 126.263132 -274.291496)
			(xy 126.284065 -274.28118) (xy 126.291594 -274.272248) (xy 126.340616 -274.208494) (xy 126.347295 -274.198892)
			(xy 126.351931 -274.175994) (xy 126.349506 -274.164552) (xy 126.349506 -274.164298) (xy 126.34476 -274.145218)
			(xy 126.33966 -274.106233) (xy 126.339346 -274.086574) (xy 126.339346 -274.083272) (xy 126.340041 -274.059438)
			(xy 126.347921 -274.012414) (xy 126.363016 -273.967187) (xy 126.384958 -273.924857) (xy 126.413215 -273.886453)
			(xy 126.4471 -273.852909) (xy 126.485787 -273.825042) (xy 126.528336 -273.803527) (xy 126.573713 -273.78889)
			(xy 126.620814 -273.781486) (xy 126.644654 -273.781012) (xy 126.669222 -273.781509) (xy 126.717723 -273.78939)
			(xy 126.764334 -273.804941) (xy 126.807851 -273.827758) (xy 126.84715 -273.857254) (xy 126.881216 -273.892665)
			(xy 126.895606 -273.912584) (xy 126.898146 -273.91614) (xy 126.901702 -273.919696) (xy 126.909068 -273.926536)
			(xy 126.927601 -273.934278) (xy 126.947685 -273.934278) (xy 126.966218 -273.926536) (xy 126.973584 -273.919696)
			(xy 126.997714 -273.895566) (xy 126.998222 -273.895058) (xy 127.004809 -273.887679) (xy 127.012269 -273.86938)
			(xy 127.0127 -273.859498) (xy 127.0127 -273.583146) (xy 126.997206 -273.558508) (xy 126.983744 -273.552158)
			(xy 126.96175 -273.541139) (xy 126.921299 -273.513148) (xy 126.885855 -273.479039) (xy 126.856335 -273.439691)
			(xy 126.8335 -273.396121) (xy 126.81794 -273.349456) (xy 126.810058 -273.300901) (xy 126.810057 -273.251711)
			(xy 126.817937 -273.203155) (xy 126.833495 -273.15649) (xy 126.856328 -273.11292) (xy 126.885847 -273.073571)
			(xy 126.92129 -273.039459) (xy 126.961739 -273.011467) (xy 126.983744 -273.00047) (xy 126.997206 -272.99412)
			(xy 127.0127 -272.969482) (xy 127.0127 -271.963134) (xy 126.997206 -271.938496) (xy 126.983744 -271.932146)
			(xy 126.961751 -271.921127) (xy 126.921302 -271.893137) (xy 126.88586 -271.859027) (xy 126.856341 -271.819681)
			(xy 126.833508 -271.776112) (xy 126.817949 -271.729449) (xy 126.810068 -271.680895) (xy 126.810068 -271.631706)
			(xy 126.817949 -271.583153) (xy 126.833507 -271.536489) (xy 126.85634 -271.492921) (xy 126.885859 -271.453574)
			(xy 126.9213 -271.419464) (xy 126.961749 -271.391474) (xy 126.983744 -271.380458) (xy 126.997206 -271.374108)
			(xy 127.0127 -271.34947) (xy 127.0127 -271.15389) (xy 127.012268 -271.144178) (xy 127.005043 -271.126149)
			(xy 126.991633 -271.112098) (xy 126.982982 -271.107662) (xy 126.885192 -271.062958) (xy 126.855982 -271.067022)
			(xy 126.844552 -271.076928) (xy 126.823565 -271.094347) (xy 126.776681 -271.122205) (xy 126.72559 -271.141282)
			(xy 126.671922 -271.150971) (xy 126.644654 -271.151604) (xy 126.619402 -271.151079) (xy 126.569586 -271.142759)
			(xy 126.52182 -271.126355) (xy 126.477404 -271.102312) (xy 126.437551 -271.071288) (xy 126.403348 -271.034128)
			(xy 126.375726 -270.991845) (xy 126.35544 -270.945593) (xy 126.343043 -270.896633) (xy 126.338873 -270.8463)
			(xy 126.343043 -270.795967) (xy 126.35544 -270.747007) (xy 126.375726 -270.700755) (xy 126.403348 -270.658472)
			(xy 126.437551 -270.621312) (xy 126.477404 -270.590288) (xy 126.52182 -270.566245) (xy 126.569586 -270.549841)
			(xy 126.619402 -270.541521) (xy 126.644654 -270.540988) (xy 126.671919 -270.541617) (xy 126.725576 -270.551345)
			(xy 126.776658 -270.570429) (xy 126.82355 -270.598266) (xy 126.844552 -270.615664) (xy 126.855982 -270.62557)
			(xy 126.885192 -270.629634) (xy 126.982982 -270.58493) (xy 126.991642 -270.580508) (xy 127.005055 -270.566452)
			(xy 127.012279 -270.548416) (xy 127.0127 -270.538702) (xy 127.0127 -270.343122) (xy 126.997206 -270.318484)
			(xy 126.983744 -270.312134) (xy 126.961752 -270.301115) (xy 126.921305 -270.273125) (xy 126.885865 -270.239016)
			(xy 126.856348 -270.19967) (xy 126.833515 -270.156103) (xy 126.817958 -270.109441) (xy 126.810079 -270.060889)
			(xy 126.810079 -270.011702) (xy 126.817961 -269.96315) (xy 126.833519 -269.916489) (xy 126.856352 -269.872922)
			(xy 126.885871 -269.833577) (xy 126.921311 -269.79947) (xy 126.961759 -269.771481) (xy 126.983744 -269.760446)
			(xy 126.997206 -269.754096) (xy 127.0127 -269.729458) (xy 127.0127 -268.72311) (xy 126.997206 -268.698472)
			(xy 126.983744 -268.692122) (xy 126.961748 -268.681102) (xy 126.921294 -268.65311) (xy 126.885844 -268.619002)
			(xy 126.856313 -268.579657) (xy 126.833464 -268.536092) (xy 126.817885 -268.48943) (xy 126.80998 -268.440875)
			(xy 126.8095 -268.416278) (xy 126.810073 -268.389728) (xy 126.819261 -268.337427) (xy 126.837354 -268.287504)
			(xy 126.86381 -268.241462) (xy 126.880366 -268.220698) (xy 126.886072 -268.213166) (xy 126.892095 -268.195273)
			(xy 126.891252 -268.176413) (xy 126.883656 -268.159129) (xy 126.877318 -268.152118) (xy 126.650496 -267.925296)
			(xy 126.643928 -267.91918) (xy 126.627656 -267.91164) (xy 126.618746 -267.910564) (xy 126.595092 -267.908091)
			(xy 126.548907 -267.896752) (xy 126.505038 -267.87839) (xy 126.464546 -267.85345) (xy 126.428409 -267.822534)
			(xy 126.397503 -267.786389) (xy 126.372573 -267.745891) (xy 126.354223 -267.702017) (xy 126.342896 -267.655829)
			(xy 126.340362 -267.63218) (xy 126.339199 -267.623295) (xy 126.331668 -267.607051) (xy 126.32563 -267.60043)
			(xy 126.128526 -267.403326) (xy 126.121414 -267.39596) (xy 126.102618 -267.38834) (xy 125.15469 -267.38834)
			(xy 125.142748 -267.388973) (xy 125.121402 -267.399689) (xy 125.113796 -267.408914) (xy 125.057916 -267.484098)
			(xy 125.053852 -267.507212) (xy 125.057408 -267.51915) (xy 125.063254 -267.540134) (xy 125.069634 -267.583224)
			(xy 125.070108 -267.605002) (xy 125.070108 -267.609574) (xy 125.069329 -267.63465) (xy 125.060594 -267.684051)
			(xy 125.0439 -267.731358) (xy 125.019698 -267.7753) (xy 124.988638 -267.814695) (xy 124.951555 -267.848483)
			(xy 124.909448 -267.875754) (xy 124.86345 -267.895774) (xy 124.814798 -267.908007) (xy 124.7648 -267.912121)
			(xy 124.714802 -267.908007) (xy 124.66615 -267.895774) (xy 124.620152 -267.875754) (xy 124.578045 -267.848483)
			(xy 124.540962 -267.814695) (xy 124.509902 -267.7753) (xy 124.4857 -267.731358) (xy 124.469006 -267.684051)
			(xy 124.460271 -267.63465) (xy 124.459492 -267.609574) (xy 124.459492 -267.606018) (xy 124.4599 -267.583984)
			(xy 124.46628 -267.54038) (xy 124.472192 -267.51915) (xy 124.475748 -267.507212) (xy 124.471684 -267.484098)
			(xy 124.415804 -267.408914) (xy 124.408195 -267.399685) (xy 124.386856 -267.388952) (xy 124.37491 -267.38834)
			(xy 123.274582 -267.38834) (xy 123.262641 -267.388975) (xy 123.241298 -267.399692) (xy 123.233688 -267.408914)
			(xy 123.177808 -267.484098) (xy 123.173744 -267.507212) (xy 123.1773 -267.51915) (xy 123.183147 -267.540134)
			(xy 123.189527 -267.583224) (xy 123.19 -267.605002) (xy 123.19 -267.609574) (xy 123.189221 -267.63465)
			(xy 123.180486 -267.684051) (xy 123.163792 -267.731358) (xy 123.13959 -267.7753) (xy 123.10853 -267.814695)
			(xy 123.071447 -267.848483) (xy 123.02934 -267.875754) (xy 122.983342 -267.895774) (xy 122.93469 -267.908007)
			(xy 122.884692 -267.912121) (xy 122.834694 -267.908007) (xy 122.786042 -267.895774) (xy 122.740044 -267.875754)
			(xy 122.697937 -267.848483) (xy 122.660854 -267.814695) (xy 122.629794 -267.7753) (xy 122.605592 -267.731358)
			(xy 122.588898 -267.684051) (xy 122.580163 -267.63465) (xy 122.579384 -267.609574) (xy 122.579384 -267.606018)
			(xy 122.579792 -267.583984) (xy 122.586172 -267.54038) (xy 122.592084 -267.51915) (xy 122.59564 -267.507212)
			(xy 122.591576 -267.484098) (xy 122.535696 -267.408914) (xy 122.528086 -267.399687) (xy 122.506747 -267.388956)
			(xy 122.494802 -267.38834) (xy 121.394728 -267.38834) (xy 121.382793 -267.388986) (xy 121.361469 -267.399717)
			(xy 121.353834 -267.408914) (xy 121.297954 -267.484098) (xy 121.29389 -267.507212) (xy 121.297446 -267.51915)
			(xy 121.303292 -267.540134) (xy 121.309671 -267.583224) (xy 121.310146 -267.605002) (xy 121.310146 -267.609574)
			(xy 121.309367 -267.63465) (xy 121.300632 -267.684051) (xy 121.283938 -267.731358) (xy 121.259736 -267.7753)
			(xy 121.228676 -267.814695) (xy 121.191593 -267.848483) (xy 121.149486 -267.875754) (xy 121.103488 -267.895774)
			(xy 121.054836 -267.908007) (xy 121.004838 -267.912121) (xy 120.95484 -267.908007) (xy 120.906188 -267.895774)
			(xy 120.86019 -267.875754) (xy 120.818083 -267.848483) (xy 120.781 -267.814695) (xy 120.74994 -267.7753)
			(xy 120.725738 -267.731358) (xy 120.709044 -267.684051) (xy 120.700309 -267.63465) (xy 120.69953 -267.609574)
			(xy 120.69953 -267.606018) (xy 120.699938 -267.583984) (xy 120.706319 -267.54038) (xy 120.71223 -267.51915)
			(xy 120.715786 -267.507212) (xy 120.711722 -267.484098) (xy 120.655842 -267.408914) (xy 120.648235 -267.399679)
			(xy 120.626897 -267.388929) (xy 120.614948 -267.38834) (xy 119.51462 -267.38834) (xy 119.502686 -267.388988)
			(xy 119.481364 -267.399721) (xy 119.473726 -267.408914) (xy 119.417846 -267.484098) (xy 119.413782 -267.507212)
			(xy 119.417338 -267.51915) (xy 119.423184 -267.540134) (xy 119.429563 -267.583224) (xy 119.430038 -267.605002)
			(xy 119.430038 -267.609574) (xy 119.429259 -267.63465) (xy 119.420524 -267.684051) (xy 119.40383 -267.731358)
			(xy 119.379628 -267.7753) (xy 119.348568 -267.814695) (xy 119.311485 -267.848483) (xy 119.269378 -267.875754)
			(xy 119.22338 -267.895774) (xy 119.174728 -267.908007) (xy 119.12473 -267.912121) (xy 119.074732 -267.908007)
			(xy 119.02608 -267.895774) (xy 118.980082 -267.875754) (xy 118.937975 -267.848483) (xy 118.900892 -267.814695)
			(xy 118.869832 -267.7753) (xy 118.84563 -267.731358) (xy 118.828936 -267.684051) (xy 118.820201 -267.63465)
			(xy 118.819422 -267.609574) (xy 118.819422 -267.606018) (xy 118.81983 -267.583984) (xy 118.826211 -267.54038)
			(xy 118.832122 -267.51915) (xy 118.835678 -267.507212) (xy 118.831614 -267.484098) (xy 118.775734 -267.408914)
			(xy 118.768127 -267.39968) (xy 118.746788 -267.388934) (xy 118.73484 -267.38834) (xy 117.634512 -267.38834)
			(xy 117.622579 -267.388989) (xy 117.60126 -267.399724) (xy 117.593618 -267.408914) (xy 117.537738 -267.484098)
			(xy 117.533674 -267.507212) (xy 117.53723 -267.51915) (xy 117.543076 -267.540134) (xy 117.549456 -267.583224)
			(xy 117.54993 -267.605002) (xy 117.54993 -267.609574) (xy 117.549151 -267.63465) (xy 117.540416 -267.684051)
			(xy 117.523722 -267.731358) (xy 117.49952 -267.7753) (xy 117.46846 -267.814695) (xy 117.431377 -267.848483)
			(xy 117.38927 -267.875754) (xy 117.343272 -267.895774) (xy 117.29462 -267.908007) (xy 117.244622 -267.912121)
			(xy 117.194624 -267.908007) (xy 117.145972 -267.895774) (xy 117.099974 -267.875754) (xy 117.057867 -267.848483)
			(xy 117.020784 -267.814695) (xy 116.989724 -267.7753) (xy 116.965522 -267.731358) (xy 116.948828 -267.684051)
			(xy 116.940093 -267.63465) (xy 116.939314 -267.609574) (xy 116.939314 -267.606018) (xy 116.939722 -267.583984)
			(xy 116.946103 -267.54038) (xy 116.952014 -267.51915) (xy 116.95557 -267.507212) (xy 116.951506 -267.484098)
			(xy 116.895626 -267.408914) (xy 116.888018 -267.399682) (xy 116.866679 -267.388938) (xy 116.854732 -267.38834)
			(xy 115.754658 -267.38834) (xy 115.742719 -267.38898) (xy 115.721385 -267.399703) (xy 115.713764 -267.408914)
			(xy 115.657884 -267.484098) (xy 115.65382 -267.507212) (xy 115.657376 -267.51915) (xy 115.663223 -267.540134)
			(xy 115.669604 -267.583224) (xy 115.670076 -267.605002) (xy 115.670076 -267.609574) (xy 115.669297 -267.63465)
			(xy 115.660562 -267.684051) (xy 115.643868 -267.731358) (xy 115.619666 -267.7753) (xy 115.588606 -267.814695)
			(xy 115.551523 -267.848483) (xy 115.509416 -267.875754) (xy 115.463418 -267.895774) (xy 115.414766 -267.908007)
			(xy 115.364768 -267.912121) (xy 115.31477 -267.908007) (xy 115.266118 -267.895774) (xy 115.22012 -267.875754)
			(xy 115.178013 -267.848483) (xy 115.14093 -267.814695) (xy 115.10987 -267.7753) (xy 115.085668 -267.731358)
			(xy 115.068974 -267.684051) (xy 115.060239 -267.63465) (xy 115.05946 -267.609574) (xy 115.05946 -267.606018)
			(xy 115.059868 -267.583984) (xy 115.06625 -267.54038) (xy 115.07216 -267.51915) (xy 115.075716 -267.507212)
			(xy 115.071652 -267.484098) (xy 115.015772 -267.408914) (xy 115.008167 -267.399674) (xy 114.986829 -267.388912)
			(xy 114.974878 -267.38834) (xy 113.87455 -267.38834) (xy 113.862612 -267.388981) (xy 113.84128 -267.399707)
			(xy 113.833656 -267.408914) (xy 113.777776 -267.484098) (xy 113.773712 -267.507212) (xy 113.777268 -267.51915)
			(xy 113.783115 -267.540134) (xy 113.789496 -267.583224) (xy 113.789968 -267.605002) (xy 113.789968 -267.609574)
			(xy 113.789189 -267.63465) (xy 113.780454 -267.684051) (xy 113.76376 -267.731358) (xy 113.739558 -267.7753)
			(xy 113.708498 -267.814695) (xy 113.671415 -267.848483) (xy 113.629308 -267.875754) (xy 113.58331 -267.895774)
			(xy 113.534658 -267.908007) (xy 113.48466 -267.912121) (xy 113.434662 -267.908007) (xy 113.38601 -267.895774)
			(xy 113.340012 -267.875754) (xy 113.297905 -267.848483) (xy 113.260822 -267.814695) (xy 113.229762 -267.7753)
			(xy 113.20556 -267.731358) (xy 113.188866 -267.684051) (xy 113.180131 -267.63465) (xy 113.179352 -267.609574)
			(xy 113.179352 -267.606018) (xy 113.17976 -267.583984) (xy 113.186142 -267.54038) (xy 113.192052 -267.51915)
			(xy 113.195608 -267.507212) (xy 113.191544 -267.484098) (xy 113.135664 -267.408914) (xy 113.128059 -267.399675)
			(xy 113.10672 -267.388917) (xy 113.09477 -267.38834) (xy 112.289336 -267.38834) (xy 112.281779 -267.388612)
			(xy 112.267312 -267.392989) (xy 112.260888 -267.396976) (xy 112.237897 -267.411908) (xy 112.188432 -267.435543)
			(xy 112.136013 -267.451594) (xy 112.081796 -267.459709) (xy 112.026976 -267.459709) (xy 111.972759 -267.451594)
			(xy 111.92034 -267.435543) (xy 111.870875 -267.411908) (xy 111.847884 -267.396976) (xy 111.841479 -267.39294)
			(xy 111.827003 -267.388532) (xy 111.819436 -267.38834) (xy 110.120938 -267.38834) (xy 110.109002 -267.388984)
			(xy 110.087674 -267.399712) (xy 110.080044 -267.408914) (xy 110.024164 -267.484098) (xy 110.0201 -267.507212)
			(xy 110.023656 -267.51915) (xy 110.029502 -267.540134) (xy 110.035881 -267.583224) (xy 110.036356 -267.605002)
			(xy 110.036356 -267.609574) (xy 110.035577 -267.63465) (xy 110.026842 -267.684051) (xy 110.010148 -267.731358)
			(xy 109.985946 -267.7753) (xy 109.954886 -267.814695) (xy 109.917803 -267.848483) (xy 109.875696 -267.875754)
			(xy 109.829698 -267.895774) (xy 109.781046 -267.908007) (xy 109.731048 -267.912121) (xy 109.68105 -267.908007)
			(xy 109.632398 -267.895774) (xy 109.5864 -267.875754) (xy 109.544293 -267.848483) (xy 109.50721 -267.814695)
			(xy 109.47615 -267.7753) (xy 109.451948 -267.731358) (xy 109.435254 -267.684051) (xy 109.426519 -267.63465)
			(xy 109.42574 -267.609574) (xy 109.42574 -267.606018) (xy 109.426148 -267.583984) (xy 109.432529 -267.54038)
			(xy 109.43844 -267.51915) (xy 109.441996 -267.507212) (xy 109.437932 -267.484098) (xy 109.382052 -267.408914)
			(xy 109.374446 -267.399677) (xy 109.353107 -267.388924) (xy 109.341158 -267.38834) (xy 108.24083 -267.38834)
			(xy 108.228895 -267.388986) (xy 108.20757 -267.399716) (xy 108.199936 -267.408914) (xy 108.144056 -267.484098)
			(xy 108.139992 -267.507212) (xy 108.143548 -267.51915) (xy 108.149394 -267.540134) (xy 108.155773 -267.583224)
			(xy 108.156248 -267.605002) (xy 108.156248 -267.609574) (xy 108.155469 -267.63465) (xy 108.146734 -267.684051)
			(xy 108.13004 -267.731358) (xy 108.105838 -267.7753) (xy 108.074778 -267.814695) (xy 108.037695 -267.848483)
			(xy 107.995588 -267.875754) (xy 107.94959 -267.895774) (xy 107.900938 -267.908007) (xy 107.85094 -267.912121)
			(xy 107.800942 -267.908007) (xy 107.75229 -267.895774) (xy 107.706292 -267.875754) (xy 107.664185 -267.848483)
			(xy 107.627102 -267.814695) (xy 107.596042 -267.7753) (xy 107.57184 -267.731358) (xy 107.555146 -267.684051)
			(xy 107.546411 -267.63465) (xy 107.545632 -267.609574) (xy 107.545632 -267.606018) (xy 107.54604 -267.583984)
			(xy 107.552421 -267.54038) (xy 107.558332 -267.51915) (xy 107.561888 -267.507212) (xy 107.557824 -267.484098)
			(xy 107.501944 -267.408914) (xy 107.494337 -267.399679) (xy 107.472999 -267.388928) (xy 107.46105 -267.38834)
			(xy 106.360976 -267.38834) (xy 106.349035 -267.388976) (xy 106.327695 -267.399695) (xy 106.320082 -267.408914)
			(xy 106.264202 -267.484098) (xy 106.260138 -267.507212) (xy 106.263694 -267.51915) (xy 106.269541 -267.540134)
			(xy 106.275921 -267.583224) (xy 106.276394 -267.605002) (xy 106.276394 -267.609574) (xy 106.275615 -267.63465)
			(xy 106.26688 -267.684051) (xy 106.250186 -267.731358) (xy 106.225984 -267.7753) (xy 106.194924 -267.814695)
			(xy 106.157841 -267.848483) (xy 106.115734 -267.875754) (xy 106.069736 -267.895774) (xy 106.021084 -267.908007)
			(xy 105.971086 -267.912121) (xy 105.921088 -267.908007) (xy 105.872436 -267.895774) (xy 105.826438 -267.875754)
			(xy 105.784331 -267.848483) (xy 105.747248 -267.814695) (xy 105.716188 -267.7753) (xy 105.691986 -267.731358)
			(xy 105.675292 -267.684051) (xy 105.666557 -267.63465) (xy 105.665778 -267.609574) (xy 105.665778 -267.606018)
			(xy 105.666186 -267.583984) (xy 105.672566 -267.54038) (xy 105.678478 -267.51915) (xy 105.682034 -267.507212)
			(xy 105.67797 -267.484098) (xy 105.62209 -267.408914) (xy 105.61448 -267.399688) (xy 105.593141 -267.38896)
			(xy 105.581196 -267.38834) (xy 104.480868 -267.38834) (xy 104.468928 -267.388978) (xy 104.44759 -267.399699)
			(xy 104.439974 -267.408914) (xy 104.384094 -267.484098) (xy 104.38003 -267.507212) (xy 104.383586 -267.51915)
			(xy 104.389433 -267.540134) (xy 104.395813 -267.583224) (xy 104.396286 -267.605002) (xy 104.396286 -267.609574)
			(xy 104.395507 -267.63465) (xy 104.386772 -267.684051) (xy 104.370078 -267.731358) (xy 104.345876 -267.7753)
			(xy 104.314816 -267.814695) (xy 104.277733 -267.848483) (xy 104.235626 -267.875754) (xy 104.189628 -267.895774)
			(xy 104.140976 -267.908007) (xy 104.090978 -267.912121) (xy 104.04098 -267.908007) (xy 103.992328 -267.895774)
			(xy 103.94633 -267.875754) (xy 103.904223 -267.848483) (xy 103.86714 -267.814695) (xy 103.83608 -267.7753)
			(xy 103.811878 -267.731358) (xy 103.795184 -267.684051) (xy 103.786449 -267.63465) (xy 103.78567 -267.609574)
			(xy 103.78567 -267.606018) (xy 103.786078 -267.583984) (xy 103.792458 -267.54038) (xy 103.79837 -267.51915)
			(xy 103.801926 -267.507212) (xy 103.797862 -267.484098) (xy 103.741982 -267.408914) (xy 103.734371 -267.399689)
			(xy 103.713032 -267.388965) (xy 103.701088 -267.38834) (xy 102.601014 -267.38834) (xy 102.58908 -267.388989)
			(xy 102.567761 -267.399723) (xy 102.56012 -267.408914) (xy 102.50424 -267.484098) (xy 102.500176 -267.507212)
			(xy 102.503732 -267.51915) (xy 102.509578 -267.540134) (xy 102.515957 -267.583224) (xy 102.516432 -267.605002)
			(xy 102.516432 -267.609574) (xy 102.515653 -267.63465) (xy 102.506918 -267.684051) (xy 102.490224 -267.731358)
			(xy 102.466022 -267.7753) (xy 102.434962 -267.814695) (xy 102.397879 -267.848483) (xy 102.355772 -267.875754)
			(xy 102.309774 -267.895774) (xy 102.261122 -267.908007) (xy 102.211124 -267.912121) (xy 102.161126 -267.908007)
			(xy 102.112474 -267.895774) (xy 102.066476 -267.875754) (xy 102.024369 -267.848483) (xy 101.987286 -267.814695)
			(xy 101.956226 -267.7753) (xy 101.932024 -267.731358) (xy 101.91533 -267.684051) (xy 101.906595 -267.63465)
			(xy 101.905816 -267.609574) (xy 101.905816 -267.606018) (xy 101.906224 -267.583984) (xy 101.912605 -267.54038)
			(xy 101.918516 -267.51915) (xy 101.922072 -267.507212) (xy 101.918008 -267.484098) (xy 101.862128 -267.408914)
			(xy 101.85452 -267.399681) (xy 101.833182 -267.388937) (xy 101.821234 -267.38834) (xy 100.720906 -267.38834)
			(xy 100.708973 -267.388991) (xy 100.687657 -267.399727) (xy 100.680012 -267.408914) (xy 100.624132 -267.484098)
			(xy 100.620068 -267.507212) (xy 100.623624 -267.51915) (xy 100.62947 -267.540134) (xy 100.63585 -267.583224)
			(xy 100.636324 -267.605002) (xy 100.636324 -267.609574) (xy 100.635545 -267.63465) (xy 100.62681 -267.684051)
			(xy 100.610116 -267.731358) (xy 100.585914 -267.7753) (xy 100.554854 -267.814695) (xy 100.517771 -267.848483)
			(xy 100.475664 -267.875754) (xy 100.429666 -267.895774) (xy 100.381014 -267.908007) (xy 100.331016 -267.912121)
			(xy 100.281018 -267.908007) (xy 100.232366 -267.895774) (xy 100.186368 -267.875754) (xy 100.144261 -267.848483)
			(xy 100.107178 -267.814695) (xy 100.076118 -267.7753) (xy 100.051916 -267.731358) (xy 100.035222 -267.684051)
			(xy 100.026487 -267.63465) (xy 100.025708 -267.609574) (xy 100.025708 -267.606018) (xy 100.026116 -267.583984)
			(xy 100.032497 -267.54038) (xy 100.038408 -267.51915) (xy 100.041964 -267.507212) (xy 100.0379 -267.484098)
			(xy 99.98202 -267.408914) (xy 99.974412 -267.399683) (xy 99.953073 -267.388942) (xy 99.941126 -267.38834)
			(xy 99.780852 -267.38834) (xy 99.768914 -267.388981) (xy 99.747582 -267.399706) (xy 99.739958 -267.408914)
			(xy 99.684078 -267.484098) (xy 99.680014 -267.507212) (xy 99.68357 -267.51915) (xy 99.689417 -267.540134)
			(xy 99.695798 -267.583224) (xy 99.69627 -267.605002) (xy 99.69627 -267.609574) (xy 99.695557 -267.633396)
			(xy 99.687647 -267.680391) (xy 99.672531 -267.725586) (xy 99.650576 -267.767884) (xy 99.622315 -267.806256)
			(xy 99.588435 -267.839771) (xy 99.549758 -267.867614) (xy 99.507225 -267.889109) (xy 99.461868 -267.903733)
			(xy 99.41479 -267.911133) (xy 99.390962 -267.91158) (xy 99.366974 -267.911107) (xy 99.319588 -267.903596)
			(xy 99.273961 -267.888764) (xy 99.231216 -267.866978) (xy 99.192404 -267.838774) (xy 99.158483 -267.804845)
			(xy 99.130287 -267.766028) (xy 99.10851 -267.723278) (xy 99.093689 -267.677648) (xy 99.086188 -267.630261)
			(xy 99.085654 -267.606272) (xy 99.086169 -267.581401) (xy 99.094279 -267.532325) (xy 99.110232 -267.48521)
			(xy 99.121468 -267.463016) (xy 99.124262 -267.457682) (xy 99.125786 -267.451586) (xy 99.128089 -267.440176)
			(xy 99.123342 -267.417414) (xy 99.116642 -267.407898) (xy 99.10953 -267.3985) (xy 99.088448 -267.38834)
			(xy 99.007422 -267.38834) (xy 98.997359 -267.388779) (xy 98.978779 -267.396517) (xy 98.971354 -267.403326)
			(xy 98.763328 -267.611352) (xy 98.755962 -267.6271) (xy 98.754946 -267.63599) (xy 98.751847 -267.662076)
			(xy 98.737865 -267.712708) (xy 98.715424 -267.7602) (xy 98.685185 -267.803151) (xy 98.648042 -267.840292)
			(xy 98.605091 -267.870529) (xy 98.557598 -267.892969) (xy 98.506965 -267.906949) (xy 98.48088 -267.910056)
			(xy 98.47199 -267.911072) (xy 98.456242 -267.918438) (xy 98.368866 -268.005814) (xy 111.710473 -268.005814)
			(xy 111.714503 -267.953316) (xy 111.7265 -267.902048) (xy 111.746183 -267.853213) (xy 111.773089 -267.807954)
			(xy 111.806589 -267.767333) (xy 111.845897 -267.732302) (xy 111.890092 -267.703682) (xy 111.938137 -267.682143)
			(xy 111.988908 -267.668191) (xy 112.041213 -267.662153) (xy 112.093827 -267.66417) (xy 112.145517 -267.674194)
			(xy 112.19507 -267.691992) (xy 112.241326 -267.717145) (xy 112.2832 -267.749064) (xy 112.319712 -267.787002)
			(xy 112.350004 -267.830068) (xy 112.373367 -267.877253) (xy 112.389253 -267.927452) (xy 112.39729 -267.979488)
			(xy 112.397794 -268.005814) (xy 112.39729 -268.03214) (xy 112.389253 -268.084176) (xy 112.373367 -268.134375)
			(xy 112.350004 -268.18156) (xy 112.319712 -268.224626) (xy 112.2832 -268.262564) (xy 112.241326 -268.294483)
			(xy 112.19507 -268.319636) (xy 112.145517 -268.337434) (xy 112.093827 -268.347458) (xy 112.041213 -268.349475)
			(xy 111.988908 -268.343437) (xy 111.938137 -268.329485) (xy 111.890092 -268.307946) (xy 111.845897 -268.279326)
			(xy 111.806589 -268.244295) (xy 111.773089 -268.203674) (xy 111.746183 -268.158415) (xy 111.7265 -268.10958)
			(xy 111.714503 -268.058312) (xy 111.710473 -268.005814) (xy 98.368866 -268.005814) (xy 98.220276 -268.154404)
			(xy 98.213983 -268.161347) (xy 98.206437 -268.178482) (xy 98.205524 -268.197183) (xy 98.211364 -268.214972)
			(xy 98.216974 -268.222476) (xy 98.233203 -268.243125) (xy 98.259075 -268.288827) (xy 98.276759 -268.338276)
			(xy 98.285735 -268.39002) (xy 98.286316 -268.416278) (xy 99.555312 -268.416278) (xy 99.559272 -268.367224)
			(xy 99.571049 -268.31944) (xy 99.59034 -268.274164) (xy 99.616643 -268.232568) (xy 99.649278 -268.195731)
			(xy 99.687399 -268.164606) (xy 99.73002 -268.139999) (xy 99.776036 -268.122547) (xy 99.824255 -268.112703)
			(xy 99.87343 -268.110722) (xy 99.922285 -268.116654) (xy 99.969556 -268.130346) (xy 100.014018 -268.151444)
			(xy 100.054521 -268.1794) (xy 100.090014 -268.213492) (xy 100.119579 -268.252836) (xy 100.14245 -268.296413)
			(xy 100.158034 -268.343094) (xy 100.165929 -268.391671) (xy 100.166424 -268.416278) (xy 101.435166 -268.416278)
			(xy 101.439126 -268.367224) (xy 101.450903 -268.31944) (xy 101.470194 -268.274164) (xy 101.496497 -268.232568)
			(xy 101.529132 -268.195731) (xy 101.567253 -268.164606) (xy 101.609874 -268.139999) (xy 101.65589 -268.122547)
			(xy 101.704109 -268.112703) (xy 101.753284 -268.110722) (xy 101.802139 -268.116654) (xy 101.84941 -268.130346)
			(xy 101.893872 -268.151444) (xy 101.934375 -268.1794) (xy 101.969868 -268.213492) (xy 101.999433 -268.252836)
			(xy 102.022304 -268.296413) (xy 102.037888 -268.343094) (xy 102.045783 -268.391671) (xy 102.046278 -268.416278)
			(xy 103.315274 -268.416278) (xy 103.319234 -268.367224) (xy 103.331011 -268.31944) (xy 103.350302 -268.274164)
			(xy 103.376605 -268.232568) (xy 103.40924 -268.195731) (xy 103.447361 -268.164606) (xy 103.489982 -268.139999)
			(xy 103.535998 -268.122547) (xy 103.584217 -268.112703) (xy 103.633392 -268.110722) (xy 103.682247 -268.116654)
			(xy 103.729518 -268.130346) (xy 103.77398 -268.151444) (xy 103.814483 -268.1794) (xy 103.849976 -268.213492)
			(xy 103.879541 -268.252836) (xy 103.902412 -268.296413) (xy 103.917996 -268.343094) (xy 103.925891 -268.391671)
			(xy 103.926386 -268.416278) (xy 105.195128 -268.416278) (xy 105.199088 -268.367224) (xy 105.210865 -268.31944)
			(xy 105.230156 -268.274164) (xy 105.256459 -268.232568) (xy 105.289094 -268.195731) (xy 105.327215 -268.164606)
			(xy 105.369836 -268.139999) (xy 105.415852 -268.122547) (xy 105.464071 -268.112703) (xy 105.513246 -268.110722)
			(xy 105.562101 -268.116654) (xy 105.609372 -268.130346) (xy 105.653834 -268.151444) (xy 105.694337 -268.1794)
			(xy 105.72983 -268.213492) (xy 105.759395 -268.252836) (xy 105.782266 -268.296413) (xy 105.79785 -268.343094)
			(xy 105.805745 -268.391671) (xy 105.80624 -268.416278) (xy 107.075236 -268.416278) (xy 107.079196 -268.367224)
			(xy 107.090973 -268.31944) (xy 107.110264 -268.274164) (xy 107.136567 -268.232568) (xy 107.169202 -268.195731)
			(xy 107.207323 -268.164606) (xy 107.249944 -268.139999) (xy 107.29596 -268.122547) (xy 107.344179 -268.112703)
			(xy 107.393354 -268.110722) (xy 107.442209 -268.116654) (xy 107.48948 -268.130346) (xy 107.533942 -268.151444)
			(xy 107.574445 -268.1794) (xy 107.609938 -268.213492) (xy 107.639503 -268.252836) (xy 107.662374 -268.296413)
			(xy 107.677958 -268.343094) (xy 107.685853 -268.391671) (xy 107.686348 -268.416278) (xy 108.955344 -268.416278)
			(xy 108.959304 -268.367224) (xy 108.971081 -268.31944) (xy 108.990372 -268.274164) (xy 109.016675 -268.232568)
			(xy 109.04931 -268.195731) (xy 109.087431 -268.164606) (xy 109.130052 -268.139999) (xy 109.176068 -268.122547)
			(xy 109.224287 -268.112703) (xy 109.273462 -268.110722) (xy 109.322317 -268.116654) (xy 109.369588 -268.130346)
			(xy 109.41405 -268.151444) (xy 109.454553 -268.1794) (xy 109.490046 -268.213492) (xy 109.519611 -268.252836)
			(xy 109.542482 -268.296413) (xy 109.558066 -268.343094) (xy 109.565961 -268.391671) (xy 109.566456 -268.416278)
			(xy 113.64901 -268.416278) (xy 113.65297 -268.367224) (xy 113.664747 -268.31944) (xy 113.684038 -268.274164)
			(xy 113.710341 -268.232568) (xy 113.742976 -268.195731) (xy 113.781097 -268.164606) (xy 113.823718 -268.139999)
			(xy 113.869734 -268.122547) (xy 113.917953 -268.112703) (xy 113.967128 -268.110722) (xy 114.015983 -268.116654)
			(xy 114.063254 -268.130346) (xy 114.107716 -268.151444) (xy 114.148219 -268.1794) (xy 114.183712 -268.213492)
			(xy 114.213277 -268.252836) (xy 114.236148 -268.296413) (xy 114.251732 -268.343094) (xy 114.259627 -268.391671)
			(xy 114.260122 -268.416278) (xy 115.528864 -268.416278) (xy 115.532824 -268.367224) (xy 115.544601 -268.31944)
			(xy 115.563892 -268.274164) (xy 115.590195 -268.232568) (xy 115.62283 -268.195731) (xy 115.660951 -268.164606)
			(xy 115.703572 -268.139999) (xy 115.749588 -268.122547) (xy 115.797807 -268.112703) (xy 115.846982 -268.110722)
			(xy 115.895837 -268.116654) (xy 115.943108 -268.130346) (xy 115.98757 -268.151444) (xy 116.028073 -268.1794)
			(xy 116.063566 -268.213492) (xy 116.093131 -268.252836) (xy 116.116002 -268.296413) (xy 116.131586 -268.343094)
			(xy 116.139481 -268.391671) (xy 116.139976 -268.416278) (xy 117.408972 -268.416278) (xy 117.412932 -268.367224)
			(xy 117.424709 -268.31944) (xy 117.444 -268.274164) (xy 117.470303 -268.232568) (xy 117.502938 -268.195731)
			(xy 117.541059 -268.164606) (xy 117.58368 -268.139999) (xy 117.629696 -268.122547) (xy 117.677915 -268.112703)
			(xy 117.72709 -268.110722) (xy 117.775945 -268.116654) (xy 117.823216 -268.130346) (xy 117.867678 -268.151444)
			(xy 117.908181 -268.1794) (xy 117.943674 -268.213492) (xy 117.973239 -268.252836) (xy 117.99611 -268.296413)
			(xy 118.011694 -268.343094) (xy 118.019589 -268.391671) (xy 118.020084 -268.416278) (xy 119.288826 -268.416278)
			(xy 119.292786 -268.367224) (xy 119.304563 -268.31944) (xy 119.323854 -268.274164) (xy 119.350157 -268.232568)
			(xy 119.382792 -268.195731) (xy 119.420913 -268.164606) (xy 119.463534 -268.139999) (xy 119.50955 -268.122547)
			(xy 119.557769 -268.112703) (xy 119.606944 -268.110722) (xy 119.655799 -268.116654) (xy 119.70307 -268.130346)
			(xy 119.747532 -268.151444) (xy 119.788035 -268.1794) (xy 119.823528 -268.213492) (xy 119.853093 -268.252836)
			(xy 119.875964 -268.296413) (xy 119.891548 -268.343094) (xy 119.899443 -268.391671) (xy 119.899938 -268.416278)
			(xy 121.168934 -268.416278) (xy 121.172894 -268.367224) (xy 121.184671 -268.31944) (xy 121.203962 -268.274164)
			(xy 121.230265 -268.232568) (xy 121.2629 -268.195731) (xy 121.301021 -268.164606) (xy 121.343642 -268.139999)
			(xy 121.389658 -268.122547) (xy 121.437877 -268.112703) (xy 121.487052 -268.110722) (xy 121.535907 -268.116654)
			(xy 121.583178 -268.130346) (xy 121.62764 -268.151444) (xy 121.668143 -268.1794) (xy 121.703636 -268.213492)
			(xy 121.733201 -268.252836) (xy 121.756072 -268.296413) (xy 121.771656 -268.343094) (xy 121.779551 -268.391671)
			(xy 121.780046 -268.416278) (xy 123.049042 -268.416278) (xy 123.053002 -268.367224) (xy 123.064779 -268.31944)
			(xy 123.08407 -268.274164) (xy 123.110373 -268.232568) (xy 123.143008 -268.195731) (xy 123.181129 -268.164606)
			(xy 123.22375 -268.139999) (xy 123.269766 -268.122547) (xy 123.317985 -268.112703) (xy 123.36716 -268.110722)
			(xy 123.416015 -268.116654) (xy 123.463286 -268.130346) (xy 123.507748 -268.151444) (xy 123.548251 -268.1794)
			(xy 123.583744 -268.213492) (xy 123.613309 -268.252836) (xy 123.63618 -268.296413) (xy 123.651764 -268.343094)
			(xy 123.659659 -268.391671) (xy 123.660154 -268.416278) (xy 124.928896 -268.416278) (xy 124.932856 -268.367224)
			(xy 124.944633 -268.31944) (xy 124.963924 -268.274164) (xy 124.990227 -268.232568) (xy 125.022862 -268.195731)
			(xy 125.060983 -268.164606) (xy 125.103604 -268.139999) (xy 125.14962 -268.122547) (xy 125.197839 -268.112703)
			(xy 125.247014 -268.110722) (xy 125.295869 -268.116654) (xy 125.34314 -268.130346) (xy 125.387602 -268.151444)
			(xy 125.428105 -268.1794) (xy 125.463598 -268.213492) (xy 125.493163 -268.252836) (xy 125.516034 -268.296413)
			(xy 125.531618 -268.343094) (xy 125.539513 -268.391671) (xy 125.540008 -268.416278) (xy 125.539513 -268.440885)
			(xy 125.531618 -268.489462) (xy 125.516034 -268.536143) (xy 125.493163 -268.57972) (xy 125.463598 -268.619064)
			(xy 125.428105 -268.653156) (xy 125.387602 -268.681112) (xy 125.34314 -268.70221) (xy 125.295869 -268.715902)
			(xy 125.247014 -268.721834) (xy 125.197839 -268.719853) (xy 125.14962 -268.710009) (xy 125.103604 -268.692557)
			(xy 125.060983 -268.66795) (xy 125.022862 -268.636825) (xy 124.990227 -268.599988) (xy 124.963924 -268.558392)
			(xy 124.944633 -268.513116) (xy 124.932856 -268.465332) (xy 124.928896 -268.416278) (xy 123.660154 -268.416278)
			(xy 123.659659 -268.440885) (xy 123.651764 -268.489462) (xy 123.63618 -268.536143) (xy 123.613309 -268.57972)
			(xy 123.583744 -268.619064) (xy 123.548251 -268.653156) (xy 123.507748 -268.681112) (xy 123.463286 -268.70221)
			(xy 123.416015 -268.715902) (xy 123.36716 -268.721834) (xy 123.317985 -268.719853) (xy 123.269766 -268.710009)
			(xy 123.22375 -268.692557) (xy 123.181129 -268.66795) (xy 123.143008 -268.636825) (xy 123.110373 -268.599988)
			(xy 123.08407 -268.558392) (xy 123.064779 -268.513116) (xy 123.053002 -268.465332) (xy 123.049042 -268.416278)
			(xy 121.780046 -268.416278) (xy 121.779551 -268.440885) (xy 121.771656 -268.489462) (xy 121.756072 -268.536143)
			(xy 121.733201 -268.57972) (xy 121.703636 -268.619064) (xy 121.668143 -268.653156) (xy 121.62764 -268.681112)
			(xy 121.583178 -268.70221) (xy 121.535907 -268.715902) (xy 121.487052 -268.721834) (xy 121.437877 -268.719853)
			(xy 121.389658 -268.710009) (xy 121.343642 -268.692557) (xy 121.301021 -268.66795) (xy 121.2629 -268.636825)
			(xy 121.230265 -268.599988) (xy 121.203962 -268.558392) (xy 121.184671 -268.513116) (xy 121.172894 -268.465332)
			(xy 121.168934 -268.416278) (xy 119.899938 -268.416278) (xy 119.899443 -268.440885) (xy 119.891548 -268.489462)
			(xy 119.875964 -268.536143) (xy 119.853093 -268.57972) (xy 119.823528 -268.619064) (xy 119.788035 -268.653156)
			(xy 119.747532 -268.681112) (xy 119.70307 -268.70221) (xy 119.655799 -268.715902) (xy 119.606944 -268.721834)
			(xy 119.557769 -268.719853) (xy 119.50955 -268.710009) (xy 119.463534 -268.692557) (xy 119.420913 -268.66795)
			(xy 119.382792 -268.636825) (xy 119.350157 -268.599988) (xy 119.323854 -268.558392) (xy 119.304563 -268.513116)
			(xy 119.292786 -268.465332) (xy 119.288826 -268.416278) (xy 118.020084 -268.416278) (xy 118.019589 -268.440885)
			(xy 118.011694 -268.489462) (xy 117.99611 -268.536143) (xy 117.973239 -268.57972) (xy 117.943674 -268.619064)
			(xy 117.908181 -268.653156) (xy 117.867678 -268.681112) (xy 117.823216 -268.70221) (xy 117.775945 -268.715902)
			(xy 117.72709 -268.721834) (xy 117.677915 -268.719853) (xy 117.629696 -268.710009) (xy 117.58368 -268.692557)
			(xy 117.541059 -268.66795) (xy 117.502938 -268.636825) (xy 117.470303 -268.599988) (xy 117.444 -268.558392)
			(xy 117.424709 -268.513116) (xy 117.412932 -268.465332) (xy 117.408972 -268.416278) (xy 116.139976 -268.416278)
			(xy 116.139481 -268.440885) (xy 116.131586 -268.489462) (xy 116.116002 -268.536143) (xy 116.093131 -268.57972)
			(xy 116.063566 -268.619064) (xy 116.028073 -268.653156) (xy 115.98757 -268.681112) (xy 115.943108 -268.70221)
			(xy 115.895837 -268.715902) (xy 115.846982 -268.721834) (xy 115.797807 -268.719853) (xy 115.749588 -268.710009)
			(xy 115.703572 -268.692557) (xy 115.660951 -268.66795) (xy 115.62283 -268.636825) (xy 115.590195 -268.599988)
			(xy 115.563892 -268.558392) (xy 115.544601 -268.513116) (xy 115.532824 -268.465332) (xy 115.528864 -268.416278)
			(xy 114.260122 -268.416278) (xy 114.259627 -268.440885) (xy 114.251732 -268.489462) (xy 114.236148 -268.536143)
			(xy 114.213277 -268.57972) (xy 114.183712 -268.619064) (xy 114.148219 -268.653156) (xy 114.107716 -268.681112)
			(xy 114.063254 -268.70221) (xy 114.015983 -268.715902) (xy 113.967128 -268.721834) (xy 113.917953 -268.719853)
			(xy 113.869734 -268.710009) (xy 113.823718 -268.692557) (xy 113.781097 -268.66795) (xy 113.742976 -268.636825)
			(xy 113.710341 -268.599988) (xy 113.684038 -268.558392) (xy 113.664747 -268.513116) (xy 113.65297 -268.465332)
			(xy 113.64901 -268.416278) (xy 109.566456 -268.416278) (xy 109.565961 -268.440885) (xy 109.558066 -268.489462)
			(xy 109.542482 -268.536143) (xy 109.519611 -268.57972) (xy 109.490046 -268.619064) (xy 109.454553 -268.653156)
			(xy 109.41405 -268.681112) (xy 109.369588 -268.70221) (xy 109.322317 -268.715902) (xy 109.273462 -268.721834)
			(xy 109.224287 -268.719853) (xy 109.176068 -268.710009) (xy 109.130052 -268.692557) (xy 109.087431 -268.66795)
			(xy 109.04931 -268.636825) (xy 109.016675 -268.599988) (xy 108.990372 -268.558392) (xy 108.971081 -268.513116)
			(xy 108.959304 -268.465332) (xy 108.955344 -268.416278) (xy 107.686348 -268.416278) (xy 107.685853 -268.440885)
			(xy 107.677958 -268.489462) (xy 107.662374 -268.536143) (xy 107.639503 -268.57972) (xy 107.609938 -268.619064)
			(xy 107.574445 -268.653156) (xy 107.533942 -268.681112) (xy 107.48948 -268.70221) (xy 107.442209 -268.715902)
			(xy 107.393354 -268.721834) (xy 107.344179 -268.719853) (xy 107.29596 -268.710009) (xy 107.249944 -268.692557)
			(xy 107.207323 -268.66795) (xy 107.169202 -268.636825) (xy 107.136567 -268.599988) (xy 107.110264 -268.558392)
			(xy 107.090973 -268.513116) (xy 107.079196 -268.465332) (xy 107.075236 -268.416278) (xy 105.80624 -268.416278)
			(xy 105.805745 -268.440885) (xy 105.79785 -268.489462) (xy 105.782266 -268.536143) (xy 105.759395 -268.57972)
			(xy 105.72983 -268.619064) (xy 105.694337 -268.653156) (xy 105.653834 -268.681112) (xy 105.609372 -268.70221)
			(xy 105.562101 -268.715902) (xy 105.513246 -268.721834) (xy 105.464071 -268.719853) (xy 105.415852 -268.710009)
			(xy 105.369836 -268.692557) (xy 105.327215 -268.66795) (xy 105.289094 -268.636825) (xy 105.256459 -268.599988)
			(xy 105.230156 -268.558392) (xy 105.210865 -268.513116) (xy 105.199088 -268.465332) (xy 105.195128 -268.416278)
			(xy 103.926386 -268.416278) (xy 103.925891 -268.440885) (xy 103.917996 -268.489462) (xy 103.902412 -268.536143)
			(xy 103.879541 -268.57972) (xy 103.849976 -268.619064) (xy 103.814483 -268.653156) (xy 103.77398 -268.681112)
			(xy 103.729518 -268.70221) (xy 103.682247 -268.715902) (xy 103.633392 -268.721834) (xy 103.584217 -268.719853)
			(xy 103.535998 -268.710009) (xy 103.489982 -268.692557) (xy 103.447361 -268.66795) (xy 103.40924 -268.636825)
			(xy 103.376605 -268.599988) (xy 103.350302 -268.558392) (xy 103.331011 -268.513116) (xy 103.319234 -268.465332)
			(xy 103.315274 -268.416278) (xy 102.046278 -268.416278) (xy 102.045783 -268.440885) (xy 102.037888 -268.489462)
			(xy 102.022304 -268.536143) (xy 101.999433 -268.57972) (xy 101.969868 -268.619064) (xy 101.934375 -268.653156)
			(xy 101.893872 -268.681112) (xy 101.84941 -268.70221) (xy 101.802139 -268.715902) (xy 101.753284 -268.721834)
			(xy 101.704109 -268.719853) (xy 101.65589 -268.710009) (xy 101.609874 -268.692557) (xy 101.567253 -268.66795)
			(xy 101.529132 -268.636825) (xy 101.496497 -268.599988) (xy 101.470194 -268.558392) (xy 101.450903 -268.513116)
			(xy 101.439126 -268.465332) (xy 101.435166 -268.416278) (xy 100.166424 -268.416278) (xy 100.165929 -268.440885)
			(xy 100.158034 -268.489462) (xy 100.14245 -268.536143) (xy 100.119579 -268.57972) (xy 100.090014 -268.619064)
			(xy 100.054521 -268.653156) (xy 100.014018 -268.681112) (xy 99.969556 -268.70221) (xy 99.922285 -268.715902)
			(xy 99.87343 -268.721834) (xy 99.824255 -268.719853) (xy 99.776036 -268.710009) (xy 99.73002 -268.692557)
			(xy 99.687399 -268.66795) (xy 99.649278 -268.636825) (xy 99.616643 -268.599988) (xy 99.59034 -268.558392)
			(xy 99.571049 -268.513116) (xy 99.559272 -268.465332) (xy 99.555312 -268.416278) (xy 98.286316 -268.416278)
			(xy 98.285871 -268.440273) (xy 98.278368 -268.487671) (xy 98.263541 -268.533312) (xy 98.241757 -268.576072)
			(xy 98.213552 -268.614897) (xy 98.17962 -268.648832) (xy 98.140798 -268.677041) (xy 98.09804 -268.69883)
			(xy 98.0524 -268.713661) (xy 98.005002 -268.721169) (xy 97.981008 -268.721586) (xy 97.968245 -268.721449)
			(xy 97.94281 -268.719291) (xy 97.930208 -268.717268) (xy 97.930208 -268.717522) (xy 97.906998 -268.713144)
			(xy 97.862199 -268.698184) (xy 97.820238 -268.676505) (xy 97.800922 -268.662912) (xy 97.793712 -268.65808)
			(xy 97.777088 -268.653136) (xy 97.76841 -268.65326) (xy 97.738438 -268.654784) (xy 97.729136 -268.655661)
			(xy 97.712065 -268.663217) (xy 97.705164 -268.669516) (xy 97.220786 -269.153894) (xy 97.21342 -269.161006)
			(xy 97.2058 -269.179802) (xy 97.2058 -269.226284) (xy 99.085158 -269.226284) (xy 99.089118 -269.17723)
			(xy 99.100895 -269.129446) (xy 99.120186 -269.08417) (xy 99.146489 -269.042574) (xy 99.179124 -269.005737)
			(xy 99.217245 -268.974612) (xy 99.259866 -268.950005) (xy 99.305882 -268.932553) (xy 99.354101 -268.922709)
			(xy 99.403276 -268.920728) (xy 99.452131 -268.92666) (xy 99.499402 -268.940352) (xy 99.543864 -268.96145)
			(xy 99.584367 -268.989406) (xy 99.61986 -269.023498) (xy 99.649425 -269.062842) (xy 99.672296 -269.106419)
			(xy 99.68788 -269.1531) (xy 99.695775 -269.201677) (xy 99.69627 -269.226284) (xy 101.90532 -269.226284)
			(xy 101.90928 -269.17723) (xy 101.921057 -269.129446) (xy 101.940348 -269.08417) (xy 101.966651 -269.042574)
			(xy 101.999286 -269.005737) (xy 102.037407 -268.974612) (xy 102.080028 -268.950005) (xy 102.126044 -268.932553)
			(xy 102.174263 -268.922709) (xy 102.223438 -268.920728) (xy 102.272293 -268.92666) (xy 102.319564 -268.940352)
			(xy 102.364026 -268.96145) (xy 102.404529 -268.989406) (xy 102.440022 -269.023498) (xy 102.469587 -269.062842)
			(xy 102.492458 -269.106419) (xy 102.508042 -269.1531) (xy 102.515937 -269.201677) (xy 102.516432 -269.226284)
			(xy 104.725228 -269.226284) (xy 104.729188 -269.17723) (xy 104.740965 -269.129446) (xy 104.760256 -269.08417)
			(xy 104.786559 -269.042574) (xy 104.819194 -269.005737) (xy 104.857315 -268.974612) (xy 104.899936 -268.950005)
			(xy 104.945952 -268.932553) (xy 104.994171 -268.922709) (xy 105.043346 -268.920728) (xy 105.092201 -268.92666)
			(xy 105.139472 -268.940352) (xy 105.183934 -268.96145) (xy 105.224437 -268.989406) (xy 105.25993 -269.023498)
			(xy 105.289495 -269.062842) (xy 105.312366 -269.106419) (xy 105.32795 -269.1531) (xy 105.335845 -269.201677)
			(xy 105.33634 -269.226284) (xy 107.545136 -269.226284) (xy 107.549096 -269.17723) (xy 107.560873 -269.129446)
			(xy 107.580164 -269.08417) (xy 107.606467 -269.042574) (xy 107.639102 -269.005737) (xy 107.677223 -268.974612)
			(xy 107.719844 -268.950005) (xy 107.76586 -268.932553) (xy 107.814079 -268.922709) (xy 107.863254 -268.920728)
			(xy 107.912109 -268.92666) (xy 107.95938 -268.940352) (xy 108.003842 -268.96145) (xy 108.044345 -268.989406)
			(xy 108.079838 -269.023498) (xy 108.109403 -269.062842) (xy 108.132274 -269.106419) (xy 108.147858 -269.1531)
			(xy 108.155753 -269.201677) (xy 108.156248 -269.226284) (xy 108.48519 -269.226284) (xy 108.48915 -269.17723)
			(xy 108.500927 -269.129446) (xy 108.520218 -269.08417) (xy 108.546521 -269.042574) (xy 108.579156 -269.005737)
			(xy 108.617277 -268.974612) (xy 108.659898 -268.950005) (xy 108.705914 -268.932553) (xy 108.754133 -268.922709)
			(xy 108.803308 -268.920728) (xy 108.852163 -268.92666) (xy 108.899434 -268.940352) (xy 108.943896 -268.96145)
			(xy 108.984399 -268.989406) (xy 109.019892 -269.023498) (xy 109.049457 -269.062842) (xy 109.072328 -269.106419)
			(xy 109.087912 -269.1531) (xy 109.095807 -269.201677) (xy 109.096302 -269.226284) (xy 109.425244 -269.226284)
			(xy 109.429204 -269.17723) (xy 109.440981 -269.129446) (xy 109.460272 -269.08417) (xy 109.486575 -269.042574)
			(xy 109.51921 -269.005737) (xy 109.557331 -268.974612) (xy 109.599952 -268.950005) (xy 109.645968 -268.932553)
			(xy 109.694187 -268.922709) (xy 109.743362 -268.920728) (xy 109.792217 -268.92666) (xy 109.839488 -268.940352)
			(xy 109.88395 -268.96145) (xy 109.924453 -268.989406) (xy 109.959946 -269.023498) (xy 109.989511 -269.062842)
			(xy 110.012382 -269.106419) (xy 110.027966 -269.1531) (xy 110.035861 -269.201677) (xy 110.036356 -269.226284)
			(xy 110.365298 -269.226284) (xy 110.369258 -269.17723) (xy 110.381035 -269.129446) (xy 110.400326 -269.08417)
			(xy 110.426629 -269.042574) (xy 110.459264 -269.005737) (xy 110.497385 -268.974612) (xy 110.540006 -268.950005)
			(xy 110.586022 -268.932553) (xy 110.634241 -268.922709) (xy 110.683416 -268.920728) (xy 110.732271 -268.92666)
			(xy 110.779542 -268.940352) (xy 110.824004 -268.96145) (xy 110.864507 -268.989406) (xy 110.9 -269.023498)
			(xy 110.929565 -269.062842) (xy 110.952436 -269.106419) (xy 110.96802 -269.1531) (xy 110.975915 -269.201677)
			(xy 110.97641 -269.226284) (xy 113.178856 -269.226284) (xy 113.182816 -269.17723) (xy 113.194593 -269.129446)
			(xy 113.213884 -269.08417) (xy 113.240187 -269.042574) (xy 113.272822 -269.005737) (xy 113.310943 -268.974612)
			(xy 113.353564 -268.950005) (xy 113.39958 -268.932553) (xy 113.447799 -268.922709) (xy 113.496974 -268.920728)
			(xy 113.545829 -268.92666) (xy 113.5931 -268.940352) (xy 113.637562 -268.96145) (xy 113.678065 -268.989406)
			(xy 113.713558 -269.023498) (xy 113.743123 -269.062842) (xy 113.765994 -269.106419) (xy 113.781578 -269.1531)
			(xy 113.789473 -269.201677) (xy 113.789968 -269.226284) (xy 114.11891 -269.226284) (xy 114.12287 -269.17723)
			(xy 114.134647 -269.129446) (xy 114.153938 -269.08417) (xy 114.180241 -269.042574) (xy 114.212876 -269.005737)
			(xy 114.250997 -268.974612) (xy 114.293618 -268.950005) (xy 114.339634 -268.932553) (xy 114.387853 -268.922709)
			(xy 114.437028 -268.920728) (xy 114.485883 -268.92666) (xy 114.533154 -268.940352) (xy 114.577616 -268.96145)
			(xy 114.618119 -268.989406) (xy 114.653612 -269.023498) (xy 114.683177 -269.062842) (xy 114.706048 -269.106419)
			(xy 114.721632 -269.1531) (xy 114.729527 -269.201677) (xy 114.730022 -269.226284) (xy 115.058964 -269.226284)
			(xy 115.062924 -269.17723) (xy 115.074701 -269.129446) (xy 115.093992 -269.08417) (xy 115.120295 -269.042574)
			(xy 115.15293 -269.005737) (xy 115.191051 -268.974612) (xy 115.233672 -268.950005) (xy 115.279688 -268.932553)
			(xy 115.327907 -268.922709) (xy 115.377082 -268.920728) (xy 115.425937 -268.92666) (xy 115.473208 -268.940352)
			(xy 115.51767 -268.96145) (xy 115.558173 -268.989406) (xy 115.593666 -269.023498) (xy 115.623231 -269.062842)
			(xy 115.646102 -269.106419) (xy 115.661686 -269.1531) (xy 115.669581 -269.201677) (xy 115.670076 -269.226284)
			(xy 115.999018 -269.226284) (xy 116.002978 -269.17723) (xy 116.014755 -269.129446) (xy 116.034046 -269.08417)
			(xy 116.060349 -269.042574) (xy 116.092984 -269.005737) (xy 116.131105 -268.974612) (xy 116.173726 -268.950005)
			(xy 116.219742 -268.932553) (xy 116.267961 -268.922709) (xy 116.317136 -268.920728) (xy 116.365991 -268.92666)
			(xy 116.413262 -268.940352) (xy 116.457724 -268.96145) (xy 116.498227 -268.989406) (xy 116.53372 -269.023498)
			(xy 116.563285 -269.062842) (xy 116.586156 -269.106419) (xy 116.60174 -269.1531) (xy 116.609635 -269.201677)
			(xy 116.61013 -269.226284) (xy 118.818926 -269.226284) (xy 118.822886 -269.17723) (xy 118.834663 -269.129446)
			(xy 118.853954 -269.08417) (xy 118.880257 -269.042574) (xy 118.912892 -269.005737) (xy 118.951013 -268.974612)
			(xy 118.993634 -268.950005) (xy 119.03965 -268.932553) (xy 119.087869 -268.922709) (xy 119.137044 -268.920728)
			(xy 119.185899 -268.92666) (xy 119.23317 -268.940352) (xy 119.277632 -268.96145) (xy 119.318135 -268.989406)
			(xy 119.353628 -269.023498) (xy 119.383193 -269.062842) (xy 119.406064 -269.106419) (xy 119.421648 -269.1531)
			(xy 119.429543 -269.201677) (xy 119.430038 -269.226284) (xy 121.638834 -269.226284) (xy 121.642794 -269.17723)
			(xy 121.654571 -269.129446) (xy 121.673862 -269.08417) (xy 121.700165 -269.042574) (xy 121.7328 -269.005737)
			(xy 121.770921 -268.974612) (xy 121.813542 -268.950005) (xy 121.859558 -268.932553) (xy 121.907777 -268.922709)
			(xy 121.956952 -268.920728) (xy 122.005807 -268.92666) (xy 122.053078 -268.940352) (xy 122.09754 -268.96145)
			(xy 122.138043 -268.989406) (xy 122.173536 -269.023498) (xy 122.203101 -269.062842) (xy 122.225972 -269.106419)
			(xy 122.241556 -269.1531) (xy 122.249451 -269.201677) (xy 122.249946 -269.226284) (xy 124.458996 -269.226284)
			(xy 124.462956 -269.17723) (xy 124.474733 -269.129446) (xy 124.494024 -269.08417) (xy 124.520327 -269.042574)
			(xy 124.552962 -269.005737) (xy 124.591083 -268.974612) (xy 124.633704 -268.950005) (xy 124.67972 -268.932553)
			(xy 124.727939 -268.922709) (xy 124.777114 -268.920728) (xy 124.825969 -268.92666) (xy 124.87324 -268.940352)
			(xy 124.917702 -268.96145) (xy 124.958205 -268.989406) (xy 124.993698 -269.023498) (xy 125.023263 -269.062842)
			(xy 125.046134 -269.106419) (xy 125.061718 -269.1531) (xy 125.069613 -269.201677) (xy 125.070108 -269.226284)
			(xy 125.069613 -269.250891) (xy 125.061718 -269.299468) (xy 125.046134 -269.346149) (xy 125.023263 -269.389726)
			(xy 124.993698 -269.42907) (xy 124.958205 -269.463162) (xy 124.917702 -269.491118) (xy 124.87324 -269.512216)
			(xy 124.825969 -269.525908) (xy 124.777114 -269.53184) (xy 124.727939 -269.529859) (xy 124.67972 -269.520015)
			(xy 124.633704 -269.502563) (xy 124.591083 -269.477956) (xy 124.552962 -269.446831) (xy 124.520327 -269.409994)
			(xy 124.494024 -269.368398) (xy 124.474733 -269.323122) (xy 124.462956 -269.275338) (xy 124.458996 -269.226284)
			(xy 122.249946 -269.226284) (xy 122.249451 -269.250891) (xy 122.241556 -269.299468) (xy 122.225972 -269.346149)
			(xy 122.203101 -269.389726) (xy 122.173536 -269.42907) (xy 122.138043 -269.463162) (xy 122.09754 -269.491118)
			(xy 122.053078 -269.512216) (xy 122.005807 -269.525908) (xy 121.956952 -269.53184) (xy 121.907777 -269.529859)
			(xy 121.859558 -269.520015) (xy 121.813542 -269.502563) (xy 121.770921 -269.477956) (xy 121.7328 -269.446831)
			(xy 121.700165 -269.409994) (xy 121.673862 -269.368398) (xy 121.654571 -269.323122) (xy 121.642794 -269.275338)
			(xy 121.638834 -269.226284) (xy 119.430038 -269.226284) (xy 119.429543 -269.250891) (xy 119.421648 -269.299468)
			(xy 119.406064 -269.346149) (xy 119.383193 -269.389726) (xy 119.353628 -269.42907) (xy 119.318135 -269.463162)
			(xy 119.277632 -269.491118) (xy 119.23317 -269.512216) (xy 119.185899 -269.525908) (xy 119.137044 -269.53184)
			(xy 119.087869 -269.529859) (xy 119.03965 -269.520015) (xy 118.993634 -269.502563) (xy 118.951013 -269.477956)
			(xy 118.912892 -269.446831) (xy 118.880257 -269.409994) (xy 118.853954 -269.368398) (xy 118.834663 -269.323122)
			(xy 118.822886 -269.275338) (xy 118.818926 -269.226284) (xy 116.61013 -269.226284) (xy 116.609635 -269.250891)
			(xy 116.60174 -269.299468) (xy 116.586156 -269.346149) (xy 116.563285 -269.389726) (xy 116.53372 -269.42907)
			(xy 116.498227 -269.463162) (xy 116.457724 -269.491118) (xy 116.413262 -269.512216) (xy 116.365991 -269.525908)
			(xy 116.317136 -269.53184) (xy 116.267961 -269.529859) (xy 116.219742 -269.520015) (xy 116.173726 -269.502563)
			(xy 116.131105 -269.477956) (xy 116.092984 -269.446831) (xy 116.060349 -269.409994) (xy 116.034046 -269.368398)
			(xy 116.014755 -269.323122) (xy 116.002978 -269.275338) (xy 115.999018 -269.226284) (xy 115.670076 -269.226284)
			(xy 115.669581 -269.250891) (xy 115.661686 -269.299468) (xy 115.646102 -269.346149) (xy 115.623231 -269.389726)
			(xy 115.593666 -269.42907) (xy 115.558173 -269.463162) (xy 115.51767 -269.491118) (xy 115.473208 -269.512216)
			(xy 115.425937 -269.525908) (xy 115.377082 -269.53184) (xy 115.327907 -269.529859) (xy 115.279688 -269.520015)
			(xy 115.233672 -269.502563) (xy 115.191051 -269.477956) (xy 115.15293 -269.446831) (xy 115.120295 -269.409994)
			(xy 115.093992 -269.368398) (xy 115.074701 -269.323122) (xy 115.062924 -269.275338) (xy 115.058964 -269.226284)
			(xy 114.730022 -269.226284) (xy 114.729527 -269.250891) (xy 114.721632 -269.299468) (xy 114.706048 -269.346149)
			(xy 114.683177 -269.389726) (xy 114.653612 -269.42907) (xy 114.618119 -269.463162) (xy 114.577616 -269.491118)
			(xy 114.533154 -269.512216) (xy 114.485883 -269.525908) (xy 114.437028 -269.53184) (xy 114.387853 -269.529859)
			(xy 114.339634 -269.520015) (xy 114.293618 -269.502563) (xy 114.250997 -269.477956) (xy 114.212876 -269.446831)
			(xy 114.180241 -269.409994) (xy 114.153938 -269.368398) (xy 114.134647 -269.323122) (xy 114.12287 -269.275338)
			(xy 114.11891 -269.226284) (xy 113.789968 -269.226284) (xy 113.789473 -269.250891) (xy 113.781578 -269.299468)
			(xy 113.765994 -269.346149) (xy 113.743123 -269.389726) (xy 113.713558 -269.42907) (xy 113.678065 -269.463162)
			(xy 113.637562 -269.491118) (xy 113.5931 -269.512216) (xy 113.545829 -269.525908) (xy 113.496974 -269.53184)
			(xy 113.447799 -269.529859) (xy 113.39958 -269.520015) (xy 113.353564 -269.502563) (xy 113.310943 -269.477956)
			(xy 113.272822 -269.446831) (xy 113.240187 -269.409994) (xy 113.213884 -269.368398) (xy 113.194593 -269.323122)
			(xy 113.182816 -269.275338) (xy 113.178856 -269.226284) (xy 110.97641 -269.226284) (xy 110.975915 -269.250891)
			(xy 110.96802 -269.299468) (xy 110.952436 -269.346149) (xy 110.929565 -269.389726) (xy 110.9 -269.42907)
			(xy 110.864507 -269.463162) (xy 110.824004 -269.491118) (xy 110.779542 -269.512216) (xy 110.732271 -269.525908)
			(xy 110.683416 -269.53184) (xy 110.634241 -269.529859) (xy 110.586022 -269.520015) (xy 110.540006 -269.502563)
			(xy 110.497385 -269.477956) (xy 110.459264 -269.446831) (xy 110.426629 -269.409994) (xy 110.400326 -269.368398)
			(xy 110.381035 -269.323122) (xy 110.369258 -269.275338) (xy 110.365298 -269.226284) (xy 110.036356 -269.226284)
			(xy 110.035861 -269.250891) (xy 110.027966 -269.299468) (xy 110.012382 -269.346149) (xy 109.989511 -269.389726)
			(xy 109.959946 -269.42907) (xy 109.924453 -269.463162) (xy 109.88395 -269.491118) (xy 109.839488 -269.512216)
			(xy 109.792217 -269.525908) (xy 109.743362 -269.53184) (xy 109.694187 -269.529859) (xy 109.645968 -269.520015)
			(xy 109.599952 -269.502563) (xy 109.557331 -269.477956) (xy 109.51921 -269.446831) (xy 109.486575 -269.409994)
			(xy 109.460272 -269.368398) (xy 109.440981 -269.323122) (xy 109.429204 -269.275338) (xy 109.425244 -269.226284)
			(xy 109.096302 -269.226284) (xy 109.095807 -269.250891) (xy 109.087912 -269.299468) (xy 109.072328 -269.346149)
			(xy 109.049457 -269.389726) (xy 109.019892 -269.42907) (xy 108.984399 -269.463162) (xy 108.943896 -269.491118)
			(xy 108.899434 -269.512216) (xy 108.852163 -269.525908) (xy 108.803308 -269.53184) (xy 108.754133 -269.529859)
			(xy 108.705914 -269.520015) (xy 108.659898 -269.502563) (xy 108.617277 -269.477956) (xy 108.579156 -269.446831)
			(xy 108.546521 -269.409994) (xy 108.520218 -269.368398) (xy 108.500927 -269.323122) (xy 108.48915 -269.275338)
			(xy 108.48519 -269.226284) (xy 108.156248 -269.226284) (xy 108.155753 -269.250891) (xy 108.147858 -269.299468)
			(xy 108.132274 -269.346149) (xy 108.109403 -269.389726) (xy 108.079838 -269.42907) (xy 108.044345 -269.463162)
			(xy 108.003842 -269.491118) (xy 107.95938 -269.512216) (xy 107.912109 -269.525908) (xy 107.863254 -269.53184)
			(xy 107.814079 -269.529859) (xy 107.76586 -269.520015) (xy 107.719844 -269.502563) (xy 107.677223 -269.477956)
			(xy 107.639102 -269.446831) (xy 107.606467 -269.409994) (xy 107.580164 -269.368398) (xy 107.560873 -269.323122)
			(xy 107.549096 -269.275338) (xy 107.545136 -269.226284) (xy 105.33634 -269.226284) (xy 105.335845 -269.250891)
			(xy 105.32795 -269.299468) (xy 105.312366 -269.346149) (xy 105.289495 -269.389726) (xy 105.25993 -269.42907)
			(xy 105.224437 -269.463162) (xy 105.183934 -269.491118) (xy 105.139472 -269.512216) (xy 105.092201 -269.525908)
			(xy 105.043346 -269.53184) (xy 104.994171 -269.529859) (xy 104.945952 -269.520015) (xy 104.899936 -269.502563)
			(xy 104.857315 -269.477956) (xy 104.819194 -269.446831) (xy 104.786559 -269.409994) (xy 104.760256 -269.368398)
			(xy 104.740965 -269.323122) (xy 104.729188 -269.275338) (xy 104.725228 -269.226284) (xy 102.516432 -269.226284)
			(xy 102.515937 -269.250891) (xy 102.508042 -269.299468) (xy 102.492458 -269.346149) (xy 102.469587 -269.389726)
			(xy 102.440022 -269.42907) (xy 102.404529 -269.463162) (xy 102.364026 -269.491118) (xy 102.319564 -269.512216)
			(xy 102.272293 -269.525908) (xy 102.223438 -269.53184) (xy 102.174263 -269.529859) (xy 102.126044 -269.520015)
			(xy 102.080028 -269.502563) (xy 102.037407 -269.477956) (xy 101.999286 -269.446831) (xy 101.966651 -269.409994)
			(xy 101.940348 -269.368398) (xy 101.921057 -269.323122) (xy 101.90928 -269.275338) (xy 101.90532 -269.226284)
			(xy 99.69627 -269.226284) (xy 99.695775 -269.250891) (xy 99.68788 -269.299468) (xy 99.672296 -269.346149)
			(xy 99.649425 -269.389726) (xy 99.61986 -269.42907) (xy 99.584367 -269.463162) (xy 99.543864 -269.491118)
			(xy 99.499402 -269.512216) (xy 99.452131 -269.525908) (xy 99.403276 -269.53184) (xy 99.354101 -269.529859)
			(xy 99.305882 -269.520015) (xy 99.259866 -269.502563) (xy 99.217245 -269.477956) (xy 99.179124 -269.446831)
			(xy 99.146489 -269.409994) (xy 99.120186 -269.368398) (xy 99.100895 -269.323122) (xy 99.089118 -269.275338)
			(xy 99.085158 -269.226284) (xy 97.2058 -269.226284) (xy 97.2058 -269.740888) (xy 97.205968 -269.746753)
			(xy 97.208668 -269.758169) (xy 97.211134 -269.763494) (xy 97.223326 -269.788132) (xy 97.229676 -269.79626)
			(xy 97.234248 -269.799816) (xy 97.25297 -269.815776) (xy 97.285556 -269.852629) (xy 97.311817 -269.894226)
			(xy 97.331075 -269.939492) (xy 97.342833 -269.98726) (xy 97.346787 -270.03629) (xy 97.675204 -270.03629)
			(xy 97.679164 -269.987236) (xy 97.690941 -269.939452) (xy 97.710232 -269.894176) (xy 97.736535 -269.85258)
			(xy 97.76917 -269.815743) (xy 97.807291 -269.784618) (xy 97.849912 -269.760011) (xy 97.895928 -269.742559)
			(xy 97.944147 -269.732715) (xy 97.993322 -269.730734) (xy 98.042177 -269.736666) (xy 98.089448 -269.750358)
			(xy 98.13391 -269.771456) (xy 98.174413 -269.799412) (xy 98.209906 -269.833504) (xy 98.239471 -269.872848)
			(xy 98.262342 -269.916425) (xy 98.277926 -269.963106) (xy 98.285821 -270.011683) (xy 98.286316 -270.03629)
			(xy 98.615258 -270.03629) (xy 98.619218 -269.987236) (xy 98.630995 -269.939452) (xy 98.650286 -269.894176)
			(xy 98.676589 -269.85258) (xy 98.709224 -269.815743) (xy 98.747345 -269.784618) (xy 98.789966 -269.760011)
			(xy 98.835982 -269.742559) (xy 98.884201 -269.732715) (xy 98.933376 -269.730734) (xy 98.982231 -269.736666)
			(xy 99.029502 -269.750358) (xy 99.073964 -269.771456) (xy 99.114467 -269.799412) (xy 99.14996 -269.833504)
			(xy 99.179525 -269.872848) (xy 99.202396 -269.916425) (xy 99.21798 -269.963106) (xy 99.225875 -270.011683)
			(xy 99.22637 -270.03629) (xy 99.555312 -270.03629) (xy 99.559272 -269.987236) (xy 99.571049 -269.939452)
			(xy 99.59034 -269.894176) (xy 99.616643 -269.85258) (xy 99.649278 -269.815743) (xy 99.687399 -269.784618)
			(xy 99.73002 -269.760011) (xy 99.776036 -269.742559) (xy 99.824255 -269.732715) (xy 99.87343 -269.730734)
			(xy 99.922285 -269.736666) (xy 99.969556 -269.750358) (xy 100.014018 -269.771456) (xy 100.054521 -269.799412)
			(xy 100.090014 -269.833504) (xy 100.119579 -269.872848) (xy 100.14245 -269.916425) (xy 100.158034 -269.963106)
			(xy 100.165929 -270.011683) (xy 100.166424 -270.03629) (xy 100.495366 -270.03629) (xy 100.499326 -269.987236)
			(xy 100.511103 -269.939452) (xy 100.530394 -269.894176) (xy 100.556697 -269.85258) (xy 100.589332 -269.815743)
			(xy 100.627453 -269.784618) (xy 100.670074 -269.760011) (xy 100.71609 -269.742559) (xy 100.764309 -269.732715)
			(xy 100.813484 -269.730734) (xy 100.862339 -269.736666) (xy 100.90961 -269.750358) (xy 100.954072 -269.771456)
			(xy 100.994575 -269.799412) (xy 101.030068 -269.833504) (xy 101.059633 -269.872848) (xy 101.082504 -269.916425)
			(xy 101.098088 -269.963106) (xy 101.105983 -270.011683) (xy 101.106478 -270.03629) (xy 101.435166 -270.03629)
			(xy 101.439126 -269.987236) (xy 101.450903 -269.939452) (xy 101.470194 -269.894176) (xy 101.496497 -269.85258)
			(xy 101.529132 -269.815743) (xy 101.567253 -269.784618) (xy 101.609874 -269.760011) (xy 101.65589 -269.742559)
			(xy 101.704109 -269.732715) (xy 101.753284 -269.730734) (xy 101.802139 -269.736666) (xy 101.84941 -269.750358)
			(xy 101.893872 -269.771456) (xy 101.934375 -269.799412) (xy 101.969868 -269.833504) (xy 101.999433 -269.872848)
			(xy 102.022304 -269.916425) (xy 102.037888 -269.963106) (xy 102.045783 -270.011683) (xy 102.046278 -270.03629)
			(xy 102.37522 -270.03629) (xy 102.37918 -269.987236) (xy 102.390957 -269.939452) (xy 102.410248 -269.894176)
			(xy 102.436551 -269.85258) (xy 102.469186 -269.815743) (xy 102.507307 -269.784618) (xy 102.549928 -269.760011)
			(xy 102.595944 -269.742559) (xy 102.644163 -269.732715) (xy 102.693338 -269.730734) (xy 102.742193 -269.736666)
			(xy 102.789464 -269.750358) (xy 102.833926 -269.771456) (xy 102.874429 -269.799412) (xy 102.909922 -269.833504)
			(xy 102.939487 -269.872848) (xy 102.962358 -269.916425) (xy 102.977942 -269.963106) (xy 102.985837 -270.011683)
			(xy 102.986332 -270.03629) (xy 103.315274 -270.03629) (xy 103.319234 -269.987236) (xy 103.331011 -269.939452)
			(xy 103.350302 -269.894176) (xy 103.376605 -269.85258) (xy 103.40924 -269.815743) (xy 103.447361 -269.784618)
			(xy 103.489982 -269.760011) (xy 103.535998 -269.742559) (xy 103.584217 -269.732715) (xy 103.633392 -269.730734)
			(xy 103.682247 -269.736666) (xy 103.729518 -269.750358) (xy 103.77398 -269.771456) (xy 103.814483 -269.799412)
			(xy 103.849976 -269.833504) (xy 103.879541 -269.872848) (xy 103.902412 -269.916425) (xy 103.917996 -269.963106)
			(xy 103.925891 -270.011683) (xy 103.926386 -270.03629) (xy 104.255328 -270.03629) (xy 104.259288 -269.987236)
			(xy 104.271065 -269.939452) (xy 104.290356 -269.894176) (xy 104.316659 -269.85258) (xy 104.349294 -269.815743)
			(xy 104.387415 -269.784618) (xy 104.430036 -269.760011) (xy 104.476052 -269.742559) (xy 104.524271 -269.732715)
			(xy 104.573446 -269.730734) (xy 104.622301 -269.736666) (xy 104.669572 -269.750358) (xy 104.714034 -269.771456)
			(xy 104.754537 -269.799412) (xy 104.79003 -269.833504) (xy 104.819595 -269.872848) (xy 104.842466 -269.916425)
			(xy 104.85805 -269.963106) (xy 104.865945 -270.011683) (xy 104.86644 -270.03629) (xy 105.195128 -270.03629)
			(xy 105.199088 -269.987236) (xy 105.210865 -269.939452) (xy 105.230156 -269.894176) (xy 105.256459 -269.85258)
			(xy 105.289094 -269.815743) (xy 105.327215 -269.784618) (xy 105.369836 -269.760011) (xy 105.415852 -269.742559)
			(xy 105.464071 -269.732715) (xy 105.513246 -269.730734) (xy 105.562101 -269.736666) (xy 105.609372 -269.750358)
			(xy 105.653834 -269.771456) (xy 105.694337 -269.799412) (xy 105.72983 -269.833504) (xy 105.759395 -269.872848)
			(xy 105.782266 -269.916425) (xy 105.79785 -269.963106) (xy 105.805745 -270.011683) (xy 105.80624 -270.03629)
			(xy 106.135182 -270.03629) (xy 106.139142 -269.987236) (xy 106.150919 -269.939452) (xy 106.17021 -269.894176)
			(xy 106.196513 -269.85258) (xy 106.229148 -269.815743) (xy 106.267269 -269.784618) (xy 106.30989 -269.760011)
			(xy 106.355906 -269.742559) (xy 106.404125 -269.732715) (xy 106.4533 -269.730734) (xy 106.502155 -269.736666)
			(xy 106.549426 -269.750358) (xy 106.593888 -269.771456) (xy 106.634391 -269.799412) (xy 106.669884 -269.833504)
			(xy 106.699449 -269.872848) (xy 106.72232 -269.916425) (xy 106.737904 -269.963106) (xy 106.745799 -270.011683)
			(xy 106.746294 -270.03629) (xy 107.075236 -270.03629) (xy 107.079196 -269.987236) (xy 107.090973 -269.939452)
			(xy 107.110264 -269.894176) (xy 107.136567 -269.85258) (xy 107.169202 -269.815743) (xy 107.207323 -269.784618)
			(xy 107.249944 -269.760011) (xy 107.29596 -269.742559) (xy 107.344179 -269.732715) (xy 107.393354 -269.730734)
			(xy 107.442209 -269.736666) (xy 107.48948 -269.750358) (xy 107.533942 -269.771456) (xy 107.574445 -269.799412)
			(xy 107.609938 -269.833504) (xy 107.639503 -269.872848) (xy 107.662374 -269.916425) (xy 107.677958 -269.963106)
			(xy 107.685853 -270.011683) (xy 107.686348 -270.03629) (xy 108.01529 -270.03629) (xy 108.01925 -269.987236)
			(xy 108.031027 -269.939452) (xy 108.050318 -269.894176) (xy 108.076621 -269.85258) (xy 108.109256 -269.815743)
			(xy 108.147377 -269.784618) (xy 108.189998 -269.760011) (xy 108.236014 -269.742559) (xy 108.284233 -269.732715)
			(xy 108.333408 -269.730734) (xy 108.382263 -269.736666) (xy 108.429534 -269.750358) (xy 108.473996 -269.771456)
			(xy 108.514499 -269.799412) (xy 108.549992 -269.833504) (xy 108.579557 -269.872848) (xy 108.602428 -269.916425)
			(xy 108.618012 -269.963106) (xy 108.625907 -270.011683) (xy 108.626402 -270.03629) (xy 108.955344 -270.03629)
			(xy 108.959304 -269.987236) (xy 108.971081 -269.939452) (xy 108.990372 -269.894176) (xy 109.016675 -269.85258)
			(xy 109.04931 -269.815743) (xy 109.087431 -269.784618) (xy 109.130052 -269.760011) (xy 109.176068 -269.742559)
			(xy 109.224287 -269.732715) (xy 109.273462 -269.730734) (xy 109.322317 -269.736666) (xy 109.369588 -269.750358)
			(xy 109.41405 -269.771456) (xy 109.454553 -269.799412) (xy 109.490046 -269.833504) (xy 109.519611 -269.872848)
			(xy 109.542482 -269.916425) (xy 109.558066 -269.963106) (xy 109.565961 -270.011683) (xy 109.566456 -270.03629)
			(xy 109.895144 -270.03629) (xy 109.899104 -269.987236) (xy 109.910881 -269.939452) (xy 109.930172 -269.894176)
			(xy 109.956475 -269.85258) (xy 109.98911 -269.815743) (xy 110.027231 -269.784618) (xy 110.069852 -269.760011)
			(xy 110.115868 -269.742559) (xy 110.164087 -269.732715) (xy 110.213262 -269.730734) (xy 110.262117 -269.736666)
			(xy 110.309388 -269.750358) (xy 110.35385 -269.771456) (xy 110.394353 -269.799412) (xy 110.429846 -269.833504)
			(xy 110.459411 -269.872848) (xy 110.482282 -269.916425) (xy 110.497866 -269.963106) (xy 110.505761 -270.011683)
			(xy 110.506256 -270.03629) (xy 113.64901 -270.03629) (xy 113.65297 -269.987236) (xy 113.664747 -269.939452)
			(xy 113.684038 -269.894176) (xy 113.710341 -269.85258) (xy 113.742976 -269.815743) (xy 113.781097 -269.784618)
			(xy 113.823718 -269.760011) (xy 113.869734 -269.742559) (xy 113.917953 -269.732715) (xy 113.967128 -269.730734)
			(xy 114.015983 -269.736666) (xy 114.063254 -269.750358) (xy 114.107716 -269.771456) (xy 114.148219 -269.799412)
			(xy 114.183712 -269.833504) (xy 114.213277 -269.872848) (xy 114.236148 -269.916425) (xy 114.251732 -269.963106)
			(xy 114.259627 -270.011683) (xy 114.260122 -270.03629) (xy 114.58881 -270.03629) (xy 114.59277 -269.987236)
			(xy 114.604547 -269.939452) (xy 114.623838 -269.894176) (xy 114.650141 -269.85258) (xy 114.682776 -269.815743)
			(xy 114.720897 -269.784618) (xy 114.763518 -269.760011) (xy 114.809534 -269.742559) (xy 114.857753 -269.732715)
			(xy 114.906928 -269.730734) (xy 114.955783 -269.736666) (xy 115.003054 -269.750358) (xy 115.047516 -269.771456)
			(xy 115.088019 -269.799412) (xy 115.123512 -269.833504) (xy 115.153077 -269.872848) (xy 115.175948 -269.916425)
			(xy 115.191532 -269.963106) (xy 115.199427 -270.011683) (xy 115.199922 -270.03629) (xy 115.528864 -270.03629)
			(xy 115.532824 -269.987236) (xy 115.544601 -269.939452) (xy 115.563892 -269.894176) (xy 115.590195 -269.85258)
			(xy 115.62283 -269.815743) (xy 115.660951 -269.784618) (xy 115.703572 -269.760011) (xy 115.749588 -269.742559)
			(xy 115.797807 -269.732715) (xy 115.846982 -269.730734) (xy 115.895837 -269.736666) (xy 115.943108 -269.750358)
			(xy 115.98757 -269.771456) (xy 116.028073 -269.799412) (xy 116.063566 -269.833504) (xy 116.093131 -269.872848)
			(xy 116.116002 -269.916425) (xy 116.131586 -269.963106) (xy 116.139481 -270.011683) (xy 116.139976 -270.03629)
			(xy 116.468918 -270.03629) (xy 116.472878 -269.987236) (xy 116.484655 -269.939452) (xy 116.503946 -269.894176)
			(xy 116.530249 -269.85258) (xy 116.562884 -269.815743) (xy 116.601005 -269.784618) (xy 116.643626 -269.760011)
			(xy 116.689642 -269.742559) (xy 116.737861 -269.732715) (xy 116.787036 -269.730734) (xy 116.835891 -269.736666)
			(xy 116.883162 -269.750358) (xy 116.927624 -269.771456) (xy 116.968127 -269.799412) (xy 117.00362 -269.833504)
			(xy 117.033185 -269.872848) (xy 117.056056 -269.916425) (xy 117.07164 -269.963106) (xy 117.079535 -270.011683)
			(xy 117.08003 -270.03629) (xy 117.408972 -270.03629) (xy 117.412932 -269.987236) (xy 117.424709 -269.939452)
			(xy 117.444 -269.894176) (xy 117.470303 -269.85258) (xy 117.502938 -269.815743) (xy 117.541059 -269.784618)
			(xy 117.58368 -269.760011) (xy 117.629696 -269.742559) (xy 117.677915 -269.732715) (xy 117.72709 -269.730734)
			(xy 117.775945 -269.736666) (xy 117.823216 -269.750358) (xy 117.867678 -269.771456) (xy 117.908181 -269.799412)
			(xy 117.943674 -269.833504) (xy 117.973239 -269.872848) (xy 117.99611 -269.916425) (xy 118.011694 -269.963106)
			(xy 118.019589 -270.011683) (xy 118.020084 -270.03629) (xy 118.349026 -270.03629) (xy 118.352986 -269.987236)
			(xy 118.364763 -269.939452) (xy 118.384054 -269.894176) (xy 118.410357 -269.85258) (xy 118.442992 -269.815743)
			(xy 118.481113 -269.784618) (xy 118.523734 -269.760011) (xy 118.56975 -269.742559) (xy 118.617969 -269.732715)
			(xy 118.667144 -269.730734) (xy 118.715999 -269.736666) (xy 118.76327 -269.750358) (xy 118.807732 -269.771456)
			(xy 118.848235 -269.799412) (xy 118.883728 -269.833504) (xy 118.913293 -269.872848) (xy 118.936164 -269.916425)
			(xy 118.951748 -269.963106) (xy 118.959643 -270.011683) (xy 118.960138 -270.03629) (xy 119.288826 -270.03629)
			(xy 119.292786 -269.987236) (xy 119.304563 -269.939452) (xy 119.323854 -269.894176) (xy 119.350157 -269.85258)
			(xy 119.382792 -269.815743) (xy 119.420913 -269.784618) (xy 119.463534 -269.760011) (xy 119.50955 -269.742559)
			(xy 119.557769 -269.732715) (xy 119.606944 -269.730734) (xy 119.655799 -269.736666) (xy 119.70307 -269.750358)
			(xy 119.747532 -269.771456) (xy 119.788035 -269.799412) (xy 119.823528 -269.833504) (xy 119.853093 -269.872848)
			(xy 119.875964 -269.916425) (xy 119.891548 -269.963106) (xy 119.899443 -270.011683) (xy 119.899938 -270.03629)
			(xy 120.22888 -270.03629) (xy 120.23284 -269.987236) (xy 120.244617 -269.939452) (xy 120.263908 -269.894176)
			(xy 120.290211 -269.85258) (xy 120.322846 -269.815743) (xy 120.360967 -269.784618) (xy 120.403588 -269.760011)
			(xy 120.449604 -269.742559) (xy 120.497823 -269.732715) (xy 120.546998 -269.730734) (xy 120.595853 -269.736666)
			(xy 120.643124 -269.750358) (xy 120.687586 -269.771456) (xy 120.728089 -269.799412) (xy 120.763582 -269.833504)
			(xy 120.793147 -269.872848) (xy 120.816018 -269.916425) (xy 120.831602 -269.963106) (xy 120.839497 -270.011683)
			(xy 120.839992 -270.03629) (xy 121.168934 -270.03629) (xy 121.172894 -269.987236) (xy 121.184671 -269.939452)
			(xy 121.203962 -269.894176) (xy 121.230265 -269.85258) (xy 121.2629 -269.815743) (xy 121.301021 -269.784618)
			(xy 121.343642 -269.760011) (xy 121.389658 -269.742559) (xy 121.437877 -269.732715) (xy 121.487052 -269.730734)
			(xy 121.535907 -269.736666) (xy 121.583178 -269.750358) (xy 121.62764 -269.771456) (xy 121.668143 -269.799412)
			(xy 121.703636 -269.833504) (xy 121.733201 -269.872848) (xy 121.756072 -269.916425) (xy 121.771656 -269.963106)
			(xy 121.779551 -270.011683) (xy 121.780046 -270.03629) (xy 122.108988 -270.03629) (xy 122.112948 -269.987236)
			(xy 122.124725 -269.939452) (xy 122.144016 -269.894176) (xy 122.170319 -269.85258) (xy 122.202954 -269.815743)
			(xy 122.241075 -269.784618) (xy 122.283696 -269.760011) (xy 122.329712 -269.742559) (xy 122.377931 -269.732715)
			(xy 122.427106 -269.730734) (xy 122.475961 -269.736666) (xy 122.523232 -269.750358) (xy 122.567694 -269.771456)
			(xy 122.608197 -269.799412) (xy 122.64369 -269.833504) (xy 122.673255 -269.872848) (xy 122.696126 -269.916425)
			(xy 122.71171 -269.963106) (xy 122.719605 -270.011683) (xy 122.7201 -270.03629) (xy 123.049042 -270.03629)
			(xy 123.053002 -269.987236) (xy 123.064779 -269.939452) (xy 123.08407 -269.894176) (xy 123.110373 -269.85258)
			(xy 123.143008 -269.815743) (xy 123.181129 -269.784618) (xy 123.22375 -269.760011) (xy 123.269766 -269.742559)
			(xy 123.317985 -269.732715) (xy 123.36716 -269.730734) (xy 123.416015 -269.736666) (xy 123.463286 -269.750358)
			(xy 123.507748 -269.771456) (xy 123.548251 -269.799412) (xy 123.583744 -269.833504) (xy 123.613309 -269.872848)
			(xy 123.63618 -269.916425) (xy 123.651764 -269.963106) (xy 123.659659 -270.011683) (xy 123.660154 -270.03629)
			(xy 123.988842 -270.03629) (xy 123.992802 -269.987236) (xy 124.004579 -269.939452) (xy 124.02387 -269.894176)
			(xy 124.050173 -269.85258) (xy 124.082808 -269.815743) (xy 124.120929 -269.784618) (xy 124.16355 -269.760011)
			(xy 124.209566 -269.742559) (xy 124.257785 -269.732715) (xy 124.30696 -269.730734) (xy 124.355815 -269.736666)
			(xy 124.403086 -269.750358) (xy 124.447548 -269.771456) (xy 124.488051 -269.799412) (xy 124.523544 -269.833504)
			(xy 124.553109 -269.872848) (xy 124.57598 -269.916425) (xy 124.591564 -269.963106) (xy 124.599459 -270.011683)
			(xy 124.599954 -270.03629) (xy 124.928896 -270.03629) (xy 124.932856 -269.987236) (xy 124.944633 -269.939452)
			(xy 124.963924 -269.894176) (xy 124.990227 -269.85258) (xy 125.022862 -269.815743) (xy 125.060983 -269.784618)
			(xy 125.103604 -269.760011) (xy 125.14962 -269.742559) (xy 125.197839 -269.732715) (xy 125.247014 -269.730734)
			(xy 125.295869 -269.736666) (xy 125.34314 -269.750358) (xy 125.387602 -269.771456) (xy 125.428105 -269.799412)
			(xy 125.463598 -269.833504) (xy 125.493163 -269.872848) (xy 125.516034 -269.916425) (xy 125.531618 -269.963106)
			(xy 125.539513 -270.011683) (xy 125.540008 -270.03629) (xy 125.86895 -270.03629) (xy 125.87291 -269.987236)
			(xy 125.884687 -269.939452) (xy 125.903978 -269.894176) (xy 125.930281 -269.85258) (xy 125.962916 -269.815743)
			(xy 126.001037 -269.784618) (xy 126.043658 -269.760011) (xy 126.089674 -269.742559) (xy 126.137893 -269.732715)
			(xy 126.187068 -269.730734) (xy 126.235923 -269.736666) (xy 126.283194 -269.750358) (xy 126.327656 -269.771456)
			(xy 126.368159 -269.799412) (xy 126.403652 -269.833504) (xy 126.433217 -269.872848) (xy 126.456088 -269.916425)
			(xy 126.471672 -269.963106) (xy 126.479567 -270.011683) (xy 126.480062 -270.03629) (xy 126.479567 -270.060897)
			(xy 126.471672 -270.109474) (xy 126.456088 -270.156155) (xy 126.433217 -270.199732) (xy 126.403652 -270.239076)
			(xy 126.368159 -270.273168) (xy 126.327656 -270.301124) (xy 126.283194 -270.322222) (xy 126.235923 -270.335914)
			(xy 126.187068 -270.341846) (xy 126.137893 -270.339865) (xy 126.089674 -270.330021) (xy 126.043658 -270.312569)
			(xy 126.001037 -270.287962) (xy 125.962916 -270.256837) (xy 125.930281 -270.22) (xy 125.903978 -270.178404)
			(xy 125.884687 -270.133128) (xy 125.87291 -270.085344) (xy 125.86895 -270.03629) (xy 125.540008 -270.03629)
			(xy 125.539513 -270.060897) (xy 125.531618 -270.109474) (xy 125.516034 -270.156155) (xy 125.493163 -270.199732)
			(xy 125.463598 -270.239076) (xy 125.428105 -270.273168) (xy 125.387602 -270.301124) (xy 125.34314 -270.322222)
			(xy 125.295869 -270.335914) (xy 125.247014 -270.341846) (xy 125.197839 -270.339865) (xy 125.14962 -270.330021)
			(xy 125.103604 -270.312569) (xy 125.060983 -270.287962) (xy 125.022862 -270.256837) (xy 124.990227 -270.22)
			(xy 124.963924 -270.178404) (xy 124.944633 -270.133128) (xy 124.932856 -270.085344) (xy 124.928896 -270.03629)
			(xy 124.599954 -270.03629) (xy 124.599459 -270.060897) (xy 124.591564 -270.109474) (xy 124.57598 -270.156155)
			(xy 124.553109 -270.199732) (xy 124.523544 -270.239076) (xy 124.488051 -270.273168) (xy 124.447548 -270.301124)
			(xy 124.403086 -270.322222) (xy 124.355815 -270.335914) (xy 124.30696 -270.341846) (xy 124.257785 -270.339865)
			(xy 124.209566 -270.330021) (xy 124.16355 -270.312569) (xy 124.120929 -270.287962) (xy 124.082808 -270.256837)
			(xy 124.050173 -270.22) (xy 124.02387 -270.178404) (xy 124.004579 -270.133128) (xy 123.992802 -270.085344)
			(xy 123.988842 -270.03629) (xy 123.660154 -270.03629) (xy 123.659659 -270.060897) (xy 123.651764 -270.109474)
			(xy 123.63618 -270.156155) (xy 123.613309 -270.199732) (xy 123.583744 -270.239076) (xy 123.548251 -270.273168)
			(xy 123.507748 -270.301124) (xy 123.463286 -270.322222) (xy 123.416015 -270.335914) (xy 123.36716 -270.341846)
			(xy 123.317985 -270.339865) (xy 123.269766 -270.330021) (xy 123.22375 -270.312569) (xy 123.181129 -270.287962)
			(xy 123.143008 -270.256837) (xy 123.110373 -270.22) (xy 123.08407 -270.178404) (xy 123.064779 -270.133128)
			(xy 123.053002 -270.085344) (xy 123.049042 -270.03629) (xy 122.7201 -270.03629) (xy 122.719605 -270.060897)
			(xy 122.71171 -270.109474) (xy 122.696126 -270.156155) (xy 122.673255 -270.199732) (xy 122.64369 -270.239076)
			(xy 122.608197 -270.273168) (xy 122.567694 -270.301124) (xy 122.523232 -270.322222) (xy 122.475961 -270.335914)
			(xy 122.427106 -270.341846) (xy 122.377931 -270.339865) (xy 122.329712 -270.330021) (xy 122.283696 -270.312569)
			(xy 122.241075 -270.287962) (xy 122.202954 -270.256837) (xy 122.170319 -270.22) (xy 122.144016 -270.178404)
			(xy 122.124725 -270.133128) (xy 122.112948 -270.085344) (xy 122.108988 -270.03629) (xy 121.780046 -270.03629)
			(xy 121.779551 -270.060897) (xy 121.771656 -270.109474) (xy 121.756072 -270.156155) (xy 121.733201 -270.199732)
			(xy 121.703636 -270.239076) (xy 121.668143 -270.273168) (xy 121.62764 -270.301124) (xy 121.583178 -270.322222)
			(xy 121.535907 -270.335914) (xy 121.487052 -270.341846) (xy 121.437877 -270.339865) (xy 121.389658 -270.330021)
			(xy 121.343642 -270.312569) (xy 121.301021 -270.287962) (xy 121.2629 -270.256837) (xy 121.230265 -270.22)
			(xy 121.203962 -270.178404) (xy 121.184671 -270.133128) (xy 121.172894 -270.085344) (xy 121.168934 -270.03629)
			(xy 120.839992 -270.03629) (xy 120.839497 -270.060897) (xy 120.831602 -270.109474) (xy 120.816018 -270.156155)
			(xy 120.793147 -270.199732) (xy 120.763582 -270.239076) (xy 120.728089 -270.273168) (xy 120.687586 -270.301124)
			(xy 120.643124 -270.322222) (xy 120.595853 -270.335914) (xy 120.546998 -270.341846) (xy 120.497823 -270.339865)
			(xy 120.449604 -270.330021) (xy 120.403588 -270.312569) (xy 120.360967 -270.287962) (xy 120.322846 -270.256837)
			(xy 120.290211 -270.22) (xy 120.263908 -270.178404) (xy 120.244617 -270.133128) (xy 120.23284 -270.085344)
			(xy 120.22888 -270.03629) (xy 119.899938 -270.03629) (xy 119.899443 -270.060897) (xy 119.891548 -270.109474)
			(xy 119.875964 -270.156155) (xy 119.853093 -270.199732) (xy 119.823528 -270.239076) (xy 119.788035 -270.273168)
			(xy 119.747532 -270.301124) (xy 119.70307 -270.322222) (xy 119.655799 -270.335914) (xy 119.606944 -270.341846)
			(xy 119.557769 -270.339865) (xy 119.50955 -270.330021) (xy 119.463534 -270.312569) (xy 119.420913 -270.287962)
			(xy 119.382792 -270.256837) (xy 119.350157 -270.22) (xy 119.323854 -270.178404) (xy 119.304563 -270.133128)
			(xy 119.292786 -270.085344) (xy 119.288826 -270.03629) (xy 118.960138 -270.03629) (xy 118.959643 -270.060897)
			(xy 118.951748 -270.109474) (xy 118.936164 -270.156155) (xy 118.913293 -270.199732) (xy 118.883728 -270.239076)
			(xy 118.848235 -270.273168) (xy 118.807732 -270.301124) (xy 118.76327 -270.322222) (xy 118.715999 -270.335914)
			(xy 118.667144 -270.341846) (xy 118.617969 -270.339865) (xy 118.56975 -270.330021) (xy 118.523734 -270.312569)
			(xy 118.481113 -270.287962) (xy 118.442992 -270.256837) (xy 118.410357 -270.22) (xy 118.384054 -270.178404)
			(xy 118.364763 -270.133128) (xy 118.352986 -270.085344) (xy 118.349026 -270.03629) (xy 118.020084 -270.03629)
			(xy 118.019589 -270.060897) (xy 118.011694 -270.109474) (xy 117.99611 -270.156155) (xy 117.973239 -270.199732)
			(xy 117.943674 -270.239076) (xy 117.908181 -270.273168) (xy 117.867678 -270.301124) (xy 117.823216 -270.322222)
			(xy 117.775945 -270.335914) (xy 117.72709 -270.341846) (xy 117.677915 -270.339865) (xy 117.629696 -270.330021)
			(xy 117.58368 -270.312569) (xy 117.541059 -270.287962) (xy 117.502938 -270.256837) (xy 117.470303 -270.22)
			(xy 117.444 -270.178404) (xy 117.424709 -270.133128) (xy 117.412932 -270.085344) (xy 117.408972 -270.03629)
			(xy 117.08003 -270.03629) (xy 117.079535 -270.060897) (xy 117.07164 -270.109474) (xy 117.056056 -270.156155)
			(xy 117.033185 -270.199732) (xy 117.00362 -270.239076) (xy 116.968127 -270.273168) (xy 116.927624 -270.301124)
			(xy 116.883162 -270.322222) (xy 116.835891 -270.335914) (xy 116.787036 -270.341846) (xy 116.737861 -270.339865)
			(xy 116.689642 -270.330021) (xy 116.643626 -270.312569) (xy 116.601005 -270.287962) (xy 116.562884 -270.256837)
			(xy 116.530249 -270.22) (xy 116.503946 -270.178404) (xy 116.484655 -270.133128) (xy 116.472878 -270.085344)
			(xy 116.468918 -270.03629) (xy 116.139976 -270.03629) (xy 116.139481 -270.060897) (xy 116.131586 -270.109474)
			(xy 116.116002 -270.156155) (xy 116.093131 -270.199732) (xy 116.063566 -270.239076) (xy 116.028073 -270.273168)
			(xy 115.98757 -270.301124) (xy 115.943108 -270.322222) (xy 115.895837 -270.335914) (xy 115.846982 -270.341846)
			(xy 115.797807 -270.339865) (xy 115.749588 -270.330021) (xy 115.703572 -270.312569) (xy 115.660951 -270.287962)
			(xy 115.62283 -270.256837) (xy 115.590195 -270.22) (xy 115.563892 -270.178404) (xy 115.544601 -270.133128)
			(xy 115.532824 -270.085344) (xy 115.528864 -270.03629) (xy 115.199922 -270.03629) (xy 115.199427 -270.060897)
			(xy 115.191532 -270.109474) (xy 115.175948 -270.156155) (xy 115.153077 -270.199732) (xy 115.123512 -270.239076)
			(xy 115.088019 -270.273168) (xy 115.047516 -270.301124) (xy 115.003054 -270.322222) (xy 114.955783 -270.335914)
			(xy 114.906928 -270.341846) (xy 114.857753 -270.339865) (xy 114.809534 -270.330021) (xy 114.763518 -270.312569)
			(xy 114.720897 -270.287962) (xy 114.682776 -270.256837) (xy 114.650141 -270.22) (xy 114.623838 -270.178404)
			(xy 114.604547 -270.133128) (xy 114.59277 -270.085344) (xy 114.58881 -270.03629) (xy 114.260122 -270.03629)
			(xy 114.259627 -270.060897) (xy 114.251732 -270.109474) (xy 114.236148 -270.156155) (xy 114.213277 -270.199732)
			(xy 114.183712 -270.239076) (xy 114.148219 -270.273168) (xy 114.107716 -270.301124) (xy 114.063254 -270.322222)
			(xy 114.015983 -270.335914) (xy 113.967128 -270.341846) (xy 113.917953 -270.339865) (xy 113.869734 -270.330021)
			(xy 113.823718 -270.312569) (xy 113.781097 -270.287962) (xy 113.742976 -270.256837) (xy 113.710341 -270.22)
			(xy 113.684038 -270.178404) (xy 113.664747 -270.133128) (xy 113.65297 -270.085344) (xy 113.64901 -270.03629)
			(xy 110.506256 -270.03629) (xy 110.505761 -270.060897) (xy 110.497866 -270.109474) (xy 110.482282 -270.156155)
			(xy 110.459411 -270.199732) (xy 110.429846 -270.239076) (xy 110.394353 -270.273168) (xy 110.35385 -270.301124)
			(xy 110.309388 -270.322222) (xy 110.262117 -270.335914) (xy 110.213262 -270.341846) (xy 110.164087 -270.339865)
			(xy 110.115868 -270.330021) (xy 110.069852 -270.312569) (xy 110.027231 -270.287962) (xy 109.98911 -270.256837)
			(xy 109.956475 -270.22) (xy 109.930172 -270.178404) (xy 109.910881 -270.133128) (xy 109.899104 -270.085344)
			(xy 109.895144 -270.03629) (xy 109.566456 -270.03629) (xy 109.565961 -270.060897) (xy 109.558066 -270.109474)
			(xy 109.542482 -270.156155) (xy 109.519611 -270.199732) (xy 109.490046 -270.239076) (xy 109.454553 -270.273168)
			(xy 109.41405 -270.301124) (xy 109.369588 -270.322222) (xy 109.322317 -270.335914) (xy 109.273462 -270.341846)
			(xy 109.224287 -270.339865) (xy 109.176068 -270.330021) (xy 109.130052 -270.312569) (xy 109.087431 -270.287962)
			(xy 109.04931 -270.256837) (xy 109.016675 -270.22) (xy 108.990372 -270.178404) (xy 108.971081 -270.133128)
			(xy 108.959304 -270.085344) (xy 108.955344 -270.03629) (xy 108.626402 -270.03629) (xy 108.625907 -270.060897)
			(xy 108.618012 -270.109474) (xy 108.602428 -270.156155) (xy 108.579557 -270.199732) (xy 108.549992 -270.239076)
			(xy 108.514499 -270.273168) (xy 108.473996 -270.301124) (xy 108.429534 -270.322222) (xy 108.382263 -270.335914)
			(xy 108.333408 -270.341846) (xy 108.284233 -270.339865) (xy 108.236014 -270.330021) (xy 108.189998 -270.312569)
			(xy 108.147377 -270.287962) (xy 108.109256 -270.256837) (xy 108.076621 -270.22) (xy 108.050318 -270.178404)
			(xy 108.031027 -270.133128) (xy 108.01925 -270.085344) (xy 108.01529 -270.03629) (xy 107.686348 -270.03629)
			(xy 107.685853 -270.060897) (xy 107.677958 -270.109474) (xy 107.662374 -270.156155) (xy 107.639503 -270.199732)
			(xy 107.609938 -270.239076) (xy 107.574445 -270.273168) (xy 107.533942 -270.301124) (xy 107.48948 -270.322222)
			(xy 107.442209 -270.335914) (xy 107.393354 -270.341846) (xy 107.344179 -270.339865) (xy 107.29596 -270.330021)
			(xy 107.249944 -270.312569) (xy 107.207323 -270.287962) (xy 107.169202 -270.256837) (xy 107.136567 -270.22)
			(xy 107.110264 -270.178404) (xy 107.090973 -270.133128) (xy 107.079196 -270.085344) (xy 107.075236 -270.03629)
			(xy 106.746294 -270.03629) (xy 106.745799 -270.060897) (xy 106.737904 -270.109474) (xy 106.72232 -270.156155)
			(xy 106.699449 -270.199732) (xy 106.669884 -270.239076) (xy 106.634391 -270.273168) (xy 106.593888 -270.301124)
			(xy 106.549426 -270.322222) (xy 106.502155 -270.335914) (xy 106.4533 -270.341846) (xy 106.404125 -270.339865)
			(xy 106.355906 -270.330021) (xy 106.30989 -270.312569) (xy 106.267269 -270.287962) (xy 106.229148 -270.256837)
			(xy 106.196513 -270.22) (xy 106.17021 -270.178404) (xy 106.150919 -270.133128) (xy 106.139142 -270.085344)
			(xy 106.135182 -270.03629) (xy 105.80624 -270.03629) (xy 105.805745 -270.060897) (xy 105.79785 -270.109474)
			(xy 105.782266 -270.156155) (xy 105.759395 -270.199732) (xy 105.72983 -270.239076) (xy 105.694337 -270.273168)
			(xy 105.653834 -270.301124) (xy 105.609372 -270.322222) (xy 105.562101 -270.335914) (xy 105.513246 -270.341846)
			(xy 105.464071 -270.339865) (xy 105.415852 -270.330021) (xy 105.369836 -270.312569) (xy 105.327215 -270.287962)
			(xy 105.289094 -270.256837) (xy 105.256459 -270.22) (xy 105.230156 -270.178404) (xy 105.210865 -270.133128)
			(xy 105.199088 -270.085344) (xy 105.195128 -270.03629) (xy 104.86644 -270.03629) (xy 104.865945 -270.060897)
			(xy 104.85805 -270.109474) (xy 104.842466 -270.156155) (xy 104.819595 -270.199732) (xy 104.79003 -270.239076)
			(xy 104.754537 -270.273168) (xy 104.714034 -270.301124) (xy 104.669572 -270.322222) (xy 104.622301 -270.335914)
			(xy 104.573446 -270.341846) (xy 104.524271 -270.339865) (xy 104.476052 -270.330021) (xy 104.430036 -270.312569)
			(xy 104.387415 -270.287962) (xy 104.349294 -270.256837) (xy 104.316659 -270.22) (xy 104.290356 -270.178404)
			(xy 104.271065 -270.133128) (xy 104.259288 -270.085344) (xy 104.255328 -270.03629) (xy 103.926386 -270.03629)
			(xy 103.925891 -270.060897) (xy 103.917996 -270.109474) (xy 103.902412 -270.156155) (xy 103.879541 -270.199732)
			(xy 103.849976 -270.239076) (xy 103.814483 -270.273168) (xy 103.77398 -270.301124) (xy 103.729518 -270.322222)
			(xy 103.682247 -270.335914) (xy 103.633392 -270.341846) (xy 103.584217 -270.339865) (xy 103.535998 -270.330021)
			(xy 103.489982 -270.312569) (xy 103.447361 -270.287962) (xy 103.40924 -270.256837) (xy 103.376605 -270.22)
			(xy 103.350302 -270.178404) (xy 103.331011 -270.133128) (xy 103.319234 -270.085344) (xy 103.315274 -270.03629)
			(xy 102.986332 -270.03629) (xy 102.985837 -270.060897) (xy 102.977942 -270.109474) (xy 102.962358 -270.156155)
			(xy 102.939487 -270.199732) (xy 102.909922 -270.239076) (xy 102.874429 -270.273168) (xy 102.833926 -270.301124)
			(xy 102.789464 -270.322222) (xy 102.742193 -270.335914) (xy 102.693338 -270.341846) (xy 102.644163 -270.339865)
			(xy 102.595944 -270.330021) (xy 102.549928 -270.312569) (xy 102.507307 -270.287962) (xy 102.469186 -270.256837)
			(xy 102.436551 -270.22) (xy 102.410248 -270.178404) (xy 102.390957 -270.133128) (xy 102.37918 -270.085344)
			(xy 102.37522 -270.03629) (xy 102.046278 -270.03629) (xy 102.045783 -270.060897) (xy 102.037888 -270.109474)
			(xy 102.022304 -270.156155) (xy 101.999433 -270.199732) (xy 101.969868 -270.239076) (xy 101.934375 -270.273168)
			(xy 101.893872 -270.301124) (xy 101.84941 -270.322222) (xy 101.802139 -270.335914) (xy 101.753284 -270.341846)
			(xy 101.704109 -270.339865) (xy 101.65589 -270.330021) (xy 101.609874 -270.312569) (xy 101.567253 -270.287962)
			(xy 101.529132 -270.256837) (xy 101.496497 -270.22) (xy 101.470194 -270.178404) (xy 101.450903 -270.133128)
			(xy 101.439126 -270.085344) (xy 101.435166 -270.03629) (xy 101.106478 -270.03629) (xy 101.105983 -270.060897)
			(xy 101.098088 -270.109474) (xy 101.082504 -270.156155) (xy 101.059633 -270.199732) (xy 101.030068 -270.239076)
			(xy 100.994575 -270.273168) (xy 100.954072 -270.301124) (xy 100.90961 -270.322222) (xy 100.862339 -270.335914)
			(xy 100.813484 -270.341846) (xy 100.764309 -270.339865) (xy 100.71609 -270.330021) (xy 100.670074 -270.312569)
			(xy 100.627453 -270.287962) (xy 100.589332 -270.256837) (xy 100.556697 -270.22) (xy 100.530394 -270.178404)
			(xy 100.511103 -270.133128) (xy 100.499326 -270.085344) (xy 100.495366 -270.03629) (xy 100.166424 -270.03629)
			(xy 100.165929 -270.060897) (xy 100.158034 -270.109474) (xy 100.14245 -270.156155) (xy 100.119579 -270.199732)
			(xy 100.090014 -270.239076) (xy 100.054521 -270.273168) (xy 100.014018 -270.301124) (xy 99.969556 -270.322222)
			(xy 99.922285 -270.335914) (xy 99.87343 -270.341846) (xy 99.824255 -270.339865) (xy 99.776036 -270.330021)
			(xy 99.73002 -270.312569) (xy 99.687399 -270.287962) (xy 99.649278 -270.256837) (xy 99.616643 -270.22)
			(xy 99.59034 -270.178404) (xy 99.571049 -270.133128) (xy 99.559272 -270.085344) (xy 99.555312 -270.03629)
			(xy 99.22637 -270.03629) (xy 99.225875 -270.060897) (xy 99.21798 -270.109474) (xy 99.202396 -270.156155)
			(xy 99.179525 -270.199732) (xy 99.14996 -270.239076) (xy 99.114467 -270.273168) (xy 99.073964 -270.301124)
			(xy 99.029502 -270.322222) (xy 98.982231 -270.335914) (xy 98.933376 -270.341846) (xy 98.884201 -270.339865)
			(xy 98.835982 -270.330021) (xy 98.789966 -270.312569) (xy 98.747345 -270.287962) (xy 98.709224 -270.256837)
			(xy 98.676589 -270.22) (xy 98.650286 -270.178404) (xy 98.630995 -270.133128) (xy 98.619218 -270.085344)
			(xy 98.615258 -270.03629) (xy 98.286316 -270.03629) (xy 98.285821 -270.060897) (xy 98.277926 -270.109474)
			(xy 98.262342 -270.156155) (xy 98.239471 -270.199732) (xy 98.209906 -270.239076) (xy 98.174413 -270.273168)
			(xy 98.13391 -270.301124) (xy 98.089448 -270.322222) (xy 98.042177 -270.335914) (xy 97.993322 -270.341846)
			(xy 97.944147 -270.339865) (xy 97.895928 -270.330021) (xy 97.849912 -270.312569) (xy 97.807291 -270.287962)
			(xy 97.76917 -270.256837) (xy 97.736535 -270.22) (xy 97.710232 -270.178404) (xy 97.690941 -270.133128)
			(xy 97.679164 -270.085344) (xy 97.675204 -270.03629) (xy 97.346787 -270.03629) (xy 97.346787 -270.036294)
			(xy 97.342835 -270.085328) (xy 97.331079 -270.133095) (xy 97.311823 -270.178363) (xy 97.285563 -270.219961)
			(xy 97.252979 -270.256815) (xy 97.234248 -270.272764) (xy 97.229676 -270.27632) (xy 97.223326 -270.284448)
			(xy 97.211134 -270.309086) (xy 97.208677 -270.314413) (xy 97.205992 -270.325829) (xy 97.2058 -270.331692)
			(xy 97.2058 -270.493998) (xy 97.206141 -270.502885) (xy 97.212236 -270.519582) (xy 97.223687 -270.533176)
			(xy 97.2312 -270.53794) (xy 97.319338 -270.588994) (xy 97.346516 -270.58874) (xy 97.358454 -270.581882)
			(xy 97.381755 -270.569088) (xy 97.431691 -270.550878) (xy 97.484025 -270.541589) (xy 97.5106 -270.540988)
			(xy 97.51695 -270.540988) (xy 97.541889 -270.541962) (xy 97.590966 -270.551019) (xy 97.637917 -270.567935)
			(xy 97.681493 -270.592261) (xy 97.720533 -270.623349) (xy 97.753999 -270.660371) (xy 97.780999 -270.702342)
			(xy 97.800816 -270.748145) (xy 97.81292 -270.79656) (xy 97.816992 -270.846296) (xy 98.145358 -270.846296)
			(xy 98.149318 -270.797242) (xy 98.161095 -270.749458) (xy 98.180386 -270.704182) (xy 98.206689 -270.662586)
			(xy 98.239324 -270.625749) (xy 98.277445 -270.594624) (xy 98.320066 -270.570017) (xy 98.366082 -270.552565)
			(xy 98.414301 -270.542721) (xy 98.463476 -270.54074) (xy 98.512331 -270.546672) (xy 98.559602 -270.560364)
			(xy 98.604064 -270.581462) (xy 98.644567 -270.609418) (xy 98.68006 -270.64351) (xy 98.709625 -270.682854)
			(xy 98.732496 -270.726431) (xy 98.74808 -270.773112) (xy 98.755975 -270.821689) (xy 98.75647 -270.846296)
			(xy 99.085158 -270.846296) (xy 99.089118 -270.797242) (xy 99.100895 -270.749458) (xy 99.120186 -270.704182)
			(xy 99.146489 -270.662586) (xy 99.179124 -270.625749) (xy 99.217245 -270.594624) (xy 99.259866 -270.570017)
			(xy 99.305882 -270.552565) (xy 99.354101 -270.542721) (xy 99.403276 -270.54074) (xy 99.452131 -270.546672)
			(xy 99.499402 -270.560364) (xy 99.543864 -270.581462) (xy 99.584367 -270.609418) (xy 99.61986 -270.64351)
			(xy 99.649425 -270.682854) (xy 99.672296 -270.726431) (xy 99.68788 -270.773112) (xy 99.695775 -270.821689)
			(xy 99.69627 -270.846296) (xy 100.025212 -270.846296) (xy 100.029172 -270.797242) (xy 100.040949 -270.749458)
			(xy 100.06024 -270.704182) (xy 100.086543 -270.662586) (xy 100.119178 -270.625749) (xy 100.157299 -270.594624)
			(xy 100.19992 -270.570017) (xy 100.245936 -270.552565) (xy 100.294155 -270.542721) (xy 100.34333 -270.54074)
			(xy 100.392185 -270.546672) (xy 100.439456 -270.560364) (xy 100.483918 -270.581462) (xy 100.524421 -270.609418)
			(xy 100.559914 -270.64351) (xy 100.589479 -270.682854) (xy 100.61235 -270.726431) (xy 100.627934 -270.773112)
			(xy 100.635829 -270.821689) (xy 100.636324 -270.846296) (xy 100.965266 -270.846296) (xy 100.969226 -270.797242)
			(xy 100.981003 -270.749458) (xy 101.000294 -270.704182) (xy 101.026597 -270.662586) (xy 101.059232 -270.625749)
			(xy 101.097353 -270.594624) (xy 101.139974 -270.570017) (xy 101.18599 -270.552565) (xy 101.234209 -270.542721)
			(xy 101.283384 -270.54074) (xy 101.332239 -270.546672) (xy 101.37951 -270.560364) (xy 101.423972 -270.581462)
			(xy 101.464475 -270.609418) (xy 101.499968 -270.64351) (xy 101.529533 -270.682854) (xy 101.552404 -270.726431)
			(xy 101.567988 -270.773112) (xy 101.575883 -270.821689) (xy 101.576378 -270.846296) (xy 101.90532 -270.846296)
			(xy 101.90928 -270.797242) (xy 101.921057 -270.749458) (xy 101.940348 -270.704182) (xy 101.966651 -270.662586)
			(xy 101.999286 -270.625749) (xy 102.037407 -270.594624) (xy 102.080028 -270.570017) (xy 102.126044 -270.552565)
			(xy 102.174263 -270.542721) (xy 102.223438 -270.54074) (xy 102.272293 -270.546672) (xy 102.319564 -270.560364)
			(xy 102.364026 -270.581462) (xy 102.404529 -270.609418) (xy 102.440022 -270.64351) (xy 102.469587 -270.682854)
			(xy 102.492458 -270.726431) (xy 102.508042 -270.773112) (xy 102.515937 -270.821689) (xy 102.516432 -270.846296)
			(xy 102.845374 -270.846296) (xy 102.849334 -270.797242) (xy 102.861111 -270.749458) (xy 102.880402 -270.704182)
			(xy 102.906705 -270.662586) (xy 102.93934 -270.625749) (xy 102.977461 -270.594624) (xy 103.020082 -270.570017)
			(xy 103.066098 -270.552565) (xy 103.114317 -270.542721) (xy 103.163492 -270.54074) (xy 103.212347 -270.546672)
			(xy 103.259618 -270.560364) (xy 103.30408 -270.581462) (xy 103.344583 -270.609418) (xy 103.380076 -270.64351)
			(xy 103.409641 -270.682854) (xy 103.432512 -270.726431) (xy 103.448096 -270.773112) (xy 103.455991 -270.821689)
			(xy 103.456486 -270.846296) (xy 103.785174 -270.846296) (xy 103.789134 -270.797242) (xy 103.800911 -270.749458)
			(xy 103.820202 -270.704182) (xy 103.846505 -270.662586) (xy 103.87914 -270.625749) (xy 103.917261 -270.594624)
			(xy 103.959882 -270.570017) (xy 104.005898 -270.552565) (xy 104.054117 -270.542721) (xy 104.103292 -270.54074)
			(xy 104.152147 -270.546672) (xy 104.199418 -270.560364) (xy 104.24388 -270.581462) (xy 104.284383 -270.609418)
			(xy 104.319876 -270.64351) (xy 104.349441 -270.682854) (xy 104.372312 -270.726431) (xy 104.387896 -270.773112)
			(xy 104.395791 -270.821689) (xy 104.396286 -270.846296) (xy 104.725228 -270.846296) (xy 104.729188 -270.797242)
			(xy 104.740965 -270.749458) (xy 104.760256 -270.704182) (xy 104.786559 -270.662586) (xy 104.819194 -270.625749)
			(xy 104.857315 -270.594624) (xy 104.899936 -270.570017) (xy 104.945952 -270.552565) (xy 104.994171 -270.542721)
			(xy 105.043346 -270.54074) (xy 105.092201 -270.546672) (xy 105.139472 -270.560364) (xy 105.183934 -270.581462)
			(xy 105.224437 -270.609418) (xy 105.25993 -270.64351) (xy 105.289495 -270.682854) (xy 105.312366 -270.726431)
			(xy 105.32795 -270.773112) (xy 105.335845 -270.821689) (xy 105.33634 -270.846296) (xy 105.665282 -270.846296)
			(xy 105.669242 -270.797242) (xy 105.681019 -270.749458) (xy 105.70031 -270.704182) (xy 105.726613 -270.662586)
			(xy 105.759248 -270.625749) (xy 105.797369 -270.594624) (xy 105.83999 -270.570017) (xy 105.886006 -270.552565)
			(xy 105.934225 -270.542721) (xy 105.9834 -270.54074) (xy 106.032255 -270.546672) (xy 106.079526 -270.560364)
			(xy 106.123988 -270.581462) (xy 106.164491 -270.609418) (xy 106.199984 -270.64351) (xy 106.229549 -270.682854)
			(xy 106.25242 -270.726431) (xy 106.268004 -270.773112) (xy 106.275899 -270.821689) (xy 106.276394 -270.846296)
			(xy 106.605336 -270.846296) (xy 106.609296 -270.797242) (xy 106.621073 -270.749458) (xy 106.640364 -270.704182)
			(xy 106.666667 -270.662586) (xy 106.699302 -270.625749) (xy 106.737423 -270.594624) (xy 106.780044 -270.570017)
			(xy 106.82606 -270.552565) (xy 106.874279 -270.542721) (xy 106.923454 -270.54074) (xy 106.972309 -270.546672)
			(xy 107.01958 -270.560364) (xy 107.064042 -270.581462) (xy 107.104545 -270.609418) (xy 107.140038 -270.64351)
			(xy 107.169603 -270.682854) (xy 107.192474 -270.726431) (xy 107.208058 -270.773112) (xy 107.215953 -270.821689)
			(xy 107.216448 -270.846296) (xy 107.545136 -270.846296) (xy 107.549096 -270.797242) (xy 107.560873 -270.749458)
			(xy 107.580164 -270.704182) (xy 107.606467 -270.662586) (xy 107.639102 -270.625749) (xy 107.677223 -270.594624)
			(xy 107.719844 -270.570017) (xy 107.76586 -270.552565) (xy 107.814079 -270.542721) (xy 107.863254 -270.54074)
			(xy 107.912109 -270.546672) (xy 107.95938 -270.560364) (xy 108.003842 -270.581462) (xy 108.044345 -270.609418)
			(xy 108.079838 -270.64351) (xy 108.109403 -270.682854) (xy 108.132274 -270.726431) (xy 108.147858 -270.773112)
			(xy 108.155753 -270.821689) (xy 108.156248 -270.846296) (xy 108.48519 -270.846296) (xy 108.48915 -270.797242)
			(xy 108.500927 -270.749458) (xy 108.520218 -270.704182) (xy 108.546521 -270.662586) (xy 108.579156 -270.625749)
			(xy 108.617277 -270.594624) (xy 108.659898 -270.570017) (xy 108.705914 -270.552565) (xy 108.754133 -270.542721)
			(xy 108.803308 -270.54074) (xy 108.852163 -270.546672) (xy 108.899434 -270.560364) (xy 108.943896 -270.581462)
			(xy 108.984399 -270.609418) (xy 109.019892 -270.64351) (xy 109.049457 -270.682854) (xy 109.072328 -270.726431)
			(xy 109.087912 -270.773112) (xy 109.095807 -270.821689) (xy 109.096302 -270.846296) (xy 109.425244 -270.846296)
			(xy 109.429204 -270.797242) (xy 109.440981 -270.749458) (xy 109.460272 -270.704182) (xy 109.486575 -270.662586)
			(xy 109.51921 -270.625749) (xy 109.557331 -270.594624) (xy 109.599952 -270.570017) (xy 109.645968 -270.552565)
			(xy 109.694187 -270.542721) (xy 109.743362 -270.54074) (xy 109.792217 -270.546672) (xy 109.839488 -270.560364)
			(xy 109.88395 -270.581462) (xy 109.924453 -270.609418) (xy 109.959946 -270.64351) (xy 109.989511 -270.682854)
			(xy 110.012382 -270.726431) (xy 110.027966 -270.773112) (xy 110.035861 -270.821689) (xy 110.036356 -270.846296)
			(xy 110.365298 -270.846296) (xy 110.369258 -270.797242) (xy 110.381035 -270.749458) (xy 110.400326 -270.704182)
			(xy 110.426629 -270.662586) (xy 110.459264 -270.625749) (xy 110.497385 -270.594624) (xy 110.540006 -270.570017)
			(xy 110.586022 -270.552565) (xy 110.634241 -270.542721) (xy 110.683416 -270.54074) (xy 110.732271 -270.546672)
			(xy 110.779542 -270.560364) (xy 110.824004 -270.581462) (xy 110.864507 -270.609418) (xy 110.9 -270.64351)
			(xy 110.929565 -270.682854) (xy 110.952436 -270.726431) (xy 110.96802 -270.773112) (xy 110.975915 -270.821689)
			(xy 110.97641 -270.846296) (xy 113.178856 -270.846296) (xy 113.182816 -270.797242) (xy 113.194593 -270.749458)
			(xy 113.213884 -270.704182) (xy 113.240187 -270.662586) (xy 113.272822 -270.625749) (xy 113.310943 -270.594624)
			(xy 113.353564 -270.570017) (xy 113.39958 -270.552565) (xy 113.447799 -270.542721) (xy 113.496974 -270.54074)
			(xy 113.545829 -270.546672) (xy 113.5931 -270.560364) (xy 113.637562 -270.581462) (xy 113.678065 -270.609418)
			(xy 113.713558 -270.64351) (xy 113.743123 -270.682854) (xy 113.765994 -270.726431) (xy 113.781578 -270.773112)
			(xy 113.789473 -270.821689) (xy 113.789968 -270.846296) (xy 114.11891 -270.846296) (xy 114.12287 -270.797242)
			(xy 114.134647 -270.749458) (xy 114.153938 -270.704182) (xy 114.180241 -270.662586) (xy 114.212876 -270.625749)
			(xy 114.250997 -270.594624) (xy 114.293618 -270.570017) (xy 114.339634 -270.552565) (xy 114.387853 -270.542721)
			(xy 114.437028 -270.54074) (xy 114.485883 -270.546672) (xy 114.533154 -270.560364) (xy 114.577616 -270.581462)
			(xy 114.618119 -270.609418) (xy 114.653612 -270.64351) (xy 114.683177 -270.682854) (xy 114.706048 -270.726431)
			(xy 114.721632 -270.773112) (xy 114.729527 -270.821689) (xy 114.730022 -270.846296) (xy 115.058964 -270.846296)
			(xy 115.062924 -270.797242) (xy 115.074701 -270.749458) (xy 115.093992 -270.704182) (xy 115.120295 -270.662586)
			(xy 115.15293 -270.625749) (xy 115.191051 -270.594624) (xy 115.233672 -270.570017) (xy 115.279688 -270.552565)
			(xy 115.327907 -270.542721) (xy 115.377082 -270.54074) (xy 115.425937 -270.546672) (xy 115.473208 -270.560364)
			(xy 115.51767 -270.581462) (xy 115.558173 -270.609418) (xy 115.593666 -270.64351) (xy 115.623231 -270.682854)
			(xy 115.646102 -270.726431) (xy 115.661686 -270.773112) (xy 115.669581 -270.821689) (xy 115.670076 -270.846296)
			(xy 115.999018 -270.846296) (xy 116.002978 -270.797242) (xy 116.014755 -270.749458) (xy 116.034046 -270.704182)
			(xy 116.060349 -270.662586) (xy 116.092984 -270.625749) (xy 116.131105 -270.594624) (xy 116.173726 -270.570017)
			(xy 116.219742 -270.552565) (xy 116.267961 -270.542721) (xy 116.317136 -270.54074) (xy 116.365991 -270.546672)
			(xy 116.413262 -270.560364) (xy 116.457724 -270.581462) (xy 116.498227 -270.609418) (xy 116.53372 -270.64351)
			(xy 116.563285 -270.682854) (xy 116.586156 -270.726431) (xy 116.60174 -270.773112) (xy 116.609635 -270.821689)
			(xy 116.61013 -270.846296) (xy 116.938818 -270.846296) (xy 116.942778 -270.797242) (xy 116.954555 -270.749458)
			(xy 116.973846 -270.704182) (xy 117.000149 -270.662586) (xy 117.032784 -270.625749) (xy 117.070905 -270.594624)
			(xy 117.113526 -270.570017) (xy 117.159542 -270.552565) (xy 117.207761 -270.542721) (xy 117.256936 -270.54074)
			(xy 117.305791 -270.546672) (xy 117.353062 -270.560364) (xy 117.397524 -270.581462) (xy 117.438027 -270.609418)
			(xy 117.47352 -270.64351) (xy 117.503085 -270.682854) (xy 117.525956 -270.726431) (xy 117.54154 -270.773112)
			(xy 117.549435 -270.821689) (xy 117.54993 -270.846296) (xy 117.878872 -270.846296) (xy 117.882832 -270.797242)
			(xy 117.894609 -270.749458) (xy 117.9139 -270.704182) (xy 117.940203 -270.662586) (xy 117.972838 -270.625749)
			(xy 118.010959 -270.594624) (xy 118.05358 -270.570017) (xy 118.099596 -270.552565) (xy 118.147815 -270.542721)
			(xy 118.19699 -270.54074) (xy 118.245845 -270.546672) (xy 118.293116 -270.560364) (xy 118.337578 -270.581462)
			(xy 118.378081 -270.609418) (xy 118.413574 -270.64351) (xy 118.443139 -270.682854) (xy 118.46601 -270.726431)
			(xy 118.481594 -270.773112) (xy 118.489489 -270.821689) (xy 118.489984 -270.846296) (xy 118.818926 -270.846296)
			(xy 118.822886 -270.797242) (xy 118.834663 -270.749458) (xy 118.853954 -270.704182) (xy 118.880257 -270.662586)
			(xy 118.912892 -270.625749) (xy 118.951013 -270.594624) (xy 118.993634 -270.570017) (xy 119.03965 -270.552565)
			(xy 119.087869 -270.542721) (xy 119.137044 -270.54074) (xy 119.185899 -270.546672) (xy 119.23317 -270.560364)
			(xy 119.277632 -270.581462) (xy 119.318135 -270.609418) (xy 119.353628 -270.64351) (xy 119.383193 -270.682854)
			(xy 119.406064 -270.726431) (xy 119.421648 -270.773112) (xy 119.429543 -270.821689) (xy 119.430038 -270.846296)
			(xy 119.75898 -270.846296) (xy 119.76294 -270.797242) (xy 119.774717 -270.749458) (xy 119.794008 -270.704182)
			(xy 119.820311 -270.662586) (xy 119.852946 -270.625749) (xy 119.891067 -270.594624) (xy 119.933688 -270.570017)
			(xy 119.979704 -270.552565) (xy 120.027923 -270.542721) (xy 120.077098 -270.54074) (xy 120.125953 -270.546672)
			(xy 120.173224 -270.560364) (xy 120.217686 -270.581462) (xy 120.258189 -270.609418) (xy 120.293682 -270.64351)
			(xy 120.323247 -270.682854) (xy 120.346118 -270.726431) (xy 120.361702 -270.773112) (xy 120.369597 -270.821689)
			(xy 120.370092 -270.846296) (xy 120.699034 -270.846296) (xy 120.702994 -270.797242) (xy 120.714771 -270.749458)
			(xy 120.734062 -270.704182) (xy 120.760365 -270.662586) (xy 120.793 -270.625749) (xy 120.831121 -270.594624)
			(xy 120.873742 -270.570017) (xy 120.919758 -270.552565) (xy 120.967977 -270.542721) (xy 121.017152 -270.54074)
			(xy 121.066007 -270.546672) (xy 121.113278 -270.560364) (xy 121.15774 -270.581462) (xy 121.198243 -270.609418)
			(xy 121.233736 -270.64351) (xy 121.263301 -270.682854) (xy 121.286172 -270.726431) (xy 121.301756 -270.773112)
			(xy 121.309651 -270.821689) (xy 121.310146 -270.846296) (xy 121.638834 -270.846296) (xy 121.642794 -270.797242)
			(xy 121.654571 -270.749458) (xy 121.673862 -270.704182) (xy 121.700165 -270.662586) (xy 121.7328 -270.625749)
			(xy 121.770921 -270.594624) (xy 121.813542 -270.570017) (xy 121.859558 -270.552565) (xy 121.907777 -270.542721)
			(xy 121.956952 -270.54074) (xy 122.005807 -270.546672) (xy 122.053078 -270.560364) (xy 122.09754 -270.581462)
			(xy 122.138043 -270.609418) (xy 122.173536 -270.64351) (xy 122.203101 -270.682854) (xy 122.225972 -270.726431)
			(xy 122.241556 -270.773112) (xy 122.249451 -270.821689) (xy 122.249946 -270.846296) (xy 122.578888 -270.846296)
			(xy 122.582848 -270.797242) (xy 122.594625 -270.749458) (xy 122.613916 -270.704182) (xy 122.640219 -270.662586)
			(xy 122.672854 -270.625749) (xy 122.710975 -270.594624) (xy 122.753596 -270.570017) (xy 122.799612 -270.552565)
			(xy 122.847831 -270.542721) (xy 122.897006 -270.54074) (xy 122.945861 -270.546672) (xy 122.993132 -270.560364)
			(xy 123.037594 -270.581462) (xy 123.078097 -270.609418) (xy 123.11359 -270.64351) (xy 123.143155 -270.682854)
			(xy 123.166026 -270.726431) (xy 123.18161 -270.773112) (xy 123.189505 -270.821689) (xy 123.19 -270.846296)
			(xy 123.518942 -270.846296) (xy 123.522902 -270.797242) (xy 123.534679 -270.749458) (xy 123.55397 -270.704182)
			(xy 123.580273 -270.662586) (xy 123.612908 -270.625749) (xy 123.651029 -270.594624) (xy 123.69365 -270.570017)
			(xy 123.739666 -270.552565) (xy 123.787885 -270.542721) (xy 123.83706 -270.54074) (xy 123.885915 -270.546672)
			(xy 123.933186 -270.560364) (xy 123.977648 -270.581462) (xy 124.018151 -270.609418) (xy 124.053644 -270.64351)
			(xy 124.083209 -270.682854) (xy 124.10608 -270.726431) (xy 124.121664 -270.773112) (xy 124.129559 -270.821689)
			(xy 124.130054 -270.846296) (xy 124.458996 -270.846296) (xy 124.462956 -270.797242) (xy 124.474733 -270.749458)
			(xy 124.494024 -270.704182) (xy 124.520327 -270.662586) (xy 124.552962 -270.625749) (xy 124.591083 -270.594624)
			(xy 124.633704 -270.570017) (xy 124.67972 -270.552565) (xy 124.727939 -270.542721) (xy 124.777114 -270.54074)
			(xy 124.825969 -270.546672) (xy 124.87324 -270.560364) (xy 124.917702 -270.581462) (xy 124.958205 -270.609418)
			(xy 124.993698 -270.64351) (xy 125.023263 -270.682854) (xy 125.046134 -270.726431) (xy 125.061718 -270.773112)
			(xy 125.069613 -270.821689) (xy 125.070108 -270.846296) (xy 125.39905 -270.846296) (xy 125.40301 -270.797242)
			(xy 125.414787 -270.749458) (xy 125.434078 -270.704182) (xy 125.460381 -270.662586) (xy 125.493016 -270.625749)
			(xy 125.531137 -270.594624) (xy 125.573758 -270.570017) (xy 125.619774 -270.552565) (xy 125.667993 -270.542721)
			(xy 125.717168 -270.54074) (xy 125.766023 -270.546672) (xy 125.813294 -270.560364) (xy 125.857756 -270.581462)
			(xy 125.898259 -270.609418) (xy 125.933752 -270.64351) (xy 125.963317 -270.682854) (xy 125.986188 -270.726431)
			(xy 126.001772 -270.773112) (xy 126.009667 -270.821689) (xy 126.010162 -270.846296) (xy 126.009667 -270.870903)
			(xy 126.001772 -270.91948) (xy 125.986188 -270.966161) (xy 125.963317 -271.009738) (xy 125.933752 -271.049082)
			(xy 125.898259 -271.083174) (xy 125.857756 -271.11113) (xy 125.813294 -271.132228) (xy 125.766023 -271.14592)
			(xy 125.717168 -271.151852) (xy 125.667993 -271.149871) (xy 125.619774 -271.140027) (xy 125.573758 -271.122575)
			(xy 125.531137 -271.097968) (xy 125.493016 -271.066843) (xy 125.460381 -271.030006) (xy 125.434078 -270.98841)
			(xy 125.414787 -270.943134) (xy 125.40301 -270.89535) (xy 125.39905 -270.846296) (xy 125.070108 -270.846296)
			(xy 125.069613 -270.870903) (xy 125.061718 -270.91948) (xy 125.046134 -270.966161) (xy 125.023263 -271.009738)
			(xy 124.993698 -271.049082) (xy 124.958205 -271.083174) (xy 124.917702 -271.11113) (xy 124.87324 -271.132228)
			(xy 124.825969 -271.14592) (xy 124.777114 -271.151852) (xy 124.727939 -271.149871) (xy 124.67972 -271.140027)
			(xy 124.633704 -271.122575) (xy 124.591083 -271.097968) (xy 124.552962 -271.066843) (xy 124.520327 -271.030006)
			(xy 124.494024 -270.98841) (xy 124.474733 -270.943134) (xy 124.462956 -270.89535) (xy 124.458996 -270.846296)
			(xy 124.130054 -270.846296) (xy 124.129559 -270.870903) (xy 124.121664 -270.91948) (xy 124.10608 -270.966161)
			(xy 124.083209 -271.009738) (xy 124.053644 -271.049082) (xy 124.018151 -271.083174) (xy 123.977648 -271.11113)
			(xy 123.933186 -271.132228) (xy 123.885915 -271.14592) (xy 123.83706 -271.151852) (xy 123.787885 -271.149871)
			(xy 123.739666 -271.140027) (xy 123.69365 -271.122575) (xy 123.651029 -271.097968) (xy 123.612908 -271.066843)
			(xy 123.580273 -271.030006) (xy 123.55397 -270.98841) (xy 123.534679 -270.943134) (xy 123.522902 -270.89535)
			(xy 123.518942 -270.846296) (xy 123.19 -270.846296) (xy 123.189505 -270.870903) (xy 123.18161 -270.91948)
			(xy 123.166026 -270.966161) (xy 123.143155 -271.009738) (xy 123.11359 -271.049082) (xy 123.078097 -271.083174)
			(xy 123.037594 -271.11113) (xy 122.993132 -271.132228) (xy 122.945861 -271.14592) (xy 122.897006 -271.151852)
			(xy 122.847831 -271.149871) (xy 122.799612 -271.140027) (xy 122.753596 -271.122575) (xy 122.710975 -271.097968)
			(xy 122.672854 -271.066843) (xy 122.640219 -271.030006) (xy 122.613916 -270.98841) (xy 122.594625 -270.943134)
			(xy 122.582848 -270.89535) (xy 122.578888 -270.846296) (xy 122.249946 -270.846296) (xy 122.249451 -270.870903)
			(xy 122.241556 -270.91948) (xy 122.225972 -270.966161) (xy 122.203101 -271.009738) (xy 122.173536 -271.049082)
			(xy 122.138043 -271.083174) (xy 122.09754 -271.11113) (xy 122.053078 -271.132228) (xy 122.005807 -271.14592)
			(xy 121.956952 -271.151852) (xy 121.907777 -271.149871) (xy 121.859558 -271.140027) (xy 121.813542 -271.122575)
			(xy 121.770921 -271.097968) (xy 121.7328 -271.066843) (xy 121.700165 -271.030006) (xy 121.673862 -270.98841)
			(xy 121.654571 -270.943134) (xy 121.642794 -270.89535) (xy 121.638834 -270.846296) (xy 121.310146 -270.846296)
			(xy 121.309651 -270.870903) (xy 121.301756 -270.91948) (xy 121.286172 -270.966161) (xy 121.263301 -271.009738)
			(xy 121.233736 -271.049082) (xy 121.198243 -271.083174) (xy 121.15774 -271.11113) (xy 121.113278 -271.132228)
			(xy 121.066007 -271.14592) (xy 121.017152 -271.151852) (xy 120.967977 -271.149871) (xy 120.919758 -271.140027)
			(xy 120.873742 -271.122575) (xy 120.831121 -271.097968) (xy 120.793 -271.066843) (xy 120.760365 -271.030006)
			(xy 120.734062 -270.98841) (xy 120.714771 -270.943134) (xy 120.702994 -270.89535) (xy 120.699034 -270.846296)
			(xy 120.370092 -270.846296) (xy 120.369597 -270.870903) (xy 120.361702 -270.91948) (xy 120.346118 -270.966161)
			(xy 120.323247 -271.009738) (xy 120.293682 -271.049082) (xy 120.258189 -271.083174) (xy 120.217686 -271.11113)
			(xy 120.173224 -271.132228) (xy 120.125953 -271.14592) (xy 120.077098 -271.151852) (xy 120.027923 -271.149871)
			(xy 119.979704 -271.140027) (xy 119.933688 -271.122575) (xy 119.891067 -271.097968) (xy 119.852946 -271.066843)
			(xy 119.820311 -271.030006) (xy 119.794008 -270.98841) (xy 119.774717 -270.943134) (xy 119.76294 -270.89535)
			(xy 119.75898 -270.846296) (xy 119.430038 -270.846296) (xy 119.429543 -270.870903) (xy 119.421648 -270.91948)
			(xy 119.406064 -270.966161) (xy 119.383193 -271.009738) (xy 119.353628 -271.049082) (xy 119.318135 -271.083174)
			(xy 119.277632 -271.11113) (xy 119.23317 -271.132228) (xy 119.185899 -271.14592) (xy 119.137044 -271.151852)
			(xy 119.087869 -271.149871) (xy 119.03965 -271.140027) (xy 118.993634 -271.122575) (xy 118.951013 -271.097968)
			(xy 118.912892 -271.066843) (xy 118.880257 -271.030006) (xy 118.853954 -270.98841) (xy 118.834663 -270.943134)
			(xy 118.822886 -270.89535) (xy 118.818926 -270.846296) (xy 118.489984 -270.846296) (xy 118.489489 -270.870903)
			(xy 118.481594 -270.91948) (xy 118.46601 -270.966161) (xy 118.443139 -271.009738) (xy 118.413574 -271.049082)
			(xy 118.378081 -271.083174) (xy 118.337578 -271.11113) (xy 118.293116 -271.132228) (xy 118.245845 -271.14592)
			(xy 118.19699 -271.151852) (xy 118.147815 -271.149871) (xy 118.099596 -271.140027) (xy 118.05358 -271.122575)
			(xy 118.010959 -271.097968) (xy 117.972838 -271.066843) (xy 117.940203 -271.030006) (xy 117.9139 -270.98841)
			(xy 117.894609 -270.943134) (xy 117.882832 -270.89535) (xy 117.878872 -270.846296) (xy 117.54993 -270.846296)
			(xy 117.549435 -270.870903) (xy 117.54154 -270.91948) (xy 117.525956 -270.966161) (xy 117.503085 -271.009738)
			(xy 117.47352 -271.049082) (xy 117.438027 -271.083174) (xy 117.397524 -271.11113) (xy 117.353062 -271.132228)
			(xy 117.305791 -271.14592) (xy 117.256936 -271.151852) (xy 117.207761 -271.149871) (xy 117.159542 -271.140027)
			(xy 117.113526 -271.122575) (xy 117.070905 -271.097968) (xy 117.032784 -271.066843) (xy 117.000149 -271.030006)
			(xy 116.973846 -270.98841) (xy 116.954555 -270.943134) (xy 116.942778 -270.89535) (xy 116.938818 -270.846296)
			(xy 116.61013 -270.846296) (xy 116.609635 -270.870903) (xy 116.60174 -270.91948) (xy 116.586156 -270.966161)
			(xy 116.563285 -271.009738) (xy 116.53372 -271.049082) (xy 116.498227 -271.083174) (xy 116.457724 -271.11113)
			(xy 116.413262 -271.132228) (xy 116.365991 -271.14592) (xy 116.317136 -271.151852) (xy 116.267961 -271.149871)
			(xy 116.219742 -271.140027) (xy 116.173726 -271.122575) (xy 116.131105 -271.097968) (xy 116.092984 -271.066843)
			(xy 116.060349 -271.030006) (xy 116.034046 -270.98841) (xy 116.014755 -270.943134) (xy 116.002978 -270.89535)
			(xy 115.999018 -270.846296) (xy 115.670076 -270.846296) (xy 115.669581 -270.870903) (xy 115.661686 -270.91948)
			(xy 115.646102 -270.966161) (xy 115.623231 -271.009738) (xy 115.593666 -271.049082) (xy 115.558173 -271.083174)
			(xy 115.51767 -271.11113) (xy 115.473208 -271.132228) (xy 115.425937 -271.14592) (xy 115.377082 -271.151852)
			(xy 115.327907 -271.149871) (xy 115.279688 -271.140027) (xy 115.233672 -271.122575) (xy 115.191051 -271.097968)
			(xy 115.15293 -271.066843) (xy 115.120295 -271.030006) (xy 115.093992 -270.98841) (xy 115.074701 -270.943134)
			(xy 115.062924 -270.89535) (xy 115.058964 -270.846296) (xy 114.730022 -270.846296) (xy 114.729527 -270.870903)
			(xy 114.721632 -270.91948) (xy 114.706048 -270.966161) (xy 114.683177 -271.009738) (xy 114.653612 -271.049082)
			(xy 114.618119 -271.083174) (xy 114.577616 -271.11113) (xy 114.533154 -271.132228) (xy 114.485883 -271.14592)
			(xy 114.437028 -271.151852) (xy 114.387853 -271.149871) (xy 114.339634 -271.140027) (xy 114.293618 -271.122575)
			(xy 114.250997 -271.097968) (xy 114.212876 -271.066843) (xy 114.180241 -271.030006) (xy 114.153938 -270.98841)
			(xy 114.134647 -270.943134) (xy 114.12287 -270.89535) (xy 114.11891 -270.846296) (xy 113.789968 -270.846296)
			(xy 113.789473 -270.870903) (xy 113.781578 -270.91948) (xy 113.765994 -270.966161) (xy 113.743123 -271.009738)
			(xy 113.713558 -271.049082) (xy 113.678065 -271.083174) (xy 113.637562 -271.11113) (xy 113.5931 -271.132228)
			(xy 113.545829 -271.14592) (xy 113.496974 -271.151852) (xy 113.447799 -271.149871) (xy 113.39958 -271.140027)
			(xy 113.353564 -271.122575) (xy 113.310943 -271.097968) (xy 113.272822 -271.066843) (xy 113.240187 -271.030006)
			(xy 113.213884 -270.98841) (xy 113.194593 -270.943134) (xy 113.182816 -270.89535) (xy 113.178856 -270.846296)
			(xy 110.97641 -270.846296) (xy 110.975915 -270.870903) (xy 110.96802 -270.91948) (xy 110.952436 -270.966161)
			(xy 110.929565 -271.009738) (xy 110.9 -271.049082) (xy 110.864507 -271.083174) (xy 110.824004 -271.11113)
			(xy 110.779542 -271.132228) (xy 110.732271 -271.14592) (xy 110.683416 -271.151852) (xy 110.634241 -271.149871)
			(xy 110.586022 -271.140027) (xy 110.540006 -271.122575) (xy 110.497385 -271.097968) (xy 110.459264 -271.066843)
			(xy 110.426629 -271.030006) (xy 110.400326 -270.98841) (xy 110.381035 -270.943134) (xy 110.369258 -270.89535)
			(xy 110.365298 -270.846296) (xy 110.036356 -270.846296) (xy 110.035861 -270.870903) (xy 110.027966 -270.91948)
			(xy 110.012382 -270.966161) (xy 109.989511 -271.009738) (xy 109.959946 -271.049082) (xy 109.924453 -271.083174)
			(xy 109.88395 -271.11113) (xy 109.839488 -271.132228) (xy 109.792217 -271.14592) (xy 109.743362 -271.151852)
			(xy 109.694187 -271.149871) (xy 109.645968 -271.140027) (xy 109.599952 -271.122575) (xy 109.557331 -271.097968)
			(xy 109.51921 -271.066843) (xy 109.486575 -271.030006) (xy 109.460272 -270.98841) (xy 109.440981 -270.943134)
			(xy 109.429204 -270.89535) (xy 109.425244 -270.846296) (xy 109.096302 -270.846296) (xy 109.095807 -270.870903)
			(xy 109.087912 -270.91948) (xy 109.072328 -270.966161) (xy 109.049457 -271.009738) (xy 109.019892 -271.049082)
			(xy 108.984399 -271.083174) (xy 108.943896 -271.11113) (xy 108.899434 -271.132228) (xy 108.852163 -271.14592)
			(xy 108.803308 -271.151852) (xy 108.754133 -271.149871) (xy 108.705914 -271.140027) (xy 108.659898 -271.122575)
			(xy 108.617277 -271.097968) (xy 108.579156 -271.066843) (xy 108.546521 -271.030006) (xy 108.520218 -270.98841)
			(xy 108.500927 -270.943134) (xy 108.48915 -270.89535) (xy 108.48519 -270.846296) (xy 108.156248 -270.846296)
			(xy 108.155753 -270.870903) (xy 108.147858 -270.91948) (xy 108.132274 -270.966161) (xy 108.109403 -271.009738)
			(xy 108.079838 -271.049082) (xy 108.044345 -271.083174) (xy 108.003842 -271.11113) (xy 107.95938 -271.132228)
			(xy 107.912109 -271.14592) (xy 107.863254 -271.151852) (xy 107.814079 -271.149871) (xy 107.76586 -271.140027)
			(xy 107.719844 -271.122575) (xy 107.677223 -271.097968) (xy 107.639102 -271.066843) (xy 107.606467 -271.030006)
			(xy 107.580164 -270.98841) (xy 107.560873 -270.943134) (xy 107.549096 -270.89535) (xy 107.545136 -270.846296)
			(xy 107.216448 -270.846296) (xy 107.215953 -270.870903) (xy 107.208058 -270.91948) (xy 107.192474 -270.966161)
			(xy 107.169603 -271.009738) (xy 107.140038 -271.049082) (xy 107.104545 -271.083174) (xy 107.064042 -271.11113)
			(xy 107.01958 -271.132228) (xy 106.972309 -271.14592) (xy 106.923454 -271.151852) (xy 106.874279 -271.149871)
			(xy 106.82606 -271.140027) (xy 106.780044 -271.122575) (xy 106.737423 -271.097968) (xy 106.699302 -271.066843)
			(xy 106.666667 -271.030006) (xy 106.640364 -270.98841) (xy 106.621073 -270.943134) (xy 106.609296 -270.89535)
			(xy 106.605336 -270.846296) (xy 106.276394 -270.846296) (xy 106.275899 -270.870903) (xy 106.268004 -270.91948)
			(xy 106.25242 -270.966161) (xy 106.229549 -271.009738) (xy 106.199984 -271.049082) (xy 106.164491 -271.083174)
			(xy 106.123988 -271.11113) (xy 106.079526 -271.132228) (xy 106.032255 -271.14592) (xy 105.9834 -271.151852)
			(xy 105.934225 -271.149871) (xy 105.886006 -271.140027) (xy 105.83999 -271.122575) (xy 105.797369 -271.097968)
			(xy 105.759248 -271.066843) (xy 105.726613 -271.030006) (xy 105.70031 -270.98841) (xy 105.681019 -270.943134)
			(xy 105.669242 -270.89535) (xy 105.665282 -270.846296) (xy 105.33634 -270.846296) (xy 105.335845 -270.870903)
			(xy 105.32795 -270.91948) (xy 105.312366 -270.966161) (xy 105.289495 -271.009738) (xy 105.25993 -271.049082)
			(xy 105.224437 -271.083174) (xy 105.183934 -271.11113) (xy 105.139472 -271.132228) (xy 105.092201 -271.14592)
			(xy 105.043346 -271.151852) (xy 104.994171 -271.149871) (xy 104.945952 -271.140027) (xy 104.899936 -271.122575)
			(xy 104.857315 -271.097968) (xy 104.819194 -271.066843) (xy 104.786559 -271.030006) (xy 104.760256 -270.98841)
			(xy 104.740965 -270.943134) (xy 104.729188 -270.89535) (xy 104.725228 -270.846296) (xy 104.396286 -270.846296)
			(xy 104.395791 -270.870903) (xy 104.387896 -270.91948) (xy 104.372312 -270.966161) (xy 104.349441 -271.009738)
			(xy 104.319876 -271.049082) (xy 104.284383 -271.083174) (xy 104.24388 -271.11113) (xy 104.199418 -271.132228)
			(xy 104.152147 -271.14592) (xy 104.103292 -271.151852) (xy 104.054117 -271.149871) (xy 104.005898 -271.140027)
			(xy 103.959882 -271.122575) (xy 103.917261 -271.097968) (xy 103.87914 -271.066843) (xy 103.846505 -271.030006)
			(xy 103.820202 -270.98841) (xy 103.800911 -270.943134) (xy 103.789134 -270.89535) (xy 103.785174 -270.846296)
			(xy 103.456486 -270.846296) (xy 103.455991 -270.870903) (xy 103.448096 -270.91948) (xy 103.432512 -270.966161)
			(xy 103.409641 -271.009738) (xy 103.380076 -271.049082) (xy 103.344583 -271.083174) (xy 103.30408 -271.11113)
			(xy 103.259618 -271.132228) (xy 103.212347 -271.14592) (xy 103.163492 -271.151852) (xy 103.114317 -271.149871)
			(xy 103.066098 -271.140027) (xy 103.020082 -271.122575) (xy 102.977461 -271.097968) (xy 102.93934 -271.066843)
			(xy 102.906705 -271.030006) (xy 102.880402 -270.98841) (xy 102.861111 -270.943134) (xy 102.849334 -270.89535)
			(xy 102.845374 -270.846296) (xy 102.516432 -270.846296) (xy 102.515937 -270.870903) (xy 102.508042 -270.91948)
			(xy 102.492458 -270.966161) (xy 102.469587 -271.009738) (xy 102.440022 -271.049082) (xy 102.404529 -271.083174)
			(xy 102.364026 -271.11113) (xy 102.319564 -271.132228) (xy 102.272293 -271.14592) (xy 102.223438 -271.151852)
			(xy 102.174263 -271.149871) (xy 102.126044 -271.140027) (xy 102.080028 -271.122575) (xy 102.037407 -271.097968)
			(xy 101.999286 -271.066843) (xy 101.966651 -271.030006) (xy 101.940348 -270.98841) (xy 101.921057 -270.943134)
			(xy 101.90928 -270.89535) (xy 101.90532 -270.846296) (xy 101.576378 -270.846296) (xy 101.575883 -270.870903)
			(xy 101.567988 -270.91948) (xy 101.552404 -270.966161) (xy 101.529533 -271.009738) (xy 101.499968 -271.049082)
			(xy 101.464475 -271.083174) (xy 101.423972 -271.11113) (xy 101.37951 -271.132228) (xy 101.332239 -271.14592)
			(xy 101.283384 -271.151852) (xy 101.234209 -271.149871) (xy 101.18599 -271.140027) (xy 101.139974 -271.122575)
			(xy 101.097353 -271.097968) (xy 101.059232 -271.066843) (xy 101.026597 -271.030006) (xy 101.000294 -270.98841)
			(xy 100.981003 -270.943134) (xy 100.969226 -270.89535) (xy 100.965266 -270.846296) (xy 100.636324 -270.846296)
			(xy 100.635829 -270.870903) (xy 100.627934 -270.91948) (xy 100.61235 -270.966161) (xy 100.589479 -271.009738)
			(xy 100.559914 -271.049082) (xy 100.524421 -271.083174) (xy 100.483918 -271.11113) (xy 100.439456 -271.132228)
			(xy 100.392185 -271.14592) (xy 100.34333 -271.151852) (xy 100.294155 -271.149871) (xy 100.245936 -271.140027)
			(xy 100.19992 -271.122575) (xy 100.157299 -271.097968) (xy 100.119178 -271.066843) (xy 100.086543 -271.030006)
			(xy 100.06024 -270.98841) (xy 100.040949 -270.943134) (xy 100.029172 -270.89535) (xy 100.025212 -270.846296)
			(xy 99.69627 -270.846296) (xy 99.695775 -270.870903) (xy 99.68788 -270.91948) (xy 99.672296 -270.966161)
			(xy 99.649425 -271.009738) (xy 99.61986 -271.049082) (xy 99.584367 -271.083174) (xy 99.543864 -271.11113)
			(xy 99.499402 -271.132228) (xy 99.452131 -271.14592) (xy 99.403276 -271.151852) (xy 99.354101 -271.149871)
			(xy 99.305882 -271.140027) (xy 99.259866 -271.122575) (xy 99.217245 -271.097968) (xy 99.179124 -271.066843)
			(xy 99.146489 -271.030006) (xy 99.120186 -270.98841) (xy 99.100895 -270.943134) (xy 99.089118 -270.89535)
			(xy 99.085158 -270.846296) (xy 98.75647 -270.846296) (xy 98.755975 -270.870903) (xy 98.74808 -270.91948)
			(xy 98.732496 -270.966161) (xy 98.709625 -271.009738) (xy 98.68006 -271.049082) (xy 98.644567 -271.083174)
			(xy 98.604064 -271.11113) (xy 98.559602 -271.132228) (xy 98.512331 -271.14592) (xy 98.463476 -271.151852)
			(xy 98.414301 -271.149871) (xy 98.366082 -271.140027) (xy 98.320066 -271.122575) (xy 98.277445 -271.097968)
			(xy 98.239324 -271.066843) (xy 98.206689 -271.030006) (xy 98.180386 -270.98841) (xy 98.161095 -270.943134)
			(xy 98.149318 -270.89535) (xy 98.145358 -270.846296) (xy 97.816992 -270.846296) (xy 97.816992 -270.8463)
			(xy 97.812921 -270.896039) (xy 97.800816 -270.944455) (xy 97.781 -270.990258) (xy 97.753999 -271.032229)
			(xy 97.720533 -271.069251) (xy 97.681493 -271.100339) (xy 97.637917 -271.124665) (xy 97.590966 -271.141581)
			(xy 97.541889 -271.150638) (xy 97.51695 -271.151604) (xy 97.510854 -271.151604) (xy 97.484237 -271.151006)
			(xy 97.431814 -271.141737) (xy 97.381792 -271.123523) (xy 97.358454 -271.11071) (xy 97.346516 -271.103852)
			(xy 97.319338 -271.103598) (xy 97.2312 -271.154652) (xy 97.223707 -271.159431) (xy 97.212294 -271.173035)
			(xy 97.206204 -271.189716) (xy 97.2058 -271.198594) (xy 97.2058 -271.3609) (xy 97.205958 -271.366768)
			(xy 97.208641 -271.378193) (xy 97.211134 -271.383506) (xy 97.223326 -271.408144) (xy 97.229676 -271.416272)
			(xy 97.234248 -271.419828) (xy 97.252969 -271.435788) (xy 97.285553 -271.47264) (xy 97.311812 -271.514237)
			(xy 97.331069 -271.559503) (xy 97.342825 -271.607269) (xy 97.346778 -271.656301) (xy 97.346778 -271.656302)
			(xy 97.675204 -271.656302) (xy 97.679164 -271.607248) (xy 97.690941 -271.559464) (xy 97.710232 -271.514188)
			(xy 97.736535 -271.472592) (xy 97.76917 -271.435755) (xy 97.807291 -271.40463) (xy 97.849912 -271.380023)
			(xy 97.895928 -271.362571) (xy 97.944147 -271.352727) (xy 97.993322 -271.350746) (xy 98.042177 -271.356678)
			(xy 98.089448 -271.37037) (xy 98.13391 -271.391468) (xy 98.174413 -271.419424) (xy 98.209906 -271.453516)
			(xy 98.239471 -271.49286) (xy 98.262342 -271.536437) (xy 98.277926 -271.583118) (xy 98.285821 -271.631695)
			(xy 98.286316 -271.656302) (xy 98.615258 -271.656302) (xy 98.619218 -271.607248) (xy 98.630995 -271.559464)
			(xy 98.650286 -271.514188) (xy 98.676589 -271.472592) (xy 98.709224 -271.435755) (xy 98.747345 -271.40463)
			(xy 98.789966 -271.380023) (xy 98.835982 -271.362571) (xy 98.884201 -271.352727) (xy 98.933376 -271.350746)
			(xy 98.982231 -271.356678) (xy 99.029502 -271.37037) (xy 99.073964 -271.391468) (xy 99.114467 -271.419424)
			(xy 99.14996 -271.453516) (xy 99.179525 -271.49286) (xy 99.202396 -271.536437) (xy 99.21798 -271.583118)
			(xy 99.225875 -271.631695) (xy 99.22637 -271.656302) (xy 99.555312 -271.656302) (xy 99.559272 -271.607248)
			(xy 99.571049 -271.559464) (xy 99.59034 -271.514188) (xy 99.616643 -271.472592) (xy 99.649278 -271.435755)
			(xy 99.687399 -271.40463) (xy 99.73002 -271.380023) (xy 99.776036 -271.362571) (xy 99.824255 -271.352727)
			(xy 99.87343 -271.350746) (xy 99.922285 -271.356678) (xy 99.969556 -271.37037) (xy 100.014018 -271.391468)
			(xy 100.054521 -271.419424) (xy 100.090014 -271.453516) (xy 100.119579 -271.49286) (xy 100.14245 -271.536437)
			(xy 100.158034 -271.583118) (xy 100.165929 -271.631695) (xy 100.166424 -271.656302) (xy 100.495366 -271.656302)
			(xy 100.499326 -271.607248) (xy 100.511103 -271.559464) (xy 100.530394 -271.514188) (xy 100.556697 -271.472592)
			(xy 100.589332 -271.435755) (xy 100.627453 -271.40463) (xy 100.670074 -271.380023) (xy 100.71609 -271.362571)
			(xy 100.764309 -271.352727) (xy 100.813484 -271.350746) (xy 100.862339 -271.356678) (xy 100.90961 -271.37037)
			(xy 100.954072 -271.391468) (xy 100.994575 -271.419424) (xy 101.030068 -271.453516) (xy 101.059633 -271.49286)
			(xy 101.082504 -271.536437) (xy 101.098088 -271.583118) (xy 101.105983 -271.631695) (xy 101.106478 -271.656302)
			(xy 101.435166 -271.656302) (xy 101.439126 -271.607248) (xy 101.450903 -271.559464) (xy 101.470194 -271.514188)
			(xy 101.496497 -271.472592) (xy 101.529132 -271.435755) (xy 101.567253 -271.40463) (xy 101.609874 -271.380023)
			(xy 101.65589 -271.362571) (xy 101.704109 -271.352727) (xy 101.753284 -271.350746) (xy 101.802139 -271.356678)
			(xy 101.84941 -271.37037) (xy 101.893872 -271.391468) (xy 101.934375 -271.419424) (xy 101.969868 -271.453516)
			(xy 101.999433 -271.49286) (xy 102.022304 -271.536437) (xy 102.037888 -271.583118) (xy 102.045783 -271.631695)
			(xy 102.046278 -271.656302) (xy 102.37522 -271.656302) (xy 102.37918 -271.607248) (xy 102.390957 -271.559464)
			(xy 102.410248 -271.514188) (xy 102.436551 -271.472592) (xy 102.469186 -271.435755) (xy 102.507307 -271.40463)
			(xy 102.549928 -271.380023) (xy 102.595944 -271.362571) (xy 102.644163 -271.352727) (xy 102.693338 -271.350746)
			(xy 102.742193 -271.356678) (xy 102.789464 -271.37037) (xy 102.833926 -271.391468) (xy 102.874429 -271.419424)
			(xy 102.909922 -271.453516) (xy 102.939487 -271.49286) (xy 102.962358 -271.536437) (xy 102.977942 -271.583118)
			(xy 102.985837 -271.631695) (xy 102.986332 -271.656302) (xy 103.315274 -271.656302) (xy 103.319234 -271.607248)
			(xy 103.331011 -271.559464) (xy 103.350302 -271.514188) (xy 103.376605 -271.472592) (xy 103.40924 -271.435755)
			(xy 103.447361 -271.40463) (xy 103.489982 -271.380023) (xy 103.535998 -271.362571) (xy 103.584217 -271.352727)
			(xy 103.633392 -271.350746) (xy 103.682247 -271.356678) (xy 103.729518 -271.37037) (xy 103.77398 -271.391468)
			(xy 103.814483 -271.419424) (xy 103.849976 -271.453516) (xy 103.879541 -271.49286) (xy 103.902412 -271.536437)
			(xy 103.917996 -271.583118) (xy 103.925891 -271.631695) (xy 103.926386 -271.656302) (xy 104.255328 -271.656302)
			(xy 104.259288 -271.607248) (xy 104.271065 -271.559464) (xy 104.290356 -271.514188) (xy 104.316659 -271.472592)
			(xy 104.349294 -271.435755) (xy 104.387415 -271.40463) (xy 104.430036 -271.380023) (xy 104.476052 -271.362571)
			(xy 104.524271 -271.352727) (xy 104.573446 -271.350746) (xy 104.622301 -271.356678) (xy 104.669572 -271.37037)
			(xy 104.714034 -271.391468) (xy 104.754537 -271.419424) (xy 104.79003 -271.453516) (xy 104.819595 -271.49286)
			(xy 104.842466 -271.536437) (xy 104.85805 -271.583118) (xy 104.865945 -271.631695) (xy 104.86644 -271.656302)
			(xy 105.195128 -271.656302) (xy 105.199088 -271.607248) (xy 105.210865 -271.559464) (xy 105.230156 -271.514188)
			(xy 105.256459 -271.472592) (xy 105.289094 -271.435755) (xy 105.327215 -271.40463) (xy 105.369836 -271.380023)
			(xy 105.415852 -271.362571) (xy 105.464071 -271.352727) (xy 105.513246 -271.350746) (xy 105.562101 -271.356678)
			(xy 105.609372 -271.37037) (xy 105.653834 -271.391468) (xy 105.694337 -271.419424) (xy 105.72983 -271.453516)
			(xy 105.759395 -271.49286) (xy 105.782266 -271.536437) (xy 105.79785 -271.583118) (xy 105.805745 -271.631695)
			(xy 105.80624 -271.656302) (xy 106.135182 -271.656302) (xy 106.139142 -271.607248) (xy 106.150919 -271.559464)
			(xy 106.17021 -271.514188) (xy 106.196513 -271.472592) (xy 106.229148 -271.435755) (xy 106.267269 -271.40463)
			(xy 106.30989 -271.380023) (xy 106.355906 -271.362571) (xy 106.404125 -271.352727) (xy 106.4533 -271.350746)
			(xy 106.502155 -271.356678) (xy 106.549426 -271.37037) (xy 106.593888 -271.391468) (xy 106.634391 -271.419424)
			(xy 106.669884 -271.453516) (xy 106.699449 -271.49286) (xy 106.72232 -271.536437) (xy 106.737904 -271.583118)
			(xy 106.745799 -271.631695) (xy 106.746294 -271.656302) (xy 107.075236 -271.656302) (xy 107.079196 -271.607248)
			(xy 107.090973 -271.559464) (xy 107.110264 -271.514188) (xy 107.136567 -271.472592) (xy 107.169202 -271.435755)
			(xy 107.207323 -271.40463) (xy 107.249944 -271.380023) (xy 107.29596 -271.362571) (xy 107.344179 -271.352727)
			(xy 107.393354 -271.350746) (xy 107.442209 -271.356678) (xy 107.48948 -271.37037) (xy 107.533942 -271.391468)
			(xy 107.574445 -271.419424) (xy 107.609938 -271.453516) (xy 107.639503 -271.49286) (xy 107.662374 -271.536437)
			(xy 107.677958 -271.583118) (xy 107.685853 -271.631695) (xy 107.686348 -271.656302) (xy 108.01529 -271.656302)
			(xy 108.01925 -271.607248) (xy 108.031027 -271.559464) (xy 108.050318 -271.514188) (xy 108.076621 -271.472592)
			(xy 108.109256 -271.435755) (xy 108.147377 -271.40463) (xy 108.189998 -271.380023) (xy 108.236014 -271.362571)
			(xy 108.284233 -271.352727) (xy 108.333408 -271.350746) (xy 108.382263 -271.356678) (xy 108.429534 -271.37037)
			(xy 108.473996 -271.391468) (xy 108.514499 -271.419424) (xy 108.549992 -271.453516) (xy 108.579557 -271.49286)
			(xy 108.602428 -271.536437) (xy 108.618012 -271.583118) (xy 108.625907 -271.631695) (xy 108.626402 -271.656302)
			(xy 115.528864 -271.656302) (xy 115.532824 -271.607248) (xy 115.544601 -271.559464) (xy 115.563892 -271.514188)
			(xy 115.590195 -271.472592) (xy 115.62283 -271.435755) (xy 115.660951 -271.40463) (xy 115.703572 -271.380023)
			(xy 115.749588 -271.362571) (xy 115.797807 -271.352727) (xy 115.846982 -271.350746) (xy 115.895837 -271.356678)
			(xy 115.943108 -271.37037) (xy 115.98757 -271.391468) (xy 116.028073 -271.419424) (xy 116.063566 -271.453516)
			(xy 116.093131 -271.49286) (xy 116.116002 -271.536437) (xy 116.131586 -271.583118) (xy 116.139481 -271.631695)
			(xy 116.139976 -271.656302) (xy 116.468918 -271.656302) (xy 116.472878 -271.607248) (xy 116.484655 -271.559464)
			(xy 116.503946 -271.514188) (xy 116.530249 -271.472592) (xy 116.562884 -271.435755) (xy 116.601005 -271.40463)
			(xy 116.643626 -271.380023) (xy 116.689642 -271.362571) (xy 116.737861 -271.352727) (xy 116.787036 -271.350746)
			(xy 116.835891 -271.356678) (xy 116.883162 -271.37037) (xy 116.927624 -271.391468) (xy 116.968127 -271.419424)
			(xy 117.00362 -271.453516) (xy 117.033185 -271.49286) (xy 117.056056 -271.536437) (xy 117.07164 -271.583118)
			(xy 117.079535 -271.631695) (xy 117.08003 -271.656302) (xy 117.408972 -271.656302) (xy 117.412932 -271.607248)
			(xy 117.424709 -271.559464) (xy 117.444 -271.514188) (xy 117.470303 -271.472592) (xy 117.502938 -271.435755)
			(xy 117.541059 -271.40463) (xy 117.58368 -271.380023) (xy 117.629696 -271.362571) (xy 117.677915 -271.352727)
			(xy 117.72709 -271.350746) (xy 117.775945 -271.356678) (xy 117.823216 -271.37037) (xy 117.867678 -271.391468)
			(xy 117.908181 -271.419424) (xy 117.943674 -271.453516) (xy 117.973239 -271.49286) (xy 117.99611 -271.536437)
			(xy 118.011694 -271.583118) (xy 118.019589 -271.631695) (xy 118.020084 -271.656302) (xy 118.349026 -271.656302)
			(xy 118.352986 -271.607248) (xy 118.364763 -271.559464) (xy 118.384054 -271.514188) (xy 118.410357 -271.472592)
			(xy 118.442992 -271.435755) (xy 118.481113 -271.40463) (xy 118.523734 -271.380023) (xy 118.56975 -271.362571)
			(xy 118.617969 -271.352727) (xy 118.667144 -271.350746) (xy 118.715999 -271.356678) (xy 118.76327 -271.37037)
			(xy 118.807732 -271.391468) (xy 118.848235 -271.419424) (xy 118.883728 -271.453516) (xy 118.913293 -271.49286)
			(xy 118.936164 -271.536437) (xy 118.951748 -271.583118) (xy 118.959643 -271.631695) (xy 118.960138 -271.656302)
			(xy 119.288826 -271.656302) (xy 119.292786 -271.607248) (xy 119.304563 -271.559464) (xy 119.323854 -271.514188)
			(xy 119.350157 -271.472592) (xy 119.382792 -271.435755) (xy 119.420913 -271.40463) (xy 119.463534 -271.380023)
			(xy 119.50955 -271.362571) (xy 119.557769 -271.352727) (xy 119.606944 -271.350746) (xy 119.655799 -271.356678)
			(xy 119.70307 -271.37037) (xy 119.747532 -271.391468) (xy 119.788035 -271.419424) (xy 119.823528 -271.453516)
			(xy 119.853093 -271.49286) (xy 119.875964 -271.536437) (xy 119.891548 -271.583118) (xy 119.899443 -271.631695)
			(xy 119.899938 -271.656302) (xy 120.22888 -271.656302) (xy 120.23284 -271.607248) (xy 120.244617 -271.559464)
			(xy 120.263908 -271.514188) (xy 120.290211 -271.472592) (xy 120.322846 -271.435755) (xy 120.360967 -271.40463)
			(xy 120.403588 -271.380023) (xy 120.449604 -271.362571) (xy 120.497823 -271.352727) (xy 120.546998 -271.350746)
			(xy 120.595853 -271.356678) (xy 120.643124 -271.37037) (xy 120.687586 -271.391468) (xy 120.728089 -271.419424)
			(xy 120.763582 -271.453516) (xy 120.793147 -271.49286) (xy 120.816018 -271.536437) (xy 120.831602 -271.583118)
			(xy 120.839497 -271.631695) (xy 120.839992 -271.656302) (xy 121.168934 -271.656302) (xy 121.172894 -271.607248)
			(xy 121.184671 -271.559464) (xy 121.203962 -271.514188) (xy 121.230265 -271.472592) (xy 121.2629 -271.435755)
			(xy 121.301021 -271.40463) (xy 121.343642 -271.380023) (xy 121.389658 -271.362571) (xy 121.437877 -271.352727)
			(xy 121.487052 -271.350746) (xy 121.535907 -271.356678) (xy 121.583178 -271.37037) (xy 121.62764 -271.391468)
			(xy 121.668143 -271.419424) (xy 121.703636 -271.453516) (xy 121.733201 -271.49286) (xy 121.756072 -271.536437)
			(xy 121.771656 -271.583118) (xy 121.779551 -271.631695) (xy 121.780046 -271.656302) (xy 122.108988 -271.656302)
			(xy 122.112948 -271.607248) (xy 122.124725 -271.559464) (xy 122.144016 -271.514188) (xy 122.170319 -271.472592)
			(xy 122.202954 -271.435755) (xy 122.241075 -271.40463) (xy 122.283696 -271.380023) (xy 122.329712 -271.362571)
			(xy 122.377931 -271.352727) (xy 122.427106 -271.350746) (xy 122.475961 -271.356678) (xy 122.523232 -271.37037)
			(xy 122.567694 -271.391468) (xy 122.608197 -271.419424) (xy 122.64369 -271.453516) (xy 122.673255 -271.49286)
			(xy 122.696126 -271.536437) (xy 122.71171 -271.583118) (xy 122.719605 -271.631695) (xy 122.7201 -271.656302)
			(xy 123.049042 -271.656302) (xy 123.053002 -271.607248) (xy 123.064779 -271.559464) (xy 123.08407 -271.514188)
			(xy 123.110373 -271.472592) (xy 123.143008 -271.435755) (xy 123.181129 -271.40463) (xy 123.22375 -271.380023)
			(xy 123.269766 -271.362571) (xy 123.317985 -271.352727) (xy 123.36716 -271.350746) (xy 123.416015 -271.356678)
			(xy 123.463286 -271.37037) (xy 123.507748 -271.391468) (xy 123.548251 -271.419424) (xy 123.583744 -271.453516)
			(xy 123.613309 -271.49286) (xy 123.63618 -271.536437) (xy 123.651764 -271.583118) (xy 123.659659 -271.631695)
			(xy 123.660154 -271.656302) (xy 123.988842 -271.656302) (xy 123.992802 -271.607248) (xy 124.004579 -271.559464)
			(xy 124.02387 -271.514188) (xy 124.050173 -271.472592) (xy 124.082808 -271.435755) (xy 124.120929 -271.40463)
			(xy 124.16355 -271.380023) (xy 124.209566 -271.362571) (xy 124.257785 -271.352727) (xy 124.30696 -271.350746)
			(xy 124.355815 -271.356678) (xy 124.403086 -271.37037) (xy 124.447548 -271.391468) (xy 124.488051 -271.419424)
			(xy 124.523544 -271.453516) (xy 124.553109 -271.49286) (xy 124.57598 -271.536437) (xy 124.591564 -271.583118)
			(xy 124.599459 -271.631695) (xy 124.599954 -271.656302) (xy 124.928896 -271.656302) (xy 124.932856 -271.607248)
			(xy 124.944633 -271.559464) (xy 124.963924 -271.514188) (xy 124.990227 -271.472592) (xy 125.022862 -271.435755)
			(xy 125.060983 -271.40463) (xy 125.103604 -271.380023) (xy 125.14962 -271.362571) (xy 125.197839 -271.352727)
			(xy 125.247014 -271.350746) (xy 125.295869 -271.356678) (xy 125.34314 -271.37037) (xy 125.387602 -271.391468)
			(xy 125.428105 -271.419424) (xy 125.463598 -271.453516) (xy 125.493163 -271.49286) (xy 125.516034 -271.536437)
			(xy 125.531618 -271.583118) (xy 125.539513 -271.631695) (xy 125.540008 -271.656302) (xy 125.86895 -271.656302)
			(xy 125.87291 -271.607248) (xy 125.884687 -271.559464) (xy 125.903978 -271.514188) (xy 125.930281 -271.472592)
			(xy 125.962916 -271.435755) (xy 126.001037 -271.40463) (xy 126.043658 -271.380023) (xy 126.089674 -271.362571)
			(xy 126.137893 -271.352727) (xy 126.187068 -271.350746) (xy 126.235923 -271.356678) (xy 126.283194 -271.37037)
			(xy 126.327656 -271.391468) (xy 126.368159 -271.419424) (xy 126.403652 -271.453516) (xy 126.433217 -271.49286)
			(xy 126.456088 -271.536437) (xy 126.471672 -271.583118) (xy 126.479567 -271.631695) (xy 126.480062 -271.656302)
			(xy 126.479567 -271.680909) (xy 126.471672 -271.729486) (xy 126.456088 -271.776167) (xy 126.433217 -271.819744)
			(xy 126.403652 -271.859088) (xy 126.368159 -271.89318) (xy 126.327656 -271.921136) (xy 126.283194 -271.942234)
			(xy 126.235923 -271.955926) (xy 126.187068 -271.961858) (xy 126.137893 -271.959877) (xy 126.089674 -271.950033)
			(xy 126.043658 -271.932581) (xy 126.001037 -271.907974) (xy 125.962916 -271.876849) (xy 125.930281 -271.840012)
			(xy 125.903978 -271.798416) (xy 125.884687 -271.75314) (xy 125.87291 -271.705356) (xy 125.86895 -271.656302)
			(xy 125.540008 -271.656302) (xy 125.539513 -271.680909) (xy 125.531618 -271.729486) (xy 125.516034 -271.776167)
			(xy 125.493163 -271.819744) (xy 125.463598 -271.859088) (xy 125.428105 -271.89318) (xy 125.387602 -271.921136)
			(xy 125.34314 -271.942234) (xy 125.295869 -271.955926) (xy 125.247014 -271.961858) (xy 125.197839 -271.959877)
			(xy 125.14962 -271.950033) (xy 125.103604 -271.932581) (xy 125.060983 -271.907974) (xy 125.022862 -271.876849)
			(xy 124.990227 -271.840012) (xy 124.963924 -271.798416) (xy 124.944633 -271.75314) (xy 124.932856 -271.705356)
			(xy 124.928896 -271.656302) (xy 124.599954 -271.656302) (xy 124.599459 -271.680909) (xy 124.591564 -271.729486)
			(xy 124.57598 -271.776167) (xy 124.553109 -271.819744) (xy 124.523544 -271.859088) (xy 124.488051 -271.89318)
			(xy 124.447548 -271.921136) (xy 124.403086 -271.942234) (xy 124.355815 -271.955926) (xy 124.30696 -271.961858)
			(xy 124.257785 -271.959877) (xy 124.209566 -271.950033) (xy 124.16355 -271.932581) (xy 124.120929 -271.907974)
			(xy 124.082808 -271.876849) (xy 124.050173 -271.840012) (xy 124.02387 -271.798416) (xy 124.004579 -271.75314)
			(xy 123.992802 -271.705356) (xy 123.988842 -271.656302) (xy 123.660154 -271.656302) (xy 123.659659 -271.680909)
			(xy 123.651764 -271.729486) (xy 123.63618 -271.776167) (xy 123.613309 -271.819744) (xy 123.583744 -271.859088)
			(xy 123.548251 -271.89318) (xy 123.507748 -271.921136) (xy 123.463286 -271.942234) (xy 123.416015 -271.955926)
			(xy 123.36716 -271.961858) (xy 123.317985 -271.959877) (xy 123.269766 -271.950033) (xy 123.22375 -271.932581)
			(xy 123.181129 -271.907974) (xy 123.143008 -271.876849) (xy 123.110373 -271.840012) (xy 123.08407 -271.798416)
			(xy 123.064779 -271.75314) (xy 123.053002 -271.705356) (xy 123.049042 -271.656302) (xy 122.7201 -271.656302)
			(xy 122.719605 -271.680909) (xy 122.71171 -271.729486) (xy 122.696126 -271.776167) (xy 122.673255 -271.819744)
			(xy 122.64369 -271.859088) (xy 122.608197 -271.89318) (xy 122.567694 -271.921136) (xy 122.523232 -271.942234)
			(xy 122.475961 -271.955926) (xy 122.427106 -271.961858) (xy 122.377931 -271.959877) (xy 122.329712 -271.950033)
			(xy 122.283696 -271.932581) (xy 122.241075 -271.907974) (xy 122.202954 -271.876849) (xy 122.170319 -271.840012)
			(xy 122.144016 -271.798416) (xy 122.124725 -271.75314) (xy 122.112948 -271.705356) (xy 122.108988 -271.656302)
			(xy 121.780046 -271.656302) (xy 121.779551 -271.680909) (xy 121.771656 -271.729486) (xy 121.756072 -271.776167)
			(xy 121.733201 -271.819744) (xy 121.703636 -271.859088) (xy 121.668143 -271.89318) (xy 121.62764 -271.921136)
			(xy 121.583178 -271.942234) (xy 121.535907 -271.955926) (xy 121.487052 -271.961858) (xy 121.437877 -271.959877)
			(xy 121.389658 -271.950033) (xy 121.343642 -271.932581) (xy 121.301021 -271.907974) (xy 121.2629 -271.876849)
			(xy 121.230265 -271.840012) (xy 121.203962 -271.798416) (xy 121.184671 -271.75314) (xy 121.172894 -271.705356)
			(xy 121.168934 -271.656302) (xy 120.839992 -271.656302) (xy 120.839497 -271.680909) (xy 120.831602 -271.729486)
			(xy 120.816018 -271.776167) (xy 120.793147 -271.819744) (xy 120.763582 -271.859088) (xy 120.728089 -271.89318)
			(xy 120.687586 -271.921136) (xy 120.643124 -271.942234) (xy 120.595853 -271.955926) (xy 120.546998 -271.961858)
			(xy 120.497823 -271.959877) (xy 120.449604 -271.950033) (xy 120.403588 -271.932581) (xy 120.360967 -271.907974)
			(xy 120.322846 -271.876849) (xy 120.290211 -271.840012) (xy 120.263908 -271.798416) (xy 120.244617 -271.75314)
			(xy 120.23284 -271.705356) (xy 120.22888 -271.656302) (xy 119.899938 -271.656302) (xy 119.899443 -271.680909)
			(xy 119.891548 -271.729486) (xy 119.875964 -271.776167) (xy 119.853093 -271.819744) (xy 119.823528 -271.859088)
			(xy 119.788035 -271.89318) (xy 119.747532 -271.921136) (xy 119.70307 -271.942234) (xy 119.655799 -271.955926)
			(xy 119.606944 -271.961858) (xy 119.557769 -271.959877) (xy 119.50955 -271.950033) (xy 119.463534 -271.932581)
			(xy 119.420913 -271.907974) (xy 119.382792 -271.876849) (xy 119.350157 -271.840012) (xy 119.323854 -271.798416)
			(xy 119.304563 -271.75314) (xy 119.292786 -271.705356) (xy 119.288826 -271.656302) (xy 118.960138 -271.656302)
			(xy 118.959643 -271.680909) (xy 118.951748 -271.729486) (xy 118.936164 -271.776167) (xy 118.913293 -271.819744)
			(xy 118.883728 -271.859088) (xy 118.848235 -271.89318) (xy 118.807732 -271.921136) (xy 118.76327 -271.942234)
			(xy 118.715999 -271.955926) (xy 118.667144 -271.961858) (xy 118.617969 -271.959877) (xy 118.56975 -271.950033)
			(xy 118.523734 -271.932581) (xy 118.481113 -271.907974) (xy 118.442992 -271.876849) (xy 118.410357 -271.840012)
			(xy 118.384054 -271.798416) (xy 118.364763 -271.75314) (xy 118.352986 -271.705356) (xy 118.349026 -271.656302)
			(xy 118.020084 -271.656302) (xy 118.019589 -271.680909) (xy 118.011694 -271.729486) (xy 117.99611 -271.776167)
			(xy 117.973239 -271.819744) (xy 117.943674 -271.859088) (xy 117.908181 -271.89318) (xy 117.867678 -271.921136)
			(xy 117.823216 -271.942234) (xy 117.775945 -271.955926) (xy 117.72709 -271.961858) (xy 117.677915 -271.959877)
			(xy 117.629696 -271.950033) (xy 117.58368 -271.932581) (xy 117.541059 -271.907974) (xy 117.502938 -271.876849)
			(xy 117.470303 -271.840012) (xy 117.444 -271.798416) (xy 117.424709 -271.75314) (xy 117.412932 -271.705356)
			(xy 117.408972 -271.656302) (xy 117.08003 -271.656302) (xy 117.079535 -271.680909) (xy 117.07164 -271.729486)
			(xy 117.056056 -271.776167) (xy 117.033185 -271.819744) (xy 117.00362 -271.859088) (xy 116.968127 -271.89318)
			(xy 116.927624 -271.921136) (xy 116.883162 -271.942234) (xy 116.835891 -271.955926) (xy 116.787036 -271.961858)
			(xy 116.737861 -271.959877) (xy 116.689642 -271.950033) (xy 116.643626 -271.932581) (xy 116.601005 -271.907974)
			(xy 116.562884 -271.876849) (xy 116.530249 -271.840012) (xy 116.503946 -271.798416) (xy 116.484655 -271.75314)
			(xy 116.472878 -271.705356) (xy 116.468918 -271.656302) (xy 116.139976 -271.656302) (xy 116.139481 -271.680909)
			(xy 116.131586 -271.729486) (xy 116.116002 -271.776167) (xy 116.093131 -271.819744) (xy 116.063566 -271.859088)
			(xy 116.028073 -271.89318) (xy 115.98757 -271.921136) (xy 115.943108 -271.942234) (xy 115.895837 -271.955926)
			(xy 115.846982 -271.961858) (xy 115.797807 -271.959877) (xy 115.749588 -271.950033) (xy 115.703572 -271.932581)
			(xy 115.660951 -271.907974) (xy 115.62283 -271.876849) (xy 115.590195 -271.840012) (xy 115.563892 -271.798416)
			(xy 115.544601 -271.75314) (xy 115.532824 -271.705356) (xy 115.528864 -271.656302) (xy 108.626402 -271.656302)
			(xy 108.625907 -271.680909) (xy 108.618012 -271.729486) (xy 108.602428 -271.776167) (xy 108.579557 -271.819744)
			(xy 108.549992 -271.859088) (xy 108.514499 -271.89318) (xy 108.473996 -271.921136) (xy 108.429534 -271.942234)
			(xy 108.382263 -271.955926) (xy 108.333408 -271.961858) (xy 108.284233 -271.959877) (xy 108.236014 -271.950033)
			(xy 108.189998 -271.932581) (xy 108.147377 -271.907974) (xy 108.109256 -271.876849) (xy 108.076621 -271.840012)
			(xy 108.050318 -271.798416) (xy 108.031027 -271.75314) (xy 108.01925 -271.705356) (xy 108.01529 -271.656302)
			(xy 107.686348 -271.656302) (xy 107.685853 -271.680909) (xy 107.677958 -271.729486) (xy 107.662374 -271.776167)
			(xy 107.639503 -271.819744) (xy 107.609938 -271.859088) (xy 107.574445 -271.89318) (xy 107.533942 -271.921136)
			(xy 107.48948 -271.942234) (xy 107.442209 -271.955926) (xy 107.393354 -271.961858) (xy 107.344179 -271.959877)
			(xy 107.29596 -271.950033) (xy 107.249944 -271.932581) (xy 107.207323 -271.907974) (xy 107.169202 -271.876849)
			(xy 107.136567 -271.840012) (xy 107.110264 -271.798416) (xy 107.090973 -271.75314) (xy 107.079196 -271.705356)
			(xy 107.075236 -271.656302) (xy 106.746294 -271.656302) (xy 106.745799 -271.680909) (xy 106.737904 -271.729486)
			(xy 106.72232 -271.776167) (xy 106.699449 -271.819744) (xy 106.669884 -271.859088) (xy 106.634391 -271.89318)
			(xy 106.593888 -271.921136) (xy 106.549426 -271.942234) (xy 106.502155 -271.955926) (xy 106.4533 -271.961858)
			(xy 106.404125 -271.959877) (xy 106.355906 -271.950033) (xy 106.30989 -271.932581) (xy 106.267269 -271.907974)
			(xy 106.229148 -271.876849) (xy 106.196513 -271.840012) (xy 106.17021 -271.798416) (xy 106.150919 -271.75314)
			(xy 106.139142 -271.705356) (xy 106.135182 -271.656302) (xy 105.80624 -271.656302) (xy 105.805745 -271.680909)
			(xy 105.79785 -271.729486) (xy 105.782266 -271.776167) (xy 105.759395 -271.819744) (xy 105.72983 -271.859088)
			(xy 105.694337 -271.89318) (xy 105.653834 -271.921136) (xy 105.609372 -271.942234) (xy 105.562101 -271.955926)
			(xy 105.513246 -271.961858) (xy 105.464071 -271.959877) (xy 105.415852 -271.950033) (xy 105.369836 -271.932581)
			(xy 105.327215 -271.907974) (xy 105.289094 -271.876849) (xy 105.256459 -271.840012) (xy 105.230156 -271.798416)
			(xy 105.210865 -271.75314) (xy 105.199088 -271.705356) (xy 105.195128 -271.656302) (xy 104.86644 -271.656302)
			(xy 104.865945 -271.680909) (xy 104.85805 -271.729486) (xy 104.842466 -271.776167) (xy 104.819595 -271.819744)
			(xy 104.79003 -271.859088) (xy 104.754537 -271.89318) (xy 104.714034 -271.921136) (xy 104.669572 -271.942234)
			(xy 104.622301 -271.955926) (xy 104.573446 -271.961858) (xy 104.524271 -271.959877) (xy 104.476052 -271.950033)
			(xy 104.430036 -271.932581) (xy 104.387415 -271.907974) (xy 104.349294 -271.876849) (xy 104.316659 -271.840012)
			(xy 104.290356 -271.798416) (xy 104.271065 -271.75314) (xy 104.259288 -271.705356) (xy 104.255328 -271.656302)
			(xy 103.926386 -271.656302) (xy 103.925891 -271.680909) (xy 103.917996 -271.729486) (xy 103.902412 -271.776167)
			(xy 103.879541 -271.819744) (xy 103.849976 -271.859088) (xy 103.814483 -271.89318) (xy 103.77398 -271.921136)
			(xy 103.729518 -271.942234) (xy 103.682247 -271.955926) (xy 103.633392 -271.961858) (xy 103.584217 -271.959877)
			(xy 103.535998 -271.950033) (xy 103.489982 -271.932581) (xy 103.447361 -271.907974) (xy 103.40924 -271.876849)
			(xy 103.376605 -271.840012) (xy 103.350302 -271.798416) (xy 103.331011 -271.75314) (xy 103.319234 -271.705356)
			(xy 103.315274 -271.656302) (xy 102.986332 -271.656302) (xy 102.985837 -271.680909) (xy 102.977942 -271.729486)
			(xy 102.962358 -271.776167) (xy 102.939487 -271.819744) (xy 102.909922 -271.859088) (xy 102.874429 -271.89318)
			(xy 102.833926 -271.921136) (xy 102.789464 -271.942234) (xy 102.742193 -271.955926) (xy 102.693338 -271.961858)
			(xy 102.644163 -271.959877) (xy 102.595944 -271.950033) (xy 102.549928 -271.932581) (xy 102.507307 -271.907974)
			(xy 102.469186 -271.876849) (xy 102.436551 -271.840012) (xy 102.410248 -271.798416) (xy 102.390957 -271.75314)
			(xy 102.37918 -271.705356) (xy 102.37522 -271.656302) (xy 102.046278 -271.656302) (xy 102.045783 -271.680909)
			(xy 102.037888 -271.729486) (xy 102.022304 -271.776167) (xy 101.999433 -271.819744) (xy 101.969868 -271.859088)
			(xy 101.934375 -271.89318) (xy 101.893872 -271.921136) (xy 101.84941 -271.942234) (xy 101.802139 -271.955926)
			(xy 101.753284 -271.961858) (xy 101.704109 -271.959877) (xy 101.65589 -271.950033) (xy 101.609874 -271.932581)
			(xy 101.567253 -271.907974) (xy 101.529132 -271.876849) (xy 101.496497 -271.840012) (xy 101.470194 -271.798416)
			(xy 101.450903 -271.75314) (xy 101.439126 -271.705356) (xy 101.435166 -271.656302) (xy 101.106478 -271.656302)
			(xy 101.105983 -271.680909) (xy 101.098088 -271.729486) (xy 101.082504 -271.776167) (xy 101.059633 -271.819744)
			(xy 101.030068 -271.859088) (xy 100.994575 -271.89318) (xy 100.954072 -271.921136) (xy 100.90961 -271.942234)
			(xy 100.862339 -271.955926) (xy 100.813484 -271.961858) (xy 100.764309 -271.959877) (xy 100.71609 -271.950033)
			(xy 100.670074 -271.932581) (xy 100.627453 -271.907974) (xy 100.589332 -271.876849) (xy 100.556697 -271.840012)
			(xy 100.530394 -271.798416) (xy 100.511103 -271.75314) (xy 100.499326 -271.705356) (xy 100.495366 -271.656302)
			(xy 100.166424 -271.656302) (xy 100.165929 -271.680909) (xy 100.158034 -271.729486) (xy 100.14245 -271.776167)
			(xy 100.119579 -271.819744) (xy 100.090014 -271.859088) (xy 100.054521 -271.89318) (xy 100.014018 -271.921136)
			(xy 99.969556 -271.942234) (xy 99.922285 -271.955926) (xy 99.87343 -271.961858) (xy 99.824255 -271.959877)
			(xy 99.776036 -271.950033) (xy 99.73002 -271.932581) (xy 99.687399 -271.907974) (xy 99.649278 -271.876849)
			(xy 99.616643 -271.840012) (xy 99.59034 -271.798416) (xy 99.571049 -271.75314) (xy 99.559272 -271.705356)
			(xy 99.555312 -271.656302) (xy 99.22637 -271.656302) (xy 99.225875 -271.680909) (xy 99.21798 -271.729486)
			(xy 99.202396 -271.776167) (xy 99.179525 -271.819744) (xy 99.14996 -271.859088) (xy 99.114467 -271.89318)
			(xy 99.073964 -271.921136) (xy 99.029502 -271.942234) (xy 98.982231 -271.955926) (xy 98.933376 -271.961858)
			(xy 98.884201 -271.959877) (xy 98.835982 -271.950033) (xy 98.789966 -271.932581) (xy 98.747345 -271.907974)
			(xy 98.709224 -271.876849) (xy 98.676589 -271.840012) (xy 98.650286 -271.798416) (xy 98.630995 -271.75314)
			(xy 98.619218 -271.705356) (xy 98.615258 -271.656302) (xy 98.286316 -271.656302) (xy 98.285821 -271.680909)
			(xy 98.277926 -271.729486) (xy 98.262342 -271.776167) (xy 98.239471 -271.819744) (xy 98.209906 -271.859088)
			(xy 98.174413 -271.89318) (xy 98.13391 -271.921136) (xy 98.089448 -271.942234) (xy 98.042177 -271.955926)
			(xy 97.993322 -271.961858) (xy 97.944147 -271.959877) (xy 97.895928 -271.950033) (xy 97.849912 -271.932581)
			(xy 97.807291 -271.907974) (xy 97.76917 -271.876849) (xy 97.736535 -271.840012) (xy 97.710232 -271.798416)
			(xy 97.690941 -271.75314) (xy 97.679164 -271.705356) (xy 97.675204 -271.656302) (xy 97.346778 -271.656302)
			(xy 97.342825 -271.705334) (xy 97.331068 -271.7531) (xy 97.311811 -271.798365) (xy 97.285551 -271.839962)
			(xy 97.252967 -271.876814) (xy 97.234248 -271.892776) (xy 97.229676 -271.896332) (xy 97.223326 -271.90446)
			(xy 97.211134 -271.929098) (xy 97.208667 -271.934423) (xy 97.205963 -271.945839) (xy 97.2058 -271.951704)
			(xy 97.2058 -272.466308) (xy 99.085158 -272.466308) (xy 99.089118 -272.417254) (xy 99.100895 -272.36947)
			(xy 99.120186 -272.324194) (xy 99.146489 -272.282598) (xy 99.179124 -272.245761) (xy 99.217245 -272.214636)
			(xy 99.259866 -272.190029) (xy 99.305882 -272.172577) (xy 99.354101 -272.162733) (xy 99.403276 -272.160752)
			(xy 99.452131 -272.166684) (xy 99.499402 -272.180376) (xy 99.543864 -272.201474) (xy 99.584367 -272.22943)
			(xy 99.61986 -272.263522) (xy 99.649425 -272.302866) (xy 99.672296 -272.346443) (xy 99.68788 -272.393124)
			(xy 99.695775 -272.441701) (xy 99.69627 -272.466308) (xy 101.90532 -272.466308) (xy 101.90928 -272.417254)
			(xy 101.921057 -272.36947) (xy 101.940348 -272.324194) (xy 101.966651 -272.282598) (xy 101.999286 -272.245761)
			(xy 102.037407 -272.214636) (xy 102.080028 -272.190029) (xy 102.126044 -272.172577) (xy 102.174263 -272.162733)
			(xy 102.223438 -272.160752) (xy 102.272293 -272.166684) (xy 102.319564 -272.180376) (xy 102.364026 -272.201474)
			(xy 102.404529 -272.22943) (xy 102.440022 -272.263522) (xy 102.469587 -272.302866) (xy 102.492458 -272.346443)
			(xy 102.508042 -272.393124) (xy 102.515937 -272.441701) (xy 102.516432 -272.466308) (xy 104.725228 -272.466308)
			(xy 104.729188 -272.417254) (xy 104.740965 -272.36947) (xy 104.760256 -272.324194) (xy 104.786559 -272.282598)
			(xy 104.819194 -272.245761) (xy 104.857315 -272.214636) (xy 104.899936 -272.190029) (xy 104.945952 -272.172577)
			(xy 104.994171 -272.162733) (xy 105.043346 -272.160752) (xy 105.092201 -272.166684) (xy 105.139472 -272.180376)
			(xy 105.183934 -272.201474) (xy 105.224437 -272.22943) (xy 105.25993 -272.263522) (xy 105.289495 -272.302866)
			(xy 105.312366 -272.346443) (xy 105.32795 -272.393124) (xy 105.335845 -272.441701) (xy 105.33634 -272.466308)
			(xy 107.545136 -272.466308) (xy 107.549096 -272.417254) (xy 107.560873 -272.36947) (xy 107.580164 -272.324194)
			(xy 107.606467 -272.282598) (xy 107.639102 -272.245761) (xy 107.677223 -272.214636) (xy 107.719844 -272.190029)
			(xy 107.76586 -272.172577) (xy 107.814079 -272.162733) (xy 107.863254 -272.160752) (xy 107.912109 -272.166684)
			(xy 107.95938 -272.180376) (xy 108.003842 -272.201474) (xy 108.044345 -272.22943) (xy 108.079838 -272.263522)
			(xy 108.109403 -272.302866) (xy 108.132274 -272.346443) (xy 108.147858 -272.393124) (xy 108.155753 -272.441701)
			(xy 108.156248 -272.466308) (xy 108.48519 -272.466308) (xy 108.48915 -272.417254) (xy 108.500927 -272.36947)
			(xy 108.520218 -272.324194) (xy 108.546521 -272.282598) (xy 108.579156 -272.245761) (xy 108.617277 -272.214636)
			(xy 108.659898 -272.190029) (xy 108.705914 -272.172577) (xy 108.754133 -272.162733) (xy 108.803308 -272.160752)
			(xy 108.852163 -272.166684) (xy 108.899434 -272.180376) (xy 108.943896 -272.201474) (xy 108.984399 -272.22943)
			(xy 109.019892 -272.263522) (xy 109.049457 -272.302866) (xy 109.072328 -272.346443) (xy 109.087912 -272.393124)
			(xy 109.095807 -272.441701) (xy 109.096302 -272.466308) (xy 109.425244 -272.466308) (xy 109.429204 -272.417254)
			(xy 109.440981 -272.36947) (xy 109.460272 -272.324194) (xy 109.486575 -272.282598) (xy 109.51921 -272.245761)
			(xy 109.557331 -272.214636) (xy 109.599952 -272.190029) (xy 109.645968 -272.172577) (xy 109.694187 -272.162733)
			(xy 109.743362 -272.160752) (xy 109.792217 -272.166684) (xy 109.839488 -272.180376) (xy 109.88395 -272.201474)
			(xy 109.924453 -272.22943) (xy 109.959946 -272.263522) (xy 109.989511 -272.302866) (xy 110.012382 -272.346443)
			(xy 110.027966 -272.393124) (xy 110.035861 -272.441701) (xy 110.036356 -272.466308) (xy 110.365298 -272.466308)
			(xy 110.369258 -272.417254) (xy 110.381035 -272.36947) (xy 110.400326 -272.324194) (xy 110.426629 -272.282598)
			(xy 110.459264 -272.245761) (xy 110.497385 -272.214636) (xy 110.540006 -272.190029) (xy 110.586022 -272.172577)
			(xy 110.634241 -272.162733) (xy 110.683416 -272.160752) (xy 110.732271 -272.166684) (xy 110.779542 -272.180376)
			(xy 110.824004 -272.201474) (xy 110.864507 -272.22943) (xy 110.9 -272.263522) (xy 110.929565 -272.302866)
			(xy 110.952436 -272.346443) (xy 110.96802 -272.393124) (xy 110.975915 -272.441701) (xy 110.97641 -272.466308)
			(xy 113.178856 -272.466308) (xy 113.182816 -272.417254) (xy 113.194593 -272.36947) (xy 113.213884 -272.324194)
			(xy 113.240187 -272.282598) (xy 113.272822 -272.245761) (xy 113.310943 -272.214636) (xy 113.353564 -272.190029)
			(xy 113.39958 -272.172577) (xy 113.447799 -272.162733) (xy 113.496974 -272.160752) (xy 113.545829 -272.166684)
			(xy 113.5931 -272.180376) (xy 113.637562 -272.201474) (xy 113.678065 -272.22943) (xy 113.713558 -272.263522)
			(xy 113.743123 -272.302866) (xy 113.765994 -272.346443) (xy 113.781578 -272.393124) (xy 113.789473 -272.441701)
			(xy 113.789968 -272.466308) (xy 114.11891 -272.466308) (xy 114.12287 -272.417254) (xy 114.134647 -272.36947)
			(xy 114.153938 -272.324194) (xy 114.180241 -272.282598) (xy 114.212876 -272.245761) (xy 114.250997 -272.214636)
			(xy 114.293618 -272.190029) (xy 114.339634 -272.172577) (xy 114.387853 -272.162733) (xy 114.437028 -272.160752)
			(xy 114.485883 -272.166684) (xy 114.533154 -272.180376) (xy 114.577616 -272.201474) (xy 114.618119 -272.22943)
			(xy 114.653612 -272.263522) (xy 114.683177 -272.302866) (xy 114.706048 -272.346443) (xy 114.721632 -272.393124)
			(xy 114.729527 -272.441701) (xy 114.730022 -272.466308) (xy 115.058964 -272.466308) (xy 115.062924 -272.417254)
			(xy 115.074701 -272.36947) (xy 115.093992 -272.324194) (xy 115.120295 -272.282598) (xy 115.15293 -272.245761)
			(xy 115.191051 -272.214636) (xy 115.233672 -272.190029) (xy 115.279688 -272.172577) (xy 115.327907 -272.162733)
			(xy 115.377082 -272.160752) (xy 115.425937 -272.166684) (xy 115.473208 -272.180376) (xy 115.51767 -272.201474)
			(xy 115.558173 -272.22943) (xy 115.593666 -272.263522) (xy 115.623231 -272.302866) (xy 115.646102 -272.346443)
			(xy 115.661686 -272.393124) (xy 115.669581 -272.441701) (xy 115.670076 -272.466308) (xy 115.999018 -272.466308)
			(xy 116.002978 -272.417254) (xy 116.014755 -272.36947) (xy 116.034046 -272.324194) (xy 116.060349 -272.282598)
			(xy 116.092984 -272.245761) (xy 116.131105 -272.214636) (xy 116.173726 -272.190029) (xy 116.219742 -272.172577)
			(xy 116.267961 -272.162733) (xy 116.317136 -272.160752) (xy 116.365991 -272.166684) (xy 116.413262 -272.180376)
			(xy 116.457724 -272.201474) (xy 116.498227 -272.22943) (xy 116.53372 -272.263522) (xy 116.563285 -272.302866)
			(xy 116.586156 -272.346443) (xy 116.60174 -272.393124) (xy 116.609635 -272.441701) (xy 116.61013 -272.466308)
			(xy 118.818926 -272.466308) (xy 118.822886 -272.417254) (xy 118.834663 -272.36947) (xy 118.853954 -272.324194)
			(xy 118.880257 -272.282598) (xy 118.912892 -272.245761) (xy 118.951013 -272.214636) (xy 118.993634 -272.190029)
			(xy 119.03965 -272.172577) (xy 119.087869 -272.162733) (xy 119.137044 -272.160752) (xy 119.185899 -272.166684)
			(xy 119.23317 -272.180376) (xy 119.277632 -272.201474) (xy 119.318135 -272.22943) (xy 119.353628 -272.263522)
			(xy 119.383193 -272.302866) (xy 119.406064 -272.346443) (xy 119.421648 -272.393124) (xy 119.429543 -272.441701)
			(xy 119.430038 -272.466308) (xy 121.638834 -272.466308) (xy 121.642794 -272.417254) (xy 121.654571 -272.36947)
			(xy 121.673862 -272.324194) (xy 121.700165 -272.282598) (xy 121.7328 -272.245761) (xy 121.770921 -272.214636)
			(xy 121.813542 -272.190029) (xy 121.859558 -272.172577) (xy 121.907777 -272.162733) (xy 121.956952 -272.160752)
			(xy 122.005807 -272.166684) (xy 122.053078 -272.180376) (xy 122.09754 -272.201474) (xy 122.138043 -272.22943)
			(xy 122.173536 -272.263522) (xy 122.203101 -272.302866) (xy 122.225972 -272.346443) (xy 122.241556 -272.393124)
			(xy 122.249451 -272.441701) (xy 122.249946 -272.466308) (xy 124.458996 -272.466308) (xy 124.462956 -272.417254)
			(xy 124.474733 -272.36947) (xy 124.494024 -272.324194) (xy 124.520327 -272.282598) (xy 124.552962 -272.245761)
			(xy 124.591083 -272.214636) (xy 124.633704 -272.190029) (xy 124.67972 -272.172577) (xy 124.727939 -272.162733)
			(xy 124.777114 -272.160752) (xy 124.825969 -272.166684) (xy 124.87324 -272.180376) (xy 124.917702 -272.201474)
			(xy 124.958205 -272.22943) (xy 124.993698 -272.263522) (xy 125.023263 -272.302866) (xy 125.046134 -272.346443)
			(xy 125.061718 -272.393124) (xy 125.069613 -272.441701) (xy 125.070108 -272.466308) (xy 125.069613 -272.490915)
			(xy 125.061718 -272.539492) (xy 125.046134 -272.586173) (xy 125.023263 -272.62975) (xy 124.993698 -272.669094)
			(xy 124.958205 -272.703186) (xy 124.917702 -272.731142) (xy 124.87324 -272.75224) (xy 124.825969 -272.765932)
			(xy 124.777114 -272.771864) (xy 124.727939 -272.769883) (xy 124.67972 -272.760039) (xy 124.633704 -272.742587)
			(xy 124.591083 -272.71798) (xy 124.552962 -272.686855) (xy 124.520327 -272.650018) (xy 124.494024 -272.608422)
			(xy 124.474733 -272.563146) (xy 124.462956 -272.515362) (xy 124.458996 -272.466308) (xy 122.249946 -272.466308)
			(xy 122.249451 -272.490915) (xy 122.241556 -272.539492) (xy 122.225972 -272.586173) (xy 122.203101 -272.62975)
			(xy 122.173536 -272.669094) (xy 122.138043 -272.703186) (xy 122.09754 -272.731142) (xy 122.053078 -272.75224)
			(xy 122.005807 -272.765932) (xy 121.956952 -272.771864) (xy 121.907777 -272.769883) (xy 121.859558 -272.760039)
			(xy 121.813542 -272.742587) (xy 121.770921 -272.71798) (xy 121.7328 -272.686855) (xy 121.700165 -272.650018)
			(xy 121.673862 -272.608422) (xy 121.654571 -272.563146) (xy 121.642794 -272.515362) (xy 121.638834 -272.466308)
			(xy 119.430038 -272.466308) (xy 119.429543 -272.490915) (xy 119.421648 -272.539492) (xy 119.406064 -272.586173)
			(xy 119.383193 -272.62975) (xy 119.353628 -272.669094) (xy 119.318135 -272.703186) (xy 119.277632 -272.731142)
			(xy 119.23317 -272.75224) (xy 119.185899 -272.765932) (xy 119.137044 -272.771864) (xy 119.087869 -272.769883)
			(xy 119.03965 -272.760039) (xy 118.993634 -272.742587) (xy 118.951013 -272.71798) (xy 118.912892 -272.686855)
			(xy 118.880257 -272.650018) (xy 118.853954 -272.608422) (xy 118.834663 -272.563146) (xy 118.822886 -272.515362)
			(xy 118.818926 -272.466308) (xy 116.61013 -272.466308) (xy 116.609635 -272.490915) (xy 116.60174 -272.539492)
			(xy 116.586156 -272.586173) (xy 116.563285 -272.62975) (xy 116.53372 -272.669094) (xy 116.498227 -272.703186)
			(xy 116.457724 -272.731142) (xy 116.413262 -272.75224) (xy 116.365991 -272.765932) (xy 116.317136 -272.771864)
			(xy 116.267961 -272.769883) (xy 116.219742 -272.760039) (xy 116.173726 -272.742587) (xy 116.131105 -272.71798)
			(xy 116.092984 -272.686855) (xy 116.060349 -272.650018) (xy 116.034046 -272.608422) (xy 116.014755 -272.563146)
			(xy 116.002978 -272.515362) (xy 115.999018 -272.466308) (xy 115.670076 -272.466308) (xy 115.669581 -272.490915)
			(xy 115.661686 -272.539492) (xy 115.646102 -272.586173) (xy 115.623231 -272.62975) (xy 115.593666 -272.669094)
			(xy 115.558173 -272.703186) (xy 115.51767 -272.731142) (xy 115.473208 -272.75224) (xy 115.425937 -272.765932)
			(xy 115.377082 -272.771864) (xy 115.327907 -272.769883) (xy 115.279688 -272.760039) (xy 115.233672 -272.742587)
			(xy 115.191051 -272.71798) (xy 115.15293 -272.686855) (xy 115.120295 -272.650018) (xy 115.093992 -272.608422)
			(xy 115.074701 -272.563146) (xy 115.062924 -272.515362) (xy 115.058964 -272.466308) (xy 114.730022 -272.466308)
			(xy 114.729527 -272.490915) (xy 114.721632 -272.539492) (xy 114.706048 -272.586173) (xy 114.683177 -272.62975)
			(xy 114.653612 -272.669094) (xy 114.618119 -272.703186) (xy 114.577616 -272.731142) (xy 114.533154 -272.75224)
			(xy 114.485883 -272.765932) (xy 114.437028 -272.771864) (xy 114.387853 -272.769883) (xy 114.339634 -272.760039)
			(xy 114.293618 -272.742587) (xy 114.250997 -272.71798) (xy 114.212876 -272.686855) (xy 114.180241 -272.650018)
			(xy 114.153938 -272.608422) (xy 114.134647 -272.563146) (xy 114.12287 -272.515362) (xy 114.11891 -272.466308)
			(xy 113.789968 -272.466308) (xy 113.789473 -272.490915) (xy 113.781578 -272.539492) (xy 113.765994 -272.586173)
			(xy 113.743123 -272.62975) (xy 113.713558 -272.669094) (xy 113.678065 -272.703186) (xy 113.637562 -272.731142)
			(xy 113.5931 -272.75224) (xy 113.545829 -272.765932) (xy 113.496974 -272.771864) (xy 113.447799 -272.769883)
			(xy 113.39958 -272.760039) (xy 113.353564 -272.742587) (xy 113.310943 -272.71798) (xy 113.272822 -272.686855)
			(xy 113.240187 -272.650018) (xy 113.213884 -272.608422) (xy 113.194593 -272.563146) (xy 113.182816 -272.515362)
			(xy 113.178856 -272.466308) (xy 110.97641 -272.466308) (xy 110.975915 -272.490915) (xy 110.96802 -272.539492)
			(xy 110.952436 -272.586173) (xy 110.929565 -272.62975) (xy 110.9 -272.669094) (xy 110.864507 -272.703186)
			(xy 110.824004 -272.731142) (xy 110.779542 -272.75224) (xy 110.732271 -272.765932) (xy 110.683416 -272.771864)
			(xy 110.634241 -272.769883) (xy 110.586022 -272.760039) (xy 110.540006 -272.742587) (xy 110.497385 -272.71798)
			(xy 110.459264 -272.686855) (xy 110.426629 -272.650018) (xy 110.400326 -272.608422) (xy 110.381035 -272.563146)
			(xy 110.369258 -272.515362) (xy 110.365298 -272.466308) (xy 110.036356 -272.466308) (xy 110.035861 -272.490915)
			(xy 110.027966 -272.539492) (xy 110.012382 -272.586173) (xy 109.989511 -272.62975) (xy 109.959946 -272.669094)
			(xy 109.924453 -272.703186) (xy 109.88395 -272.731142) (xy 109.839488 -272.75224) (xy 109.792217 -272.765932)
			(xy 109.743362 -272.771864) (xy 109.694187 -272.769883) (xy 109.645968 -272.760039) (xy 109.599952 -272.742587)
			(xy 109.557331 -272.71798) (xy 109.51921 -272.686855) (xy 109.486575 -272.650018) (xy 109.460272 -272.608422)
			(xy 109.440981 -272.563146) (xy 109.429204 -272.515362) (xy 109.425244 -272.466308) (xy 109.096302 -272.466308)
			(xy 109.095807 -272.490915) (xy 109.087912 -272.539492) (xy 109.072328 -272.586173) (xy 109.049457 -272.62975)
			(xy 109.019892 -272.669094) (xy 108.984399 -272.703186) (xy 108.943896 -272.731142) (xy 108.899434 -272.75224)
			(xy 108.852163 -272.765932) (xy 108.803308 -272.771864) (xy 108.754133 -272.769883) (xy 108.705914 -272.760039)
			(xy 108.659898 -272.742587) (xy 108.617277 -272.71798) (xy 108.579156 -272.686855) (xy 108.546521 -272.650018)
			(xy 108.520218 -272.608422) (xy 108.500927 -272.563146) (xy 108.48915 -272.515362) (xy 108.48519 -272.466308)
			(xy 108.156248 -272.466308) (xy 108.155753 -272.490915) (xy 108.147858 -272.539492) (xy 108.132274 -272.586173)
			(xy 108.109403 -272.62975) (xy 108.079838 -272.669094) (xy 108.044345 -272.703186) (xy 108.003842 -272.731142)
			(xy 107.95938 -272.75224) (xy 107.912109 -272.765932) (xy 107.863254 -272.771864) (xy 107.814079 -272.769883)
			(xy 107.76586 -272.760039) (xy 107.719844 -272.742587) (xy 107.677223 -272.71798) (xy 107.639102 -272.686855)
			(xy 107.606467 -272.650018) (xy 107.580164 -272.608422) (xy 107.560873 -272.563146) (xy 107.549096 -272.515362)
			(xy 107.545136 -272.466308) (xy 105.33634 -272.466308) (xy 105.335845 -272.490915) (xy 105.32795 -272.539492)
			(xy 105.312366 -272.586173) (xy 105.289495 -272.62975) (xy 105.25993 -272.669094) (xy 105.224437 -272.703186)
			(xy 105.183934 -272.731142) (xy 105.139472 -272.75224) (xy 105.092201 -272.765932) (xy 105.043346 -272.771864)
			(xy 104.994171 -272.769883) (xy 104.945952 -272.760039) (xy 104.899936 -272.742587) (xy 104.857315 -272.71798)
			(xy 104.819194 -272.686855) (xy 104.786559 -272.650018) (xy 104.760256 -272.608422) (xy 104.740965 -272.563146)
			(xy 104.729188 -272.515362) (xy 104.725228 -272.466308) (xy 102.516432 -272.466308) (xy 102.515937 -272.490915)
			(xy 102.508042 -272.539492) (xy 102.492458 -272.586173) (xy 102.469587 -272.62975) (xy 102.440022 -272.669094)
			(xy 102.404529 -272.703186) (xy 102.364026 -272.731142) (xy 102.319564 -272.75224) (xy 102.272293 -272.765932)
			(xy 102.223438 -272.771864) (xy 102.174263 -272.769883) (xy 102.126044 -272.760039) (xy 102.080028 -272.742587)
			(xy 102.037407 -272.71798) (xy 101.999286 -272.686855) (xy 101.966651 -272.650018) (xy 101.940348 -272.608422)
			(xy 101.921057 -272.563146) (xy 101.90928 -272.515362) (xy 101.90532 -272.466308) (xy 99.69627 -272.466308)
			(xy 99.695775 -272.490915) (xy 99.68788 -272.539492) (xy 99.672296 -272.586173) (xy 99.649425 -272.62975)
			(xy 99.61986 -272.669094) (xy 99.584367 -272.703186) (xy 99.543864 -272.731142) (xy 99.499402 -272.75224)
			(xy 99.452131 -272.765932) (xy 99.403276 -272.771864) (xy 99.354101 -272.769883) (xy 99.305882 -272.760039)
			(xy 99.259866 -272.742587) (xy 99.217245 -272.71798) (xy 99.179124 -272.686855) (xy 99.146489 -272.650018)
			(xy 99.120186 -272.608422) (xy 99.100895 -272.563146) (xy 99.089118 -272.515362) (xy 99.085158 -272.466308)
			(xy 97.2058 -272.466308) (xy 97.2058 -272.980912) (xy 97.20596 -272.98678) (xy 97.208644 -272.998203)
			(xy 97.211134 -273.003518) (xy 97.223326 -273.028156) (xy 97.229676 -273.036284) (xy 97.234248 -273.03984)
			(xy 97.252968 -273.0558) (xy 97.28555 -273.092652) (xy 97.311808 -273.134248) (xy 97.331062 -273.179513)
			(xy 97.342817 -273.227278) (xy 97.346769 -273.276309) (xy 97.346769 -273.276314) (xy 97.675204 -273.276314)
			(xy 97.679164 -273.22726) (xy 97.690941 -273.179476) (xy 97.710232 -273.1342) (xy 97.736535 -273.092604)
			(xy 97.76917 -273.055767) (xy 97.807291 -273.024642) (xy 97.849912 -273.000035) (xy 97.895928 -272.982583)
			(xy 97.944147 -272.972739) (xy 97.993322 -272.970758) (xy 98.042177 -272.97669) (xy 98.089448 -272.990382)
			(xy 98.13391 -273.01148) (xy 98.174413 -273.039436) (xy 98.209906 -273.073528) (xy 98.239471 -273.112872)
			(xy 98.262342 -273.156449) (xy 98.277926 -273.20313) (xy 98.285821 -273.251707) (xy 98.286316 -273.276314)
			(xy 98.615258 -273.276314) (xy 98.619218 -273.22726) (xy 98.630995 -273.179476) (xy 98.650286 -273.1342)
			(xy 98.676589 -273.092604) (xy 98.709224 -273.055767) (xy 98.747345 -273.024642) (xy 98.789966 -273.000035)
			(xy 98.835982 -272.982583) (xy 98.884201 -272.972739) (xy 98.933376 -272.970758) (xy 98.982231 -272.97669)
			(xy 99.029502 -272.990382) (xy 99.073964 -273.01148) (xy 99.114467 -273.039436) (xy 99.14996 -273.073528)
			(xy 99.179525 -273.112872) (xy 99.202396 -273.156449) (xy 99.21798 -273.20313) (xy 99.225875 -273.251707)
			(xy 99.22637 -273.276314) (xy 99.555312 -273.276314) (xy 99.559272 -273.22726) (xy 99.571049 -273.179476)
			(xy 99.59034 -273.1342) (xy 99.616643 -273.092604) (xy 99.649278 -273.055767) (xy 99.687399 -273.024642)
			(xy 99.73002 -273.000035) (xy 99.776036 -272.982583) (xy 99.824255 -272.972739) (xy 99.87343 -272.970758)
			(xy 99.922285 -272.97669) (xy 99.969556 -272.990382) (xy 100.014018 -273.01148) (xy 100.054521 -273.039436)
			(xy 100.090014 -273.073528) (xy 100.119579 -273.112872) (xy 100.14245 -273.156449) (xy 100.158034 -273.20313)
			(xy 100.165929 -273.251707) (xy 100.166424 -273.276314) (xy 100.495366 -273.276314) (xy 100.499326 -273.22726)
			(xy 100.511103 -273.179476) (xy 100.530394 -273.1342) (xy 100.556697 -273.092604) (xy 100.589332 -273.055767)
			(xy 100.627453 -273.024642) (xy 100.670074 -273.000035) (xy 100.71609 -272.982583) (xy 100.764309 -272.972739)
			(xy 100.813484 -272.970758) (xy 100.862339 -272.97669) (xy 100.90961 -272.990382) (xy 100.954072 -273.01148)
			(xy 100.994575 -273.039436) (xy 101.030068 -273.073528) (xy 101.059633 -273.112872) (xy 101.082504 -273.156449)
			(xy 101.098088 -273.20313) (xy 101.105983 -273.251707) (xy 101.106478 -273.276314) (xy 101.435166 -273.276314)
			(xy 101.439126 -273.22726) (xy 101.450903 -273.179476) (xy 101.470194 -273.1342) (xy 101.496497 -273.092604)
			(xy 101.529132 -273.055767) (xy 101.567253 -273.024642) (xy 101.609874 -273.000035) (xy 101.65589 -272.982583)
			(xy 101.704109 -272.972739) (xy 101.753284 -272.970758) (xy 101.802139 -272.97669) (xy 101.84941 -272.990382)
			(xy 101.893872 -273.01148) (xy 101.934375 -273.039436) (xy 101.969868 -273.073528) (xy 101.999433 -273.112872)
			(xy 102.022304 -273.156449) (xy 102.037888 -273.20313) (xy 102.045783 -273.251707) (xy 102.046278 -273.276314)
			(xy 102.37522 -273.276314) (xy 102.37918 -273.22726) (xy 102.390957 -273.179476) (xy 102.410248 -273.1342)
			(xy 102.436551 -273.092604) (xy 102.469186 -273.055767) (xy 102.507307 -273.024642) (xy 102.549928 -273.000035)
			(xy 102.595944 -272.982583) (xy 102.644163 -272.972739) (xy 102.693338 -272.970758) (xy 102.742193 -272.97669)
			(xy 102.789464 -272.990382) (xy 102.833926 -273.01148) (xy 102.874429 -273.039436) (xy 102.909922 -273.073528)
			(xy 102.939487 -273.112872) (xy 102.962358 -273.156449) (xy 102.977942 -273.20313) (xy 102.985837 -273.251707)
			(xy 102.986332 -273.276314) (xy 103.315274 -273.276314) (xy 103.319234 -273.22726) (xy 103.331011 -273.179476)
			(xy 103.350302 -273.1342) (xy 103.376605 -273.092604) (xy 103.40924 -273.055767) (xy 103.447361 -273.024642)
			(xy 103.489982 -273.000035) (xy 103.535998 -272.982583) (xy 103.584217 -272.972739) (xy 103.633392 -272.970758)
			(xy 103.682247 -272.97669) (xy 103.729518 -272.990382) (xy 103.77398 -273.01148) (xy 103.814483 -273.039436)
			(xy 103.849976 -273.073528) (xy 103.879541 -273.112872) (xy 103.902412 -273.156449) (xy 103.917996 -273.20313)
			(xy 103.925891 -273.251707) (xy 103.926386 -273.276314) (xy 104.255328 -273.276314) (xy 104.259288 -273.22726)
			(xy 104.271065 -273.179476) (xy 104.290356 -273.1342) (xy 104.316659 -273.092604) (xy 104.349294 -273.055767)
			(xy 104.387415 -273.024642) (xy 104.430036 -273.000035) (xy 104.476052 -272.982583) (xy 104.524271 -272.972739)
			(xy 104.573446 -272.970758) (xy 104.622301 -272.97669) (xy 104.669572 -272.990382) (xy 104.714034 -273.01148)
			(xy 104.754537 -273.039436) (xy 104.79003 -273.073528) (xy 104.819595 -273.112872) (xy 104.842466 -273.156449)
			(xy 104.85805 -273.20313) (xy 104.865945 -273.251707) (xy 104.86644 -273.276314) (xy 105.195128 -273.276314)
			(xy 105.199088 -273.22726) (xy 105.210865 -273.179476) (xy 105.230156 -273.1342) (xy 105.256459 -273.092604)
			(xy 105.289094 -273.055767) (xy 105.327215 -273.024642) (xy 105.369836 -273.000035) (xy 105.415852 -272.982583)
			(xy 105.464071 -272.972739) (xy 105.513246 -272.970758) (xy 105.562101 -272.97669) (xy 105.609372 -272.990382)
			(xy 105.653834 -273.01148) (xy 105.694337 -273.039436) (xy 105.72983 -273.073528) (xy 105.759395 -273.112872)
			(xy 105.782266 -273.156449) (xy 105.79785 -273.20313) (xy 105.805745 -273.251707) (xy 105.80624 -273.276314)
			(xy 106.135182 -273.276314) (xy 106.139142 -273.22726) (xy 106.150919 -273.179476) (xy 106.17021 -273.1342)
			(xy 106.196513 -273.092604) (xy 106.229148 -273.055767) (xy 106.267269 -273.024642) (xy 106.30989 -273.000035)
			(xy 106.355906 -272.982583) (xy 106.404125 -272.972739) (xy 106.4533 -272.970758) (xy 106.502155 -272.97669)
			(xy 106.549426 -272.990382) (xy 106.593888 -273.01148) (xy 106.634391 -273.039436) (xy 106.669884 -273.073528)
			(xy 106.699449 -273.112872) (xy 106.72232 -273.156449) (xy 106.737904 -273.20313) (xy 106.745799 -273.251707)
			(xy 106.746294 -273.276314) (xy 107.075236 -273.276314) (xy 107.079196 -273.22726) (xy 107.090973 -273.179476)
			(xy 107.110264 -273.1342) (xy 107.136567 -273.092604) (xy 107.169202 -273.055767) (xy 107.207323 -273.024642)
			(xy 107.249944 -273.000035) (xy 107.29596 -272.982583) (xy 107.344179 -272.972739) (xy 107.393354 -272.970758)
			(xy 107.442209 -272.97669) (xy 107.48948 -272.990382) (xy 107.533942 -273.01148) (xy 107.574445 -273.039436)
			(xy 107.609938 -273.073528) (xy 107.639503 -273.112872) (xy 107.662374 -273.156449) (xy 107.677958 -273.20313)
			(xy 107.685853 -273.251707) (xy 107.686348 -273.276314) (xy 108.01529 -273.276314) (xy 108.01925 -273.22726)
			(xy 108.031027 -273.179476) (xy 108.050318 -273.1342) (xy 108.076621 -273.092604) (xy 108.109256 -273.055767)
			(xy 108.147377 -273.024642) (xy 108.189998 -273.000035) (xy 108.236014 -272.982583) (xy 108.284233 -272.972739)
			(xy 108.333408 -272.970758) (xy 108.382263 -272.97669) (xy 108.429534 -272.990382) (xy 108.473996 -273.01148)
			(xy 108.514499 -273.039436) (xy 108.549992 -273.073528) (xy 108.579557 -273.112872) (xy 108.602428 -273.156449)
			(xy 108.618012 -273.20313) (xy 108.625907 -273.251707) (xy 108.626402 -273.276314) (xy 108.955344 -273.276314)
			(xy 108.959304 -273.22726) (xy 108.971081 -273.179476) (xy 108.990372 -273.1342) (xy 109.016675 -273.092604)
			(xy 109.04931 -273.055767) (xy 109.087431 -273.024642) (xy 109.130052 -273.000035) (xy 109.176068 -272.982583)
			(xy 109.224287 -272.972739) (xy 109.273462 -272.970758) (xy 109.322317 -272.97669) (xy 109.369588 -272.990382)
			(xy 109.41405 -273.01148) (xy 109.454553 -273.039436) (xy 109.490046 -273.073528) (xy 109.519611 -273.112872)
			(xy 109.542482 -273.156449) (xy 109.558066 -273.20313) (xy 109.565961 -273.251707) (xy 109.566456 -273.276314)
			(xy 109.895144 -273.276314) (xy 109.899104 -273.22726) (xy 109.910881 -273.179476) (xy 109.930172 -273.1342)
			(xy 109.956475 -273.092604) (xy 109.98911 -273.055767) (xy 110.027231 -273.024642) (xy 110.069852 -273.000035)
			(xy 110.115868 -272.982583) (xy 110.164087 -272.972739) (xy 110.213262 -272.970758) (xy 110.262117 -272.97669)
			(xy 110.309388 -272.990382) (xy 110.35385 -273.01148) (xy 110.394353 -273.039436) (xy 110.429846 -273.073528)
			(xy 110.459411 -273.112872) (xy 110.482282 -273.156449) (xy 110.497866 -273.20313) (xy 110.505761 -273.251707)
			(xy 110.506256 -273.276314) (xy 113.64901 -273.276314) (xy 113.65297 -273.22726) (xy 113.664747 -273.179476)
			(xy 113.684038 -273.1342) (xy 113.710341 -273.092604) (xy 113.742976 -273.055767) (xy 113.781097 -273.024642)
			(xy 113.823718 -273.000035) (xy 113.869734 -272.982583) (xy 113.917953 -272.972739) (xy 113.967128 -272.970758)
			(xy 114.015983 -272.97669) (xy 114.063254 -272.990382) (xy 114.107716 -273.01148) (xy 114.148219 -273.039436)
			(xy 114.183712 -273.073528) (xy 114.213277 -273.112872) (xy 114.236148 -273.156449) (xy 114.251732 -273.20313)
			(xy 114.259627 -273.251707) (xy 114.260122 -273.276314) (xy 114.58881 -273.276314) (xy 114.59277 -273.22726)
			(xy 114.604547 -273.179476) (xy 114.623838 -273.1342) (xy 114.650141 -273.092604) (xy 114.682776 -273.055767)
			(xy 114.720897 -273.024642) (xy 114.763518 -273.000035) (xy 114.809534 -272.982583) (xy 114.857753 -272.972739)
			(xy 114.906928 -272.970758) (xy 114.955783 -272.97669) (xy 115.003054 -272.990382) (xy 115.047516 -273.01148)
			(xy 115.088019 -273.039436) (xy 115.123512 -273.073528) (xy 115.153077 -273.112872) (xy 115.175948 -273.156449)
			(xy 115.191532 -273.20313) (xy 115.199427 -273.251707) (xy 115.199922 -273.276314) (xy 115.528864 -273.276314)
			(xy 115.532824 -273.22726) (xy 115.544601 -273.179476) (xy 115.563892 -273.1342) (xy 115.590195 -273.092604)
			(xy 115.62283 -273.055767) (xy 115.660951 -273.024642) (xy 115.703572 -273.000035) (xy 115.749588 -272.982583)
			(xy 115.797807 -272.972739) (xy 115.846982 -272.970758) (xy 115.895837 -272.97669) (xy 115.943108 -272.990382)
			(xy 115.98757 -273.01148) (xy 116.028073 -273.039436) (xy 116.063566 -273.073528) (xy 116.093131 -273.112872)
			(xy 116.116002 -273.156449) (xy 116.131586 -273.20313) (xy 116.139481 -273.251707) (xy 116.139976 -273.276314)
			(xy 116.468918 -273.276314) (xy 116.472878 -273.22726) (xy 116.484655 -273.179476) (xy 116.503946 -273.1342)
			(xy 116.530249 -273.092604) (xy 116.562884 -273.055767) (xy 116.601005 -273.024642) (xy 116.643626 -273.000035)
			(xy 116.689642 -272.982583) (xy 116.737861 -272.972739) (xy 116.787036 -272.970758) (xy 116.835891 -272.97669)
			(xy 116.883162 -272.990382) (xy 116.927624 -273.01148) (xy 116.968127 -273.039436) (xy 117.00362 -273.073528)
			(xy 117.033185 -273.112872) (xy 117.056056 -273.156449) (xy 117.07164 -273.20313) (xy 117.079535 -273.251707)
			(xy 117.08003 -273.276314) (xy 117.408972 -273.276314) (xy 117.412932 -273.22726) (xy 117.424709 -273.179476)
			(xy 117.444 -273.1342) (xy 117.470303 -273.092604) (xy 117.502938 -273.055767) (xy 117.541059 -273.024642)
			(xy 117.58368 -273.000035) (xy 117.629696 -272.982583) (xy 117.677915 -272.972739) (xy 117.72709 -272.970758)
			(xy 117.775945 -272.97669) (xy 117.823216 -272.990382) (xy 117.867678 -273.01148) (xy 117.908181 -273.039436)
			(xy 117.943674 -273.073528) (xy 117.973239 -273.112872) (xy 117.99611 -273.156449) (xy 118.011694 -273.20313)
			(xy 118.019589 -273.251707) (xy 118.020084 -273.276314) (xy 118.349026 -273.276314) (xy 118.352986 -273.22726)
			(xy 118.364763 -273.179476) (xy 118.384054 -273.1342) (xy 118.410357 -273.092604) (xy 118.442992 -273.055767)
			(xy 118.481113 -273.024642) (xy 118.523734 -273.000035) (xy 118.56975 -272.982583) (xy 118.617969 -272.972739)
			(xy 118.667144 -272.970758) (xy 118.715999 -272.97669) (xy 118.76327 -272.990382) (xy 118.807732 -273.01148)
			(xy 118.848235 -273.039436) (xy 118.883728 -273.073528) (xy 118.913293 -273.112872) (xy 118.936164 -273.156449)
			(xy 118.951748 -273.20313) (xy 118.959643 -273.251707) (xy 118.960138 -273.276314) (xy 119.288826 -273.276314)
			(xy 119.292786 -273.22726) (xy 119.304563 -273.179476) (xy 119.323854 -273.1342) (xy 119.350157 -273.092604)
			(xy 119.382792 -273.055767) (xy 119.420913 -273.024642) (xy 119.463534 -273.000035) (xy 119.50955 -272.982583)
			(xy 119.557769 -272.972739) (xy 119.606944 -272.970758) (xy 119.655799 -272.97669) (xy 119.70307 -272.990382)
			(xy 119.747532 -273.01148) (xy 119.788035 -273.039436) (xy 119.823528 -273.073528) (xy 119.853093 -273.112872)
			(xy 119.875964 -273.156449) (xy 119.891548 -273.20313) (xy 119.899443 -273.251707) (xy 119.899938 -273.276314)
			(xy 120.22888 -273.276314) (xy 120.23284 -273.22726) (xy 120.244617 -273.179476) (xy 120.263908 -273.1342)
			(xy 120.290211 -273.092604) (xy 120.322846 -273.055767) (xy 120.360967 -273.024642) (xy 120.403588 -273.000035)
			(xy 120.449604 -272.982583) (xy 120.497823 -272.972739) (xy 120.546998 -272.970758) (xy 120.595853 -272.97669)
			(xy 120.643124 -272.990382) (xy 120.687586 -273.01148) (xy 120.728089 -273.039436) (xy 120.763582 -273.073528)
			(xy 120.793147 -273.112872) (xy 120.816018 -273.156449) (xy 120.831602 -273.20313) (xy 120.839497 -273.251707)
			(xy 120.839992 -273.276314) (xy 121.168934 -273.276314) (xy 121.172894 -273.22726) (xy 121.184671 -273.179476)
			(xy 121.203962 -273.1342) (xy 121.230265 -273.092604) (xy 121.2629 -273.055767) (xy 121.301021 -273.024642)
			(xy 121.343642 -273.000035) (xy 121.389658 -272.982583) (xy 121.437877 -272.972739) (xy 121.487052 -272.970758)
			(xy 121.535907 -272.97669) (xy 121.583178 -272.990382) (xy 121.62764 -273.01148) (xy 121.668143 -273.039436)
			(xy 121.703636 -273.073528) (xy 121.733201 -273.112872) (xy 121.756072 -273.156449) (xy 121.771656 -273.20313)
			(xy 121.779551 -273.251707) (xy 121.780046 -273.276314) (xy 122.108988 -273.276314) (xy 122.112948 -273.22726)
			(xy 122.124725 -273.179476) (xy 122.144016 -273.1342) (xy 122.170319 -273.092604) (xy 122.202954 -273.055767)
			(xy 122.241075 -273.024642) (xy 122.283696 -273.000035) (xy 122.329712 -272.982583) (xy 122.377931 -272.972739)
			(xy 122.427106 -272.970758) (xy 122.475961 -272.97669) (xy 122.523232 -272.990382) (xy 122.567694 -273.01148)
			(xy 122.608197 -273.039436) (xy 122.64369 -273.073528) (xy 122.673255 -273.112872) (xy 122.696126 -273.156449)
			(xy 122.71171 -273.20313) (xy 122.719605 -273.251707) (xy 122.7201 -273.276314) (xy 123.049042 -273.276314)
			(xy 123.053002 -273.22726) (xy 123.064779 -273.179476) (xy 123.08407 -273.1342) (xy 123.110373 -273.092604)
			(xy 123.143008 -273.055767) (xy 123.181129 -273.024642) (xy 123.22375 -273.000035) (xy 123.269766 -272.982583)
			(xy 123.317985 -272.972739) (xy 123.36716 -272.970758) (xy 123.416015 -272.97669) (xy 123.463286 -272.990382)
			(xy 123.507748 -273.01148) (xy 123.548251 -273.039436) (xy 123.583744 -273.073528) (xy 123.613309 -273.112872)
			(xy 123.63618 -273.156449) (xy 123.651764 -273.20313) (xy 123.659659 -273.251707) (xy 123.660154 -273.276314)
			(xy 123.988842 -273.276314) (xy 123.992802 -273.22726) (xy 124.004579 -273.179476) (xy 124.02387 -273.1342)
			(xy 124.050173 -273.092604) (xy 124.082808 -273.055767) (xy 124.120929 -273.024642) (xy 124.16355 -273.000035)
			(xy 124.209566 -272.982583) (xy 124.257785 -272.972739) (xy 124.30696 -272.970758) (xy 124.355815 -272.97669)
			(xy 124.403086 -272.990382) (xy 124.447548 -273.01148) (xy 124.488051 -273.039436) (xy 124.523544 -273.073528)
			(xy 124.553109 -273.112872) (xy 124.57598 -273.156449) (xy 124.591564 -273.20313) (xy 124.599459 -273.251707)
			(xy 124.599954 -273.276314) (xy 124.928896 -273.276314) (xy 124.932856 -273.22726) (xy 124.944633 -273.179476)
			(xy 124.963924 -273.1342) (xy 124.990227 -273.092604) (xy 125.022862 -273.055767) (xy 125.060983 -273.024642)
			(xy 125.103604 -273.000035) (xy 125.14962 -272.982583) (xy 125.197839 -272.972739) (xy 125.247014 -272.970758)
			(xy 125.295869 -272.97669) (xy 125.34314 -272.990382) (xy 125.387602 -273.01148) (xy 125.428105 -273.039436)
			(xy 125.463598 -273.073528) (xy 125.493163 -273.112872) (xy 125.516034 -273.156449) (xy 125.531618 -273.20313)
			(xy 125.539513 -273.251707) (xy 125.540008 -273.276314) (xy 125.86895 -273.276314) (xy 125.87291 -273.22726)
			(xy 125.884687 -273.179476) (xy 125.903978 -273.1342) (xy 125.930281 -273.092604) (xy 125.962916 -273.055767)
			(xy 126.001037 -273.024642) (xy 126.043658 -273.000035) (xy 126.089674 -272.982583) (xy 126.137893 -272.972739)
			(xy 126.187068 -272.970758) (xy 126.235923 -272.97669) (xy 126.283194 -272.990382) (xy 126.327656 -273.01148)
			(xy 126.368159 -273.039436) (xy 126.403652 -273.073528) (xy 126.433217 -273.112872) (xy 126.456088 -273.156449)
			(xy 126.471672 -273.20313) (xy 126.479567 -273.251707) (xy 126.480062 -273.276314) (xy 126.479567 -273.300921)
			(xy 126.471672 -273.349498) (xy 126.456088 -273.396179) (xy 126.433217 -273.439756) (xy 126.403652 -273.4791)
			(xy 126.368159 -273.513192) (xy 126.327656 -273.541148) (xy 126.283194 -273.562246) (xy 126.235923 -273.575938)
			(xy 126.187068 -273.58187) (xy 126.137893 -273.579889) (xy 126.089674 -273.570045) (xy 126.043658 -273.552593)
			(xy 126.001037 -273.527986) (xy 125.962916 -273.496861) (xy 125.930281 -273.460024) (xy 125.903978 -273.418428)
			(xy 125.884687 -273.373152) (xy 125.87291 -273.325368) (xy 125.86895 -273.276314) (xy 125.540008 -273.276314)
			(xy 125.539513 -273.300921) (xy 125.531618 -273.349498) (xy 125.516034 -273.396179) (xy 125.493163 -273.439756)
			(xy 125.463598 -273.4791) (xy 125.428105 -273.513192) (xy 125.387602 -273.541148) (xy 125.34314 -273.562246)
			(xy 125.295869 -273.575938) (xy 125.247014 -273.58187) (xy 125.197839 -273.579889) (xy 125.14962 -273.570045)
			(xy 125.103604 -273.552593) (xy 125.060983 -273.527986) (xy 125.022862 -273.496861) (xy 124.990227 -273.460024)
			(xy 124.963924 -273.418428) (xy 124.944633 -273.373152) (xy 124.932856 -273.325368) (xy 124.928896 -273.276314)
			(xy 124.599954 -273.276314) (xy 124.599459 -273.300921) (xy 124.591564 -273.349498) (xy 124.57598 -273.396179)
			(xy 124.553109 -273.439756) (xy 124.523544 -273.4791) (xy 124.488051 -273.513192) (xy 124.447548 -273.541148)
			(xy 124.403086 -273.562246) (xy 124.355815 -273.575938) (xy 124.30696 -273.58187) (xy 124.257785 -273.579889)
			(xy 124.209566 -273.570045) (xy 124.16355 -273.552593) (xy 124.120929 -273.527986) (xy 124.082808 -273.496861)
			(xy 124.050173 -273.460024) (xy 124.02387 -273.418428) (xy 124.004579 -273.373152) (xy 123.992802 -273.325368)
			(xy 123.988842 -273.276314) (xy 123.660154 -273.276314) (xy 123.659659 -273.300921) (xy 123.651764 -273.349498)
			(xy 123.63618 -273.396179) (xy 123.613309 -273.439756) (xy 123.583744 -273.4791) (xy 123.548251 -273.513192)
			(xy 123.507748 -273.541148) (xy 123.463286 -273.562246) (xy 123.416015 -273.575938) (xy 123.36716 -273.58187)
			(xy 123.317985 -273.579889) (xy 123.269766 -273.570045) (xy 123.22375 -273.552593) (xy 123.181129 -273.527986)
			(xy 123.143008 -273.496861) (xy 123.110373 -273.460024) (xy 123.08407 -273.418428) (xy 123.064779 -273.373152)
			(xy 123.053002 -273.325368) (xy 123.049042 -273.276314) (xy 122.7201 -273.276314) (xy 122.719605 -273.300921)
			(xy 122.71171 -273.349498) (xy 122.696126 -273.396179) (xy 122.673255 -273.439756) (xy 122.64369 -273.4791)
			(xy 122.608197 -273.513192) (xy 122.567694 -273.541148) (xy 122.523232 -273.562246) (xy 122.475961 -273.575938)
			(xy 122.427106 -273.58187) (xy 122.377931 -273.579889) (xy 122.329712 -273.570045) (xy 122.283696 -273.552593)
			(xy 122.241075 -273.527986) (xy 122.202954 -273.496861) (xy 122.170319 -273.460024) (xy 122.144016 -273.418428)
			(xy 122.124725 -273.373152) (xy 122.112948 -273.325368) (xy 122.108988 -273.276314) (xy 121.780046 -273.276314)
			(xy 121.779551 -273.300921) (xy 121.771656 -273.349498) (xy 121.756072 -273.396179) (xy 121.733201 -273.439756)
			(xy 121.703636 -273.4791) (xy 121.668143 -273.513192) (xy 121.62764 -273.541148) (xy 121.583178 -273.562246)
			(xy 121.535907 -273.575938) (xy 121.487052 -273.58187) (xy 121.437877 -273.579889) (xy 121.389658 -273.570045)
			(xy 121.343642 -273.552593) (xy 121.301021 -273.527986) (xy 121.2629 -273.496861) (xy 121.230265 -273.460024)
			(xy 121.203962 -273.418428) (xy 121.184671 -273.373152) (xy 121.172894 -273.325368) (xy 121.168934 -273.276314)
			(xy 120.839992 -273.276314) (xy 120.839497 -273.300921) (xy 120.831602 -273.349498) (xy 120.816018 -273.396179)
			(xy 120.793147 -273.439756) (xy 120.763582 -273.4791) (xy 120.728089 -273.513192) (xy 120.687586 -273.541148)
			(xy 120.643124 -273.562246) (xy 120.595853 -273.575938) (xy 120.546998 -273.58187) (xy 120.497823 -273.579889)
			(xy 120.449604 -273.570045) (xy 120.403588 -273.552593) (xy 120.360967 -273.527986) (xy 120.322846 -273.496861)
			(xy 120.290211 -273.460024) (xy 120.263908 -273.418428) (xy 120.244617 -273.373152) (xy 120.23284 -273.325368)
			(xy 120.22888 -273.276314) (xy 119.899938 -273.276314) (xy 119.899443 -273.300921) (xy 119.891548 -273.349498)
			(xy 119.875964 -273.396179) (xy 119.853093 -273.439756) (xy 119.823528 -273.4791) (xy 119.788035 -273.513192)
			(xy 119.747532 -273.541148) (xy 119.70307 -273.562246) (xy 119.655799 -273.575938) (xy 119.606944 -273.58187)
			(xy 119.557769 -273.579889) (xy 119.50955 -273.570045) (xy 119.463534 -273.552593) (xy 119.420913 -273.527986)
			(xy 119.382792 -273.496861) (xy 119.350157 -273.460024) (xy 119.323854 -273.418428) (xy 119.304563 -273.373152)
			(xy 119.292786 -273.325368) (xy 119.288826 -273.276314) (xy 118.960138 -273.276314) (xy 118.959643 -273.300921)
			(xy 118.951748 -273.349498) (xy 118.936164 -273.396179) (xy 118.913293 -273.439756) (xy 118.883728 -273.4791)
			(xy 118.848235 -273.513192) (xy 118.807732 -273.541148) (xy 118.76327 -273.562246) (xy 118.715999 -273.575938)
			(xy 118.667144 -273.58187) (xy 118.617969 -273.579889) (xy 118.56975 -273.570045) (xy 118.523734 -273.552593)
			(xy 118.481113 -273.527986) (xy 118.442992 -273.496861) (xy 118.410357 -273.460024) (xy 118.384054 -273.418428)
			(xy 118.364763 -273.373152) (xy 118.352986 -273.325368) (xy 118.349026 -273.276314) (xy 118.020084 -273.276314)
			(xy 118.019589 -273.300921) (xy 118.011694 -273.349498) (xy 117.99611 -273.396179) (xy 117.973239 -273.439756)
			(xy 117.943674 -273.4791) (xy 117.908181 -273.513192) (xy 117.867678 -273.541148) (xy 117.823216 -273.562246)
			(xy 117.775945 -273.575938) (xy 117.72709 -273.58187) (xy 117.677915 -273.579889) (xy 117.629696 -273.570045)
			(xy 117.58368 -273.552593) (xy 117.541059 -273.527986) (xy 117.502938 -273.496861) (xy 117.470303 -273.460024)
			(xy 117.444 -273.418428) (xy 117.424709 -273.373152) (xy 117.412932 -273.325368) (xy 117.408972 -273.276314)
			(xy 117.08003 -273.276314) (xy 117.079535 -273.300921) (xy 117.07164 -273.349498) (xy 117.056056 -273.396179)
			(xy 117.033185 -273.439756) (xy 117.00362 -273.4791) (xy 116.968127 -273.513192) (xy 116.927624 -273.541148)
			(xy 116.883162 -273.562246) (xy 116.835891 -273.575938) (xy 116.787036 -273.58187) (xy 116.737861 -273.579889)
			(xy 116.689642 -273.570045) (xy 116.643626 -273.552593) (xy 116.601005 -273.527986) (xy 116.562884 -273.496861)
			(xy 116.530249 -273.460024) (xy 116.503946 -273.418428) (xy 116.484655 -273.373152) (xy 116.472878 -273.325368)
			(xy 116.468918 -273.276314) (xy 116.139976 -273.276314) (xy 116.139481 -273.300921) (xy 116.131586 -273.349498)
			(xy 116.116002 -273.396179) (xy 116.093131 -273.439756) (xy 116.063566 -273.4791) (xy 116.028073 -273.513192)
			(xy 115.98757 -273.541148) (xy 115.943108 -273.562246) (xy 115.895837 -273.575938) (xy 115.846982 -273.58187)
			(xy 115.797807 -273.579889) (xy 115.749588 -273.570045) (xy 115.703572 -273.552593) (xy 115.660951 -273.527986)
			(xy 115.62283 -273.496861) (xy 115.590195 -273.460024) (xy 115.563892 -273.418428) (xy 115.544601 -273.373152)
			(xy 115.532824 -273.325368) (xy 115.528864 -273.276314) (xy 115.199922 -273.276314) (xy 115.199427 -273.300921)
			(xy 115.191532 -273.349498) (xy 115.175948 -273.396179) (xy 115.153077 -273.439756) (xy 115.123512 -273.4791)
			(xy 115.088019 -273.513192) (xy 115.047516 -273.541148) (xy 115.003054 -273.562246) (xy 114.955783 -273.575938)
			(xy 114.906928 -273.58187) (xy 114.857753 -273.579889) (xy 114.809534 -273.570045) (xy 114.763518 -273.552593)
			(xy 114.720897 -273.527986) (xy 114.682776 -273.496861) (xy 114.650141 -273.460024) (xy 114.623838 -273.418428)
			(xy 114.604547 -273.373152) (xy 114.59277 -273.325368) (xy 114.58881 -273.276314) (xy 114.260122 -273.276314)
			(xy 114.259627 -273.300921) (xy 114.251732 -273.349498) (xy 114.236148 -273.396179) (xy 114.213277 -273.439756)
			(xy 114.183712 -273.4791) (xy 114.148219 -273.513192) (xy 114.107716 -273.541148) (xy 114.063254 -273.562246)
			(xy 114.015983 -273.575938) (xy 113.967128 -273.58187) (xy 113.917953 -273.579889) (xy 113.869734 -273.570045)
			(xy 113.823718 -273.552593) (xy 113.781097 -273.527986) (xy 113.742976 -273.496861) (xy 113.710341 -273.460024)
			(xy 113.684038 -273.418428) (xy 113.664747 -273.373152) (xy 113.65297 -273.325368) (xy 113.64901 -273.276314)
			(xy 110.506256 -273.276314) (xy 110.505761 -273.300921) (xy 110.497866 -273.349498) (xy 110.482282 -273.396179)
			(xy 110.459411 -273.439756) (xy 110.429846 -273.4791) (xy 110.394353 -273.513192) (xy 110.35385 -273.541148)
			(xy 110.309388 -273.562246) (xy 110.262117 -273.575938) (xy 110.213262 -273.58187) (xy 110.164087 -273.579889)
			(xy 110.115868 -273.570045) (xy 110.069852 -273.552593) (xy 110.027231 -273.527986) (xy 109.98911 -273.496861)
			(xy 109.956475 -273.460024) (xy 109.930172 -273.418428) (xy 109.910881 -273.373152) (xy 109.899104 -273.325368)
			(xy 109.895144 -273.276314) (xy 109.566456 -273.276314) (xy 109.565961 -273.300921) (xy 109.558066 -273.349498)
			(xy 109.542482 -273.396179) (xy 109.519611 -273.439756) (xy 109.490046 -273.4791) (xy 109.454553 -273.513192)
			(xy 109.41405 -273.541148) (xy 109.369588 -273.562246) (xy 109.322317 -273.575938) (xy 109.273462 -273.58187)
			(xy 109.224287 -273.579889) (xy 109.176068 -273.570045) (xy 109.130052 -273.552593) (xy 109.087431 -273.527986)
			(xy 109.04931 -273.496861) (xy 109.016675 -273.460024) (xy 108.990372 -273.418428) (xy 108.971081 -273.373152)
			(xy 108.959304 -273.325368) (xy 108.955344 -273.276314) (xy 108.626402 -273.276314) (xy 108.625907 -273.300921)
			(xy 108.618012 -273.349498) (xy 108.602428 -273.396179) (xy 108.579557 -273.439756) (xy 108.549992 -273.4791)
			(xy 108.514499 -273.513192) (xy 108.473996 -273.541148) (xy 108.429534 -273.562246) (xy 108.382263 -273.575938)
			(xy 108.333408 -273.58187) (xy 108.284233 -273.579889) (xy 108.236014 -273.570045) (xy 108.189998 -273.552593)
			(xy 108.147377 -273.527986) (xy 108.109256 -273.496861) (xy 108.076621 -273.460024) (xy 108.050318 -273.418428)
			(xy 108.031027 -273.373152) (xy 108.01925 -273.325368) (xy 108.01529 -273.276314) (xy 107.686348 -273.276314)
			(xy 107.685853 -273.300921) (xy 107.677958 -273.349498) (xy 107.662374 -273.396179) (xy 107.639503 -273.439756)
			(xy 107.609938 -273.4791) (xy 107.574445 -273.513192) (xy 107.533942 -273.541148) (xy 107.48948 -273.562246)
			(xy 107.442209 -273.575938) (xy 107.393354 -273.58187) (xy 107.344179 -273.579889) (xy 107.29596 -273.570045)
			(xy 107.249944 -273.552593) (xy 107.207323 -273.527986) (xy 107.169202 -273.496861) (xy 107.136567 -273.460024)
			(xy 107.110264 -273.418428) (xy 107.090973 -273.373152) (xy 107.079196 -273.325368) (xy 107.075236 -273.276314)
			(xy 106.746294 -273.276314) (xy 106.745799 -273.300921) (xy 106.737904 -273.349498) (xy 106.72232 -273.396179)
			(xy 106.699449 -273.439756) (xy 106.669884 -273.4791) (xy 106.634391 -273.513192) (xy 106.593888 -273.541148)
			(xy 106.549426 -273.562246) (xy 106.502155 -273.575938) (xy 106.4533 -273.58187) (xy 106.404125 -273.579889)
			(xy 106.355906 -273.570045) (xy 106.30989 -273.552593) (xy 106.267269 -273.527986) (xy 106.229148 -273.496861)
			(xy 106.196513 -273.460024) (xy 106.17021 -273.418428) (xy 106.150919 -273.373152) (xy 106.139142 -273.325368)
			(xy 106.135182 -273.276314) (xy 105.80624 -273.276314) (xy 105.805745 -273.300921) (xy 105.79785 -273.349498)
			(xy 105.782266 -273.396179) (xy 105.759395 -273.439756) (xy 105.72983 -273.4791) (xy 105.694337 -273.513192)
			(xy 105.653834 -273.541148) (xy 105.609372 -273.562246) (xy 105.562101 -273.575938) (xy 105.513246 -273.58187)
			(xy 105.464071 -273.579889) (xy 105.415852 -273.570045) (xy 105.369836 -273.552593) (xy 105.327215 -273.527986)
			(xy 105.289094 -273.496861) (xy 105.256459 -273.460024) (xy 105.230156 -273.418428) (xy 105.210865 -273.373152)
			(xy 105.199088 -273.325368) (xy 105.195128 -273.276314) (xy 104.86644 -273.276314) (xy 104.865945 -273.300921)
			(xy 104.85805 -273.349498) (xy 104.842466 -273.396179) (xy 104.819595 -273.439756) (xy 104.79003 -273.4791)
			(xy 104.754537 -273.513192) (xy 104.714034 -273.541148) (xy 104.669572 -273.562246) (xy 104.622301 -273.575938)
			(xy 104.573446 -273.58187) (xy 104.524271 -273.579889) (xy 104.476052 -273.570045) (xy 104.430036 -273.552593)
			(xy 104.387415 -273.527986) (xy 104.349294 -273.496861) (xy 104.316659 -273.460024) (xy 104.290356 -273.418428)
			(xy 104.271065 -273.373152) (xy 104.259288 -273.325368) (xy 104.255328 -273.276314) (xy 103.926386 -273.276314)
			(xy 103.925891 -273.300921) (xy 103.917996 -273.349498) (xy 103.902412 -273.396179) (xy 103.879541 -273.439756)
			(xy 103.849976 -273.4791) (xy 103.814483 -273.513192) (xy 103.77398 -273.541148) (xy 103.729518 -273.562246)
			(xy 103.682247 -273.575938) (xy 103.633392 -273.58187) (xy 103.584217 -273.579889) (xy 103.535998 -273.570045)
			(xy 103.489982 -273.552593) (xy 103.447361 -273.527986) (xy 103.40924 -273.496861) (xy 103.376605 -273.460024)
			(xy 103.350302 -273.418428) (xy 103.331011 -273.373152) (xy 103.319234 -273.325368) (xy 103.315274 -273.276314)
			(xy 102.986332 -273.276314) (xy 102.985837 -273.300921) (xy 102.977942 -273.349498) (xy 102.962358 -273.396179)
			(xy 102.939487 -273.439756) (xy 102.909922 -273.4791) (xy 102.874429 -273.513192) (xy 102.833926 -273.541148)
			(xy 102.789464 -273.562246) (xy 102.742193 -273.575938) (xy 102.693338 -273.58187) (xy 102.644163 -273.579889)
			(xy 102.595944 -273.570045) (xy 102.549928 -273.552593) (xy 102.507307 -273.527986) (xy 102.469186 -273.496861)
			(xy 102.436551 -273.460024) (xy 102.410248 -273.418428) (xy 102.390957 -273.373152) (xy 102.37918 -273.325368)
			(xy 102.37522 -273.276314) (xy 102.046278 -273.276314) (xy 102.045783 -273.300921) (xy 102.037888 -273.349498)
			(xy 102.022304 -273.396179) (xy 101.999433 -273.439756) (xy 101.969868 -273.4791) (xy 101.934375 -273.513192)
			(xy 101.893872 -273.541148) (xy 101.84941 -273.562246) (xy 101.802139 -273.575938) (xy 101.753284 -273.58187)
			(xy 101.704109 -273.579889) (xy 101.65589 -273.570045) (xy 101.609874 -273.552593) (xy 101.567253 -273.527986)
			(xy 101.529132 -273.496861) (xy 101.496497 -273.460024) (xy 101.470194 -273.418428) (xy 101.450903 -273.373152)
			(xy 101.439126 -273.325368) (xy 101.435166 -273.276314) (xy 101.106478 -273.276314) (xy 101.105983 -273.300921)
			(xy 101.098088 -273.349498) (xy 101.082504 -273.396179) (xy 101.059633 -273.439756) (xy 101.030068 -273.4791)
			(xy 100.994575 -273.513192) (xy 100.954072 -273.541148) (xy 100.90961 -273.562246) (xy 100.862339 -273.575938)
			(xy 100.813484 -273.58187) (xy 100.764309 -273.579889) (xy 100.71609 -273.570045) (xy 100.670074 -273.552593)
			(xy 100.627453 -273.527986) (xy 100.589332 -273.496861) (xy 100.556697 -273.460024) (xy 100.530394 -273.418428)
			(xy 100.511103 -273.373152) (xy 100.499326 -273.325368) (xy 100.495366 -273.276314) (xy 100.166424 -273.276314)
			(xy 100.165929 -273.300921) (xy 100.158034 -273.349498) (xy 100.14245 -273.396179) (xy 100.119579 -273.439756)
			(xy 100.090014 -273.4791) (xy 100.054521 -273.513192) (xy 100.014018 -273.541148) (xy 99.969556 -273.562246)
			(xy 99.922285 -273.575938) (xy 99.87343 -273.58187) (xy 99.824255 -273.579889) (xy 99.776036 -273.570045)
			(xy 99.73002 -273.552593) (xy 99.687399 -273.527986) (xy 99.649278 -273.496861) (xy 99.616643 -273.460024)
			(xy 99.59034 -273.418428) (xy 99.571049 -273.373152) (xy 99.559272 -273.325368) (xy 99.555312 -273.276314)
			(xy 99.22637 -273.276314) (xy 99.225875 -273.300921) (xy 99.21798 -273.349498) (xy 99.202396 -273.396179)
			(xy 99.179525 -273.439756) (xy 99.14996 -273.4791) (xy 99.114467 -273.513192) (xy 99.073964 -273.541148)
			(xy 99.029502 -273.562246) (xy 98.982231 -273.575938) (xy 98.933376 -273.58187) (xy 98.884201 -273.579889)
			(xy 98.835982 -273.570045) (xy 98.789966 -273.552593) (xy 98.747345 -273.527986) (xy 98.709224 -273.496861)
			(xy 98.676589 -273.460024) (xy 98.650286 -273.418428) (xy 98.630995 -273.373152) (xy 98.619218 -273.325368)
			(xy 98.615258 -273.276314) (xy 98.286316 -273.276314) (xy 98.285821 -273.300921) (xy 98.277926 -273.349498)
			(xy 98.262342 -273.396179) (xy 98.239471 -273.439756) (xy 98.209906 -273.4791) (xy 98.174413 -273.513192)
			(xy 98.13391 -273.541148) (xy 98.089448 -273.562246) (xy 98.042177 -273.575938) (xy 97.993322 -273.58187)
			(xy 97.944147 -273.579889) (xy 97.895928 -273.570045) (xy 97.849912 -273.552593) (xy 97.807291 -273.527986)
			(xy 97.76917 -273.496861) (xy 97.736535 -273.460024) (xy 97.710232 -273.418428) (xy 97.690941 -273.373152)
			(xy 97.679164 -273.325368) (xy 97.675204 -273.276314) (xy 97.346769 -273.276314) (xy 97.342815 -273.32534)
			(xy 97.331057 -273.373104) (xy 97.311799 -273.418368) (xy 97.285539 -273.459962) (xy 97.252955 -273.496813)
			(xy 97.234248 -273.512788) (xy 97.229676 -273.516344) (xy 97.223326 -273.524472) (xy 97.211134 -273.54911)
			(xy 97.208668 -273.554435) (xy 97.205967 -273.565851) (xy 97.2058 -273.571716) (xy 97.2058 -273.734022)
			(xy 97.206129 -273.742916) (xy 97.212207 -273.759632) (xy 97.223653 -273.773247) (xy 97.2312 -273.777964)
			(xy 97.319084 -273.828764) (xy 97.346262 -273.828764) (xy 97.357946 -273.821906) (xy 97.37662 -273.811561)
			(xy 97.41622 -273.795613) (xy 97.457654 -273.785334) (xy 97.47885 -273.78279) (xy 97.511108 -273.781012)
			(xy 97.532709 -273.781368) (xy 97.575487 -273.78741) (xy 97.616991 -273.799402) (xy 97.636838 -273.807936)
			(xy 97.651316 -273.81454) (xy 97.682304 -273.808952) (xy 97.724976 -273.76628) (xy 97.732375 -273.759437)
			(xy 97.750974 -273.751718) (xy 97.761044 -273.751294) (xy 108.15701 -273.751294) (xy 108.16708 -273.751719)
			(xy 108.185682 -273.759435) (xy 108.193078 -273.76628) (xy 108.372148 -273.94535) (xy 108.380687 -273.95317)
			(xy 108.402506 -273.960855) (xy 108.414058 -273.960082) (xy 108.50499 -273.94916) (xy 108.524548 -273.936714)
			(xy 108.530644 -273.926808) (xy 108.544674 -273.904916) (xy 108.578959 -273.865828) (xy 108.619369 -273.833112)
			(xy 108.664737 -273.807714) (xy 108.713752 -273.790369) (xy 108.764997 -273.781577) (xy 108.790994 -273.781012)
			(xy 108.81625 -273.781504) (xy 108.866074 -273.789817) (xy 108.91385 -273.806218) (xy 108.958275 -273.830259)
			(xy 108.998137 -273.861284) (xy 109.032349 -273.898447) (xy 109.059977 -273.940735) (xy 109.080268 -273.986993)
			(xy 109.092669 -274.03596) (xy 109.09684 -274.0863) (xy 109.096838 -274.08632) (xy 109.425244 -274.08632)
			(xy 109.429204 -274.037266) (xy 109.440981 -273.989482) (xy 109.460272 -273.944206) (xy 109.486575 -273.90261)
			(xy 109.51921 -273.865773) (xy 109.557331 -273.834648) (xy 109.599952 -273.810041) (xy 109.645968 -273.792589)
			(xy 109.694187 -273.782745) (xy 109.743362 -273.780764) (xy 109.792217 -273.786696) (xy 109.839488 -273.800388)
			(xy 109.88395 -273.821486) (xy 109.924453 -273.849442) (xy 109.959946 -273.883534) (xy 109.989511 -273.922878)
			(xy 110.012382 -273.966455) (xy 110.027966 -274.013136) (xy 110.035861 -274.061713) (xy 110.036356 -274.08632)
			(xy 110.365298 -274.08632) (xy 110.369258 -274.037266) (xy 110.381035 -273.989482) (xy 110.400326 -273.944206)
			(xy 110.426629 -273.90261) (xy 110.459264 -273.865773) (xy 110.497385 -273.834648) (xy 110.540006 -273.810041)
			(xy 110.586022 -273.792589) (xy 110.634241 -273.782745) (xy 110.683416 -273.780764) (xy 110.732271 -273.786696)
			(xy 110.779542 -273.800388) (xy 110.824004 -273.821486) (xy 110.864507 -273.849442) (xy 110.9 -273.883534)
			(xy 110.929565 -273.922878) (xy 110.952436 -273.966455) (xy 110.96802 -274.013136) (xy 110.975915 -274.061713)
			(xy 110.97641 -274.08632) (xy 113.178856 -274.08632) (xy 113.182816 -274.037266) (xy 113.194593 -273.989482)
			(xy 113.213884 -273.944206) (xy 113.240187 -273.90261) (xy 113.272822 -273.865773) (xy 113.310943 -273.834648)
			(xy 113.353564 -273.810041) (xy 113.39958 -273.792589) (xy 113.447799 -273.782745) (xy 113.496974 -273.780764)
			(xy 113.545829 -273.786696) (xy 113.5931 -273.800388) (xy 113.637562 -273.821486) (xy 113.678065 -273.849442)
			(xy 113.713558 -273.883534) (xy 113.743123 -273.922878) (xy 113.765994 -273.966455) (xy 113.781578 -274.013136)
			(xy 113.789473 -274.061713) (xy 113.789968 -274.08632) (xy 114.11891 -274.08632) (xy 114.12287 -274.037266)
			(xy 114.134647 -273.989482) (xy 114.153938 -273.944206) (xy 114.180241 -273.90261) (xy 114.212876 -273.865773)
			(xy 114.250997 -273.834648) (xy 114.293618 -273.810041) (xy 114.339634 -273.792589) (xy 114.387853 -273.782745)
			(xy 114.437028 -273.780764) (xy 114.485883 -273.786696) (xy 114.533154 -273.800388) (xy 114.577616 -273.821486)
			(xy 114.618119 -273.849442) (xy 114.653612 -273.883534) (xy 114.683177 -273.922878) (xy 114.706048 -273.966455)
			(xy 114.721632 -274.013136) (xy 114.729527 -274.061713) (xy 114.730022 -274.08632) (xy 115.058964 -274.08632)
			(xy 115.062924 -274.037266) (xy 115.074701 -273.989482) (xy 115.093992 -273.944206) (xy 115.120295 -273.90261)
			(xy 115.15293 -273.865773) (xy 115.191051 -273.834648) (xy 115.233672 -273.810041) (xy 115.279688 -273.792589)
			(xy 115.327907 -273.782745) (xy 115.377082 -273.780764) (xy 115.425937 -273.786696) (xy 115.473208 -273.800388)
			(xy 115.51767 -273.821486) (xy 115.558173 -273.849442) (xy 115.593666 -273.883534) (xy 115.623231 -273.922878)
			(xy 115.646102 -273.966455) (xy 115.661686 -274.013136) (xy 115.669581 -274.061713) (xy 115.670076 -274.08632)
			(xy 115.669581 -274.110927) (xy 115.661686 -274.159504) (xy 115.646102 -274.206185) (xy 115.623231 -274.249762)
			(xy 115.593666 -274.289106) (xy 115.558173 -274.323198) (xy 115.51767 -274.351154) (xy 115.473208 -274.372252)
			(xy 115.425937 -274.385944) (xy 115.377082 -274.391876) (xy 115.327907 -274.389895) (xy 115.279688 -274.380051)
			(xy 115.233672 -274.362599) (xy 115.191051 -274.337992) (xy 115.15293 -274.306867) (xy 115.120295 -274.27003)
			(xy 115.093992 -274.228434) (xy 115.074701 -274.183158) (xy 115.062924 -274.135374) (xy 115.058964 -274.08632)
			(xy 114.730022 -274.08632) (xy 114.729527 -274.110927) (xy 114.721632 -274.159504) (xy 114.706048 -274.206185)
			(xy 114.683177 -274.249762) (xy 114.653612 -274.289106) (xy 114.618119 -274.323198) (xy 114.577616 -274.351154)
			(xy 114.533154 -274.372252) (xy 114.485883 -274.385944) (xy 114.437028 -274.391876) (xy 114.387853 -274.389895)
			(xy 114.339634 -274.380051) (xy 114.293618 -274.362599) (xy 114.250997 -274.337992) (xy 114.212876 -274.306867)
			(xy 114.180241 -274.27003) (xy 114.153938 -274.228434) (xy 114.134647 -274.183158) (xy 114.12287 -274.135374)
			(xy 114.11891 -274.08632) (xy 113.789968 -274.08632) (xy 113.789473 -274.110927) (xy 113.781578 -274.159504)
			(xy 113.765994 -274.206185) (xy 113.743123 -274.249762) (xy 113.713558 -274.289106) (xy 113.678065 -274.323198)
			(xy 113.637562 -274.351154) (xy 113.5931 -274.372252) (xy 113.545829 -274.385944) (xy 113.496974 -274.391876)
			(xy 113.447799 -274.389895) (xy 113.39958 -274.380051) (xy 113.353564 -274.362599) (xy 113.310943 -274.337992)
			(xy 113.272822 -274.306867) (xy 113.240187 -274.27003) (xy 113.213884 -274.228434) (xy 113.194593 -274.183158)
			(xy 113.182816 -274.135374) (xy 113.178856 -274.08632) (xy 110.97641 -274.08632) (xy 110.975915 -274.110927)
			(xy 110.96802 -274.159504) (xy 110.952436 -274.206185) (xy 110.929565 -274.249762) (xy 110.9 -274.289106)
			(xy 110.864507 -274.323198) (xy 110.824004 -274.351154) (xy 110.779542 -274.372252) (xy 110.732271 -274.385944)
			(xy 110.683416 -274.391876) (xy 110.634241 -274.389895) (xy 110.586022 -274.380051) (xy 110.540006 -274.362599)
			(xy 110.497385 -274.337992) (xy 110.459264 -274.306867) (xy 110.426629 -274.27003) (xy 110.400326 -274.228434)
			(xy 110.381035 -274.183158) (xy 110.369258 -274.135374) (xy 110.365298 -274.08632) (xy 110.036356 -274.08632)
			(xy 110.035861 -274.110927) (xy 110.027966 -274.159504) (xy 110.012382 -274.206185) (xy 109.989511 -274.249762)
			(xy 109.959946 -274.289106) (xy 109.924453 -274.323198) (xy 109.88395 -274.351154) (xy 109.839488 -274.372252)
			(xy 109.792217 -274.385944) (xy 109.743362 -274.391876) (xy 109.694187 -274.389895) (xy 109.645968 -274.380051)
			(xy 109.599952 -274.362599) (xy 109.557331 -274.337992) (xy 109.51921 -274.306867) (xy 109.486575 -274.27003)
			(xy 109.460272 -274.228434) (xy 109.440981 -274.183158) (xy 109.429204 -274.135374) (xy 109.425244 -274.08632)
			(xy 109.096838 -274.08632) (xy 109.092669 -274.13664) (xy 109.080268 -274.185607) (xy 109.059977 -274.231865)
			(xy 109.032349 -274.274153) (xy 108.998137 -274.311316) (xy 108.958275 -274.342341) (xy 108.91385 -274.366382)
			(xy 108.866074 -274.382783) (xy 108.81625 -274.391096) (xy 108.790994 -274.391628) (xy 108.767858 -274.391222)
			(xy 108.72211 -274.38428) (xy 108.677935 -274.37051) (xy 108.636346 -274.350228) (xy 108.598296 -274.323899)
			(xy 108.58119 -274.308316) (xy 108.574069 -274.302067) (xy 108.55656 -274.294868) (xy 108.537631 -274.294495)
			(xy 108.528612 -274.297394) (xy 108.50372 -274.306792) (xy 108.494252 -274.310861) (xy 108.479363 -274.325083)
			(xy 108.471228 -274.343997) (xy 108.4707 -274.35429) (xy 108.4707 -274.420838) (xy 108.47113 -274.430905)
			(xy 108.478854 -274.449499) (xy 108.485686 -274.456906) (xy 109.17047 -275.14169) (xy 109.183932 -275.148802)
			(xy 109.191552 -275.150326) (xy 109.205531 -275.152955) (xy 109.23323 -275.159433) (xy 109.246924 -275.16328)
			(xy 109.253859 -275.165081) (xy 109.268183 -275.165081) (xy 109.275118 -275.16328) (xy 109.313769 -275.152794)
			(xy 109.393063 -275.141575) (xy 109.433106 -275.140928) (xy 109.731048 -275.140928) (xy 109.763879 -275.141387)
			(xy 109.829102 -275.14896) (xy 109.89301 -275.164034) (xy 109.954742 -275.186407) (xy 110.013469 -275.215776)
			(xy 110.041182 -275.233384) (xy 110.04751 -275.237255) (xy 110.061709 -275.241527) (xy 110.069122 -275.241766)
			(xy 113.215928 -275.241766)
		)
		(stroke
			(width 0)
			(type solid)
		)
		(fill yes)
		(layer "In11.Cu")
		(net "PVDDCR_CPU1_P1")
	)
	(gr_poly
		(pts
			(xy 361.530138 -275.419566) (xy 361.539338 -275.42251) (xy 361.558633 -275.422017) (xy 361.576379 -275.41443)
			(xy 361.583478 -275.407882) (xy 361.792774 -275.198586) (xy 361.800172 -275.191742) (xy 361.818772 -275.184021)
			(xy 361.828842 -275.1836) (xy 362.14812 -275.1836) (xy 362.15701 -275.180044) (xy 362.190201 -275.167512)
			(xy 362.258921 -275.149878) (xy 362.329309 -275.140983) (xy 362.364782 -275.14042) (xy 362.662724 -275.14042)
			(xy 362.701912 -275.141086) (xy 362.779536 -275.151923) (xy 362.81741 -275.16201) (xy 362.820712 -275.163026)
			(xy 362.82757 -275.164042) (xy 362.831174 -275.164513) (xy 362.838444 -275.164513) (xy 362.842048 -275.164042)
			(xy 362.848906 -275.163026) (xy 362.852208 -275.16201) (xy 362.890084 -275.151936) (xy 362.967707 -275.141101)
			(xy 363.006894 -275.14042) (xy 363.104938 -275.14042) (xy 363.114903 -275.13994) (xy 363.133337 -275.132361)
			(xy 363.140752 -275.125688) (xy 363.496606 -274.769834) (xy 363.500416 -274.762214) (xy 363.511964 -274.73969)
			(xy 363.541364 -274.698492) (xy 363.577158 -274.662709) (xy 363.618364 -274.63332) (xy 363.640878 -274.621752)
			(xy 363.648498 -274.617942) (xy 363.982254 -274.284186) (xy 363.98708 -274.250404) (xy 363.978698 -274.235418)
			(xy 363.966403 -274.212466) (xy 363.948971 -274.163407) (xy 363.94013 -274.112098) (xy 363.939582 -274.086066)
			(xy 363.940104 -274.060811) (xy 363.948417 -274.010989) (xy 363.964818 -273.963215) (xy 363.988859 -273.918792)
			(xy 364.019883 -273.878932) (xy 364.057045 -273.844722) (xy 364.099331 -273.817096) (xy 364.145587 -273.796806)
			(xy 364.194552 -273.784406) (xy 364.24489 -273.780235) (xy 364.295228 -273.784406) (xy 364.344193 -273.796806)
			(xy 364.390449 -273.817096) (xy 364.432735 -273.844722) (xy 364.469897 -273.878932) (xy 364.500921 -273.918792)
			(xy 364.524962 -273.963215) (xy 364.541363 -274.010989) (xy 364.549676 -274.060811) (xy 364.550198 -274.086066)
			(xy 364.550063 -274.097542) (xy 364.548283 -274.120427) (xy 364.546642 -274.131786) (xy 364.545118 -274.142708)
			(xy 364.548166 -274.15363) (xy 364.54983 -274.15885) (xy 364.555089 -274.168458) (xy 364.55858 -274.17268)
			(xy 364.608618 -274.2311) (xy 364.616191 -274.239121) (xy 364.636208 -274.248334) (xy 364.647226 -274.24888)
			(xy 364.782354 -274.24888) (xy 364.793376 -274.248348) (xy 364.813403 -274.239138) (xy 364.820962 -274.2311)
			(xy 364.871 -274.17268) (xy 364.874476 -274.168448) (xy 364.879728 -274.158841) (xy 364.881414 -274.15363)
			(xy 364.884462 -274.142708) (xy 364.882938 -274.131786) (xy 364.881297 -274.120427) (xy 364.879521 -274.097542)
			(xy 364.879382 -274.086066) (xy 364.879904 -274.060811) (xy 364.888217 -274.010989) (xy 364.904618 -273.963215)
			(xy 364.928659 -273.918792) (xy 364.959683 -273.878932) (xy 364.996845 -273.844722) (xy 365.039131 -273.817096)
			(xy 365.085387 -273.796806) (xy 365.134352 -273.784406) (xy 365.18469 -273.780235) (xy 365.235028 -273.784406)
			(xy 365.283993 -273.796806) (xy 365.330249 -273.817096) (xy 365.372535 -273.844722) (xy 365.409697 -273.878932)
			(xy 365.440721 -273.918792) (xy 365.464762 -273.963215) (xy 365.481163 -274.010989) (xy 365.489476 -274.060811)
			(xy 365.489998 -274.086066) (xy 365.489863 -274.097542) (xy 365.488083 -274.120427) (xy 365.486442 -274.131786)
			(xy 365.484918 -274.142708) (xy 365.487966 -274.15363) (xy 365.48963 -274.15885) (xy 365.494889 -274.168458)
			(xy 365.49838 -274.17268) (xy 365.548418 -274.2311) (xy 365.555991 -274.239121) (xy 365.576008 -274.248334)
			(xy 365.587026 -274.24888) (xy 365.722408 -274.24888) (xy 365.733425 -274.248337) (xy 365.753436 -274.239114)
			(xy 365.761016 -274.2311) (xy 365.811054 -274.17268) (xy 365.814533 -274.16845) (xy 365.819789 -274.158843)
			(xy 365.821468 -274.15363) (xy 365.824516 -274.142708) (xy 365.822992 -274.131786) (xy 365.821351 -274.120427)
			(xy 365.819575 -274.097542) (xy 365.819436 -274.086066) (xy 365.819958 -274.060811) (xy 365.828271 -274.010989)
			(xy 365.844672 -273.963215) (xy 365.868713 -273.918792) (xy 365.899737 -273.878932) (xy 365.936899 -273.844722)
			(xy 365.979185 -273.817096) (xy 366.025441 -273.796806) (xy 366.074406 -273.784406) (xy 366.124744 -273.780235)
			(xy 366.175082 -273.784406) (xy 366.224047 -273.796806) (xy 366.270303 -273.817096) (xy 366.312589 -273.844722)
			(xy 366.349751 -273.878932) (xy 366.380775 -273.918792) (xy 366.404816 -273.963215) (xy 366.421217 -274.010989)
			(xy 366.42953 -274.060811) (xy 366.430052 -274.086066) (xy 366.429917 -274.097542) (xy 366.428137 -274.120427)
			(xy 366.426496 -274.131786) (xy 366.424972 -274.142708) (xy 366.42802 -274.15363) (xy 366.429682 -274.158851)
			(xy 366.434938 -274.168462) (xy 366.438434 -274.17268) (xy 366.488472 -274.2311) (xy 366.496042 -274.239129)
			(xy 366.516059 -274.24836) (xy 366.52708 -274.24888) (xy 366.662462 -274.24888) (xy 366.673483 -274.248347)
			(xy 366.693508 -274.239135) (xy 366.70107 -274.2311) (xy 366.751108 -274.17268) (xy 366.754584 -274.168448)
			(xy 366.759835 -274.15884) (xy 366.761522 -274.15363) (xy 366.76457 -274.142708) (xy 366.763046 -274.131786)
			(xy 366.761405 -274.120427) (xy 366.759629 -274.097542) (xy 366.75949 -274.086066) (xy 366.760012 -274.060811)
			(xy 366.768325 -274.010989) (xy 366.784726 -273.963215) (xy 366.808767 -273.918792) (xy 366.839791 -273.878932)
			(xy 366.876953 -273.844722) (xy 366.919239 -273.817096) (xy 366.965495 -273.796806) (xy 367.01446 -273.784406)
			(xy 367.064798 -273.780235) (xy 367.115136 -273.784406) (xy 367.164101 -273.796806) (xy 367.210357 -273.817096)
			(xy 367.252643 -273.844722) (xy 367.289805 -273.878932) (xy 367.320829 -273.918792) (xy 367.34487 -273.963215)
			(xy 367.361271 -274.010989) (xy 367.369584 -274.060811) (xy 367.370106 -274.086066) (xy 367.369971 -274.097542)
			(xy 367.368191 -274.120427) (xy 367.36655 -274.131786) (xy 367.365026 -274.142708) (xy 367.368074 -274.15363)
			(xy 367.369735 -274.158852) (xy 367.374987 -274.168465) (xy 367.378488 -274.17268) (xy 367.428526 -274.2311)
			(xy 367.4361 -274.239119) (xy 367.456117 -274.248329) (xy 367.467134 -274.24888) (xy 367.602516 -274.24888)
			(xy 367.613532 -274.248336) (xy 367.63354 -274.23911) (xy 367.641124 -274.2311) (xy 367.691162 -274.17268)
			(xy 367.69464 -274.168449) (xy 367.699896 -274.158843) (xy 367.701576 -274.15363) (xy 367.704624 -274.142708)
			(xy 367.7031 -274.131786) (xy 367.701459 -274.120427) (xy 367.699683 -274.097542) (xy 367.699544 -274.086066)
			(xy 367.700066 -274.060811) (xy 367.708379 -274.010989) (xy 367.72478 -273.963215) (xy 367.748821 -273.918792)
			(xy 367.779845 -273.878932) (xy 367.817007 -273.844722) (xy 367.859293 -273.817096) (xy 367.905549 -273.796806)
			(xy 367.954514 -273.784406) (xy 368.004852 -273.780235) (xy 368.05519 -273.784406) (xy 368.104155 -273.796806)
			(xy 368.150411 -273.817096) (xy 368.192697 -273.844722) (xy 368.229859 -273.878932) (xy 368.260883 -273.918792)
			(xy 368.284924 -273.963215) (xy 368.301325 -274.010989) (xy 368.309638 -274.060811) (xy 368.31016 -274.086066)
			(xy 368.310025 -274.097542) (xy 368.308245 -274.120427) (xy 368.306604 -274.131786) (xy 368.30508 -274.142708)
			(xy 368.308128 -274.15363) (xy 368.30979 -274.15885) (xy 368.315047 -274.168461) (xy 368.318542 -274.17268)
			(xy 368.36858 -274.2311) (xy 368.376151 -274.239127) (xy 368.396167 -274.248355) (xy 368.407188 -274.24888)
			(xy 368.54257 -274.24888) (xy 368.553591 -274.248345) (xy 368.573613 -274.239131) (xy 368.581178 -274.2311)
			(xy 368.631216 -274.17268) (xy 368.634692 -274.168448) (xy 368.639942 -274.15884) (xy 368.64163 -274.15363)
			(xy 368.644678 -274.142708) (xy 368.643154 -274.131786) (xy 368.641513 -274.120427) (xy 368.639737 -274.097542)
			(xy 368.639598 -274.086066) (xy 368.64012 -274.060811) (xy 368.648433 -274.010989) (xy 368.664834 -273.963215)
			(xy 368.688875 -273.918792) (xy 368.719899 -273.878932) (xy 368.757061 -273.844722) (xy 368.799347 -273.817096)
			(xy 368.845603 -273.796806) (xy 368.894568 -273.784406) (xy 368.944906 -273.780235) (xy 368.995244 -273.784406)
			(xy 369.044209 -273.796806) (xy 369.090465 -273.817096) (xy 369.132751 -273.844722) (xy 369.169913 -273.878932)
			(xy 369.200937 -273.918792) (xy 369.224978 -273.963215) (xy 369.241379 -274.010989) (xy 369.249692 -274.060811)
			(xy 369.250214 -274.086066) (xy 369.250079 -274.097542) (xy 369.248299 -274.120427) (xy 369.246658 -274.131786)
			(xy 369.245134 -274.142708) (xy 369.248182 -274.15363) (xy 369.249843 -274.158851) (xy 369.255096 -274.168465)
			(xy 369.258596 -274.17268) (xy 369.308634 -274.2311) (xy 369.316208 -274.239118) (xy 369.336225 -274.248325)
			(xy 369.347242 -274.24888) (xy 369.48237 -274.24888) (xy 369.493391 -274.248345) (xy 369.513413 -274.239131)
			(xy 369.520978 -274.2311) (xy 369.571016 -274.17268) (xy 369.574492 -274.168448) (xy 369.579742 -274.15884)
			(xy 369.58143 -274.15363) (xy 369.584478 -274.142708) (xy 369.582954 -274.131786) (xy 369.581313 -274.120427)
			(xy 369.579537 -274.097542) (xy 369.579398 -274.086066) (xy 369.57992 -274.060811) (xy 369.588233 -274.010989)
			(xy 369.604634 -273.963215) (xy 369.628675 -273.918792) (xy 369.659699 -273.878932) (xy 369.696861 -273.844722)
			(xy 369.739147 -273.817096) (xy 369.785403 -273.796806) (xy 369.834368 -273.784406) (xy 369.884706 -273.780235)
			(xy 369.935044 -273.784406) (xy 369.984009 -273.796806) (xy 370.030265 -273.817096) (xy 370.072551 -273.844722)
			(xy 370.109713 -273.878932) (xy 370.140737 -273.918792) (xy 370.164778 -273.963215) (xy 370.181179 -274.010989)
			(xy 370.189492 -274.060811) (xy 370.190014 -274.086066) (xy 370.189879 -274.097542) (xy 370.188099 -274.120427)
			(xy 370.186458 -274.131786) (xy 370.184934 -274.142708) (xy 370.187982 -274.15363) (xy 370.189643 -274.158851)
			(xy 370.194896 -274.168465) (xy 370.198396 -274.17268) (xy 370.248434 -274.2311) (xy 370.256008 -274.239118)
			(xy 370.276025 -274.248325) (xy 370.287042 -274.24888) (xy 370.422424 -274.24888) (xy 370.433439 -274.248334)
			(xy 370.453445 -274.239107) (xy 370.461032 -274.2311) (xy 370.51107 -274.17268) (xy 370.514548 -274.168449)
			(xy 370.519803 -274.158842) (xy 370.521484 -274.15363) (xy 370.524532 -274.142708) (xy 370.523008 -274.131786)
			(xy 370.521367 -274.120427) (xy 370.519591 -274.097542) (xy 370.519452 -274.086066) (xy 370.519974 -274.060811)
			(xy 370.528287 -274.010989) (xy 370.544688 -273.963215) (xy 370.568729 -273.918792) (xy 370.599753 -273.878932)
			(xy 370.636915 -273.844722) (xy 370.679201 -273.817096) (xy 370.725457 -273.796806) (xy 370.774422 -273.784406)
			(xy 370.82476 -273.780235) (xy 370.875098 -273.784406) (xy 370.924063 -273.796806) (xy 370.970319 -273.817096)
			(xy 371.012605 -273.844722) (xy 371.049767 -273.878932) (xy 371.080791 -273.918792) (xy 371.104832 -273.963215)
			(xy 371.121233 -274.010989) (xy 371.129546 -274.060811) (xy 371.130068 -274.086066) (xy 371.129933 -274.097542)
			(xy 371.128153 -274.120427) (xy 371.126512 -274.131786) (xy 371.124988 -274.142708) (xy 371.128036 -274.15363)
			(xy 371.129699 -274.15885) (xy 371.134956 -274.16846) (xy 371.13845 -274.17268) (xy 371.188488 -274.2311)
			(xy 371.196059 -274.239126) (xy 371.216076 -274.248351) (xy 371.227096 -274.24888) (xy 371.362478 -274.24888)
			(xy 371.373498 -274.248343) (xy 371.393518 -274.239127) (xy 371.401086 -274.2311) (xy 371.451124 -274.17268)
			(xy 371.454599 -274.168448) (xy 371.459848 -274.158839) (xy 371.461538 -274.15363) (xy 371.464586 -274.142708)
			(xy 371.463062 -274.131786) (xy 371.461421 -274.120427) (xy 371.459644 -274.097542) (xy 371.459506 -274.086066)
			(xy 371.460028 -274.060811) (xy 371.468341 -274.010989) (xy 371.484742 -273.963215) (xy 371.508783 -273.918792)
			(xy 371.539807 -273.878932) (xy 371.576969 -273.844722) (xy 371.619255 -273.817096) (xy 371.665511 -273.796806)
			(xy 371.714476 -273.784406) (xy 371.764814 -273.780235) (xy 371.815152 -273.784406) (xy 371.864117 -273.796806)
			(xy 371.910373 -273.817096) (xy 371.952659 -273.844722) (xy 371.989821 -273.878932) (xy 372.020845 -273.918792)
			(xy 372.044886 -273.963215) (xy 372.061287 -274.010989) (xy 372.0696 -274.060811) (xy 372.070122 -274.086066)
			(xy 372.069987 -274.097542) (xy 372.068207 -274.120427) (xy 372.066566 -274.131786) (xy 372.065042 -274.142708)
			(xy 372.06809 -274.15363) (xy 372.069751 -274.158851) (xy 372.075005 -274.168464) (xy 372.078504 -274.17268)
			(xy 372.128542 -274.2311) (xy 372.136116 -274.239117) (xy 372.156134 -274.248321) (xy 372.16715 -274.24888)
			(xy 372.302532 -274.24888) (xy 372.313547 -274.248333) (xy 372.33355 -274.239103) (xy 372.34114 -274.2311)
			(xy 372.391178 -274.17268) (xy 372.394655 -274.168449) (xy 372.399909 -274.158842) (xy 372.401592 -274.15363)
			(xy 372.40464 -274.142708) (xy 372.403116 -274.131786) (xy 372.401475 -274.120427) (xy 372.399699 -274.097542)
			(xy 372.39956 -274.086066) (xy 372.400082 -274.060811) (xy 372.408395 -274.010989) (xy 372.424796 -273.963215)
			(xy 372.448837 -273.918792) (xy 372.479861 -273.878932) (xy 372.517023 -273.844722) (xy 372.559309 -273.817096)
			(xy 372.605565 -273.796806) (xy 372.65453 -273.784406) (xy 372.704868 -273.780235) (xy 372.755206 -273.784406)
			(xy 372.804171 -273.796806) (xy 372.850427 -273.817096) (xy 372.892713 -273.844722) (xy 372.929875 -273.878932)
			(xy 372.960899 -273.918792) (xy 372.98494 -273.963215) (xy 373.001341 -274.010989) (xy 373.009654 -274.060811)
			(xy 373.010176 -274.086066) (xy 373.010041 -274.097542) (xy 373.008261 -274.120427) (xy 373.00662 -274.131786)
			(xy 373.005096 -274.142708) (xy 373.008144 -274.15363) (xy 373.009807 -274.15885) (xy 373.015065 -274.168459)
			(xy 373.018558 -274.17268) (xy 373.068596 -274.2311) (xy 373.076168 -274.239125) (xy 373.096184 -274.248346)
			(xy 373.107204 -274.24888) (xy 373.242586 -274.24888) (xy 373.253605 -274.248342) (xy 373.273623 -274.239124)
			(xy 373.281194 -274.2311) (xy 373.331232 -274.17268) (xy 373.334707 -274.168447) (xy 373.339955 -274.158839)
			(xy 373.341646 -274.15363) (xy 373.344694 -274.142708) (xy 373.34317 -274.131786) (xy 373.341529 -274.120427)
			(xy 373.339752 -274.097542) (xy 373.339614 -274.086066) (xy 373.340136 -274.060811) (xy 373.348449 -274.010989)
			(xy 373.36485 -273.963215) (xy 373.388891 -273.918792) (xy 373.419915 -273.878932) (xy 373.457077 -273.844722)
			(xy 373.499363 -273.817096) (xy 373.545619 -273.796806) (xy 373.594584 -273.784406) (xy 373.644922 -273.780235)
			(xy 373.69526 -273.784406) (xy 373.744225 -273.796806) (xy 373.790481 -273.817096) (xy 373.832767 -273.844722)
			(xy 373.869929 -273.878932) (xy 373.900953 -273.918792) (xy 373.924994 -273.963215) (xy 373.941395 -274.010989)
			(xy 373.949708 -274.060811) (xy 373.95023 -274.086066) (xy 373.950095 -274.097542) (xy 373.948315 -274.120427)
			(xy 373.946674 -274.131786) (xy 373.94515 -274.142708) (xy 373.948198 -274.15363) (xy 373.949859 -274.158851)
			(xy 373.955113 -274.168463) (xy 373.958612 -274.17268) (xy 374.00865 -274.2311) (xy 374.016219 -274.239132)
			(xy 374.036235 -274.248372) (xy 374.047258 -274.24888) (xy 374.182386 -274.24888) (xy 374.193405 -274.248342)
			(xy 374.213423 -274.239124) (xy 374.220994 -274.2311) (xy 374.271032 -274.17268) (xy 374.274507 -274.168447)
			(xy 374.279755 -274.158839) (xy 374.281446 -274.15363) (xy 374.284494 -274.142708) (xy 374.28297 -274.131786)
			(xy 374.281329 -274.120427) (xy 374.279552 -274.097542) (xy 374.279414 -274.086066) (xy 374.279855 -274.062477)
			(xy 374.287113 -274.015861) (xy 374.301451 -273.970916) (xy 374.322529 -273.928708) (xy 374.349845 -273.890243)
			(xy 374.38275 -273.856435) (xy 374.420461 -273.828088) (xy 374.462082 -273.805875) (xy 374.506623 -273.790324)
			(xy 374.553025 -273.781806) (xy 374.576594 -273.780758) (xy 374.582944 -273.780758) (xy 374.584722 -273.780758)
			(xy 374.612199 -273.781343) (xy 374.666267 -273.791179) (xy 374.717702 -273.810532) (xy 374.764844 -273.838775)
			(xy 374.78589 -273.85645) (xy 374.793256 -273.8628) (xy 374.811544 -273.869404) (xy 374.890538 -273.866864)
			(xy 374.900112 -273.86617) (xy 374.917736 -273.8586) (xy 374.924828 -273.852132) (xy 374.962674 -273.814286)
			(xy 374.963182 -273.813778) (xy 374.969766 -273.806397) (xy 374.977223 -273.788099) (xy 374.97766 -273.778218)
			(xy 374.97766 -273.592544) (xy 374.95988 -273.56689) (xy 374.945148 -273.561048) (xy 374.922454 -273.551785)
			(xy 374.880117 -273.527089) (xy 374.842269 -273.495946) (xy 374.809881 -273.459158) (xy 374.783786 -273.417669)
			(xy 374.764654 -273.372544) (xy 374.752975 -273.324942) (xy 374.74905 -273.276086) (xy 374.752979 -273.22723)
			(xy 374.764663 -273.179629) (xy 374.7838 -273.134506) (xy 374.809899 -273.093019) (xy 374.84229 -273.056234)
			(xy 374.880141 -273.025095) (xy 374.92248 -273.000402) (xy 374.945148 -272.991072) (xy 374.95988 -272.98523)
			(xy 374.97766 -272.959576) (xy 374.97766 -271.972532) (xy 374.95988 -271.946878) (xy 374.945148 -271.941036)
			(xy 374.922447 -271.931773) (xy 374.880096 -271.907075) (xy 374.842234 -271.875928) (xy 374.809834 -271.839133)
			(xy 374.783728 -271.797635) (xy 374.764585 -271.7525) (xy 374.752898 -271.704886) (xy 374.748967 -271.656017)
			(xy 374.752893 -271.607148) (xy 374.764574 -271.559533) (xy 374.783712 -271.514396) (xy 374.809814 -271.472895)
			(xy 374.842209 -271.436096) (xy 374.880068 -271.404945) (xy 374.922416 -271.380242) (xy 374.945148 -271.37106)
			(xy 374.95988 -271.365218) (xy 374.97766 -271.339564) (xy 374.97766 -271.130014) (xy 374.977243 -271.119927)
			(xy 374.969483 -271.101309) (xy 374.955125 -271.087141) (xy 374.94591 -271.083024) (xy 374.859042 -271.047464)
			(xy 374.849523 -271.044098) (xy 374.829348 -271.044323) (xy 374.810796 -271.052255) (xy 374.803416 -271.059148)
			(xy 374.786043 -271.07627) (xy 374.746866 -271.105326) (xy 374.703574 -271.127793) (xy 374.657263 -271.143102)
			(xy 374.609109 -271.150865) (xy 374.584722 -271.15135) (xy 374.55946 -271.150859) (xy 374.509623 -271.142546)
			(xy 374.461835 -271.126143) (xy 374.417399 -271.102099) (xy 374.377527 -271.071067) (xy 374.343306 -271.033896)
			(xy 374.315671 -270.991599) (xy 374.295374 -270.945331) (xy 374.28297 -270.896352) (xy 374.278798 -270.846)
			(xy 374.28297 -270.795648) (xy 374.295374 -270.746669) (xy 374.315671 -270.700401) (xy 374.343306 -270.658104)
			(xy 374.377527 -270.620933) (xy 374.417399 -270.589901) (xy 374.461835 -270.565857) (xy 374.509623 -270.549454)
			(xy 374.55946 -270.541141) (xy 374.584722 -270.540734) (xy 374.609113 -270.541205) (xy 374.657275 -270.548948)
			(xy 374.703594 -270.564249) (xy 374.746892 -270.58672) (xy 374.786066 -270.615787) (xy 374.803416 -270.632936)
			(xy 374.810741 -270.639917) (xy 374.829311 -270.647915) (xy 374.849529 -270.648068) (xy 374.859042 -270.64462)
			(xy 374.94591 -270.60906) (xy 374.955084 -270.604874) (xy 374.96942 -270.590714) (xy 374.977238 -270.572143)
			(xy 374.97766 -270.56207) (xy 374.97766 -270.35252) (xy 374.95988 -270.326866) (xy 374.945148 -270.321024)
			(xy 374.922448 -270.311761) (xy 374.880099 -270.287063) (xy 374.842239 -270.255917) (xy 374.809841 -270.219123)
			(xy 374.783736 -270.177626) (xy 374.764594 -270.132492) (xy 374.752909 -270.08488) (xy 374.748978 -270.036013)
			(xy 374.752905 -269.987145) (xy 374.764586 -269.939533) (xy 374.783724 -269.894397) (xy 374.809825 -269.852898)
			(xy 374.84222 -269.816101) (xy 374.880078 -269.784952) (xy 374.922424 -269.76025) (xy 374.945148 -269.751048)
			(xy 374.95988 -269.745206) (xy 374.97766 -269.719552) (xy 374.97766 -268.732508) (xy 374.95988 -268.7066)
			(xy 374.945148 -268.701012) (xy 374.920831 -268.691072) (xy 374.875755 -268.6641) (xy 374.835961 -268.629809)
			(xy 374.802624 -268.589213) (xy 374.776729 -268.54351) (xy 374.759039 -268.494049) (xy 374.750077 -268.442289)
			(xy 374.749568 -268.416024) (xy 374.750027 -268.391852) (xy 374.757644 -268.344111) (xy 374.772691 -268.298167)
			(xy 374.794793 -268.25517) (xy 374.80875 -268.23543) (xy 374.819926 -268.22019) (xy 374.817132 -268.182852)
			(xy 374.554242 -267.919962) (xy 374.548785 -267.914837) (xy 374.535615 -267.907734) (xy 374.528334 -267.905992)
			(xy 374.527572 -267.905992) (xy 374.502062 -267.900595) (xy 374.453244 -267.882287) (xy 374.408243 -267.855957)
			(xy 374.368366 -267.822368) (xy 374.33477 -267.782496) (xy 374.308433 -267.737499) (xy 374.290117 -267.688683)
			(xy 374.284748 -267.663168) (xy 374.284748 -267.662406) (xy 374.282997 -267.655128) (xy 374.275899 -267.641957)
			(xy 374.270778 -267.636498) (xy 374.057926 -267.423646) (xy 374.050814 -267.41628) (xy 374.032018 -267.40866)
			(xy 373.100346 -267.40866) (xy 373.088818 -267.409216) (xy 373.068073 -267.41928) (xy 373.060468 -267.427964)
			(xy 373.003826 -267.5001) (xy 372.998746 -267.52296) (xy 373.00154 -267.534136) (xy 373.005577 -267.551832)
			(xy 373.009909 -267.58787) (xy 373.010176 -267.606018) (xy 373.009654 -267.631273) (xy 373.001341 -267.681095)
			(xy 372.98494 -267.728869) (xy 372.960899 -267.773292) (xy 372.929875 -267.813152) (xy 372.892713 -267.847362)
			(xy 372.850427 -267.874988) (xy 372.804171 -267.895278) (xy 372.755206 -267.907678) (xy 372.704868 -267.911849)
			(xy 372.65453 -267.907678) (xy 372.605565 -267.895278) (xy 372.559309 -267.874988) (xy 372.517023 -267.847362)
			(xy 372.479861 -267.813152) (xy 372.448837 -267.773292) (xy 372.424796 -267.728869) (xy 372.408395 -267.681095)
			(xy 372.400082 -267.631273) (xy 372.39956 -267.606018) (xy 372.399835 -267.58787) (xy 372.404163 -267.551832)
			(xy 372.408196 -267.534136) (xy 372.41099 -267.52296) (xy 372.40591 -267.5001) (xy 372.349268 -267.427964)
			(xy 372.341693 -267.419243) (xy 372.320928 -267.409176) (xy 372.30939 -267.40866) (xy 371.220238 -267.40866)
			(xy 371.208711 -267.409217) (xy 371.187969 -267.419284) (xy 371.18036 -267.427964) (xy 371.123718 -267.5001)
			(xy 371.118638 -267.52296) (xy 371.121432 -267.534136) (xy 371.125469 -267.551832) (xy 371.129802 -267.58787)
			(xy 371.130068 -267.606018) (xy 371.129546 -267.631273) (xy 371.121233 -267.681095) (xy 371.104832 -267.728869)
			(xy 371.080791 -267.773292) (xy 371.049767 -267.813152) (xy 371.012605 -267.847362) (xy 370.970319 -267.874988)
			(xy 370.924063 -267.895278) (xy 370.875098 -267.907678) (xy 370.82476 -267.911849) (xy 370.774422 -267.907678)
			(xy 370.725457 -267.895278) (xy 370.679201 -267.874988) (xy 370.636915 -267.847362) (xy 370.599753 -267.813152)
			(xy 370.568729 -267.773292) (xy 370.544688 -267.728869) (xy 370.528287 -267.681095) (xy 370.519974 -267.631273)
			(xy 370.519452 -267.606018) (xy 370.519727 -267.58787) (xy 370.524055 -267.551832) (xy 370.528088 -267.534136)
			(xy 370.530882 -267.52296) (xy 370.525802 -267.5001) (xy 370.46916 -267.427964) (xy 370.461584 -267.419245)
			(xy 370.44082 -267.40918) (xy 370.429282 -267.40866) (xy 369.340384 -267.40866) (xy 369.328852 -267.409208)
			(xy 369.308095 -267.419263) (xy 369.300506 -267.427964) (xy 369.243864 -267.5001) (xy 369.238784 -267.52296)
			(xy 369.241578 -267.534136) (xy 369.245614 -267.551832) (xy 369.249946 -267.58787) (xy 369.250214 -267.606018)
			(xy 369.249692 -267.631273) (xy 369.241379 -267.681095) (xy 369.224978 -267.728869) (xy 369.200937 -267.773292)
			(xy 369.169913 -267.813152) (xy 369.132751 -267.847362) (xy 369.090465 -267.874988) (xy 369.044209 -267.895278)
			(xy 368.995244 -267.907678) (xy 368.944906 -267.911849) (xy 368.894568 -267.907678) (xy 368.845603 -267.895278)
			(xy 368.799347 -267.874988) (xy 368.757061 -267.847362) (xy 368.719899 -267.813152) (xy 368.688875 -267.773292)
			(xy 368.664834 -267.728869) (xy 368.648433 -267.681095) (xy 368.64012 -267.631273) (xy 368.639598 -267.606018)
			(xy 368.639874 -267.58787) (xy 368.644202 -267.551833) (xy 368.648234 -267.534136) (xy 368.651028 -267.52296)
			(xy 368.645948 -267.5001) (xy 368.589306 -267.427964) (xy 368.581727 -267.419254) (xy 368.560962 -267.409211)
			(xy 368.549428 -267.40866) (xy 367.460276 -267.40866) (xy 367.448745 -267.409209) (xy 367.42799 -267.419266)
			(xy 367.420398 -267.427964) (xy 367.363756 -267.5001) (xy 367.358676 -267.52296) (xy 367.36147 -267.534136)
			(xy 367.365506 -267.551832) (xy 367.369839 -267.58787) (xy 367.370106 -267.606018) (xy 367.369584 -267.631273)
			(xy 367.361271 -267.681095) (xy 367.34487 -267.728869) (xy 367.320829 -267.773292) (xy 367.289805 -267.813152)
			(xy 367.252643 -267.847362) (xy 367.210357 -267.874988) (xy 367.164101 -267.895278) (xy 367.115136 -267.907678)
			(xy 367.064798 -267.911849) (xy 367.01446 -267.907678) (xy 366.965495 -267.895278) (xy 366.919239 -267.874988)
			(xy 366.876953 -267.847362) (xy 366.839791 -267.813152) (xy 366.808767 -267.773292) (xy 366.784726 -267.728869)
			(xy 366.768325 -267.681095) (xy 366.760012 -267.631273) (xy 366.75949 -267.606018) (xy 366.759766 -267.58787)
			(xy 366.764094 -267.551833) (xy 366.768126 -267.534136) (xy 366.77092 -267.52296) (xy 366.76584 -267.5001)
			(xy 366.709198 -267.427964) (xy 366.701619 -267.419255) (xy 366.680853 -267.409215) (xy 366.66932 -267.40866)
			(xy 365.580168 -267.40866) (xy 365.568638 -267.409211) (xy 365.547886 -267.41927) (xy 365.54029 -267.427964)
			(xy 365.483648 -267.5001) (xy 365.478568 -267.52296) (xy 365.481362 -267.534136) (xy 365.485398 -267.551832)
			(xy 365.489731 -267.58787) (xy 365.489998 -267.606018) (xy 365.489476 -267.631273) (xy 365.481163 -267.681095)
			(xy 365.464762 -267.728869) (xy 365.440721 -267.773292) (xy 365.409697 -267.813152) (xy 365.372535 -267.847362)
			(xy 365.330249 -267.874988) (xy 365.283993 -267.895278) (xy 365.235028 -267.907678) (xy 365.18469 -267.911849)
			(xy 365.134352 -267.907678) (xy 365.085387 -267.895278) (xy 365.039131 -267.874988) (xy 364.996845 -267.847362)
			(xy 364.959683 -267.813152) (xy 364.928659 -267.773292) (xy 364.904618 -267.728869) (xy 364.888217 -267.681095)
			(xy 364.879904 -267.631273) (xy 364.879382 -267.606018) (xy 364.879658 -267.58787) (xy 364.883986 -267.551832)
			(xy 364.888018 -267.534136) (xy 364.890812 -267.52296) (xy 364.885732 -267.5001) (xy 364.82909 -267.427964)
			(xy 364.82151 -267.419256) (xy 364.800745 -267.40922) (xy 364.789212 -267.40866) (xy 363.700314 -267.40866)
			(xy 363.688779 -267.409202) (xy 363.668012 -267.419249) (xy 363.660436 -267.427964) (xy 363.603794 -267.5001)
			(xy 363.598714 -267.52296) (xy 363.601508 -267.534136) (xy 363.605545 -267.551832) (xy 363.609878 -267.58787)
			(xy 363.610144 -267.606018) (xy 363.609622 -267.631273) (xy 363.601309 -267.681095) (xy 363.584908 -267.728869)
			(xy 363.560867 -267.773292) (xy 363.529843 -267.813152) (xy 363.492681 -267.847362) (xy 363.450395 -267.874988)
			(xy 363.404139 -267.895278) (xy 363.355174 -267.907678) (xy 363.304836 -267.911849) (xy 363.254498 -267.907678)
			(xy 363.205533 -267.895278) (xy 363.159277 -267.874988) (xy 363.116991 -267.847362) (xy 363.079829 -267.813152)
			(xy 363.048805 -267.773292) (xy 363.024764 -267.728869) (xy 363.008363 -267.681095) (xy 363.00005 -267.631273)
			(xy 362.999528 -267.606018) (xy 362.999804 -267.58787) (xy 363.004132 -267.551833) (xy 363.008164 -267.534136)
			(xy 363.010958 -267.52296) (xy 363.005878 -267.5001) (xy 362.949236 -267.427964) (xy 362.941659 -267.419248)
			(xy 362.920894 -267.409194) (xy 362.909358 -267.40866) (xy 361.820206 -267.40866) (xy 361.808672 -267.409203)
			(xy 361.787907 -267.419253) (xy 361.780328 -267.427964) (xy 361.723686 -267.5001) (xy 361.718606 -267.52296)
			(xy 361.7214 -267.534136) (xy 361.725437 -267.551832) (xy 361.72977 -267.58787) (xy 361.730036 -267.606018)
			(xy 361.729514 -267.631273) (xy 361.721201 -267.681095) (xy 361.7048 -267.728869) (xy 361.680759 -267.773292)
			(xy 361.649735 -267.813152) (xy 361.612573 -267.847362) (xy 361.570287 -267.874988) (xy 361.524031 -267.895278)
			(xy 361.475066 -267.907678) (xy 361.424728 -267.911849) (xy 361.37439 -267.907678) (xy 361.325425 -267.895278)
			(xy 361.279169 -267.874988) (xy 361.236883 -267.847362) (xy 361.199721 -267.813152) (xy 361.168697 -267.773292)
			(xy 361.144656 -267.728869) (xy 361.128255 -267.681095) (xy 361.119942 -267.631273) (xy 361.11942 -267.606018)
			(xy 361.119696 -267.58787) (xy 361.124024 -267.551833) (xy 361.128056 -267.534136) (xy 361.13085 -267.52296)
			(xy 361.12577 -267.5001) (xy 361.069128 -267.427964) (xy 361.061551 -267.41925) (xy 361.040785 -267.409198)
			(xy 361.02925 -267.40866) (xy 360.195622 -267.40866) (xy 360.189264 -267.408828) (xy 360.17693 -267.411917)
			(xy 360.171238 -267.414756) (xy 360.143966 -267.42898) (xy 360.085857 -267.449135) (xy 360.025206 -267.45935)
			(xy 359.994454 -267.459968) (xy 359.963704 -267.459329) (xy 359.903061 -267.449094) (xy 359.844948 -267.428964)
			(xy 359.81767 -267.414756) (xy 359.811982 -267.411906) (xy 359.799646 -267.408814) (xy 359.793286 -267.40866)
			(xy 359.319322 -267.40866) (xy 359.309259 -267.408221) (xy 359.290679 -267.400483) (xy 359.283254 -267.393674)
			(xy 358.619806 -266.730226) (xy 358.612483 -266.723417) (xy 358.594059 -266.715683) (xy 358.574078 -266.715616)
			(xy 358.564688 -266.71905) (xy 358.478074 -266.754102) (xy 358.469055 -266.758281) (xy 358.45487 -266.772178)
			(xy 358.447002 -266.790412) (xy 358.446324 -266.80033) (xy 358.446324 -266.800584) (xy 358.445514 -266.824337)
			(xy 358.437445 -266.871172) (xy 358.422214 -266.916191) (xy 358.400191 -266.958306) (xy 358.371907 -266.996498)
			(xy 358.338045 -267.029846) (xy 358.299425 -267.057542) (xy 358.256978 -267.078919) (xy 358.211732 -267.09346)
			(xy 358.164779 -267.100812) (xy 358.141016 -267.10132) (xy 358.117022 -267.100875) (xy 358.069624 -267.09337)
			(xy 358.023983 -267.078543) (xy 357.981224 -267.056759) (xy 357.942399 -267.028554) (xy 357.908464 -266.994622)
			(xy 357.880256 -266.9558) (xy 357.858467 -266.913043) (xy 357.843636 -266.867404) (xy 357.836127 -266.820006)
			(xy 357.835708 -266.796012) (xy 357.836071 -266.774314) (xy 357.842192 -266.731351) (xy 357.8479 -266.710414)
			(xy 357.851456 -266.69873) (xy 357.847138 -266.675616) (xy 357.791004 -266.60094) (xy 357.7834 -266.591838)
			(xy 357.762209 -266.581253) (xy 357.750364 -266.58062) (xy 357.591868 -266.58062) (xy 357.580026 -266.581246)
			(xy 357.558849 -266.591852) (xy 357.551228 -266.60094) (xy 357.495094 -266.675616) (xy 357.490776 -266.69873)
			(xy 357.494332 -266.710414) (xy 357.500032 -266.731353) (xy 357.506154 -266.774314) (xy 357.506524 -266.796012)
			(xy 357.506002 -266.821267) (xy 357.497689 -266.871089) (xy 357.481288 -266.918863) (xy 357.457247 -266.963286)
			(xy 357.426223 -267.003146) (xy 357.389061 -267.037356) (xy 357.346775 -267.064982) (xy 357.300519 -267.085272)
			(xy 357.251554 -267.097672) (xy 357.201216 -267.101843) (xy 357.150878 -267.097672) (xy 357.101913 -267.085272)
			(xy 357.055657 -267.064982) (xy 357.013371 -267.037356) (xy 356.976209 -267.003146) (xy 356.945185 -266.963286)
			(xy 356.921144 -266.918863) (xy 356.904743 -266.871089) (xy 356.89643 -266.821267) (xy 356.895908 -266.796012)
			(xy 356.896271 -266.774314) (xy 356.902392 -266.731351) (xy 356.9081 -266.710414) (xy 356.911656 -266.69873)
			(xy 356.907338 -266.675616) (xy 356.851204 -266.60094) (xy 356.843838 -266.591288) (xy 356.822756 -266.58062)
			(xy 355.71176 -266.58062) (xy 355.699919 -266.581248) (xy 355.678745 -266.591856) (xy 355.67112 -266.60094)
			(xy 355.614986 -266.675616) (xy 355.610668 -266.69873) (xy 355.614224 -266.710414) (xy 355.619924 -266.731353)
			(xy 355.626047 -266.774314) (xy 355.626416 -266.796012) (xy 355.625894 -266.821267) (xy 355.617581 -266.871089)
			(xy 355.60118 -266.918863) (xy 355.577139 -266.963286) (xy 355.546115 -267.003146) (xy 355.508953 -267.037356)
			(xy 355.466667 -267.064982) (xy 355.420411 -267.085272) (xy 355.371446 -267.097672) (xy 355.321108 -267.101843)
			(xy 355.27077 -267.097672) (xy 355.221805 -267.085272) (xy 355.175549 -267.064982) (xy 355.133263 -267.037356)
			(xy 355.096101 -267.003146) (xy 355.065077 -266.963286) (xy 355.041036 -266.918863) (xy 355.024635 -266.871089)
			(xy 355.016322 -266.821267) (xy 355.0158 -266.796012) (xy 355.016163 -266.774314) (xy 355.022284 -266.731351)
			(xy 355.027992 -266.710414) (xy 355.031548 -266.69873) (xy 355.02723 -266.675616) (xy 354.971096 -266.60094)
			(xy 354.96373 -266.591288) (xy 354.942648 -266.58062) (xy 354.771706 -266.58062) (xy 354.75986 -266.581238)
			(xy 354.73867 -266.591835) (xy 354.731066 -266.60094) (xy 354.674932 -266.675616) (xy 354.670614 -266.69873)
			(xy 354.67417 -266.710414) (xy 354.67987 -266.731353) (xy 354.685991 -266.774314) (xy 354.686362 -266.796012)
			(xy 354.68584 -266.821267) (xy 354.677527 -266.871089) (xy 354.661126 -266.918863) (xy 354.637085 -266.963286)
			(xy 354.606061 -267.003146) (xy 354.568899 -267.037356) (xy 354.526613 -267.064982) (xy 354.480357 -267.085272)
			(xy 354.431392 -267.097672) (xy 354.381054 -267.101843) (xy 354.330716 -267.097672) (xy 354.281751 -267.085272)
			(xy 354.235495 -267.064982) (xy 354.193209 -267.037356) (xy 354.156047 -267.003146) (xy 354.125023 -266.963286)
			(xy 354.100982 -266.918863) (xy 354.084581 -266.871089) (xy 354.076268 -266.821267) (xy 354.075746 -266.796012)
			(xy 354.076109 -266.774314) (xy 354.082231 -266.731352) (xy 354.087938 -266.710414) (xy 354.091494 -266.69873)
			(xy 354.087176 -266.675616) (xy 354.031042 -266.60094) (xy 354.023676 -266.591288) (xy 354.002594 -266.58062)
			(xy 353.831652 -266.58062) (xy 353.819812 -266.58125) (xy 353.79864 -266.59186) (xy 353.791012 -266.60094)
			(xy 353.734878 -266.675616) (xy 353.73056 -266.69873) (xy 353.734116 -266.710414) (xy 353.739816 -266.731353)
			(xy 353.745939 -266.774314) (xy 353.746308 -266.796012) (xy 353.745786 -266.821267) (xy 353.737473 -266.871089)
			(xy 353.721072 -266.918863) (xy 353.697031 -266.963286) (xy 353.666007 -267.003146) (xy 353.628845 -267.037356)
			(xy 353.586559 -267.064982) (xy 353.540303 -267.085272) (xy 353.491338 -267.097672) (xy 353.441 -267.101843)
			(xy 353.390662 -267.097672) (xy 353.341697 -267.085272) (xy 353.295441 -267.064982) (xy 353.253155 -267.037356)
			(xy 353.215993 -267.003146) (xy 353.184969 -266.963286) (xy 353.160928 -266.918863) (xy 353.144527 -266.871089)
			(xy 353.136214 -266.821267) (xy 353.135692 -266.796012) (xy 353.136055 -266.774314) (xy 353.142178 -266.731352)
			(xy 353.147884 -266.710414) (xy 353.15144 -266.69873) (xy 353.147122 -266.675616) (xy 353.090988 -266.60094)
			(xy 353.083622 -266.591288) (xy 353.06254 -266.58062) (xy 351.951798 -266.58062) (xy 351.939953 -266.58124)
			(xy 351.918765 -266.591839) (xy 351.911158 -266.60094) (xy 351.855024 -266.675616) (xy 351.850706 -266.69873)
			(xy 351.854262 -266.710414) (xy 351.859962 -266.731353) (xy 351.866084 -266.774314) (xy 351.866454 -266.796012)
			(xy 351.865932 -266.821267) (xy 351.857619 -266.871089) (xy 351.841218 -266.918863) (xy 351.817177 -266.963286)
			(xy 351.786153 -267.003146) (xy 351.748991 -267.037356) (xy 351.706705 -267.064982) (xy 351.660449 -267.085272)
			(xy 351.611484 -267.097672) (xy 351.561146 -267.101843) (xy 351.510808 -267.097672) (xy 351.461843 -267.085272)
			(xy 351.415587 -267.064982) (xy 351.373301 -267.037356) (xy 351.336139 -267.003146) (xy 351.305115 -266.963286)
			(xy 351.281074 -266.918863) (xy 351.264673 -266.871089) (xy 351.25636 -266.821267) (xy 351.255838 -266.796012)
			(xy 351.256201 -266.774314) (xy 351.262323 -266.731352) (xy 351.26803 -266.710414) (xy 351.271586 -266.69873)
			(xy 351.267268 -266.675616) (xy 351.211134 -266.60094) (xy 351.203768 -266.591288) (xy 351.182686 -266.58062)
			(xy 351.011744 -266.58062) (xy 350.999894 -266.58123) (xy 350.978691 -266.591818) (xy 350.971104 -266.60094)
			(xy 350.91497 -266.675616) (xy 350.910652 -266.69873) (xy 350.914208 -266.710414) (xy 350.919908 -266.731353)
			(xy 350.926031 -266.774314) (xy 350.9264 -266.796012) (xy 350.925878 -266.821267) (xy 350.917565 -266.871089)
			(xy 350.901164 -266.918863) (xy 350.877123 -266.963286) (xy 350.846099 -267.003146) (xy 350.808937 -267.037356)
			(xy 350.766651 -267.064982) (xy 350.720395 -267.085272) (xy 350.67143 -267.097672) (xy 350.621092 -267.101843)
			(xy 350.570754 -267.097672) (xy 350.521789 -267.085272) (xy 350.475533 -267.064982) (xy 350.433247 -267.037356)
			(xy 350.396085 -267.003146) (xy 350.365061 -266.963286) (xy 350.34102 -266.918863) (xy 350.324619 -266.871089)
			(xy 350.316306 -266.821267) (xy 350.315784 -266.796012) (xy 350.316147 -266.774314) (xy 350.32227 -266.731352)
			(xy 350.327976 -266.710414) (xy 350.331532 -266.69873) (xy 350.327214 -266.675616) (xy 350.27108 -266.60094)
			(xy 350.263714 -266.591288) (xy 350.242632 -266.58062) (xy 350.07169 -266.58062) (xy 350.059846 -266.581242)
			(xy 350.038661 -266.591842) (xy 350.03105 -266.60094) (xy 349.974916 -266.675616) (xy 349.970598 -266.69873)
			(xy 349.974154 -266.710414) (xy 349.979854 -266.731353) (xy 349.985976 -266.774314) (xy 349.986346 -266.796012)
			(xy 349.985824 -266.821267) (xy 349.977511 -266.871089) (xy 349.96111 -266.918863) (xy 349.937069 -266.963286)
			(xy 349.906045 -267.003146) (xy 349.868883 -267.037356) (xy 349.826597 -267.064982) (xy 349.780341 -267.085272)
			(xy 349.731376 -267.097672) (xy 349.681038 -267.101843) (xy 349.6307 -267.097672) (xy 349.581735 -267.085272)
			(xy 349.535479 -267.064982) (xy 349.493193 -267.037356) (xy 349.456031 -267.003146) (xy 349.425007 -266.963286)
			(xy 349.400966 -266.918863) (xy 349.384565 -266.871089) (xy 349.376252 -266.821267) (xy 349.37573 -266.796012)
			(xy 349.376093 -266.774314) (xy 349.382215 -266.731352) (xy 349.387922 -266.710414) (xy 349.391478 -266.69873)
			(xy 349.38716 -266.675616) (xy 349.331026 -266.60094) (xy 349.32366 -266.591288) (xy 349.302578 -266.58062)
			(xy 348.191836 -266.58062) (xy 348.179987 -266.581232) (xy 348.158786 -266.591821) (xy 348.151196 -266.60094)
			(xy 348.095062 -266.675616) (xy 348.090744 -266.69873) (xy 348.0943 -266.710414) (xy 348.1 -266.731353)
			(xy 348.106123 -266.774314) (xy 348.106492 -266.796012) (xy 348.10597 -266.821267) (xy 348.097657 -266.871089)
			(xy 348.081256 -266.918863) (xy 348.057215 -266.963286) (xy 348.026191 -267.003146) (xy 347.989029 -267.037356)
			(xy 347.946743 -267.064982) (xy 347.900487 -267.085272) (xy 347.851522 -267.097672) (xy 347.801184 -267.101843)
			(xy 347.750846 -267.097672) (xy 347.701881 -267.085272) (xy 347.655625 -267.064982) (xy 347.613339 -267.037356)
			(xy 347.576177 -267.003146) (xy 347.545153 -266.963286) (xy 347.521112 -266.918863) (xy 347.504711 -266.871089)
			(xy 347.496398 -266.821267) (xy 347.495876 -266.796012) (xy 347.496239 -266.774314) (xy 347.502362 -266.731352)
			(xy 347.508068 -266.710414) (xy 347.511624 -266.69873) (xy 347.507306 -266.675616) (xy 347.451172 -266.60094)
			(xy 347.443806 -266.591288) (xy 347.422724 -266.58062) (xy 347.251782 -266.58062) (xy 347.239939 -266.581243)
			(xy 347.218757 -266.591846) (xy 347.211142 -266.60094) (xy 347.155008 -266.675616) (xy 347.15069 -266.69873)
			(xy 347.154246 -266.710414) (xy 347.159946 -266.731353) (xy 347.166068 -266.774314) (xy 347.166438 -266.796012)
			(xy 347.165967 -266.820003) (xy 347.158459 -266.867395) (xy 347.143631 -266.91303) (xy 347.121847 -266.955783)
			(xy 347.093644 -266.994602) (xy 347.059716 -267.028533) (xy 347.020898 -267.056738) (xy 346.978146 -267.078524)
			(xy 346.932513 -267.093355) (xy 346.885121 -267.100865) (xy 346.86113 -267.10132) (xy 346.837405 -267.100865)
			(xy 346.790529 -267.093516) (xy 346.745353 -267.079006) (xy 346.702964 -267.057685) (xy 346.664382 -267.030064)
			(xy 346.630537 -266.996809) (xy 346.602241 -266.95872) (xy 346.580176 -266.916713) (xy 346.564874 -266.871799)
			(xy 346.556701 -266.825059) (xy 346.555822 -266.801346) (xy 346.555822 -266.796774) (xy 346.556208 -266.772163)
			(xy 346.563953 -266.723558) (xy 346.579415 -266.676832) (xy 346.590366 -266.654788) (xy 346.59316 -266.6492)
			(xy 346.596208 -266.63777) (xy 346.596208 -266.63142) (xy 346.595792 -266.621395) (xy 346.588126 -266.60287)
			(xy 346.573953 -266.58869) (xy 346.555432 -266.581014) (xy 346.545408 -266.58062) (xy 346.515182 -266.58062)
			(xy 346.505114 -266.581047) (xy 346.486516 -266.588768) (xy 346.479114 -266.595606) (xy 346.226384 -266.848336)
			(xy 346.21978 -266.860274) (xy 346.218002 -266.867386) (xy 346.211938 -266.890596) (xy 346.19357 -266.934907)
			(xy 346.168499 -266.975802) (xy 346.137343 -267.012274) (xy 346.100867 -267.043425) (xy 346.059969 -267.06849)
			(xy 346.015654 -267.086852) (xy 345.99245 -267.092938) (xy 345.985338 -267.094716) (xy 345.9734 -267.10132)
			(xy 345.694508 -267.380212) (xy 345.69146 -267.416534) (xy 345.701874 -267.431774) (xy 345.714752 -267.451065)
			(xy 345.73515 -267.49272) (xy 345.749015 -267.53698) (xy 345.756026 -267.582828) (xy 345.756484 -267.606018)
			(xy 346.085426 -267.606018) (xy 346.089386 -267.556964) (xy 346.101163 -267.50918) (xy 346.120454 -267.463904)
			(xy 346.146757 -267.422308) (xy 346.179392 -267.385471) (xy 346.217513 -267.354346) (xy 346.260134 -267.329739)
			(xy 346.30615 -267.312287) (xy 346.354369 -267.302443) (xy 346.403544 -267.300462) (xy 346.452399 -267.306394)
			(xy 346.49967 -267.320086) (xy 346.544132 -267.341184) (xy 346.584635 -267.36914) (xy 346.620128 -267.403232)
			(xy 346.649693 -267.442576) (xy 346.672564 -267.486153) (xy 346.688148 -267.532834) (xy 346.696043 -267.581411)
			(xy 346.696538 -267.606018) (xy 347.025226 -267.606018) (xy 347.029186 -267.556964) (xy 347.040963 -267.50918)
			(xy 347.060254 -267.463904) (xy 347.086557 -267.422308) (xy 347.119192 -267.385471) (xy 347.157313 -267.354346)
			(xy 347.199934 -267.329739) (xy 347.24595 -267.312287) (xy 347.294169 -267.302443) (xy 347.343344 -267.300462)
			(xy 347.392199 -267.306394) (xy 347.43947 -267.320086) (xy 347.483932 -267.341184) (xy 347.524435 -267.36914)
			(xy 347.559928 -267.403232) (xy 347.589493 -267.442576) (xy 347.612364 -267.486153) (xy 347.627948 -267.532834)
			(xy 347.635843 -267.581411) (xy 347.636338 -267.606018) (xy 347.96528 -267.606018) (xy 347.96924 -267.556964)
			(xy 347.981017 -267.50918) (xy 348.000308 -267.463904) (xy 348.026611 -267.422308) (xy 348.059246 -267.385471)
			(xy 348.097367 -267.354346) (xy 348.139988 -267.329739) (xy 348.186004 -267.312287) (xy 348.234223 -267.302443)
			(xy 348.283398 -267.300462) (xy 348.332253 -267.306394) (xy 348.379524 -267.320086) (xy 348.423986 -267.341184)
			(xy 348.464489 -267.36914) (xy 348.499982 -267.403232) (xy 348.529547 -267.442576) (xy 348.552418 -267.486153)
			(xy 348.568002 -267.532834) (xy 348.575897 -267.581411) (xy 348.576392 -267.606018) (xy 349.845388 -267.606018)
			(xy 349.849348 -267.556964) (xy 349.861125 -267.50918) (xy 349.880416 -267.463904) (xy 349.906719 -267.422308)
			(xy 349.939354 -267.385471) (xy 349.977475 -267.354346) (xy 350.020096 -267.329739) (xy 350.066112 -267.312287)
			(xy 350.114331 -267.302443) (xy 350.163506 -267.300462) (xy 350.212361 -267.306394) (xy 350.259632 -267.320086)
			(xy 350.304094 -267.341184) (xy 350.344597 -267.36914) (xy 350.38009 -267.403232) (xy 350.409655 -267.442576)
			(xy 350.432526 -267.486153) (xy 350.44811 -267.532834) (xy 350.456005 -267.581411) (xy 350.4565 -267.606018)
			(xy 351.725242 -267.606018) (xy 351.729202 -267.556964) (xy 351.740979 -267.50918) (xy 351.76027 -267.463904)
			(xy 351.786573 -267.422308) (xy 351.819208 -267.385471) (xy 351.857329 -267.354346) (xy 351.89995 -267.329739)
			(xy 351.945966 -267.312287) (xy 351.994185 -267.302443) (xy 352.04336 -267.300462) (xy 352.092215 -267.306394)
			(xy 352.139486 -267.320086) (xy 352.183948 -267.341184) (xy 352.224451 -267.36914) (xy 352.259944 -267.403232)
			(xy 352.289509 -267.442576) (xy 352.31238 -267.486153) (xy 352.327964 -267.532834) (xy 352.335859 -267.581411)
			(xy 352.336354 -267.606018) (xy 353.60535 -267.606018) (xy 353.60931 -267.556964) (xy 353.621087 -267.50918)
			(xy 353.640378 -267.463904) (xy 353.666681 -267.422308) (xy 353.699316 -267.385471) (xy 353.737437 -267.354346)
			(xy 353.780058 -267.329739) (xy 353.826074 -267.312287) (xy 353.874293 -267.302443) (xy 353.923468 -267.300462)
			(xy 353.972323 -267.306394) (xy 354.019594 -267.320086) (xy 354.064056 -267.341184) (xy 354.104559 -267.36914)
			(xy 354.140052 -267.403232) (xy 354.169617 -267.442576) (xy 354.192488 -267.486153) (xy 354.208072 -267.532834)
			(xy 354.215967 -267.581411) (xy 354.216462 -267.606018) (xy 355.485204 -267.606018) (xy 355.489164 -267.556964)
			(xy 355.500941 -267.50918) (xy 355.520232 -267.463904) (xy 355.546535 -267.422308) (xy 355.57917 -267.385471)
			(xy 355.617291 -267.354346) (xy 355.659912 -267.329739) (xy 355.705928 -267.312287) (xy 355.754147 -267.302443)
			(xy 355.803322 -267.300462) (xy 355.852177 -267.306394) (xy 355.899448 -267.320086) (xy 355.94391 -267.341184)
			(xy 355.984413 -267.36914) (xy 356.019906 -267.403232) (xy 356.049471 -267.442576) (xy 356.072342 -267.486153)
			(xy 356.087926 -267.532834) (xy 356.095821 -267.581411) (xy 356.096316 -267.606018) (xy 357.365312 -267.606018)
			(xy 357.369272 -267.556964) (xy 357.381049 -267.50918) (xy 357.40034 -267.463904) (xy 357.426643 -267.422308)
			(xy 357.459278 -267.385471) (xy 357.497399 -267.354346) (xy 357.54002 -267.329739) (xy 357.586036 -267.312287)
			(xy 357.634255 -267.302443) (xy 357.68343 -267.300462) (xy 357.732285 -267.306394) (xy 357.779556 -267.320086)
			(xy 357.824018 -267.341184) (xy 357.864521 -267.36914) (xy 357.900014 -267.403232) (xy 357.929579 -267.442576)
			(xy 357.95245 -267.486153) (xy 357.968034 -267.532834) (xy 357.975929 -267.581411) (xy 357.976424 -267.606018)
			(xy 357.975929 -267.630625) (xy 357.968034 -267.679202) (xy 357.95245 -267.725883) (xy 357.929579 -267.76946)
			(xy 357.900014 -267.808804) (xy 357.864521 -267.842896) (xy 357.824018 -267.870852) (xy 357.779556 -267.89195)
			(xy 357.732285 -267.905642) (xy 357.68343 -267.911574) (xy 357.634255 -267.909593) (xy 357.586036 -267.899749)
			(xy 357.54002 -267.882297) (xy 357.497399 -267.85769) (xy 357.459278 -267.826565) (xy 357.426643 -267.789728)
			(xy 357.40034 -267.748132) (xy 357.381049 -267.702856) (xy 357.369272 -267.655072) (xy 357.365312 -267.606018)
			(xy 356.096316 -267.606018) (xy 356.095821 -267.630625) (xy 356.087926 -267.679202) (xy 356.072342 -267.725883)
			(xy 356.049471 -267.76946) (xy 356.019906 -267.808804) (xy 355.984413 -267.842896) (xy 355.94391 -267.870852)
			(xy 355.899448 -267.89195) (xy 355.852177 -267.905642) (xy 355.803322 -267.911574) (xy 355.754147 -267.909593)
			(xy 355.705928 -267.899749) (xy 355.659912 -267.882297) (xy 355.617291 -267.85769) (xy 355.57917 -267.826565)
			(xy 355.546535 -267.789728) (xy 355.520232 -267.748132) (xy 355.500941 -267.702856) (xy 355.489164 -267.655072)
			(xy 355.485204 -267.606018) (xy 354.216462 -267.606018) (xy 354.215967 -267.630625) (xy 354.208072 -267.679202)
			(xy 354.192488 -267.725883) (xy 354.169617 -267.76946) (xy 354.140052 -267.808804) (xy 354.104559 -267.842896)
			(xy 354.064056 -267.870852) (xy 354.019594 -267.89195) (xy 353.972323 -267.905642) (xy 353.923468 -267.911574)
			(xy 353.874293 -267.909593) (xy 353.826074 -267.899749) (xy 353.780058 -267.882297) (xy 353.737437 -267.85769)
			(xy 353.699316 -267.826565) (xy 353.666681 -267.789728) (xy 353.640378 -267.748132) (xy 353.621087 -267.702856)
			(xy 353.60931 -267.655072) (xy 353.60535 -267.606018) (xy 352.336354 -267.606018) (xy 352.335859 -267.630625)
			(xy 352.327964 -267.679202) (xy 352.31238 -267.725883) (xy 352.289509 -267.76946) (xy 352.259944 -267.808804)
			(xy 352.224451 -267.842896) (xy 352.183948 -267.870852) (xy 352.139486 -267.89195) (xy 352.092215 -267.905642)
			(xy 352.04336 -267.911574) (xy 351.994185 -267.909593) (xy 351.945966 -267.899749) (xy 351.89995 -267.882297)
			(xy 351.857329 -267.85769) (xy 351.819208 -267.826565) (xy 351.786573 -267.789728) (xy 351.76027 -267.748132)
			(xy 351.740979 -267.702856) (xy 351.729202 -267.655072) (xy 351.725242 -267.606018) (xy 350.4565 -267.606018)
			(xy 350.456005 -267.630625) (xy 350.44811 -267.679202) (xy 350.432526 -267.725883) (xy 350.409655 -267.76946)
			(xy 350.38009 -267.808804) (xy 350.344597 -267.842896) (xy 350.304094 -267.870852) (xy 350.259632 -267.89195)
			(xy 350.212361 -267.905642) (xy 350.163506 -267.911574) (xy 350.114331 -267.909593) (xy 350.066112 -267.899749)
			(xy 350.020096 -267.882297) (xy 349.977475 -267.85769) (xy 349.939354 -267.826565) (xy 349.906719 -267.789728)
			(xy 349.880416 -267.748132) (xy 349.861125 -267.702856) (xy 349.849348 -267.655072) (xy 349.845388 -267.606018)
			(xy 348.576392 -267.606018) (xy 348.575897 -267.630625) (xy 348.568002 -267.679202) (xy 348.552418 -267.725883)
			(xy 348.529547 -267.76946) (xy 348.499982 -267.808804) (xy 348.464489 -267.842896) (xy 348.423986 -267.870852)
			(xy 348.379524 -267.89195) (xy 348.332253 -267.905642) (xy 348.283398 -267.911574) (xy 348.234223 -267.909593)
			(xy 348.186004 -267.899749) (xy 348.139988 -267.882297) (xy 348.097367 -267.85769) (xy 348.059246 -267.826565)
			(xy 348.026611 -267.789728) (xy 348.000308 -267.748132) (xy 347.981017 -267.702856) (xy 347.96924 -267.655072)
			(xy 347.96528 -267.606018) (xy 347.636338 -267.606018) (xy 347.635843 -267.630625) (xy 347.627948 -267.679202)
			(xy 347.612364 -267.725883) (xy 347.589493 -267.76946) (xy 347.559928 -267.808804) (xy 347.524435 -267.842896)
			(xy 347.483932 -267.870852) (xy 347.43947 -267.89195) (xy 347.392199 -267.905642) (xy 347.343344 -267.911574)
			(xy 347.294169 -267.909593) (xy 347.24595 -267.899749) (xy 347.199934 -267.882297) (xy 347.157313 -267.85769)
			(xy 347.119192 -267.826565) (xy 347.086557 -267.789728) (xy 347.060254 -267.748132) (xy 347.040963 -267.702856)
			(xy 347.029186 -267.655072) (xy 347.025226 -267.606018) (xy 346.696538 -267.606018) (xy 346.696043 -267.630625)
			(xy 346.688148 -267.679202) (xy 346.672564 -267.725883) (xy 346.649693 -267.76946) (xy 346.620128 -267.808804)
			(xy 346.584635 -267.842896) (xy 346.544132 -267.870852) (xy 346.49967 -267.89195) (xy 346.452399 -267.905642)
			(xy 346.403544 -267.911574) (xy 346.354369 -267.909593) (xy 346.30615 -267.899749) (xy 346.260134 -267.882297)
			(xy 346.217513 -267.85769) (xy 346.179392 -267.826565) (xy 346.146757 -267.789728) (xy 346.120454 -267.748132)
			(xy 346.101163 -267.702856) (xy 346.089386 -267.655072) (xy 346.085426 -267.606018) (xy 345.756484 -267.606018)
			(xy 345.756036 -267.63001) (xy 345.748527 -267.677401) (xy 345.733697 -267.723035) (xy 345.71191 -267.765787)
			(xy 345.683704 -267.804604) (xy 345.649772 -267.838531) (xy 345.610951 -267.866732) (xy 345.568196 -267.888513)
			(xy 345.522561 -267.903337) (xy 345.475168 -267.91084) (xy 345.451176 -267.911326) (xy 345.427985 -267.910892)
			(xy 345.382138 -267.903871) (xy 345.337881 -267.889994) (xy 345.296233 -267.869581) (xy 345.276932 -267.856716)
			(xy 345.261692 -267.846302) (xy 345.22537 -267.84935) (xy 345.06916 -268.00556) (xy 359.650541 -268.00556)
			(xy 359.654571 -267.953062) (xy 359.666568 -267.901794) (xy 359.686251 -267.852959) (xy 359.713157 -267.8077)
			(xy 359.746657 -267.767079) (xy 359.785965 -267.732048) (xy 359.83016 -267.703428) (xy 359.878205 -267.681889)
			(xy 359.928976 -267.667937) (xy 359.981281 -267.661899) (xy 360.033895 -267.663916) (xy 360.085585 -267.67394)
			(xy 360.135138 -267.691738) (xy 360.181394 -267.716891) (xy 360.223268 -267.74881) (xy 360.25978 -267.786748)
			(xy 360.290072 -267.829814) (xy 360.313435 -267.876999) (xy 360.329321 -267.927198) (xy 360.337358 -267.979234)
			(xy 360.337862 -268.00556) (xy 360.337358 -268.031886) (xy 360.329321 -268.083922) (xy 360.313435 -268.134121)
			(xy 360.290072 -268.181306) (xy 360.25978 -268.224372) (xy 360.223268 -268.26231) (xy 360.181394 -268.294229)
			(xy 360.135138 -268.319382) (xy 360.085585 -268.33718) (xy 360.033895 -268.347204) (xy 359.981281 -268.349221)
			(xy 359.928976 -268.343183) (xy 359.878205 -268.329231) (xy 359.83016 -268.307692) (xy 359.785965 -268.279072)
			(xy 359.746657 -268.244041) (xy 359.713157 -268.20342) (xy 359.686251 -268.158161) (xy 359.666568 -268.109326)
			(xy 359.654571 -268.058058) (xy 359.650541 -268.00556) (xy 345.06916 -268.00556) (xy 345.068906 -268.005814)
			(xy 345.06154 -268.012926) (xy 345.05392 -268.031722) (xy 345.05392 -268.082014) (xy 345.054408 -268.092386)
			(xy 345.06259 -268.111448) (xy 345.077624 -268.125742) (xy 345.087194 -268.129766) (xy 345.087702 -268.13002)
			(xy 345.110689 -268.139106) (xy 345.153609 -268.16362) (xy 345.192018 -268.194729) (xy 345.224912 -268.231619)
			(xy 345.251433 -268.273328) (xy 345.270888 -268.318765) (xy 345.282767 -268.366743) (xy 345.28676 -268.416008)
			(xy 345.286759 -268.416024) (xy 345.615272 -268.416024) (xy 345.619232 -268.36697) (xy 345.631009 -268.319186)
			(xy 345.6503 -268.27391) (xy 345.676603 -268.232314) (xy 345.709238 -268.195477) (xy 345.747359 -268.164352)
			(xy 345.78998 -268.139745) (xy 345.835996 -268.122293) (xy 345.884215 -268.112449) (xy 345.93339 -268.110468)
			(xy 345.982245 -268.1164) (xy 346.029516 -268.130092) (xy 346.073978 -268.15119) (xy 346.114481 -268.179146)
			(xy 346.149974 -268.213238) (xy 346.179539 -268.252582) (xy 346.20241 -268.296159) (xy 346.217994 -268.34284)
			(xy 346.225889 -268.391417) (xy 346.226384 -268.416024) (xy 347.49538 -268.416024) (xy 347.49934 -268.36697)
			(xy 347.511117 -268.319186) (xy 347.530408 -268.27391) (xy 347.556711 -268.232314) (xy 347.589346 -268.195477)
			(xy 347.627467 -268.164352) (xy 347.670088 -268.139745) (xy 347.716104 -268.122293) (xy 347.764323 -268.112449)
			(xy 347.813498 -268.110468) (xy 347.862353 -268.1164) (xy 347.909624 -268.130092) (xy 347.954086 -268.15119)
			(xy 347.994589 -268.179146) (xy 348.030082 -268.213238) (xy 348.059647 -268.252582) (xy 348.082518 -268.296159)
			(xy 348.098102 -268.34284) (xy 348.105997 -268.391417) (xy 348.106492 -268.416024) (xy 349.375234 -268.416024)
			(xy 349.379194 -268.36697) (xy 349.390971 -268.319186) (xy 349.410262 -268.27391) (xy 349.436565 -268.232314)
			(xy 349.4692 -268.195477) (xy 349.507321 -268.164352) (xy 349.549942 -268.139745) (xy 349.595958 -268.122293)
			(xy 349.644177 -268.112449) (xy 349.693352 -268.110468) (xy 349.742207 -268.1164) (xy 349.789478 -268.130092)
			(xy 349.83394 -268.15119) (xy 349.874443 -268.179146) (xy 349.909936 -268.213238) (xy 349.939501 -268.252582)
			(xy 349.962372 -268.296159) (xy 349.977956 -268.34284) (xy 349.985851 -268.391417) (xy 349.986346 -268.416024)
			(xy 351.255342 -268.416024) (xy 351.259302 -268.36697) (xy 351.271079 -268.319186) (xy 351.29037 -268.27391)
			(xy 351.316673 -268.232314) (xy 351.349308 -268.195477) (xy 351.387429 -268.164352) (xy 351.43005 -268.139745)
			(xy 351.476066 -268.122293) (xy 351.524285 -268.112449) (xy 351.57346 -268.110468) (xy 351.622315 -268.1164)
			(xy 351.669586 -268.130092) (xy 351.714048 -268.15119) (xy 351.754551 -268.179146) (xy 351.790044 -268.213238)
			(xy 351.819609 -268.252582) (xy 351.84248 -268.296159) (xy 351.858064 -268.34284) (xy 351.865959 -268.391417)
			(xy 351.866454 -268.416024) (xy 353.135196 -268.416024) (xy 353.139156 -268.36697) (xy 353.150933 -268.319186)
			(xy 353.170224 -268.27391) (xy 353.196527 -268.232314) (xy 353.229162 -268.195477) (xy 353.267283 -268.164352)
			(xy 353.309904 -268.139745) (xy 353.35592 -268.122293) (xy 353.404139 -268.112449) (xy 353.453314 -268.110468)
			(xy 353.502169 -268.1164) (xy 353.54944 -268.130092) (xy 353.593902 -268.15119) (xy 353.634405 -268.179146)
			(xy 353.669898 -268.213238) (xy 353.699463 -268.252582) (xy 353.722334 -268.296159) (xy 353.737918 -268.34284)
			(xy 353.745813 -268.391417) (xy 353.746308 -268.416024) (xy 355.015304 -268.416024) (xy 355.019264 -268.36697)
			(xy 355.031041 -268.319186) (xy 355.050332 -268.27391) (xy 355.076635 -268.232314) (xy 355.10927 -268.195477)
			(xy 355.147391 -268.164352) (xy 355.190012 -268.139745) (xy 355.236028 -268.122293) (xy 355.284247 -268.112449)
			(xy 355.333422 -268.110468) (xy 355.382277 -268.1164) (xy 355.429548 -268.130092) (xy 355.47401 -268.15119)
			(xy 355.514513 -268.179146) (xy 355.550006 -268.213238) (xy 355.579571 -268.252582) (xy 355.602442 -268.296159)
			(xy 355.618026 -268.34284) (xy 355.625921 -268.391417) (xy 355.626416 -268.416024) (xy 356.895412 -268.416024)
			(xy 356.899372 -268.36697) (xy 356.911149 -268.319186) (xy 356.93044 -268.27391) (xy 356.956743 -268.232314)
			(xy 356.989378 -268.195477) (xy 357.027499 -268.164352) (xy 357.07012 -268.139745) (xy 357.116136 -268.122293)
			(xy 357.164355 -268.112449) (xy 357.21353 -268.110468) (xy 357.262385 -268.1164) (xy 357.309656 -268.130092)
			(xy 357.354118 -268.15119) (xy 357.394621 -268.179146) (xy 357.430114 -268.213238) (xy 357.459679 -268.252582)
			(xy 357.48255 -268.296159) (xy 357.498134 -268.34284) (xy 357.506029 -268.391417) (xy 357.506524 -268.416024)
			(xy 361.589078 -268.416024) (xy 361.593038 -268.36697) (xy 361.604815 -268.319186) (xy 361.624106 -268.27391)
			(xy 361.650409 -268.232314) (xy 361.683044 -268.195477) (xy 361.721165 -268.164352) (xy 361.763786 -268.139745)
			(xy 361.809802 -268.122293) (xy 361.858021 -268.112449) (xy 361.907196 -268.110468) (xy 361.956051 -268.1164)
			(xy 362.003322 -268.130092) (xy 362.047784 -268.15119) (xy 362.088287 -268.179146) (xy 362.12378 -268.213238)
			(xy 362.153345 -268.252582) (xy 362.176216 -268.296159) (xy 362.1918 -268.34284) (xy 362.199695 -268.391417)
			(xy 362.20019 -268.416024) (xy 363.468932 -268.416024) (xy 363.472892 -268.36697) (xy 363.484669 -268.319186)
			(xy 363.50396 -268.27391) (xy 363.530263 -268.232314) (xy 363.562898 -268.195477) (xy 363.601019 -268.164352)
			(xy 363.64364 -268.139745) (xy 363.689656 -268.122293) (xy 363.737875 -268.112449) (xy 363.78705 -268.110468)
			(xy 363.835905 -268.1164) (xy 363.883176 -268.130092) (xy 363.927638 -268.15119) (xy 363.968141 -268.179146)
			(xy 364.003634 -268.213238) (xy 364.033199 -268.252582) (xy 364.05607 -268.296159) (xy 364.071654 -268.34284)
			(xy 364.079549 -268.391417) (xy 364.080044 -268.416024) (xy 365.34904 -268.416024) (xy 365.353 -268.36697)
			(xy 365.364777 -268.319186) (xy 365.384068 -268.27391) (xy 365.410371 -268.232314) (xy 365.443006 -268.195477)
			(xy 365.481127 -268.164352) (xy 365.523748 -268.139745) (xy 365.569764 -268.122293) (xy 365.617983 -268.112449)
			(xy 365.667158 -268.110468) (xy 365.716013 -268.1164) (xy 365.763284 -268.130092) (xy 365.807746 -268.15119)
			(xy 365.848249 -268.179146) (xy 365.883742 -268.213238) (xy 365.913307 -268.252582) (xy 365.936178 -268.296159)
			(xy 365.951762 -268.34284) (xy 365.959657 -268.391417) (xy 365.960152 -268.416024) (xy 367.228894 -268.416024)
			(xy 367.232854 -268.36697) (xy 367.244631 -268.319186) (xy 367.263922 -268.27391) (xy 367.290225 -268.232314)
			(xy 367.32286 -268.195477) (xy 367.360981 -268.164352) (xy 367.403602 -268.139745) (xy 367.449618 -268.122293)
			(xy 367.497837 -268.112449) (xy 367.547012 -268.110468) (xy 367.595867 -268.1164) (xy 367.643138 -268.130092)
			(xy 367.6876 -268.15119) (xy 367.728103 -268.179146) (xy 367.763596 -268.213238) (xy 367.793161 -268.252582)
			(xy 367.816032 -268.296159) (xy 367.831616 -268.34284) (xy 367.839511 -268.391417) (xy 367.840006 -268.416024)
			(xy 369.109002 -268.416024) (xy 369.112962 -268.36697) (xy 369.124739 -268.319186) (xy 369.14403 -268.27391)
			(xy 369.170333 -268.232314) (xy 369.202968 -268.195477) (xy 369.241089 -268.164352) (xy 369.28371 -268.139745)
			(xy 369.329726 -268.122293) (xy 369.377945 -268.112449) (xy 369.42712 -268.110468) (xy 369.475975 -268.1164)
			(xy 369.523246 -268.130092) (xy 369.567708 -268.15119) (xy 369.608211 -268.179146) (xy 369.643704 -268.213238)
			(xy 369.673269 -268.252582) (xy 369.69614 -268.296159) (xy 369.711724 -268.34284) (xy 369.719619 -268.391417)
			(xy 369.720114 -268.416024) (xy 370.98911 -268.416024) (xy 370.99307 -268.36697) (xy 371.004847 -268.319186)
			(xy 371.024138 -268.27391) (xy 371.050441 -268.232314) (xy 371.083076 -268.195477) (xy 371.121197 -268.164352)
			(xy 371.163818 -268.139745) (xy 371.209834 -268.122293) (xy 371.258053 -268.112449) (xy 371.307228 -268.110468)
			(xy 371.356083 -268.1164) (xy 371.403354 -268.130092) (xy 371.447816 -268.15119) (xy 371.488319 -268.179146)
			(xy 371.523812 -268.213238) (xy 371.553377 -268.252582) (xy 371.576248 -268.296159) (xy 371.591832 -268.34284)
			(xy 371.599727 -268.391417) (xy 371.600222 -268.416024) (xy 372.868964 -268.416024) (xy 372.872924 -268.36697)
			(xy 372.884701 -268.319186) (xy 372.903992 -268.27391) (xy 372.930295 -268.232314) (xy 372.96293 -268.195477)
			(xy 373.001051 -268.164352) (xy 373.043672 -268.139745) (xy 373.089688 -268.122293) (xy 373.137907 -268.112449)
			(xy 373.187082 -268.110468) (xy 373.235937 -268.1164) (xy 373.283208 -268.130092) (xy 373.32767 -268.15119)
			(xy 373.368173 -268.179146) (xy 373.403666 -268.213238) (xy 373.433231 -268.252582) (xy 373.456102 -268.296159)
			(xy 373.471686 -268.34284) (xy 373.479581 -268.391417) (xy 373.480076 -268.416024) (xy 373.479581 -268.440631)
			(xy 373.471686 -268.489208) (xy 373.456102 -268.535889) (xy 373.433231 -268.579466) (xy 373.403666 -268.61881)
			(xy 373.368173 -268.652902) (xy 373.32767 -268.680858) (xy 373.283208 -268.701956) (xy 373.235937 -268.715648)
			(xy 373.187082 -268.72158) (xy 373.137907 -268.719599) (xy 373.089688 -268.709755) (xy 373.043672 -268.692303)
			(xy 373.001051 -268.667696) (xy 372.96293 -268.636571) (xy 372.930295 -268.599734) (xy 372.903992 -268.558138)
			(xy 372.884701 -268.512862) (xy 372.872924 -268.465078) (xy 372.868964 -268.416024) (xy 371.600222 -268.416024)
			(xy 371.599727 -268.440631) (xy 371.591832 -268.489208) (xy 371.576248 -268.535889) (xy 371.553377 -268.579466)
			(xy 371.523812 -268.61881) (xy 371.488319 -268.652902) (xy 371.447816 -268.680858) (xy 371.403354 -268.701956)
			(xy 371.356083 -268.715648) (xy 371.307228 -268.72158) (xy 371.258053 -268.719599) (xy 371.209834 -268.709755)
			(xy 371.163818 -268.692303) (xy 371.121197 -268.667696) (xy 371.083076 -268.636571) (xy 371.050441 -268.599734)
			(xy 371.024138 -268.558138) (xy 371.004847 -268.512862) (xy 370.99307 -268.465078) (xy 370.98911 -268.416024)
			(xy 369.720114 -268.416024) (xy 369.719619 -268.440631) (xy 369.711724 -268.489208) (xy 369.69614 -268.535889)
			(xy 369.673269 -268.579466) (xy 369.643704 -268.61881) (xy 369.608211 -268.652902) (xy 369.567708 -268.680858)
			(xy 369.523246 -268.701956) (xy 369.475975 -268.715648) (xy 369.42712 -268.72158) (xy 369.377945 -268.719599)
			(xy 369.329726 -268.709755) (xy 369.28371 -268.692303) (xy 369.241089 -268.667696) (xy 369.202968 -268.636571)
			(xy 369.170333 -268.599734) (xy 369.14403 -268.558138) (xy 369.124739 -268.512862) (xy 369.112962 -268.465078)
			(xy 369.109002 -268.416024) (xy 367.840006 -268.416024) (xy 367.839511 -268.440631) (xy 367.831616 -268.489208)
			(xy 367.816032 -268.535889) (xy 367.793161 -268.579466) (xy 367.763596 -268.61881) (xy 367.728103 -268.652902)
			(xy 367.6876 -268.680858) (xy 367.643138 -268.701956) (xy 367.595867 -268.715648) (xy 367.547012 -268.72158)
			(xy 367.497837 -268.719599) (xy 367.449618 -268.709755) (xy 367.403602 -268.692303) (xy 367.360981 -268.667696)
			(xy 367.32286 -268.636571) (xy 367.290225 -268.599734) (xy 367.263922 -268.558138) (xy 367.244631 -268.512862)
			(xy 367.232854 -268.465078) (xy 367.228894 -268.416024) (xy 365.960152 -268.416024) (xy 365.959657 -268.440631)
			(xy 365.951762 -268.489208) (xy 365.936178 -268.535889) (xy 365.913307 -268.579466) (xy 365.883742 -268.61881)
			(xy 365.848249 -268.652902) (xy 365.807746 -268.680858) (xy 365.763284 -268.701956) (xy 365.716013 -268.715648)
			(xy 365.667158 -268.72158) (xy 365.617983 -268.719599) (xy 365.569764 -268.709755) (xy 365.523748 -268.692303)
			(xy 365.481127 -268.667696) (xy 365.443006 -268.636571) (xy 365.410371 -268.599734) (xy 365.384068 -268.558138)
			(xy 365.364777 -268.512862) (xy 365.353 -268.465078) (xy 365.34904 -268.416024) (xy 364.080044 -268.416024)
			(xy 364.079549 -268.440631) (xy 364.071654 -268.489208) (xy 364.05607 -268.535889) (xy 364.033199 -268.579466)
			(xy 364.003634 -268.61881) (xy 363.968141 -268.652902) (xy 363.927638 -268.680858) (xy 363.883176 -268.701956)
			(xy 363.835905 -268.715648) (xy 363.78705 -268.72158) (xy 363.737875 -268.719599) (xy 363.689656 -268.709755)
			(xy 363.64364 -268.692303) (xy 363.601019 -268.667696) (xy 363.562898 -268.636571) (xy 363.530263 -268.599734)
			(xy 363.50396 -268.558138) (xy 363.484669 -268.512862) (xy 363.472892 -268.465078) (xy 363.468932 -268.416024)
			(xy 362.20019 -268.416024) (xy 362.199695 -268.440631) (xy 362.1918 -268.489208) (xy 362.176216 -268.535889)
			(xy 362.153345 -268.579466) (xy 362.12378 -268.61881) (xy 362.088287 -268.652902) (xy 362.047784 -268.680858)
			(xy 362.003322 -268.701956) (xy 361.956051 -268.715648) (xy 361.907196 -268.72158) (xy 361.858021 -268.719599)
			(xy 361.809802 -268.709755) (xy 361.763786 -268.692303) (xy 361.721165 -268.667696) (xy 361.683044 -268.636571)
			(xy 361.650409 -268.599734) (xy 361.624106 -268.558138) (xy 361.604815 -268.512862) (xy 361.593038 -268.465078)
			(xy 361.589078 -268.416024) (xy 357.506524 -268.416024) (xy 357.506029 -268.440631) (xy 357.498134 -268.489208)
			(xy 357.48255 -268.535889) (xy 357.459679 -268.579466) (xy 357.430114 -268.61881) (xy 357.394621 -268.652902)
			(xy 357.354118 -268.680858) (xy 357.309656 -268.701956) (xy 357.262385 -268.715648) (xy 357.21353 -268.72158)
			(xy 357.164355 -268.719599) (xy 357.116136 -268.709755) (xy 357.07012 -268.692303) (xy 357.027499 -268.667696)
			(xy 356.989378 -268.636571) (xy 356.956743 -268.599734) (xy 356.93044 -268.558138) (xy 356.911149 -268.512862)
			(xy 356.899372 -268.465078) (xy 356.895412 -268.416024) (xy 355.626416 -268.416024) (xy 355.625921 -268.440631)
			(xy 355.618026 -268.489208) (xy 355.602442 -268.535889) (xy 355.579571 -268.579466) (xy 355.550006 -268.61881)
			(xy 355.514513 -268.652902) (xy 355.47401 -268.680858) (xy 355.429548 -268.701956) (xy 355.382277 -268.715648)
			(xy 355.333422 -268.72158) (xy 355.284247 -268.719599) (xy 355.236028 -268.709755) (xy 355.190012 -268.692303)
			(xy 355.147391 -268.667696) (xy 355.10927 -268.636571) (xy 355.076635 -268.599734) (xy 355.050332 -268.558138)
			(xy 355.031041 -268.512862) (xy 355.019264 -268.465078) (xy 355.015304 -268.416024) (xy 353.746308 -268.416024)
			(xy 353.745813 -268.440631) (xy 353.737918 -268.489208) (xy 353.722334 -268.535889) (xy 353.699463 -268.579466)
			(xy 353.669898 -268.61881) (xy 353.634405 -268.652902) (xy 353.593902 -268.680858) (xy 353.54944 -268.701956)
			(xy 353.502169 -268.715648) (xy 353.453314 -268.72158) (xy 353.404139 -268.719599) (xy 353.35592 -268.709755)
			(xy 353.309904 -268.692303) (xy 353.267283 -268.667696) (xy 353.229162 -268.636571) (xy 353.196527 -268.599734)
			(xy 353.170224 -268.558138) (xy 353.150933 -268.512862) (xy 353.139156 -268.465078) (xy 353.135196 -268.416024)
			(xy 351.866454 -268.416024) (xy 351.865959 -268.440631) (xy 351.858064 -268.489208) (xy 351.84248 -268.535889)
			(xy 351.819609 -268.579466) (xy 351.790044 -268.61881) (xy 351.754551 -268.652902) (xy 351.714048 -268.680858)
			(xy 351.669586 -268.701956) (xy 351.622315 -268.715648) (xy 351.57346 -268.72158) (xy 351.524285 -268.719599)
			(xy 351.476066 -268.709755) (xy 351.43005 -268.692303) (xy 351.387429 -268.667696) (xy 351.349308 -268.636571)
			(xy 351.316673 -268.599734) (xy 351.29037 -268.558138) (xy 351.271079 -268.512862) (xy 351.259302 -268.465078)
			(xy 351.255342 -268.416024) (xy 349.986346 -268.416024) (xy 349.985851 -268.440631) (xy 349.977956 -268.489208)
			(xy 349.962372 -268.535889) (xy 349.939501 -268.579466) (xy 349.909936 -268.61881) (xy 349.874443 -268.652902)
			(xy 349.83394 -268.680858) (xy 349.789478 -268.701956) (xy 349.742207 -268.715648) (xy 349.693352 -268.72158)
			(xy 349.644177 -268.719599) (xy 349.595958 -268.709755) (xy 349.549942 -268.692303) (xy 349.507321 -268.667696)
			(xy 349.4692 -268.636571) (xy 349.436565 -268.599734) (xy 349.410262 -268.558138) (xy 349.390971 -268.512862)
			(xy 349.379194 -268.465078) (xy 349.375234 -268.416024) (xy 348.106492 -268.416024) (xy 348.105997 -268.440631)
			(xy 348.098102 -268.489208) (xy 348.082518 -268.535889) (xy 348.059647 -268.579466) (xy 348.030082 -268.61881)
			(xy 347.994589 -268.652902) (xy 347.954086 -268.680858) (xy 347.909624 -268.701956) (xy 347.862353 -268.715648)
			(xy 347.813498 -268.72158) (xy 347.764323 -268.719599) (xy 347.716104 -268.709755) (xy 347.670088 -268.692303)
			(xy 347.627467 -268.667696) (xy 347.589346 -268.636571) (xy 347.556711 -268.599734) (xy 347.530408 -268.558138)
			(xy 347.511117 -268.512862) (xy 347.49934 -268.465078) (xy 347.49538 -268.416024) (xy 346.226384 -268.416024)
			(xy 346.225889 -268.440631) (xy 346.217994 -268.489208) (xy 346.20241 -268.535889) (xy 346.179539 -268.579466)
			(xy 346.149974 -268.61881) (xy 346.114481 -268.652902) (xy 346.073978 -268.680858) (xy 346.029516 -268.701956)
			(xy 345.982245 -268.715648) (xy 345.93339 -268.72158) (xy 345.884215 -268.719599) (xy 345.835996 -268.709755)
			(xy 345.78998 -268.692303) (xy 345.747359 -268.667696) (xy 345.709238 -268.636571) (xy 345.676603 -268.599734)
			(xy 345.6503 -268.558138) (xy 345.631009 -268.512862) (xy 345.619232 -268.465078) (xy 345.615272 -268.416024)
			(xy 345.286759 -268.416024) (xy 345.282764 -268.465273) (xy 345.270882 -268.513251) (xy 345.251426 -268.558687)
			(xy 345.224902 -268.600394) (xy 345.192005 -268.637283) (xy 345.153595 -268.668389) (xy 345.110674 -268.692901)
			(xy 345.087702 -268.702028) (xy 345.087194 -268.702282) (xy 345.077617 -268.706309) (xy 345.062546 -268.72058)
			(xy 345.054368 -268.739655) (xy 345.05392 -268.750034) (xy 345.05392 -269.22603) (xy 347.025226 -269.22603)
			(xy 347.029186 -269.176976) (xy 347.040963 -269.129192) (xy 347.060254 -269.083916) (xy 347.086557 -269.04232)
			(xy 347.119192 -269.005483) (xy 347.157313 -268.974358) (xy 347.199934 -268.949751) (xy 347.24595 -268.932299)
			(xy 347.294169 -268.922455) (xy 347.343344 -268.920474) (xy 347.392199 -268.926406) (xy 347.43947 -268.940098)
			(xy 347.483932 -268.961196) (xy 347.524435 -268.989152) (xy 347.559928 -269.023244) (xy 347.589493 -269.062588)
			(xy 347.612364 -269.106165) (xy 347.627948 -269.152846) (xy 347.635843 -269.201423) (xy 347.636338 -269.22603)
			(xy 349.845388 -269.22603) (xy 349.849348 -269.176976) (xy 349.861125 -269.129192) (xy 349.880416 -269.083916)
			(xy 349.906719 -269.04232) (xy 349.939354 -269.005483) (xy 349.977475 -268.974358) (xy 350.020096 -268.949751)
			(xy 350.066112 -268.932299) (xy 350.114331 -268.922455) (xy 350.163506 -268.920474) (xy 350.212361 -268.926406)
			(xy 350.259632 -268.940098) (xy 350.304094 -268.961196) (xy 350.344597 -268.989152) (xy 350.38009 -269.023244)
			(xy 350.409655 -269.062588) (xy 350.432526 -269.106165) (xy 350.44811 -269.152846) (xy 350.456005 -269.201423)
			(xy 350.4565 -269.22603) (xy 352.665296 -269.22603) (xy 352.669256 -269.176976) (xy 352.681033 -269.129192)
			(xy 352.700324 -269.083916) (xy 352.726627 -269.04232) (xy 352.759262 -269.005483) (xy 352.797383 -268.974358)
			(xy 352.840004 -268.949751) (xy 352.88602 -268.932299) (xy 352.934239 -268.922455) (xy 352.983414 -268.920474)
			(xy 353.032269 -268.926406) (xy 353.07954 -268.940098) (xy 353.124002 -268.961196) (xy 353.164505 -268.989152)
			(xy 353.199998 -269.023244) (xy 353.229563 -269.062588) (xy 353.252434 -269.106165) (xy 353.268018 -269.152846)
			(xy 353.275913 -269.201423) (xy 353.276408 -269.22603) (xy 355.485204 -269.22603) (xy 355.489164 -269.176976)
			(xy 355.500941 -269.129192) (xy 355.520232 -269.083916) (xy 355.546535 -269.04232) (xy 355.57917 -269.005483)
			(xy 355.617291 -268.974358) (xy 355.659912 -268.949751) (xy 355.705928 -268.932299) (xy 355.754147 -268.922455)
			(xy 355.803322 -268.920474) (xy 355.852177 -268.926406) (xy 355.899448 -268.940098) (xy 355.94391 -268.961196)
			(xy 355.984413 -268.989152) (xy 356.019906 -269.023244) (xy 356.049471 -269.062588) (xy 356.072342 -269.106165)
			(xy 356.087926 -269.152846) (xy 356.095821 -269.201423) (xy 356.096316 -269.22603) (xy 356.425258 -269.22603)
			(xy 356.429218 -269.176976) (xy 356.440995 -269.129192) (xy 356.460286 -269.083916) (xy 356.486589 -269.04232)
			(xy 356.519224 -269.005483) (xy 356.557345 -268.974358) (xy 356.599966 -268.949751) (xy 356.645982 -268.932299)
			(xy 356.694201 -268.922455) (xy 356.743376 -268.920474) (xy 356.792231 -268.926406) (xy 356.839502 -268.940098)
			(xy 356.883964 -268.961196) (xy 356.924467 -268.989152) (xy 356.95996 -269.023244) (xy 356.989525 -269.062588)
			(xy 357.012396 -269.106165) (xy 357.02798 -269.152846) (xy 357.035875 -269.201423) (xy 357.03637 -269.22603)
			(xy 357.365312 -269.22603) (xy 357.369272 -269.176976) (xy 357.381049 -269.129192) (xy 357.40034 -269.083916)
			(xy 357.426643 -269.04232) (xy 357.459278 -269.005483) (xy 357.497399 -268.974358) (xy 357.54002 -268.949751)
			(xy 357.586036 -268.932299) (xy 357.634255 -268.922455) (xy 357.68343 -268.920474) (xy 357.732285 -268.926406)
			(xy 357.779556 -268.940098) (xy 357.824018 -268.961196) (xy 357.864521 -268.989152) (xy 357.900014 -269.023244)
			(xy 357.929579 -269.062588) (xy 357.95245 -269.106165) (xy 357.968034 -269.152846) (xy 357.975929 -269.201423)
			(xy 357.976424 -269.22603) (xy 358.305366 -269.22603) (xy 358.309326 -269.176976) (xy 358.321103 -269.129192)
			(xy 358.340394 -269.083916) (xy 358.366697 -269.04232) (xy 358.399332 -269.005483) (xy 358.437453 -268.974358)
			(xy 358.480074 -268.949751) (xy 358.52609 -268.932299) (xy 358.574309 -268.922455) (xy 358.623484 -268.920474)
			(xy 358.672339 -268.926406) (xy 358.71961 -268.940098) (xy 358.764072 -268.961196) (xy 358.804575 -268.989152)
			(xy 358.840068 -269.023244) (xy 358.869633 -269.062588) (xy 358.892504 -269.106165) (xy 358.908088 -269.152846)
			(xy 358.915983 -269.201423) (xy 358.916478 -269.22603) (xy 361.118924 -269.22603) (xy 361.122884 -269.176976)
			(xy 361.134661 -269.129192) (xy 361.153952 -269.083916) (xy 361.180255 -269.04232) (xy 361.21289 -269.005483)
			(xy 361.251011 -268.974358) (xy 361.293632 -268.949751) (xy 361.339648 -268.932299) (xy 361.387867 -268.922455)
			(xy 361.437042 -268.920474) (xy 361.485897 -268.926406) (xy 361.533168 -268.940098) (xy 361.57763 -268.961196)
			(xy 361.618133 -268.989152) (xy 361.653626 -269.023244) (xy 361.683191 -269.062588) (xy 361.706062 -269.106165)
			(xy 361.721646 -269.152846) (xy 361.729541 -269.201423) (xy 361.730036 -269.22603) (xy 362.058978 -269.22603)
			(xy 362.062938 -269.176976) (xy 362.074715 -269.129192) (xy 362.094006 -269.083916) (xy 362.120309 -269.04232)
			(xy 362.152944 -269.005483) (xy 362.191065 -268.974358) (xy 362.233686 -268.949751) (xy 362.279702 -268.932299)
			(xy 362.327921 -268.922455) (xy 362.377096 -268.920474) (xy 362.425951 -268.926406) (xy 362.473222 -268.940098)
			(xy 362.517684 -268.961196) (xy 362.558187 -268.989152) (xy 362.59368 -269.023244) (xy 362.623245 -269.062588)
			(xy 362.646116 -269.106165) (xy 362.6617 -269.152846) (xy 362.669595 -269.201423) (xy 362.67009 -269.22603)
			(xy 362.999032 -269.22603) (xy 363.002992 -269.176976) (xy 363.014769 -269.129192) (xy 363.03406 -269.083916)
			(xy 363.060363 -269.04232) (xy 363.092998 -269.005483) (xy 363.131119 -268.974358) (xy 363.17374 -268.949751)
			(xy 363.219756 -268.932299) (xy 363.267975 -268.922455) (xy 363.31715 -268.920474) (xy 363.366005 -268.926406)
			(xy 363.413276 -268.940098) (xy 363.457738 -268.961196) (xy 363.498241 -268.989152) (xy 363.533734 -269.023244)
			(xy 363.563299 -269.062588) (xy 363.58617 -269.106165) (xy 363.601754 -269.152846) (xy 363.609649 -269.201423)
			(xy 363.610144 -269.22603) (xy 363.939086 -269.22603) (xy 363.943046 -269.176976) (xy 363.954823 -269.129192)
			(xy 363.974114 -269.083916) (xy 364.000417 -269.04232) (xy 364.033052 -269.005483) (xy 364.071173 -268.974358)
			(xy 364.113794 -268.949751) (xy 364.15981 -268.932299) (xy 364.208029 -268.922455) (xy 364.257204 -268.920474)
			(xy 364.306059 -268.926406) (xy 364.35333 -268.940098) (xy 364.397792 -268.961196) (xy 364.438295 -268.989152)
			(xy 364.473788 -269.023244) (xy 364.503353 -269.062588) (xy 364.526224 -269.106165) (xy 364.541808 -269.152846)
			(xy 364.549703 -269.201423) (xy 364.550198 -269.22603) (xy 366.758994 -269.22603) (xy 366.762954 -269.176976)
			(xy 366.774731 -269.129192) (xy 366.794022 -269.083916) (xy 366.820325 -269.04232) (xy 366.85296 -269.005483)
			(xy 366.891081 -268.974358) (xy 366.933702 -268.949751) (xy 366.979718 -268.932299) (xy 367.027937 -268.922455)
			(xy 367.077112 -268.920474) (xy 367.125967 -268.926406) (xy 367.173238 -268.940098) (xy 367.2177 -268.961196)
			(xy 367.258203 -268.989152) (xy 367.293696 -269.023244) (xy 367.323261 -269.062588) (xy 367.346132 -269.106165)
			(xy 367.361716 -269.152846) (xy 367.369611 -269.201423) (xy 367.370106 -269.22603) (xy 369.578902 -269.22603)
			(xy 369.582862 -269.176976) (xy 369.594639 -269.129192) (xy 369.61393 -269.083916) (xy 369.640233 -269.04232)
			(xy 369.672868 -269.005483) (xy 369.710989 -268.974358) (xy 369.75361 -268.949751) (xy 369.799626 -268.932299)
			(xy 369.847845 -268.922455) (xy 369.89702 -268.920474) (xy 369.945875 -268.926406) (xy 369.993146 -268.940098)
			(xy 370.037608 -268.961196) (xy 370.078111 -268.989152) (xy 370.113604 -269.023244) (xy 370.143169 -269.062588)
			(xy 370.16604 -269.106165) (xy 370.181624 -269.152846) (xy 370.189519 -269.201423) (xy 370.190014 -269.22603)
			(xy 372.399064 -269.22603) (xy 372.403024 -269.176976) (xy 372.414801 -269.129192) (xy 372.434092 -269.083916)
			(xy 372.460395 -269.04232) (xy 372.49303 -269.005483) (xy 372.531151 -268.974358) (xy 372.573772 -268.949751)
			(xy 372.619788 -268.932299) (xy 372.668007 -268.922455) (xy 372.717182 -268.920474) (xy 372.766037 -268.926406)
			(xy 372.813308 -268.940098) (xy 372.85777 -268.961196) (xy 372.898273 -268.989152) (xy 372.933766 -269.023244)
			(xy 372.963331 -269.062588) (xy 372.986202 -269.106165) (xy 373.001786 -269.152846) (xy 373.009681 -269.201423)
			(xy 373.010176 -269.22603) (xy 373.009681 -269.250637) (xy 373.001786 -269.299214) (xy 372.986202 -269.345895)
			(xy 372.963331 -269.389472) (xy 372.933766 -269.428816) (xy 372.898273 -269.462908) (xy 372.85777 -269.490864)
			(xy 372.813308 -269.511962) (xy 372.766037 -269.525654) (xy 372.717182 -269.531586) (xy 372.668007 -269.529605)
			(xy 372.619788 -269.519761) (xy 372.573772 -269.502309) (xy 372.531151 -269.477702) (xy 372.49303 -269.446577)
			(xy 372.460395 -269.40974) (xy 372.434092 -269.368144) (xy 372.414801 -269.322868) (xy 372.403024 -269.275084)
			(xy 372.399064 -269.22603) (xy 370.190014 -269.22603) (xy 370.189519 -269.250637) (xy 370.181624 -269.299214)
			(xy 370.16604 -269.345895) (xy 370.143169 -269.389472) (xy 370.113604 -269.428816) (xy 370.078111 -269.462908)
			(xy 370.037608 -269.490864) (xy 369.993146 -269.511962) (xy 369.945875 -269.525654) (xy 369.89702 -269.531586)
			(xy 369.847845 -269.529605) (xy 369.799626 -269.519761) (xy 369.75361 -269.502309) (xy 369.710989 -269.477702)
			(xy 369.672868 -269.446577) (xy 369.640233 -269.40974) (xy 369.61393 -269.368144) (xy 369.594639 -269.322868)
			(xy 369.582862 -269.275084) (xy 369.578902 -269.22603) (xy 367.370106 -269.22603) (xy 367.369611 -269.250637)
			(xy 367.361716 -269.299214) (xy 367.346132 -269.345895) (xy 367.323261 -269.389472) (xy 367.293696 -269.428816)
			(xy 367.258203 -269.462908) (xy 367.2177 -269.490864) (xy 367.173238 -269.511962) (xy 367.125967 -269.525654)
			(xy 367.077112 -269.531586) (xy 367.027937 -269.529605) (xy 366.979718 -269.519761) (xy 366.933702 -269.502309)
			(xy 366.891081 -269.477702) (xy 366.85296 -269.446577) (xy 366.820325 -269.40974) (xy 366.794022 -269.368144)
			(xy 366.774731 -269.322868) (xy 366.762954 -269.275084) (xy 366.758994 -269.22603) (xy 364.550198 -269.22603)
			(xy 364.549703 -269.250637) (xy 364.541808 -269.299214) (xy 364.526224 -269.345895) (xy 364.503353 -269.389472)
			(xy 364.473788 -269.428816) (xy 364.438295 -269.462908) (xy 364.397792 -269.490864) (xy 364.35333 -269.511962)
			(xy 364.306059 -269.525654) (xy 364.257204 -269.531586) (xy 364.208029 -269.529605) (xy 364.15981 -269.519761)
			(xy 364.113794 -269.502309) (xy 364.071173 -269.477702) (xy 364.033052 -269.446577) (xy 364.000417 -269.40974)
			(xy 363.974114 -269.368144) (xy 363.954823 -269.322868) (xy 363.943046 -269.275084) (xy 363.939086 -269.22603)
			(xy 363.610144 -269.22603) (xy 363.609649 -269.250637) (xy 363.601754 -269.299214) (xy 363.58617 -269.345895)
			(xy 363.563299 -269.389472) (xy 363.533734 -269.428816) (xy 363.498241 -269.462908) (xy 363.457738 -269.490864)
			(xy 363.413276 -269.511962) (xy 363.366005 -269.525654) (xy 363.31715 -269.531586) (xy 363.267975 -269.529605)
			(xy 363.219756 -269.519761) (xy 363.17374 -269.502309) (xy 363.131119 -269.477702) (xy 363.092998 -269.446577)
			(xy 363.060363 -269.40974) (xy 363.03406 -269.368144) (xy 363.014769 -269.322868) (xy 363.002992 -269.275084)
			(xy 362.999032 -269.22603) (xy 362.67009 -269.22603) (xy 362.669595 -269.250637) (xy 362.6617 -269.299214)
			(xy 362.646116 -269.345895) (xy 362.623245 -269.389472) (xy 362.59368 -269.428816) (xy 362.558187 -269.462908)
			(xy 362.517684 -269.490864) (xy 362.473222 -269.511962) (xy 362.425951 -269.525654) (xy 362.377096 -269.531586)
			(xy 362.327921 -269.529605) (xy 362.279702 -269.519761) (xy 362.233686 -269.502309) (xy 362.191065 -269.477702)
			(xy 362.152944 -269.446577) (xy 362.120309 -269.40974) (xy 362.094006 -269.368144) (xy 362.074715 -269.322868)
			(xy 362.062938 -269.275084) (xy 362.058978 -269.22603) (xy 361.730036 -269.22603) (xy 361.729541 -269.250637)
			(xy 361.721646 -269.299214) (xy 361.706062 -269.345895) (xy 361.683191 -269.389472) (xy 361.653626 -269.428816)
			(xy 361.618133 -269.462908) (xy 361.57763 -269.490864) (xy 361.533168 -269.511962) (xy 361.485897 -269.525654)
			(xy 361.437042 -269.531586) (xy 361.387867 -269.529605) (xy 361.339648 -269.519761) (xy 361.293632 -269.502309)
			(xy 361.251011 -269.477702) (xy 361.21289 -269.446577) (xy 361.180255 -269.40974) (xy 361.153952 -269.368144)
			(xy 361.134661 -269.322868) (xy 361.122884 -269.275084) (xy 361.118924 -269.22603) (xy 358.916478 -269.22603)
			(xy 358.915983 -269.250637) (xy 358.908088 -269.299214) (xy 358.892504 -269.345895) (xy 358.869633 -269.389472)
			(xy 358.840068 -269.428816) (xy 358.804575 -269.462908) (xy 358.764072 -269.490864) (xy 358.71961 -269.511962)
			(xy 358.672339 -269.525654) (xy 358.623484 -269.531586) (xy 358.574309 -269.529605) (xy 358.52609 -269.519761)
			(xy 358.480074 -269.502309) (xy 358.437453 -269.477702) (xy 358.399332 -269.446577) (xy 358.366697 -269.40974)
			(xy 358.340394 -269.368144) (xy 358.321103 -269.322868) (xy 358.309326 -269.275084) (xy 358.305366 -269.22603)
			(xy 357.976424 -269.22603) (xy 357.975929 -269.250637) (xy 357.968034 -269.299214) (xy 357.95245 -269.345895)
			(xy 357.929579 -269.389472) (xy 357.900014 -269.428816) (xy 357.864521 -269.462908) (xy 357.824018 -269.490864)
			(xy 357.779556 -269.511962) (xy 357.732285 -269.525654) (xy 357.68343 -269.531586) (xy 357.634255 -269.529605)
			(xy 357.586036 -269.519761) (xy 357.54002 -269.502309) (xy 357.497399 -269.477702) (xy 357.459278 -269.446577)
			(xy 357.426643 -269.40974) (xy 357.40034 -269.368144) (xy 357.381049 -269.322868) (xy 357.369272 -269.275084)
			(xy 357.365312 -269.22603) (xy 357.03637 -269.22603) (xy 357.035875 -269.250637) (xy 357.02798 -269.299214)
			(xy 357.012396 -269.345895) (xy 356.989525 -269.389472) (xy 356.95996 -269.428816) (xy 356.924467 -269.462908)
			(xy 356.883964 -269.490864) (xy 356.839502 -269.511962) (xy 356.792231 -269.525654) (xy 356.743376 -269.531586)
			(xy 356.694201 -269.529605) (xy 356.645982 -269.519761) (xy 356.599966 -269.502309) (xy 356.557345 -269.477702)
			(xy 356.519224 -269.446577) (xy 356.486589 -269.40974) (xy 356.460286 -269.368144) (xy 356.440995 -269.322868)
			(xy 356.429218 -269.275084) (xy 356.425258 -269.22603) (xy 356.096316 -269.22603) (xy 356.095821 -269.250637)
			(xy 356.087926 -269.299214) (xy 356.072342 -269.345895) (xy 356.049471 -269.389472) (xy 356.019906 -269.428816)
			(xy 355.984413 -269.462908) (xy 355.94391 -269.490864) (xy 355.899448 -269.511962) (xy 355.852177 -269.525654)
			(xy 355.803322 -269.531586) (xy 355.754147 -269.529605) (xy 355.705928 -269.519761) (xy 355.659912 -269.502309)
			(xy 355.617291 -269.477702) (xy 355.57917 -269.446577) (xy 355.546535 -269.40974) (xy 355.520232 -269.368144)
			(xy 355.500941 -269.322868) (xy 355.489164 -269.275084) (xy 355.485204 -269.22603) (xy 353.276408 -269.22603)
			(xy 353.275913 -269.250637) (xy 353.268018 -269.299214) (xy 353.252434 -269.345895) (xy 353.229563 -269.389472)
			(xy 353.199998 -269.428816) (xy 353.164505 -269.462908) (xy 353.124002 -269.490864) (xy 353.07954 -269.511962)
			(xy 353.032269 -269.525654) (xy 352.983414 -269.531586) (xy 352.934239 -269.529605) (xy 352.88602 -269.519761)
			(xy 352.840004 -269.502309) (xy 352.797383 -269.477702) (xy 352.759262 -269.446577) (xy 352.726627 -269.40974)
			(xy 352.700324 -269.368144) (xy 352.681033 -269.322868) (xy 352.669256 -269.275084) (xy 352.665296 -269.22603)
			(xy 350.4565 -269.22603) (xy 350.456005 -269.250637) (xy 350.44811 -269.299214) (xy 350.432526 -269.345895)
			(xy 350.409655 -269.389472) (xy 350.38009 -269.428816) (xy 350.344597 -269.462908) (xy 350.304094 -269.490864)
			(xy 350.259632 -269.511962) (xy 350.212361 -269.525654) (xy 350.163506 -269.531586) (xy 350.114331 -269.529605)
			(xy 350.066112 -269.519761) (xy 350.020096 -269.502309) (xy 349.977475 -269.477702) (xy 349.939354 -269.446577)
			(xy 349.906719 -269.40974) (xy 349.880416 -269.368144) (xy 349.861125 -269.322868) (xy 349.849348 -269.275084)
			(xy 349.845388 -269.22603) (xy 347.636338 -269.22603) (xy 347.635843 -269.250637) (xy 347.627948 -269.299214)
			(xy 347.612364 -269.345895) (xy 347.589493 -269.389472) (xy 347.559928 -269.428816) (xy 347.524435 -269.462908)
			(xy 347.483932 -269.490864) (xy 347.43947 -269.511962) (xy 347.392199 -269.525654) (xy 347.343344 -269.531586)
			(xy 347.294169 -269.529605) (xy 347.24595 -269.519761) (xy 347.199934 -269.502309) (xy 347.157313 -269.477702)
			(xy 347.119192 -269.446577) (xy 347.086557 -269.40974) (xy 347.060254 -269.368144) (xy 347.040963 -269.322868)
			(xy 347.029186 -269.275084) (xy 347.025226 -269.22603) (xy 345.05392 -269.22603) (xy 345.05392 -269.702026)
			(xy 345.05441 -269.712397) (xy 345.062595 -269.731455) (xy 345.077629 -269.745745) (xy 345.087194 -269.749778)
			(xy 345.087702 -269.750032) (xy 345.110688 -269.759118) (xy 345.153606 -269.783632) (xy 345.192013 -269.81474)
			(xy 345.224906 -269.85163) (xy 345.251425 -269.893337) (xy 345.270878 -269.938773) (xy 345.282756 -269.986749)
			(xy 345.286749 -270.036013) (xy 345.286747 -270.036036) (xy 345.615272 -270.036036) (xy 345.619232 -269.986982)
			(xy 345.631009 -269.939198) (xy 345.6503 -269.893922) (xy 345.676603 -269.852326) (xy 345.709238 -269.815489)
			(xy 345.747359 -269.784364) (xy 345.78998 -269.759757) (xy 345.835996 -269.742305) (xy 345.884215 -269.732461)
			(xy 345.93339 -269.73048) (xy 345.982245 -269.736412) (xy 346.029516 -269.750104) (xy 346.073978 -269.771202)
			(xy 346.114481 -269.799158) (xy 346.149974 -269.83325) (xy 346.179539 -269.872594) (xy 346.20241 -269.916171)
			(xy 346.217994 -269.962852) (xy 346.225889 -270.011429) (xy 346.226384 -270.036036) (xy 346.555326 -270.036036)
			(xy 346.559286 -269.986982) (xy 346.571063 -269.939198) (xy 346.590354 -269.893922) (xy 346.616657 -269.852326)
			(xy 346.649292 -269.815489) (xy 346.687413 -269.784364) (xy 346.730034 -269.759757) (xy 346.77605 -269.742305)
			(xy 346.824269 -269.732461) (xy 346.873444 -269.73048) (xy 346.922299 -269.736412) (xy 346.96957 -269.750104)
			(xy 347.014032 -269.771202) (xy 347.054535 -269.799158) (xy 347.090028 -269.83325) (xy 347.119593 -269.872594)
			(xy 347.142464 -269.916171) (xy 347.158048 -269.962852) (xy 347.165943 -270.011429) (xy 347.166438 -270.036036)
			(xy 347.49538 -270.036036) (xy 347.49934 -269.986982) (xy 347.511117 -269.939198) (xy 347.530408 -269.893922)
			(xy 347.556711 -269.852326) (xy 347.589346 -269.815489) (xy 347.627467 -269.784364) (xy 347.670088 -269.759757)
			(xy 347.716104 -269.742305) (xy 347.764323 -269.732461) (xy 347.813498 -269.73048) (xy 347.862353 -269.736412)
			(xy 347.909624 -269.750104) (xy 347.954086 -269.771202) (xy 347.994589 -269.799158) (xy 348.030082 -269.83325)
			(xy 348.059647 -269.872594) (xy 348.082518 -269.916171) (xy 348.098102 -269.962852) (xy 348.105997 -270.011429)
			(xy 348.106492 -270.036036) (xy 348.435434 -270.036036) (xy 348.439394 -269.986982) (xy 348.451171 -269.939198)
			(xy 348.470462 -269.893922) (xy 348.496765 -269.852326) (xy 348.5294 -269.815489) (xy 348.567521 -269.784364)
			(xy 348.610142 -269.759757) (xy 348.656158 -269.742305) (xy 348.704377 -269.732461) (xy 348.753552 -269.73048)
			(xy 348.802407 -269.736412) (xy 348.849678 -269.750104) (xy 348.89414 -269.771202) (xy 348.934643 -269.799158)
			(xy 348.970136 -269.83325) (xy 348.999701 -269.872594) (xy 349.022572 -269.916171) (xy 349.038156 -269.962852)
			(xy 349.046051 -270.011429) (xy 349.046546 -270.036036) (xy 349.375234 -270.036036) (xy 349.379194 -269.986982)
			(xy 349.390971 -269.939198) (xy 349.410262 -269.893922) (xy 349.436565 -269.852326) (xy 349.4692 -269.815489)
			(xy 349.507321 -269.784364) (xy 349.549942 -269.759757) (xy 349.595958 -269.742305) (xy 349.644177 -269.732461)
			(xy 349.693352 -269.73048) (xy 349.742207 -269.736412) (xy 349.789478 -269.750104) (xy 349.83394 -269.771202)
			(xy 349.874443 -269.799158) (xy 349.909936 -269.83325) (xy 349.939501 -269.872594) (xy 349.962372 -269.916171)
			(xy 349.977956 -269.962852) (xy 349.985851 -270.011429) (xy 349.986346 -270.036036) (xy 350.315288 -270.036036)
			(xy 350.319248 -269.986982) (xy 350.331025 -269.939198) (xy 350.350316 -269.893922) (xy 350.376619 -269.852326)
			(xy 350.409254 -269.815489) (xy 350.447375 -269.784364) (xy 350.489996 -269.759757) (xy 350.536012 -269.742305)
			(xy 350.584231 -269.732461) (xy 350.633406 -269.73048) (xy 350.682261 -269.736412) (xy 350.729532 -269.750104)
			(xy 350.773994 -269.771202) (xy 350.814497 -269.799158) (xy 350.84999 -269.83325) (xy 350.879555 -269.872594)
			(xy 350.902426 -269.916171) (xy 350.91801 -269.962852) (xy 350.925905 -270.011429) (xy 350.9264 -270.036036)
			(xy 351.255342 -270.036036) (xy 351.259302 -269.986982) (xy 351.271079 -269.939198) (xy 351.29037 -269.893922)
			(xy 351.316673 -269.852326) (xy 351.349308 -269.815489) (xy 351.387429 -269.784364) (xy 351.43005 -269.759757)
			(xy 351.476066 -269.742305) (xy 351.524285 -269.732461) (xy 351.57346 -269.73048) (xy 351.622315 -269.736412)
			(xy 351.669586 -269.750104) (xy 351.714048 -269.771202) (xy 351.754551 -269.799158) (xy 351.790044 -269.83325)
			(xy 351.819609 -269.872594) (xy 351.84248 -269.916171) (xy 351.858064 -269.962852) (xy 351.865959 -270.011429)
			(xy 351.866454 -270.036036) (xy 352.195396 -270.036036) (xy 352.199356 -269.986982) (xy 352.211133 -269.939198)
			(xy 352.230424 -269.893922) (xy 352.256727 -269.852326) (xy 352.289362 -269.815489) (xy 352.327483 -269.784364)
			(xy 352.370104 -269.759757) (xy 352.41612 -269.742305) (xy 352.464339 -269.732461) (xy 352.513514 -269.73048)
			(xy 352.562369 -269.736412) (xy 352.60964 -269.750104) (xy 352.654102 -269.771202) (xy 352.694605 -269.799158)
			(xy 352.730098 -269.83325) (xy 352.759663 -269.872594) (xy 352.782534 -269.916171) (xy 352.798118 -269.962852)
			(xy 352.806013 -270.011429) (xy 352.806508 -270.036036) (xy 353.135196 -270.036036) (xy 353.139156 -269.986982)
			(xy 353.150933 -269.939198) (xy 353.170224 -269.893922) (xy 353.196527 -269.852326) (xy 353.229162 -269.815489)
			(xy 353.267283 -269.784364) (xy 353.309904 -269.759757) (xy 353.35592 -269.742305) (xy 353.404139 -269.732461)
			(xy 353.453314 -269.73048) (xy 353.502169 -269.736412) (xy 353.54944 -269.750104) (xy 353.593902 -269.771202)
			(xy 353.634405 -269.799158) (xy 353.669898 -269.83325) (xy 353.699463 -269.872594) (xy 353.722334 -269.916171)
			(xy 353.737918 -269.962852) (xy 353.745813 -270.011429) (xy 353.746308 -270.036036) (xy 354.07525 -270.036036)
			(xy 354.07921 -269.986982) (xy 354.090987 -269.939198) (xy 354.110278 -269.893922) (xy 354.136581 -269.852326)
			(xy 354.169216 -269.815489) (xy 354.207337 -269.784364) (xy 354.249958 -269.759757) (xy 354.295974 -269.742305)
			(xy 354.344193 -269.732461) (xy 354.393368 -269.73048) (xy 354.442223 -269.736412) (xy 354.489494 -269.750104)
			(xy 354.533956 -269.771202) (xy 354.574459 -269.799158) (xy 354.609952 -269.83325) (xy 354.639517 -269.872594)
			(xy 354.662388 -269.916171) (xy 354.677972 -269.962852) (xy 354.685867 -270.011429) (xy 354.686362 -270.036036)
			(xy 355.015304 -270.036036) (xy 355.019264 -269.986982) (xy 355.031041 -269.939198) (xy 355.050332 -269.893922)
			(xy 355.076635 -269.852326) (xy 355.10927 -269.815489) (xy 355.147391 -269.784364) (xy 355.190012 -269.759757)
			(xy 355.236028 -269.742305) (xy 355.284247 -269.732461) (xy 355.333422 -269.73048) (xy 355.382277 -269.736412)
			(xy 355.429548 -269.750104) (xy 355.47401 -269.771202) (xy 355.514513 -269.799158) (xy 355.550006 -269.83325)
			(xy 355.579571 -269.872594) (xy 355.602442 -269.916171) (xy 355.618026 -269.962852) (xy 355.625921 -270.011429)
			(xy 355.626416 -270.036036) (xy 355.955358 -270.036036) (xy 355.959318 -269.986982) (xy 355.971095 -269.939198)
			(xy 355.990386 -269.893922) (xy 356.016689 -269.852326) (xy 356.049324 -269.815489) (xy 356.087445 -269.784364)
			(xy 356.130066 -269.759757) (xy 356.176082 -269.742305) (xy 356.224301 -269.732461) (xy 356.273476 -269.73048)
			(xy 356.322331 -269.736412) (xy 356.369602 -269.750104) (xy 356.414064 -269.771202) (xy 356.454567 -269.799158)
			(xy 356.49006 -269.83325) (xy 356.519625 -269.872594) (xy 356.542496 -269.916171) (xy 356.55808 -269.962852)
			(xy 356.565975 -270.011429) (xy 356.56647 -270.036036) (xy 356.895412 -270.036036) (xy 356.899372 -269.986982)
			(xy 356.911149 -269.939198) (xy 356.93044 -269.893922) (xy 356.956743 -269.852326) (xy 356.989378 -269.815489)
			(xy 357.027499 -269.784364) (xy 357.07012 -269.759757) (xy 357.116136 -269.742305) (xy 357.164355 -269.732461)
			(xy 357.21353 -269.73048) (xy 357.262385 -269.736412) (xy 357.309656 -269.750104) (xy 357.354118 -269.771202)
			(xy 357.394621 -269.799158) (xy 357.430114 -269.83325) (xy 357.459679 -269.872594) (xy 357.48255 -269.916171)
			(xy 357.498134 -269.962852) (xy 357.506029 -270.011429) (xy 357.506524 -270.036036) (xy 357.835212 -270.036036)
			(xy 357.839172 -269.986982) (xy 357.850949 -269.939198) (xy 357.87024 -269.893922) (xy 357.896543 -269.852326)
			(xy 357.929178 -269.815489) (xy 357.967299 -269.784364) (xy 358.00992 -269.759757) (xy 358.055936 -269.742305)
			(xy 358.104155 -269.732461) (xy 358.15333 -269.73048) (xy 358.202185 -269.736412) (xy 358.249456 -269.750104)
			(xy 358.293918 -269.771202) (xy 358.334421 -269.799158) (xy 358.369914 -269.83325) (xy 358.399479 -269.872594)
			(xy 358.42235 -269.916171) (xy 358.437934 -269.962852) (xy 358.445829 -270.011429) (xy 358.446324 -270.036036)
			(xy 361.589078 -270.036036) (xy 361.593038 -269.986982) (xy 361.604815 -269.939198) (xy 361.624106 -269.893922)
			(xy 361.650409 -269.852326) (xy 361.683044 -269.815489) (xy 361.721165 -269.784364) (xy 361.763786 -269.759757)
			(xy 361.809802 -269.742305) (xy 361.858021 -269.732461) (xy 361.907196 -269.73048) (xy 361.956051 -269.736412)
			(xy 362.003322 -269.750104) (xy 362.047784 -269.771202) (xy 362.088287 -269.799158) (xy 362.12378 -269.83325)
			(xy 362.153345 -269.872594) (xy 362.176216 -269.916171) (xy 362.1918 -269.962852) (xy 362.199695 -270.011429)
			(xy 362.20019 -270.036036) (xy 362.528878 -270.036036) (xy 362.532838 -269.986982) (xy 362.544615 -269.939198)
			(xy 362.563906 -269.893922) (xy 362.590209 -269.852326) (xy 362.622844 -269.815489) (xy 362.660965 -269.784364)
			(xy 362.703586 -269.759757) (xy 362.749602 -269.742305) (xy 362.797821 -269.732461) (xy 362.846996 -269.73048)
			(xy 362.895851 -269.736412) (xy 362.943122 -269.750104) (xy 362.987584 -269.771202) (xy 363.028087 -269.799158)
			(xy 363.06358 -269.83325) (xy 363.093145 -269.872594) (xy 363.116016 -269.916171) (xy 363.1316 -269.962852)
			(xy 363.139495 -270.011429) (xy 363.13999 -270.036036) (xy 363.468932 -270.036036) (xy 363.472892 -269.986982)
			(xy 363.484669 -269.939198) (xy 363.50396 -269.893922) (xy 363.530263 -269.852326) (xy 363.562898 -269.815489)
			(xy 363.601019 -269.784364) (xy 363.64364 -269.759757) (xy 363.689656 -269.742305) (xy 363.737875 -269.732461)
			(xy 363.78705 -269.73048) (xy 363.835905 -269.736412) (xy 363.883176 -269.750104) (xy 363.927638 -269.771202)
			(xy 363.968141 -269.799158) (xy 364.003634 -269.83325) (xy 364.033199 -269.872594) (xy 364.05607 -269.916171)
			(xy 364.071654 -269.962852) (xy 364.079549 -270.011429) (xy 364.080044 -270.036036) (xy 364.408986 -270.036036)
			(xy 364.412946 -269.986982) (xy 364.424723 -269.939198) (xy 364.444014 -269.893922) (xy 364.470317 -269.852326)
			(xy 364.502952 -269.815489) (xy 364.541073 -269.784364) (xy 364.583694 -269.759757) (xy 364.62971 -269.742305)
			(xy 364.677929 -269.732461) (xy 364.727104 -269.73048) (xy 364.775959 -269.736412) (xy 364.82323 -269.750104)
			(xy 364.867692 -269.771202) (xy 364.908195 -269.799158) (xy 364.943688 -269.83325) (xy 364.973253 -269.872594)
			(xy 364.996124 -269.916171) (xy 365.011708 -269.962852) (xy 365.019603 -270.011429) (xy 365.020098 -270.036036)
			(xy 365.34904 -270.036036) (xy 365.353 -269.986982) (xy 365.364777 -269.939198) (xy 365.384068 -269.893922)
			(xy 365.410371 -269.852326) (xy 365.443006 -269.815489) (xy 365.481127 -269.784364) (xy 365.523748 -269.759757)
			(xy 365.569764 -269.742305) (xy 365.617983 -269.732461) (xy 365.667158 -269.73048) (xy 365.716013 -269.736412)
			(xy 365.763284 -269.750104) (xy 365.807746 -269.771202) (xy 365.848249 -269.799158) (xy 365.883742 -269.83325)
			(xy 365.913307 -269.872594) (xy 365.936178 -269.916171) (xy 365.951762 -269.962852) (xy 365.959657 -270.011429)
			(xy 365.960152 -270.036036) (xy 366.289094 -270.036036) (xy 366.293054 -269.986982) (xy 366.304831 -269.939198)
			(xy 366.324122 -269.893922) (xy 366.350425 -269.852326) (xy 366.38306 -269.815489) (xy 366.421181 -269.784364)
			(xy 366.463802 -269.759757) (xy 366.509818 -269.742305) (xy 366.558037 -269.732461) (xy 366.607212 -269.73048)
			(xy 366.656067 -269.736412) (xy 366.703338 -269.750104) (xy 366.7478 -269.771202) (xy 366.788303 -269.799158)
			(xy 366.823796 -269.83325) (xy 366.853361 -269.872594) (xy 366.876232 -269.916171) (xy 366.891816 -269.962852)
			(xy 366.899711 -270.011429) (xy 366.900206 -270.036036) (xy 367.228894 -270.036036) (xy 367.232854 -269.986982)
			(xy 367.244631 -269.939198) (xy 367.263922 -269.893922) (xy 367.290225 -269.852326) (xy 367.32286 -269.815489)
			(xy 367.360981 -269.784364) (xy 367.403602 -269.759757) (xy 367.449618 -269.742305) (xy 367.497837 -269.732461)
			(xy 367.547012 -269.73048) (xy 367.595867 -269.736412) (xy 367.643138 -269.750104) (xy 367.6876 -269.771202)
			(xy 367.728103 -269.799158) (xy 367.763596 -269.83325) (xy 367.793161 -269.872594) (xy 367.816032 -269.916171)
			(xy 367.831616 -269.962852) (xy 367.839511 -270.011429) (xy 367.840006 -270.036036) (xy 368.168948 -270.036036)
			(xy 368.172908 -269.986982) (xy 368.184685 -269.939198) (xy 368.203976 -269.893922) (xy 368.230279 -269.852326)
			(xy 368.262914 -269.815489) (xy 368.301035 -269.784364) (xy 368.343656 -269.759757) (xy 368.389672 -269.742305)
			(xy 368.437891 -269.732461) (xy 368.487066 -269.73048) (xy 368.535921 -269.736412) (xy 368.583192 -269.750104)
			(xy 368.627654 -269.771202) (xy 368.668157 -269.799158) (xy 368.70365 -269.83325) (xy 368.733215 -269.872594)
			(xy 368.756086 -269.916171) (xy 368.77167 -269.962852) (xy 368.779565 -270.011429) (xy 368.78006 -270.036036)
			(xy 369.109002 -270.036036) (xy 369.112962 -269.986982) (xy 369.124739 -269.939198) (xy 369.14403 -269.893922)
			(xy 369.170333 -269.852326) (xy 369.202968 -269.815489) (xy 369.241089 -269.784364) (xy 369.28371 -269.759757)
			(xy 369.329726 -269.742305) (xy 369.377945 -269.732461) (xy 369.42712 -269.73048) (xy 369.475975 -269.736412)
			(xy 369.523246 -269.750104) (xy 369.567708 -269.771202) (xy 369.608211 -269.799158) (xy 369.643704 -269.83325)
			(xy 369.673269 -269.872594) (xy 369.69614 -269.916171) (xy 369.711724 -269.962852) (xy 369.719619 -270.011429)
			(xy 369.720114 -270.036036) (xy 370.049056 -270.036036) (xy 370.053016 -269.986982) (xy 370.064793 -269.939198)
			(xy 370.084084 -269.893922) (xy 370.110387 -269.852326) (xy 370.143022 -269.815489) (xy 370.181143 -269.784364)
			(xy 370.223764 -269.759757) (xy 370.26978 -269.742305) (xy 370.317999 -269.732461) (xy 370.367174 -269.73048)
			(xy 370.416029 -269.736412) (xy 370.4633 -269.750104) (xy 370.507762 -269.771202) (xy 370.548265 -269.799158)
			(xy 370.583758 -269.83325) (xy 370.613323 -269.872594) (xy 370.636194 -269.916171) (xy 370.651778 -269.962852)
			(xy 370.659673 -270.011429) (xy 370.660168 -270.036036) (xy 370.98911 -270.036036) (xy 370.99307 -269.986982)
			(xy 371.004847 -269.939198) (xy 371.024138 -269.893922) (xy 371.050441 -269.852326) (xy 371.083076 -269.815489)
			(xy 371.121197 -269.784364) (xy 371.163818 -269.759757) (xy 371.209834 -269.742305) (xy 371.258053 -269.732461)
			(xy 371.307228 -269.73048) (xy 371.356083 -269.736412) (xy 371.403354 -269.750104) (xy 371.447816 -269.771202)
			(xy 371.488319 -269.799158) (xy 371.523812 -269.83325) (xy 371.553377 -269.872594) (xy 371.576248 -269.916171)
			(xy 371.591832 -269.962852) (xy 371.599727 -270.011429) (xy 371.600222 -270.036036) (xy 371.92891 -270.036036)
			(xy 371.93287 -269.986982) (xy 371.944647 -269.939198) (xy 371.963938 -269.893922) (xy 371.990241 -269.852326)
			(xy 372.022876 -269.815489) (xy 372.060997 -269.784364) (xy 372.103618 -269.759757) (xy 372.149634 -269.742305)
			(xy 372.197853 -269.732461) (xy 372.247028 -269.73048) (xy 372.295883 -269.736412) (xy 372.343154 -269.750104)
			(xy 372.387616 -269.771202) (xy 372.428119 -269.799158) (xy 372.463612 -269.83325) (xy 372.493177 -269.872594)
			(xy 372.516048 -269.916171) (xy 372.531632 -269.962852) (xy 372.539527 -270.011429) (xy 372.540022 -270.036036)
			(xy 372.868964 -270.036036) (xy 372.872924 -269.986982) (xy 372.884701 -269.939198) (xy 372.903992 -269.893922)
			(xy 372.930295 -269.852326) (xy 372.96293 -269.815489) (xy 373.001051 -269.784364) (xy 373.043672 -269.759757)
			(xy 373.089688 -269.742305) (xy 373.137907 -269.732461) (xy 373.187082 -269.73048) (xy 373.235937 -269.736412)
			(xy 373.283208 -269.750104) (xy 373.32767 -269.771202) (xy 373.368173 -269.799158) (xy 373.403666 -269.83325)
			(xy 373.433231 -269.872594) (xy 373.456102 -269.916171) (xy 373.471686 -269.962852) (xy 373.479581 -270.011429)
			(xy 373.480076 -270.036036) (xy 373.809018 -270.036036) (xy 373.812978 -269.986982) (xy 373.824755 -269.939198)
			(xy 373.844046 -269.893922) (xy 373.870349 -269.852326) (xy 373.902984 -269.815489) (xy 373.941105 -269.784364)
			(xy 373.983726 -269.759757) (xy 374.029742 -269.742305) (xy 374.077961 -269.732461) (xy 374.127136 -269.73048)
			(xy 374.175991 -269.736412) (xy 374.223262 -269.750104) (xy 374.267724 -269.771202) (xy 374.308227 -269.799158)
			(xy 374.34372 -269.83325) (xy 374.373285 -269.872594) (xy 374.396156 -269.916171) (xy 374.41174 -269.962852)
			(xy 374.419635 -270.011429) (xy 374.42013 -270.036036) (xy 374.419635 -270.060643) (xy 374.41174 -270.10922)
			(xy 374.396156 -270.155901) (xy 374.373285 -270.199478) (xy 374.34372 -270.238822) (xy 374.308227 -270.272914)
			(xy 374.267724 -270.30087) (xy 374.223262 -270.321968) (xy 374.175991 -270.33566) (xy 374.127136 -270.341592)
			(xy 374.077961 -270.339611) (xy 374.029742 -270.329767) (xy 373.983726 -270.312315) (xy 373.941105 -270.287708)
			(xy 373.902984 -270.256583) (xy 373.870349 -270.219746) (xy 373.844046 -270.17815) (xy 373.824755 -270.132874)
			(xy 373.812978 -270.08509) (xy 373.809018 -270.036036) (xy 373.480076 -270.036036) (xy 373.479581 -270.060643)
			(xy 373.471686 -270.10922) (xy 373.456102 -270.155901) (xy 373.433231 -270.199478) (xy 373.403666 -270.238822)
			(xy 373.368173 -270.272914) (xy 373.32767 -270.30087) (xy 373.283208 -270.321968) (xy 373.235937 -270.33566)
			(xy 373.187082 -270.341592) (xy 373.137907 -270.339611) (xy 373.089688 -270.329767) (xy 373.043672 -270.312315)
			(xy 373.001051 -270.287708) (xy 372.96293 -270.256583) (xy 372.930295 -270.219746) (xy 372.903992 -270.17815)
			(xy 372.884701 -270.132874) (xy 372.872924 -270.08509) (xy 372.868964 -270.036036) (xy 372.540022 -270.036036)
			(xy 372.539527 -270.060643) (xy 372.531632 -270.10922) (xy 372.516048 -270.155901) (xy 372.493177 -270.199478)
			(xy 372.463612 -270.238822) (xy 372.428119 -270.272914) (xy 372.387616 -270.30087) (xy 372.343154 -270.321968)
			(xy 372.295883 -270.33566) (xy 372.247028 -270.341592) (xy 372.197853 -270.339611) (xy 372.149634 -270.329767)
			(xy 372.103618 -270.312315) (xy 372.060997 -270.287708) (xy 372.022876 -270.256583) (xy 371.990241 -270.219746)
			(xy 371.963938 -270.17815) (xy 371.944647 -270.132874) (xy 371.93287 -270.08509) (xy 371.92891 -270.036036)
			(xy 371.600222 -270.036036) (xy 371.599727 -270.060643) (xy 371.591832 -270.10922) (xy 371.576248 -270.155901)
			(xy 371.553377 -270.199478) (xy 371.523812 -270.238822) (xy 371.488319 -270.272914) (xy 371.447816 -270.30087)
			(xy 371.403354 -270.321968) (xy 371.356083 -270.33566) (xy 371.307228 -270.341592) (xy 371.258053 -270.339611)
			(xy 371.209834 -270.329767) (xy 371.163818 -270.312315) (xy 371.121197 -270.287708) (xy 371.083076 -270.256583)
			(xy 371.050441 -270.219746) (xy 371.024138 -270.17815) (xy 371.004847 -270.132874) (xy 370.99307 -270.08509)
			(xy 370.98911 -270.036036) (xy 370.660168 -270.036036) (xy 370.659673 -270.060643) (xy 370.651778 -270.10922)
			(xy 370.636194 -270.155901) (xy 370.613323 -270.199478) (xy 370.583758 -270.238822) (xy 370.548265 -270.272914)
			(xy 370.507762 -270.30087) (xy 370.4633 -270.321968) (xy 370.416029 -270.33566) (xy 370.367174 -270.341592)
			(xy 370.317999 -270.339611) (xy 370.26978 -270.329767) (xy 370.223764 -270.312315) (xy 370.181143 -270.287708)
			(xy 370.143022 -270.256583) (xy 370.110387 -270.219746) (xy 370.084084 -270.17815) (xy 370.064793 -270.132874)
			(xy 370.053016 -270.08509) (xy 370.049056 -270.036036) (xy 369.720114 -270.036036) (xy 369.719619 -270.060643)
			(xy 369.711724 -270.10922) (xy 369.69614 -270.155901) (xy 369.673269 -270.199478) (xy 369.643704 -270.238822)
			(xy 369.608211 -270.272914) (xy 369.567708 -270.30087) (xy 369.523246 -270.321968) (xy 369.475975 -270.33566)
			(xy 369.42712 -270.341592) (xy 369.377945 -270.339611) (xy 369.329726 -270.329767) (xy 369.28371 -270.312315)
			(xy 369.241089 -270.287708) (xy 369.202968 -270.256583) (xy 369.170333 -270.219746) (xy 369.14403 -270.17815)
			(xy 369.124739 -270.132874) (xy 369.112962 -270.08509) (xy 369.109002 -270.036036) (xy 368.78006 -270.036036)
			(xy 368.779565 -270.060643) (xy 368.77167 -270.10922) (xy 368.756086 -270.155901) (xy 368.733215 -270.199478)
			(xy 368.70365 -270.238822) (xy 368.668157 -270.272914) (xy 368.627654 -270.30087) (xy 368.583192 -270.321968)
			(xy 368.535921 -270.33566) (xy 368.487066 -270.341592) (xy 368.437891 -270.339611) (xy 368.389672 -270.329767)
			(xy 368.343656 -270.312315) (xy 368.301035 -270.287708) (xy 368.262914 -270.256583) (xy 368.230279 -270.219746)
			(xy 368.203976 -270.17815) (xy 368.184685 -270.132874) (xy 368.172908 -270.08509) (xy 368.168948 -270.036036)
			(xy 367.840006 -270.036036) (xy 367.839511 -270.060643) (xy 367.831616 -270.10922) (xy 367.816032 -270.155901)
			(xy 367.793161 -270.199478) (xy 367.763596 -270.238822) (xy 367.728103 -270.272914) (xy 367.6876 -270.30087)
			(xy 367.643138 -270.321968) (xy 367.595867 -270.33566) (xy 367.547012 -270.341592) (xy 367.497837 -270.339611)
			(xy 367.449618 -270.329767) (xy 367.403602 -270.312315) (xy 367.360981 -270.287708) (xy 367.32286 -270.256583)
			(xy 367.290225 -270.219746) (xy 367.263922 -270.17815) (xy 367.244631 -270.132874) (xy 367.232854 -270.08509)
			(xy 367.228894 -270.036036) (xy 366.900206 -270.036036) (xy 366.899711 -270.060643) (xy 366.891816 -270.10922)
			(xy 366.876232 -270.155901) (xy 366.853361 -270.199478) (xy 366.823796 -270.238822) (xy 366.788303 -270.272914)
			(xy 366.7478 -270.30087) (xy 366.703338 -270.321968) (xy 366.656067 -270.33566) (xy 366.607212 -270.341592)
			(xy 366.558037 -270.339611) (xy 366.509818 -270.329767) (xy 366.463802 -270.312315) (xy 366.421181 -270.287708)
			(xy 366.38306 -270.256583) (xy 366.350425 -270.219746) (xy 366.324122 -270.17815) (xy 366.304831 -270.132874)
			(xy 366.293054 -270.08509) (xy 366.289094 -270.036036) (xy 365.960152 -270.036036) (xy 365.959657 -270.060643)
			(xy 365.951762 -270.10922) (xy 365.936178 -270.155901) (xy 365.913307 -270.199478) (xy 365.883742 -270.238822)
			(xy 365.848249 -270.272914) (xy 365.807746 -270.30087) (xy 365.763284 -270.321968) (xy 365.716013 -270.33566)
			(xy 365.667158 -270.341592) (xy 365.617983 -270.339611) (xy 365.569764 -270.329767) (xy 365.523748 -270.312315)
			(xy 365.481127 -270.287708) (xy 365.443006 -270.256583) (xy 365.410371 -270.219746) (xy 365.384068 -270.17815)
			(xy 365.364777 -270.132874) (xy 365.353 -270.08509) (xy 365.34904 -270.036036) (xy 365.020098 -270.036036)
			(xy 365.019603 -270.060643) (xy 365.011708 -270.10922) (xy 364.996124 -270.155901) (xy 364.973253 -270.199478)
			(xy 364.943688 -270.238822) (xy 364.908195 -270.272914) (xy 364.867692 -270.30087) (xy 364.82323 -270.321968)
			(xy 364.775959 -270.33566) (xy 364.727104 -270.341592) (xy 364.677929 -270.339611) (xy 364.62971 -270.329767)
			(xy 364.583694 -270.312315) (xy 364.541073 -270.287708) (xy 364.502952 -270.256583) (xy 364.470317 -270.219746)
			(xy 364.444014 -270.17815) (xy 364.424723 -270.132874) (xy 364.412946 -270.08509) (xy 364.408986 -270.036036)
			(xy 364.080044 -270.036036) (xy 364.079549 -270.060643) (xy 364.071654 -270.10922) (xy 364.05607 -270.155901)
			(xy 364.033199 -270.199478) (xy 364.003634 -270.238822) (xy 363.968141 -270.272914) (xy 363.927638 -270.30087)
			(xy 363.883176 -270.321968) (xy 363.835905 -270.33566) (xy 363.78705 -270.341592) (xy 363.737875 -270.339611)
			(xy 363.689656 -270.329767) (xy 363.64364 -270.312315) (xy 363.601019 -270.287708) (xy 363.562898 -270.256583)
			(xy 363.530263 -270.219746) (xy 363.50396 -270.17815) (xy 363.484669 -270.132874) (xy 363.472892 -270.08509)
			(xy 363.468932 -270.036036) (xy 363.13999 -270.036036) (xy 363.139495 -270.060643) (xy 363.1316 -270.10922)
			(xy 363.116016 -270.155901) (xy 363.093145 -270.199478) (xy 363.06358 -270.238822) (xy 363.028087 -270.272914)
			(xy 362.987584 -270.30087) (xy 362.943122 -270.321968) (xy 362.895851 -270.33566) (xy 362.846996 -270.341592)
			(xy 362.797821 -270.339611) (xy 362.749602 -270.329767) (xy 362.703586 -270.312315) (xy 362.660965 -270.287708)
			(xy 362.622844 -270.256583) (xy 362.590209 -270.219746) (xy 362.563906 -270.17815) (xy 362.544615 -270.132874)
			(xy 362.532838 -270.08509) (xy 362.528878 -270.036036) (xy 362.20019 -270.036036) (xy 362.199695 -270.060643)
			(xy 362.1918 -270.10922) (xy 362.176216 -270.155901) (xy 362.153345 -270.199478) (xy 362.12378 -270.238822)
			(xy 362.088287 -270.272914) (xy 362.047784 -270.30087) (xy 362.003322 -270.321968) (xy 361.956051 -270.33566)
			(xy 361.907196 -270.341592) (xy 361.858021 -270.339611) (xy 361.809802 -270.329767) (xy 361.763786 -270.312315)
			(xy 361.721165 -270.287708) (xy 361.683044 -270.256583) (xy 361.650409 -270.219746) (xy 361.624106 -270.17815)
			(xy 361.604815 -270.132874) (xy 361.593038 -270.08509) (xy 361.589078 -270.036036) (xy 358.446324 -270.036036)
			(xy 358.445829 -270.060643) (xy 358.437934 -270.10922) (xy 358.42235 -270.155901) (xy 358.399479 -270.199478)
			(xy 358.369914 -270.238822) (xy 358.334421 -270.272914) (xy 358.293918 -270.30087) (xy 358.249456 -270.321968)
			(xy 358.202185 -270.33566) (xy 358.15333 -270.341592) (xy 358.104155 -270.339611) (xy 358.055936 -270.329767)
			(xy 358.00992 -270.312315) (xy 357.967299 -270.287708) (xy 357.929178 -270.256583) (xy 357.896543 -270.219746)
			(xy 357.87024 -270.17815) (xy 357.850949 -270.132874) (xy 357.839172 -270.08509) (xy 357.835212 -270.036036)
			(xy 357.506524 -270.036036) (xy 357.506029 -270.060643) (xy 357.498134 -270.10922) (xy 357.48255 -270.155901)
			(xy 357.459679 -270.199478) (xy 357.430114 -270.238822) (xy 357.394621 -270.272914) (xy 357.354118 -270.30087)
			(xy 357.309656 -270.321968) (xy 357.262385 -270.33566) (xy 357.21353 -270.341592) (xy 357.164355 -270.339611)
			(xy 357.116136 -270.329767) (xy 357.07012 -270.312315) (xy 357.027499 -270.287708) (xy 356.989378 -270.256583)
			(xy 356.956743 -270.219746) (xy 356.93044 -270.17815) (xy 356.911149 -270.132874) (xy 356.899372 -270.08509)
			(xy 356.895412 -270.036036) (xy 356.56647 -270.036036) (xy 356.565975 -270.060643) (xy 356.55808 -270.10922)
			(xy 356.542496 -270.155901) (xy 356.519625 -270.199478) (xy 356.49006 -270.238822) (xy 356.454567 -270.272914)
			(xy 356.414064 -270.30087) (xy 356.369602 -270.321968) (xy 356.322331 -270.33566) (xy 356.273476 -270.341592)
			(xy 356.224301 -270.339611) (xy 356.176082 -270.329767) (xy 356.130066 -270.312315) (xy 356.087445 -270.287708)
			(xy 356.049324 -270.256583) (xy 356.016689 -270.219746) (xy 355.990386 -270.17815) (xy 355.971095 -270.132874)
			(xy 355.959318 -270.08509) (xy 355.955358 -270.036036) (xy 355.626416 -270.036036) (xy 355.625921 -270.060643)
			(xy 355.618026 -270.10922) (xy 355.602442 -270.155901) (xy 355.579571 -270.199478) (xy 355.550006 -270.238822)
			(xy 355.514513 -270.272914) (xy 355.47401 -270.30087) (xy 355.429548 -270.321968) (xy 355.382277 -270.33566)
			(xy 355.333422 -270.341592) (xy 355.284247 -270.339611) (xy 355.236028 -270.329767) (xy 355.190012 -270.312315)
			(xy 355.147391 -270.287708) (xy 355.10927 -270.256583) (xy 355.076635 -270.219746) (xy 355.050332 -270.17815)
			(xy 355.031041 -270.132874) (xy 355.019264 -270.08509) (xy 355.015304 -270.036036) (xy 354.686362 -270.036036)
			(xy 354.685867 -270.060643) (xy 354.677972 -270.10922) (xy 354.662388 -270.155901) (xy 354.639517 -270.199478)
			(xy 354.609952 -270.238822) (xy 354.574459 -270.272914) (xy 354.533956 -270.30087) (xy 354.489494 -270.321968)
			(xy 354.442223 -270.33566) (xy 354.393368 -270.341592) (xy 354.344193 -270.339611) (xy 354.295974 -270.329767)
			(xy 354.249958 -270.312315) (xy 354.207337 -270.287708) (xy 354.169216 -270.256583) (xy 354.136581 -270.219746)
			(xy 354.110278 -270.17815) (xy 354.090987 -270.132874) (xy 354.07921 -270.08509) (xy 354.07525 -270.036036)
			(xy 353.746308 -270.036036) (xy 353.745813 -270.060643) (xy 353.737918 -270.10922) (xy 353.722334 -270.155901)
			(xy 353.699463 -270.199478) (xy 353.669898 -270.238822) (xy 353.634405 -270.272914) (xy 353.593902 -270.30087)
			(xy 353.54944 -270.321968) (xy 353.502169 -270.33566) (xy 353.453314 -270.341592) (xy 353.404139 -270.339611)
			(xy 353.35592 -270.329767) (xy 353.309904 -270.312315) (xy 353.267283 -270.287708) (xy 353.229162 -270.256583)
			(xy 353.196527 -270.219746) (xy 353.170224 -270.17815) (xy 353.150933 -270.132874) (xy 353.139156 -270.08509)
			(xy 353.135196 -270.036036) (xy 352.806508 -270.036036) (xy 352.806013 -270.060643) (xy 352.798118 -270.10922)
			(xy 352.782534 -270.155901) (xy 352.759663 -270.199478) (xy 352.730098 -270.238822) (xy 352.694605 -270.272914)
			(xy 352.654102 -270.30087) (xy 352.60964 -270.321968) (xy 352.562369 -270.33566) (xy 352.513514 -270.341592)
			(xy 352.464339 -270.339611) (xy 352.41612 -270.329767) (xy 352.370104 -270.312315) (xy 352.327483 -270.287708)
			(xy 352.289362 -270.256583) (xy 352.256727 -270.219746) (xy 352.230424 -270.17815) (xy 352.211133 -270.132874)
			(xy 352.199356 -270.08509) (xy 352.195396 -270.036036) (xy 351.866454 -270.036036) (xy 351.865959 -270.060643)
			(xy 351.858064 -270.10922) (xy 351.84248 -270.155901) (xy 351.819609 -270.199478) (xy 351.790044 -270.238822)
			(xy 351.754551 -270.272914) (xy 351.714048 -270.30087) (xy 351.669586 -270.321968) (xy 351.622315 -270.33566)
			(xy 351.57346 -270.341592) (xy 351.524285 -270.339611) (xy 351.476066 -270.329767) (xy 351.43005 -270.312315)
			(xy 351.387429 -270.287708) (xy 351.349308 -270.256583) (xy 351.316673 -270.219746) (xy 351.29037 -270.17815)
			(xy 351.271079 -270.132874) (xy 351.259302 -270.08509) (xy 351.255342 -270.036036) (xy 350.9264 -270.036036)
			(xy 350.925905 -270.060643) (xy 350.91801 -270.10922) (xy 350.902426 -270.155901) (xy 350.879555 -270.199478)
			(xy 350.84999 -270.238822) (xy 350.814497 -270.272914) (xy 350.773994 -270.30087) (xy 350.729532 -270.321968)
			(xy 350.682261 -270.33566) (xy 350.633406 -270.341592) (xy 350.584231 -270.339611) (xy 350.536012 -270.329767)
			(xy 350.489996 -270.312315) (xy 350.447375 -270.287708) (xy 350.409254 -270.256583) (xy 350.376619 -270.219746)
			(xy 350.350316 -270.17815) (xy 350.331025 -270.132874) (xy 350.319248 -270.08509) (xy 350.315288 -270.036036)
			(xy 349.986346 -270.036036) (xy 349.985851 -270.060643) (xy 349.977956 -270.10922) (xy 349.962372 -270.155901)
			(xy 349.939501 -270.199478) (xy 349.909936 -270.238822) (xy 349.874443 -270.272914) (xy 349.83394 -270.30087)
			(xy 349.789478 -270.321968) (xy 349.742207 -270.33566) (xy 349.693352 -270.341592) (xy 349.644177 -270.339611)
			(xy 349.595958 -270.329767) (xy 349.549942 -270.312315) (xy 349.507321 -270.287708) (xy 349.4692 -270.256583)
			(xy 349.436565 -270.219746) (xy 349.410262 -270.17815) (xy 349.390971 -270.132874) (xy 349.379194 -270.08509)
			(xy 349.375234 -270.036036) (xy 349.046546 -270.036036) (xy 349.046051 -270.060643) (xy 349.038156 -270.10922)
			(xy 349.022572 -270.155901) (xy 348.999701 -270.199478) (xy 348.970136 -270.238822) (xy 348.934643 -270.272914)
			(xy 348.89414 -270.30087) (xy 348.849678 -270.321968) (xy 348.802407 -270.33566) (xy 348.753552 -270.341592)
			(xy 348.704377 -270.339611) (xy 348.656158 -270.329767) (xy 348.610142 -270.312315) (xy 348.567521 -270.287708)
			(xy 348.5294 -270.256583) (xy 348.496765 -270.219746) (xy 348.470462 -270.17815) (xy 348.451171 -270.132874)
			(xy 348.439394 -270.08509) (xy 348.435434 -270.036036) (xy 348.106492 -270.036036) (xy 348.105997 -270.060643)
			(xy 348.098102 -270.10922) (xy 348.082518 -270.155901) (xy 348.059647 -270.199478) (xy 348.030082 -270.238822)
			(xy 347.994589 -270.272914) (xy 347.954086 -270.30087) (xy 347.909624 -270.321968) (xy 347.862353 -270.33566)
			(xy 347.813498 -270.341592) (xy 347.764323 -270.339611) (xy 347.716104 -270.329767) (xy 347.670088 -270.312315)
			(xy 347.627467 -270.287708) (xy 347.589346 -270.256583) (xy 347.556711 -270.219746) (xy 347.530408 -270.17815)
			(xy 347.511117 -270.132874) (xy 347.49934 -270.08509) (xy 347.49538 -270.036036) (xy 347.166438 -270.036036)
			(xy 347.165943 -270.060643) (xy 347.158048 -270.10922) (xy 347.142464 -270.155901) (xy 347.119593 -270.199478)
			(xy 347.090028 -270.238822) (xy 347.054535 -270.272914) (xy 347.014032 -270.30087) (xy 346.96957 -270.321968)
			(xy 346.922299 -270.33566) (xy 346.873444 -270.341592) (xy 346.824269 -270.339611) (xy 346.77605 -270.329767)
			(xy 346.730034 -270.312315) (xy 346.687413 -270.287708) (xy 346.649292 -270.256583) (xy 346.616657 -270.219746)
			(xy 346.590354 -270.17815) (xy 346.571063 -270.132874) (xy 346.559286 -270.08509) (xy 346.555326 -270.036036)
			(xy 346.226384 -270.036036) (xy 346.225889 -270.060643) (xy 346.217994 -270.10922) (xy 346.20241 -270.155901)
			(xy 346.179539 -270.199478) (xy 346.149974 -270.238822) (xy 346.114481 -270.272914) (xy 346.073978 -270.30087)
			(xy 346.029516 -270.321968) (xy 345.982245 -270.33566) (xy 345.93339 -270.341592) (xy 345.884215 -270.339611)
			(xy 345.835996 -270.329767) (xy 345.78998 -270.312315) (xy 345.747359 -270.287708) (xy 345.709238 -270.256583)
			(xy 345.676603 -270.219746) (xy 345.6503 -270.17815) (xy 345.631009 -270.132874) (xy 345.619232 -270.08509)
			(xy 345.615272 -270.036036) (xy 345.286747 -270.036036) (xy 345.282752 -270.085276) (xy 345.27087 -270.133251)
			(xy 345.251414 -270.178685) (xy 345.224891 -270.220391) (xy 345.191995 -270.257278) (xy 345.153585 -270.288383)
			(xy 345.110666 -270.312892) (xy 345.087702 -270.32204) (xy 345.087194 -270.322294) (xy 345.077619 -270.326322)
			(xy 345.062551 -270.340593) (xy 345.054377 -270.359668) (xy 345.05392 -270.370046) (xy 345.05392 -270.566388)
			(xy 345.054375 -270.576526) (xy 345.062227 -270.59522) (xy 345.076682 -270.60944) (xy 345.085924 -270.613632)
			(xy 345.188286 -270.654272) (xy 345.218766 -270.647668) (xy 345.229434 -270.636238) (xy 345.246848 -270.618521)
			(xy 345.286368 -270.588425) (xy 345.330244 -270.565135) (xy 345.377316 -270.549267) (xy 345.426338 -270.541241)
			(xy 345.451176 -270.540734) (xy 345.476432 -270.541225) (xy 345.526254 -270.549535) (xy 345.574029 -270.565933)
			(xy 345.618454 -270.589971) (xy 345.658316 -270.620994) (xy 345.692527 -270.658155) (xy 345.720155 -270.70044)
			(xy 345.740446 -270.746696) (xy 345.752847 -270.795662) (xy 345.757018 -270.846) (xy 345.757015 -270.846042)
			(xy 346.085426 -270.846042) (xy 346.089386 -270.796988) (xy 346.101163 -270.749204) (xy 346.120454 -270.703928)
			(xy 346.146757 -270.662332) (xy 346.179392 -270.625495) (xy 346.217513 -270.59437) (xy 346.260134 -270.569763)
			(xy 346.30615 -270.552311) (xy 346.354369 -270.542467) (xy 346.403544 -270.540486) (xy 346.452399 -270.546418)
			(xy 346.49967 -270.56011) (xy 346.544132 -270.581208) (xy 346.584635 -270.609164) (xy 346.620128 -270.643256)
			(xy 346.649693 -270.6826) (xy 346.672564 -270.726177) (xy 346.688148 -270.772858) (xy 346.696043 -270.821435)
			(xy 346.696538 -270.846042) (xy 347.025226 -270.846042) (xy 347.029186 -270.796988) (xy 347.040963 -270.749204)
			(xy 347.060254 -270.703928) (xy 347.086557 -270.662332) (xy 347.119192 -270.625495) (xy 347.157313 -270.59437)
			(xy 347.199934 -270.569763) (xy 347.24595 -270.552311) (xy 347.294169 -270.542467) (xy 347.343344 -270.540486)
			(xy 347.392199 -270.546418) (xy 347.43947 -270.56011) (xy 347.483932 -270.581208) (xy 347.524435 -270.609164)
			(xy 347.559928 -270.643256) (xy 347.589493 -270.6826) (xy 347.612364 -270.726177) (xy 347.627948 -270.772858)
			(xy 347.635843 -270.821435) (xy 347.636338 -270.846042) (xy 347.96528 -270.846042) (xy 347.96924 -270.796988)
			(xy 347.981017 -270.749204) (xy 348.000308 -270.703928) (xy 348.026611 -270.662332) (xy 348.059246 -270.625495)
			(xy 348.097367 -270.59437) (xy 348.139988 -270.569763) (xy 348.186004 -270.552311) (xy 348.234223 -270.542467)
			(xy 348.283398 -270.540486) (xy 348.332253 -270.546418) (xy 348.379524 -270.56011) (xy 348.423986 -270.581208)
			(xy 348.464489 -270.609164) (xy 348.499982 -270.643256) (xy 348.529547 -270.6826) (xy 348.552418 -270.726177)
			(xy 348.568002 -270.772858) (xy 348.575897 -270.821435) (xy 348.576392 -270.846042) (xy 348.905334 -270.846042)
			(xy 348.909294 -270.796988) (xy 348.921071 -270.749204) (xy 348.940362 -270.703928) (xy 348.966665 -270.662332)
			(xy 348.9993 -270.625495) (xy 349.037421 -270.59437) (xy 349.080042 -270.569763) (xy 349.126058 -270.552311)
			(xy 349.174277 -270.542467) (xy 349.223452 -270.540486) (xy 349.272307 -270.546418) (xy 349.319578 -270.56011)
			(xy 349.36404 -270.581208) (xy 349.404543 -270.609164) (xy 349.440036 -270.643256) (xy 349.469601 -270.6826)
			(xy 349.492472 -270.726177) (xy 349.508056 -270.772858) (xy 349.515951 -270.821435) (xy 349.516446 -270.846042)
			(xy 349.845388 -270.846042) (xy 349.849348 -270.796988) (xy 349.861125 -270.749204) (xy 349.880416 -270.703928)
			(xy 349.906719 -270.662332) (xy 349.939354 -270.625495) (xy 349.977475 -270.59437) (xy 350.020096 -270.569763)
			(xy 350.066112 -270.552311) (xy 350.114331 -270.542467) (xy 350.163506 -270.540486) (xy 350.212361 -270.546418)
			(xy 350.259632 -270.56011) (xy 350.304094 -270.581208) (xy 350.344597 -270.609164) (xy 350.38009 -270.643256)
			(xy 350.409655 -270.6826) (xy 350.432526 -270.726177) (xy 350.44811 -270.772858) (xy 350.456005 -270.821435)
			(xy 350.4565 -270.846042) (xy 350.785442 -270.846042) (xy 350.789402 -270.796988) (xy 350.801179 -270.749204)
			(xy 350.82047 -270.703928) (xy 350.846773 -270.662332) (xy 350.879408 -270.625495) (xy 350.917529 -270.59437)
			(xy 350.96015 -270.569763) (xy 351.006166 -270.552311) (xy 351.054385 -270.542467) (xy 351.10356 -270.540486)
			(xy 351.152415 -270.546418) (xy 351.199686 -270.56011) (xy 351.244148 -270.581208) (xy 351.284651 -270.609164)
			(xy 351.320144 -270.643256) (xy 351.349709 -270.6826) (xy 351.37258 -270.726177) (xy 351.388164 -270.772858)
			(xy 351.396059 -270.821435) (xy 351.396554 -270.846042) (xy 351.725242 -270.846042) (xy 351.729202 -270.796988)
			(xy 351.740979 -270.749204) (xy 351.76027 -270.703928) (xy 351.786573 -270.662332) (xy 351.819208 -270.625495)
			(xy 351.857329 -270.59437) (xy 351.89995 -270.569763) (xy 351.945966 -270.552311) (xy 351.994185 -270.542467)
			(xy 352.04336 -270.540486) (xy 352.092215 -270.546418) (xy 352.139486 -270.56011) (xy 352.183948 -270.581208)
			(xy 352.224451 -270.609164) (xy 352.259944 -270.643256) (xy 352.289509 -270.6826) (xy 352.31238 -270.726177)
			(xy 352.327964 -270.772858) (xy 352.335859 -270.821435) (xy 352.336354 -270.846042) (xy 352.665296 -270.846042)
			(xy 352.669256 -270.796988) (xy 352.681033 -270.749204) (xy 352.700324 -270.703928) (xy 352.726627 -270.662332)
			(xy 352.759262 -270.625495) (xy 352.797383 -270.59437) (xy 352.840004 -270.569763) (xy 352.88602 -270.552311)
			(xy 352.934239 -270.542467) (xy 352.983414 -270.540486) (xy 353.032269 -270.546418) (xy 353.07954 -270.56011)
			(xy 353.124002 -270.581208) (xy 353.164505 -270.609164) (xy 353.199998 -270.643256) (xy 353.229563 -270.6826)
			(xy 353.252434 -270.726177) (xy 353.268018 -270.772858) (xy 353.275913 -270.821435) (xy 353.276408 -270.846042)
			(xy 353.60535 -270.846042) (xy 353.60931 -270.796988) (xy 353.621087 -270.749204) (xy 353.640378 -270.703928)
			(xy 353.666681 -270.662332) (xy 353.699316 -270.625495) (xy 353.737437 -270.59437) (xy 353.780058 -270.569763)
			(xy 353.826074 -270.552311) (xy 353.874293 -270.542467) (xy 353.923468 -270.540486) (xy 353.972323 -270.546418)
			(xy 354.019594 -270.56011) (xy 354.064056 -270.581208) (xy 354.104559 -270.609164) (xy 354.140052 -270.643256)
			(xy 354.169617 -270.6826) (xy 354.192488 -270.726177) (xy 354.208072 -270.772858) (xy 354.215967 -270.821435)
			(xy 354.216462 -270.846042) (xy 354.545404 -270.846042) (xy 354.549364 -270.796988) (xy 354.561141 -270.749204)
			(xy 354.580432 -270.703928) (xy 354.606735 -270.662332) (xy 354.63937 -270.625495) (xy 354.677491 -270.59437)
			(xy 354.720112 -270.569763) (xy 354.766128 -270.552311) (xy 354.814347 -270.542467) (xy 354.863522 -270.540486)
			(xy 354.912377 -270.546418) (xy 354.959648 -270.56011) (xy 355.00411 -270.581208) (xy 355.044613 -270.609164)
			(xy 355.080106 -270.643256) (xy 355.109671 -270.6826) (xy 355.132542 -270.726177) (xy 355.148126 -270.772858)
			(xy 355.156021 -270.821435) (xy 355.156516 -270.846042) (xy 355.485204 -270.846042) (xy 355.489164 -270.796988)
			(xy 355.500941 -270.749204) (xy 355.520232 -270.703928) (xy 355.546535 -270.662332) (xy 355.57917 -270.625495)
			(xy 355.617291 -270.59437) (xy 355.659912 -270.569763) (xy 355.705928 -270.552311) (xy 355.754147 -270.542467)
			(xy 355.803322 -270.540486) (xy 355.852177 -270.546418) (xy 355.899448 -270.56011) (xy 355.94391 -270.581208)
			(xy 355.984413 -270.609164) (xy 356.019906 -270.643256) (xy 356.049471 -270.6826) (xy 356.072342 -270.726177)
			(xy 356.087926 -270.772858) (xy 356.095821 -270.821435) (xy 356.096316 -270.846042) (xy 356.425258 -270.846042)
			(xy 356.429218 -270.796988) (xy 356.440995 -270.749204) (xy 356.460286 -270.703928) (xy 356.486589 -270.662332)
			(xy 356.519224 -270.625495) (xy 356.557345 -270.59437) (xy 356.599966 -270.569763) (xy 356.645982 -270.552311)
			(xy 356.694201 -270.542467) (xy 356.743376 -270.540486) (xy 356.792231 -270.546418) (xy 356.839502 -270.56011)
			(xy 356.883964 -270.581208) (xy 356.924467 -270.609164) (xy 356.95996 -270.643256) (xy 356.989525 -270.6826)
			(xy 357.012396 -270.726177) (xy 357.02798 -270.772858) (xy 357.035875 -270.821435) (xy 357.03637 -270.846042)
			(xy 357.365312 -270.846042) (xy 357.369272 -270.796988) (xy 357.381049 -270.749204) (xy 357.40034 -270.703928)
			(xy 357.426643 -270.662332) (xy 357.459278 -270.625495) (xy 357.497399 -270.59437) (xy 357.54002 -270.569763)
			(xy 357.586036 -270.552311) (xy 357.634255 -270.542467) (xy 357.68343 -270.540486) (xy 357.732285 -270.546418)
			(xy 357.779556 -270.56011) (xy 357.824018 -270.581208) (xy 357.864521 -270.609164) (xy 357.900014 -270.643256)
			(xy 357.929579 -270.6826) (xy 357.95245 -270.726177) (xy 357.968034 -270.772858) (xy 357.975929 -270.821435)
			(xy 357.976424 -270.846042) (xy 358.305366 -270.846042) (xy 358.309326 -270.796988) (xy 358.321103 -270.749204)
			(xy 358.340394 -270.703928) (xy 358.366697 -270.662332) (xy 358.399332 -270.625495) (xy 358.437453 -270.59437)
			(xy 358.480074 -270.569763) (xy 358.52609 -270.552311) (xy 358.574309 -270.542467) (xy 358.623484 -270.540486)
			(xy 358.672339 -270.546418) (xy 358.71961 -270.56011) (xy 358.764072 -270.581208) (xy 358.804575 -270.609164)
			(xy 358.840068 -270.643256) (xy 358.869633 -270.6826) (xy 358.892504 -270.726177) (xy 358.908088 -270.772858)
			(xy 358.915983 -270.821435) (xy 358.916478 -270.846042) (xy 361.118924 -270.846042) (xy 361.122884 -270.796988)
			(xy 361.134661 -270.749204) (xy 361.153952 -270.703928) (xy 361.180255 -270.662332) (xy 361.21289 -270.625495)
			(xy 361.251011 -270.59437) (xy 361.293632 -270.569763) (xy 361.339648 -270.552311) (xy 361.387867 -270.542467)
			(xy 361.437042 -270.540486) (xy 361.485897 -270.546418) (xy 361.533168 -270.56011) (xy 361.57763 -270.581208)
			(xy 361.618133 -270.609164) (xy 361.653626 -270.643256) (xy 361.683191 -270.6826) (xy 361.706062 -270.726177)
			(xy 361.721646 -270.772858) (xy 361.729541 -270.821435) (xy 361.730036 -270.846042) (xy 362.058978 -270.846042)
			(xy 362.062938 -270.796988) (xy 362.074715 -270.749204) (xy 362.094006 -270.703928) (xy 362.120309 -270.662332)
			(xy 362.152944 -270.625495) (xy 362.191065 -270.59437) (xy 362.233686 -270.569763) (xy 362.279702 -270.552311)
			(xy 362.327921 -270.542467) (xy 362.377096 -270.540486) (xy 362.425951 -270.546418) (xy 362.473222 -270.56011)
			(xy 362.517684 -270.581208) (xy 362.558187 -270.609164) (xy 362.59368 -270.643256) (xy 362.623245 -270.6826)
			(xy 362.646116 -270.726177) (xy 362.6617 -270.772858) (xy 362.669595 -270.821435) (xy 362.67009 -270.846042)
			(xy 362.999032 -270.846042) (xy 363.002992 -270.796988) (xy 363.014769 -270.749204) (xy 363.03406 -270.703928)
			(xy 363.060363 -270.662332) (xy 363.092998 -270.625495) (xy 363.131119 -270.59437) (xy 363.17374 -270.569763)
			(xy 363.219756 -270.552311) (xy 363.267975 -270.542467) (xy 363.31715 -270.540486) (xy 363.366005 -270.546418)
			(xy 363.413276 -270.56011) (xy 363.457738 -270.581208) (xy 363.498241 -270.609164) (xy 363.533734 -270.643256)
			(xy 363.563299 -270.6826) (xy 363.58617 -270.726177) (xy 363.601754 -270.772858) (xy 363.609649 -270.821435)
			(xy 363.610144 -270.846042) (xy 363.939086 -270.846042) (xy 363.943046 -270.796988) (xy 363.954823 -270.749204)
			(xy 363.974114 -270.703928) (xy 364.000417 -270.662332) (xy 364.033052 -270.625495) (xy 364.071173 -270.59437)
			(xy 364.113794 -270.569763) (xy 364.15981 -270.552311) (xy 364.208029 -270.542467) (xy 364.257204 -270.540486)
			(xy 364.306059 -270.546418) (xy 364.35333 -270.56011) (xy 364.397792 -270.581208) (xy 364.438295 -270.609164)
			(xy 364.473788 -270.643256) (xy 364.503353 -270.6826) (xy 364.526224 -270.726177) (xy 364.541808 -270.772858)
			(xy 364.549703 -270.821435) (xy 364.550198 -270.846042) (xy 364.878886 -270.846042) (xy 364.882846 -270.796988)
			(xy 364.894623 -270.749204) (xy 364.913914 -270.703928) (xy 364.940217 -270.662332) (xy 364.972852 -270.625495)
			(xy 365.010973 -270.59437) (xy 365.053594 -270.569763) (xy 365.09961 -270.552311) (xy 365.147829 -270.542467)
			(xy 365.197004 -270.540486) (xy 365.245859 -270.546418) (xy 365.29313 -270.56011) (xy 365.337592 -270.581208)
			(xy 365.378095 -270.609164) (xy 365.413588 -270.643256) (xy 365.443153 -270.6826) (xy 365.466024 -270.726177)
			(xy 365.481608 -270.772858) (xy 365.489503 -270.821435) (xy 365.489998 -270.846042) (xy 365.81894 -270.846042)
			(xy 365.8229 -270.796988) (xy 365.834677 -270.749204) (xy 365.853968 -270.703928) (xy 365.880271 -270.662332)
			(xy 365.912906 -270.625495) (xy 365.951027 -270.59437) (xy 365.993648 -270.569763) (xy 366.039664 -270.552311)
			(xy 366.087883 -270.542467) (xy 366.137058 -270.540486) (xy 366.185913 -270.546418) (xy 366.233184 -270.56011)
			(xy 366.277646 -270.581208) (xy 366.318149 -270.609164) (xy 366.353642 -270.643256) (xy 366.383207 -270.6826)
			(xy 366.406078 -270.726177) (xy 366.421662 -270.772858) (xy 366.429557 -270.821435) (xy 366.430052 -270.846042)
			(xy 366.758994 -270.846042) (xy 366.762954 -270.796988) (xy 366.774731 -270.749204) (xy 366.794022 -270.703928)
			(xy 366.820325 -270.662332) (xy 366.85296 -270.625495) (xy 366.891081 -270.59437) (xy 366.933702 -270.569763)
			(xy 366.979718 -270.552311) (xy 367.027937 -270.542467) (xy 367.077112 -270.540486) (xy 367.125967 -270.546418)
			(xy 367.173238 -270.56011) (xy 367.2177 -270.581208) (xy 367.258203 -270.609164) (xy 367.293696 -270.643256)
			(xy 367.323261 -270.6826) (xy 367.346132 -270.726177) (xy 367.361716 -270.772858) (xy 367.369611 -270.821435)
			(xy 367.370106 -270.846042) (xy 367.699048 -270.846042) (xy 367.703008 -270.796988) (xy 367.714785 -270.749204)
			(xy 367.734076 -270.703928) (xy 367.760379 -270.662332) (xy 367.793014 -270.625495) (xy 367.831135 -270.59437)
			(xy 367.873756 -270.569763) (xy 367.919772 -270.552311) (xy 367.967991 -270.542467) (xy 368.017166 -270.540486)
			(xy 368.066021 -270.546418) (xy 368.113292 -270.56011) (xy 368.157754 -270.581208) (xy 368.198257 -270.609164)
			(xy 368.23375 -270.643256) (xy 368.263315 -270.6826) (xy 368.286186 -270.726177) (xy 368.30177 -270.772858)
			(xy 368.309665 -270.821435) (xy 368.31016 -270.846042) (xy 368.639102 -270.846042) (xy 368.643062 -270.796988)
			(xy 368.654839 -270.749204) (xy 368.67413 -270.703928) (xy 368.700433 -270.662332) (xy 368.733068 -270.625495)
			(xy 368.771189 -270.59437) (xy 368.81381 -270.569763) (xy 368.859826 -270.552311) (xy 368.908045 -270.542467)
			(xy 368.95722 -270.540486) (xy 369.006075 -270.546418) (xy 369.053346 -270.56011) (xy 369.097808 -270.581208)
			(xy 369.138311 -270.609164) (xy 369.173804 -270.643256) (xy 369.203369 -270.6826) (xy 369.22624 -270.726177)
			(xy 369.241824 -270.772858) (xy 369.249719 -270.821435) (xy 369.250214 -270.846042) (xy 369.578902 -270.846042)
			(xy 369.582862 -270.796988) (xy 369.594639 -270.749204) (xy 369.61393 -270.703928) (xy 369.640233 -270.662332)
			(xy 369.672868 -270.625495) (xy 369.710989 -270.59437) (xy 369.75361 -270.569763) (xy 369.799626 -270.552311)
			(xy 369.847845 -270.542467) (xy 369.89702 -270.540486) (xy 369.945875 -270.546418) (xy 369.993146 -270.56011)
			(xy 370.037608 -270.581208) (xy 370.078111 -270.609164) (xy 370.113604 -270.643256) (xy 370.143169 -270.6826)
			(xy 370.16604 -270.726177) (xy 370.181624 -270.772858) (xy 370.189519 -270.821435) (xy 370.190014 -270.846042)
			(xy 370.518956 -270.846042) (xy 370.522916 -270.796988) (xy 370.534693 -270.749204) (xy 370.553984 -270.703928)
			(xy 370.580287 -270.662332) (xy 370.612922 -270.625495) (xy 370.651043 -270.59437) (xy 370.693664 -270.569763)
			(xy 370.73968 -270.552311) (xy 370.787899 -270.542467) (xy 370.837074 -270.540486) (xy 370.885929 -270.546418)
			(xy 370.9332 -270.56011) (xy 370.977662 -270.581208) (xy 371.018165 -270.609164) (xy 371.053658 -270.643256)
			(xy 371.083223 -270.6826) (xy 371.106094 -270.726177) (xy 371.121678 -270.772858) (xy 371.129573 -270.821435)
			(xy 371.130068 -270.846042) (xy 371.45901 -270.846042) (xy 371.46297 -270.796988) (xy 371.474747 -270.749204)
			(xy 371.494038 -270.703928) (xy 371.520341 -270.662332) (xy 371.552976 -270.625495) (xy 371.591097 -270.59437)
			(xy 371.633718 -270.569763) (xy 371.679734 -270.552311) (xy 371.727953 -270.542467) (xy 371.777128 -270.540486)
			(xy 371.825983 -270.546418) (xy 371.873254 -270.56011) (xy 371.917716 -270.581208) (xy 371.958219 -270.609164)
			(xy 371.993712 -270.643256) (xy 372.023277 -270.6826) (xy 372.046148 -270.726177) (xy 372.061732 -270.772858)
			(xy 372.069627 -270.821435) (xy 372.070122 -270.846042) (xy 372.399064 -270.846042) (xy 372.403024 -270.796988)
			(xy 372.414801 -270.749204) (xy 372.434092 -270.703928) (xy 372.460395 -270.662332) (xy 372.49303 -270.625495)
			(xy 372.531151 -270.59437) (xy 372.573772 -270.569763) (xy 372.619788 -270.552311) (xy 372.668007 -270.542467)
			(xy 372.717182 -270.540486) (xy 372.766037 -270.546418) (xy 372.813308 -270.56011) (xy 372.85777 -270.581208)
			(xy 372.898273 -270.609164) (xy 372.933766 -270.643256) (xy 372.963331 -270.6826) (xy 372.986202 -270.726177)
			(xy 373.001786 -270.772858) (xy 373.009681 -270.821435) (xy 373.010176 -270.846042) (xy 373.339118 -270.846042)
			(xy 373.343078 -270.796988) (xy 373.354855 -270.749204) (xy 373.374146 -270.703928) (xy 373.400449 -270.662332)
			(xy 373.433084 -270.625495) (xy 373.471205 -270.59437) (xy 373.513826 -270.569763) (xy 373.559842 -270.552311)
			(xy 373.608061 -270.542467) (xy 373.657236 -270.540486) (xy 373.706091 -270.546418) (xy 373.753362 -270.56011)
			(xy 373.797824 -270.581208) (xy 373.838327 -270.609164) (xy 373.87382 -270.643256) (xy 373.903385 -270.6826)
			(xy 373.926256 -270.726177) (xy 373.94184 -270.772858) (xy 373.949735 -270.821435) (xy 373.95023 -270.846042)
			(xy 373.949735 -270.870649) (xy 373.94184 -270.919226) (xy 373.926256 -270.965907) (xy 373.903385 -271.009484)
			(xy 373.87382 -271.048828) (xy 373.838327 -271.08292) (xy 373.797824 -271.110876) (xy 373.753362 -271.131974)
			(xy 373.706091 -271.145666) (xy 373.657236 -271.151598) (xy 373.608061 -271.149617) (xy 373.559842 -271.139773)
			(xy 373.513826 -271.122321) (xy 373.471205 -271.097714) (xy 373.433084 -271.066589) (xy 373.400449 -271.029752)
			(xy 373.374146 -270.988156) (xy 373.354855 -270.94288) (xy 373.343078 -270.895096) (xy 373.339118 -270.846042)
			(xy 373.010176 -270.846042) (xy 373.009681 -270.870649) (xy 373.001786 -270.919226) (xy 372.986202 -270.965907)
			(xy 372.963331 -271.009484) (xy 372.933766 -271.048828) (xy 372.898273 -271.08292) (xy 372.85777 -271.110876)
			(xy 372.813308 -271.131974) (xy 372.766037 -271.145666) (xy 372.717182 -271.151598) (xy 372.668007 -271.149617)
			(xy 372.619788 -271.139773) (xy 372.573772 -271.122321) (xy 372.531151 -271.097714) (xy 372.49303 -271.066589)
			(xy 372.460395 -271.029752) (xy 372.434092 -270.988156) (xy 372.414801 -270.94288) (xy 372.403024 -270.895096)
			(xy 372.399064 -270.846042) (xy 372.070122 -270.846042) (xy 372.069627 -270.870649) (xy 372.061732 -270.919226)
			(xy 372.046148 -270.965907) (xy 372.023277 -271.009484) (xy 371.993712 -271.048828) (xy 371.958219 -271.08292)
			(xy 371.917716 -271.110876) (xy 371.873254 -271.131974) (xy 371.825983 -271.145666) (xy 371.777128 -271.151598)
			(xy 371.727953 -271.149617) (xy 371.679734 -271.139773) (xy 371.633718 -271.122321) (xy 371.591097 -271.097714)
			(xy 371.552976 -271.066589) (xy 371.520341 -271.029752) (xy 371.494038 -270.988156) (xy 371.474747 -270.94288)
			(xy 371.46297 -270.895096) (xy 371.45901 -270.846042) (xy 371.130068 -270.846042) (xy 371.129573 -270.870649)
			(xy 371.121678 -270.919226) (xy 371.106094 -270.965907) (xy 371.083223 -271.009484) (xy 371.053658 -271.048828)
			(xy 371.018165 -271.08292) (xy 370.977662 -271.110876) (xy 370.9332 -271.131974) (xy 370.885929 -271.145666)
			(xy 370.837074 -271.151598) (xy 370.787899 -271.149617) (xy 370.73968 -271.139773) (xy 370.693664 -271.122321)
			(xy 370.651043 -271.097714) (xy 370.612922 -271.066589) (xy 370.580287 -271.029752) (xy 370.553984 -270.988156)
			(xy 370.534693 -270.94288) (xy 370.522916 -270.895096) (xy 370.518956 -270.846042) (xy 370.190014 -270.846042)
			(xy 370.189519 -270.870649) (xy 370.181624 -270.919226) (xy 370.16604 -270.965907) (xy 370.143169 -271.009484)
			(xy 370.113604 -271.048828) (xy 370.078111 -271.08292) (xy 370.037608 -271.110876) (xy 369.993146 -271.131974)
			(xy 369.945875 -271.145666) (xy 369.89702 -271.151598) (xy 369.847845 -271.149617) (xy 369.799626 -271.139773)
			(xy 369.75361 -271.122321) (xy 369.710989 -271.097714) (xy 369.672868 -271.066589) (xy 369.640233 -271.029752)
			(xy 369.61393 -270.988156) (xy 369.594639 -270.94288) (xy 369.582862 -270.895096) (xy 369.578902 -270.846042)
			(xy 369.250214 -270.846042) (xy 369.249719 -270.870649) (xy 369.241824 -270.919226) (xy 369.22624 -270.965907)
			(xy 369.203369 -271.009484) (xy 369.173804 -271.048828) (xy 369.138311 -271.08292) (xy 369.097808 -271.110876)
			(xy 369.053346 -271.131974) (xy 369.006075 -271.145666) (xy 368.95722 -271.151598) (xy 368.908045 -271.149617)
			(xy 368.859826 -271.139773) (xy 368.81381 -271.122321) (xy 368.771189 -271.097714) (xy 368.733068 -271.066589)
			(xy 368.700433 -271.029752) (xy 368.67413 -270.988156) (xy 368.654839 -270.94288) (xy 368.643062 -270.895096)
			(xy 368.639102 -270.846042) (xy 368.31016 -270.846042) (xy 368.309665 -270.870649) (xy 368.30177 -270.919226)
			(xy 368.286186 -270.965907) (xy 368.263315 -271.009484) (xy 368.23375 -271.048828) (xy 368.198257 -271.08292)
			(xy 368.157754 -271.110876) (xy 368.113292 -271.131974) (xy 368.066021 -271.145666) (xy 368.017166 -271.151598)
			(xy 367.967991 -271.149617) (xy 367.919772 -271.139773) (xy 367.873756 -271.122321) (xy 367.831135 -271.097714)
			(xy 367.793014 -271.066589) (xy 367.760379 -271.029752) (xy 367.734076 -270.988156) (xy 367.714785 -270.94288)
			(xy 367.703008 -270.895096) (xy 367.699048 -270.846042) (xy 367.370106 -270.846042) (xy 367.369611 -270.870649)
			(xy 367.361716 -270.919226) (xy 367.346132 -270.965907) (xy 367.323261 -271.009484) (xy 367.293696 -271.048828)
			(xy 367.258203 -271.08292) (xy 367.2177 -271.110876) (xy 367.173238 -271.131974) (xy 367.125967 -271.145666)
			(xy 367.077112 -271.151598) (xy 367.027937 -271.149617) (xy 366.979718 -271.139773) (xy 366.933702 -271.122321)
			(xy 366.891081 -271.097714) (xy 366.85296 -271.066589) (xy 366.820325 -271.029752) (xy 366.794022 -270.988156)
			(xy 366.774731 -270.94288) (xy 366.762954 -270.895096) (xy 366.758994 -270.846042) (xy 366.430052 -270.846042)
			(xy 366.429557 -270.870649) (xy 366.421662 -270.919226) (xy 366.406078 -270.965907) (xy 366.383207 -271.009484)
			(xy 366.353642 -271.048828) (xy 366.318149 -271.08292) (xy 366.277646 -271.110876) (xy 366.233184 -271.131974)
			(xy 366.185913 -271.145666) (xy 366.137058 -271.151598) (xy 366.087883 -271.149617) (xy 366.039664 -271.139773)
			(xy 365.993648 -271.122321) (xy 365.951027 -271.097714) (xy 365.912906 -271.066589) (xy 365.880271 -271.029752)
			(xy 365.853968 -270.988156) (xy 365.834677 -270.94288) (xy 365.8229 -270.895096) (xy 365.81894 -270.846042)
			(xy 365.489998 -270.846042) (xy 365.489503 -270.870649) (xy 365.481608 -270.919226) (xy 365.466024 -270.965907)
			(xy 365.443153 -271.009484) (xy 365.413588 -271.048828) (xy 365.378095 -271.08292) (xy 365.337592 -271.110876)
			(xy 365.29313 -271.131974) (xy 365.245859 -271.145666) (xy 365.197004 -271.151598) (xy 365.147829 -271.149617)
			(xy 365.09961 -271.139773) (xy 365.053594 -271.122321) (xy 365.010973 -271.097714) (xy 364.972852 -271.066589)
			(xy 364.940217 -271.029752) (xy 364.913914 -270.988156) (xy 364.894623 -270.94288) (xy 364.882846 -270.895096)
			(xy 364.878886 -270.846042) (xy 364.550198 -270.846042) (xy 364.549703 -270.870649) (xy 364.541808 -270.919226)
			(xy 364.526224 -270.965907) (xy 364.503353 -271.009484) (xy 364.473788 -271.048828) (xy 364.438295 -271.08292)
			(xy 364.397792 -271.110876) (xy 364.35333 -271.131974) (xy 364.306059 -271.145666) (xy 364.257204 -271.151598)
			(xy 364.208029 -271.149617) (xy 364.15981 -271.139773) (xy 364.113794 -271.122321) (xy 364.071173 -271.097714)
			(xy 364.033052 -271.066589) (xy 364.000417 -271.029752) (xy 363.974114 -270.988156) (xy 363.954823 -270.94288)
			(xy 363.943046 -270.895096) (xy 363.939086 -270.846042) (xy 363.610144 -270.846042) (xy 363.609649 -270.870649)
			(xy 363.601754 -270.919226) (xy 363.58617 -270.965907) (xy 363.563299 -271.009484) (xy 363.533734 -271.048828)
			(xy 363.498241 -271.08292) (xy 363.457738 -271.110876) (xy 363.413276 -271.131974) (xy 363.366005 -271.145666)
			(xy 363.31715 -271.151598) (xy 363.267975 -271.149617) (xy 363.219756 -271.139773) (xy 363.17374 -271.122321)
			(xy 363.131119 -271.097714) (xy 363.092998 -271.066589) (xy 363.060363 -271.029752) (xy 363.03406 -270.988156)
			(xy 363.014769 -270.94288) (xy 363.002992 -270.895096) (xy 362.999032 -270.846042) (xy 362.67009 -270.846042)
			(xy 362.669595 -270.870649) (xy 362.6617 -270.919226) (xy 362.646116 -270.965907) (xy 362.623245 -271.009484)
			(xy 362.59368 -271.048828) (xy 362.558187 -271.08292) (xy 362.517684 -271.110876) (xy 362.473222 -271.131974)
			(xy 362.425951 -271.145666) (xy 362.377096 -271.151598) (xy 362.327921 -271.149617) (xy 362.279702 -271.139773)
			(xy 362.233686 -271.122321) (xy 362.191065 -271.097714) (xy 362.152944 -271.066589) (xy 362.120309 -271.029752)
			(xy 362.094006 -270.988156) (xy 362.074715 -270.94288) (xy 362.062938 -270.895096) (xy 362.058978 -270.846042)
			(xy 361.730036 -270.846042) (xy 361.729541 -270.870649) (xy 361.721646 -270.919226) (xy 361.706062 -270.965907)
			(xy 361.683191 -271.009484) (xy 361.653626 -271.048828) (xy 361.618133 -271.08292) (xy 361.57763 -271.110876)
			(xy 361.533168 -271.131974) (xy 361.485897 -271.145666) (xy 361.437042 -271.151598) (xy 361.387867 -271.149617)
			(xy 361.339648 -271.139773) (xy 361.293632 -271.122321) (xy 361.251011 -271.097714) (xy 361.21289 -271.066589)
			(xy 361.180255 -271.029752) (xy 361.153952 -270.988156) (xy 361.134661 -270.94288) (xy 361.122884 -270.895096)
			(xy 361.118924 -270.846042) (xy 358.916478 -270.846042) (xy 358.915983 -270.870649) (xy 358.908088 -270.919226)
			(xy 358.892504 -270.965907) (xy 358.869633 -271.009484) (xy 358.840068 -271.048828) (xy 358.804575 -271.08292)
			(xy 358.764072 -271.110876) (xy 358.71961 -271.131974) (xy 358.672339 -271.145666) (xy 358.623484 -271.151598)
			(xy 358.574309 -271.149617) (xy 358.52609 -271.139773) (xy 358.480074 -271.122321) (xy 358.437453 -271.097714)
			(xy 358.399332 -271.066589) (xy 358.366697 -271.029752) (xy 358.340394 -270.988156) (xy 358.321103 -270.94288)
			(xy 358.309326 -270.895096) (xy 358.305366 -270.846042) (xy 357.976424 -270.846042) (xy 357.975929 -270.870649)
			(xy 357.968034 -270.919226) (xy 357.95245 -270.965907) (xy 357.929579 -271.009484) (xy 357.900014 -271.048828)
			(xy 357.864521 -271.08292) (xy 357.824018 -271.110876) (xy 357.779556 -271.131974) (xy 357.732285 -271.145666)
			(xy 357.68343 -271.151598) (xy 357.634255 -271.149617) (xy 357.586036 -271.139773) (xy 357.54002 -271.122321)
			(xy 357.497399 -271.097714) (xy 357.459278 -271.066589) (xy 357.426643 -271.029752) (xy 357.40034 -270.988156)
			(xy 357.381049 -270.94288) (xy 357.369272 -270.895096) (xy 357.365312 -270.846042) (xy 357.03637 -270.846042)
			(xy 357.035875 -270.870649) (xy 357.02798 -270.919226) (xy 357.012396 -270.965907) (xy 356.989525 -271.009484)
			(xy 356.95996 -271.048828) (xy 356.924467 -271.08292) (xy 356.883964 -271.110876) (xy 356.839502 -271.131974)
			(xy 356.792231 -271.145666) (xy 356.743376 -271.151598) (xy 356.694201 -271.149617) (xy 356.645982 -271.139773)
			(xy 356.599966 -271.122321) (xy 356.557345 -271.097714) (xy 356.519224 -271.066589) (xy 356.486589 -271.029752)
			(xy 356.460286 -270.988156) (xy 356.440995 -270.94288) (xy 356.429218 -270.895096) (xy 356.425258 -270.846042)
			(xy 356.096316 -270.846042) (xy 356.095821 -270.870649) (xy 356.087926 -270.919226) (xy 356.072342 -270.965907)
			(xy 356.049471 -271.009484) (xy 356.019906 -271.048828) (xy 355.984413 -271.08292) (xy 355.94391 -271.110876)
			(xy 355.899448 -271.131974) (xy 355.852177 -271.145666) (xy 355.803322 -271.151598) (xy 355.754147 -271.149617)
			(xy 355.705928 -271.139773) (xy 355.659912 -271.122321) (xy 355.617291 -271.097714) (xy 355.57917 -271.066589)
			(xy 355.546535 -271.029752) (xy 355.520232 -270.988156) (xy 355.500941 -270.94288) (xy 355.489164 -270.895096)
			(xy 355.485204 -270.846042) (xy 355.156516 -270.846042) (xy 355.156021 -270.870649) (xy 355.148126 -270.919226)
			(xy 355.132542 -270.965907) (xy 355.109671 -271.009484) (xy 355.080106 -271.048828) (xy 355.044613 -271.08292)
			(xy 355.00411 -271.110876) (xy 354.959648 -271.131974) (xy 354.912377 -271.145666) (xy 354.863522 -271.151598)
			(xy 354.814347 -271.149617) (xy 354.766128 -271.139773) (xy 354.720112 -271.122321) (xy 354.677491 -271.097714)
			(xy 354.63937 -271.066589) (xy 354.606735 -271.029752) (xy 354.580432 -270.988156) (xy 354.561141 -270.94288)
			(xy 354.549364 -270.895096) (xy 354.545404 -270.846042) (xy 354.216462 -270.846042) (xy 354.215967 -270.870649)
			(xy 354.208072 -270.919226) (xy 354.192488 -270.965907) (xy 354.169617 -271.009484) (xy 354.140052 -271.048828)
			(xy 354.104559 -271.08292) (xy 354.064056 -271.110876) (xy 354.019594 -271.131974) (xy 353.972323 -271.145666)
			(xy 353.923468 -271.151598) (xy 353.874293 -271.149617) (xy 353.826074 -271.139773) (xy 353.780058 -271.122321)
			(xy 353.737437 -271.097714) (xy 353.699316 -271.066589) (xy 353.666681 -271.029752) (xy 353.640378 -270.988156)
			(xy 353.621087 -270.94288) (xy 353.60931 -270.895096) (xy 353.60535 -270.846042) (xy 353.276408 -270.846042)
			(xy 353.275913 -270.870649) (xy 353.268018 -270.919226) (xy 353.252434 -270.965907) (xy 353.229563 -271.009484)
			(xy 353.199998 -271.048828) (xy 353.164505 -271.08292) (xy 353.124002 -271.110876) (xy 353.07954 -271.131974)
			(xy 353.032269 -271.145666) (xy 352.983414 -271.151598) (xy 352.934239 -271.149617) (xy 352.88602 -271.139773)
			(xy 352.840004 -271.122321) (xy 352.797383 -271.097714) (xy 352.759262 -271.066589) (xy 352.726627 -271.029752)
			(xy 352.700324 -270.988156) (xy 352.681033 -270.94288) (xy 352.669256 -270.895096) (xy 352.665296 -270.846042)
			(xy 352.336354 -270.846042) (xy 352.335859 -270.870649) (xy 352.327964 -270.919226) (xy 352.31238 -270.965907)
			(xy 352.289509 -271.009484) (xy 352.259944 -271.048828) (xy 352.224451 -271.08292) (xy 352.183948 -271.110876)
			(xy 352.139486 -271.131974) (xy 352.092215 -271.145666) (xy 352.04336 -271.151598) (xy 351.994185 -271.149617)
			(xy 351.945966 -271.139773) (xy 351.89995 -271.122321) (xy 351.857329 -271.097714) (xy 351.819208 -271.066589)
			(xy 351.786573 -271.029752) (xy 351.76027 -270.988156) (xy 351.740979 -270.94288) (xy 351.729202 -270.895096)
			(xy 351.725242 -270.846042) (xy 351.396554 -270.846042) (xy 351.396059 -270.870649) (xy 351.388164 -270.919226)
			(xy 351.37258 -270.965907) (xy 351.349709 -271.009484) (xy 351.320144 -271.048828) (xy 351.284651 -271.08292)
			(xy 351.244148 -271.110876) (xy 351.199686 -271.131974) (xy 351.152415 -271.145666) (xy 351.10356 -271.151598)
			(xy 351.054385 -271.149617) (xy 351.006166 -271.139773) (xy 350.96015 -271.122321) (xy 350.917529 -271.097714)
			(xy 350.879408 -271.066589) (xy 350.846773 -271.029752) (xy 350.82047 -270.988156) (xy 350.801179 -270.94288)
			(xy 350.789402 -270.895096) (xy 350.785442 -270.846042) (xy 350.4565 -270.846042) (xy 350.456005 -270.870649)
			(xy 350.44811 -270.919226) (xy 350.432526 -270.965907) (xy 350.409655 -271.009484) (xy 350.38009 -271.048828)
			(xy 350.344597 -271.08292) (xy 350.304094 -271.110876) (xy 350.259632 -271.131974) (xy 350.212361 -271.145666)
			(xy 350.163506 -271.151598) (xy 350.114331 -271.149617) (xy 350.066112 -271.139773) (xy 350.020096 -271.122321)
			(xy 349.977475 -271.097714) (xy 349.939354 -271.066589) (xy 349.906719 -271.029752) (xy 349.880416 -270.988156)
			(xy 349.861125 -270.94288) (xy 349.849348 -270.895096) (xy 349.845388 -270.846042) (xy 349.516446 -270.846042)
			(xy 349.515951 -270.870649) (xy 349.508056 -270.919226) (xy 349.492472 -270.965907) (xy 349.469601 -271.009484)
			(xy 349.440036 -271.048828) (xy 349.404543 -271.08292) (xy 349.36404 -271.110876) (xy 349.319578 -271.131974)
			(xy 349.272307 -271.145666) (xy 349.223452 -271.151598) (xy 349.174277 -271.149617) (xy 349.126058 -271.139773)
			(xy 349.080042 -271.122321) (xy 349.037421 -271.097714) (xy 348.9993 -271.066589) (xy 348.966665 -271.029752)
			(xy 348.940362 -270.988156) (xy 348.921071 -270.94288) (xy 348.909294 -270.895096) (xy 348.905334 -270.846042)
			(xy 348.576392 -270.846042) (xy 348.575897 -270.870649) (xy 348.568002 -270.919226) (xy 348.552418 -270.965907)
			(xy 348.529547 -271.009484) (xy 348.499982 -271.048828) (xy 348.464489 -271.08292) (xy 348.423986 -271.110876)
			(xy 348.379524 -271.131974) (xy 348.332253 -271.145666) (xy 348.283398 -271.151598) (xy 348.234223 -271.149617)
			(xy 348.186004 -271.139773) (xy 348.139988 -271.122321) (xy 348.097367 -271.097714) (xy 348.059246 -271.066589)
			(xy 348.026611 -271.029752) (xy 348.000308 -270.988156) (xy 347.981017 -270.94288) (xy 347.96924 -270.895096)
			(xy 347.96528 -270.846042) (xy 347.636338 -270.846042) (xy 347.635843 -270.870649) (xy 347.627948 -270.919226)
			(xy 347.612364 -270.965907) (xy 347.589493 -271.009484) (xy 347.559928 -271.048828) (xy 347.524435 -271.08292)
			(xy 347.483932 -271.110876) (xy 347.43947 -271.131974) (xy 347.392199 -271.145666) (xy 347.343344 -271.151598)
			(xy 347.294169 -271.149617) (xy 347.24595 -271.139773) (xy 347.199934 -271.122321) (xy 347.157313 -271.097714)
			(xy 347.119192 -271.066589) (xy 347.086557 -271.029752) (xy 347.060254 -270.988156) (xy 347.040963 -270.94288)
			(xy 347.029186 -270.895096) (xy 347.025226 -270.846042) (xy 346.696538 -270.846042) (xy 346.696043 -270.870649)
			(xy 346.688148 -270.919226) (xy 346.672564 -270.965907) (xy 346.649693 -271.009484) (xy 346.620128 -271.048828)
			(xy 346.584635 -271.08292) (xy 346.544132 -271.110876) (xy 346.49967 -271.131974) (xy 346.452399 -271.145666)
			(xy 346.403544 -271.151598) (xy 346.354369 -271.149617) (xy 346.30615 -271.139773) (xy 346.260134 -271.122321)
			(xy 346.217513 -271.097714) (xy 346.179392 -271.066589) (xy 346.146757 -271.029752) (xy 346.120454 -270.988156)
			(xy 346.101163 -270.94288) (xy 346.089386 -270.895096) (xy 346.085426 -270.846042) (xy 345.757015 -270.846042)
			(xy 345.752847 -270.896338) (xy 345.740446 -270.945304) (xy 345.720155 -270.99156) (xy 345.692527 -271.033845)
			(xy 345.658316 -271.071006) (xy 345.618454 -271.102029) (xy 345.574029 -271.126067) (xy 345.526254 -271.142465)
			(xy 345.476432 -271.150775) (xy 345.451176 -271.15135) (xy 345.426339 -271.150861) (xy 345.377321 -271.142814)
			(xy 345.330253 -271.126936) (xy 345.286376 -271.103647) (xy 345.24685 -271.07356) (xy 345.229434 -271.055846)
			(xy 345.218766 -271.044416) (xy 345.188286 -271.037812) (xy 345.085924 -271.078452) (xy 345.076652 -271.082607)
			(xy 345.062159 -271.096821) (xy 345.054317 -271.115545) (xy 345.05392 -271.125696) (xy 345.05392 -271.322038)
			(xy 345.054412 -271.332407) (xy 345.062599 -271.351462) (xy 345.077633 -271.365748) (xy 345.087194 -271.36979)
			(xy 345.087702 -271.370044) (xy 345.110687 -271.37913) (xy 345.153603 -271.403643) (xy 345.192008 -271.434751)
			(xy 345.2249 -271.47164) (xy 345.251417 -271.513346) (xy 345.270869 -271.558781) (xy 345.282746 -271.606755)
			(xy 345.286738 -271.656017) (xy 345.286735 -271.656048) (xy 345.615272 -271.656048) (xy 345.619232 -271.606994)
			(xy 345.631009 -271.55921) (xy 345.6503 -271.513934) (xy 345.676603 -271.472338) (xy 345.709238 -271.435501)
			(xy 345.747359 -271.404376) (xy 345.78998 -271.379769) (xy 345.835996 -271.362317) (xy 345.884215 -271.352473)
			(xy 345.93339 -271.350492) (xy 345.982245 -271.356424) (xy 346.029516 -271.370116) (xy 346.073978 -271.391214)
			(xy 346.114481 -271.41917) (xy 346.149974 -271.453262) (xy 346.179539 -271.492606) (xy 346.20241 -271.536183)
			(xy 346.217994 -271.582864) (xy 346.225889 -271.631441) (xy 346.226384 -271.656048) (xy 346.555326 -271.656048)
			(xy 346.559286 -271.606994) (xy 346.571063 -271.55921) (xy 346.590354 -271.513934) (xy 346.616657 -271.472338)
			(xy 346.649292 -271.435501) (xy 346.687413 -271.404376) (xy 346.730034 -271.379769) (xy 346.77605 -271.362317)
			(xy 346.824269 -271.352473) (xy 346.873444 -271.350492) (xy 346.922299 -271.356424) (xy 346.96957 -271.370116)
			(xy 347.014032 -271.391214) (xy 347.054535 -271.41917) (xy 347.090028 -271.453262) (xy 347.119593 -271.492606)
			(xy 347.142464 -271.536183) (xy 347.158048 -271.582864) (xy 347.165943 -271.631441) (xy 347.166438 -271.656048)
			(xy 347.49538 -271.656048) (xy 347.49934 -271.606994) (xy 347.511117 -271.55921) (xy 347.530408 -271.513934)
			(xy 347.556711 -271.472338) (xy 347.589346 -271.435501) (xy 347.627467 -271.404376) (xy 347.670088 -271.379769)
			(xy 347.716104 -271.362317) (xy 347.764323 -271.352473) (xy 347.813498 -271.350492) (xy 347.862353 -271.356424)
			(xy 347.909624 -271.370116) (xy 347.954086 -271.391214) (xy 347.994589 -271.41917) (xy 348.030082 -271.453262)
			(xy 348.059647 -271.492606) (xy 348.082518 -271.536183) (xy 348.098102 -271.582864) (xy 348.105997 -271.631441)
			(xy 348.106492 -271.656048) (xy 348.435434 -271.656048) (xy 348.439394 -271.606994) (xy 348.451171 -271.55921)
			(xy 348.470462 -271.513934) (xy 348.496765 -271.472338) (xy 348.5294 -271.435501) (xy 348.567521 -271.404376)
			(xy 348.610142 -271.379769) (xy 348.656158 -271.362317) (xy 348.704377 -271.352473) (xy 348.753552 -271.350492)
			(xy 348.802407 -271.356424) (xy 348.849678 -271.370116) (xy 348.89414 -271.391214) (xy 348.934643 -271.41917)
			(xy 348.970136 -271.453262) (xy 348.999701 -271.492606) (xy 349.022572 -271.536183) (xy 349.038156 -271.582864)
			(xy 349.046051 -271.631441) (xy 349.046546 -271.656048) (xy 349.375234 -271.656048) (xy 349.379194 -271.606994)
			(xy 349.390971 -271.55921) (xy 349.410262 -271.513934) (xy 349.436565 -271.472338) (xy 349.4692 -271.435501)
			(xy 349.507321 -271.404376) (xy 349.549942 -271.379769) (xy 349.595958 -271.362317) (xy 349.644177 -271.352473)
			(xy 349.693352 -271.350492) (xy 349.742207 -271.356424) (xy 349.789478 -271.370116) (xy 349.83394 -271.391214)
			(xy 349.874443 -271.41917) (xy 349.909936 -271.453262) (xy 349.939501 -271.492606) (xy 349.962372 -271.536183)
			(xy 349.977956 -271.582864) (xy 349.985851 -271.631441) (xy 349.986346 -271.656048) (xy 350.315288 -271.656048)
			(xy 350.319248 -271.606994) (xy 350.331025 -271.55921) (xy 350.350316 -271.513934) (xy 350.376619 -271.472338)
			(xy 350.409254 -271.435501) (xy 350.447375 -271.404376) (xy 350.489996 -271.379769) (xy 350.536012 -271.362317)
			(xy 350.584231 -271.352473) (xy 350.633406 -271.350492) (xy 350.682261 -271.356424) (xy 350.729532 -271.370116)
			(xy 350.773994 -271.391214) (xy 350.814497 -271.41917) (xy 350.84999 -271.453262) (xy 350.879555 -271.492606)
			(xy 350.902426 -271.536183) (xy 350.91801 -271.582864) (xy 350.925905 -271.631441) (xy 350.9264 -271.656048)
			(xy 351.255342 -271.656048) (xy 351.259302 -271.606994) (xy 351.271079 -271.55921) (xy 351.29037 -271.513934)
			(xy 351.316673 -271.472338) (xy 351.349308 -271.435501) (xy 351.387429 -271.404376) (xy 351.43005 -271.379769)
			(xy 351.476066 -271.362317) (xy 351.524285 -271.352473) (xy 351.57346 -271.350492) (xy 351.622315 -271.356424)
			(xy 351.669586 -271.370116) (xy 351.714048 -271.391214) (xy 351.754551 -271.41917) (xy 351.790044 -271.453262)
			(xy 351.819609 -271.492606) (xy 351.84248 -271.536183) (xy 351.858064 -271.582864) (xy 351.865959 -271.631441)
			(xy 351.866454 -271.656048) (xy 352.195396 -271.656048) (xy 352.199356 -271.606994) (xy 352.211133 -271.55921)
			(xy 352.230424 -271.513934) (xy 352.256727 -271.472338) (xy 352.289362 -271.435501) (xy 352.327483 -271.404376)
			(xy 352.370104 -271.379769) (xy 352.41612 -271.362317) (xy 352.464339 -271.352473) (xy 352.513514 -271.350492)
			(xy 352.562369 -271.356424) (xy 352.60964 -271.370116) (xy 352.654102 -271.391214) (xy 352.694605 -271.41917)
			(xy 352.730098 -271.453262) (xy 352.759663 -271.492606) (xy 352.782534 -271.536183) (xy 352.798118 -271.582864)
			(xy 352.806013 -271.631441) (xy 352.806508 -271.656048) (xy 353.135196 -271.656048) (xy 353.139156 -271.606994)
			(xy 353.150933 -271.55921) (xy 353.170224 -271.513934) (xy 353.196527 -271.472338) (xy 353.229162 -271.435501)
			(xy 353.267283 -271.404376) (xy 353.309904 -271.379769) (xy 353.35592 -271.362317) (xy 353.404139 -271.352473)
			(xy 353.453314 -271.350492) (xy 353.502169 -271.356424) (xy 353.54944 -271.370116) (xy 353.593902 -271.391214)
			(xy 353.634405 -271.41917) (xy 353.669898 -271.453262) (xy 353.699463 -271.492606) (xy 353.722334 -271.536183)
			(xy 353.737918 -271.582864) (xy 353.745813 -271.631441) (xy 353.746308 -271.656048) (xy 354.07525 -271.656048)
			(xy 354.07921 -271.606994) (xy 354.090987 -271.55921) (xy 354.110278 -271.513934) (xy 354.136581 -271.472338)
			(xy 354.169216 -271.435501) (xy 354.207337 -271.404376) (xy 354.249958 -271.379769) (xy 354.295974 -271.362317)
			(xy 354.344193 -271.352473) (xy 354.393368 -271.350492) (xy 354.442223 -271.356424) (xy 354.489494 -271.370116)
			(xy 354.533956 -271.391214) (xy 354.574459 -271.41917) (xy 354.609952 -271.453262) (xy 354.639517 -271.492606)
			(xy 354.662388 -271.536183) (xy 354.677972 -271.582864) (xy 354.685867 -271.631441) (xy 354.686362 -271.656048)
			(xy 355.015304 -271.656048) (xy 355.019264 -271.606994) (xy 355.031041 -271.55921) (xy 355.050332 -271.513934)
			(xy 355.076635 -271.472338) (xy 355.10927 -271.435501) (xy 355.147391 -271.404376) (xy 355.190012 -271.379769)
			(xy 355.236028 -271.362317) (xy 355.284247 -271.352473) (xy 355.333422 -271.350492) (xy 355.382277 -271.356424)
			(xy 355.429548 -271.370116) (xy 355.47401 -271.391214) (xy 355.514513 -271.41917) (xy 355.550006 -271.453262)
			(xy 355.579571 -271.492606) (xy 355.602442 -271.536183) (xy 355.618026 -271.582864) (xy 355.625921 -271.631441)
			(xy 355.626416 -271.656048) (xy 355.955358 -271.656048) (xy 355.959318 -271.606994) (xy 355.971095 -271.55921)
			(xy 355.990386 -271.513934) (xy 356.016689 -271.472338) (xy 356.049324 -271.435501) (xy 356.087445 -271.404376)
			(xy 356.130066 -271.379769) (xy 356.176082 -271.362317) (xy 356.224301 -271.352473) (xy 356.273476 -271.350492)
			(xy 356.322331 -271.356424) (xy 356.369602 -271.370116) (xy 356.414064 -271.391214) (xy 356.454567 -271.41917)
			(xy 356.49006 -271.453262) (xy 356.519625 -271.492606) (xy 356.542496 -271.536183) (xy 356.55808 -271.582864)
			(xy 356.565975 -271.631441) (xy 356.56647 -271.656048) (xy 363.468932 -271.656048) (xy 363.472892 -271.606994)
			(xy 363.484669 -271.55921) (xy 363.50396 -271.513934) (xy 363.530263 -271.472338) (xy 363.562898 -271.435501)
			(xy 363.601019 -271.404376) (xy 363.64364 -271.379769) (xy 363.689656 -271.362317) (xy 363.737875 -271.352473)
			(xy 363.78705 -271.350492) (xy 363.835905 -271.356424) (xy 363.883176 -271.370116) (xy 363.927638 -271.391214)
			(xy 363.968141 -271.41917) (xy 364.003634 -271.453262) (xy 364.033199 -271.492606) (xy 364.05607 -271.536183)
			(xy 364.071654 -271.582864) (xy 364.079549 -271.631441) (xy 364.080044 -271.656048) (xy 364.408986 -271.656048)
			(xy 364.412946 -271.606994) (xy 364.424723 -271.55921) (xy 364.444014 -271.513934) (xy 364.470317 -271.472338)
			(xy 364.502952 -271.435501) (xy 364.541073 -271.404376) (xy 364.583694 -271.379769) (xy 364.62971 -271.362317)
			(xy 364.677929 -271.352473) (xy 364.727104 -271.350492) (xy 364.775959 -271.356424) (xy 364.82323 -271.370116)
			(xy 364.867692 -271.391214) (xy 364.908195 -271.41917) (xy 364.943688 -271.453262) (xy 364.973253 -271.492606)
			(xy 364.996124 -271.536183) (xy 365.011708 -271.582864) (xy 365.019603 -271.631441) (xy 365.020098 -271.656048)
			(xy 365.34904 -271.656048) (xy 365.353 -271.606994) (xy 365.364777 -271.55921) (xy 365.384068 -271.513934)
			(xy 365.410371 -271.472338) (xy 365.443006 -271.435501) (xy 365.481127 -271.404376) (xy 365.523748 -271.379769)
			(xy 365.569764 -271.362317) (xy 365.617983 -271.352473) (xy 365.667158 -271.350492) (xy 365.716013 -271.356424)
			(xy 365.763284 -271.370116) (xy 365.807746 -271.391214) (xy 365.848249 -271.41917) (xy 365.883742 -271.453262)
			(xy 365.913307 -271.492606) (xy 365.936178 -271.536183) (xy 365.951762 -271.582864) (xy 365.959657 -271.631441)
			(xy 365.960152 -271.656048) (xy 366.289094 -271.656048) (xy 366.293054 -271.606994) (xy 366.304831 -271.55921)
			(xy 366.324122 -271.513934) (xy 366.350425 -271.472338) (xy 366.38306 -271.435501) (xy 366.421181 -271.404376)
			(xy 366.463802 -271.379769) (xy 366.509818 -271.362317) (xy 366.558037 -271.352473) (xy 366.607212 -271.350492)
			(xy 366.656067 -271.356424) (xy 366.703338 -271.370116) (xy 366.7478 -271.391214) (xy 366.788303 -271.41917)
			(xy 366.823796 -271.453262) (xy 366.853361 -271.492606) (xy 366.876232 -271.536183) (xy 366.891816 -271.582864)
			(xy 366.899711 -271.631441) (xy 366.900206 -271.656048) (xy 367.228894 -271.656048) (xy 367.232854 -271.606994)
			(xy 367.244631 -271.55921) (xy 367.263922 -271.513934) (xy 367.290225 -271.472338) (xy 367.32286 -271.435501)
			(xy 367.360981 -271.404376) (xy 367.403602 -271.379769) (xy 367.449618 -271.362317) (xy 367.497837 -271.352473)
			(xy 367.547012 -271.350492) (xy 367.595867 -271.356424) (xy 367.643138 -271.370116) (xy 367.6876 -271.391214)
			(xy 367.728103 -271.41917) (xy 367.763596 -271.453262) (xy 367.793161 -271.492606) (xy 367.816032 -271.536183)
			(xy 367.831616 -271.582864) (xy 367.839511 -271.631441) (xy 367.840006 -271.656048) (xy 368.168948 -271.656048)
			(xy 368.172908 -271.606994) (xy 368.184685 -271.55921) (xy 368.203976 -271.513934) (xy 368.230279 -271.472338)
			(xy 368.262914 -271.435501) (xy 368.301035 -271.404376) (xy 368.343656 -271.379769) (xy 368.389672 -271.362317)
			(xy 368.437891 -271.352473) (xy 368.487066 -271.350492) (xy 368.535921 -271.356424) (xy 368.583192 -271.370116)
			(xy 368.627654 -271.391214) (xy 368.668157 -271.41917) (xy 368.70365 -271.453262) (xy 368.733215 -271.492606)
			(xy 368.756086 -271.536183) (xy 368.77167 -271.582864) (xy 368.779565 -271.631441) (xy 368.78006 -271.656048)
			(xy 369.109002 -271.656048) (xy 369.112962 -271.606994) (xy 369.124739 -271.55921) (xy 369.14403 -271.513934)
			(xy 369.170333 -271.472338) (xy 369.202968 -271.435501) (xy 369.241089 -271.404376) (xy 369.28371 -271.379769)
			(xy 369.329726 -271.362317) (xy 369.377945 -271.352473) (xy 369.42712 -271.350492) (xy 369.475975 -271.356424)
			(xy 369.523246 -271.370116) (xy 369.567708 -271.391214) (xy 369.608211 -271.41917) (xy 369.643704 -271.453262)
			(xy 369.673269 -271.492606) (xy 369.69614 -271.536183) (xy 369.711724 -271.582864) (xy 369.719619 -271.631441)
			(xy 369.720114 -271.656048) (xy 370.049056 -271.656048) (xy 370.053016 -271.606994) (xy 370.064793 -271.55921)
			(xy 370.084084 -271.513934) (xy 370.110387 -271.472338) (xy 370.143022 -271.435501) (xy 370.181143 -271.404376)
			(xy 370.223764 -271.379769) (xy 370.26978 -271.362317) (xy 370.317999 -271.352473) (xy 370.367174 -271.350492)
			(xy 370.416029 -271.356424) (xy 370.4633 -271.370116) (xy 370.507762 -271.391214) (xy 370.548265 -271.41917)
			(xy 370.583758 -271.453262) (xy 370.613323 -271.492606) (xy 370.636194 -271.536183) (xy 370.651778 -271.582864)
			(xy 370.659673 -271.631441) (xy 370.660168 -271.656048) (xy 370.98911 -271.656048) (xy 370.99307 -271.606994)
			(xy 371.004847 -271.55921) (xy 371.024138 -271.513934) (xy 371.050441 -271.472338) (xy 371.083076 -271.435501)
			(xy 371.121197 -271.404376) (xy 371.163818 -271.379769) (xy 371.209834 -271.362317) (xy 371.258053 -271.352473)
			(xy 371.307228 -271.350492) (xy 371.356083 -271.356424) (xy 371.403354 -271.370116) (xy 371.447816 -271.391214)
			(xy 371.488319 -271.41917) (xy 371.523812 -271.453262) (xy 371.553377 -271.492606) (xy 371.576248 -271.536183)
			(xy 371.591832 -271.582864) (xy 371.599727 -271.631441) (xy 371.600222 -271.656048) (xy 371.92891 -271.656048)
			(xy 371.93287 -271.606994) (xy 371.944647 -271.55921) (xy 371.963938 -271.513934) (xy 371.990241 -271.472338)
			(xy 372.022876 -271.435501) (xy 372.060997 -271.404376) (xy 372.103618 -271.379769) (xy 372.149634 -271.362317)
			(xy 372.197853 -271.352473) (xy 372.247028 -271.350492) (xy 372.295883 -271.356424) (xy 372.343154 -271.370116)
			(xy 372.387616 -271.391214) (xy 372.428119 -271.41917) (xy 372.463612 -271.453262) (xy 372.493177 -271.492606)
			(xy 372.516048 -271.536183) (xy 372.531632 -271.582864) (xy 372.539527 -271.631441) (xy 372.540022 -271.656048)
			(xy 372.868964 -271.656048) (xy 372.872924 -271.606994) (xy 372.884701 -271.55921) (xy 372.903992 -271.513934)
			(xy 372.930295 -271.472338) (xy 372.96293 -271.435501) (xy 373.001051 -271.404376) (xy 373.043672 -271.379769)
			(xy 373.089688 -271.362317) (xy 373.137907 -271.352473) (xy 373.187082 -271.350492) (xy 373.235937 -271.356424)
			(xy 373.283208 -271.370116) (xy 373.32767 -271.391214) (xy 373.368173 -271.41917) (xy 373.403666 -271.453262)
			(xy 373.433231 -271.492606) (xy 373.456102 -271.536183) (xy 373.471686 -271.582864) (xy 373.479581 -271.631441)
			(xy 373.480076 -271.656048) (xy 373.809018 -271.656048) (xy 373.812978 -271.606994) (xy 373.824755 -271.55921)
			(xy 373.844046 -271.513934) (xy 373.870349 -271.472338) (xy 373.902984 -271.435501) (xy 373.941105 -271.404376)
			(xy 373.983726 -271.379769) (xy 374.029742 -271.362317) (xy 374.077961 -271.352473) (xy 374.127136 -271.350492)
			(xy 374.175991 -271.356424) (xy 374.223262 -271.370116) (xy 374.267724 -271.391214) (xy 374.308227 -271.41917)
			(xy 374.34372 -271.453262) (xy 374.373285 -271.492606) (xy 374.396156 -271.536183) (xy 374.41174 -271.582864)
			(xy 374.419635 -271.631441) (xy 374.42013 -271.656048) (xy 374.419635 -271.680655) (xy 374.41174 -271.729232)
			(xy 374.396156 -271.775913) (xy 374.373285 -271.81949) (xy 374.34372 -271.858834) (xy 374.308227 -271.892926)
			(xy 374.267724 -271.920882) (xy 374.223262 -271.94198) (xy 374.175991 -271.955672) (xy 374.127136 -271.961604)
			(xy 374.077961 -271.959623) (xy 374.029742 -271.949779) (xy 373.983726 -271.932327) (xy 373.941105 -271.90772)
			(xy 373.902984 -271.876595) (xy 373.870349 -271.839758) (xy 373.844046 -271.798162) (xy 373.824755 -271.752886)
			(xy 373.812978 -271.705102) (xy 373.809018 -271.656048) (xy 373.480076 -271.656048) (xy 373.479581 -271.680655)
			(xy 373.471686 -271.729232) (xy 373.456102 -271.775913) (xy 373.433231 -271.81949) (xy 373.403666 -271.858834)
			(xy 373.368173 -271.892926) (xy 373.32767 -271.920882) (xy 373.283208 -271.94198) (xy 373.235937 -271.955672)
			(xy 373.187082 -271.961604) (xy 373.137907 -271.959623) (xy 373.089688 -271.949779) (xy 373.043672 -271.932327)
			(xy 373.001051 -271.90772) (xy 372.96293 -271.876595) (xy 372.930295 -271.839758) (xy 372.903992 -271.798162)
			(xy 372.884701 -271.752886) (xy 372.872924 -271.705102) (xy 372.868964 -271.656048) (xy 372.540022 -271.656048)
			(xy 372.539527 -271.680655) (xy 372.531632 -271.729232) (xy 372.516048 -271.775913) (xy 372.493177 -271.81949)
			(xy 372.463612 -271.858834) (xy 372.428119 -271.892926) (xy 372.387616 -271.920882) (xy 372.343154 -271.94198)
			(xy 372.295883 -271.955672) (xy 372.247028 -271.961604) (xy 372.197853 -271.959623) (xy 372.149634 -271.949779)
			(xy 372.103618 -271.932327) (xy 372.060997 -271.90772) (xy 372.022876 -271.876595) (xy 371.990241 -271.839758)
			(xy 371.963938 -271.798162) (xy 371.944647 -271.752886) (xy 371.93287 -271.705102) (xy 371.92891 -271.656048)
			(xy 371.600222 -271.656048) (xy 371.599727 -271.680655) (xy 371.591832 -271.729232) (xy 371.576248 -271.775913)
			(xy 371.553377 -271.81949) (xy 371.523812 -271.858834) (xy 371.488319 -271.892926) (xy 371.447816 -271.920882)
			(xy 371.403354 -271.94198) (xy 371.356083 -271.955672) (xy 371.307228 -271.961604) (xy 371.258053 -271.959623)
			(xy 371.209834 -271.949779) (xy 371.163818 -271.932327) (xy 371.121197 -271.90772) (xy 371.083076 -271.876595)
			(xy 371.050441 -271.839758) (xy 371.024138 -271.798162) (xy 371.004847 -271.752886) (xy 370.99307 -271.705102)
			(xy 370.98911 -271.656048) (xy 370.660168 -271.656048) (xy 370.659673 -271.680655) (xy 370.651778 -271.729232)
			(xy 370.636194 -271.775913) (xy 370.613323 -271.81949) (xy 370.583758 -271.858834) (xy 370.548265 -271.892926)
			(xy 370.507762 -271.920882) (xy 370.4633 -271.94198) (xy 370.416029 -271.955672) (xy 370.367174 -271.961604)
			(xy 370.317999 -271.959623) (xy 370.26978 -271.949779) (xy 370.223764 -271.932327) (xy 370.181143 -271.90772)
			(xy 370.143022 -271.876595) (xy 370.110387 -271.839758) (xy 370.084084 -271.798162) (xy 370.064793 -271.752886)
			(xy 370.053016 -271.705102) (xy 370.049056 -271.656048) (xy 369.720114 -271.656048) (xy 369.719619 -271.680655)
			(xy 369.711724 -271.729232) (xy 369.69614 -271.775913) (xy 369.673269 -271.81949) (xy 369.643704 -271.858834)
			(xy 369.608211 -271.892926) (xy 369.567708 -271.920882) (xy 369.523246 -271.94198) (xy 369.475975 -271.955672)
			(xy 369.42712 -271.961604) (xy 369.377945 -271.959623) (xy 369.329726 -271.949779) (xy 369.28371 -271.932327)
			(xy 369.241089 -271.90772) (xy 369.202968 -271.876595) (xy 369.170333 -271.839758) (xy 369.14403 -271.798162)
			(xy 369.124739 -271.752886) (xy 369.112962 -271.705102) (xy 369.109002 -271.656048) (xy 368.78006 -271.656048)
			(xy 368.779565 -271.680655) (xy 368.77167 -271.729232) (xy 368.756086 -271.775913) (xy 368.733215 -271.81949)
			(xy 368.70365 -271.858834) (xy 368.668157 -271.892926) (xy 368.627654 -271.920882) (xy 368.583192 -271.94198)
			(xy 368.535921 -271.955672) (xy 368.487066 -271.961604) (xy 368.437891 -271.959623) (xy 368.389672 -271.949779)
			(xy 368.343656 -271.932327) (xy 368.301035 -271.90772) (xy 368.262914 -271.876595) (xy 368.230279 -271.839758)
			(xy 368.203976 -271.798162) (xy 368.184685 -271.752886) (xy 368.172908 -271.705102) (xy 368.168948 -271.656048)
			(xy 367.840006 -271.656048) (xy 367.839511 -271.680655) (xy 367.831616 -271.729232) (xy 367.816032 -271.775913)
			(xy 367.793161 -271.81949) (xy 367.763596 -271.858834) (xy 367.728103 -271.892926) (xy 367.6876 -271.920882)
			(xy 367.643138 -271.94198) (xy 367.595867 -271.955672) (xy 367.547012 -271.961604) (xy 367.497837 -271.959623)
			(xy 367.449618 -271.949779) (xy 367.403602 -271.932327) (xy 367.360981 -271.90772) (xy 367.32286 -271.876595)
			(xy 367.290225 -271.839758) (xy 367.263922 -271.798162) (xy 367.244631 -271.752886) (xy 367.232854 -271.705102)
			(xy 367.228894 -271.656048) (xy 366.900206 -271.656048) (xy 366.899711 -271.680655) (xy 366.891816 -271.729232)
			(xy 366.876232 -271.775913) (xy 366.853361 -271.81949) (xy 366.823796 -271.858834) (xy 366.788303 -271.892926)
			(xy 366.7478 -271.920882) (xy 366.703338 -271.94198) (xy 366.656067 -271.955672) (xy 366.607212 -271.961604)
			(xy 366.558037 -271.959623) (xy 366.509818 -271.949779) (xy 366.463802 -271.932327) (xy 366.421181 -271.90772)
			(xy 366.38306 -271.876595) (xy 366.350425 -271.839758) (xy 366.324122 -271.798162) (xy 366.304831 -271.752886)
			(xy 366.293054 -271.705102) (xy 366.289094 -271.656048) (xy 365.960152 -271.656048) (xy 365.959657 -271.680655)
			(xy 365.951762 -271.729232) (xy 365.936178 -271.775913) (xy 365.913307 -271.81949) (xy 365.883742 -271.858834)
			(xy 365.848249 -271.892926) (xy 365.807746 -271.920882) (xy 365.763284 -271.94198) (xy 365.716013 -271.955672)
			(xy 365.667158 -271.961604) (xy 365.617983 -271.959623) (xy 365.569764 -271.949779) (xy 365.523748 -271.932327)
			(xy 365.481127 -271.90772) (xy 365.443006 -271.876595) (xy 365.410371 -271.839758) (xy 365.384068 -271.798162)
			(xy 365.364777 -271.752886) (xy 365.353 -271.705102) (xy 365.34904 -271.656048) (xy 365.020098 -271.656048)
			(xy 365.019603 -271.680655) (xy 365.011708 -271.729232) (xy 364.996124 -271.775913) (xy 364.973253 -271.81949)
			(xy 364.943688 -271.858834) (xy 364.908195 -271.892926) (xy 364.867692 -271.920882) (xy 364.82323 -271.94198)
			(xy 364.775959 -271.955672) (xy 364.727104 -271.961604) (xy 364.677929 -271.959623) (xy 364.62971 -271.949779)
			(xy 364.583694 -271.932327) (xy 364.541073 -271.90772) (xy 364.502952 -271.876595) (xy 364.470317 -271.839758)
			(xy 364.444014 -271.798162) (xy 364.424723 -271.752886) (xy 364.412946 -271.705102) (xy 364.408986 -271.656048)
			(xy 364.080044 -271.656048) (xy 364.079549 -271.680655) (xy 364.071654 -271.729232) (xy 364.05607 -271.775913)
			(xy 364.033199 -271.81949) (xy 364.003634 -271.858834) (xy 363.968141 -271.892926) (xy 363.927638 -271.920882)
			(xy 363.883176 -271.94198) (xy 363.835905 -271.955672) (xy 363.78705 -271.961604) (xy 363.737875 -271.959623)
			(xy 363.689656 -271.949779) (xy 363.64364 -271.932327) (xy 363.601019 -271.90772) (xy 363.562898 -271.876595)
			(xy 363.530263 -271.839758) (xy 363.50396 -271.798162) (xy 363.484669 -271.752886) (xy 363.472892 -271.705102)
			(xy 363.468932 -271.656048) (xy 356.56647 -271.656048) (xy 356.565975 -271.680655) (xy 356.55808 -271.729232)
			(xy 356.542496 -271.775913) (xy 356.519625 -271.81949) (xy 356.49006 -271.858834) (xy 356.454567 -271.892926)
			(xy 356.414064 -271.920882) (xy 356.369602 -271.94198) (xy 356.322331 -271.955672) (xy 356.273476 -271.961604)
			(xy 356.224301 -271.959623) (xy 356.176082 -271.949779) (xy 356.130066 -271.932327) (xy 356.087445 -271.90772)
			(xy 356.049324 -271.876595) (xy 356.016689 -271.839758) (xy 355.990386 -271.798162) (xy 355.971095 -271.752886)
			(xy 355.959318 -271.705102) (xy 355.955358 -271.656048) (xy 355.626416 -271.656048) (xy 355.625921 -271.680655)
			(xy 355.618026 -271.729232) (xy 355.602442 -271.775913) (xy 355.579571 -271.81949) (xy 355.550006 -271.858834)
			(xy 355.514513 -271.892926) (xy 355.47401 -271.920882) (xy 355.429548 -271.94198) (xy 355.382277 -271.955672)
			(xy 355.333422 -271.961604) (xy 355.284247 -271.959623) (xy 355.236028 -271.949779) (xy 355.190012 -271.932327)
			(xy 355.147391 -271.90772) (xy 355.10927 -271.876595) (xy 355.076635 -271.839758) (xy 355.050332 -271.798162)
			(xy 355.031041 -271.752886) (xy 355.019264 -271.705102) (xy 355.015304 -271.656048) (xy 354.686362 -271.656048)
			(xy 354.685867 -271.680655) (xy 354.677972 -271.729232) (xy 354.662388 -271.775913) (xy 354.639517 -271.81949)
			(xy 354.609952 -271.858834) (xy 354.574459 -271.892926) (xy 354.533956 -271.920882) (xy 354.489494 -271.94198)
			(xy 354.442223 -271.955672) (xy 354.393368 -271.961604) (xy 354.344193 -271.959623) (xy 354.295974 -271.949779)
			(xy 354.249958 -271.932327) (xy 354.207337 -271.90772) (xy 354.169216 -271.876595) (xy 354.136581 -271.839758)
			(xy 354.110278 -271.798162) (xy 354.090987 -271.752886) (xy 354.07921 -271.705102) (xy 354.07525 -271.656048)
			(xy 353.746308 -271.656048) (xy 353.745813 -271.680655) (xy 353.737918 -271.729232) (xy 353.722334 -271.775913)
			(xy 353.699463 -271.81949) (xy 353.669898 -271.858834) (xy 353.634405 -271.892926) (xy 353.593902 -271.920882)
			(xy 353.54944 -271.94198) (xy 353.502169 -271.955672) (xy 353.453314 -271.961604) (xy 353.404139 -271.959623)
			(xy 353.35592 -271.949779) (xy 353.309904 -271.932327) (xy 353.267283 -271.90772) (xy 353.229162 -271.876595)
			(xy 353.196527 -271.839758) (xy 353.170224 -271.798162) (xy 353.150933 -271.752886) (xy 353.139156 -271.705102)
			(xy 353.135196 -271.656048) (xy 352.806508 -271.656048) (xy 352.806013 -271.680655) (xy 352.798118 -271.729232)
			(xy 352.782534 -271.775913) (xy 352.759663 -271.81949) (xy 352.730098 -271.858834) (xy 352.694605 -271.892926)
			(xy 352.654102 -271.920882) (xy 352.60964 -271.94198) (xy 352.562369 -271.955672) (xy 352.513514 -271.961604)
			(xy 352.464339 -271.959623) (xy 352.41612 -271.949779) (xy 352.370104 -271.932327) (xy 352.327483 -271.90772)
			(xy 352.289362 -271.876595) (xy 352.256727 -271.839758) (xy 352.230424 -271.798162) (xy 352.211133 -271.752886)
			(xy 352.199356 -271.705102) (xy 352.195396 -271.656048) (xy 351.866454 -271.656048) (xy 351.865959 -271.680655)
			(xy 351.858064 -271.729232) (xy 351.84248 -271.775913) (xy 351.819609 -271.81949) (xy 351.790044 -271.858834)
			(xy 351.754551 -271.892926) (xy 351.714048 -271.920882) (xy 351.669586 -271.94198) (xy 351.622315 -271.955672)
			(xy 351.57346 -271.961604) (xy 351.524285 -271.959623) (xy 351.476066 -271.949779) (xy 351.43005 -271.932327)
			(xy 351.387429 -271.90772) (xy 351.349308 -271.876595) (xy 351.316673 -271.839758) (xy 351.29037 -271.798162)
			(xy 351.271079 -271.752886) (xy 351.259302 -271.705102) (xy 351.255342 -271.656048) (xy 350.9264 -271.656048)
			(xy 350.925905 -271.680655) (xy 350.91801 -271.729232) (xy 350.902426 -271.775913) (xy 350.879555 -271.81949)
			(xy 350.84999 -271.858834) (xy 350.814497 -271.892926) (xy 350.773994 -271.920882) (xy 350.729532 -271.94198)
			(xy 350.682261 -271.955672) (xy 350.633406 -271.961604) (xy 350.584231 -271.959623) (xy 350.536012 -271.949779)
			(xy 350.489996 -271.932327) (xy 350.447375 -271.90772) (xy 350.409254 -271.876595) (xy 350.376619 -271.839758)
			(xy 350.350316 -271.798162) (xy 350.331025 -271.752886) (xy 350.319248 -271.705102) (xy 350.315288 -271.656048)
			(xy 349.986346 -271.656048) (xy 349.985851 -271.680655) (xy 349.977956 -271.729232) (xy 349.962372 -271.775913)
			(xy 349.939501 -271.81949) (xy 349.909936 -271.858834) (xy 349.874443 -271.892926) (xy 349.83394 -271.920882)
			(xy 349.789478 -271.94198) (xy 349.742207 -271.955672) (xy 349.693352 -271.961604) (xy 349.644177 -271.959623)
			(xy 349.595958 -271.949779) (xy 349.549942 -271.932327) (xy 349.507321 -271.90772) (xy 349.4692 -271.876595)
			(xy 349.436565 -271.839758) (xy 349.410262 -271.798162) (xy 349.390971 -271.752886) (xy 349.379194 -271.705102)
			(xy 349.375234 -271.656048) (xy 349.046546 -271.656048) (xy 349.046051 -271.680655) (xy 349.038156 -271.729232)
			(xy 349.022572 -271.775913) (xy 348.999701 -271.81949) (xy 348.970136 -271.858834) (xy 348.934643 -271.892926)
			(xy 348.89414 -271.920882) (xy 348.849678 -271.94198) (xy 348.802407 -271.955672) (xy 348.753552 -271.961604)
			(xy 348.704377 -271.959623) (xy 348.656158 -271.949779) (xy 348.610142 -271.932327) (xy 348.567521 -271.90772)
			(xy 348.5294 -271.876595) (xy 348.496765 -271.839758) (xy 348.470462 -271.798162) (xy 348.451171 -271.752886)
			(xy 348.439394 -271.705102) (xy 348.435434 -271.656048) (xy 348.106492 -271.656048) (xy 348.105997 -271.680655)
			(xy 348.098102 -271.729232) (xy 348.082518 -271.775913) (xy 348.059647 -271.81949) (xy 348.030082 -271.858834)
			(xy 347.994589 -271.892926) (xy 347.954086 -271.920882) (xy 347.909624 -271.94198) (xy 347.862353 -271.955672)
			(xy 347.813498 -271.961604) (xy 347.764323 -271.959623) (xy 347.716104 -271.949779) (xy 347.670088 -271.932327)
			(xy 347.627467 -271.90772) (xy 347.589346 -271.876595) (xy 347.556711 -271.839758) (xy 347.530408 -271.798162)
			(xy 347.511117 -271.752886) (xy 347.49934 -271.705102) (xy 347.49538 -271.656048) (xy 347.166438 -271.656048)
			(xy 347.165943 -271.680655) (xy 347.158048 -271.729232) (xy 347.142464 -271.775913) (xy 347.119593 -271.81949)
			(xy 347.090028 -271.858834) (xy 347.054535 -271.892926) (xy 347.014032 -271.920882) (xy 346.96957 -271.94198)
			(xy 346.922299 -271.955672) (xy 346.873444 -271.961604) (xy 346.824269 -271.959623) (xy 346.77605 -271.949779)
			(xy 346.730034 -271.932327) (xy 346.687413 -271.90772) (xy 346.649292 -271.876595) (xy 346.616657 -271.839758)
			(xy 346.590354 -271.798162) (xy 346.571063 -271.752886) (xy 346.559286 -271.705102) (xy 346.555326 -271.656048)
			(xy 346.226384 -271.656048) (xy 346.225889 -271.680655) (xy 346.217994 -271.729232) (xy 346.20241 -271.775913)
			(xy 346.179539 -271.81949) (xy 346.149974 -271.858834) (xy 346.114481 -271.892926) (xy 346.073978 -271.920882)
			(xy 346.029516 -271.94198) (xy 345.982245 -271.955672) (xy 345.93339 -271.961604) (xy 345.884215 -271.959623)
			(xy 345.835996 -271.949779) (xy 345.78998 -271.932327) (xy 345.747359 -271.90772) (xy 345.709238 -271.876595)
			(xy 345.676603 -271.839758) (xy 345.6503 -271.798162) (xy 345.631009 -271.752886) (xy 345.619232 -271.705102)
			(xy 345.615272 -271.656048) (xy 345.286735 -271.656048) (xy 345.282741 -271.705278) (xy 345.270858 -271.753251)
			(xy 345.251402 -271.798683) (xy 345.224879 -271.840387) (xy 345.191984 -271.877272) (xy 345.153575 -271.908376)
			(xy 345.110657 -271.932884) (xy 345.087702 -271.942052) (xy 345.087194 -271.942306) (xy 345.07762 -271.946335)
			(xy 345.062556 -271.960606) (xy 345.054386 -271.979681) (xy 345.05392 -271.990058) (xy 345.05392 -272.466054)
			(xy 347.025226 -272.466054) (xy 347.029186 -272.417) (xy 347.040963 -272.369216) (xy 347.060254 -272.32394)
			(xy 347.086557 -272.282344) (xy 347.119192 -272.245507) (xy 347.157313 -272.214382) (xy 347.199934 -272.189775)
			(xy 347.24595 -272.172323) (xy 347.294169 -272.162479) (xy 347.343344 -272.160498) (xy 347.392199 -272.16643)
			(xy 347.43947 -272.180122) (xy 347.483932 -272.20122) (xy 347.524435 -272.229176) (xy 347.559928 -272.263268)
			(xy 347.589493 -272.302612) (xy 347.612364 -272.346189) (xy 347.627948 -272.39287) (xy 347.635843 -272.441447)
			(xy 347.636338 -272.466054) (xy 349.845388 -272.466054) (xy 349.849348 -272.417) (xy 349.861125 -272.369216)
			(xy 349.880416 -272.32394) (xy 349.906719 -272.282344) (xy 349.939354 -272.245507) (xy 349.977475 -272.214382)
			(xy 350.020096 -272.189775) (xy 350.066112 -272.172323) (xy 350.114331 -272.162479) (xy 350.163506 -272.160498)
			(xy 350.212361 -272.16643) (xy 350.259632 -272.180122) (xy 350.304094 -272.20122) (xy 350.344597 -272.229176)
			(xy 350.38009 -272.263268) (xy 350.409655 -272.302612) (xy 350.432526 -272.346189) (xy 350.44811 -272.39287)
			(xy 350.456005 -272.441447) (xy 350.4565 -272.466054) (xy 352.665296 -272.466054) (xy 352.669256 -272.417)
			(xy 352.681033 -272.369216) (xy 352.700324 -272.32394) (xy 352.726627 -272.282344) (xy 352.759262 -272.245507)
			(xy 352.797383 -272.214382) (xy 352.840004 -272.189775) (xy 352.88602 -272.172323) (xy 352.934239 -272.162479)
			(xy 352.983414 -272.160498) (xy 353.032269 -272.16643) (xy 353.07954 -272.180122) (xy 353.124002 -272.20122)
			(xy 353.164505 -272.229176) (xy 353.199998 -272.263268) (xy 353.229563 -272.302612) (xy 353.252434 -272.346189)
			(xy 353.268018 -272.39287) (xy 353.275913 -272.441447) (xy 353.276408 -272.466054) (xy 355.485204 -272.466054)
			(xy 355.489164 -272.417) (xy 355.500941 -272.369216) (xy 355.520232 -272.32394) (xy 355.546535 -272.282344)
			(xy 355.57917 -272.245507) (xy 355.617291 -272.214382) (xy 355.659912 -272.189775) (xy 355.705928 -272.172323)
			(xy 355.754147 -272.162479) (xy 355.803322 -272.160498) (xy 355.852177 -272.16643) (xy 355.899448 -272.180122)
			(xy 355.94391 -272.20122) (xy 355.984413 -272.229176) (xy 356.019906 -272.263268) (xy 356.049471 -272.302612)
			(xy 356.072342 -272.346189) (xy 356.087926 -272.39287) (xy 356.095821 -272.441447) (xy 356.096316 -272.466054)
			(xy 356.425258 -272.466054) (xy 356.429218 -272.417) (xy 356.440995 -272.369216) (xy 356.460286 -272.32394)
			(xy 356.486589 -272.282344) (xy 356.519224 -272.245507) (xy 356.557345 -272.214382) (xy 356.599966 -272.189775)
			(xy 356.645982 -272.172323) (xy 356.694201 -272.162479) (xy 356.743376 -272.160498) (xy 356.792231 -272.16643)
			(xy 356.839502 -272.180122) (xy 356.883964 -272.20122) (xy 356.924467 -272.229176) (xy 356.95996 -272.263268)
			(xy 356.989525 -272.302612) (xy 357.012396 -272.346189) (xy 357.02798 -272.39287) (xy 357.035875 -272.441447)
			(xy 357.03637 -272.466054) (xy 357.365312 -272.466054) (xy 357.369272 -272.417) (xy 357.381049 -272.369216)
			(xy 357.40034 -272.32394) (xy 357.426643 -272.282344) (xy 357.459278 -272.245507) (xy 357.497399 -272.214382)
			(xy 357.54002 -272.189775) (xy 357.586036 -272.172323) (xy 357.634255 -272.162479) (xy 357.68343 -272.160498)
			(xy 357.732285 -272.16643) (xy 357.779556 -272.180122) (xy 357.824018 -272.20122) (xy 357.864521 -272.229176)
			(xy 357.900014 -272.263268) (xy 357.929579 -272.302612) (xy 357.95245 -272.346189) (xy 357.968034 -272.39287)
			(xy 357.975929 -272.441447) (xy 357.976424 -272.466054) (xy 358.305366 -272.466054) (xy 358.309326 -272.417)
			(xy 358.321103 -272.369216) (xy 358.340394 -272.32394) (xy 358.366697 -272.282344) (xy 358.399332 -272.245507)
			(xy 358.437453 -272.214382) (xy 358.480074 -272.189775) (xy 358.52609 -272.172323) (xy 358.574309 -272.162479)
			(xy 358.623484 -272.160498) (xy 358.672339 -272.16643) (xy 358.71961 -272.180122) (xy 358.764072 -272.20122)
			(xy 358.804575 -272.229176) (xy 358.840068 -272.263268) (xy 358.869633 -272.302612) (xy 358.892504 -272.346189)
			(xy 358.908088 -272.39287) (xy 358.915983 -272.441447) (xy 358.916478 -272.466054) (xy 361.118924 -272.466054)
			(xy 361.122884 -272.417) (xy 361.134661 -272.369216) (xy 361.153952 -272.32394) (xy 361.180255 -272.282344)
			(xy 361.21289 -272.245507) (xy 361.251011 -272.214382) (xy 361.293632 -272.189775) (xy 361.339648 -272.172323)
			(xy 361.387867 -272.162479) (xy 361.437042 -272.160498) (xy 361.485897 -272.16643) (xy 361.533168 -272.180122)
			(xy 361.57763 -272.20122) (xy 361.618133 -272.229176) (xy 361.653626 -272.263268) (xy 361.683191 -272.302612)
			(xy 361.706062 -272.346189) (xy 361.721646 -272.39287) (xy 361.729541 -272.441447) (xy 361.730036 -272.466054)
			(xy 362.058978 -272.466054) (xy 362.062938 -272.417) (xy 362.074715 -272.369216) (xy 362.094006 -272.32394)
			(xy 362.120309 -272.282344) (xy 362.152944 -272.245507) (xy 362.191065 -272.214382) (xy 362.233686 -272.189775)
			(xy 362.279702 -272.172323) (xy 362.327921 -272.162479) (xy 362.377096 -272.160498) (xy 362.425951 -272.16643)
			(xy 362.473222 -272.180122) (xy 362.517684 -272.20122) (xy 362.558187 -272.229176) (xy 362.59368 -272.263268)
			(xy 362.623245 -272.302612) (xy 362.646116 -272.346189) (xy 362.6617 -272.39287) (xy 362.669595 -272.441447)
			(xy 362.67009 -272.466054) (xy 362.999032 -272.466054) (xy 363.002992 -272.417) (xy 363.014769 -272.369216)
			(xy 363.03406 -272.32394) (xy 363.060363 -272.282344) (xy 363.092998 -272.245507) (xy 363.131119 -272.214382)
			(xy 363.17374 -272.189775) (xy 363.219756 -272.172323) (xy 363.267975 -272.162479) (xy 363.31715 -272.160498)
			(xy 363.366005 -272.16643) (xy 363.413276 -272.180122) (xy 363.457738 -272.20122) (xy 363.498241 -272.229176)
			(xy 363.533734 -272.263268) (xy 363.563299 -272.302612) (xy 363.58617 -272.346189) (xy 363.601754 -272.39287)
			(xy 363.609649 -272.441447) (xy 363.610144 -272.466054) (xy 363.939086 -272.466054) (xy 363.943046 -272.417)
			(xy 363.954823 -272.369216) (xy 363.974114 -272.32394) (xy 364.000417 -272.282344) (xy 364.033052 -272.245507)
			(xy 364.071173 -272.214382) (xy 364.113794 -272.189775) (xy 364.15981 -272.172323) (xy 364.208029 -272.162479)
			(xy 364.257204 -272.160498) (xy 364.306059 -272.16643) (xy 364.35333 -272.180122) (xy 364.397792 -272.20122)
			(xy 364.438295 -272.229176) (xy 364.473788 -272.263268) (xy 364.503353 -272.302612) (xy 364.526224 -272.346189)
			(xy 364.541808 -272.39287) (xy 364.549703 -272.441447) (xy 364.550198 -272.466054) (xy 366.758994 -272.466054)
			(xy 366.762954 -272.417) (xy 366.774731 -272.369216) (xy 366.794022 -272.32394) (xy 366.820325 -272.282344)
			(xy 366.85296 -272.245507) (xy 366.891081 -272.214382) (xy 366.933702 -272.189775) (xy 366.979718 -272.172323)
			(xy 367.027937 -272.162479) (xy 367.077112 -272.160498) (xy 367.125967 -272.16643) (xy 367.173238 -272.180122)
			(xy 367.2177 -272.20122) (xy 367.258203 -272.229176) (xy 367.293696 -272.263268) (xy 367.323261 -272.302612)
			(xy 367.346132 -272.346189) (xy 367.361716 -272.39287) (xy 367.369611 -272.441447) (xy 367.370106 -272.466054)
			(xy 369.578902 -272.466054) (xy 369.582862 -272.417) (xy 369.594639 -272.369216) (xy 369.61393 -272.32394)
			(xy 369.640233 -272.282344) (xy 369.672868 -272.245507) (xy 369.710989 -272.214382) (xy 369.75361 -272.189775)
			(xy 369.799626 -272.172323) (xy 369.847845 -272.162479) (xy 369.89702 -272.160498) (xy 369.945875 -272.16643)
			(xy 369.993146 -272.180122) (xy 370.037608 -272.20122) (xy 370.078111 -272.229176) (xy 370.113604 -272.263268)
			(xy 370.143169 -272.302612) (xy 370.16604 -272.346189) (xy 370.181624 -272.39287) (xy 370.189519 -272.441447)
			(xy 370.190014 -272.466054) (xy 372.399064 -272.466054) (xy 372.403024 -272.417) (xy 372.414801 -272.369216)
			(xy 372.434092 -272.32394) (xy 372.460395 -272.282344) (xy 372.49303 -272.245507) (xy 372.531151 -272.214382)
			(xy 372.573772 -272.189775) (xy 372.619788 -272.172323) (xy 372.668007 -272.162479) (xy 372.717182 -272.160498)
			(xy 372.766037 -272.16643) (xy 372.813308 -272.180122) (xy 372.85777 -272.20122) (xy 372.898273 -272.229176)
			(xy 372.933766 -272.263268) (xy 372.963331 -272.302612) (xy 372.986202 -272.346189) (xy 373.001786 -272.39287)
			(xy 373.009681 -272.441447) (xy 373.010176 -272.466054) (xy 373.009681 -272.490661) (xy 373.001786 -272.539238)
			(xy 372.986202 -272.585919) (xy 372.963331 -272.629496) (xy 372.933766 -272.66884) (xy 372.898273 -272.702932)
			(xy 372.85777 -272.730888) (xy 372.813308 -272.751986) (xy 372.766037 -272.765678) (xy 372.717182 -272.77161)
			(xy 372.668007 -272.769629) (xy 372.619788 -272.759785) (xy 372.573772 -272.742333) (xy 372.531151 -272.717726)
			(xy 372.49303 -272.686601) (xy 372.460395 -272.649764) (xy 372.434092 -272.608168) (xy 372.414801 -272.562892)
			(xy 372.403024 -272.515108) (xy 372.399064 -272.466054) (xy 370.190014 -272.466054) (xy 370.189519 -272.490661)
			(xy 370.181624 -272.539238) (xy 370.16604 -272.585919) (xy 370.143169 -272.629496) (xy 370.113604 -272.66884)
			(xy 370.078111 -272.702932) (xy 370.037608 -272.730888) (xy 369.993146 -272.751986) (xy 369.945875 -272.765678)
			(xy 369.89702 -272.77161) (xy 369.847845 -272.769629) (xy 369.799626 -272.759785) (xy 369.75361 -272.742333)
			(xy 369.710989 -272.717726) (xy 369.672868 -272.686601) (xy 369.640233 -272.649764) (xy 369.61393 -272.608168)
			(xy 369.594639 -272.562892) (xy 369.582862 -272.515108) (xy 369.578902 -272.466054) (xy 367.370106 -272.466054)
			(xy 367.369611 -272.490661) (xy 367.361716 -272.539238) (xy 367.346132 -272.585919) (xy 367.323261 -272.629496)
			(xy 367.293696 -272.66884) (xy 367.258203 -272.702932) (xy 367.2177 -272.730888) (xy 367.173238 -272.751986)
			(xy 367.125967 -272.765678) (xy 367.077112 -272.77161) (xy 367.027937 -272.769629) (xy 366.979718 -272.759785)
			(xy 366.933702 -272.742333) (xy 366.891081 -272.717726) (xy 366.85296 -272.686601) (xy 366.820325 -272.649764)
			(xy 366.794022 -272.608168) (xy 366.774731 -272.562892) (xy 366.762954 -272.515108) (xy 366.758994 -272.466054)
			(xy 364.550198 -272.466054) (xy 364.549703 -272.490661) (xy 364.541808 -272.539238) (xy 364.526224 -272.585919)
			(xy 364.503353 -272.629496) (xy 364.473788 -272.66884) (xy 364.438295 -272.702932) (xy 364.397792 -272.730888)
			(xy 364.35333 -272.751986) (xy 364.306059 -272.765678) (xy 364.257204 -272.77161) (xy 364.208029 -272.769629)
			(xy 364.15981 -272.759785) (xy 364.113794 -272.742333) (xy 364.071173 -272.717726) (xy 364.033052 -272.686601)
			(xy 364.000417 -272.649764) (xy 363.974114 -272.608168) (xy 363.954823 -272.562892) (xy 363.943046 -272.515108)
			(xy 363.939086 -272.466054) (xy 363.610144 -272.466054) (xy 363.609649 -272.490661) (xy 363.601754 -272.539238)
			(xy 363.58617 -272.585919) (xy 363.563299 -272.629496) (xy 363.533734 -272.66884) (xy 363.498241 -272.702932)
			(xy 363.457738 -272.730888) (xy 363.413276 -272.751986) (xy 363.366005 -272.765678) (xy 363.31715 -272.77161)
			(xy 363.267975 -272.769629) (xy 363.219756 -272.759785) (xy 363.17374 -272.742333) (xy 363.131119 -272.717726)
			(xy 363.092998 -272.686601) (xy 363.060363 -272.649764) (xy 363.03406 -272.608168) (xy 363.014769 -272.562892)
			(xy 363.002992 -272.515108) (xy 362.999032 -272.466054) (xy 362.67009 -272.466054) (xy 362.669595 -272.490661)
			(xy 362.6617 -272.539238) (xy 362.646116 -272.585919) (xy 362.623245 -272.629496) (xy 362.59368 -272.66884)
			(xy 362.558187 -272.702932) (xy 362.517684 -272.730888) (xy 362.473222 -272.751986) (xy 362.425951 -272.765678)
			(xy 362.377096 -272.77161) (xy 362.327921 -272.769629) (xy 362.279702 -272.759785) (xy 362.233686 -272.742333)
			(xy 362.191065 -272.717726) (xy 362.152944 -272.686601) (xy 362.120309 -272.649764) (xy 362.094006 -272.608168)
			(xy 362.074715 -272.562892) (xy 362.062938 -272.515108) (xy 362.058978 -272.466054) (xy 361.730036 -272.466054)
			(xy 361.729541 -272.490661) (xy 361.721646 -272.539238) (xy 361.706062 -272.585919) (xy 361.683191 -272.629496)
			(xy 361.653626 -272.66884) (xy 361.618133 -272.702932) (xy 361.57763 -272.730888) (xy 361.533168 -272.751986)
			(xy 361.485897 -272.765678) (xy 361.437042 -272.77161) (xy 361.387867 -272.769629) (xy 361.339648 -272.759785)
			(xy 361.293632 -272.742333) (xy 361.251011 -272.717726) (xy 361.21289 -272.686601) (xy 361.180255 -272.649764)
			(xy 361.153952 -272.608168) (xy 361.134661 -272.562892) (xy 361.122884 -272.515108) (xy 361.118924 -272.466054)
			(xy 358.916478 -272.466054) (xy 358.915983 -272.490661) (xy 358.908088 -272.539238) (xy 358.892504 -272.585919)
			(xy 358.869633 -272.629496) (xy 358.840068 -272.66884) (xy 358.804575 -272.702932) (xy 358.764072 -272.730888)
			(xy 358.71961 -272.751986) (xy 358.672339 -272.765678) (xy 358.623484 -272.77161) (xy 358.574309 -272.769629)
			(xy 358.52609 -272.759785) (xy 358.480074 -272.742333) (xy 358.437453 -272.717726) (xy 358.399332 -272.686601)
			(xy 358.366697 -272.649764) (xy 358.340394 -272.608168) (xy 358.321103 -272.562892) (xy 358.309326 -272.515108)
			(xy 358.305366 -272.466054) (xy 357.976424 -272.466054) (xy 357.975929 -272.490661) (xy 357.968034 -272.539238)
			(xy 357.95245 -272.585919) (xy 357.929579 -272.629496) (xy 357.900014 -272.66884) (xy 357.864521 -272.702932)
			(xy 357.824018 -272.730888) (xy 357.779556 -272.751986) (xy 357.732285 -272.765678) (xy 357.68343 -272.77161)
			(xy 357.634255 -272.769629) (xy 357.586036 -272.759785) (xy 357.54002 -272.742333) (xy 357.497399 -272.717726)
			(xy 357.459278 -272.686601) (xy 357.426643 -272.649764) (xy 357.40034 -272.608168) (xy 357.381049 -272.562892)
			(xy 357.369272 -272.515108) (xy 357.365312 -272.466054) (xy 357.03637 -272.466054) (xy 357.035875 -272.490661)
			(xy 357.02798 -272.539238) (xy 357.012396 -272.585919) (xy 356.989525 -272.629496) (xy 356.95996 -272.66884)
			(xy 356.924467 -272.702932) (xy 356.883964 -272.730888) (xy 356.839502 -272.751986) (xy 356.792231 -272.765678)
			(xy 356.743376 -272.77161) (xy 356.694201 -272.769629) (xy 356.645982 -272.759785) (xy 356.599966 -272.742333)
			(xy 356.557345 -272.717726) (xy 356.519224 -272.686601) (xy 356.486589 -272.649764) (xy 356.460286 -272.608168)
			(xy 356.440995 -272.562892) (xy 356.429218 -272.515108) (xy 356.425258 -272.466054) (xy 356.096316 -272.466054)
			(xy 356.095821 -272.490661) (xy 356.087926 -272.539238) (xy 356.072342 -272.585919) (xy 356.049471 -272.629496)
			(xy 356.019906 -272.66884) (xy 355.984413 -272.702932) (xy 355.94391 -272.730888) (xy 355.899448 -272.751986)
			(xy 355.852177 -272.765678) (xy 355.803322 -272.77161) (xy 355.754147 -272.769629) (xy 355.705928 -272.759785)
			(xy 355.659912 -272.742333) (xy 355.617291 -272.717726) (xy 355.57917 -272.686601) (xy 355.546535 -272.649764)
			(xy 355.520232 -272.608168) (xy 355.500941 -272.562892) (xy 355.489164 -272.515108) (xy 355.485204 -272.466054)
			(xy 353.276408 -272.466054) (xy 353.275913 -272.490661) (xy 353.268018 -272.539238) (xy 353.252434 -272.585919)
			(xy 353.229563 -272.629496) (xy 353.199998 -272.66884) (xy 353.164505 -272.702932) (xy 353.124002 -272.730888)
			(xy 353.07954 -272.751986) (xy 353.032269 -272.765678) (xy 352.983414 -272.77161) (xy 352.934239 -272.769629)
			(xy 352.88602 -272.759785) (xy 352.840004 -272.742333) (xy 352.797383 -272.717726) (xy 352.759262 -272.686601)
			(xy 352.726627 -272.649764) (xy 352.700324 -272.608168) (xy 352.681033 -272.562892) (xy 352.669256 -272.515108)
			(xy 352.665296 -272.466054) (xy 350.4565 -272.466054) (xy 350.456005 -272.490661) (xy 350.44811 -272.539238)
			(xy 350.432526 -272.585919) (xy 350.409655 -272.629496) (xy 350.38009 -272.66884) (xy 350.344597 -272.702932)
			(xy 350.304094 -272.730888) (xy 350.259632 -272.751986) (xy 350.212361 -272.765678) (xy 350.163506 -272.77161)
			(xy 350.114331 -272.769629) (xy 350.066112 -272.759785) (xy 350.020096 -272.742333) (xy 349.977475 -272.717726)
			(xy 349.939354 -272.686601) (xy 349.906719 -272.649764) (xy 349.880416 -272.608168) (xy 349.861125 -272.562892)
			(xy 349.849348 -272.515108) (xy 349.845388 -272.466054) (xy 347.636338 -272.466054) (xy 347.635843 -272.490661)
			(xy 347.627948 -272.539238) (xy 347.612364 -272.585919) (xy 347.589493 -272.629496) (xy 347.559928 -272.66884)
			(xy 347.524435 -272.702932) (xy 347.483932 -272.730888) (xy 347.43947 -272.751986) (xy 347.392199 -272.765678)
			(xy 347.343344 -272.77161) (xy 347.294169 -272.769629) (xy 347.24595 -272.759785) (xy 347.199934 -272.742333)
			(xy 347.157313 -272.717726) (xy 347.119192 -272.686601) (xy 347.086557 -272.649764) (xy 347.060254 -272.608168)
			(xy 347.040963 -272.562892) (xy 347.029186 -272.515108) (xy 347.025226 -272.466054) (xy 345.05392 -272.466054)
			(xy 345.05392 -272.94205) (xy 345.054414 -272.952418) (xy 345.062604 -272.971469) (xy 345.077638 -272.985751)
			(xy 345.087194 -272.989802) (xy 345.087702 -272.990056) (xy 345.110694 -272.999143) (xy 345.153624 -273.023658)
			(xy 345.192043 -273.05477) (xy 345.224947 -273.091665) (xy 345.251476 -273.133381) (xy 345.270937 -273.178825)
			(xy 345.282822 -273.226812) (xy 345.286818 -273.27606) (xy 345.615272 -273.27606) (xy 345.619232 -273.227006)
			(xy 345.631009 -273.179222) (xy 345.6503 -273.133946) (xy 345.676603 -273.09235) (xy 345.709238 -273.055513)
			(xy 345.747359 -273.024388) (xy 345.78998 -272.999781) (xy 345.835996 -272.982329) (xy 345.884215 -272.972485)
			(xy 345.93339 -272.970504) (xy 345.982245 -272.976436) (xy 346.029516 -272.990128) (xy 346.073978 -273.011226)
			(xy 346.114481 -273.039182) (xy 346.149974 -273.073274) (xy 346.179539 -273.112618) (xy 346.20241 -273.156195)
			(xy 346.217994 -273.202876) (xy 346.225889 -273.251453) (xy 346.226384 -273.27606) (xy 346.555326 -273.27606)
			(xy 346.559286 -273.227006) (xy 346.571063 -273.179222) (xy 346.590354 -273.133946) (xy 346.616657 -273.09235)
			(xy 346.649292 -273.055513) (xy 346.687413 -273.024388) (xy 346.730034 -272.999781) (xy 346.77605 -272.982329)
			(xy 346.824269 -272.972485) (xy 346.873444 -272.970504) (xy 346.922299 -272.976436) (xy 346.96957 -272.990128)
			(xy 347.014032 -273.011226) (xy 347.054535 -273.039182) (xy 347.090028 -273.073274) (xy 347.119593 -273.112618)
			(xy 347.142464 -273.156195) (xy 347.158048 -273.202876) (xy 347.165943 -273.251453) (xy 347.166438 -273.27606)
			(xy 347.49538 -273.27606) (xy 347.49934 -273.227006) (xy 347.511117 -273.179222) (xy 347.530408 -273.133946)
			(xy 347.556711 -273.09235) (xy 347.589346 -273.055513) (xy 347.627467 -273.024388) (xy 347.670088 -272.999781)
			(xy 347.716104 -272.982329) (xy 347.764323 -272.972485) (xy 347.813498 -272.970504) (xy 347.862353 -272.976436)
			(xy 347.909624 -272.990128) (xy 347.954086 -273.011226) (xy 347.994589 -273.039182) (xy 348.030082 -273.073274)
			(xy 348.059647 -273.112618) (xy 348.082518 -273.156195) (xy 348.098102 -273.202876) (xy 348.105997 -273.251453)
			(xy 348.106492 -273.27606) (xy 348.435434 -273.27606) (xy 348.439394 -273.227006) (xy 348.451171 -273.179222)
			(xy 348.470462 -273.133946) (xy 348.496765 -273.09235) (xy 348.5294 -273.055513) (xy 348.567521 -273.024388)
			(xy 348.610142 -272.999781) (xy 348.656158 -272.982329) (xy 348.704377 -272.972485) (xy 348.753552 -272.970504)
			(xy 348.802407 -272.976436) (xy 348.849678 -272.990128) (xy 348.89414 -273.011226) (xy 348.934643 -273.039182)
			(xy 348.970136 -273.073274) (xy 348.999701 -273.112618) (xy 349.022572 -273.156195) (xy 349.038156 -273.202876)
			(xy 349.046051 -273.251453) (xy 349.046546 -273.27606) (xy 349.375234 -273.27606) (xy 349.379194 -273.227006)
			(xy 349.390971 -273.179222) (xy 349.410262 -273.133946) (xy 349.436565 -273.09235) (xy 349.4692 -273.055513)
			(xy 349.507321 -273.024388) (xy 349.549942 -272.999781) (xy 349.595958 -272.982329) (xy 349.644177 -272.972485)
			(xy 349.693352 -272.970504) (xy 349.742207 -272.976436) (xy 349.789478 -272.990128) (xy 349.83394 -273.011226)
			(xy 349.874443 -273.039182) (xy 349.909936 -273.073274) (xy 349.939501 -273.112618) (xy 349.962372 -273.156195)
			(xy 349.977956 -273.202876) (xy 349.985851 -273.251453) (xy 349.986346 -273.27606) (xy 350.315288 -273.27606)
			(xy 350.319248 -273.227006) (xy 350.331025 -273.179222) (xy 350.350316 -273.133946) (xy 350.376619 -273.09235)
			(xy 350.409254 -273.055513) (xy 350.447375 -273.024388) (xy 350.489996 -272.999781) (xy 350.536012 -272.982329)
			(xy 350.584231 -272.972485) (xy 350.633406 -272.970504) (xy 350.682261 -272.976436) (xy 350.729532 -272.990128)
			(xy 350.773994 -273.011226) (xy 350.814497 -273.039182) (xy 350.84999 -273.073274) (xy 350.879555 -273.112618)
			(xy 350.902426 -273.156195) (xy 350.91801 -273.202876) (xy 350.925905 -273.251453) (xy 350.9264 -273.27606)
			(xy 351.255342 -273.27606) (xy 351.259302 -273.227006) (xy 351.271079 -273.179222) (xy 351.29037 -273.133946)
			(xy 351.316673 -273.09235) (xy 351.349308 -273.055513) (xy 351.387429 -273.024388) (xy 351.43005 -272.999781)
			(xy 351.476066 -272.982329) (xy 351.524285 -272.972485) (xy 351.57346 -272.970504) (xy 351.622315 -272.976436)
			(xy 351.669586 -272.990128) (xy 351.714048 -273.011226) (xy 351.754551 -273.039182) (xy 351.790044 -273.073274)
			(xy 351.819609 -273.112618) (xy 351.84248 -273.156195) (xy 351.858064 -273.202876) (xy 351.865959 -273.251453)
			(xy 351.866454 -273.27606) (xy 352.195396 -273.27606) (xy 352.199356 -273.227006) (xy 352.211133 -273.179222)
			(xy 352.230424 -273.133946) (xy 352.256727 -273.09235) (xy 352.289362 -273.055513) (xy 352.327483 -273.024388)
			(xy 352.370104 -272.999781) (xy 352.41612 -272.982329) (xy 352.464339 -272.972485) (xy 352.513514 -272.970504)
			(xy 352.562369 -272.976436) (xy 352.60964 -272.990128) (xy 352.654102 -273.011226) (xy 352.694605 -273.039182)
			(xy 352.730098 -273.073274) (xy 352.759663 -273.112618) (xy 352.782534 -273.156195) (xy 352.798118 -273.202876)
			(xy 352.806013 -273.251453) (xy 352.806508 -273.27606) (xy 353.135196 -273.27606) (xy 353.139156 -273.227006)
			(xy 353.150933 -273.179222) (xy 353.170224 -273.133946) (xy 353.196527 -273.09235) (xy 353.229162 -273.055513)
			(xy 353.267283 -273.024388) (xy 353.309904 -272.999781) (xy 353.35592 -272.982329) (xy 353.404139 -272.972485)
			(xy 353.453314 -272.970504) (xy 353.502169 -272.976436) (xy 353.54944 -272.990128) (xy 353.593902 -273.011226)
			(xy 353.634405 -273.039182) (xy 353.669898 -273.073274) (xy 353.699463 -273.112618) (xy 353.722334 -273.156195)
			(xy 353.737918 -273.202876) (xy 353.745813 -273.251453) (xy 353.746308 -273.27606) (xy 354.07525 -273.27606)
			(xy 354.07921 -273.227006) (xy 354.090987 -273.179222) (xy 354.110278 -273.133946) (xy 354.136581 -273.09235)
			(xy 354.169216 -273.055513) (xy 354.207337 -273.024388) (xy 354.249958 -272.999781) (xy 354.295974 -272.982329)
			(xy 354.344193 -272.972485) (xy 354.393368 -272.970504) (xy 354.442223 -272.976436) (xy 354.489494 -272.990128)
			(xy 354.533956 -273.011226) (xy 354.574459 -273.039182) (xy 354.609952 -273.073274) (xy 354.639517 -273.112618)
			(xy 354.662388 -273.156195) (xy 354.677972 -273.202876) (xy 354.685867 -273.251453) (xy 354.686362 -273.27606)
			(xy 355.015304 -273.27606) (xy 355.019264 -273.227006) (xy 355.031041 -273.179222) (xy 355.050332 -273.133946)
			(xy 355.076635 -273.09235) (xy 355.10927 -273.055513) (xy 355.147391 -273.024388) (xy 355.190012 -272.999781)
			(xy 355.236028 -272.982329) (xy 355.284247 -272.972485) (xy 355.333422 -272.970504) (xy 355.382277 -272.976436)
			(xy 355.429548 -272.990128) (xy 355.47401 -273.011226) (xy 355.514513 -273.039182) (xy 355.550006 -273.073274)
			(xy 355.579571 -273.112618) (xy 355.602442 -273.156195) (xy 355.618026 -273.202876) (xy 355.625921 -273.251453)
			(xy 355.626416 -273.27606) (xy 355.955358 -273.27606) (xy 355.959318 -273.227006) (xy 355.971095 -273.179222)
			(xy 355.990386 -273.133946) (xy 356.016689 -273.09235) (xy 356.049324 -273.055513) (xy 356.087445 -273.024388)
			(xy 356.130066 -272.999781) (xy 356.176082 -272.982329) (xy 356.224301 -272.972485) (xy 356.273476 -272.970504)
			(xy 356.322331 -272.976436) (xy 356.369602 -272.990128) (xy 356.414064 -273.011226) (xy 356.454567 -273.039182)
			(xy 356.49006 -273.073274) (xy 356.519625 -273.112618) (xy 356.542496 -273.156195) (xy 356.55808 -273.202876)
			(xy 356.565975 -273.251453) (xy 356.56647 -273.27606) (xy 356.895412 -273.27606) (xy 356.899372 -273.227006)
			(xy 356.911149 -273.179222) (xy 356.93044 -273.133946) (xy 356.956743 -273.09235) (xy 356.989378 -273.055513)
			(xy 357.027499 -273.024388) (xy 357.07012 -272.999781) (xy 357.116136 -272.982329) (xy 357.164355 -272.972485)
			(xy 357.21353 -272.970504) (xy 357.262385 -272.976436) (xy 357.309656 -272.990128) (xy 357.354118 -273.011226)
			(xy 357.394621 -273.039182) (xy 357.430114 -273.073274) (xy 357.459679 -273.112618) (xy 357.48255 -273.156195)
			(xy 357.498134 -273.202876) (xy 357.506029 -273.251453) (xy 357.506524 -273.27606) (xy 357.835212 -273.27606)
			(xy 357.839172 -273.227006) (xy 357.850949 -273.179222) (xy 357.87024 -273.133946) (xy 357.896543 -273.09235)
			(xy 357.929178 -273.055513) (xy 357.967299 -273.024388) (xy 358.00992 -272.999781) (xy 358.055936 -272.982329)
			(xy 358.104155 -272.972485) (xy 358.15333 -272.970504) (xy 358.202185 -272.976436) (xy 358.249456 -272.990128)
			(xy 358.293918 -273.011226) (xy 358.334421 -273.039182) (xy 358.369914 -273.073274) (xy 358.399479 -273.112618)
			(xy 358.42235 -273.156195) (xy 358.437934 -273.202876) (xy 358.445829 -273.251453) (xy 358.446324 -273.27606)
			(xy 361.589078 -273.27606) (xy 361.593038 -273.227006) (xy 361.604815 -273.179222) (xy 361.624106 -273.133946)
			(xy 361.650409 -273.09235) (xy 361.683044 -273.055513) (xy 361.721165 -273.024388) (xy 361.763786 -272.999781)
			(xy 361.809802 -272.982329) (xy 361.858021 -272.972485) (xy 361.907196 -272.970504) (xy 361.956051 -272.976436)
			(xy 362.003322 -272.990128) (xy 362.047784 -273.011226) (xy 362.088287 -273.039182) (xy 362.12378 -273.073274)
			(xy 362.153345 -273.112618) (xy 362.176216 -273.156195) (xy 362.1918 -273.202876) (xy 362.199695 -273.251453)
			(xy 362.20019 -273.27606) (xy 362.528878 -273.27606) (xy 362.532838 -273.227006) (xy 362.544615 -273.179222)
			(xy 362.563906 -273.133946) (xy 362.590209 -273.09235) (xy 362.622844 -273.055513) (xy 362.660965 -273.024388)
			(xy 362.703586 -272.999781) (xy 362.749602 -272.982329) (xy 362.797821 -272.972485) (xy 362.846996 -272.970504)
			(xy 362.895851 -272.976436) (xy 362.943122 -272.990128) (xy 362.987584 -273.011226) (xy 363.028087 -273.039182)
			(xy 363.06358 -273.073274) (xy 363.093145 -273.112618) (xy 363.116016 -273.156195) (xy 363.1316 -273.202876)
			(xy 363.139495 -273.251453) (xy 363.13999 -273.27606) (xy 363.468932 -273.27606) (xy 363.472892 -273.227006)
			(xy 363.484669 -273.179222) (xy 363.50396 -273.133946) (xy 363.530263 -273.09235) (xy 363.562898 -273.055513)
			(xy 363.601019 -273.024388) (xy 363.64364 -272.999781) (xy 363.689656 -272.982329) (xy 363.737875 -272.972485)
			(xy 363.78705 -272.970504) (xy 363.835905 -272.976436) (xy 363.883176 -272.990128) (xy 363.927638 -273.011226)
			(xy 363.968141 -273.039182) (xy 364.003634 -273.073274) (xy 364.033199 -273.112618) (xy 364.05607 -273.156195)
			(xy 364.071654 -273.202876) (xy 364.079549 -273.251453) (xy 364.080044 -273.27606) (xy 364.408986 -273.27606)
			(xy 364.412946 -273.227006) (xy 364.424723 -273.179222) (xy 364.444014 -273.133946) (xy 364.470317 -273.09235)
			(xy 364.502952 -273.055513) (xy 364.541073 -273.024388) (xy 364.583694 -272.999781) (xy 364.62971 -272.982329)
			(xy 364.677929 -272.972485) (xy 364.727104 -272.970504) (xy 364.775959 -272.976436) (xy 364.82323 -272.990128)
			(xy 364.867692 -273.011226) (xy 364.908195 -273.039182) (xy 364.943688 -273.073274) (xy 364.973253 -273.112618)
			(xy 364.996124 -273.156195) (xy 365.011708 -273.202876) (xy 365.019603 -273.251453) (xy 365.020098 -273.27606)
			(xy 365.34904 -273.27606) (xy 365.353 -273.227006) (xy 365.364777 -273.179222) (xy 365.384068 -273.133946)
			(xy 365.410371 -273.09235) (xy 365.443006 -273.055513) (xy 365.481127 -273.024388) (xy 365.523748 -272.999781)
			(xy 365.569764 -272.982329) (xy 365.617983 -272.972485) (xy 365.667158 -272.970504) (xy 365.716013 -272.976436)
			(xy 365.763284 -272.990128) (xy 365.807746 -273.011226) (xy 365.848249 -273.039182) (xy 365.883742 -273.073274)
			(xy 365.913307 -273.112618) (xy 365.936178 -273.156195) (xy 365.951762 -273.202876) (xy 365.959657 -273.251453)
			(xy 365.960152 -273.27606) (xy 366.289094 -273.27606) (xy 366.293054 -273.227006) (xy 366.304831 -273.179222)
			(xy 366.324122 -273.133946) (xy 366.350425 -273.09235) (xy 366.38306 -273.055513) (xy 366.421181 -273.024388)
			(xy 366.463802 -272.999781) (xy 366.509818 -272.982329) (xy 366.558037 -272.972485) (xy 366.607212 -272.970504)
			(xy 366.656067 -272.976436) (xy 366.703338 -272.990128) (xy 366.7478 -273.011226) (xy 366.788303 -273.039182)
			(xy 366.823796 -273.073274) (xy 366.853361 -273.112618) (xy 366.876232 -273.156195) (xy 366.891816 -273.202876)
			(xy 366.899711 -273.251453) (xy 366.900206 -273.27606) (xy 367.228894 -273.27606) (xy 367.232854 -273.227006)
			(xy 367.244631 -273.179222) (xy 367.263922 -273.133946) (xy 367.290225 -273.09235) (xy 367.32286 -273.055513)
			(xy 367.360981 -273.024388) (xy 367.403602 -272.999781) (xy 367.449618 -272.982329) (xy 367.497837 -272.972485)
			(xy 367.547012 -272.970504) (xy 367.595867 -272.976436) (xy 367.643138 -272.990128) (xy 367.6876 -273.011226)
			(xy 367.728103 -273.039182) (xy 367.763596 -273.073274) (xy 367.793161 -273.112618) (xy 367.816032 -273.156195)
			(xy 367.831616 -273.202876) (xy 367.839511 -273.251453) (xy 367.840006 -273.27606) (xy 368.168948 -273.27606)
			(xy 368.172908 -273.227006) (xy 368.184685 -273.179222) (xy 368.203976 -273.133946) (xy 368.230279 -273.09235)
			(xy 368.262914 -273.055513) (xy 368.301035 -273.024388) (xy 368.343656 -272.999781) (xy 368.389672 -272.982329)
			(xy 368.437891 -272.972485) (xy 368.487066 -272.970504) (xy 368.535921 -272.976436) (xy 368.583192 -272.990128)
			(xy 368.627654 -273.011226) (xy 368.668157 -273.039182) (xy 368.70365 -273.073274) (xy 368.733215 -273.112618)
			(xy 368.756086 -273.156195) (xy 368.77167 -273.202876) (xy 368.779565 -273.251453) (xy 368.78006 -273.27606)
			(xy 369.109002 -273.27606) (xy 369.112962 -273.227006) (xy 369.124739 -273.179222) (xy 369.14403 -273.133946)
			(xy 369.170333 -273.09235) (xy 369.202968 -273.055513) (xy 369.241089 -273.024388) (xy 369.28371 -272.999781)
			(xy 369.329726 -272.982329) (xy 369.377945 -272.972485) (xy 369.42712 -272.970504) (xy 369.475975 -272.976436)
			(xy 369.523246 -272.990128) (xy 369.567708 -273.011226) (xy 369.608211 -273.039182) (xy 369.643704 -273.073274)
			(xy 369.673269 -273.112618) (xy 369.69614 -273.156195) (xy 369.711724 -273.202876) (xy 369.719619 -273.251453)
			(xy 369.720114 -273.27606) (xy 370.049056 -273.27606) (xy 370.053016 -273.227006) (xy 370.064793 -273.179222)
			(xy 370.084084 -273.133946) (xy 370.110387 -273.09235) (xy 370.143022 -273.055513) (xy 370.181143 -273.024388)
			(xy 370.223764 -272.999781) (xy 370.26978 -272.982329) (xy 370.317999 -272.972485) (xy 370.367174 -272.970504)
			(xy 370.416029 -272.976436) (xy 370.4633 -272.990128) (xy 370.507762 -273.011226) (xy 370.548265 -273.039182)
			(xy 370.583758 -273.073274) (xy 370.613323 -273.112618) (xy 370.636194 -273.156195) (xy 370.651778 -273.202876)
			(xy 370.659673 -273.251453) (xy 370.660168 -273.27606) (xy 370.98911 -273.27606) (xy 370.99307 -273.227006)
			(xy 371.004847 -273.179222) (xy 371.024138 -273.133946) (xy 371.050441 -273.09235) (xy 371.083076 -273.055513)
			(xy 371.121197 -273.024388) (xy 371.163818 -272.999781) (xy 371.209834 -272.982329) (xy 371.258053 -272.972485)
			(xy 371.307228 -272.970504) (xy 371.356083 -272.976436) (xy 371.403354 -272.990128) (xy 371.447816 -273.011226)
			(xy 371.488319 -273.039182) (xy 371.523812 -273.073274) (xy 371.553377 -273.112618) (xy 371.576248 -273.156195)
			(xy 371.591832 -273.202876) (xy 371.599727 -273.251453) (xy 371.600222 -273.27606) (xy 371.92891 -273.27606)
			(xy 371.93287 -273.227006) (xy 371.944647 -273.179222) (xy 371.963938 -273.133946) (xy 371.990241 -273.09235)
			(xy 372.022876 -273.055513) (xy 372.060997 -273.024388) (xy 372.103618 -272.999781) (xy 372.149634 -272.982329)
			(xy 372.197853 -272.972485) (xy 372.247028 -272.970504) (xy 372.295883 -272.976436) (xy 372.343154 -272.990128)
			(xy 372.387616 -273.011226) (xy 372.428119 -273.039182) (xy 372.463612 -273.073274) (xy 372.493177 -273.112618)
			(xy 372.516048 -273.156195) (xy 372.531632 -273.202876) (xy 372.539527 -273.251453) (xy 372.540022 -273.27606)
			(xy 372.868964 -273.27606) (xy 372.872924 -273.227006) (xy 372.884701 -273.179222) (xy 372.903992 -273.133946)
			(xy 372.930295 -273.09235) (xy 372.96293 -273.055513) (xy 373.001051 -273.024388) (xy 373.043672 -272.999781)
			(xy 373.089688 -272.982329) (xy 373.137907 -272.972485) (xy 373.187082 -272.970504) (xy 373.235937 -272.976436)
			(xy 373.283208 -272.990128) (xy 373.32767 -273.011226) (xy 373.368173 -273.039182) (xy 373.403666 -273.073274)
			(xy 373.433231 -273.112618) (xy 373.456102 -273.156195) (xy 373.471686 -273.202876) (xy 373.479581 -273.251453)
			(xy 373.480076 -273.27606) (xy 373.809018 -273.27606) (xy 373.812978 -273.227006) (xy 373.824755 -273.179222)
			(xy 373.844046 -273.133946) (xy 373.870349 -273.09235) (xy 373.902984 -273.055513) (xy 373.941105 -273.024388)
			(xy 373.983726 -272.999781) (xy 374.029742 -272.982329) (xy 374.077961 -272.972485) (xy 374.127136 -272.970504)
			(xy 374.175991 -272.976436) (xy 374.223262 -272.990128) (xy 374.267724 -273.011226) (xy 374.308227 -273.039182)
			(xy 374.34372 -273.073274) (xy 374.373285 -273.112618) (xy 374.396156 -273.156195) (xy 374.41174 -273.202876)
			(xy 374.419635 -273.251453) (xy 374.42013 -273.27606) (xy 374.419635 -273.300667) (xy 374.41174 -273.349244)
			(xy 374.396156 -273.395925) (xy 374.373285 -273.439502) (xy 374.34372 -273.478846) (xy 374.308227 -273.512938)
			(xy 374.267724 -273.540894) (xy 374.223262 -273.561992) (xy 374.175991 -273.575684) (xy 374.127136 -273.581616)
			(xy 374.077961 -273.579635) (xy 374.029742 -273.569791) (xy 373.983726 -273.552339) (xy 373.941105 -273.527732)
			(xy 373.902984 -273.496607) (xy 373.870349 -273.45977) (xy 373.844046 -273.418174) (xy 373.824755 -273.372898)
			(xy 373.812978 -273.325114) (xy 373.809018 -273.27606) (xy 373.480076 -273.27606) (xy 373.479581 -273.300667)
			(xy 373.471686 -273.349244) (xy 373.456102 -273.395925) (xy 373.433231 -273.439502) (xy 373.403666 -273.478846)
			(xy 373.368173 -273.512938) (xy 373.32767 -273.540894) (xy 373.283208 -273.561992) (xy 373.235937 -273.575684)
			(xy 373.187082 -273.581616) (xy 373.137907 -273.579635) (xy 373.089688 -273.569791) (xy 373.043672 -273.552339)
			(xy 373.001051 -273.527732) (xy 372.96293 -273.496607) (xy 372.930295 -273.45977) (xy 372.903992 -273.418174)
			(xy 372.884701 -273.372898) (xy 372.872924 -273.325114) (xy 372.868964 -273.27606) (xy 372.540022 -273.27606)
			(xy 372.539527 -273.300667) (xy 372.531632 -273.349244) (xy 372.516048 -273.395925) (xy 372.493177 -273.439502)
			(xy 372.463612 -273.478846) (xy 372.428119 -273.512938) (xy 372.387616 -273.540894) (xy 372.343154 -273.561992)
			(xy 372.295883 -273.575684) (xy 372.247028 -273.581616) (xy 372.197853 -273.579635) (xy 372.149634 -273.569791)
			(xy 372.103618 -273.552339) (xy 372.060997 -273.527732) (xy 372.022876 -273.496607) (xy 371.990241 -273.45977)
			(xy 371.963938 -273.418174) (xy 371.944647 -273.372898) (xy 371.93287 -273.325114) (xy 371.92891 -273.27606)
			(xy 371.600222 -273.27606) (xy 371.599727 -273.300667) (xy 371.591832 -273.349244) (xy 371.576248 -273.395925)
			(xy 371.553377 -273.439502) (xy 371.523812 -273.478846) (xy 371.488319 -273.512938) (xy 371.447816 -273.540894)
			(xy 371.403354 -273.561992) (xy 371.356083 -273.575684) (xy 371.307228 -273.581616) (xy 371.258053 -273.579635)
			(xy 371.209834 -273.569791) (xy 371.163818 -273.552339) (xy 371.121197 -273.527732) (xy 371.083076 -273.496607)
			(xy 371.050441 -273.45977) (xy 371.024138 -273.418174) (xy 371.004847 -273.372898) (xy 370.99307 -273.325114)
			(xy 370.98911 -273.27606) (xy 370.660168 -273.27606) (xy 370.659673 -273.300667) (xy 370.651778 -273.349244)
			(xy 370.636194 -273.395925) (xy 370.613323 -273.439502) (xy 370.583758 -273.478846) (xy 370.548265 -273.512938)
			(xy 370.507762 -273.540894) (xy 370.4633 -273.561992) (xy 370.416029 -273.575684) (xy 370.367174 -273.581616)
			(xy 370.317999 -273.579635) (xy 370.26978 -273.569791) (xy 370.223764 -273.552339) (xy 370.181143 -273.527732)
			(xy 370.143022 -273.496607) (xy 370.110387 -273.45977) (xy 370.084084 -273.418174) (xy 370.064793 -273.372898)
			(xy 370.053016 -273.325114) (xy 370.049056 -273.27606) (xy 369.720114 -273.27606) (xy 369.719619 -273.300667)
			(xy 369.711724 -273.349244) (xy 369.69614 -273.395925) (xy 369.673269 -273.439502) (xy 369.643704 -273.478846)
			(xy 369.608211 -273.512938) (xy 369.567708 -273.540894) (xy 369.523246 -273.561992) (xy 369.475975 -273.575684)
			(xy 369.42712 -273.581616) (xy 369.377945 -273.579635) (xy 369.329726 -273.569791) (xy 369.28371 -273.552339)
			(xy 369.241089 -273.527732) (xy 369.202968 -273.496607) (xy 369.170333 -273.45977) (xy 369.14403 -273.418174)
			(xy 369.124739 -273.372898) (xy 369.112962 -273.325114) (xy 369.109002 -273.27606) (xy 368.78006 -273.27606)
			(xy 368.779565 -273.300667) (xy 368.77167 -273.349244) (xy 368.756086 -273.395925) (xy 368.733215 -273.439502)
			(xy 368.70365 -273.478846) (xy 368.668157 -273.512938) (xy 368.627654 -273.540894) (xy 368.583192 -273.561992)
			(xy 368.535921 -273.575684) (xy 368.487066 -273.581616) (xy 368.437891 -273.579635) (xy 368.389672 -273.569791)
			(xy 368.343656 -273.552339) (xy 368.301035 -273.527732) (xy 368.262914 -273.496607) (xy 368.230279 -273.45977)
			(xy 368.203976 -273.418174) (xy 368.184685 -273.372898) (xy 368.172908 -273.325114) (xy 368.168948 -273.27606)
			(xy 367.840006 -273.27606) (xy 367.839511 -273.300667) (xy 367.831616 -273.349244) (xy 367.816032 -273.395925)
			(xy 367.793161 -273.439502) (xy 367.763596 -273.478846) (xy 367.728103 -273.512938) (xy 367.6876 -273.540894)
			(xy 367.643138 -273.561992) (xy 367.595867 -273.575684) (xy 367.547012 -273.581616) (xy 367.497837 -273.579635)
			(xy 367.449618 -273.569791) (xy 367.403602 -273.552339) (xy 367.360981 -273.527732) (xy 367.32286 -273.496607)
			(xy 367.290225 -273.45977) (xy 367.263922 -273.418174) (xy 367.244631 -273.372898) (xy 367.232854 -273.325114)
			(xy 367.228894 -273.27606) (xy 366.900206 -273.27606) (xy 366.899711 -273.300667) (xy 366.891816 -273.349244)
			(xy 366.876232 -273.395925) (xy 366.853361 -273.439502) (xy 366.823796 -273.478846) (xy 366.788303 -273.512938)
			(xy 366.7478 -273.540894) (xy 366.703338 -273.561992) (xy 366.656067 -273.575684) (xy 366.607212 -273.581616)
			(xy 366.558037 -273.579635) (xy 366.509818 -273.569791) (xy 366.463802 -273.552339) (xy 366.421181 -273.527732)
			(xy 366.38306 -273.496607) (xy 366.350425 -273.45977) (xy 366.324122 -273.418174) (xy 366.304831 -273.372898)
			(xy 366.293054 -273.325114) (xy 366.289094 -273.27606) (xy 365.960152 -273.27606) (xy 365.959657 -273.300667)
			(xy 365.951762 -273.349244) (xy 365.936178 -273.395925) (xy 365.913307 -273.439502) (xy 365.883742 -273.478846)
			(xy 365.848249 -273.512938) (xy 365.807746 -273.540894) (xy 365.763284 -273.561992) (xy 365.716013 -273.575684)
			(xy 365.667158 -273.581616) (xy 365.617983 -273.579635) (xy 365.569764 -273.569791) (xy 365.523748 -273.552339)
			(xy 365.481127 -273.527732) (xy 365.443006 -273.496607) (xy 365.410371 -273.45977) (xy 365.384068 -273.418174)
			(xy 365.364777 -273.372898) (xy 365.353 -273.325114) (xy 365.34904 -273.27606) (xy 365.020098 -273.27606)
			(xy 365.019603 -273.300667) (xy 365.011708 -273.349244) (xy 364.996124 -273.395925) (xy 364.973253 -273.439502)
			(xy 364.943688 -273.478846) (xy 364.908195 -273.512938) (xy 364.867692 -273.540894) (xy 364.82323 -273.561992)
			(xy 364.775959 -273.575684) (xy 364.727104 -273.581616) (xy 364.677929 -273.579635) (xy 364.62971 -273.569791)
			(xy 364.583694 -273.552339) (xy 364.541073 -273.527732) (xy 364.502952 -273.496607) (xy 364.470317 -273.45977)
			(xy 364.444014 -273.418174) (xy 364.424723 -273.372898) (xy 364.412946 -273.325114) (xy 364.408986 -273.27606)
			(xy 364.080044 -273.27606) (xy 364.079549 -273.300667) (xy 364.071654 -273.349244) (xy 364.05607 -273.395925)
			(xy 364.033199 -273.439502) (xy 364.003634 -273.478846) (xy 363.968141 -273.512938) (xy 363.927638 -273.540894)
			(xy 363.883176 -273.561992) (xy 363.835905 -273.575684) (xy 363.78705 -273.581616) (xy 363.737875 -273.579635)
			(xy 363.689656 -273.569791) (xy 363.64364 -273.552339) (xy 363.601019 -273.527732) (xy 363.562898 -273.496607)
			(xy 363.530263 -273.45977) (xy 363.50396 -273.418174) (xy 363.484669 -273.372898) (xy 363.472892 -273.325114)
			(xy 363.468932 -273.27606) (xy 363.13999 -273.27606) (xy 363.139495 -273.300667) (xy 363.1316 -273.349244)
			(xy 363.116016 -273.395925) (xy 363.093145 -273.439502) (xy 363.06358 -273.478846) (xy 363.028087 -273.512938)
			(xy 362.987584 -273.540894) (xy 362.943122 -273.561992) (xy 362.895851 -273.575684) (xy 362.846996 -273.581616)
			(xy 362.797821 -273.579635) (xy 362.749602 -273.569791) (xy 362.703586 -273.552339) (xy 362.660965 -273.527732)
			(xy 362.622844 -273.496607) (xy 362.590209 -273.45977) (xy 362.563906 -273.418174) (xy 362.544615 -273.372898)
			(xy 362.532838 -273.325114) (xy 362.528878 -273.27606) (xy 362.20019 -273.27606) (xy 362.199695 -273.300667)
			(xy 362.1918 -273.349244) (xy 362.176216 -273.395925) (xy 362.153345 -273.439502) (xy 362.12378 -273.478846)
			(xy 362.088287 -273.512938) (xy 362.047784 -273.540894) (xy 362.003322 -273.561992) (xy 361.956051 -273.575684)
			(xy 361.907196 -273.581616) (xy 361.858021 -273.579635) (xy 361.809802 -273.569791) (xy 361.763786 -273.552339)
			(xy 361.721165 -273.527732) (xy 361.683044 -273.496607) (xy 361.650409 -273.45977) (xy 361.624106 -273.418174)
			(xy 361.604815 -273.372898) (xy 361.593038 -273.325114) (xy 361.589078 -273.27606) (xy 358.446324 -273.27606)
			(xy 358.445829 -273.300667) (xy 358.437934 -273.349244) (xy 358.42235 -273.395925) (xy 358.399479 -273.439502)
			(xy 358.369914 -273.478846) (xy 358.334421 -273.512938) (xy 358.293918 -273.540894) (xy 358.249456 -273.561992)
			(xy 358.202185 -273.575684) (xy 358.15333 -273.581616) (xy 358.104155 -273.579635) (xy 358.055936 -273.569791)
			(xy 358.00992 -273.552339) (xy 357.967299 -273.527732) (xy 357.929178 -273.496607) (xy 357.896543 -273.45977)
			(xy 357.87024 -273.418174) (xy 357.850949 -273.372898) (xy 357.839172 -273.325114) (xy 357.835212 -273.27606)
			(xy 357.506524 -273.27606) (xy 357.506029 -273.300667) (xy 357.498134 -273.349244) (xy 357.48255 -273.395925)
			(xy 357.459679 -273.439502) (xy 357.430114 -273.478846) (xy 357.394621 -273.512938) (xy 357.354118 -273.540894)
			(xy 357.309656 -273.561992) (xy 357.262385 -273.575684) (xy 357.21353 -273.581616) (xy 357.164355 -273.579635)
			(xy 357.116136 -273.569791) (xy 357.07012 -273.552339) (xy 357.027499 -273.527732) (xy 356.989378 -273.496607)
			(xy 356.956743 -273.45977) (xy 356.93044 -273.418174) (xy 356.911149 -273.372898) (xy 356.899372 -273.325114)
			(xy 356.895412 -273.27606) (xy 356.56647 -273.27606) (xy 356.565975 -273.300667) (xy 356.55808 -273.349244)
			(xy 356.542496 -273.395925) (xy 356.519625 -273.439502) (xy 356.49006 -273.478846) (xy 356.454567 -273.512938)
			(xy 356.414064 -273.540894) (xy 356.369602 -273.561992) (xy 356.322331 -273.575684) (xy 356.273476 -273.581616)
			(xy 356.224301 -273.579635) (xy 356.176082 -273.569791) (xy 356.130066 -273.552339) (xy 356.087445 -273.527732)
			(xy 356.049324 -273.496607) (xy 356.016689 -273.45977) (xy 355.990386 -273.418174) (xy 355.971095 -273.372898)
			(xy 355.959318 -273.325114) (xy 355.955358 -273.27606) (xy 355.626416 -273.27606) (xy 355.625921 -273.300667)
			(xy 355.618026 -273.349244) (xy 355.602442 -273.395925) (xy 355.579571 -273.439502) (xy 355.550006 -273.478846)
			(xy 355.514513 -273.512938) (xy 355.47401 -273.540894) (xy 355.429548 -273.561992) (xy 355.382277 -273.575684)
			(xy 355.333422 -273.581616) (xy 355.284247 -273.579635) (xy 355.236028 -273.569791) (xy 355.190012 -273.552339)
			(xy 355.147391 -273.527732) (xy 355.10927 -273.496607) (xy 355.076635 -273.45977) (xy 355.050332 -273.418174)
			(xy 355.031041 -273.372898) (xy 355.019264 -273.325114) (xy 355.015304 -273.27606) (xy 354.686362 -273.27606)
			(xy 354.685867 -273.300667) (xy 354.677972 -273.349244) (xy 354.662388 -273.395925) (xy 354.639517 -273.439502)
			(xy 354.609952 -273.478846) (xy 354.574459 -273.512938) (xy 354.533956 -273.540894) (xy 354.489494 -273.561992)
			(xy 354.442223 -273.575684) (xy 354.393368 -273.581616) (xy 354.344193 -273.579635) (xy 354.295974 -273.569791)
			(xy 354.249958 -273.552339) (xy 354.207337 -273.527732) (xy 354.169216 -273.496607) (xy 354.136581 -273.45977)
			(xy 354.110278 -273.418174) (xy 354.090987 -273.372898) (xy 354.07921 -273.325114) (xy 354.07525 -273.27606)
			(xy 353.746308 -273.27606) (xy 353.745813 -273.300667) (xy 353.737918 -273.349244) (xy 353.722334 -273.395925)
			(xy 353.699463 -273.439502) (xy 353.669898 -273.478846) (xy 353.634405 -273.512938) (xy 353.593902 -273.540894)
			(xy 353.54944 -273.561992) (xy 353.502169 -273.575684) (xy 353.453314 -273.581616) (xy 353.404139 -273.579635)
			(xy 353.35592 -273.569791) (xy 353.309904 -273.552339) (xy 353.267283 -273.527732) (xy 353.229162 -273.496607)
			(xy 353.196527 -273.45977) (xy 353.170224 -273.418174) (xy 353.150933 -273.372898) (xy 353.139156 -273.325114)
			(xy 353.135196 -273.27606) (xy 352.806508 -273.27606) (xy 352.806013 -273.300667) (xy 352.798118 -273.349244)
			(xy 352.782534 -273.395925) (xy 352.759663 -273.439502) (xy 352.730098 -273.478846) (xy 352.694605 -273.512938)
			(xy 352.654102 -273.540894) (xy 352.60964 -273.561992) (xy 352.562369 -273.575684) (xy 352.513514 -273.581616)
			(xy 352.464339 -273.579635) (xy 352.41612 -273.569791) (xy 352.370104 -273.552339) (xy 352.327483 -273.527732)
			(xy 352.289362 -273.496607) (xy 352.256727 -273.45977) (xy 352.230424 -273.418174) (xy 352.211133 -273.372898)
			(xy 352.199356 -273.325114) (xy 352.195396 -273.27606) (xy 351.866454 -273.27606) (xy 351.865959 -273.300667)
			(xy 351.858064 -273.349244) (xy 351.84248 -273.395925) (xy 351.819609 -273.439502) (xy 351.790044 -273.478846)
			(xy 351.754551 -273.512938) (xy 351.714048 -273.540894) (xy 351.669586 -273.561992) (xy 351.622315 -273.575684)
			(xy 351.57346 -273.581616) (xy 351.524285 -273.579635) (xy 351.476066 -273.569791) (xy 351.43005 -273.552339)
			(xy 351.387429 -273.527732) (xy 351.349308 -273.496607) (xy 351.316673 -273.45977) (xy 351.29037 -273.418174)
			(xy 351.271079 -273.372898) (xy 351.259302 -273.325114) (xy 351.255342 -273.27606) (xy 350.9264 -273.27606)
			(xy 350.925905 -273.300667) (xy 350.91801 -273.349244) (xy 350.902426 -273.395925) (xy 350.879555 -273.439502)
			(xy 350.84999 -273.478846) (xy 350.814497 -273.512938) (xy 350.773994 -273.540894) (xy 350.729532 -273.561992)
			(xy 350.682261 -273.575684) (xy 350.633406 -273.581616) (xy 350.584231 -273.579635) (xy 350.536012 -273.569791)
			(xy 350.489996 -273.552339) (xy 350.447375 -273.527732) (xy 350.409254 -273.496607) (xy 350.376619 -273.45977)
			(xy 350.350316 -273.418174) (xy 350.331025 -273.372898) (xy 350.319248 -273.325114) (xy 350.315288 -273.27606)
			(xy 349.986346 -273.27606) (xy 349.985851 -273.300667) (xy 349.977956 -273.349244) (xy 349.962372 -273.395925)
			(xy 349.939501 -273.439502) (xy 349.909936 -273.478846) (xy 349.874443 -273.512938) (xy 349.83394 -273.540894)
			(xy 349.789478 -273.561992) (xy 349.742207 -273.575684) (xy 349.693352 -273.581616) (xy 349.644177 -273.579635)
			(xy 349.595958 -273.569791) (xy 349.549942 -273.552339) (xy 349.507321 -273.527732) (xy 349.4692 -273.496607)
			(xy 349.436565 -273.45977) (xy 349.410262 -273.418174) (xy 349.390971 -273.372898) (xy 349.379194 -273.325114)
			(xy 349.375234 -273.27606) (xy 349.046546 -273.27606) (xy 349.046051 -273.300667) (xy 349.038156 -273.349244)
			(xy 349.022572 -273.395925) (xy 348.999701 -273.439502) (xy 348.970136 -273.478846) (xy 348.934643 -273.512938)
			(xy 348.89414 -273.540894) (xy 348.849678 -273.561992) (xy 348.802407 -273.575684) (xy 348.753552 -273.581616)
			(xy 348.704377 -273.579635) (xy 348.656158 -273.569791) (xy 348.610142 -273.552339) (xy 348.567521 -273.527732)
			(xy 348.5294 -273.496607) (xy 348.496765 -273.45977) (xy 348.470462 -273.418174) (xy 348.451171 -273.372898)
			(xy 348.439394 -273.325114) (xy 348.435434 -273.27606) (xy 348.106492 -273.27606) (xy 348.105997 -273.300667)
			(xy 348.098102 -273.349244) (xy 348.082518 -273.395925) (xy 348.059647 -273.439502) (xy 348.030082 -273.478846)
			(xy 347.994589 -273.512938) (xy 347.954086 -273.540894) (xy 347.909624 -273.561992) (xy 347.862353 -273.575684)
			(xy 347.813498 -273.581616) (xy 347.764323 -273.579635) (xy 347.716104 -273.569791) (xy 347.670088 -273.552339)
			(xy 347.627467 -273.527732) (xy 347.589346 -273.496607) (xy 347.556711 -273.45977) (xy 347.530408 -273.418174)
			(xy 347.511117 -273.372898) (xy 347.49934 -273.325114) (xy 347.49538 -273.27606) (xy 347.166438 -273.27606)
			(xy 347.165943 -273.300667) (xy 347.158048 -273.349244) (xy 347.142464 -273.395925) (xy 347.119593 -273.439502)
			(xy 347.090028 -273.478846) (xy 347.054535 -273.512938) (xy 347.014032 -273.540894) (xy 346.96957 -273.561992)
			(xy 346.922299 -273.575684) (xy 346.873444 -273.581616) (xy 346.824269 -273.579635) (xy 346.77605 -273.569791)
			(xy 346.730034 -273.552339) (xy 346.687413 -273.527732) (xy 346.649292 -273.496607) (xy 346.616657 -273.45977)
			(xy 346.590354 -273.418174) (xy 346.571063 -273.372898) (xy 346.559286 -273.325114) (xy 346.555326 -273.27606)
			(xy 346.226384 -273.27606) (xy 346.225889 -273.300667) (xy 346.217994 -273.349244) (xy 346.20241 -273.395925)
			(xy 346.179539 -273.439502) (xy 346.149974 -273.478846) (xy 346.114481 -273.512938) (xy 346.073978 -273.540894)
			(xy 346.029516 -273.561992) (xy 345.982245 -273.575684) (xy 345.93339 -273.581616) (xy 345.884215 -273.579635)
			(xy 345.835996 -273.569791) (xy 345.78998 -273.552339) (xy 345.747359 -273.527732) (xy 345.709238 -273.496607)
			(xy 345.676603 -273.45977) (xy 345.6503 -273.418174) (xy 345.631009 -273.372898) (xy 345.619232 -273.325114)
			(xy 345.615272 -273.27606) (xy 345.286818 -273.27606) (xy 345.28682 -273.276086) (xy 345.282827 -273.325361)
			(xy 345.270946 -273.373348) (xy 345.251489 -273.418795) (xy 345.224964 -273.460512) (xy 345.192063 -273.497411)
			(xy 345.153647 -273.528526) (xy 345.11072 -273.553046) (xy 345.087702 -273.562064) (xy 345.087194 -273.562318)
			(xy 345.077621 -273.566347) (xy 345.06256 -273.580619) (xy 345.054395 -273.599694) (xy 345.05392 -273.61007)
			(xy 345.05392 -273.806412) (xy 345.054361 -273.816558) (xy 345.062198 -273.835277) (xy 345.076651 -273.84952)
			(xy 345.085924 -273.853656) (xy 345.188286 -273.894296) (xy 345.218766 -273.887692) (xy 345.229434 -273.876262)
			(xy 345.246847 -273.858544) (xy 345.286366 -273.828446) (xy 345.330243 -273.805153) (xy 345.377315 -273.789284)
			(xy 345.426338 -273.781257) (xy 345.451176 -273.780758) (xy 345.475169 -273.781227) (xy 345.522566 -273.78873)
			(xy 345.568205 -273.803555) (xy 345.610964 -273.825336) (xy 345.649789 -273.853539) (xy 345.683724 -273.887467)
			(xy 345.711933 -273.926287) (xy 345.733723 -273.969041) (xy 345.748557 -274.014677) (xy 345.756069 -274.062073)
			(xy 345.756484 -274.086066) (xy 345.755834 -274.114766) (xy 345.745097 -274.171152) (xy 345.735148 -274.19808)
			(xy 345.730322 -274.21078) (xy 345.734132 -274.237196) (xy 345.805252 -274.32762) (xy 345.830144 -274.33778)
			(xy 345.843606 -274.335748) (xy 345.86288 -274.333312) (xy 345.901649 -274.330773) (xy 345.921076 -274.330668)
			(xy 346.01023 -274.330668) (xy 346.02255 -274.329876) (xy 346.044326 -274.31833) (xy 346.051886 -274.30857)
			(xy 346.10675 -274.229576) (xy 346.109798 -274.205192) (xy 346.10548 -274.193254) (xy 346.096413 -274.167387)
			(xy 346.086579 -274.113469) (xy 346.085922 -274.086066) (xy 346.086444 -274.060811) (xy 346.094757 -274.010989)
			(xy 346.111158 -273.963215) (xy 346.135199 -273.918792) (xy 346.166223 -273.878932) (xy 346.203385 -273.844722)
			(xy 346.245671 -273.817096) (xy 346.291927 -273.796806) (xy 346.340892 -273.784406) (xy 346.39123 -273.780235)
			(xy 346.441568 -273.784406) (xy 346.490533 -273.796806) (xy 346.536789 -273.817096) (xy 346.579075 -273.844722)
			(xy 346.616237 -273.878932) (xy 346.647261 -273.918792) (xy 346.671302 -273.963215) (xy 346.687703 -274.010989)
			(xy 346.696016 -274.060811) (xy 346.696538 -274.086066) (xy 346.695942 -274.113475) (xy 346.686106 -274.167403)
			(xy 346.67698 -274.193254) (xy 346.672662 -274.205192) (xy 346.67571 -274.229576) (xy 346.730574 -274.30857)
			(xy 346.738138 -274.318329) (xy 346.759909 -274.32989) (xy 346.77223 -274.330668) (xy 346.86113 -274.330668)
			(xy 346.880557 -274.330771) (xy 346.919326 -274.333311) (xy 346.9386 -274.335748) (xy 346.952062 -274.33778)
			(xy 346.976954 -274.32762) (xy 347.048074 -274.237196) (xy 347.051884 -274.21078) (xy 347.047058 -274.19808)
			(xy 347.037137 -274.171144) (xy 347.026392 -274.114763) (xy 347.025722 -274.086066) (xy 347.026244 -274.060811)
			(xy 347.034557 -274.010989) (xy 347.050958 -273.963215) (xy 347.074999 -273.918792) (xy 347.106023 -273.878932)
			(xy 347.143185 -273.844722) (xy 347.185471 -273.817096) (xy 347.231727 -273.796806) (xy 347.280692 -273.784406)
			(xy 347.33103 -273.780235) (xy 347.381368 -273.784406) (xy 347.430333 -273.796806) (xy 347.476589 -273.817096)
			(xy 347.518875 -273.844722) (xy 347.556037 -273.878932) (xy 347.587061 -273.918792) (xy 347.611102 -273.963215)
			(xy 347.627503 -274.010989) (xy 347.635816 -274.060811) (xy 347.636338 -274.086066) (xy 347.635836 -274.111463)
			(xy 347.627434 -274.161558) (xy 347.610854 -274.209571) (xy 347.586556 -274.254177) (xy 347.555208 -274.294146)
			(xy 347.53677 -274.311618) (xy 347.525086 -274.322286) (xy 347.51772 -274.35302) (xy 347.557852 -274.45589)
			(xy 347.561977 -274.465218) (xy 347.576165 -274.479848) (xy 347.594909 -274.487846) (xy 347.605096 -274.488402)
			(xy 347.997018 -274.488402) (xy 348.007226 -274.487949) (xy 348.026016 -274.479968) (xy 348.040166 -274.465253)
			(xy 348.044262 -274.45589) (xy 348.084394 -274.35302) (xy 348.077028 -274.322286) (xy 348.065344 -274.311618)
			(xy 348.046923 -274.294129) (xy 348.015584 -274.25416) (xy 347.991287 -274.209558) (xy 347.974704 -274.16155)
			(xy 347.966291 -274.111461) (xy 347.965776 -274.086066) (xy 347.966298 -274.060811) (xy 347.974611 -274.010989)
			(xy 347.991012 -273.963215) (xy 348.015053 -273.918792) (xy 348.046077 -273.878932) (xy 348.083239 -273.844722)
			(xy 348.125525 -273.817096) (xy 348.171781 -273.796806) (xy 348.220746 -273.784406) (xy 348.271084 -273.780235)
			(xy 348.321422 -273.784406) (xy 348.370387 -273.796806) (xy 348.416643 -273.817096) (xy 348.458929 -273.844722)
			(xy 348.496091 -273.878932) (xy 348.527115 -273.918792) (xy 348.551156 -273.963215) (xy 348.567557 -274.010989)
			(xy 348.57587 -274.060811) (xy 348.576392 -274.086066) (xy 348.575742 -274.114766) (xy 348.565005 -274.171152)
			(xy 348.555056 -274.19808) (xy 348.55023 -274.21078) (xy 348.55404 -274.237196) (xy 348.62516 -274.32762)
			(xy 348.650052 -274.33778) (xy 348.663514 -274.336002) (xy 348.682847 -274.333497) (xy 348.721744 -274.330828)
			(xy 348.741238 -274.330668) (xy 348.830138 -274.330668) (xy 348.842457 -274.329875) (xy 348.86423 -274.318326)
			(xy 348.871794 -274.30857) (xy 348.926658 -274.229576) (xy 348.929706 -274.205192) (xy 348.925388 -274.193254)
			(xy 348.916321 -274.167387) (xy 348.906486 -274.113469) (xy 348.90583 -274.086066) (xy 348.906352 -274.060811)
			(xy 348.914665 -274.010989) (xy 348.931066 -273.963215) (xy 348.955107 -273.918792) (xy 348.986131 -273.878932)
			(xy 349.023293 -273.844722) (xy 349.065579 -273.817096) (xy 349.111835 -273.796806) (xy 349.1608 -273.784406)
			(xy 349.211138 -273.780235) (xy 349.261476 -273.784406) (xy 349.310441 -273.796806) (xy 349.356697 -273.817096)
			(xy 349.398983 -273.844722) (xy 349.436145 -273.878932) (xy 349.467169 -273.918792) (xy 349.49121 -273.963215)
			(xy 349.507611 -274.010989) (xy 349.515924 -274.060811) (xy 349.516446 -274.086066) (xy 349.51585 -274.113475)
			(xy 349.506015 -274.167403) (xy 349.496888 -274.193254) (xy 349.49257 -274.205192) (xy 349.495618 -274.229576)
			(xy 349.550482 -274.30857) (xy 349.558046 -274.318328) (xy 349.579817 -274.329885) (xy 349.592138 -274.330668)
			(xy 349.681038 -274.330668) (xy 349.700532 -274.330827) (xy 349.739429 -274.333496) (xy 349.758762 -274.336002)
			(xy 349.772224 -274.33778) (xy 349.797116 -274.32762) (xy 349.868236 -274.237196) (xy 349.872046 -274.21078)
			(xy 349.86722 -274.19808) (xy 349.8573 -274.171144) (xy 349.846557 -274.114763) (xy 349.845884 -274.086066)
			(xy 349.846406 -274.060811) (xy 349.854719 -274.010989) (xy 349.87112 -273.963215) (xy 349.895161 -273.918792)
			(xy 349.926185 -273.878932) (xy 349.963347 -273.844722) (xy 350.005633 -273.817096) (xy 350.051889 -273.796806)
			(xy 350.100854 -273.784406) (xy 350.151192 -273.780235) (xy 350.20153 -273.784406) (xy 350.250495 -273.796806)
			(xy 350.296751 -273.817096) (xy 350.339037 -273.844722) (xy 350.376199 -273.878932) (xy 350.407223 -273.918792)
			(xy 350.431264 -273.963215) (xy 350.447665 -274.010989) (xy 350.455978 -274.060811) (xy 350.4565 -274.086066)
			(xy 350.455998 -274.111463) (xy 350.447594 -274.161557) (xy 350.431013 -274.209569) (xy 350.406713 -274.254173)
			(xy 350.375363 -274.294138) (xy 350.356932 -274.311618) (xy 350.345248 -274.322286) (xy 350.337882 -274.35302)
			(xy 350.378014 -274.45589) (xy 350.382137 -274.465222) (xy 350.396323 -274.479862) (xy 350.415069 -274.487874)
			(xy 350.425258 -274.488402) (xy 350.81718 -274.488402) (xy 350.827392 -274.487956) (xy 350.846194 -274.479983)
			(xy 350.860357 -274.465268) (xy 350.864424 -274.45589) (xy 350.904556 -274.35302) (xy 350.89719 -274.322286)
			(xy 350.885506 -274.311618) (xy 350.867082 -274.294131) (xy 350.835736 -274.254164) (xy 350.811435 -274.209562)
			(xy 350.794848 -274.161553) (xy 350.786433 -274.111462) (xy 350.785938 -274.086066) (xy 350.78646 -274.060811)
			(xy 350.794773 -274.010989) (xy 350.811174 -273.963215) (xy 350.835215 -273.918792) (xy 350.866239 -273.878932)
			(xy 350.903401 -273.844722) (xy 350.945687 -273.817096) (xy 350.991943 -273.796806) (xy 351.040908 -273.784406)
			(xy 351.091246 -273.780235) (xy 351.141584 -273.784406) (xy 351.190549 -273.796806) (xy 351.236805 -273.817096)
			(xy 351.279091 -273.844722) (xy 351.316253 -273.878932) (xy 351.347277 -273.918792) (xy 351.371318 -273.963215)
			(xy 351.387719 -274.010989) (xy 351.396032 -274.060811) (xy 351.396554 -274.086066) (xy 351.395904 -274.114766)
			(xy 351.385165 -274.171151) (xy 351.375218 -274.19808) (xy 351.370392 -274.21078) (xy 351.374202 -274.237196)
			(xy 351.445322 -274.32762) (xy 351.470214 -274.33778) (xy 351.483676 -274.335748) (xy 351.50295 -274.333311)
			(xy 351.541719 -274.33077) (xy 351.561146 -274.330668) (xy 351.650046 -274.330668) (xy 351.662364 -274.329873)
			(xy 351.684134 -274.318323) (xy 351.691702 -274.30857) (xy 351.746566 -274.229576) (xy 351.749614 -274.205192)
			(xy 351.745296 -274.193254) (xy 351.736229 -274.167387) (xy 351.726394 -274.113469) (xy 351.725738 -274.086066)
			(xy 351.72626 -274.060811) (xy 351.734573 -274.010989) (xy 351.750974 -273.963215) (xy 351.775015 -273.918792)
			(xy 351.806039 -273.878932) (xy 351.843201 -273.844722) (xy 351.885487 -273.817096) (xy 351.931743 -273.796806)
			(xy 351.980708 -273.784406) (xy 352.031046 -273.780235) (xy 352.081384 -273.784406) (xy 352.130349 -273.796806)
			(xy 352.176605 -273.817096) (xy 352.218891 -273.844722) (xy 352.256053 -273.878932) (xy 352.287077 -273.918792)
			(xy 352.311118 -273.963215) (xy 352.327519 -274.010989) (xy 352.335832 -274.060811) (xy 352.336354 -274.086066)
			(xy 352.335758 -274.113475) (xy 352.325923 -274.167403) (xy 352.316796 -274.193254) (xy 352.312478 -274.205192)
			(xy 352.315526 -274.229576) (xy 352.37039 -274.30857) (xy 352.377955 -274.318326) (xy 352.399726 -274.329881)
			(xy 352.412046 -274.330668) (xy 352.5012 -274.330668) (xy 352.520627 -274.330774) (xy 352.559396 -274.333318)
			(xy 352.57867 -274.335748) (xy 352.592132 -274.33778) (xy 352.617024 -274.32762) (xy 352.688144 -274.237196)
			(xy 352.691954 -274.21078) (xy 352.687128 -274.19808) (xy 352.677208 -274.171144) (xy 352.666464 -274.114763)
			(xy 352.665792 -274.086066) (xy 352.666314 -274.060811) (xy 352.674627 -274.010989) (xy 352.691028 -273.963215)
			(xy 352.715069 -273.918792) (xy 352.746093 -273.878932) (xy 352.783255 -273.844722) (xy 352.825541 -273.817096)
			(xy 352.871797 -273.796806) (xy 352.920762 -273.784406) (xy 352.9711 -273.780235) (xy 353.021438 -273.784406)
			(xy 353.070403 -273.796806) (xy 353.116659 -273.817096) (xy 353.158945 -273.844722) (xy 353.196107 -273.878932)
			(xy 353.227131 -273.918792) (xy 353.251172 -273.963215) (xy 353.267573 -274.010989) (xy 353.275886 -274.060811)
			(xy 353.276408 -274.086066) (xy 353.275906 -274.111463) (xy 353.267502 -274.161557) (xy 353.250922 -274.209569)
			(xy 353.226622 -274.254173) (xy 353.195272 -274.294139) (xy 353.17684 -274.311618) (xy 353.165156 -274.322286)
			(xy 353.15779 -274.35302) (xy 353.197922 -274.45589) (xy 353.202046 -274.465221) (xy 353.216232 -274.479859)
			(xy 353.234977 -274.487868) (xy 353.245166 -274.488402) (xy 353.637088 -274.488402) (xy 353.6473 -274.487954)
			(xy 353.666099 -274.47998) (xy 353.680259 -274.465265) (xy 353.684332 -274.45589) (xy 353.724464 -274.35302)
			(xy 353.717098 -274.322286) (xy 353.705414 -274.311618) (xy 353.68699 -274.294131) (xy 353.655643 -274.254165)
			(xy 353.631341 -274.209562) (xy 353.614754 -274.161554) (xy 353.606339 -274.111463) (xy 353.605846 -274.086066)
			(xy 353.606368 -274.060811) (xy 353.614681 -274.010989) (xy 353.631082 -273.963215) (xy 353.655123 -273.918792)
			(xy 353.686147 -273.878932) (xy 353.723309 -273.844722) (xy 353.765595 -273.817096) (xy 353.811851 -273.796806)
			(xy 353.860816 -273.784406) (xy 353.911154 -273.780235) (xy 353.961492 -273.784406) (xy 354.010457 -273.796806)
			(xy 354.056713 -273.817096) (xy 354.098999 -273.844722) (xy 354.136161 -273.878932) (xy 354.167185 -273.918792)
			(xy 354.191226 -273.963215) (xy 354.207627 -274.010989) (xy 354.21594 -274.060811) (xy 354.216462 -274.086066)
			(xy 354.215812 -274.114766) (xy 354.205074 -274.171152) (xy 354.195126 -274.19808) (xy 354.1903 -274.21078)
			(xy 354.19411 -274.237196) (xy 354.26523 -274.32762) (xy 354.290122 -274.33778) (xy 354.303584 -274.335748)
			(xy 354.322858 -274.333311) (xy 354.361627 -274.330771) (xy 354.381054 -274.330668) (xy 354.470208 -274.330668)
			(xy 354.482531 -274.329881) (xy 354.504315 -274.31834) (xy 354.511864 -274.30857) (xy 354.566728 -274.229576)
			(xy 354.569776 -274.205192) (xy 354.565458 -274.193254) (xy 354.556389 -274.167387) (xy 354.546553 -274.113469)
			(xy 354.5459 -274.086066) (xy 354.546422 -274.060811) (xy 354.554735 -274.010989) (xy 354.571136 -273.963215)
			(xy 354.595177 -273.918792) (xy 354.626201 -273.878932) (xy 354.663363 -273.844722) (xy 354.705649 -273.817096)
			(xy 354.751905 -273.796806) (xy 354.80087 -273.784406) (xy 354.851208 -273.780235) (xy 354.901546 -273.784406)
			(xy 354.950511 -273.796806) (xy 354.996767 -273.817096) (xy 355.039053 -273.844722) (xy 355.076215 -273.878932)
			(xy 355.107239 -273.918792) (xy 355.13128 -273.963215) (xy 355.147681 -274.010989) (xy 355.155994 -274.060811)
			(xy 355.156516 -274.086066) (xy 355.15592 -274.113475) (xy 355.146084 -274.167403) (xy 355.136958 -274.193254)
			(xy 355.13264 -274.205192) (xy 355.135688 -274.229576) (xy 355.190552 -274.30857) (xy 355.198114 -274.318333)
			(xy 355.219885 -274.329903) (xy 355.232208 -274.330668) (xy 355.321108 -274.330668) (xy 355.340535 -274.330774)
			(xy 355.379304 -274.333319) (xy 355.398578 -274.335748) (xy 355.41204 -274.33778) (xy 355.436932 -274.32762)
			(xy 355.508052 -274.237196) (xy 355.511862 -274.21078) (xy 355.507036 -274.19808) (xy 355.497115 -274.171144)
			(xy 355.486372 -274.114763) (xy 355.4857 -274.086066) (xy 355.486222 -274.060811) (xy 355.494535 -274.010989)
			(xy 355.510936 -273.963215) (xy 355.534977 -273.918792) (xy 355.566001 -273.878932) (xy 355.603163 -273.844722)
			(xy 355.645449 -273.817096) (xy 355.691705 -273.796806) (xy 355.74067 -273.784406) (xy 355.791008 -273.780235)
			(xy 355.841346 -273.784406) (xy 355.890311 -273.796806) (xy 355.936567 -273.817096) (xy 355.978853 -273.844722)
			(xy 356.016015 -273.878932) (xy 356.047039 -273.918792) (xy 356.07108 -273.963215) (xy 356.087481 -274.010989)
			(xy 356.095794 -274.060811) (xy 356.096316 -274.086066) (xy 356.095814 -274.111463) (xy 356.087411 -274.161558)
			(xy 356.070831 -274.20957) (xy 356.046531 -274.254175) (xy 356.015182 -274.294141) (xy 355.996748 -274.311618)
			(xy 355.985064 -274.322286) (xy 355.977698 -274.35302) (xy 356.01783 -274.45589) (xy 356.021954 -274.46522)
			(xy 356.036141 -274.479856) (xy 356.054886 -274.487862) (xy 356.065074 -274.488402) (xy 356.456996 -274.488402)
			(xy 356.467207 -274.487953) (xy 356.486003 -274.479977) (xy 356.500161 -274.465262) (xy 356.50424 -274.45589)
			(xy 356.544372 -274.35302) (xy 356.537006 -274.322286) (xy 356.525322 -274.311618) (xy 356.506897 -274.294131)
			(xy 356.47555 -274.254165) (xy 356.451247 -274.209563) (xy 356.434659 -274.161554) (xy 356.426244 -274.111463)
			(xy 356.425754 -274.086066) (xy 356.426276 -274.060811) (xy 356.434589 -274.010989) (xy 356.45099 -273.963215)
			(xy 356.475031 -273.918792) (xy 356.506055 -273.878932) (xy 356.543217 -273.844722) (xy 356.585503 -273.817096)
			(xy 356.631759 -273.796806) (xy 356.680724 -273.784406) (xy 356.731062 -273.780235) (xy 356.7814 -273.784406)
			(xy 356.830365 -273.796806) (xy 356.876621 -273.817096) (xy 356.918907 -273.844722) (xy 356.956069 -273.878932)
			(xy 356.987093 -273.918792) (xy 357.011134 -273.963215) (xy 357.027535 -274.010989) (xy 357.035848 -274.060811)
			(xy 357.03637 -274.086066) (xy 357.035868 -274.111463) (xy 357.027463 -274.161556) (xy 357.010881 -274.209567)
			(xy 356.986579 -274.254169) (xy 356.955227 -274.294132) (xy 356.936802 -274.311618) (xy 356.925118 -274.322286)
			(xy 356.917752 -274.35302) (xy 356.957884 -274.45589) (xy 356.962006 -274.465225) (xy 356.97619 -274.479874)
			(xy 356.994936 -274.487896) (xy 357.005128 -274.488402) (xy 357.39705 -274.488402) (xy 357.407266 -274.487961)
			(xy 357.426078 -274.479995) (xy 357.440249 -274.46528) (xy 357.444294 -274.45589) (xy 357.484426 -274.35302)
			(xy 357.47706 -274.322286) (xy 357.465376 -274.311618) (xy 357.446954 -274.29413) (xy 357.415611 -274.254162)
			(xy 357.391312 -274.20956) (xy 357.374727 -274.161552) (xy 357.366313 -274.111462) (xy 357.365808 -274.086066)
			(xy 357.36633 -274.060811) (xy 357.374643 -274.010989) (xy 357.391044 -273.963215) (xy 357.415085 -273.918792)
			(xy 357.446109 -273.878932) (xy 357.483271 -273.844722) (xy 357.525557 -273.817096) (xy 357.571813 -273.796806)
			(xy 357.620778 -273.784406) (xy 357.671116 -273.780235) (xy 357.721454 -273.784406) (xy 357.770419 -273.796806)
			(xy 357.816675 -273.817096) (xy 357.858961 -273.844722) (xy 357.896123 -273.878932) (xy 357.927147 -273.918792)
			(xy 357.951188 -273.963215) (xy 357.967589 -274.010989) (xy 357.975902 -274.060811) (xy 357.976424 -274.086066)
			(xy 358.305366 -274.086066) (xy 358.309326 -274.037012) (xy 358.321103 -273.989228) (xy 358.340394 -273.943952)
			(xy 358.366697 -273.902356) (xy 358.399332 -273.865519) (xy 358.437453 -273.834394) (xy 358.480074 -273.809787)
			(xy 358.52609 -273.792335) (xy 358.574309 -273.782491) (xy 358.623484 -273.78051) (xy 358.672339 -273.786442)
			(xy 358.71961 -273.800134) (xy 358.764072 -273.821232) (xy 358.804575 -273.849188) (xy 358.840068 -273.88328)
			(xy 358.869633 -273.922624) (xy 358.892504 -273.966201) (xy 358.908088 -274.012882) (xy 358.915983 -274.061459)
			(xy 358.916478 -274.086066) (xy 361.118924 -274.086066) (xy 361.122884 -274.037012) (xy 361.134661 -273.989228)
			(xy 361.153952 -273.943952) (xy 361.180255 -273.902356) (xy 361.21289 -273.865519) (xy 361.251011 -273.834394)
			(xy 361.293632 -273.809787) (xy 361.339648 -273.792335) (xy 361.387867 -273.782491) (xy 361.437042 -273.78051)
			(xy 361.485897 -273.786442) (xy 361.533168 -273.800134) (xy 361.57763 -273.821232) (xy 361.618133 -273.849188)
			(xy 361.653626 -273.88328) (xy 361.683191 -273.922624) (xy 361.706062 -273.966201) (xy 361.721646 -274.012882)
			(xy 361.729541 -274.061459) (xy 361.730036 -274.086066) (xy 362.058978 -274.086066) (xy 362.062938 -274.037012)
			(xy 362.074715 -273.989228) (xy 362.094006 -273.943952) (xy 362.120309 -273.902356) (xy 362.152944 -273.865519)
			(xy 362.191065 -273.834394) (xy 362.233686 -273.809787) (xy 362.279702 -273.792335) (xy 362.327921 -273.782491)
			(xy 362.377096 -273.78051) (xy 362.425951 -273.786442) (xy 362.473222 -273.800134) (xy 362.517684 -273.821232)
			(xy 362.558187 -273.849188) (xy 362.59368 -273.88328) (xy 362.623245 -273.922624) (xy 362.646116 -273.966201)
			(xy 362.6617 -274.012882) (xy 362.669595 -274.061459) (xy 362.67009 -274.086066) (xy 362.999032 -274.086066)
			(xy 363.002992 -274.037012) (xy 363.014769 -273.989228) (xy 363.03406 -273.943952) (xy 363.060363 -273.902356)
			(xy 363.092998 -273.865519) (xy 363.131119 -273.834394) (xy 363.17374 -273.809787) (xy 363.219756 -273.792335)
			(xy 363.267975 -273.782491) (xy 363.31715 -273.78051) (xy 363.366005 -273.786442) (xy 363.413276 -273.800134)
			(xy 363.457738 -273.821232) (xy 363.498241 -273.849188) (xy 363.533734 -273.88328) (xy 363.563299 -273.922624)
			(xy 363.58617 -273.966201) (xy 363.601754 -274.012882) (xy 363.609649 -274.061459) (xy 363.610144 -274.086066)
			(xy 363.609649 -274.110673) (xy 363.601754 -274.15925) (xy 363.58617 -274.205931) (xy 363.563299 -274.249508)
			(xy 363.533734 -274.288852) (xy 363.498241 -274.322944) (xy 363.457738 -274.3509) (xy 363.413276 -274.371998)
			(xy 363.366005 -274.38569) (xy 363.31715 -274.391622) (xy 363.267975 -274.389641) (xy 363.219756 -274.379797)
			(xy 363.17374 -274.362345) (xy 363.131119 -274.337738) (xy 363.092998 -274.306613) (xy 363.060363 -274.269776)
			(xy 363.03406 -274.22818) (xy 363.014769 -274.182904) (xy 363.002992 -274.13512) (xy 362.999032 -274.086066)
			(xy 362.67009 -274.086066) (xy 362.669595 -274.110673) (xy 362.6617 -274.15925) (xy 362.646116 -274.205931)
			(xy 362.623245 -274.249508) (xy 362.59368 -274.288852) (xy 362.558187 -274.322944) (xy 362.517684 -274.3509)
			(xy 362.473222 -274.371998) (xy 362.425951 -274.38569) (xy 362.377096 -274.391622) (xy 362.327921 -274.389641)
			(xy 362.279702 -274.379797) (xy 362.233686 -274.362345) (xy 362.191065 -274.337738) (xy 362.152944 -274.306613)
			(xy 362.120309 -274.269776) (xy 362.094006 -274.22818) (xy 362.074715 -274.182904) (xy 362.062938 -274.13512)
			(xy 362.058978 -274.086066) (xy 361.730036 -274.086066) (xy 361.729541 -274.110673) (xy 361.721646 -274.15925)
			(xy 361.706062 -274.205931) (xy 361.683191 -274.249508) (xy 361.653626 -274.288852) (xy 361.618133 -274.322944)
			(xy 361.57763 -274.3509) (xy 361.533168 -274.371998) (xy 361.485897 -274.38569) (xy 361.437042 -274.391622)
			(xy 361.387867 -274.389641) (xy 361.339648 -274.379797) (xy 361.293632 -274.362345) (xy 361.251011 -274.337738)
			(xy 361.21289 -274.306613) (xy 361.180255 -274.269776) (xy 361.153952 -274.22818) (xy 361.134661 -274.182904)
			(xy 361.122884 -274.13512) (xy 361.118924 -274.086066) (xy 358.916478 -274.086066) (xy 358.915983 -274.110673)
			(xy 358.908088 -274.15925) (xy 358.892504 -274.205931) (xy 358.869633 -274.249508) (xy 358.840068 -274.288852)
			(xy 358.804575 -274.322944) (xy 358.764072 -274.3509) (xy 358.71961 -274.371998) (xy 358.672339 -274.38569)
			(xy 358.623484 -274.391622) (xy 358.574309 -274.389641) (xy 358.52609 -274.379797) (xy 358.480074 -274.362345)
			(xy 358.437453 -274.337738) (xy 358.399332 -274.306613) (xy 358.366697 -274.269776) (xy 358.340394 -274.22818)
			(xy 358.321103 -274.182904) (xy 358.309326 -274.13512) (xy 358.305366 -274.086066) (xy 357.976424 -274.086066)
			(xy 357.975922 -274.111463) (xy 357.967519 -274.161558) (xy 357.950939 -274.20957) (xy 357.92664 -274.254176)
			(xy 357.895292 -274.294143) (xy 357.876856 -274.311618) (xy 357.865172 -274.322286) (xy 357.857806 -274.35302)
			(xy 357.897938 -274.45589) (xy 357.902062 -274.46522) (xy 357.91625 -274.479853) (xy 357.934994 -274.487856)
			(xy 357.945182 -274.488402) (xy 358.255824 -274.488402) (xy 358.265892 -274.48883) (xy 358.28449 -274.49655)
			(xy 358.291892 -274.503388) (xy 358.610916 -274.822412) (xy 358.61777 -274.829807) (xy 358.625513 -274.848406)
			(xy 358.625902 -274.85848) (xy 358.625902 -275.097748) (xy 358.626334 -275.107814) (xy 358.634061 -275.126406)
			(xy 358.640888 -275.133816) (xy 358.892856 -275.385784) (xy 358.900257 -275.392624) (xy 358.918855 -275.40034)
			(xy 358.928924 -275.40077) (xy 361.424728 -275.40077) (xy 361.451654 -275.401345) (xy 361.50467 -275.410804)
		)
		(stroke
			(width 0)
			(type solid)
		)
		(fill yes)
		(layer "In11.Cu")
		(net "PVDDCR_CPU1_P0")
	)
	(gr_poly
		(pts
			(xy 102.735634 -251.268484) (xy 102.97033 -251.268484) (xy 102.979262 -251.268182) (xy 102.99606 -251.262116)
			(xy 103.009739 -251.250633) (xy 103.014526 -251.243084) (xy 103.055928 -251.170948) (xy 103.060531 -251.16196)
			(xy 103.063137 -251.141958) (xy 103.061008 -251.132086) (xy 103.057198 -251.118116) (xy 103.05415 -251.112782)
			(xy 103.042097 -251.089934) (xy 103.024996 -251.041193) (xy 103.016327 -250.990273) (xy 103.015796 -250.964446)
			(xy 103.015796 -250.956572) (xy 103.016924 -250.931743) (xy 103.026233 -250.882923) (xy 103.043324 -250.836254)
			(xy 103.067746 -250.792968) (xy 103.098854 -250.754208) (xy 103.135828 -250.720996) (xy 103.177692 -250.694209)
			(xy 103.22334 -250.674554) (xy 103.271568 -250.66255) (xy 103.321104 -250.658513) (xy 103.37064 -250.66255)
			(xy 103.418868 -250.674554) (xy 103.464516 -250.694209) (xy 103.50638 -250.720996) (xy 103.543354 -250.754208)
			(xy 103.574462 -250.792968) (xy 103.598884 -250.836254) (xy 103.615975 -250.882923) (xy 103.625284 -250.931743)
			(xy 103.626412 -250.956572) (xy 103.626412 -250.961398) (xy 103.626412 -250.964446) (xy 103.625899 -250.990276)
			(xy 103.61725 -251.041205) (xy 103.600141 -251.089947) (xy 103.588058 -251.112782) (xy 103.58501 -251.118116)
			(xy 103.5812 -251.132086) (xy 103.578941 -251.141949) (xy 103.581565 -251.161995) (xy 103.58628 -251.170948)
			(xy 103.627682 -251.243084) (xy 103.632452 -251.250639) (xy 103.646153 -251.26209) (xy 103.662949 -251.268151)
			(xy 103.671878 -251.268484) (xy 104.850184 -251.268484) (xy 104.85912 -251.26819) (xy 104.87593 -251.262134)
			(xy 104.889622 -251.250654) (xy 104.89438 -251.243084) (xy 104.935782 -251.170948) (xy 104.940381 -251.161959)
			(xy 104.942985 -251.141958) (xy 104.940862 -251.132086) (xy 104.937052 -251.118116) (xy 104.934004 -251.112782)
			(xy 104.921953 -251.089933) (xy 104.904855 -251.041193) (xy 104.896187 -250.990272) (xy 104.89565 -250.964446)
			(xy 104.89565 -250.956572) (xy 104.896778 -250.931743) (xy 104.906087 -250.882923) (xy 104.923178 -250.836254)
			(xy 104.9476 -250.792968) (xy 104.978708 -250.754208) (xy 105.015682 -250.720996) (xy 105.057546 -250.694209)
			(xy 105.103194 -250.674554) (xy 105.151422 -250.66255) (xy 105.200958 -250.658513) (xy 105.250494 -250.66255)
			(xy 105.298722 -250.674554) (xy 105.34437 -250.694209) (xy 105.386234 -250.720996) (xy 105.423208 -250.754208)
			(xy 105.454316 -250.792968) (xy 105.478738 -250.836254) (xy 105.495829 -250.882923) (xy 105.505138 -250.931743)
			(xy 105.506266 -250.956572) (xy 105.506266 -250.961398) (xy 105.506266 -250.964446) (xy 105.505753 -250.990276)
			(xy 105.497103 -251.041204) (xy 105.479991 -251.089945) (xy 105.467912 -251.112782) (xy 105.464864 -251.118116)
			(xy 105.461054 -251.132086) (xy 105.458794 -251.141949) (xy 105.46142 -251.161994) (xy 105.466134 -251.170948)
			(xy 105.507536 -251.243084) (xy 105.512303 -251.250644) (xy 105.526002 -251.262108) (xy 105.5428 -251.268184)
			(xy 105.551732 -251.268484) (xy 106.730292 -251.268484) (xy 106.739227 -251.268188) (xy 106.756035 -251.262131)
			(xy 106.769725 -251.25065) (xy 106.774488 -251.243084) (xy 106.81589 -251.170948) (xy 106.820488 -251.161959)
			(xy 106.823092 -251.141958) (xy 106.82097 -251.132086) (xy 106.81716 -251.118116) (xy 106.814112 -251.112782)
			(xy 106.80206 -251.089934) (xy 106.784962 -251.041193) (xy 106.776294 -250.990273) (xy 106.775758 -250.964446)
			(xy 106.775758 -250.956572) (xy 106.776886 -250.931743) (xy 106.786195 -250.882923) (xy 106.803286 -250.836254)
			(xy 106.827708 -250.792968) (xy 106.858816 -250.754208) (xy 106.89579 -250.720996) (xy 106.937654 -250.694209)
			(xy 106.983302 -250.674554) (xy 107.03153 -250.66255) (xy 107.081066 -250.658513) (xy 107.130602 -250.66255)
			(xy 107.17883 -250.674554) (xy 107.224478 -250.694209) (xy 107.266342 -250.720996) (xy 107.303316 -250.754208)
			(xy 107.334424 -250.792968) (xy 107.358846 -250.836254) (xy 107.375937 -250.882923) (xy 107.385246 -250.931743)
			(xy 107.386374 -250.956572) (xy 107.386374 -250.961398) (xy 107.386374 -250.964446) (xy 107.385861 -250.990276)
			(xy 107.377211 -251.041204) (xy 107.3601 -251.089946) (xy 107.34802 -251.112782) (xy 107.344972 -251.118116)
			(xy 107.341162 -251.132086) (xy 107.338902 -251.141949) (xy 107.341528 -251.161994) (xy 107.346242 -251.170948)
			(xy 107.387644 -251.243084) (xy 107.392412 -251.250643) (xy 107.406111 -251.262105) (xy 107.422908 -251.268178)
			(xy 107.43184 -251.268484) (xy 108.34497 -251.268484) (xy 108.354807 -251.267948) (xy 108.372967 -251.260359)
			(xy 108.380276 -251.253752) (xy 108.647992 -250.986036) (xy 108.655612 -250.968256) (xy 108.655866 -250.958096)
			(xy 108.656925 -250.932119) (xy 108.666781 -250.881076) (xy 108.685136 -250.832438) (xy 108.711459 -250.787609)
			(xy 108.744992 -250.747884) (xy 108.784765 -250.714408) (xy 108.829631 -250.688148) (xy 108.878295 -250.669863)
			(xy 108.929352 -250.660079) (xy 108.955332 -250.659138) (xy 108.965238 -250.658884) (xy 108.990892 -250.647962)
			(xy 108.99648 -250.642628) (xy 109.006132 -250.638564) (xy 109.214158 -250.638564) (xy 109.223998 -250.638032)
			(xy 109.242168 -250.630455) (xy 109.249464 -250.623832) (xy 109.297724 -250.575572) (xy 109.305608 -250.566931)
			(xy 109.313144 -250.544815) (xy 109.312202 -250.533154) (xy 109.300518 -250.443746) (xy 109.287818 -250.424442)
			(xy 109.277404 -250.418346) (xy 109.254747 -250.404463) (xy 109.214176 -250.370156) (xy 109.180145 -250.329353)
			(xy 109.153676 -250.283284) (xy 109.135566 -250.233334) (xy 109.126361 -250.181006) (xy 109.125766 -250.15444)
			(xy 109.126209 -250.130444) (xy 109.133711 -250.083042) (xy 109.148535 -250.037398) (xy 109.170318 -249.994634)
			(xy 109.198523 -249.955805) (xy 109.232454 -249.921866) (xy 109.271278 -249.893653) (xy 109.314036 -249.871861)
			(xy 109.359678 -249.857026) (xy 109.407078 -249.849514) (xy 109.431074 -249.849132) (xy 109.45714 -249.84966)
			(xy 109.508514 -249.858512) (xy 109.557637 -249.875962) (xy 109.603082 -249.901504) (xy 109.643528 -249.934395)
			(xy 109.677798 -249.973679) (xy 109.704896 -250.018214) (xy 109.724035 -250.066704) (xy 109.734658 -250.117742)
			(xy 109.736128 -250.143772) (xy 109.736382 -250.14936) (xy 109.736382 -250.15444) (xy 109.735897 -250.178884)
			(xy 109.728099 -250.227145) (xy 109.71271 -250.273548) (xy 109.690123 -250.316904) (xy 109.67593 -250.336812)
			(xy 109.667294 -250.34875) (xy 109.664754 -250.376944) (xy 109.710982 -250.469146) (xy 109.715563 -250.477385)
			(xy 109.729474 -250.490081) (xy 109.747031 -250.496899) (xy 109.756448 -250.49734) (xy 112.859312 -250.49734)
			(xy 112.868739 -250.49696) (xy 112.886316 -250.490136) (xy 112.900234 -250.477416) (xy 112.904778 -250.469146)
			(xy 112.951006 -250.376944) (xy 112.948466 -250.34875) (xy 112.93983 -250.336812) (xy 112.925613 -250.31692)
			(xy 112.903026 -250.273558) (xy 112.887638 -250.227152) (xy 112.87984 -250.178886) (xy 112.879378 -250.15444)
			(xy 112.879378 -250.14936) (xy 112.879632 -250.143772) (xy 112.88097 -250.119115) (xy 112.890616 -250.070688)
			(xy 112.907932 -250.024445) (xy 112.932465 -249.981593) (xy 112.963576 -249.943248) (xy 113.000454 -249.910412)
			(xy 113.042136 -249.883939) (xy 113.087536 -249.864521) (xy 113.135469 -249.852664) (xy 113.184686 -249.848677)
			(xy 113.233903 -249.852664) (xy 113.281836 -249.864521) (xy 113.327236 -249.883939) (xy 113.368918 -249.910412)
			(xy 113.405796 -249.943248) (xy 113.436907 -249.981593) (xy 113.46144 -250.024445) (xy 113.478756 -250.070688)
			(xy 113.488402 -250.119115) (xy 113.48974 -250.143772) (xy 113.489994 -250.14936) (xy 113.489994 -250.15444)
			(xy 113.489509 -250.178884) (xy 113.481712 -250.227146) (xy 113.466323 -250.273548) (xy 113.443736 -250.316905)
			(xy 113.429542 -250.336812) (xy 113.420906 -250.34875) (xy 113.418366 -250.376944) (xy 113.464594 -250.4694)
			(xy 113.46914 -250.477645) (xy 113.48308 -250.490282) (xy 113.500651 -250.497009) (xy 113.51006 -250.49734)
			(xy 113.956084 -250.49734) (xy 114.73942 -250.49734) (xy 114.748847 -250.496959) (xy 114.766421 -250.490133)
			(xy 114.780337 -250.477412) (xy 114.784886 -250.469146) (xy 114.831114 -250.376944) (xy 114.828574 -250.34875)
			(xy 114.819938 -250.336812) (xy 114.80572 -250.31692) (xy 114.783133 -250.273559) (xy 114.767744 -250.227152)
			(xy 114.759947 -250.178886) (xy 114.759486 -250.15444) (xy 114.759486 -250.14936) (xy 114.75974 -250.143772)
			(xy 114.761185 -250.117744) (xy 114.771833 -250.066718) (xy 114.790989 -250.01824) (xy 114.818097 -249.973717)
			(xy 114.85237 -249.934443) (xy 114.892812 -249.901558) (xy 114.938251 -249.876015) (xy 114.987366 -249.858557)
			(xy 115.038731 -249.84969) (xy 115.064794 -249.849132) (xy 115.088786 -249.849578) (xy 115.13618 -249.857084)
			(xy 115.181816 -249.871913) (xy 115.22457 -249.893698) (xy 115.263389 -249.921904) (xy 115.297318 -249.955837)
			(xy 115.32552 -249.994659) (xy 115.3473 -250.037415) (xy 115.362124 -250.083053) (xy 115.369625 -250.130448)
			(xy 115.370102 -250.15444) (xy 116.638844 -250.15444) (xy 116.642804 -250.105386) (xy 116.654581 -250.057602)
			(xy 116.673872 -250.012326) (xy 116.700175 -249.97073) (xy 116.73281 -249.933893) (xy 116.770931 -249.902768)
			(xy 116.813552 -249.878161) (xy 116.859568 -249.860709) (xy 116.907787 -249.850865) (xy 116.956962 -249.848884)
			(xy 117.005817 -249.854816) (xy 117.053088 -249.868508) (xy 117.09755 -249.889606) (xy 117.138053 -249.917562)
			(xy 117.173546 -249.951654) (xy 117.203111 -249.990998) (xy 117.225982 -250.034575) (xy 117.241566 -250.081256)
			(xy 117.249461 -250.129833) (xy 117.249956 -250.15444) (xy 117.249461 -250.179047) (xy 117.241566 -250.227624)
			(xy 117.225982 -250.274305) (xy 117.203111 -250.317882) (xy 117.173546 -250.357226) (xy 117.138053 -250.391318)
			(xy 117.09755 -250.419274) (xy 117.053088 -250.440372) (xy 117.005817 -250.454064) (xy 116.956962 -250.459996)
			(xy 116.907787 -250.458015) (xy 116.859568 -250.448171) (xy 116.813552 -250.430719) (xy 116.770931 -250.406112)
			(xy 116.73281 -250.374987) (xy 116.700175 -250.33815) (xy 116.673872 -250.296554) (xy 116.654581 -250.251278)
			(xy 116.642804 -250.203494) (xy 116.638844 -250.15444) (xy 115.370102 -250.15444) (xy 115.369623 -250.178922)
			(xy 115.36182 -250.227259) (xy 115.346405 -250.273732) (xy 115.323774 -250.31715) (xy 115.294504 -250.356402)
			(xy 115.259347 -250.39048) (xy 115.239546 -250.404884) (xy 115.229386 -250.411996) (xy 115.217956 -250.43384)
			(xy 115.217956 -250.44654) (xy 115.21845 -250.456546) (xy 115.226115 -250.475031) (xy 115.240265 -250.489182)
			(xy 115.25875 -250.496849) (xy 115.268756 -250.49734) (xy 115.28171 -250.49734) (xy 115.323874 -250.49734)
			(xy 115.333712 -250.497875) (xy 115.351878 -250.505456) (xy 115.35918 -250.512072) (xy 115.385088 -250.537726)
			(xy 115.385596 -250.538234) (xy 115.389152 -250.54179) (xy 115.407948 -250.560586) (xy 115.410488 -250.563126)
			(xy 115.410996 -250.563634) (xy 115.471194 -250.623832) (xy 115.478605 -250.630514) (xy 115.497041 -250.638093)
			(xy 115.507008 -250.638564) (xy 115.57889 -250.638564) (xy 115.588727 -250.639103) (xy 115.606886 -250.646691)
			(xy 115.614196 -250.653296) (xy 115.637818 -250.676918) (xy 115.64747 -250.680728) (xy 115.6704 -250.690371)
			(xy 115.713031 -250.715996) (xy 115.750943 -250.748193) (xy 115.783134 -250.786112) (xy 115.808752 -250.828747)
			(xy 115.818412 -250.85167) (xy 115.822222 -250.861322) (xy 116.219478 -251.258578) (xy 116.22688 -251.265415)
			(xy 116.245478 -251.273124) (xy 116.255546 -251.273564) (xy 116.84889 -251.273564) (xy 116.858727 -251.273026)
			(xy 116.876889 -251.265441) (xy 116.884196 -251.258832) (xy 117.097556 -251.045472) (xy 117.104826 -251.037441)
			(xy 117.112458 -251.017187) (xy 117.112288 -251.006356) (xy 117.112034 -251.00407) (xy 117.11178 -251.002546)
			(xy 117.110685 -250.993059) (xy 117.109541 -250.973995) (xy 117.109494 -250.964446) (xy 117.109937 -250.940451)
			(xy 117.117438 -250.89305) (xy 117.132262 -250.847406) (xy 117.154045 -250.804644) (xy 117.18225 -250.765816)
			(xy 117.216182 -250.731879) (xy 117.255006 -250.703668) (xy 117.297765 -250.681879) (xy 117.343407 -250.667048)
			(xy 117.390807 -250.65954) (xy 117.414802 -250.659138) (xy 117.424482 -250.659238) (xy 117.443801 -250.660507)
			(xy 117.45341 -250.661678) (xy 117.465348 -250.663202) (xy 117.487446 -250.655582) (xy 117.743732 -250.399296)
			(xy 117.750971 -250.392585) (xy 117.769176 -250.384997) (xy 117.779038 -250.384564) (xy 118.440708 -250.384564)
			(xy 118.452798 -250.383815) (xy 118.474263 -250.372668) (xy 118.481856 -250.363228) (xy 118.535704 -250.28779)
			(xy 118.53926 -250.26366) (xy 118.53545 -250.251976) (xy 118.527975 -250.228288) (xy 118.51993 -250.179275)
			(xy 118.519448 -250.15444) (xy 118.51997 -250.129185) (xy 118.528283 -250.079363) (xy 118.544684 -250.031589)
			(xy 118.568725 -249.987166) (xy 118.599749 -249.947306) (xy 118.636911 -249.913096) (xy 118.679197 -249.88547)
			(xy 118.725453 -249.86518) (xy 118.774418 -249.85278) (xy 118.824756 -249.848609) (xy 118.875094 -249.85278)
			(xy 118.924059 -249.86518) (xy 118.970315 -249.88547) (xy 119.012601 -249.913096) (xy 119.049763 -249.947306)
			(xy 119.080787 -249.987166) (xy 119.104828 -250.031589) (xy 119.121229 -250.079363) (xy 119.129542 -250.129185)
			(xy 119.130064 -250.15444) (xy 120.398806 -250.15444) (xy 120.402766 -250.105386) (xy 120.414543 -250.057602)
			(xy 120.433834 -250.012326) (xy 120.460137 -249.97073) (xy 120.492772 -249.933893) (xy 120.530893 -249.902768)
			(xy 120.573514 -249.878161) (xy 120.61953 -249.860709) (xy 120.667749 -249.850865) (xy 120.716924 -249.848884)
			(xy 120.765779 -249.854816) (xy 120.81305 -249.868508) (xy 120.857512 -249.889606) (xy 120.898015 -249.917562)
			(xy 120.933508 -249.951654) (xy 120.963073 -249.990998) (xy 120.985944 -250.034575) (xy 121.001528 -250.081256)
			(xy 121.009423 -250.129833) (xy 121.009918 -250.15444) (xy 121.009423 -250.179047) (xy 121.001528 -250.227624)
			(xy 120.985944 -250.274305) (xy 120.963073 -250.317882) (xy 120.933508 -250.357226) (xy 120.898015 -250.391318)
			(xy 120.857512 -250.419274) (xy 120.81305 -250.440372) (xy 120.765779 -250.454064) (xy 120.716924 -250.459996)
			(xy 120.667749 -250.458015) (xy 120.61953 -250.448171) (xy 120.573514 -250.430719) (xy 120.530893 -250.406112)
			(xy 120.492772 -250.374987) (xy 120.460137 -250.33815) (xy 120.433834 -250.296554) (xy 120.414543 -250.251278)
			(xy 120.402766 -250.203494) (xy 120.398806 -250.15444) (xy 119.130064 -250.15444) (xy 119.130064 -250.161298)
			(xy 119.129144 -250.183967) (xy 119.121432 -250.228673) (xy 119.107187 -250.271746) (xy 119.086725 -250.312235)
			(xy 119.07393 -250.33097) (xy 119.069612 -250.337066) (xy 119.0625 -250.358148) (xy 119.061137 -250.36259)
			(xy 119.05986 -250.371791) (xy 119.05996 -250.376436) (xy 119.060976 -250.39828) (xy 119.061774 -250.407657)
			(xy 119.069349 -250.424869) (xy 119.075708 -250.431808) (xy 119.283226 -250.639326) (xy 119.286426 -250.642417)
			(xy 119.293711 -250.647523) (xy 119.297704 -250.649486) (xy 119.320564 -250.6599) (xy 119.328692 -250.660916)
			(xy 119.354212 -250.66431) (xy 119.403685 -250.678537) (xy 119.450073 -250.700857) (xy 119.492061 -250.73064)
			(xy 119.528462 -250.76704) (xy 119.558244 -250.809029) (xy 119.580564 -250.855417) (xy 119.59479 -250.90489)
			(xy 119.598186 -250.93041) (xy 119.599202 -250.938538) (xy 119.609616 -250.961398) (xy 119.611594 -250.965382)
			(xy 119.616699 -250.972665) (xy 119.619776 -250.975876) (xy 119.902478 -251.258578) (xy 119.90988 -251.265415)
			(xy 119.928478 -251.273124) (xy 119.938546 -251.273564) (xy 120.53189 -251.273564) (xy 120.541727 -251.273026)
			(xy 120.559889 -251.265441) (xy 120.567196 -251.258832) (xy 120.849644 -250.976384) (xy 120.852735 -250.973184)
			(xy 120.85784 -250.965899) (xy 120.859804 -250.961906) (xy 120.870218 -250.939046) (xy 120.871234 -250.930918)
			(xy 120.874597 -250.905333) (xy 120.888792 -250.855724) (xy 120.911123 -250.809206) (xy 120.940952 -250.767103)
			(xy 120.977434 -250.730611) (xy 121.019528 -250.700769) (xy 121.066039 -250.678425) (xy 121.115644 -250.664214)
			(xy 121.141236 -250.660916) (xy 121.149364 -250.6599) (xy 121.172224 -250.649486) (xy 121.176207 -250.647506)
			(xy 121.183487 -250.6424) (xy 121.186702 -250.639326) (xy 121.426732 -250.399296) (xy 121.433971 -250.392585)
			(xy 121.452176 -250.384997) (xy 121.462038 -250.384564) (xy 122.20067 -250.384564) (xy 122.212764 -250.383823)
			(xy 122.234243 -250.372685) (xy 122.241818 -250.363228) (xy 122.295666 -250.28779) (xy 122.299222 -250.26366)
			(xy 122.295412 -250.251976) (xy 122.287938 -250.228288) (xy 122.279894 -250.179274) (xy 122.27941 -250.15444)
			(xy 122.279853 -250.130445) (xy 122.287355 -250.083046) (xy 122.30218 -250.037404) (xy 122.323964 -249.994644)
			(xy 122.352169 -249.955818) (xy 122.386101 -249.921883) (xy 122.424925 -249.893675) (xy 122.467684 -249.871889)
			(xy 122.513325 -249.85706) (xy 122.560723 -249.849555) (xy 122.584718 -249.849132) (xy 122.608418 -249.849581)
			(xy 122.655249 -249.856908) (xy 122.700386 -249.871384) (xy 122.742743 -249.89266) (xy 122.781305 -249.920225)
			(xy 122.815143 -249.953418) (xy 122.843447 -249.991441) (xy 122.865535 -250.033381) (xy 122.880877 -250.07823)
			(xy 122.889105 -250.124911) (xy 122.890026 -250.148598) (xy 122.890026 -250.15444) (xy 124.159022 -250.15444)
			(xy 124.162982 -250.105386) (xy 124.174759 -250.057602) (xy 124.19405 -250.012326) (xy 124.220353 -249.97073)
			(xy 124.252988 -249.933893) (xy 124.291109 -249.902768) (xy 124.33373 -249.878161) (xy 124.379746 -249.860709)
			(xy 124.427965 -249.850865) (xy 124.47714 -249.848884) (xy 124.525995 -249.854816) (xy 124.573266 -249.868508)
			(xy 124.617728 -249.889606) (xy 124.658231 -249.917562) (xy 124.693724 -249.951654) (xy 124.723289 -249.990998)
			(xy 124.74616 -250.034575) (xy 124.761744 -250.081256) (xy 124.769639 -250.129833) (xy 124.770134 -250.15444)
			(xy 124.769639 -250.179047) (xy 124.761744 -250.227624) (xy 124.74616 -250.274305) (xy 124.723289 -250.317882)
			(xy 124.693724 -250.357226) (xy 124.658231 -250.391318) (xy 124.617728 -250.419274) (xy 124.573266 -250.440372)
			(xy 124.525995 -250.454064) (xy 124.47714 -250.459996) (xy 124.427965 -250.458015) (xy 124.379746 -250.448171)
			(xy 124.33373 -250.430719) (xy 124.291109 -250.406112) (xy 124.252988 -250.374987) (xy 124.220353 -250.33815)
			(xy 124.19405 -250.296554) (xy 124.174759 -250.251278) (xy 124.162982 -250.203494) (xy 124.159022 -250.15444)
			(xy 122.890026 -250.15444) (xy 122.890026 -250.154694) (xy 122.889448 -250.182128) (xy 122.879647 -250.236112)
			(xy 122.860359 -250.287477) (xy 122.832205 -250.33457) (xy 122.814588 -250.355608) (xy 122.808238 -250.362974)
			(xy 122.801634 -250.381008) (xy 122.804428 -250.458224) (xy 122.805164 -250.467729) (xy 122.812747 -250.485204)
			(xy 122.81916 -250.49226) (xy 122.982482 -250.655582) (xy 123.004326 -250.662948) (xy 123.016264 -250.661678)
			(xy 123.02581 -250.66051) (xy 123.045001 -250.659235) (xy 123.054618 -250.659138) (xy 123.078609 -250.659586)
			(xy 123.126 -250.667095) (xy 123.171632 -250.681926) (xy 123.214382 -250.703713) (xy 123.253198 -250.731919)
			(xy 123.287122 -250.765851) (xy 123.315321 -250.804673) (xy 123.337099 -250.847427) (xy 123.35192 -250.893063)
			(xy 123.359419 -250.940455) (xy 123.359926 -250.964446) (xy 123.359819 -250.974062) (xy 123.358549 -250.993254)
			(xy 123.357386 -251.0028) (xy 123.356116 -251.014738) (xy 123.363482 -251.036582) (xy 123.458478 -251.131578)
			(xy 123.46588 -251.138415) (xy 123.484478 -251.146124) (xy 123.494546 -251.146564) (xy 124.535946 -251.146564)
			(xy 124.547189 -251.145988) (xy 124.567508 -251.136368) (xy 124.575062 -251.128022) (xy 124.632212 -251.058172)
			(xy 124.6378 -251.036328) (xy 124.635514 -251.024898) (xy 124.632673 -251.009946) (xy 124.629619 -250.979664)
			(xy 124.629418 -250.964446) (xy 124.629861 -250.940451) (xy 124.637362 -250.893052) (xy 124.652187 -250.84741)
			(xy 124.67397 -250.804649) (xy 124.702175 -250.765823) (xy 124.736108 -250.731888) (xy 124.774932 -250.703681)
			(xy 124.817691 -250.681894) (xy 124.863332 -250.667067) (xy 124.910731 -250.659562) (xy 124.934726 -250.659138)
			(xy 124.960257 -250.659657) (xy 125.010607 -250.668163) (xy 125.058837 -250.684934) (xy 125.103602 -250.709501)
			(xy 125.123956 -250.724924) (xy 125.13945 -250.737116) (xy 125.17755 -250.73483) (xy 126.5047 -249.40768)
			(xy 126.51232 -249.386598) (xy 126.51105 -249.374914) (xy 126.509526 -249.344434) (xy 126.510122 -249.31676)
			(xy 126.520082 -249.262316) (xy 126.529338 -249.23623) (xy 126.53264 -249.227594) (xy 126.53264 -247.841262)
			(xy 126.529338 -247.832626) (xy 126.520089 -247.806536) (xy 126.510113 -247.752095) (xy 126.510109 -247.696746)
			(xy 126.520078 -247.642303) (xy 126.529338 -247.616218) (xy 126.53264 -247.607582) (xy 126.53264 -247.311926)
			(xy 126.532024 -247.300603) (xy 126.522246 -247.280177) (xy 126.513844 -247.272556) (xy 126.443232 -247.21566)
			(xy 126.42088 -247.210326) (xy 126.40945 -247.212866) (xy 126.393452 -247.216087) (xy 126.360998 -247.219526)
			(xy 126.34468 -247.219724) (xy 126.319424 -247.219201) (xy 126.269603 -247.210884) (xy 126.221829 -247.194481)
			(xy 126.177407 -247.170438) (xy 126.137548 -247.139412) (xy 126.103339 -247.102248) (xy 126.075713 -247.059962)
			(xy 126.055423 -247.013704) (xy 126.043024 -246.964739) (xy 126.038853 -246.9144) (xy 126.043024 -246.864061)
			(xy 126.055423 -246.815096) (xy 126.075713 -246.768838) (xy 126.103339 -246.726552) (xy 126.137548 -246.689388)
			(xy 126.177407 -246.658362) (xy 126.221829 -246.634319) (xy 126.269603 -246.617916) (xy 126.319424 -246.609599)
			(xy 126.34468 -246.609108) (xy 126.360999 -246.60929) (xy 126.393456 -246.612722) (xy 126.40945 -246.615966)
			(xy 126.42088 -246.618506) (xy 126.443232 -246.613172) (xy 126.513844 -246.556276) (xy 126.522244 -246.54866)
			(xy 126.532004 -246.528226) (xy 126.53264 -246.516906) (xy 126.53264 -246.22125) (xy 126.529338 -246.212614)
			(xy 126.52009 -246.186524) (xy 126.510116 -246.132083) (xy 126.510115 -246.076736) (xy 126.520085 -246.022294)
			(xy 126.529338 -245.996206) (xy 126.53264 -245.98757) (xy 126.53264 -244.601238) (xy 126.529338 -244.592602)
			(xy 126.520091 -244.566512) (xy 126.510119 -244.512071) (xy 126.51012 -244.456725) (xy 126.520092 -244.402284)
			(xy 126.529338 -244.376194) (xy 126.53264 -244.367558) (xy 126.53264 -244.071902) (xy 126.532039 -244.060571)
			(xy 126.52228 -244.04012) (xy 126.513844 -244.032532) (xy 126.443232 -243.975636) (xy 126.42088 -243.970302)
			(xy 126.40945 -243.972842) (xy 126.393452 -243.976063) (xy 126.360998 -243.979503) (xy 126.34468 -243.9797)
			(xy 126.319426 -243.979177) (xy 126.269609 -243.970861) (xy 126.221839 -243.954459) (xy 126.17742 -243.930418)
			(xy 126.137564 -243.899394) (xy 126.103358 -243.862234) (xy 126.075734 -243.81995) (xy 126.055446 -243.773697)
			(xy 126.043048 -243.724735) (xy 126.038877 -243.6744) (xy 126.043048 -243.624065) (xy 126.055446 -243.575103)
			(xy 126.075734 -243.52885) (xy 126.103358 -243.486566) (xy 126.137564 -243.449406) (xy 126.17742 -243.418382)
			(xy 126.221839 -243.394341) (xy 126.269609 -243.377939) (xy 126.319426 -243.369623) (xy 126.34468 -243.369084)
			(xy 126.360999 -243.369266) (xy 126.393455 -243.372699) (xy 126.40945 -243.375942) (xy 126.42088 -243.378482)
			(xy 126.443232 -243.373148) (xy 126.513844 -243.316252) (xy 126.52224 -243.308635) (xy 126.53199 -243.2882)
			(xy 126.53264 -243.276882) (xy 126.53264 -242.981226) (xy 126.529338 -242.97259) (xy 126.520092 -242.946501)
			(xy 126.510123 -242.89206) (xy 126.510125 -242.836714) (xy 126.520099 -242.782274) (xy 126.529338 -242.756182)
			(xy 126.53264 -242.747546) (xy 126.53264 -241.361214) (xy 126.529338 -241.352578) (xy 126.520093 -241.326489)
			(xy 126.510126 -241.272048) (xy 126.51013 -241.216703) (xy 126.520106 -241.162265) (xy 126.529338 -241.13617)
			(xy 126.53264 -241.127534) (xy 126.53264 -240.831878) (xy 126.532034 -240.820549) (xy 126.522269 -240.800106)
			(xy 126.513844 -240.792508) (xy 126.443232 -240.735612) (xy 126.42088 -240.730278) (xy 126.40945 -240.732818)
			(xy 126.393452 -240.736039) (xy 126.360998 -240.739479) (xy 126.34468 -240.739676) (xy 126.319428 -240.739153)
			(xy 126.269614 -240.730837) (xy 126.221848 -240.714437) (xy 126.177433 -240.690398) (xy 126.13758 -240.659376)
			(xy 126.103376 -240.622219) (xy 126.075755 -240.579939) (xy 126.055469 -240.533689) (xy 126.043071 -240.484731)
			(xy 126.038901 -240.4344) (xy 126.043071 -240.384069) (xy 126.055469 -240.335111) (xy 126.075755 -240.288861)
			(xy 126.103376 -240.246581) (xy 126.13758 -240.209424) (xy 126.177433 -240.178402) (xy 126.221848 -240.154363)
			(xy 126.269614 -240.137963) (xy 126.319428 -240.129647) (xy 126.34468 -240.12906) (xy 126.360999 -240.129242)
			(xy 126.393455 -240.132675) (xy 126.40945 -240.135918) (xy 126.42088 -240.138458) (xy 126.443232 -240.133124)
			(xy 126.513844 -240.076228) (xy 126.522236 -240.068609) (xy 126.531977 -240.048175) (xy 126.53264 -240.036858)
			(xy 126.53264 -239.741202) (xy 126.529338 -239.732566) (xy 126.520094 -239.706477) (xy 126.510129 -239.652037)
			(xy 126.510136 -239.596692) (xy 126.520113 -239.542255) (xy 126.529338 -239.516158) (xy 126.53264 -239.507522)
			(xy 126.53264 -238.603282) (xy 126.532212 -238.593215) (xy 126.524486 -238.574621) (xy 126.517654 -238.567214)
			(xy 126.181612 -238.231172) (xy 126.174164 -238.22428) (xy 126.15543 -238.216528) (xy 126.14529 -238.216186)
			(xy 126.114556 -238.21644) (xy 126.10518 -238.216972) (xy 126.087736 -238.223889) (xy 126.08052 -238.229902)
			(xy 126.063556 -238.244821) (xy 126.026058 -238.270012) (xy 125.985258 -238.289405) (xy 125.942047 -238.302578)
			(xy 125.897367 -238.309243) (xy 125.87478 -238.309658) (xy 125.850788 -238.309186) (xy 125.803396 -238.301678)
			(xy 125.757762 -238.286849) (xy 125.715008 -238.265065) (xy 125.676188 -238.236862) (xy 125.642257 -238.202935)
			(xy 125.61405 -238.164118) (xy 125.592262 -238.121366) (xy 125.577429 -238.075733) (xy 125.569916 -238.028342)
			(xy 125.569472 -238.00435) (xy 125.569953 -237.979852) (xy 125.577767 -237.931484) (xy 125.593202 -237.884983)
			(xy 125.615863 -237.841543) (xy 125.645168 -237.802277) (xy 125.662436 -237.784894) (xy 125.66269 -237.78464)
			(xy 125.662944 -237.784386) (xy 125.669666 -237.77695) (xy 125.677314 -237.758444) (xy 125.677327 -237.738419)
			(xy 125.669702 -237.719904) (xy 125.662944 -237.712504) (xy 125.456442 -237.506002) (xy 125.435868 -237.498128)
			(xy 125.424946 -237.49889) (xy 125.404626 -237.499652) (xy 125.380202 -237.499167) (xy 125.331978 -237.491384)
			(xy 125.285606 -237.476027) (xy 125.242269 -237.453488) (xy 125.203069 -237.424341) (xy 125.169006 -237.389329)
			(xy 125.140947 -237.349343) (xy 125.119607 -237.305403) (xy 125.105531 -237.258627) (xy 125.101858 -237.234476)
			(xy 125.099572 -237.215426) (xy 125.070616 -237.19028) (xy 124.798836 -237.19028) (xy 124.76988 -237.215426)
			(xy 124.767594 -237.234476) (xy 124.763908 -237.258631) (xy 124.749858 -237.305428) (xy 124.728536 -237.349391)
			(xy 124.700488 -237.389399) (xy 124.666427 -237.424431) (xy 124.627223 -237.453593) (xy 124.583877 -237.476141)
			(xy 124.537494 -237.491501) (xy 124.489256 -237.49928) (xy 124.440396 -237.49928) (xy 124.392158 -237.491501)
			(xy 124.345775 -237.476141) (xy 124.302429 -237.453593) (xy 124.263225 -237.424431) (xy 124.229164 -237.389399)
			(xy 124.201116 -237.349391) (xy 124.179794 -237.305428) (xy 124.165744 -237.258631) (xy 124.162058 -237.234476)
			(xy 124.159772 -237.215426) (xy 124.130816 -237.19028) (xy 123.858782 -237.19028) (xy 123.829826 -237.215426)
			(xy 123.82754 -237.234476) (xy 123.823854 -237.258631) (xy 123.809804 -237.305428) (xy 123.788482 -237.349391)
			(xy 123.760434 -237.389399) (xy 123.726373 -237.424431) (xy 123.687169 -237.453593) (xy 123.643823 -237.476141)
			(xy 123.59744 -237.491501) (xy 123.549202 -237.49928) (xy 123.500342 -237.49928) (xy 123.452104 -237.491501)
			(xy 123.405721 -237.476141) (xy 123.362375 -237.453593) (xy 123.323171 -237.424431) (xy 123.28911 -237.389399)
			(xy 123.261062 -237.349391) (xy 123.23974 -237.305428) (xy 123.22569 -237.258631) (xy 123.222004 -237.234476)
			(xy 123.219718 -237.215426) (xy 123.190762 -237.19028) (xy 122.918728 -237.19028) (xy 122.889772 -237.215426)
			(xy 122.887486 -237.234476) (xy 122.8838 -237.258631) (xy 122.86975 -237.305428) (xy 122.848428 -237.349391)
			(xy 122.82038 -237.389399) (xy 122.786319 -237.424431) (xy 122.747115 -237.453593) (xy 122.703769 -237.476141)
			(xy 122.657386 -237.491501) (xy 122.609148 -237.49928) (xy 122.560288 -237.49928) (xy 122.51205 -237.491501)
			(xy 122.465667 -237.476141) (xy 122.422321 -237.453593) (xy 122.383117 -237.424431) (xy 122.349056 -237.389399)
			(xy 122.321008 -237.349391) (xy 122.299686 -237.305428) (xy 122.285636 -237.258631) (xy 122.28195 -237.234476)
			(xy 122.279664 -237.215426) (xy 122.250708 -237.19028) (xy 121.978674 -237.19028) (xy 121.949718 -237.215426)
			(xy 121.947432 -237.234476) (xy 121.943755 -237.258632) (xy 121.929718 -237.305432) (xy 121.908403 -237.349398)
			(xy 121.880355 -237.389405) (xy 121.846291 -237.424432) (xy 121.807081 -237.453584) (xy 121.763726 -237.476115)
			(xy 121.717336 -237.491451) (xy 121.669094 -237.499199) (xy 121.644664 -237.499652) (xy 121.620686 -237.49918)
			(xy 121.573321 -237.491677) (xy 121.52771 -237.476863) (xy 121.484976 -237.4551) (xy 121.44617 -237.426925)
			(xy 121.412246 -237.393029) (xy 121.384037 -237.354247) (xy 121.362238 -237.311532) (xy 121.347384 -237.265935)
			(xy 121.339841 -237.218576) (xy 121.339356 -237.194598) (xy 121.339356 -237.184438) (xy 121.331736 -237.165896)
			(xy 120.355106 -236.189266) (xy 120.347711 -236.182411) (xy 120.329112 -236.174664) (xy 120.319038 -236.17428)
			(xy 118.747032 -236.17428) (xy 118.73528 -236.174881) (xy 118.714239 -236.185354) (xy 118.706646 -236.194346)
			(xy 118.650512 -236.26826) (xy 118.64594 -236.291374) (xy 118.649242 -236.303058) (xy 118.654378 -236.322983)
			(xy 118.659857 -236.363764) (xy 118.660164 -236.384338) (xy 118.659642 -236.409593) (xy 118.651329 -236.459415)
			(xy 118.634928 -236.507189) (xy 118.610887 -236.551612) (xy 118.579863 -236.591472) (xy 118.542701 -236.625682)
			(xy 118.500415 -236.653308) (xy 118.454159 -236.673598) (xy 118.405194 -236.685998) (xy 118.354856 -236.690169)
			(xy 118.304518 -236.685998) (xy 118.255553 -236.673598) (xy 118.209297 -236.653308) (xy 118.167011 -236.625682)
			(xy 118.129849 -236.591472) (xy 118.098825 -236.551612) (xy 118.074784 -236.507189) (xy 118.058383 -236.459415)
			(xy 118.05007 -236.409593) (xy 118.049548 -236.384338) (xy 118.04987 -236.363765) (xy 118.055352 -236.322987)
			(xy 118.06047 -236.303058) (xy 118.063772 -236.291374) (xy 118.0592 -236.26826) (xy 118.003066 -236.194346)
			(xy 117.995472 -236.185361) (xy 117.974428 -236.174902) (xy 117.96268 -236.17428) (xy 115.92687 -236.17428)
			(xy 115.915114 -236.174873) (xy 115.89406 -236.185337) (xy 115.886484 -236.194346) (xy 115.83035 -236.26826)
			(xy 115.825778 -236.291374) (xy 115.82908 -236.303058) (xy 115.834215 -236.322983) (xy 115.839693 -236.363764)
			(xy 115.840002 -236.384338) (xy 115.839529 -236.408327) (xy 115.832018 -236.455714) (xy 115.817187 -236.501342)
			(xy 115.795401 -236.544089) (xy 115.767197 -236.582902) (xy 115.733269 -236.616826) (xy 115.694452 -236.645024)
			(xy 115.651702 -236.666804) (xy 115.606071 -236.681628) (xy 115.558683 -236.689132) (xy 115.534694 -236.689646)
			(xy 115.510455 -236.689181) (xy 115.462584 -236.681522) (xy 115.416525 -236.666398) (xy 115.373433 -236.644189)
			(xy 115.33439 -236.615451) (xy 115.300376 -236.580907) (xy 115.272247 -236.541424) (xy 115.250707 -236.497993)
			(xy 115.236297 -236.451705) (xy 115.232434 -236.427772) (xy 115.231164 -236.417866) (xy 115.221766 -236.401356)
			(xy 115.151916 -236.345476) (xy 115.133882 -236.339888) (xy 115.123976 -236.34065) (xy 115.109204 -236.341719)
			(xy 115.079605 -236.342863) (xy 115.064794 -236.342936) (xy 114.92992 -236.342936) (xy 114.900456 -236.371638)
			(xy 114.899948 -236.392466) (xy 114.898801 -236.417281) (xy 114.88946 -236.46607) (xy 114.872347 -236.512703)
			(xy 114.847913 -236.555953) (xy 114.816802 -236.594678) (xy 114.779835 -236.627858) (xy 114.737985 -236.654618)
			(xy 114.692355 -236.674253) (xy 114.64415 -236.686245) (xy 114.59464 -236.690278) (xy 114.54513 -236.686245)
			(xy 114.496925 -236.674253) (xy 114.451295 -236.654618) (xy 114.409445 -236.627858) (xy 114.372478 -236.594678)
			(xy 114.341367 -236.555953) (xy 114.316933 -236.512703) (xy 114.29982 -236.46607) (xy 114.290479 -236.417281)
			(xy 114.289332 -236.392466) (xy 114.288824 -236.371638) (xy 114.25936 -236.342936) (xy 114.12474 -236.342936)
			(xy 114.109929 -236.342866) (xy 114.08033 -236.341722) (xy 114.065558 -236.34065) (xy 114.055652 -236.339888)
			(xy 114.037618 -236.345476) (xy 113.967768 -236.401356) (xy 113.95837 -236.417866) (xy 113.9571 -236.427772)
			(xy 113.953195 -236.451702) (xy 113.938809 -236.498001) (xy 113.917285 -236.541445) (xy 113.889166 -236.580942)
			(xy 113.855158 -236.615497) (xy 113.816116 -236.644244) (xy 113.773021 -236.666458) (xy 113.726957 -236.681582)
			(xy 113.679082 -236.689235) (xy 113.65484 -236.689646) (xy 113.630844 -236.689203) (xy 113.583441 -236.681701)
			(xy 113.537796 -236.666877) (xy 113.495031 -236.645094) (xy 113.456201 -236.61689) (xy 113.422261 -236.582958)
			(xy 113.394047 -236.544135) (xy 113.372253 -236.501376) (xy 113.357417 -236.455735) (xy 113.349903 -236.408334)
			(xy 113.349532 -236.384338) (xy 113.349854 -236.363765) (xy 113.355337 -236.322987) (xy 113.360454 -236.303058)
			(xy 113.363756 -236.291374) (xy 113.359184 -236.26826) (xy 113.30305 -236.194346) (xy 113.295455 -236.185364)
			(xy 113.274411 -236.174911) (xy 113.262664 -236.17428) (xy 112.240822 -236.17428) (xy 112.230758 -236.174717)
			(xy 112.212172 -236.182449) (xy 112.204754 -236.189266) (xy 111.924846 -236.469174) (xy 111.918006 -236.476574)
			(xy 111.910291 -236.495173) (xy 111.90986 -236.505242) (xy 111.90986 -237.194344) (xy 112.878882 -237.194344)
			(xy 112.882842 -237.14529) (xy 112.894619 -237.097506) (xy 112.91391 -237.05223) (xy 112.940213 -237.010634)
			(xy 112.972848 -236.973797) (xy 113.010969 -236.942672) (xy 113.05359 -236.918065) (xy 113.099606 -236.900613)
			(xy 113.147825 -236.890769) (xy 113.197 -236.888788) (xy 113.245855 -236.89472) (xy 113.293126 -236.908412)
			(xy 113.337588 -236.92951) (xy 113.378091 -236.957466) (xy 113.413584 -236.991558) (xy 113.443149 -237.030902)
			(xy 113.46602 -237.074479) (xy 113.481604 -237.12116) (xy 113.489499 -237.169737) (xy 113.489994 -237.194344)
			(xy 115.699044 -237.194344) (xy 115.703004 -237.14529) (xy 115.714781 -237.097506) (xy 115.734072 -237.05223)
			(xy 115.760375 -237.010634) (xy 115.79301 -236.973797) (xy 115.831131 -236.942672) (xy 115.873752 -236.918065)
			(xy 115.919768 -236.900613) (xy 115.967987 -236.890769) (xy 116.017162 -236.888788) (xy 116.066017 -236.89472)
			(xy 116.113288 -236.908412) (xy 116.15775 -236.92951) (xy 116.198253 -236.957466) (xy 116.233746 -236.991558)
			(xy 116.263311 -237.030902) (xy 116.286182 -237.074479) (xy 116.301766 -237.12116) (xy 116.309661 -237.169737)
			(xy 116.310156 -237.194344) (xy 116.638844 -237.194344) (xy 116.642804 -237.14529) (xy 116.654581 -237.097506)
			(xy 116.673872 -237.05223) (xy 116.700175 -237.010634) (xy 116.73281 -236.973797) (xy 116.770931 -236.942672)
			(xy 116.813552 -236.918065) (xy 116.859568 -236.900613) (xy 116.907787 -236.890769) (xy 116.956962 -236.888788)
			(xy 117.005817 -236.89472) (xy 117.053088 -236.908412) (xy 117.09755 -236.92951) (xy 117.138053 -236.957466)
			(xy 117.173546 -236.991558) (xy 117.203111 -237.030902) (xy 117.225982 -237.074479) (xy 117.241566 -237.12116)
			(xy 117.249461 -237.169737) (xy 117.249956 -237.194344) (xy 117.578898 -237.194344) (xy 117.582858 -237.14529)
			(xy 117.594635 -237.097506) (xy 117.613926 -237.05223) (xy 117.640229 -237.010634) (xy 117.672864 -236.973797)
			(xy 117.710985 -236.942672) (xy 117.753606 -236.918065) (xy 117.799622 -236.900613) (xy 117.847841 -236.890769)
			(xy 117.897016 -236.888788) (xy 117.945871 -236.89472) (xy 117.993142 -236.908412) (xy 118.037604 -236.92951)
			(xy 118.078107 -236.957466) (xy 118.1136 -236.991558) (xy 118.143165 -237.030902) (xy 118.166036 -237.074479)
			(xy 118.18162 -237.12116) (xy 118.189515 -237.169737) (xy 118.19001 -237.194344) (xy 118.518952 -237.194344)
			(xy 118.522912 -237.14529) (xy 118.534689 -237.097506) (xy 118.55398 -237.05223) (xy 118.580283 -237.010634)
			(xy 118.612918 -236.973797) (xy 118.651039 -236.942672) (xy 118.69366 -236.918065) (xy 118.739676 -236.900613)
			(xy 118.787895 -236.890769) (xy 118.83707 -236.888788) (xy 118.885925 -236.89472) (xy 118.933196 -236.908412)
			(xy 118.977658 -236.92951) (xy 119.018161 -236.957466) (xy 119.053654 -236.991558) (xy 119.083219 -237.030902)
			(xy 119.10609 -237.074479) (xy 119.121674 -237.12116) (xy 119.129569 -237.169737) (xy 119.130064 -237.194344)
			(xy 119.459006 -237.194344) (xy 119.462966 -237.14529) (xy 119.474743 -237.097506) (xy 119.494034 -237.05223)
			(xy 119.520337 -237.010634) (xy 119.552972 -236.973797) (xy 119.591093 -236.942672) (xy 119.633714 -236.918065)
			(xy 119.67973 -236.900613) (xy 119.727949 -236.890769) (xy 119.777124 -236.888788) (xy 119.825979 -236.89472)
			(xy 119.87325 -236.908412) (xy 119.917712 -236.92951) (xy 119.958215 -236.957466) (xy 119.993708 -236.991558)
			(xy 120.023273 -237.030902) (xy 120.046144 -237.074479) (xy 120.061728 -237.12116) (xy 120.069623 -237.169737)
			(xy 120.070118 -237.194344) (xy 120.398806 -237.194344) (xy 120.402766 -237.14529) (xy 120.414543 -237.097506)
			(xy 120.433834 -237.05223) (xy 120.460137 -237.010634) (xy 120.492772 -236.973797) (xy 120.530893 -236.942672)
			(xy 120.573514 -236.918065) (xy 120.61953 -236.900613) (xy 120.667749 -236.890769) (xy 120.716924 -236.888788)
			(xy 120.765779 -236.89472) (xy 120.81305 -236.908412) (xy 120.857512 -236.92951) (xy 120.898015 -236.957466)
			(xy 120.933508 -236.991558) (xy 120.963073 -237.030902) (xy 120.985944 -237.074479) (xy 121.001528 -237.12116)
			(xy 121.009423 -237.169737) (xy 121.009918 -237.194344) (xy 121.009423 -237.218951) (xy 121.001528 -237.267528)
			(xy 120.985944 -237.314209) (xy 120.963073 -237.357786) (xy 120.933508 -237.39713) (xy 120.898015 -237.431222)
			(xy 120.857512 -237.459178) (xy 120.81305 -237.480276) (xy 120.765779 -237.493968) (xy 120.716924 -237.4999)
			(xy 120.667749 -237.497919) (xy 120.61953 -237.488075) (xy 120.573514 -237.470623) (xy 120.530893 -237.446016)
			(xy 120.492772 -237.414891) (xy 120.460137 -237.378054) (xy 120.433834 -237.336458) (xy 120.414543 -237.291182)
			(xy 120.402766 -237.243398) (xy 120.398806 -237.194344) (xy 120.070118 -237.194344) (xy 120.069623 -237.218951)
			(xy 120.061728 -237.267528) (xy 120.046144 -237.314209) (xy 120.023273 -237.357786) (xy 119.993708 -237.39713)
			(xy 119.958215 -237.431222) (xy 119.917712 -237.459178) (xy 119.87325 -237.480276) (xy 119.825979 -237.493968)
			(xy 119.777124 -237.4999) (xy 119.727949 -237.497919) (xy 119.67973 -237.488075) (xy 119.633714 -237.470623)
			(xy 119.591093 -237.446016) (xy 119.552972 -237.414891) (xy 119.520337 -237.378054) (xy 119.494034 -237.336458)
			(xy 119.474743 -237.291182) (xy 119.462966 -237.243398) (xy 119.459006 -237.194344) (xy 119.130064 -237.194344)
			(xy 119.129569 -237.218951) (xy 119.121674 -237.267528) (xy 119.10609 -237.314209) (xy 119.083219 -237.357786)
			(xy 119.053654 -237.39713) (xy 119.018161 -237.431222) (xy 118.977658 -237.459178) (xy 118.933196 -237.480276)
			(xy 118.885925 -237.493968) (xy 118.83707 -237.4999) (xy 118.787895 -237.497919) (xy 118.739676 -237.488075)
			(xy 118.69366 -237.470623) (xy 118.651039 -237.446016) (xy 118.612918 -237.414891) (xy 118.580283 -237.378054)
			(xy 118.55398 -237.336458) (xy 118.534689 -237.291182) (xy 118.522912 -237.243398) (xy 118.518952 -237.194344)
			(xy 118.19001 -237.194344) (xy 118.189515 -237.218951) (xy 118.18162 -237.267528) (xy 118.166036 -237.314209)
			(xy 118.143165 -237.357786) (xy 118.1136 -237.39713) (xy 118.078107 -237.431222) (xy 118.037604 -237.459178)
			(xy 117.993142 -237.480276) (xy 117.945871 -237.493968) (xy 117.897016 -237.4999) (xy 117.847841 -237.497919)
			(xy 117.799622 -237.488075) (xy 117.753606 -237.470623) (xy 117.710985 -237.446016) (xy 117.672864 -237.414891)
			(xy 117.640229 -237.378054) (xy 117.613926 -237.336458) (xy 117.594635 -237.291182) (xy 117.582858 -237.243398)
			(xy 117.578898 -237.194344) (xy 117.249956 -237.194344) (xy 117.249461 -237.218951) (xy 117.241566 -237.267528)
			(xy 117.225982 -237.314209) (xy 117.203111 -237.357786) (xy 117.173546 -237.39713) (xy 117.138053 -237.431222)
			(xy 117.09755 -237.459178) (xy 117.053088 -237.480276) (xy 117.005817 -237.493968) (xy 116.956962 -237.4999)
			(xy 116.907787 -237.497919) (xy 116.859568 -237.488075) (xy 116.813552 -237.470623) (xy 116.770931 -237.446016)
			(xy 116.73281 -237.414891) (xy 116.700175 -237.378054) (xy 116.673872 -237.336458) (xy 116.654581 -237.291182)
			(xy 116.642804 -237.243398) (xy 116.638844 -237.194344) (xy 116.310156 -237.194344) (xy 116.309661 -237.218951)
			(xy 116.301766 -237.267528) (xy 116.286182 -237.314209) (xy 116.263311 -237.357786) (xy 116.233746 -237.39713)
			(xy 116.198253 -237.431222) (xy 116.15775 -237.459178) (xy 116.113288 -237.480276) (xy 116.066017 -237.493968)
			(xy 116.017162 -237.4999) (xy 115.967987 -237.497919) (xy 115.919768 -237.488075) (xy 115.873752 -237.470623)
			(xy 115.831131 -237.446016) (xy 115.79301 -237.414891) (xy 115.760375 -237.378054) (xy 115.734072 -237.336458)
			(xy 115.714781 -237.291182) (xy 115.703004 -237.243398) (xy 115.699044 -237.194344) (xy 113.489994 -237.194344)
			(xy 113.489499 -237.218951) (xy 113.481604 -237.267528) (xy 113.46602 -237.314209) (xy 113.443149 -237.357786)
			(xy 113.413584 -237.39713) (xy 113.378091 -237.431222) (xy 113.337588 -237.459178) (xy 113.293126 -237.480276)
			(xy 113.245855 -237.493968) (xy 113.197 -237.4999) (xy 113.147825 -237.497919) (xy 113.099606 -237.488075)
			(xy 113.05359 -237.470623) (xy 113.010969 -237.446016) (xy 112.972848 -237.414891) (xy 112.940213 -237.378054)
			(xy 112.91391 -237.336458) (xy 112.894619 -237.291182) (xy 112.882842 -237.243398) (xy 112.878882 -237.194344)
			(xy 111.90986 -237.194344) (xy 111.90986 -238.00435) (xy 113.349036 -238.00435) (xy 113.352996 -237.955296)
			(xy 113.364773 -237.907512) (xy 113.384064 -237.862236) (xy 113.410367 -237.82064) (xy 113.443002 -237.783803)
			(xy 113.481123 -237.752678) (xy 113.523744 -237.728071) (xy 113.56976 -237.710619) (xy 113.617979 -237.700775)
			(xy 113.667154 -237.698794) (xy 113.716009 -237.704726) (xy 113.76328 -237.718418) (xy 113.807742 -237.739516)
			(xy 113.848245 -237.767472) (xy 113.883738 -237.801564) (xy 113.913303 -237.840908) (xy 113.936174 -237.884485)
			(xy 113.951758 -237.931166) (xy 113.959653 -237.979743) (xy 113.960148 -238.00435) (xy 114.288836 -238.00435)
			(xy 114.292796 -237.955296) (xy 114.304573 -237.907512) (xy 114.323864 -237.862236) (xy 114.350167 -237.82064)
			(xy 114.382802 -237.783803) (xy 114.420923 -237.752678) (xy 114.463544 -237.728071) (xy 114.50956 -237.710619)
			(xy 114.557779 -237.700775) (xy 114.606954 -237.698794) (xy 114.655809 -237.704726) (xy 114.70308 -237.718418)
			(xy 114.747542 -237.739516) (xy 114.788045 -237.767472) (xy 114.823538 -237.801564) (xy 114.853103 -237.840908)
			(xy 114.875974 -237.884485) (xy 114.891558 -237.931166) (xy 114.899453 -237.979743) (xy 114.899948 -238.00435)
			(xy 115.22889 -238.00435) (xy 115.23285 -237.955296) (xy 115.244627 -237.907512) (xy 115.263918 -237.862236)
			(xy 115.290221 -237.82064) (xy 115.322856 -237.783803) (xy 115.360977 -237.752678) (xy 115.403598 -237.728071)
			(xy 115.449614 -237.710619) (xy 115.497833 -237.700775) (xy 115.547008 -237.698794) (xy 115.595863 -237.704726)
			(xy 115.643134 -237.718418) (xy 115.687596 -237.739516) (xy 115.728099 -237.767472) (xy 115.763592 -237.801564)
			(xy 115.793157 -237.840908) (xy 115.816028 -237.884485) (xy 115.831612 -237.931166) (xy 115.839507 -237.979743)
			(xy 115.840002 -238.00435) (xy 116.168944 -238.00435) (xy 116.172904 -237.955296) (xy 116.184681 -237.907512)
			(xy 116.203972 -237.862236) (xy 116.230275 -237.82064) (xy 116.26291 -237.783803) (xy 116.301031 -237.752678)
			(xy 116.343652 -237.728071) (xy 116.389668 -237.710619) (xy 116.437887 -237.700775) (xy 116.487062 -237.698794)
			(xy 116.535917 -237.704726) (xy 116.583188 -237.718418) (xy 116.62765 -237.739516) (xy 116.668153 -237.767472)
			(xy 116.703646 -237.801564) (xy 116.733211 -237.840908) (xy 116.756082 -237.884485) (xy 116.771666 -237.931166)
			(xy 116.779561 -237.979743) (xy 116.780056 -238.00435) (xy 117.108998 -238.00435) (xy 117.112958 -237.955296)
			(xy 117.124735 -237.907512) (xy 117.144026 -237.862236) (xy 117.170329 -237.82064) (xy 117.202964 -237.783803)
			(xy 117.241085 -237.752678) (xy 117.283706 -237.728071) (xy 117.329722 -237.710619) (xy 117.377941 -237.700775)
			(xy 117.427116 -237.698794) (xy 117.475971 -237.704726) (xy 117.523242 -237.718418) (xy 117.567704 -237.739516)
			(xy 117.608207 -237.767472) (xy 117.6437 -237.801564) (xy 117.673265 -237.840908) (xy 117.696136 -237.884485)
			(xy 117.71172 -237.931166) (xy 117.719615 -237.979743) (xy 117.72011 -238.00435) (xy 118.049052 -238.00435)
			(xy 118.053012 -237.955296) (xy 118.064789 -237.907512) (xy 118.08408 -237.862236) (xy 118.110383 -237.82064)
			(xy 118.143018 -237.783803) (xy 118.181139 -237.752678) (xy 118.22376 -237.728071) (xy 118.269776 -237.710619)
			(xy 118.317995 -237.700775) (xy 118.36717 -237.698794) (xy 118.416025 -237.704726) (xy 118.463296 -237.718418)
			(xy 118.507758 -237.739516) (xy 118.548261 -237.767472) (xy 118.583754 -237.801564) (xy 118.613319 -237.840908)
			(xy 118.63619 -237.884485) (xy 118.651774 -237.931166) (xy 118.659669 -237.979743) (xy 118.660164 -238.00435)
			(xy 118.988852 -238.00435) (xy 118.992812 -237.955296) (xy 119.004589 -237.907512) (xy 119.02388 -237.862236)
			(xy 119.050183 -237.82064) (xy 119.082818 -237.783803) (xy 119.120939 -237.752678) (xy 119.16356 -237.728071)
			(xy 119.209576 -237.710619) (xy 119.257795 -237.700775) (xy 119.30697 -237.698794) (xy 119.355825 -237.704726)
			(xy 119.403096 -237.718418) (xy 119.447558 -237.739516) (xy 119.488061 -237.767472) (xy 119.523554 -237.801564)
			(xy 119.553119 -237.840908) (xy 119.57599 -237.884485) (xy 119.591574 -237.931166) (xy 119.599469 -237.979743)
			(xy 119.599964 -238.00435) (xy 119.928906 -238.00435) (xy 119.932866 -237.955296) (xy 119.944643 -237.907512)
			(xy 119.963934 -237.862236) (xy 119.990237 -237.82064) (xy 120.022872 -237.783803) (xy 120.060993 -237.752678)
			(xy 120.103614 -237.728071) (xy 120.14963 -237.710619) (xy 120.197849 -237.700775) (xy 120.247024 -237.698794)
			(xy 120.295879 -237.704726) (xy 120.34315 -237.718418) (xy 120.387612 -237.739516) (xy 120.428115 -237.767472)
			(xy 120.463608 -237.801564) (xy 120.493173 -237.840908) (xy 120.516044 -237.884485) (xy 120.531628 -237.931166)
			(xy 120.539523 -237.979743) (xy 120.540018 -238.00435) (xy 120.86896 -238.00435) (xy 120.87292 -237.955296)
			(xy 120.884697 -237.907512) (xy 120.903988 -237.862236) (xy 120.930291 -237.82064) (xy 120.962926 -237.783803)
			(xy 121.001047 -237.752678) (xy 121.043668 -237.728071) (xy 121.089684 -237.710619) (xy 121.137903 -237.700775)
			(xy 121.187078 -237.698794) (xy 121.235933 -237.704726) (xy 121.283204 -237.718418) (xy 121.327666 -237.739516)
			(xy 121.368169 -237.767472) (xy 121.403662 -237.801564) (xy 121.433227 -237.840908) (xy 121.456098 -237.884485)
			(xy 121.471682 -237.931166) (xy 121.479577 -237.979743) (xy 121.480072 -238.00435) (xy 121.809014 -238.00435)
			(xy 121.812974 -237.955296) (xy 121.824751 -237.907512) (xy 121.844042 -237.862236) (xy 121.870345 -237.82064)
			(xy 121.90298 -237.783803) (xy 121.941101 -237.752678) (xy 121.983722 -237.728071) (xy 122.029738 -237.710619)
			(xy 122.077957 -237.700775) (xy 122.127132 -237.698794) (xy 122.175987 -237.704726) (xy 122.223258 -237.718418)
			(xy 122.26772 -237.739516) (xy 122.308223 -237.767472) (xy 122.343716 -237.801564) (xy 122.373281 -237.840908)
			(xy 122.396152 -237.884485) (xy 122.411736 -237.931166) (xy 122.419631 -237.979743) (xy 122.420126 -238.00435)
			(xy 122.748814 -238.00435) (xy 122.752774 -237.955296) (xy 122.764551 -237.907512) (xy 122.783842 -237.862236)
			(xy 122.810145 -237.82064) (xy 122.84278 -237.783803) (xy 122.880901 -237.752678) (xy 122.923522 -237.728071)
			(xy 122.969538 -237.710619) (xy 123.017757 -237.700775) (xy 123.066932 -237.698794) (xy 123.115787 -237.704726)
			(xy 123.163058 -237.718418) (xy 123.20752 -237.739516) (xy 123.248023 -237.767472) (xy 123.283516 -237.801564)
			(xy 123.313081 -237.840908) (xy 123.335952 -237.884485) (xy 123.351536 -237.931166) (xy 123.359431 -237.979743)
			(xy 123.359926 -238.00435) (xy 123.688868 -238.00435) (xy 123.692828 -237.955296) (xy 123.704605 -237.907512)
			(xy 123.723896 -237.862236) (xy 123.750199 -237.82064) (xy 123.782834 -237.783803) (xy 123.820955 -237.752678)
			(xy 123.863576 -237.728071) (xy 123.909592 -237.710619) (xy 123.957811 -237.700775) (xy 124.006986 -237.698794)
			(xy 124.055841 -237.704726) (xy 124.103112 -237.718418) (xy 124.147574 -237.739516) (xy 124.188077 -237.767472)
			(xy 124.22357 -237.801564) (xy 124.253135 -237.840908) (xy 124.276006 -237.884485) (xy 124.29159 -237.931166)
			(xy 124.299485 -237.979743) (xy 124.29998 -238.00435) (xy 124.628922 -238.00435) (xy 124.632882 -237.955296)
			(xy 124.644659 -237.907512) (xy 124.66395 -237.862236) (xy 124.690253 -237.82064) (xy 124.722888 -237.783803)
			(xy 124.761009 -237.752678) (xy 124.80363 -237.728071) (xy 124.849646 -237.710619) (xy 124.897865 -237.700775)
			(xy 124.94704 -237.698794) (xy 124.995895 -237.704726) (xy 125.043166 -237.718418) (xy 125.087628 -237.739516)
			(xy 125.128131 -237.767472) (xy 125.163624 -237.801564) (xy 125.193189 -237.840908) (xy 125.21606 -237.884485)
			(xy 125.231644 -237.931166) (xy 125.239539 -237.979743) (xy 125.240034 -238.00435) (xy 125.239539 -238.028957)
			(xy 125.231644 -238.077534) (xy 125.21606 -238.124215) (xy 125.193189 -238.167792) (xy 125.163624 -238.207136)
			(xy 125.128131 -238.241228) (xy 125.087628 -238.269184) (xy 125.043166 -238.290282) (xy 124.995895 -238.303974)
			(xy 124.94704 -238.309906) (xy 124.897865 -238.307925) (xy 124.849646 -238.298081) (xy 124.80363 -238.280629)
			(xy 124.761009 -238.256022) (xy 124.722888 -238.224897) (xy 124.690253 -238.18806) (xy 124.66395 -238.146464)
			(xy 124.644659 -238.101188) (xy 124.632882 -238.053404) (xy 124.628922 -238.00435) (xy 124.29998 -238.00435)
			(xy 124.299485 -238.028957) (xy 124.29159 -238.077534) (xy 124.276006 -238.124215) (xy 124.253135 -238.167792)
			(xy 124.22357 -238.207136) (xy 124.188077 -238.241228) (xy 124.147574 -238.269184) (xy 124.103112 -238.290282)
			(xy 124.055841 -238.303974) (xy 124.006986 -238.309906) (xy 123.957811 -238.307925) (xy 123.909592 -238.298081)
			(xy 123.863576 -238.280629) (xy 123.820955 -238.256022) (xy 123.782834 -238.224897) (xy 123.750199 -238.18806)
			(xy 123.723896 -238.146464) (xy 123.704605 -238.101188) (xy 123.692828 -238.053404) (xy 123.688868 -238.00435)
			(xy 123.359926 -238.00435) (xy 123.359431 -238.028957) (xy 123.351536 -238.077534) (xy 123.335952 -238.124215)
			(xy 123.313081 -238.167792) (xy 123.283516 -238.207136) (xy 123.248023 -238.241228) (xy 123.20752 -238.269184)
			(xy 123.163058 -238.290282) (xy 123.115787 -238.303974) (xy 123.066932 -238.309906) (xy 123.017757 -238.307925)
			(xy 122.969538 -238.298081) (xy 122.923522 -238.280629) (xy 122.880901 -238.256022) (xy 122.84278 -238.224897)
			(xy 122.810145 -238.18806) (xy 122.783842 -238.146464) (xy 122.764551 -238.101188) (xy 122.752774 -238.053404)
			(xy 122.748814 -238.00435) (xy 122.420126 -238.00435) (xy 122.419631 -238.028957) (xy 122.411736 -238.077534)
			(xy 122.396152 -238.124215) (xy 122.373281 -238.167792) (xy 122.343716 -238.207136) (xy 122.308223 -238.241228)
			(xy 122.26772 -238.269184) (xy 122.223258 -238.290282) (xy 122.175987 -238.303974) (xy 122.127132 -238.309906)
			(xy 122.077957 -238.307925) (xy 122.029738 -238.298081) (xy 121.983722 -238.280629) (xy 121.941101 -238.256022)
			(xy 121.90298 -238.224897) (xy 121.870345 -238.18806) (xy 121.844042 -238.146464) (xy 121.824751 -238.101188)
			(xy 121.812974 -238.053404) (xy 121.809014 -238.00435) (xy 121.480072 -238.00435) (xy 121.479577 -238.028957)
			(xy 121.471682 -238.077534) (xy 121.456098 -238.124215) (xy 121.433227 -238.167792) (xy 121.403662 -238.207136)
			(xy 121.368169 -238.241228) (xy 121.327666 -238.269184) (xy 121.283204 -238.290282) (xy 121.235933 -238.303974)
			(xy 121.187078 -238.309906) (xy 121.137903 -238.307925) (xy 121.089684 -238.298081) (xy 121.043668 -238.280629)
			(xy 121.001047 -238.256022) (xy 120.962926 -238.224897) (xy 120.930291 -238.18806) (xy 120.903988 -238.146464)
			(xy 120.884697 -238.101188) (xy 120.87292 -238.053404) (xy 120.86896 -238.00435) (xy 120.540018 -238.00435)
			(xy 120.539523 -238.028957) (xy 120.531628 -238.077534) (xy 120.516044 -238.124215) (xy 120.493173 -238.167792)
			(xy 120.463608 -238.207136) (xy 120.428115 -238.241228) (xy 120.387612 -238.269184) (xy 120.34315 -238.290282)
			(xy 120.295879 -238.303974) (xy 120.247024 -238.309906) (xy 120.197849 -238.307925) (xy 120.14963 -238.298081)
			(xy 120.103614 -238.280629) (xy 120.060993 -238.256022) (xy 120.022872 -238.224897) (xy 119.990237 -238.18806)
			(xy 119.963934 -238.146464) (xy 119.944643 -238.101188) (xy 119.932866 -238.053404) (xy 119.928906 -238.00435)
			(xy 119.599964 -238.00435) (xy 119.599469 -238.028957) (xy 119.591574 -238.077534) (xy 119.57599 -238.124215)
			(xy 119.553119 -238.167792) (xy 119.523554 -238.207136) (xy 119.488061 -238.241228) (xy 119.447558 -238.269184)
			(xy 119.403096 -238.290282) (xy 119.355825 -238.303974) (xy 119.30697 -238.309906) (xy 119.257795 -238.307925)
			(xy 119.209576 -238.298081) (xy 119.16356 -238.280629) (xy 119.120939 -238.256022) (xy 119.082818 -238.224897)
			(xy 119.050183 -238.18806) (xy 119.02388 -238.146464) (xy 119.004589 -238.101188) (xy 118.992812 -238.053404)
			(xy 118.988852 -238.00435) (xy 118.660164 -238.00435) (xy 118.659669 -238.028957) (xy 118.651774 -238.077534)
			(xy 118.63619 -238.124215) (xy 118.613319 -238.167792) (xy 118.583754 -238.207136) (xy 118.548261 -238.241228)
			(xy 118.507758 -238.269184) (xy 118.463296 -238.290282) (xy 118.416025 -238.303974) (xy 118.36717 -238.309906)
			(xy 118.317995 -238.307925) (xy 118.269776 -238.298081) (xy 118.22376 -238.280629) (xy 118.181139 -238.256022)
			(xy 118.143018 -238.224897) (xy 118.110383 -238.18806) (xy 118.08408 -238.146464) (xy 118.064789 -238.101188)
			(xy 118.053012 -238.053404) (xy 118.049052 -238.00435) (xy 117.72011 -238.00435) (xy 117.719615 -238.028957)
			(xy 117.71172 -238.077534) (xy 117.696136 -238.124215) (xy 117.673265 -238.167792) (xy 117.6437 -238.207136)
			(xy 117.608207 -238.241228) (xy 117.567704 -238.269184) (xy 117.523242 -238.290282) (xy 117.475971 -238.303974)
			(xy 117.427116 -238.309906) (xy 117.377941 -238.307925) (xy 117.329722 -238.298081) (xy 117.283706 -238.280629)
			(xy 117.241085 -238.256022) (xy 117.202964 -238.224897) (xy 117.170329 -238.18806) (xy 117.144026 -238.146464)
			(xy 117.124735 -238.101188) (xy 117.112958 -238.053404) (xy 117.108998 -238.00435) (xy 116.780056 -238.00435)
			(xy 116.779561 -238.028957) (xy 116.771666 -238.077534) (xy 116.756082 -238.124215) (xy 116.733211 -238.167792)
			(xy 116.703646 -238.207136) (xy 116.668153 -238.241228) (xy 116.62765 -238.269184) (xy 116.583188 -238.290282)
			(xy 116.535917 -238.303974) (xy 116.487062 -238.309906) (xy 116.437887 -238.307925) (xy 116.389668 -238.298081)
			(xy 116.343652 -238.280629) (xy 116.301031 -238.256022) (xy 116.26291 -238.224897) (xy 116.230275 -238.18806)
			(xy 116.203972 -238.146464) (xy 116.184681 -238.101188) (xy 116.172904 -238.053404) (xy 116.168944 -238.00435)
			(xy 115.840002 -238.00435) (xy 115.839507 -238.028957) (xy 115.831612 -238.077534) (xy 115.816028 -238.124215)
			(xy 115.793157 -238.167792) (xy 115.763592 -238.207136) (xy 115.728099 -238.241228) (xy 115.687596 -238.269184)
			(xy 115.643134 -238.290282) (xy 115.595863 -238.303974) (xy 115.547008 -238.309906) (xy 115.497833 -238.307925)
			(xy 115.449614 -238.298081) (xy 115.403598 -238.280629) (xy 115.360977 -238.256022) (xy 115.322856 -238.224897)
			(xy 115.290221 -238.18806) (xy 115.263918 -238.146464) (xy 115.244627 -238.101188) (xy 115.23285 -238.053404)
			(xy 115.22889 -238.00435) (xy 114.899948 -238.00435) (xy 114.899453 -238.028957) (xy 114.891558 -238.077534)
			(xy 114.875974 -238.124215) (xy 114.853103 -238.167792) (xy 114.823538 -238.207136) (xy 114.788045 -238.241228)
			(xy 114.747542 -238.269184) (xy 114.70308 -238.290282) (xy 114.655809 -238.303974) (xy 114.606954 -238.309906)
			(xy 114.557779 -238.307925) (xy 114.50956 -238.298081) (xy 114.463544 -238.280629) (xy 114.420923 -238.256022)
			(xy 114.382802 -238.224897) (xy 114.350167 -238.18806) (xy 114.323864 -238.146464) (xy 114.304573 -238.101188)
			(xy 114.292796 -238.053404) (xy 114.288836 -238.00435) (xy 113.960148 -238.00435) (xy 113.959653 -238.028957)
			(xy 113.951758 -238.077534) (xy 113.936174 -238.124215) (xy 113.913303 -238.167792) (xy 113.883738 -238.207136)
			(xy 113.848245 -238.241228) (xy 113.807742 -238.269184) (xy 113.76328 -238.290282) (xy 113.716009 -238.303974)
			(xy 113.667154 -238.309906) (xy 113.617979 -238.307925) (xy 113.56976 -238.298081) (xy 113.523744 -238.280629)
			(xy 113.481123 -238.256022) (xy 113.443002 -238.224897) (xy 113.410367 -238.18806) (xy 113.384064 -238.146464)
			(xy 113.364773 -238.101188) (xy 113.352996 -238.053404) (xy 113.349036 -238.00435) (xy 111.90986 -238.00435)
			(xy 111.90986 -238.814356) (xy 112.878882 -238.814356) (xy 112.882842 -238.765302) (xy 112.894619 -238.717518)
			(xy 112.91391 -238.672242) (xy 112.940213 -238.630646) (xy 112.972848 -238.593809) (xy 113.010969 -238.562684)
			(xy 113.05359 -238.538077) (xy 113.099606 -238.520625) (xy 113.147825 -238.510781) (xy 113.197 -238.5088)
			(xy 113.245855 -238.514732) (xy 113.293126 -238.528424) (xy 113.337588 -238.549522) (xy 113.378091 -238.577478)
			(xy 113.413584 -238.61157) (xy 113.443149 -238.650914) (xy 113.46602 -238.694491) (xy 113.481604 -238.741172)
			(xy 113.489499 -238.789749) (xy 113.489994 -238.814356) (xy 113.818936 -238.814356) (xy 113.822896 -238.765302)
			(xy 113.834673 -238.717518) (xy 113.853964 -238.672242) (xy 113.880267 -238.630646) (xy 113.912902 -238.593809)
			(xy 113.951023 -238.562684) (xy 113.993644 -238.538077) (xy 114.03966 -238.520625) (xy 114.087879 -238.510781)
			(xy 114.137054 -238.5088) (xy 114.185909 -238.514732) (xy 114.23318 -238.528424) (xy 114.277642 -238.549522)
			(xy 114.318145 -238.577478) (xy 114.353638 -238.61157) (xy 114.383203 -238.650914) (xy 114.406074 -238.694491)
			(xy 114.421658 -238.741172) (xy 114.429553 -238.789749) (xy 114.430048 -238.814356) (xy 114.75899 -238.814356)
			(xy 114.76295 -238.765302) (xy 114.774727 -238.717518) (xy 114.794018 -238.672242) (xy 114.820321 -238.630646)
			(xy 114.852956 -238.593809) (xy 114.891077 -238.562684) (xy 114.933698 -238.538077) (xy 114.979714 -238.520625)
			(xy 115.027933 -238.510781) (xy 115.077108 -238.5088) (xy 115.125963 -238.514732) (xy 115.173234 -238.528424)
			(xy 115.217696 -238.549522) (xy 115.258199 -238.577478) (xy 115.293692 -238.61157) (xy 115.323257 -238.650914)
			(xy 115.346128 -238.694491) (xy 115.361712 -238.741172) (xy 115.369607 -238.789749) (xy 115.370102 -238.814356)
			(xy 115.699044 -238.814356) (xy 115.703004 -238.765302) (xy 115.714781 -238.717518) (xy 115.734072 -238.672242)
			(xy 115.760375 -238.630646) (xy 115.79301 -238.593809) (xy 115.831131 -238.562684) (xy 115.873752 -238.538077)
			(xy 115.919768 -238.520625) (xy 115.967987 -238.510781) (xy 116.017162 -238.5088) (xy 116.066017 -238.514732)
			(xy 116.113288 -238.528424) (xy 116.15775 -238.549522) (xy 116.198253 -238.577478) (xy 116.233746 -238.61157)
			(xy 116.263311 -238.650914) (xy 116.286182 -238.694491) (xy 116.301766 -238.741172) (xy 116.309661 -238.789749)
			(xy 116.310156 -238.814356) (xy 118.518952 -238.814356) (xy 118.522912 -238.765302) (xy 118.534689 -238.717518)
			(xy 118.55398 -238.672242) (xy 118.580283 -238.630646) (xy 118.612918 -238.593809) (xy 118.651039 -238.562684)
			(xy 118.69366 -238.538077) (xy 118.739676 -238.520625) (xy 118.787895 -238.510781) (xy 118.83707 -238.5088)
			(xy 118.885925 -238.514732) (xy 118.933196 -238.528424) (xy 118.977658 -238.549522) (xy 119.018161 -238.577478)
			(xy 119.053654 -238.61157) (xy 119.083219 -238.650914) (xy 119.10609 -238.694491) (xy 119.121674 -238.741172)
			(xy 119.129569 -238.789749) (xy 119.130064 -238.814356) (xy 121.33886 -238.814356) (xy 121.34282 -238.765302)
			(xy 121.354597 -238.717518) (xy 121.373888 -238.672242) (xy 121.400191 -238.630646) (xy 121.432826 -238.593809)
			(xy 121.470947 -238.562684) (xy 121.513568 -238.538077) (xy 121.559584 -238.520625) (xy 121.607803 -238.510781)
			(xy 121.656978 -238.5088) (xy 121.705833 -238.514732) (xy 121.753104 -238.528424) (xy 121.797566 -238.549522)
			(xy 121.838069 -238.577478) (xy 121.873562 -238.61157) (xy 121.903127 -238.650914) (xy 121.925998 -238.694491)
			(xy 121.941582 -238.741172) (xy 121.949477 -238.789749) (xy 121.949972 -238.814356) (xy 124.159022 -238.814356)
			(xy 124.162982 -238.765302) (xy 124.174759 -238.717518) (xy 124.19405 -238.672242) (xy 124.220353 -238.630646)
			(xy 124.252988 -238.593809) (xy 124.291109 -238.562684) (xy 124.33373 -238.538077) (xy 124.379746 -238.520625)
			(xy 124.427965 -238.510781) (xy 124.47714 -238.5088) (xy 124.525995 -238.514732) (xy 124.573266 -238.528424)
			(xy 124.617728 -238.549522) (xy 124.658231 -238.577478) (xy 124.693724 -238.61157) (xy 124.723289 -238.650914)
			(xy 124.74616 -238.694491) (xy 124.761744 -238.741172) (xy 124.769639 -238.789749) (xy 124.770134 -238.814356)
			(xy 124.769639 -238.838963) (xy 124.761744 -238.88754) (xy 124.74616 -238.934221) (xy 124.723289 -238.977798)
			(xy 124.693724 -239.017142) (xy 124.658231 -239.051234) (xy 124.617728 -239.07919) (xy 124.573266 -239.100288)
			(xy 124.525995 -239.11398) (xy 124.47714 -239.119912) (xy 124.427965 -239.117931) (xy 124.379746 -239.108087)
			(xy 124.33373 -239.090635) (xy 124.291109 -239.066028) (xy 124.252988 -239.034903) (xy 124.220353 -238.998066)
			(xy 124.19405 -238.95647) (xy 124.174759 -238.911194) (xy 124.162982 -238.86341) (xy 124.159022 -238.814356)
			(xy 121.949972 -238.814356) (xy 121.949477 -238.838963) (xy 121.941582 -238.88754) (xy 121.925998 -238.934221)
			(xy 121.903127 -238.977798) (xy 121.873562 -239.017142) (xy 121.838069 -239.051234) (xy 121.797566 -239.07919)
			(xy 121.753104 -239.100288) (xy 121.705833 -239.11398) (xy 121.656978 -239.119912) (xy 121.607803 -239.117931)
			(xy 121.559584 -239.108087) (xy 121.513568 -239.090635) (xy 121.470947 -239.066028) (xy 121.432826 -239.034903)
			(xy 121.400191 -238.998066) (xy 121.373888 -238.95647) (xy 121.354597 -238.911194) (xy 121.34282 -238.86341)
			(xy 121.33886 -238.814356) (xy 119.130064 -238.814356) (xy 119.129569 -238.838963) (xy 119.121674 -238.88754)
			(xy 119.10609 -238.934221) (xy 119.083219 -238.977798) (xy 119.053654 -239.017142) (xy 119.018161 -239.051234)
			(xy 118.977658 -239.07919) (xy 118.933196 -239.100288) (xy 118.885925 -239.11398) (xy 118.83707 -239.119912)
			(xy 118.787895 -239.117931) (xy 118.739676 -239.108087) (xy 118.69366 -239.090635) (xy 118.651039 -239.066028)
			(xy 118.612918 -239.034903) (xy 118.580283 -238.998066) (xy 118.55398 -238.95647) (xy 118.534689 -238.911194)
			(xy 118.522912 -238.86341) (xy 118.518952 -238.814356) (xy 116.310156 -238.814356) (xy 116.309661 -238.838963)
			(xy 116.301766 -238.88754) (xy 116.286182 -238.934221) (xy 116.263311 -238.977798) (xy 116.233746 -239.017142)
			(xy 116.198253 -239.051234) (xy 116.15775 -239.07919) (xy 116.113288 -239.100288) (xy 116.066017 -239.11398)
			(xy 116.017162 -239.119912) (xy 115.967987 -239.117931) (xy 115.919768 -239.108087) (xy 115.873752 -239.090635)
			(xy 115.831131 -239.066028) (xy 115.79301 -239.034903) (xy 115.760375 -238.998066) (xy 115.734072 -238.95647)
			(xy 115.714781 -238.911194) (xy 115.703004 -238.86341) (xy 115.699044 -238.814356) (xy 115.370102 -238.814356)
			(xy 115.369607 -238.838963) (xy 115.361712 -238.88754) (xy 115.346128 -238.934221) (xy 115.323257 -238.977798)
			(xy 115.293692 -239.017142) (xy 115.258199 -239.051234) (xy 115.217696 -239.07919) (xy 115.173234 -239.100288)
			(xy 115.125963 -239.11398) (xy 115.077108 -239.119912) (xy 115.027933 -239.117931) (xy 114.979714 -239.108087)
			(xy 114.933698 -239.090635) (xy 114.891077 -239.066028) (xy 114.852956 -239.034903) (xy 114.820321 -238.998066)
			(xy 114.794018 -238.95647) (xy 114.774727 -238.911194) (xy 114.76295 -238.86341) (xy 114.75899 -238.814356)
			(xy 114.430048 -238.814356) (xy 114.429553 -238.838963) (xy 114.421658 -238.88754) (xy 114.406074 -238.934221)
			(xy 114.383203 -238.977798) (xy 114.353638 -239.017142) (xy 114.318145 -239.051234) (xy 114.277642 -239.07919)
			(xy 114.23318 -239.100288) (xy 114.185909 -239.11398) (xy 114.137054 -239.119912) (xy 114.087879 -239.117931)
			(xy 114.03966 -239.108087) (xy 113.993644 -239.090635) (xy 113.951023 -239.066028) (xy 113.912902 -239.034903)
			(xy 113.880267 -238.998066) (xy 113.853964 -238.95647) (xy 113.834673 -238.911194) (xy 113.822896 -238.86341)
			(xy 113.818936 -238.814356) (xy 113.489994 -238.814356) (xy 113.489499 -238.838963) (xy 113.481604 -238.88754)
			(xy 113.46602 -238.934221) (xy 113.443149 -238.977798) (xy 113.413584 -239.017142) (xy 113.378091 -239.051234)
			(xy 113.337588 -239.07919) (xy 113.293126 -239.100288) (xy 113.245855 -239.11398) (xy 113.197 -239.119912)
			(xy 113.147825 -239.117931) (xy 113.099606 -239.108087) (xy 113.05359 -239.090635) (xy 113.010969 -239.066028)
			(xy 112.972848 -239.034903) (xy 112.940213 -238.998066) (xy 112.91391 -238.95647) (xy 112.894619 -238.911194)
			(xy 112.882842 -238.86341) (xy 112.878882 -238.814356) (xy 111.90986 -238.814356) (xy 111.90986 -239.624362)
			(xy 115.22889 -239.624362) (xy 115.23285 -239.575308) (xy 115.244627 -239.527524) (xy 115.263918 -239.482248)
			(xy 115.290221 -239.440652) (xy 115.322856 -239.403815) (xy 115.360977 -239.37269) (xy 115.403598 -239.348083)
			(xy 115.449614 -239.330631) (xy 115.497833 -239.320787) (xy 115.547008 -239.318806) (xy 115.595863 -239.324738)
			(xy 115.643134 -239.33843) (xy 115.687596 -239.359528) (xy 115.728099 -239.387484) (xy 115.763592 -239.421576)
			(xy 115.793157 -239.46092) (xy 115.816028 -239.504497) (xy 115.831612 -239.551178) (xy 115.839507 -239.599755)
			(xy 115.840002 -239.624362) (xy 116.168944 -239.624362) (xy 116.172904 -239.575308) (xy 116.184681 -239.527524)
			(xy 116.203972 -239.482248) (xy 116.230275 -239.440652) (xy 116.26291 -239.403815) (xy 116.301031 -239.37269)
			(xy 116.343652 -239.348083) (xy 116.389668 -239.330631) (xy 116.437887 -239.320787) (xy 116.487062 -239.318806)
			(xy 116.535917 -239.324738) (xy 116.583188 -239.33843) (xy 116.62765 -239.359528) (xy 116.668153 -239.387484)
			(xy 116.703646 -239.421576) (xy 116.733211 -239.46092) (xy 116.756082 -239.504497) (xy 116.771666 -239.551178)
			(xy 116.779561 -239.599755) (xy 116.780056 -239.624362) (xy 117.108998 -239.624362) (xy 117.112958 -239.575308)
			(xy 117.124735 -239.527524) (xy 117.144026 -239.482248) (xy 117.170329 -239.440652) (xy 117.202964 -239.403815)
			(xy 117.241085 -239.37269) (xy 117.283706 -239.348083) (xy 117.329722 -239.330631) (xy 117.377941 -239.320787)
			(xy 117.427116 -239.318806) (xy 117.475971 -239.324738) (xy 117.523242 -239.33843) (xy 117.567704 -239.359528)
			(xy 117.608207 -239.387484) (xy 117.6437 -239.421576) (xy 117.673265 -239.46092) (xy 117.696136 -239.504497)
			(xy 117.71172 -239.551178) (xy 117.719615 -239.599755) (xy 117.72011 -239.624362) (xy 118.049052 -239.624362)
			(xy 118.053012 -239.575308) (xy 118.064789 -239.527524) (xy 118.08408 -239.482248) (xy 118.110383 -239.440652)
			(xy 118.143018 -239.403815) (xy 118.181139 -239.37269) (xy 118.22376 -239.348083) (xy 118.269776 -239.330631)
			(xy 118.317995 -239.320787) (xy 118.36717 -239.318806) (xy 118.416025 -239.324738) (xy 118.463296 -239.33843)
			(xy 118.507758 -239.359528) (xy 118.548261 -239.387484) (xy 118.583754 -239.421576) (xy 118.613319 -239.46092)
			(xy 118.63619 -239.504497) (xy 118.651774 -239.551178) (xy 118.659669 -239.599755) (xy 118.660164 -239.624362)
			(xy 118.988852 -239.624362) (xy 118.992812 -239.575308) (xy 119.004589 -239.527524) (xy 119.02388 -239.482248)
			(xy 119.050183 -239.440652) (xy 119.082818 -239.403815) (xy 119.120939 -239.37269) (xy 119.16356 -239.348083)
			(xy 119.209576 -239.330631) (xy 119.257795 -239.320787) (xy 119.30697 -239.318806) (xy 119.355825 -239.324738)
			(xy 119.403096 -239.33843) (xy 119.447558 -239.359528) (xy 119.488061 -239.387484) (xy 119.523554 -239.421576)
			(xy 119.553119 -239.46092) (xy 119.57599 -239.504497) (xy 119.591574 -239.551178) (xy 119.599469 -239.599755)
			(xy 119.599964 -239.624362) (xy 119.928906 -239.624362) (xy 119.932866 -239.575308) (xy 119.944643 -239.527524)
			(xy 119.963934 -239.482248) (xy 119.990237 -239.440652) (xy 120.022872 -239.403815) (xy 120.060993 -239.37269)
			(xy 120.103614 -239.348083) (xy 120.14963 -239.330631) (xy 120.197849 -239.320787) (xy 120.247024 -239.318806)
			(xy 120.295879 -239.324738) (xy 120.34315 -239.33843) (xy 120.387612 -239.359528) (xy 120.428115 -239.387484)
			(xy 120.463608 -239.421576) (xy 120.493173 -239.46092) (xy 120.516044 -239.504497) (xy 120.531628 -239.551178)
			(xy 120.539523 -239.599755) (xy 120.540018 -239.624362) (xy 120.86896 -239.624362) (xy 120.87292 -239.575308)
			(xy 120.884697 -239.527524) (xy 120.903988 -239.482248) (xy 120.930291 -239.440652) (xy 120.962926 -239.403815)
			(xy 121.001047 -239.37269) (xy 121.043668 -239.348083) (xy 121.089684 -239.330631) (xy 121.137903 -239.320787)
			(xy 121.187078 -239.318806) (xy 121.235933 -239.324738) (xy 121.283204 -239.33843) (xy 121.327666 -239.359528)
			(xy 121.368169 -239.387484) (xy 121.403662 -239.421576) (xy 121.433227 -239.46092) (xy 121.456098 -239.504497)
			(xy 121.471682 -239.551178) (xy 121.479577 -239.599755) (xy 121.480072 -239.624362) (xy 121.809014 -239.624362)
			(xy 121.812974 -239.575308) (xy 121.824751 -239.527524) (xy 121.844042 -239.482248) (xy 121.870345 -239.440652)
			(xy 121.90298 -239.403815) (xy 121.941101 -239.37269) (xy 121.983722 -239.348083) (xy 122.029738 -239.330631)
			(xy 122.077957 -239.320787) (xy 122.127132 -239.318806) (xy 122.175987 -239.324738) (xy 122.223258 -239.33843)
			(xy 122.26772 -239.359528) (xy 122.308223 -239.387484) (xy 122.343716 -239.421576) (xy 122.373281 -239.46092)
			(xy 122.396152 -239.504497) (xy 122.411736 -239.551178) (xy 122.419631 -239.599755) (xy 122.420126 -239.624362)
			(xy 122.748814 -239.624362) (xy 122.752774 -239.575308) (xy 122.764551 -239.527524) (xy 122.783842 -239.482248)
			(xy 122.810145 -239.440652) (xy 122.84278 -239.403815) (xy 122.880901 -239.37269) (xy 122.923522 -239.348083)
			(xy 122.969538 -239.330631) (xy 123.017757 -239.320787) (xy 123.066932 -239.318806) (xy 123.115787 -239.324738)
			(xy 123.163058 -239.33843) (xy 123.20752 -239.359528) (xy 123.248023 -239.387484) (xy 123.283516 -239.421576)
			(xy 123.313081 -239.46092) (xy 123.335952 -239.504497) (xy 123.351536 -239.551178) (xy 123.359431 -239.599755)
			(xy 123.359926 -239.624362) (xy 123.688868 -239.624362) (xy 123.692828 -239.575308) (xy 123.704605 -239.527524)
			(xy 123.723896 -239.482248) (xy 123.750199 -239.440652) (xy 123.782834 -239.403815) (xy 123.820955 -239.37269)
			(xy 123.863576 -239.348083) (xy 123.909592 -239.330631) (xy 123.957811 -239.320787) (xy 124.006986 -239.318806)
			(xy 124.055841 -239.324738) (xy 124.103112 -239.33843) (xy 124.147574 -239.359528) (xy 124.188077 -239.387484)
			(xy 124.22357 -239.421576) (xy 124.253135 -239.46092) (xy 124.276006 -239.504497) (xy 124.29159 -239.551178)
			(xy 124.299485 -239.599755) (xy 124.29998 -239.624362) (xy 124.628922 -239.624362) (xy 124.632882 -239.575308)
			(xy 124.644659 -239.527524) (xy 124.66395 -239.482248) (xy 124.690253 -239.440652) (xy 124.722888 -239.403815)
			(xy 124.761009 -239.37269) (xy 124.80363 -239.348083) (xy 124.849646 -239.330631) (xy 124.897865 -239.320787)
			(xy 124.94704 -239.318806) (xy 124.995895 -239.324738) (xy 125.043166 -239.33843) (xy 125.087628 -239.359528)
			(xy 125.128131 -239.387484) (xy 125.163624 -239.421576) (xy 125.193189 -239.46092) (xy 125.21606 -239.504497)
			(xy 125.231644 -239.551178) (xy 125.239539 -239.599755) (xy 125.240034 -239.624362) (xy 125.568976 -239.624362)
			(xy 125.572936 -239.575308) (xy 125.584713 -239.527524) (xy 125.604004 -239.482248) (xy 125.630307 -239.440652)
			(xy 125.662942 -239.403815) (xy 125.701063 -239.37269) (xy 125.743684 -239.348083) (xy 125.7897 -239.330631)
			(xy 125.837919 -239.320787) (xy 125.887094 -239.318806) (xy 125.935949 -239.324738) (xy 125.98322 -239.33843)
			(xy 126.027682 -239.359528) (xy 126.068185 -239.387484) (xy 126.103678 -239.421576) (xy 126.133243 -239.46092)
			(xy 126.156114 -239.504497) (xy 126.171698 -239.551178) (xy 126.179593 -239.599755) (xy 126.180088 -239.624362)
			(xy 126.179593 -239.648969) (xy 126.171698 -239.697546) (xy 126.156114 -239.744227) (xy 126.133243 -239.787804)
			(xy 126.103678 -239.827148) (xy 126.068185 -239.86124) (xy 126.027682 -239.889196) (xy 125.98322 -239.910294)
			(xy 125.935949 -239.923986) (xy 125.887094 -239.929918) (xy 125.837919 -239.927937) (xy 125.7897 -239.918093)
			(xy 125.743684 -239.900641) (xy 125.701063 -239.876034) (xy 125.662942 -239.844909) (xy 125.630307 -239.808072)
			(xy 125.604004 -239.766476) (xy 125.584713 -239.7212) (xy 125.572936 -239.673416) (xy 125.568976 -239.624362)
			(xy 125.240034 -239.624362) (xy 125.239539 -239.648969) (xy 125.231644 -239.697546) (xy 125.21606 -239.744227)
			(xy 125.193189 -239.787804) (xy 125.163624 -239.827148) (xy 125.128131 -239.86124) (xy 125.087628 -239.889196)
			(xy 125.043166 -239.910294) (xy 124.995895 -239.923986) (xy 124.94704 -239.929918) (xy 124.897865 -239.927937)
			(xy 124.849646 -239.918093) (xy 124.80363 -239.900641) (xy 124.761009 -239.876034) (xy 124.722888 -239.844909)
			(xy 124.690253 -239.808072) (xy 124.66395 -239.766476) (xy 124.644659 -239.7212) (xy 124.632882 -239.673416)
			(xy 124.628922 -239.624362) (xy 124.29998 -239.624362) (xy 124.299485 -239.648969) (xy 124.29159 -239.697546)
			(xy 124.276006 -239.744227) (xy 124.253135 -239.787804) (xy 124.22357 -239.827148) (xy 124.188077 -239.86124)
			(xy 124.147574 -239.889196) (xy 124.103112 -239.910294) (xy 124.055841 -239.923986) (xy 124.006986 -239.929918)
			(xy 123.957811 -239.927937) (xy 123.909592 -239.918093) (xy 123.863576 -239.900641) (xy 123.820955 -239.876034)
			(xy 123.782834 -239.844909) (xy 123.750199 -239.808072) (xy 123.723896 -239.766476) (xy 123.704605 -239.7212)
			(xy 123.692828 -239.673416) (xy 123.688868 -239.624362) (xy 123.359926 -239.624362) (xy 123.359431 -239.648969)
			(xy 123.351536 -239.697546) (xy 123.335952 -239.744227) (xy 123.313081 -239.787804) (xy 123.283516 -239.827148)
			(xy 123.248023 -239.86124) (xy 123.20752 -239.889196) (xy 123.163058 -239.910294) (xy 123.115787 -239.923986)
			(xy 123.066932 -239.929918) (xy 123.017757 -239.927937) (xy 122.969538 -239.918093) (xy 122.923522 -239.900641)
			(xy 122.880901 -239.876034) (xy 122.84278 -239.844909) (xy 122.810145 -239.808072) (xy 122.783842 -239.766476)
			(xy 122.764551 -239.7212) (xy 122.752774 -239.673416) (xy 122.748814 -239.624362) (xy 122.420126 -239.624362)
			(xy 122.419631 -239.648969) (xy 122.411736 -239.697546) (xy 122.396152 -239.744227) (xy 122.373281 -239.787804)
			(xy 122.343716 -239.827148) (xy 122.308223 -239.86124) (xy 122.26772 -239.889196) (xy 122.223258 -239.910294)
			(xy 122.175987 -239.923986) (xy 122.127132 -239.929918) (xy 122.077957 -239.927937) (xy 122.029738 -239.918093)
			(xy 121.983722 -239.900641) (xy 121.941101 -239.876034) (xy 121.90298 -239.844909) (xy 121.870345 -239.808072)
			(xy 121.844042 -239.766476) (xy 121.824751 -239.7212) (xy 121.812974 -239.673416) (xy 121.809014 -239.624362)
			(xy 121.480072 -239.624362) (xy 121.479577 -239.648969) (xy 121.471682 -239.697546) (xy 121.456098 -239.744227)
			(xy 121.433227 -239.787804) (xy 121.403662 -239.827148) (xy 121.368169 -239.86124) (xy 121.327666 -239.889196)
			(xy 121.283204 -239.910294) (xy 121.235933 -239.923986) (xy 121.187078 -239.929918) (xy 121.137903 -239.927937)
			(xy 121.089684 -239.918093) (xy 121.043668 -239.900641) (xy 121.001047 -239.876034) (xy 120.962926 -239.844909)
			(xy 120.930291 -239.808072) (xy 120.903988 -239.766476) (xy 120.884697 -239.7212) (xy 120.87292 -239.673416)
			(xy 120.86896 -239.624362) (xy 120.540018 -239.624362) (xy 120.539523 -239.648969) (xy 120.531628 -239.697546)
			(xy 120.516044 -239.744227) (xy 120.493173 -239.787804) (xy 120.463608 -239.827148) (xy 120.428115 -239.86124)
			(xy 120.387612 -239.889196) (xy 120.34315 -239.910294) (xy 120.295879 -239.923986) (xy 120.247024 -239.929918)
			(xy 120.197849 -239.927937) (xy 120.14963 -239.918093) (xy 120.103614 -239.900641) (xy 120.060993 -239.876034)
			(xy 120.022872 -239.844909) (xy 119.990237 -239.808072) (xy 119.963934 -239.766476) (xy 119.944643 -239.7212)
			(xy 119.932866 -239.673416) (xy 119.928906 -239.624362) (xy 119.599964 -239.624362) (xy 119.599469 -239.648969)
			(xy 119.591574 -239.697546) (xy 119.57599 -239.744227) (xy 119.553119 -239.787804) (xy 119.523554 -239.827148)
			(xy 119.488061 -239.86124) (xy 119.447558 -239.889196) (xy 119.403096 -239.910294) (xy 119.355825 -239.923986)
			(xy 119.30697 -239.929918) (xy 119.257795 -239.927937) (xy 119.209576 -239.918093) (xy 119.16356 -239.900641)
			(xy 119.120939 -239.876034) (xy 119.082818 -239.844909) (xy 119.050183 -239.808072) (xy 119.02388 -239.766476)
			(xy 119.004589 -239.7212) (xy 118.992812 -239.673416) (xy 118.988852 -239.624362) (xy 118.660164 -239.624362)
			(xy 118.659669 -239.648969) (xy 118.651774 -239.697546) (xy 118.63619 -239.744227) (xy 118.613319 -239.787804)
			(xy 118.583754 -239.827148) (xy 118.548261 -239.86124) (xy 118.507758 -239.889196) (xy 118.463296 -239.910294)
			(xy 118.416025 -239.923986) (xy 118.36717 -239.929918) (xy 118.317995 -239.927937) (xy 118.269776 -239.918093)
			(xy 118.22376 -239.900641) (xy 118.181139 -239.876034) (xy 118.143018 -239.844909) (xy 118.110383 -239.808072)
			(xy 118.08408 -239.766476) (xy 118.064789 -239.7212) (xy 118.053012 -239.673416) (xy 118.049052 -239.624362)
			(xy 117.72011 -239.624362) (xy 117.719615 -239.648969) (xy 117.71172 -239.697546) (xy 117.696136 -239.744227)
			(xy 117.673265 -239.787804) (xy 117.6437 -239.827148) (xy 117.608207 -239.86124) (xy 117.567704 -239.889196)
			(xy 117.523242 -239.910294) (xy 117.475971 -239.923986) (xy 117.427116 -239.929918) (xy 117.377941 -239.927937)
			(xy 117.329722 -239.918093) (xy 117.283706 -239.900641) (xy 117.241085 -239.876034) (xy 117.202964 -239.844909)
			(xy 117.170329 -239.808072) (xy 117.144026 -239.766476) (xy 117.124735 -239.7212) (xy 117.112958 -239.673416)
			(xy 117.108998 -239.624362) (xy 116.780056 -239.624362) (xy 116.779561 -239.648969) (xy 116.771666 -239.697546)
			(xy 116.756082 -239.744227) (xy 116.733211 -239.787804) (xy 116.703646 -239.827148) (xy 116.668153 -239.86124)
			(xy 116.62765 -239.889196) (xy 116.583188 -239.910294) (xy 116.535917 -239.923986) (xy 116.487062 -239.929918)
			(xy 116.437887 -239.927937) (xy 116.389668 -239.918093) (xy 116.343652 -239.900641) (xy 116.301031 -239.876034)
			(xy 116.26291 -239.844909) (xy 116.230275 -239.808072) (xy 116.203972 -239.766476) (xy 116.184681 -239.7212)
			(xy 116.172904 -239.673416) (xy 116.168944 -239.624362) (xy 115.840002 -239.624362) (xy 115.839507 -239.648969)
			(xy 115.831612 -239.697546) (xy 115.816028 -239.744227) (xy 115.793157 -239.787804) (xy 115.763592 -239.827148)
			(xy 115.728099 -239.86124) (xy 115.687596 -239.889196) (xy 115.643134 -239.910294) (xy 115.595863 -239.923986)
			(xy 115.547008 -239.929918) (xy 115.497833 -239.927937) (xy 115.449614 -239.918093) (xy 115.403598 -239.900641)
			(xy 115.360977 -239.876034) (xy 115.322856 -239.844909) (xy 115.290221 -239.808072) (xy 115.263918 -239.766476)
			(xy 115.244627 -239.7212) (xy 115.23285 -239.673416) (xy 115.22889 -239.624362) (xy 111.90986 -239.624362)
			(xy 111.90986 -240.434368) (xy 112.878882 -240.434368) (xy 112.882842 -240.385314) (xy 112.894619 -240.33753)
			(xy 112.91391 -240.292254) (xy 112.940213 -240.250658) (xy 112.972848 -240.213821) (xy 113.010969 -240.182696)
			(xy 113.05359 -240.158089) (xy 113.099606 -240.140637) (xy 113.147825 -240.130793) (xy 113.197 -240.128812)
			(xy 113.245855 -240.134744) (xy 113.293126 -240.148436) (xy 113.337588 -240.169534) (xy 113.378091 -240.19749)
			(xy 113.413584 -240.231582) (xy 113.443149 -240.270926) (xy 113.46602 -240.314503) (xy 113.481604 -240.361184)
			(xy 113.489499 -240.409761) (xy 113.489994 -240.434368) (xy 113.818936 -240.434368) (xy 113.822896 -240.385314)
			(xy 113.834673 -240.33753) (xy 113.853964 -240.292254) (xy 113.880267 -240.250658) (xy 113.912902 -240.213821)
			(xy 113.951023 -240.182696) (xy 113.993644 -240.158089) (xy 114.03966 -240.140637) (xy 114.087879 -240.130793)
			(xy 114.137054 -240.128812) (xy 114.185909 -240.134744) (xy 114.23318 -240.148436) (xy 114.277642 -240.169534)
			(xy 114.318145 -240.19749) (xy 114.353638 -240.231582) (xy 114.383203 -240.270926) (xy 114.406074 -240.314503)
			(xy 114.421658 -240.361184) (xy 114.429553 -240.409761) (xy 114.430048 -240.434368) (xy 114.75899 -240.434368)
			(xy 114.76295 -240.385314) (xy 114.774727 -240.33753) (xy 114.794018 -240.292254) (xy 114.820321 -240.250658)
			(xy 114.852956 -240.213821) (xy 114.891077 -240.182696) (xy 114.933698 -240.158089) (xy 114.979714 -240.140637)
			(xy 115.027933 -240.130793) (xy 115.077108 -240.128812) (xy 115.125963 -240.134744) (xy 115.173234 -240.148436)
			(xy 115.217696 -240.169534) (xy 115.258199 -240.19749) (xy 115.293692 -240.231582) (xy 115.323257 -240.270926)
			(xy 115.346128 -240.314503) (xy 115.361712 -240.361184) (xy 115.369607 -240.409761) (xy 115.370102 -240.434368)
			(xy 115.699044 -240.434368) (xy 115.703004 -240.385314) (xy 115.714781 -240.33753) (xy 115.734072 -240.292254)
			(xy 115.760375 -240.250658) (xy 115.79301 -240.213821) (xy 115.831131 -240.182696) (xy 115.873752 -240.158089)
			(xy 115.919768 -240.140637) (xy 115.967987 -240.130793) (xy 116.017162 -240.128812) (xy 116.066017 -240.134744)
			(xy 116.113288 -240.148436) (xy 116.15775 -240.169534) (xy 116.198253 -240.19749) (xy 116.233746 -240.231582)
			(xy 116.263311 -240.270926) (xy 116.286182 -240.314503) (xy 116.301766 -240.361184) (xy 116.309661 -240.409761)
			(xy 116.310156 -240.434368) (xy 116.638844 -240.434368) (xy 116.642804 -240.385314) (xy 116.654581 -240.33753)
			(xy 116.673872 -240.292254) (xy 116.700175 -240.250658) (xy 116.73281 -240.213821) (xy 116.770931 -240.182696)
			(xy 116.813552 -240.158089) (xy 116.859568 -240.140637) (xy 116.907787 -240.130793) (xy 116.956962 -240.128812)
			(xy 117.005817 -240.134744) (xy 117.053088 -240.148436) (xy 117.09755 -240.169534) (xy 117.138053 -240.19749)
			(xy 117.173546 -240.231582) (xy 117.203111 -240.270926) (xy 117.225982 -240.314503) (xy 117.241566 -240.361184)
			(xy 117.249461 -240.409761) (xy 117.249956 -240.434368) (xy 117.578898 -240.434368) (xy 117.582858 -240.385314)
			(xy 117.594635 -240.33753) (xy 117.613926 -240.292254) (xy 117.640229 -240.250658) (xy 117.672864 -240.213821)
			(xy 117.710985 -240.182696) (xy 117.753606 -240.158089) (xy 117.799622 -240.140637) (xy 117.847841 -240.130793)
			(xy 117.897016 -240.128812) (xy 117.945871 -240.134744) (xy 117.993142 -240.148436) (xy 118.037604 -240.169534)
			(xy 118.078107 -240.19749) (xy 118.1136 -240.231582) (xy 118.143165 -240.270926) (xy 118.166036 -240.314503)
			(xy 118.18162 -240.361184) (xy 118.189515 -240.409761) (xy 118.19001 -240.434368) (xy 118.518952 -240.434368)
			(xy 118.522912 -240.385314) (xy 118.534689 -240.33753) (xy 118.55398 -240.292254) (xy 118.580283 -240.250658)
			(xy 118.612918 -240.213821) (xy 118.651039 -240.182696) (xy 118.69366 -240.158089) (xy 118.739676 -240.140637)
			(xy 118.787895 -240.130793) (xy 118.83707 -240.128812) (xy 118.885925 -240.134744) (xy 118.933196 -240.148436)
			(xy 118.977658 -240.169534) (xy 119.018161 -240.19749) (xy 119.053654 -240.231582) (xy 119.083219 -240.270926)
			(xy 119.10609 -240.314503) (xy 119.121674 -240.361184) (xy 119.129569 -240.409761) (xy 119.130064 -240.434368)
			(xy 119.459006 -240.434368) (xy 119.462966 -240.385314) (xy 119.474743 -240.33753) (xy 119.494034 -240.292254)
			(xy 119.520337 -240.250658) (xy 119.552972 -240.213821) (xy 119.591093 -240.182696) (xy 119.633714 -240.158089)
			(xy 119.67973 -240.140637) (xy 119.727949 -240.130793) (xy 119.777124 -240.128812) (xy 119.825979 -240.134744)
			(xy 119.87325 -240.148436) (xy 119.917712 -240.169534) (xy 119.958215 -240.19749) (xy 119.993708 -240.231582)
			(xy 120.023273 -240.270926) (xy 120.046144 -240.314503) (xy 120.061728 -240.361184) (xy 120.069623 -240.409761)
			(xy 120.070118 -240.434368) (xy 120.398806 -240.434368) (xy 120.402766 -240.385314) (xy 120.414543 -240.33753)
			(xy 120.433834 -240.292254) (xy 120.460137 -240.250658) (xy 120.492772 -240.213821) (xy 120.530893 -240.182696)
			(xy 120.573514 -240.158089) (xy 120.61953 -240.140637) (xy 120.667749 -240.130793) (xy 120.716924 -240.128812)
			(xy 120.765779 -240.134744) (xy 120.81305 -240.148436) (xy 120.857512 -240.169534) (xy 120.898015 -240.19749)
			(xy 120.933508 -240.231582) (xy 120.963073 -240.270926) (xy 120.985944 -240.314503) (xy 121.001528 -240.361184)
			(xy 121.009423 -240.409761) (xy 121.009918 -240.434368) (xy 121.33886 -240.434368) (xy 121.34282 -240.385314)
			(xy 121.354597 -240.33753) (xy 121.373888 -240.292254) (xy 121.400191 -240.250658) (xy 121.432826 -240.213821)
			(xy 121.470947 -240.182696) (xy 121.513568 -240.158089) (xy 121.559584 -240.140637) (xy 121.607803 -240.130793)
			(xy 121.656978 -240.128812) (xy 121.705833 -240.134744) (xy 121.753104 -240.148436) (xy 121.797566 -240.169534)
			(xy 121.838069 -240.19749) (xy 121.873562 -240.231582) (xy 121.903127 -240.270926) (xy 121.925998 -240.314503)
			(xy 121.941582 -240.361184) (xy 121.949477 -240.409761) (xy 121.949972 -240.434368) (xy 122.278914 -240.434368)
			(xy 122.282874 -240.385314) (xy 122.294651 -240.33753) (xy 122.313942 -240.292254) (xy 122.340245 -240.250658)
			(xy 122.37288 -240.213821) (xy 122.411001 -240.182696) (xy 122.453622 -240.158089) (xy 122.499638 -240.140637)
			(xy 122.547857 -240.130793) (xy 122.597032 -240.128812) (xy 122.645887 -240.134744) (xy 122.693158 -240.148436)
			(xy 122.73762 -240.169534) (xy 122.778123 -240.19749) (xy 122.813616 -240.231582) (xy 122.843181 -240.270926)
			(xy 122.866052 -240.314503) (xy 122.881636 -240.361184) (xy 122.889531 -240.409761) (xy 122.890026 -240.434368)
			(xy 123.218968 -240.434368) (xy 123.222928 -240.385314) (xy 123.234705 -240.33753) (xy 123.253996 -240.292254)
			(xy 123.280299 -240.250658) (xy 123.312934 -240.213821) (xy 123.351055 -240.182696) (xy 123.393676 -240.158089)
			(xy 123.439692 -240.140637) (xy 123.487911 -240.130793) (xy 123.537086 -240.128812) (xy 123.585941 -240.134744)
			(xy 123.633212 -240.148436) (xy 123.677674 -240.169534) (xy 123.718177 -240.19749) (xy 123.75367 -240.231582)
			(xy 123.783235 -240.270926) (xy 123.806106 -240.314503) (xy 123.82169 -240.361184) (xy 123.829585 -240.409761)
			(xy 123.83008 -240.434368) (xy 124.159022 -240.434368) (xy 124.162982 -240.385314) (xy 124.174759 -240.33753)
			(xy 124.19405 -240.292254) (xy 124.220353 -240.250658) (xy 124.252988 -240.213821) (xy 124.291109 -240.182696)
			(xy 124.33373 -240.158089) (xy 124.379746 -240.140637) (xy 124.427965 -240.130793) (xy 124.47714 -240.128812)
			(xy 124.525995 -240.134744) (xy 124.573266 -240.148436) (xy 124.617728 -240.169534) (xy 124.658231 -240.19749)
			(xy 124.693724 -240.231582) (xy 124.723289 -240.270926) (xy 124.74616 -240.314503) (xy 124.761744 -240.361184)
			(xy 124.769639 -240.409761) (xy 124.770134 -240.434368) (xy 125.098822 -240.434368) (xy 125.102782 -240.385314)
			(xy 125.114559 -240.33753) (xy 125.13385 -240.292254) (xy 125.160153 -240.250658) (xy 125.192788 -240.213821)
			(xy 125.230909 -240.182696) (xy 125.27353 -240.158089) (xy 125.319546 -240.140637) (xy 125.367765 -240.130793)
			(xy 125.41694 -240.128812) (xy 125.465795 -240.134744) (xy 125.513066 -240.148436) (xy 125.557528 -240.169534)
			(xy 125.598031 -240.19749) (xy 125.633524 -240.231582) (xy 125.663089 -240.270926) (xy 125.68596 -240.314503)
			(xy 125.701544 -240.361184) (xy 125.709439 -240.409761) (xy 125.709934 -240.434368) (xy 125.709439 -240.458975)
			(xy 125.701544 -240.507552) (xy 125.68596 -240.554233) (xy 125.663089 -240.59781) (xy 125.633524 -240.637154)
			(xy 125.598031 -240.671246) (xy 125.557528 -240.699202) (xy 125.513066 -240.7203) (xy 125.465795 -240.733992)
			(xy 125.41694 -240.739924) (xy 125.367765 -240.737943) (xy 125.319546 -240.728099) (xy 125.27353 -240.710647)
			(xy 125.230909 -240.68604) (xy 125.192788 -240.654915) (xy 125.160153 -240.618078) (xy 125.13385 -240.576482)
			(xy 125.114559 -240.531206) (xy 125.102782 -240.483422) (xy 125.098822 -240.434368) (xy 124.770134 -240.434368)
			(xy 124.769639 -240.458975) (xy 124.761744 -240.507552) (xy 124.74616 -240.554233) (xy 124.723289 -240.59781)
			(xy 124.693724 -240.637154) (xy 124.658231 -240.671246) (xy 124.617728 -240.699202) (xy 124.573266 -240.7203)
			(xy 124.525995 -240.733992) (xy 124.47714 -240.739924) (xy 124.427965 -240.737943) (xy 124.379746 -240.728099)
			(xy 124.33373 -240.710647) (xy 124.291109 -240.68604) (xy 124.252988 -240.654915) (xy 124.220353 -240.618078)
			(xy 124.19405 -240.576482) (xy 124.174759 -240.531206) (xy 124.162982 -240.483422) (xy 124.159022 -240.434368)
			(xy 123.83008 -240.434368) (xy 123.829585 -240.458975) (xy 123.82169 -240.507552) (xy 123.806106 -240.554233)
			(xy 123.783235 -240.59781) (xy 123.75367 -240.637154) (xy 123.718177 -240.671246) (xy 123.677674 -240.699202)
			(xy 123.633212 -240.7203) (xy 123.585941 -240.733992) (xy 123.537086 -240.739924) (xy 123.487911 -240.737943)
			(xy 123.439692 -240.728099) (xy 123.393676 -240.710647) (xy 123.351055 -240.68604) (xy 123.312934 -240.654915)
			(xy 123.280299 -240.618078) (xy 123.253996 -240.576482) (xy 123.234705 -240.531206) (xy 123.222928 -240.483422)
			(xy 123.218968 -240.434368) (xy 122.890026 -240.434368) (xy 122.889531 -240.458975) (xy 122.881636 -240.507552)
			(xy 122.866052 -240.554233) (xy 122.843181 -240.59781) (xy 122.813616 -240.637154) (xy 122.778123 -240.671246)
			(xy 122.73762 -240.699202) (xy 122.693158 -240.7203) (xy 122.645887 -240.733992) (xy 122.597032 -240.739924)
			(xy 122.547857 -240.737943) (xy 122.499638 -240.728099) (xy 122.453622 -240.710647) (xy 122.411001 -240.68604)
			(xy 122.37288 -240.654915) (xy 122.340245 -240.618078) (xy 122.313942 -240.576482) (xy 122.294651 -240.531206)
			(xy 122.282874 -240.483422) (xy 122.278914 -240.434368) (xy 121.949972 -240.434368) (xy 121.949477 -240.458975)
			(xy 121.941582 -240.507552) (xy 121.925998 -240.554233) (xy 121.903127 -240.59781) (xy 121.873562 -240.637154)
			(xy 121.838069 -240.671246) (xy 121.797566 -240.699202) (xy 121.753104 -240.7203) (xy 121.705833 -240.733992)
			(xy 121.656978 -240.739924) (xy 121.607803 -240.737943) (xy 121.559584 -240.728099) (xy 121.513568 -240.710647)
			(xy 121.470947 -240.68604) (xy 121.432826 -240.654915) (xy 121.400191 -240.618078) (xy 121.373888 -240.576482)
			(xy 121.354597 -240.531206) (xy 121.34282 -240.483422) (xy 121.33886 -240.434368) (xy 121.009918 -240.434368)
			(xy 121.009423 -240.458975) (xy 121.001528 -240.507552) (xy 120.985944 -240.554233) (xy 120.963073 -240.59781)
			(xy 120.933508 -240.637154) (xy 120.898015 -240.671246) (xy 120.857512 -240.699202) (xy 120.81305 -240.7203)
			(xy 120.765779 -240.733992) (xy 120.716924 -240.739924) (xy 120.667749 -240.737943) (xy 120.61953 -240.728099)
			(xy 120.573514 -240.710647) (xy 120.530893 -240.68604) (xy 120.492772 -240.654915) (xy 120.460137 -240.618078)
			(xy 120.433834 -240.576482) (xy 120.414543 -240.531206) (xy 120.402766 -240.483422) (xy 120.398806 -240.434368)
			(xy 120.070118 -240.434368) (xy 120.069623 -240.458975) (xy 120.061728 -240.507552) (xy 120.046144 -240.554233)
			(xy 120.023273 -240.59781) (xy 119.993708 -240.637154) (xy 119.958215 -240.671246) (xy 119.917712 -240.699202)
			(xy 119.87325 -240.7203) (xy 119.825979 -240.733992) (xy 119.777124 -240.739924) (xy 119.727949 -240.737943)
			(xy 119.67973 -240.728099) (xy 119.633714 -240.710647) (xy 119.591093 -240.68604) (xy 119.552972 -240.654915)
			(xy 119.520337 -240.618078) (xy 119.494034 -240.576482) (xy 119.474743 -240.531206) (xy 119.462966 -240.483422)
			(xy 119.459006 -240.434368) (xy 119.130064 -240.434368) (xy 119.129569 -240.458975) (xy 119.121674 -240.507552)
			(xy 119.10609 -240.554233) (xy 119.083219 -240.59781) (xy 119.053654 -240.637154) (xy 119.018161 -240.671246)
			(xy 118.977658 -240.699202) (xy 118.933196 -240.7203) (xy 118.885925 -240.733992) (xy 118.83707 -240.739924)
			(xy 118.787895 -240.737943) (xy 118.739676 -240.728099) (xy 118.69366 -240.710647) (xy 118.651039 -240.68604)
			(xy 118.612918 -240.654915) (xy 118.580283 -240.618078) (xy 118.55398 -240.576482) (xy 118.534689 -240.531206)
			(xy 118.522912 -240.483422) (xy 118.518952 -240.434368) (xy 118.19001 -240.434368) (xy 118.189515 -240.458975)
			(xy 118.18162 -240.507552) (xy 118.166036 -240.554233) (xy 118.143165 -240.59781) (xy 118.1136 -240.637154)
			(xy 118.078107 -240.671246) (xy 118.037604 -240.699202) (xy 117.993142 -240.7203) (xy 117.945871 -240.733992)
			(xy 117.897016 -240.739924) (xy 117.847841 -240.737943) (xy 117.799622 -240.728099) (xy 117.753606 -240.710647)
			(xy 117.710985 -240.68604) (xy 117.672864 -240.654915) (xy 117.640229 -240.618078) (xy 117.613926 -240.576482)
			(xy 117.594635 -240.531206) (xy 117.582858 -240.483422) (xy 117.578898 -240.434368) (xy 117.249956 -240.434368)
			(xy 117.249461 -240.458975) (xy 117.241566 -240.507552) (xy 117.225982 -240.554233) (xy 117.203111 -240.59781)
			(xy 117.173546 -240.637154) (xy 117.138053 -240.671246) (xy 117.09755 -240.699202) (xy 117.053088 -240.7203)
			(xy 117.005817 -240.733992) (xy 116.956962 -240.739924) (xy 116.907787 -240.737943) (xy 116.859568 -240.728099)
			(xy 116.813552 -240.710647) (xy 116.770931 -240.68604) (xy 116.73281 -240.654915) (xy 116.700175 -240.618078)
			(xy 116.673872 -240.576482) (xy 116.654581 -240.531206) (xy 116.642804 -240.483422) (xy 116.638844 -240.434368)
			(xy 116.310156 -240.434368) (xy 116.309661 -240.458975) (xy 116.301766 -240.507552) (xy 116.286182 -240.554233)
			(xy 116.263311 -240.59781) (xy 116.233746 -240.637154) (xy 116.198253 -240.671246) (xy 116.15775 -240.699202)
			(xy 116.113288 -240.7203) (xy 116.066017 -240.733992) (xy 116.017162 -240.739924) (xy 115.967987 -240.737943)
			(xy 115.919768 -240.728099) (xy 115.873752 -240.710647) (xy 115.831131 -240.68604) (xy 115.79301 -240.654915)
			(xy 115.760375 -240.618078) (xy 115.734072 -240.576482) (xy 115.714781 -240.531206) (xy 115.703004 -240.483422)
			(xy 115.699044 -240.434368) (xy 115.370102 -240.434368) (xy 115.369607 -240.458975) (xy 115.361712 -240.507552)
			(xy 115.346128 -240.554233) (xy 115.323257 -240.59781) (xy 115.293692 -240.637154) (xy 115.258199 -240.671246)
			(xy 115.217696 -240.699202) (xy 115.173234 -240.7203) (xy 115.125963 -240.733992) (xy 115.077108 -240.739924)
			(xy 115.027933 -240.737943) (xy 114.979714 -240.728099) (xy 114.933698 -240.710647) (xy 114.891077 -240.68604)
			(xy 114.852956 -240.654915) (xy 114.820321 -240.618078) (xy 114.794018 -240.576482) (xy 114.774727 -240.531206)
			(xy 114.76295 -240.483422) (xy 114.75899 -240.434368) (xy 114.430048 -240.434368) (xy 114.429553 -240.458975)
			(xy 114.421658 -240.507552) (xy 114.406074 -240.554233) (xy 114.383203 -240.59781) (xy 114.353638 -240.637154)
			(xy 114.318145 -240.671246) (xy 114.277642 -240.699202) (xy 114.23318 -240.7203) (xy 114.185909 -240.733992)
			(xy 114.137054 -240.739924) (xy 114.087879 -240.737943) (xy 114.03966 -240.728099) (xy 113.993644 -240.710647)
			(xy 113.951023 -240.68604) (xy 113.912902 -240.654915) (xy 113.880267 -240.618078) (xy 113.853964 -240.576482)
			(xy 113.834673 -240.531206) (xy 113.822896 -240.483422) (xy 113.818936 -240.434368) (xy 113.489994 -240.434368)
			(xy 113.489499 -240.458975) (xy 113.481604 -240.507552) (xy 113.46602 -240.554233) (xy 113.443149 -240.59781)
			(xy 113.413584 -240.637154) (xy 113.378091 -240.671246) (xy 113.337588 -240.699202) (xy 113.293126 -240.7203)
			(xy 113.245855 -240.733992) (xy 113.197 -240.739924) (xy 113.147825 -240.737943) (xy 113.099606 -240.728099)
			(xy 113.05359 -240.710647) (xy 113.010969 -240.68604) (xy 112.972848 -240.654915) (xy 112.940213 -240.618078)
			(xy 112.91391 -240.576482) (xy 112.894619 -240.531206) (xy 112.882842 -240.483422) (xy 112.878882 -240.434368)
			(xy 111.90986 -240.434368) (xy 111.90986 -241.244374) (xy 113.349036 -241.244374) (xy 113.352996 -241.19532)
			(xy 113.364773 -241.147536) (xy 113.384064 -241.10226) (xy 113.410367 -241.060664) (xy 113.443002 -241.023827)
			(xy 113.481123 -240.992702) (xy 113.523744 -240.968095) (xy 113.56976 -240.950643) (xy 113.617979 -240.940799)
			(xy 113.667154 -240.938818) (xy 113.716009 -240.94475) (xy 113.76328 -240.958442) (xy 113.807742 -240.97954)
			(xy 113.848245 -241.007496) (xy 113.883738 -241.041588) (xy 113.913303 -241.080932) (xy 113.936174 -241.124509)
			(xy 113.951758 -241.17119) (xy 113.959653 -241.219767) (xy 113.960148 -241.244374) (xy 114.288836 -241.244374)
			(xy 114.292796 -241.19532) (xy 114.304573 -241.147536) (xy 114.323864 -241.10226) (xy 114.350167 -241.060664)
			(xy 114.382802 -241.023827) (xy 114.420923 -240.992702) (xy 114.463544 -240.968095) (xy 114.50956 -240.950643)
			(xy 114.557779 -240.940799) (xy 114.606954 -240.938818) (xy 114.655809 -240.94475) (xy 114.70308 -240.958442)
			(xy 114.747542 -240.97954) (xy 114.788045 -241.007496) (xy 114.823538 -241.041588) (xy 114.853103 -241.080932)
			(xy 114.875974 -241.124509) (xy 114.891558 -241.17119) (xy 114.899453 -241.219767) (xy 114.899948 -241.244374)
			(xy 115.22889 -241.244374) (xy 115.23285 -241.19532) (xy 115.244627 -241.147536) (xy 115.263918 -241.10226)
			(xy 115.290221 -241.060664) (xy 115.322856 -241.023827) (xy 115.360977 -240.992702) (xy 115.403598 -240.968095)
			(xy 115.449614 -240.950643) (xy 115.497833 -240.940799) (xy 115.547008 -240.938818) (xy 115.595863 -240.94475)
			(xy 115.643134 -240.958442) (xy 115.687596 -240.97954) (xy 115.728099 -241.007496) (xy 115.763592 -241.041588)
			(xy 115.793157 -241.080932) (xy 115.816028 -241.124509) (xy 115.831612 -241.17119) (xy 115.839507 -241.219767)
			(xy 115.840002 -241.244374) (xy 116.168944 -241.244374) (xy 116.172904 -241.19532) (xy 116.184681 -241.147536)
			(xy 116.203972 -241.10226) (xy 116.230275 -241.060664) (xy 116.26291 -241.023827) (xy 116.301031 -240.992702)
			(xy 116.343652 -240.968095) (xy 116.389668 -240.950643) (xy 116.437887 -240.940799) (xy 116.487062 -240.938818)
			(xy 116.535917 -240.94475) (xy 116.583188 -240.958442) (xy 116.62765 -240.97954) (xy 116.668153 -241.007496)
			(xy 116.703646 -241.041588) (xy 116.733211 -241.080932) (xy 116.756082 -241.124509) (xy 116.771666 -241.17119)
			(xy 116.779561 -241.219767) (xy 116.780056 -241.244374) (xy 117.108998 -241.244374) (xy 117.112958 -241.19532)
			(xy 117.124735 -241.147536) (xy 117.144026 -241.10226) (xy 117.170329 -241.060664) (xy 117.202964 -241.023827)
			(xy 117.241085 -240.992702) (xy 117.283706 -240.968095) (xy 117.329722 -240.950643) (xy 117.377941 -240.940799)
			(xy 117.427116 -240.938818) (xy 117.475971 -240.94475) (xy 117.523242 -240.958442) (xy 117.567704 -240.97954)
			(xy 117.608207 -241.007496) (xy 117.6437 -241.041588) (xy 117.673265 -241.080932) (xy 117.696136 -241.124509)
			(xy 117.71172 -241.17119) (xy 117.719615 -241.219767) (xy 117.72011 -241.244374) (xy 118.049052 -241.244374)
			(xy 118.053012 -241.19532) (xy 118.064789 -241.147536) (xy 118.08408 -241.10226) (xy 118.110383 -241.060664)
			(xy 118.143018 -241.023827) (xy 118.181139 -240.992702) (xy 118.22376 -240.968095) (xy 118.269776 -240.950643)
			(xy 118.317995 -240.940799) (xy 118.36717 -240.938818) (xy 118.416025 -240.94475) (xy 118.463296 -240.958442)
			(xy 118.507758 -240.97954) (xy 118.548261 -241.007496) (xy 118.583754 -241.041588) (xy 118.613319 -241.080932)
			(xy 118.63619 -241.124509) (xy 118.651774 -241.17119) (xy 118.659669 -241.219767) (xy 118.660164 -241.244374)
			(xy 118.988852 -241.244374) (xy 118.992812 -241.19532) (xy 119.004589 -241.147536) (xy 119.02388 -241.10226)
			(xy 119.050183 -241.060664) (xy 119.082818 -241.023827) (xy 119.120939 -240.992702) (xy 119.16356 -240.968095)
			(xy 119.209576 -240.950643) (xy 119.257795 -240.940799) (xy 119.30697 -240.938818) (xy 119.355825 -240.94475)
			(xy 119.403096 -240.958442) (xy 119.447558 -240.97954) (xy 119.488061 -241.007496) (xy 119.523554 -241.041588)
			(xy 119.553119 -241.080932) (xy 119.57599 -241.124509) (xy 119.591574 -241.17119) (xy 119.599469 -241.219767)
			(xy 119.599964 -241.244374) (xy 119.928906 -241.244374) (xy 119.932866 -241.19532) (xy 119.944643 -241.147536)
			(xy 119.963934 -241.10226) (xy 119.990237 -241.060664) (xy 120.022872 -241.023827) (xy 120.060993 -240.992702)
			(xy 120.103614 -240.968095) (xy 120.14963 -240.950643) (xy 120.197849 -240.940799) (xy 120.247024 -240.938818)
			(xy 120.295879 -240.94475) (xy 120.34315 -240.958442) (xy 120.387612 -240.97954) (xy 120.428115 -241.007496)
			(xy 120.463608 -241.041588) (xy 120.493173 -241.080932) (xy 120.516044 -241.124509) (xy 120.531628 -241.17119)
			(xy 120.539523 -241.219767) (xy 120.540018 -241.244374) (xy 120.86896 -241.244374) (xy 120.87292 -241.19532)
			(xy 120.884697 -241.147536) (xy 120.903988 -241.10226) (xy 120.930291 -241.060664) (xy 120.962926 -241.023827)
			(xy 121.001047 -240.992702) (xy 121.043668 -240.968095) (xy 121.089684 -240.950643) (xy 121.137903 -240.940799)
			(xy 121.187078 -240.938818) (xy 121.235933 -240.94475) (xy 121.283204 -240.958442) (xy 121.327666 -240.97954)
			(xy 121.368169 -241.007496) (xy 121.403662 -241.041588) (xy 121.433227 -241.080932) (xy 121.456098 -241.124509)
			(xy 121.471682 -241.17119) (xy 121.479577 -241.219767) (xy 121.480072 -241.244374) (xy 121.809014 -241.244374)
			(xy 121.812974 -241.19532) (xy 121.824751 -241.147536) (xy 121.844042 -241.10226) (xy 121.870345 -241.060664)
			(xy 121.90298 -241.023827) (xy 121.941101 -240.992702) (xy 121.983722 -240.968095) (xy 122.029738 -240.950643)
			(xy 122.077957 -240.940799) (xy 122.127132 -240.938818) (xy 122.175987 -240.94475) (xy 122.223258 -240.958442)
			(xy 122.26772 -240.97954) (xy 122.308223 -241.007496) (xy 122.343716 -241.041588) (xy 122.373281 -241.080932)
			(xy 122.396152 -241.124509) (xy 122.411736 -241.17119) (xy 122.419631 -241.219767) (xy 122.420126 -241.244374)
			(xy 122.748814 -241.244374) (xy 122.752774 -241.19532) (xy 122.764551 -241.147536) (xy 122.783842 -241.10226)
			(xy 122.810145 -241.060664) (xy 122.84278 -241.023827) (xy 122.880901 -240.992702) (xy 122.923522 -240.968095)
			(xy 122.969538 -240.950643) (xy 123.017757 -240.940799) (xy 123.066932 -240.938818) (xy 123.115787 -240.94475)
			(xy 123.163058 -240.958442) (xy 123.20752 -240.97954) (xy 123.248023 -241.007496) (xy 123.283516 -241.041588)
			(xy 123.313081 -241.080932) (xy 123.335952 -241.124509) (xy 123.351536 -241.17119) (xy 123.359431 -241.219767)
			(xy 123.359926 -241.244374) (xy 123.688868 -241.244374) (xy 123.692828 -241.19532) (xy 123.704605 -241.147536)
			(xy 123.723896 -241.10226) (xy 123.750199 -241.060664) (xy 123.782834 -241.023827) (xy 123.820955 -240.992702)
			(xy 123.863576 -240.968095) (xy 123.909592 -240.950643) (xy 123.957811 -240.940799) (xy 124.006986 -240.938818)
			(xy 124.055841 -240.94475) (xy 124.103112 -240.958442) (xy 124.147574 -240.97954) (xy 124.188077 -241.007496)
			(xy 124.22357 -241.041588) (xy 124.253135 -241.080932) (xy 124.276006 -241.124509) (xy 124.29159 -241.17119)
			(xy 124.299485 -241.219767) (xy 124.29998 -241.244374) (xy 124.628922 -241.244374) (xy 124.632882 -241.19532)
			(xy 124.644659 -241.147536) (xy 124.66395 -241.10226) (xy 124.690253 -241.060664) (xy 124.722888 -241.023827)
			(xy 124.761009 -240.992702) (xy 124.80363 -240.968095) (xy 124.849646 -240.950643) (xy 124.897865 -240.940799)
			(xy 124.94704 -240.938818) (xy 124.995895 -240.94475) (xy 125.043166 -240.958442) (xy 125.087628 -240.97954)
			(xy 125.128131 -241.007496) (xy 125.163624 -241.041588) (xy 125.193189 -241.080932) (xy 125.21606 -241.124509)
			(xy 125.231644 -241.17119) (xy 125.239539 -241.219767) (xy 125.240034 -241.244374) (xy 125.568976 -241.244374)
			(xy 125.572936 -241.19532) (xy 125.584713 -241.147536) (xy 125.604004 -241.10226) (xy 125.630307 -241.060664)
			(xy 125.662942 -241.023827) (xy 125.701063 -240.992702) (xy 125.743684 -240.968095) (xy 125.7897 -240.950643)
			(xy 125.837919 -240.940799) (xy 125.887094 -240.938818) (xy 125.935949 -240.94475) (xy 125.98322 -240.958442)
			(xy 126.027682 -240.97954) (xy 126.068185 -241.007496) (xy 126.103678 -241.041588) (xy 126.133243 -241.080932)
			(xy 126.156114 -241.124509) (xy 126.171698 -241.17119) (xy 126.179593 -241.219767) (xy 126.180088 -241.244374)
			(xy 126.179593 -241.268981) (xy 126.171698 -241.317558) (xy 126.156114 -241.364239) (xy 126.133243 -241.407816)
			(xy 126.103678 -241.44716) (xy 126.068185 -241.481252) (xy 126.027682 -241.509208) (xy 125.98322 -241.530306)
			(xy 125.935949 -241.543998) (xy 125.887094 -241.54993) (xy 125.837919 -241.547949) (xy 125.7897 -241.538105)
			(xy 125.743684 -241.520653) (xy 125.701063 -241.496046) (xy 125.662942 -241.464921) (xy 125.630307 -241.428084)
			(xy 125.604004 -241.386488) (xy 125.584713 -241.341212) (xy 125.572936 -241.293428) (xy 125.568976 -241.244374)
			(xy 125.240034 -241.244374) (xy 125.239539 -241.268981) (xy 125.231644 -241.317558) (xy 125.21606 -241.364239)
			(xy 125.193189 -241.407816) (xy 125.163624 -241.44716) (xy 125.128131 -241.481252) (xy 125.087628 -241.509208)
			(xy 125.043166 -241.530306) (xy 124.995895 -241.543998) (xy 124.94704 -241.54993) (xy 124.897865 -241.547949)
			(xy 124.849646 -241.538105) (xy 124.80363 -241.520653) (xy 124.761009 -241.496046) (xy 124.722888 -241.464921)
			(xy 124.690253 -241.428084) (xy 124.66395 -241.386488) (xy 124.644659 -241.341212) (xy 124.632882 -241.293428)
			(xy 124.628922 -241.244374) (xy 124.29998 -241.244374) (xy 124.299485 -241.268981) (xy 124.29159 -241.317558)
			(xy 124.276006 -241.364239) (xy 124.253135 -241.407816) (xy 124.22357 -241.44716) (xy 124.188077 -241.481252)
			(xy 124.147574 -241.509208) (xy 124.103112 -241.530306) (xy 124.055841 -241.543998) (xy 124.006986 -241.54993)
			(xy 123.957811 -241.547949) (xy 123.909592 -241.538105) (xy 123.863576 -241.520653) (xy 123.820955 -241.496046)
			(xy 123.782834 -241.464921) (xy 123.750199 -241.428084) (xy 123.723896 -241.386488) (xy 123.704605 -241.341212)
			(xy 123.692828 -241.293428) (xy 123.688868 -241.244374) (xy 123.359926 -241.244374) (xy 123.359431 -241.268981)
			(xy 123.351536 -241.317558) (xy 123.335952 -241.364239) (xy 123.313081 -241.407816) (xy 123.283516 -241.44716)
			(xy 123.248023 -241.481252) (xy 123.20752 -241.509208) (xy 123.163058 -241.530306) (xy 123.115787 -241.543998)
			(xy 123.066932 -241.54993) (xy 123.017757 -241.547949) (xy 122.969538 -241.538105) (xy 122.923522 -241.520653)
			(xy 122.880901 -241.496046) (xy 122.84278 -241.464921) (xy 122.810145 -241.428084) (xy 122.783842 -241.386488)
			(xy 122.764551 -241.341212) (xy 122.752774 -241.293428) (xy 122.748814 -241.244374) (xy 122.420126 -241.244374)
			(xy 122.419631 -241.268981) (xy 122.411736 -241.317558) (xy 122.396152 -241.364239) (xy 122.373281 -241.407816)
			(xy 122.343716 -241.44716) (xy 122.308223 -241.481252) (xy 122.26772 -241.509208) (xy 122.223258 -241.530306)
			(xy 122.175987 -241.543998) (xy 122.127132 -241.54993) (xy 122.077957 -241.547949) (xy 122.029738 -241.538105)
			(xy 121.983722 -241.520653) (xy 121.941101 -241.496046) (xy 121.90298 -241.464921) (xy 121.870345 -241.428084)
			(xy 121.844042 -241.386488) (xy 121.824751 -241.341212) (xy 121.812974 -241.293428) (xy 121.809014 -241.244374)
			(xy 121.480072 -241.244374) (xy 121.479577 -241.268981) (xy 121.471682 -241.317558) (xy 121.456098 -241.364239)
			(xy 121.433227 -241.407816) (xy 121.403662 -241.44716) (xy 121.368169 -241.481252) (xy 121.327666 -241.509208)
			(xy 121.283204 -241.530306) (xy 121.235933 -241.543998) (xy 121.187078 -241.54993) (xy 121.137903 -241.547949)
			(xy 121.089684 -241.538105) (xy 121.043668 -241.520653) (xy 121.001047 -241.496046) (xy 120.962926 -241.464921)
			(xy 120.930291 -241.428084) (xy 120.903988 -241.386488) (xy 120.884697 -241.341212) (xy 120.87292 -241.293428)
			(xy 120.86896 -241.244374) (xy 120.540018 -241.244374) (xy 120.539523 -241.268981) (xy 120.531628 -241.317558)
			(xy 120.516044 -241.364239) (xy 120.493173 -241.407816) (xy 120.463608 -241.44716) (xy 120.428115 -241.481252)
			(xy 120.387612 -241.509208) (xy 120.34315 -241.530306) (xy 120.295879 -241.543998) (xy 120.247024 -241.54993)
			(xy 120.197849 -241.547949) (xy 120.14963 -241.538105) (xy 120.103614 -241.520653) (xy 120.060993 -241.496046)
			(xy 120.022872 -241.464921) (xy 119.990237 -241.428084) (xy 119.963934 -241.386488) (xy 119.944643 -241.341212)
			(xy 119.932866 -241.293428) (xy 119.928906 -241.244374) (xy 119.599964 -241.244374) (xy 119.599469 -241.268981)
			(xy 119.591574 -241.317558) (xy 119.57599 -241.364239) (xy 119.553119 -241.407816) (xy 119.523554 -241.44716)
			(xy 119.488061 -241.481252) (xy 119.447558 -241.509208) (xy 119.403096 -241.530306) (xy 119.355825 -241.543998)
			(xy 119.30697 -241.54993) (xy 119.257795 -241.547949) (xy 119.209576 -241.538105) (xy 119.16356 -241.520653)
			(xy 119.120939 -241.496046) (xy 119.082818 -241.464921) (xy 119.050183 -241.428084) (xy 119.02388 -241.386488)
			(xy 119.004589 -241.341212) (xy 118.992812 -241.293428) (xy 118.988852 -241.244374) (xy 118.660164 -241.244374)
			(xy 118.659669 -241.268981) (xy 118.651774 -241.317558) (xy 118.63619 -241.364239) (xy 118.613319 -241.407816)
			(xy 118.583754 -241.44716) (xy 118.548261 -241.481252) (xy 118.507758 -241.509208) (xy 118.463296 -241.530306)
			(xy 118.416025 -241.543998) (xy 118.36717 -241.54993) (xy 118.317995 -241.547949) (xy 118.269776 -241.538105)
			(xy 118.22376 -241.520653) (xy 118.181139 -241.496046) (xy 118.143018 -241.464921) (xy 118.110383 -241.428084)
			(xy 118.08408 -241.386488) (xy 118.064789 -241.341212) (xy 118.053012 -241.293428) (xy 118.049052 -241.244374)
			(xy 117.72011 -241.244374) (xy 117.719615 -241.268981) (xy 117.71172 -241.317558) (xy 117.696136 -241.364239)
			(xy 117.673265 -241.407816) (xy 117.6437 -241.44716) (xy 117.608207 -241.481252) (xy 117.567704 -241.509208)
			(xy 117.523242 -241.530306) (xy 117.475971 -241.543998) (xy 117.427116 -241.54993) (xy 117.377941 -241.547949)
			(xy 117.329722 -241.538105) (xy 117.283706 -241.520653) (xy 117.241085 -241.496046) (xy 117.202964 -241.464921)
			(xy 117.170329 -241.428084) (xy 117.144026 -241.386488) (xy 117.124735 -241.341212) (xy 117.112958 -241.293428)
			(xy 117.108998 -241.244374) (xy 116.780056 -241.244374) (xy 116.779561 -241.268981) (xy 116.771666 -241.317558)
			(xy 116.756082 -241.364239) (xy 116.733211 -241.407816) (xy 116.703646 -241.44716) (xy 116.668153 -241.481252)
			(xy 116.62765 -241.509208) (xy 116.583188 -241.530306) (xy 116.535917 -241.543998) (xy 116.487062 -241.54993)
			(xy 116.437887 -241.547949) (xy 116.389668 -241.538105) (xy 116.343652 -241.520653) (xy 116.301031 -241.496046)
			(xy 116.26291 -241.464921) (xy 116.230275 -241.428084) (xy 116.203972 -241.386488) (xy 116.184681 -241.341212)
			(xy 116.172904 -241.293428) (xy 116.168944 -241.244374) (xy 115.840002 -241.244374) (xy 115.839507 -241.268981)
			(xy 115.831612 -241.317558) (xy 115.816028 -241.364239) (xy 115.793157 -241.407816) (xy 115.763592 -241.44716)
			(xy 115.728099 -241.481252) (xy 115.687596 -241.509208) (xy 115.643134 -241.530306) (xy 115.595863 -241.543998)
			(xy 115.547008 -241.54993) (xy 115.497833 -241.547949) (xy 115.449614 -241.538105) (xy 115.403598 -241.520653)
			(xy 115.360977 -241.496046) (xy 115.322856 -241.464921) (xy 115.290221 -241.428084) (xy 115.263918 -241.386488)
			(xy 115.244627 -241.341212) (xy 115.23285 -241.293428) (xy 115.22889 -241.244374) (xy 114.899948 -241.244374)
			(xy 114.899453 -241.268981) (xy 114.891558 -241.317558) (xy 114.875974 -241.364239) (xy 114.853103 -241.407816)
			(xy 114.823538 -241.44716) (xy 114.788045 -241.481252) (xy 114.747542 -241.509208) (xy 114.70308 -241.530306)
			(xy 114.655809 -241.543998) (xy 114.606954 -241.54993) (xy 114.557779 -241.547949) (xy 114.50956 -241.538105)
			(xy 114.463544 -241.520653) (xy 114.420923 -241.496046) (xy 114.382802 -241.464921) (xy 114.350167 -241.428084)
			(xy 114.323864 -241.386488) (xy 114.304573 -241.341212) (xy 114.292796 -241.293428) (xy 114.288836 -241.244374)
			(xy 113.960148 -241.244374) (xy 113.959653 -241.268981) (xy 113.951758 -241.317558) (xy 113.936174 -241.364239)
			(xy 113.913303 -241.407816) (xy 113.883738 -241.44716) (xy 113.848245 -241.481252) (xy 113.807742 -241.509208)
			(xy 113.76328 -241.530306) (xy 113.716009 -241.543998) (xy 113.667154 -241.54993) (xy 113.617979 -241.547949)
			(xy 113.56976 -241.538105) (xy 113.523744 -241.520653) (xy 113.481123 -241.496046) (xy 113.443002 -241.464921)
			(xy 113.410367 -241.428084) (xy 113.384064 -241.386488) (xy 113.364773 -241.341212) (xy 113.352996 -241.293428)
			(xy 113.349036 -241.244374) (xy 111.90986 -241.244374) (xy 111.90986 -242.05438) (xy 112.878882 -242.05438)
			(xy 112.882842 -242.005326) (xy 112.894619 -241.957542) (xy 112.91391 -241.912266) (xy 112.940213 -241.87067)
			(xy 112.972848 -241.833833) (xy 113.010969 -241.802708) (xy 113.05359 -241.778101) (xy 113.099606 -241.760649)
			(xy 113.147825 -241.750805) (xy 113.197 -241.748824) (xy 113.245855 -241.754756) (xy 113.293126 -241.768448)
			(xy 113.337588 -241.789546) (xy 113.378091 -241.817502) (xy 113.413584 -241.851594) (xy 113.443149 -241.890938)
			(xy 113.46602 -241.934515) (xy 113.481604 -241.981196) (xy 113.489499 -242.029773) (xy 113.489994 -242.05438)
			(xy 113.818936 -242.05438) (xy 113.822896 -242.005326) (xy 113.834673 -241.957542) (xy 113.853964 -241.912266)
			(xy 113.880267 -241.87067) (xy 113.912902 -241.833833) (xy 113.951023 -241.802708) (xy 113.993644 -241.778101)
			(xy 114.03966 -241.760649) (xy 114.087879 -241.750805) (xy 114.137054 -241.748824) (xy 114.185909 -241.754756)
			(xy 114.23318 -241.768448) (xy 114.277642 -241.789546) (xy 114.318145 -241.817502) (xy 114.353638 -241.851594)
			(xy 114.383203 -241.890938) (xy 114.406074 -241.934515) (xy 114.421658 -241.981196) (xy 114.429553 -242.029773)
			(xy 114.430048 -242.05438) (xy 114.75899 -242.05438) (xy 114.76295 -242.005326) (xy 114.774727 -241.957542)
			(xy 114.794018 -241.912266) (xy 114.820321 -241.87067) (xy 114.852956 -241.833833) (xy 114.891077 -241.802708)
			(xy 114.933698 -241.778101) (xy 114.979714 -241.760649) (xy 115.027933 -241.750805) (xy 115.077108 -241.748824)
			(xy 115.125963 -241.754756) (xy 115.173234 -241.768448) (xy 115.217696 -241.789546) (xy 115.258199 -241.817502)
			(xy 115.293692 -241.851594) (xy 115.323257 -241.890938) (xy 115.346128 -241.934515) (xy 115.361712 -241.981196)
			(xy 115.369607 -242.029773) (xy 115.370102 -242.05438) (xy 115.699044 -242.05438) (xy 115.703004 -242.005326)
			(xy 115.714781 -241.957542) (xy 115.734072 -241.912266) (xy 115.760375 -241.87067) (xy 115.79301 -241.833833)
			(xy 115.831131 -241.802708) (xy 115.873752 -241.778101) (xy 115.919768 -241.760649) (xy 115.967987 -241.750805)
			(xy 116.017162 -241.748824) (xy 116.066017 -241.754756) (xy 116.113288 -241.768448) (xy 116.15775 -241.789546)
			(xy 116.198253 -241.817502) (xy 116.233746 -241.851594) (xy 116.263311 -241.890938) (xy 116.286182 -241.934515)
			(xy 116.301766 -241.981196) (xy 116.309661 -242.029773) (xy 116.310156 -242.05438) (xy 118.518952 -242.05438)
			(xy 118.522912 -242.005326) (xy 118.534689 -241.957542) (xy 118.55398 -241.912266) (xy 118.580283 -241.87067)
			(xy 118.612918 -241.833833) (xy 118.651039 -241.802708) (xy 118.69366 -241.778101) (xy 118.739676 -241.760649)
			(xy 118.787895 -241.750805) (xy 118.83707 -241.748824) (xy 118.885925 -241.754756) (xy 118.933196 -241.768448)
			(xy 118.977658 -241.789546) (xy 119.018161 -241.817502) (xy 119.053654 -241.851594) (xy 119.083219 -241.890938)
			(xy 119.10609 -241.934515) (xy 119.121674 -241.981196) (xy 119.129569 -242.029773) (xy 119.130064 -242.05438)
			(xy 121.33886 -242.05438) (xy 121.34282 -242.005326) (xy 121.354597 -241.957542) (xy 121.373888 -241.912266)
			(xy 121.400191 -241.87067) (xy 121.432826 -241.833833) (xy 121.470947 -241.802708) (xy 121.513568 -241.778101)
			(xy 121.559584 -241.760649) (xy 121.607803 -241.750805) (xy 121.656978 -241.748824) (xy 121.705833 -241.754756)
			(xy 121.753104 -241.768448) (xy 121.797566 -241.789546) (xy 121.838069 -241.817502) (xy 121.873562 -241.851594)
			(xy 121.903127 -241.890938) (xy 121.925998 -241.934515) (xy 121.941582 -241.981196) (xy 121.949477 -242.029773)
			(xy 121.949972 -242.05438) (xy 124.159022 -242.05438) (xy 124.162982 -242.005326) (xy 124.174759 -241.957542)
			(xy 124.19405 -241.912266) (xy 124.220353 -241.87067) (xy 124.252988 -241.833833) (xy 124.291109 -241.802708)
			(xy 124.33373 -241.778101) (xy 124.379746 -241.760649) (xy 124.427965 -241.750805) (xy 124.47714 -241.748824)
			(xy 124.525995 -241.754756) (xy 124.573266 -241.768448) (xy 124.617728 -241.789546) (xy 124.658231 -241.817502)
			(xy 124.693724 -241.851594) (xy 124.723289 -241.890938) (xy 124.74616 -241.934515) (xy 124.761744 -241.981196)
			(xy 124.769639 -242.029773) (xy 124.770134 -242.05438) (xy 124.769639 -242.078987) (xy 124.761744 -242.127564)
			(xy 124.74616 -242.174245) (xy 124.723289 -242.217822) (xy 124.693724 -242.257166) (xy 124.658231 -242.291258)
			(xy 124.617728 -242.319214) (xy 124.573266 -242.340312) (xy 124.525995 -242.354004) (xy 124.47714 -242.359936)
			(xy 124.427965 -242.357955) (xy 124.379746 -242.348111) (xy 124.33373 -242.330659) (xy 124.291109 -242.306052)
			(xy 124.252988 -242.274927) (xy 124.220353 -242.23809) (xy 124.19405 -242.196494) (xy 124.174759 -242.151218)
			(xy 124.162982 -242.103434) (xy 124.159022 -242.05438) (xy 121.949972 -242.05438) (xy 121.949477 -242.078987)
			(xy 121.941582 -242.127564) (xy 121.925998 -242.174245) (xy 121.903127 -242.217822) (xy 121.873562 -242.257166)
			(xy 121.838069 -242.291258) (xy 121.797566 -242.319214) (xy 121.753104 -242.340312) (xy 121.705833 -242.354004)
			(xy 121.656978 -242.359936) (xy 121.607803 -242.357955) (xy 121.559584 -242.348111) (xy 121.513568 -242.330659)
			(xy 121.470947 -242.306052) (xy 121.432826 -242.274927) (xy 121.400191 -242.23809) (xy 121.373888 -242.196494)
			(xy 121.354597 -242.151218) (xy 121.34282 -242.103434) (xy 121.33886 -242.05438) (xy 119.130064 -242.05438)
			(xy 119.129569 -242.078987) (xy 119.121674 -242.127564) (xy 119.10609 -242.174245) (xy 119.083219 -242.217822)
			(xy 119.053654 -242.257166) (xy 119.018161 -242.291258) (xy 118.977658 -242.319214) (xy 118.933196 -242.340312)
			(xy 118.885925 -242.354004) (xy 118.83707 -242.359936) (xy 118.787895 -242.357955) (xy 118.739676 -242.348111)
			(xy 118.69366 -242.330659) (xy 118.651039 -242.306052) (xy 118.612918 -242.274927) (xy 118.580283 -242.23809)
			(xy 118.55398 -242.196494) (xy 118.534689 -242.151218) (xy 118.522912 -242.103434) (xy 118.518952 -242.05438)
			(xy 116.310156 -242.05438) (xy 116.309661 -242.078987) (xy 116.301766 -242.127564) (xy 116.286182 -242.174245)
			(xy 116.263311 -242.217822) (xy 116.233746 -242.257166) (xy 116.198253 -242.291258) (xy 116.15775 -242.319214)
			(xy 116.113288 -242.340312) (xy 116.066017 -242.354004) (xy 116.017162 -242.359936) (xy 115.967987 -242.357955)
			(xy 115.919768 -242.348111) (xy 115.873752 -242.330659) (xy 115.831131 -242.306052) (xy 115.79301 -242.274927)
			(xy 115.760375 -242.23809) (xy 115.734072 -242.196494) (xy 115.714781 -242.151218) (xy 115.703004 -242.103434)
			(xy 115.699044 -242.05438) (xy 115.370102 -242.05438) (xy 115.369607 -242.078987) (xy 115.361712 -242.127564)
			(xy 115.346128 -242.174245) (xy 115.323257 -242.217822) (xy 115.293692 -242.257166) (xy 115.258199 -242.291258)
			(xy 115.217696 -242.319214) (xy 115.173234 -242.340312) (xy 115.125963 -242.354004) (xy 115.077108 -242.359936)
			(xy 115.027933 -242.357955) (xy 114.979714 -242.348111) (xy 114.933698 -242.330659) (xy 114.891077 -242.306052)
			(xy 114.852956 -242.274927) (xy 114.820321 -242.23809) (xy 114.794018 -242.196494) (xy 114.774727 -242.151218)
			(xy 114.76295 -242.103434) (xy 114.75899 -242.05438) (xy 114.430048 -242.05438) (xy 114.429553 -242.078987)
			(xy 114.421658 -242.127564) (xy 114.406074 -242.174245) (xy 114.383203 -242.217822) (xy 114.353638 -242.257166)
			(xy 114.318145 -242.291258) (xy 114.277642 -242.319214) (xy 114.23318 -242.340312) (xy 114.185909 -242.354004)
			(xy 114.137054 -242.359936) (xy 114.087879 -242.357955) (xy 114.03966 -242.348111) (xy 113.993644 -242.330659)
			(xy 113.951023 -242.306052) (xy 113.912902 -242.274927) (xy 113.880267 -242.23809) (xy 113.853964 -242.196494)
			(xy 113.834673 -242.151218) (xy 113.822896 -242.103434) (xy 113.818936 -242.05438) (xy 113.489994 -242.05438)
			(xy 113.489499 -242.078987) (xy 113.481604 -242.127564) (xy 113.46602 -242.174245) (xy 113.443149 -242.217822)
			(xy 113.413584 -242.257166) (xy 113.378091 -242.291258) (xy 113.337588 -242.319214) (xy 113.293126 -242.340312)
			(xy 113.245855 -242.354004) (xy 113.197 -242.359936) (xy 113.147825 -242.357955) (xy 113.099606 -242.348111)
			(xy 113.05359 -242.330659) (xy 113.010969 -242.306052) (xy 112.972848 -242.274927) (xy 112.940213 -242.23809)
			(xy 112.91391 -242.196494) (xy 112.894619 -242.151218) (xy 112.882842 -242.103434) (xy 112.878882 -242.05438)
			(xy 111.90986 -242.05438) (xy 111.90986 -242.864386) (xy 115.22889 -242.864386) (xy 115.23285 -242.815332)
			(xy 115.244627 -242.767548) (xy 115.263918 -242.722272) (xy 115.290221 -242.680676) (xy 115.322856 -242.643839)
			(xy 115.360977 -242.612714) (xy 115.403598 -242.588107) (xy 115.449614 -242.570655) (xy 115.497833 -242.560811)
			(xy 115.547008 -242.55883) (xy 115.595863 -242.564762) (xy 115.643134 -242.578454) (xy 115.687596 -242.599552)
			(xy 115.728099 -242.627508) (xy 115.763592 -242.6616) (xy 115.793157 -242.700944) (xy 115.816028 -242.744521)
			(xy 115.831612 -242.791202) (xy 115.839507 -242.839779) (xy 115.840002 -242.864386) (xy 116.168944 -242.864386)
			(xy 116.172904 -242.815332) (xy 116.184681 -242.767548) (xy 116.203972 -242.722272) (xy 116.230275 -242.680676)
			(xy 116.26291 -242.643839) (xy 116.301031 -242.612714) (xy 116.343652 -242.588107) (xy 116.389668 -242.570655)
			(xy 116.437887 -242.560811) (xy 116.487062 -242.55883) (xy 116.535917 -242.564762) (xy 116.583188 -242.578454)
			(xy 116.62765 -242.599552) (xy 116.668153 -242.627508) (xy 116.703646 -242.6616) (xy 116.733211 -242.700944)
			(xy 116.756082 -242.744521) (xy 116.771666 -242.791202) (xy 116.779561 -242.839779) (xy 116.780056 -242.864386)
			(xy 117.108998 -242.864386) (xy 117.112958 -242.815332) (xy 117.124735 -242.767548) (xy 117.144026 -242.722272)
			(xy 117.170329 -242.680676) (xy 117.202964 -242.643839) (xy 117.241085 -242.612714) (xy 117.283706 -242.588107)
			(xy 117.329722 -242.570655) (xy 117.377941 -242.560811) (xy 117.427116 -242.55883) (xy 117.475971 -242.564762)
			(xy 117.523242 -242.578454) (xy 117.567704 -242.599552) (xy 117.608207 -242.627508) (xy 117.6437 -242.6616)
			(xy 117.673265 -242.700944) (xy 117.696136 -242.744521) (xy 117.71172 -242.791202) (xy 117.719615 -242.839779)
			(xy 117.72011 -242.864386) (xy 118.049052 -242.864386) (xy 118.053012 -242.815332) (xy 118.064789 -242.767548)
			(xy 118.08408 -242.722272) (xy 118.110383 -242.680676) (xy 118.143018 -242.643839) (xy 118.181139 -242.612714)
			(xy 118.22376 -242.588107) (xy 118.269776 -242.570655) (xy 118.317995 -242.560811) (xy 118.36717 -242.55883)
			(xy 118.416025 -242.564762) (xy 118.463296 -242.578454) (xy 118.507758 -242.599552) (xy 118.548261 -242.627508)
			(xy 118.583754 -242.6616) (xy 118.613319 -242.700944) (xy 118.63619 -242.744521) (xy 118.651774 -242.791202)
			(xy 118.659669 -242.839779) (xy 118.660164 -242.864386) (xy 118.988852 -242.864386) (xy 118.992812 -242.815332)
			(xy 119.004589 -242.767548) (xy 119.02388 -242.722272) (xy 119.050183 -242.680676) (xy 119.082818 -242.643839)
			(xy 119.120939 -242.612714) (xy 119.16356 -242.588107) (xy 119.209576 -242.570655) (xy 119.257795 -242.560811)
			(xy 119.30697 -242.55883) (xy 119.355825 -242.564762) (xy 119.403096 -242.578454) (xy 119.447558 -242.599552)
			(xy 119.488061 -242.627508) (xy 119.523554 -242.6616) (xy 119.553119 -242.700944) (xy 119.57599 -242.744521)
			(xy 119.591574 -242.791202) (xy 119.599469 -242.839779) (xy 119.599964 -242.864386) (xy 119.928906 -242.864386)
			(xy 119.932866 -242.815332) (xy 119.944643 -242.767548) (xy 119.963934 -242.722272) (xy 119.990237 -242.680676)
			(xy 120.022872 -242.643839) (xy 120.060993 -242.612714) (xy 120.103614 -242.588107) (xy 120.14963 -242.570655)
			(xy 120.197849 -242.560811) (xy 120.247024 -242.55883) (xy 120.295879 -242.564762) (xy 120.34315 -242.578454)
			(xy 120.387612 -242.599552) (xy 120.428115 -242.627508) (xy 120.463608 -242.6616) (xy 120.493173 -242.700944)
			(xy 120.516044 -242.744521) (xy 120.531628 -242.791202) (xy 120.539523 -242.839779) (xy 120.540018 -242.864386)
			(xy 120.86896 -242.864386) (xy 120.87292 -242.815332) (xy 120.884697 -242.767548) (xy 120.903988 -242.722272)
			(xy 120.930291 -242.680676) (xy 120.962926 -242.643839) (xy 121.001047 -242.612714) (xy 121.043668 -242.588107)
			(xy 121.089684 -242.570655) (xy 121.137903 -242.560811) (xy 121.187078 -242.55883) (xy 121.235933 -242.564762)
			(xy 121.283204 -242.578454) (xy 121.327666 -242.599552) (xy 121.368169 -242.627508) (xy 121.403662 -242.6616)
			(xy 121.433227 -242.700944) (xy 121.456098 -242.744521) (xy 121.471682 -242.791202) (xy 121.479577 -242.839779)
			(xy 121.480072 -242.864386) (xy 121.809014 -242.864386) (xy 121.812974 -242.815332) (xy 121.824751 -242.767548)
			(xy 121.844042 -242.722272) (xy 121.870345 -242.680676) (xy 121.90298 -242.643839) (xy 121.941101 -242.612714)
			(xy 121.983722 -242.588107) (xy 122.029738 -242.570655) (xy 122.077957 -242.560811) (xy 122.127132 -242.55883)
			(xy 122.175987 -242.564762) (xy 122.223258 -242.578454) (xy 122.26772 -242.599552) (xy 122.308223 -242.627508)
			(xy 122.343716 -242.6616) (xy 122.373281 -242.700944) (xy 122.396152 -242.744521) (xy 122.411736 -242.791202)
			(xy 122.419631 -242.839779) (xy 122.420126 -242.864386) (xy 122.748814 -242.864386) (xy 122.752774 -242.815332)
			(xy 122.764551 -242.767548) (xy 122.783842 -242.722272) (xy 122.810145 -242.680676) (xy 122.84278 -242.643839)
			(xy 122.880901 -242.612714) (xy 122.923522 -242.588107) (xy 122.969538 -242.570655) (xy 123.017757 -242.560811)
			(xy 123.066932 -242.55883) (xy 123.115787 -242.564762) (xy 123.163058 -242.578454) (xy 123.20752 -242.599552)
			(xy 123.248023 -242.627508) (xy 123.283516 -242.6616) (xy 123.313081 -242.700944) (xy 123.335952 -242.744521)
			(xy 123.351536 -242.791202) (xy 123.359431 -242.839779) (xy 123.359926 -242.864386) (xy 123.688868 -242.864386)
			(xy 123.692828 -242.815332) (xy 123.704605 -242.767548) (xy 123.723896 -242.722272) (xy 123.750199 -242.680676)
			(xy 123.782834 -242.643839) (xy 123.820955 -242.612714) (xy 123.863576 -242.588107) (xy 123.909592 -242.570655)
			(xy 123.957811 -242.560811) (xy 124.006986 -242.55883) (xy 124.055841 -242.564762) (xy 124.103112 -242.578454)
			(xy 124.147574 -242.599552) (xy 124.188077 -242.627508) (xy 124.22357 -242.6616) (xy 124.253135 -242.700944)
			(xy 124.276006 -242.744521) (xy 124.29159 -242.791202) (xy 124.299485 -242.839779) (xy 124.29998 -242.864386)
			(xy 124.628922 -242.864386) (xy 124.632882 -242.815332) (xy 124.644659 -242.767548) (xy 124.66395 -242.722272)
			(xy 124.690253 -242.680676) (xy 124.722888 -242.643839) (xy 124.761009 -242.612714) (xy 124.80363 -242.588107)
			(xy 124.849646 -242.570655) (xy 124.897865 -242.560811) (xy 124.94704 -242.55883) (xy 124.995895 -242.564762)
			(xy 125.043166 -242.578454) (xy 125.087628 -242.599552) (xy 125.128131 -242.627508) (xy 125.163624 -242.6616)
			(xy 125.193189 -242.700944) (xy 125.21606 -242.744521) (xy 125.231644 -242.791202) (xy 125.239539 -242.839779)
			(xy 125.240034 -242.864386) (xy 125.568976 -242.864386) (xy 125.572936 -242.815332) (xy 125.584713 -242.767548)
			(xy 125.604004 -242.722272) (xy 125.630307 -242.680676) (xy 125.662942 -242.643839) (xy 125.701063 -242.612714)
			(xy 125.743684 -242.588107) (xy 125.7897 -242.570655) (xy 125.837919 -242.560811) (xy 125.887094 -242.55883)
			(xy 125.935949 -242.564762) (xy 125.98322 -242.578454) (xy 126.027682 -242.599552) (xy 126.068185 -242.627508)
			(xy 126.103678 -242.6616) (xy 126.133243 -242.700944) (xy 126.156114 -242.744521) (xy 126.171698 -242.791202)
			(xy 126.179593 -242.839779) (xy 126.180088 -242.864386) (xy 126.179593 -242.888993) (xy 126.171698 -242.93757)
			(xy 126.156114 -242.984251) (xy 126.133243 -243.027828) (xy 126.103678 -243.067172) (xy 126.068185 -243.101264)
			(xy 126.027682 -243.12922) (xy 125.98322 -243.150318) (xy 125.935949 -243.16401) (xy 125.887094 -243.169942)
			(xy 125.837919 -243.167961) (xy 125.7897 -243.158117) (xy 125.743684 -243.140665) (xy 125.701063 -243.116058)
			(xy 125.662942 -243.084933) (xy 125.630307 -243.048096) (xy 125.604004 -243.0065) (xy 125.584713 -242.961224)
			(xy 125.572936 -242.91344) (xy 125.568976 -242.864386) (xy 125.240034 -242.864386) (xy 125.239539 -242.888993)
			(xy 125.231644 -242.93757) (xy 125.21606 -242.984251) (xy 125.193189 -243.027828) (xy 125.163624 -243.067172)
			(xy 125.128131 -243.101264) (xy 125.087628 -243.12922) (xy 125.043166 -243.150318) (xy 124.995895 -243.16401)
			(xy 124.94704 -243.169942) (xy 124.897865 -243.167961) (xy 124.849646 -243.158117) (xy 124.80363 -243.140665)
			(xy 124.761009 -243.116058) (xy 124.722888 -243.084933) (xy 124.690253 -243.048096) (xy 124.66395 -243.0065)
			(xy 124.644659 -242.961224) (xy 124.632882 -242.91344) (xy 124.628922 -242.864386) (xy 124.29998 -242.864386)
			(xy 124.299485 -242.888993) (xy 124.29159 -242.93757) (xy 124.276006 -242.984251) (xy 124.253135 -243.027828)
			(xy 124.22357 -243.067172) (xy 124.188077 -243.101264) (xy 124.147574 -243.12922) (xy 124.103112 -243.150318)
			(xy 124.055841 -243.16401) (xy 124.006986 -243.169942) (xy 123.957811 -243.167961) (xy 123.909592 -243.158117)
			(xy 123.863576 -243.140665) (xy 123.820955 -243.116058) (xy 123.782834 -243.084933) (xy 123.750199 -243.048096)
			(xy 123.723896 -243.0065) (xy 123.704605 -242.961224) (xy 123.692828 -242.91344) (xy 123.688868 -242.864386)
			(xy 123.359926 -242.864386) (xy 123.359431 -242.888993) (xy 123.351536 -242.93757) (xy 123.335952 -242.984251)
			(xy 123.313081 -243.027828) (xy 123.283516 -243.067172) (xy 123.248023 -243.101264) (xy 123.20752 -243.12922)
			(xy 123.163058 -243.150318) (xy 123.115787 -243.16401) (xy 123.066932 -243.169942) (xy 123.017757 -243.167961)
			(xy 122.969538 -243.158117) (xy 122.923522 -243.140665) (xy 122.880901 -243.116058) (xy 122.84278 -243.084933)
			(xy 122.810145 -243.048096) (xy 122.783842 -243.0065) (xy 122.764551 -242.961224) (xy 122.752774 -242.91344)
			(xy 122.748814 -242.864386) (xy 122.420126 -242.864386) (xy 122.419631 -242.888993) (xy 122.411736 -242.93757)
			(xy 122.396152 -242.984251) (xy 122.373281 -243.027828) (xy 122.343716 -243.067172) (xy 122.308223 -243.101264)
			(xy 122.26772 -243.12922) (xy 122.223258 -243.150318) (xy 122.175987 -243.16401) (xy 122.127132 -243.169942)
			(xy 122.077957 -243.167961) (xy 122.029738 -243.158117) (xy 121.983722 -243.140665) (xy 121.941101 -243.116058)
			(xy 121.90298 -243.084933) (xy 121.870345 -243.048096) (xy 121.844042 -243.0065) (xy 121.824751 -242.961224)
			(xy 121.812974 -242.91344) (xy 121.809014 -242.864386) (xy 121.480072 -242.864386) (xy 121.479577 -242.888993)
			(xy 121.471682 -242.93757) (xy 121.456098 -242.984251) (xy 121.433227 -243.027828) (xy 121.403662 -243.067172)
			(xy 121.368169 -243.101264) (xy 121.327666 -243.12922) (xy 121.283204 -243.150318) (xy 121.235933 -243.16401)
			(xy 121.187078 -243.169942) (xy 121.137903 -243.167961) (xy 121.089684 -243.158117) (xy 121.043668 -243.140665)
			(xy 121.001047 -243.116058) (xy 120.962926 -243.084933) (xy 120.930291 -243.048096) (xy 120.903988 -243.0065)
			(xy 120.884697 -242.961224) (xy 120.87292 -242.91344) (xy 120.86896 -242.864386) (xy 120.540018 -242.864386)
			(xy 120.539523 -242.888993) (xy 120.531628 -242.93757) (xy 120.516044 -242.984251) (xy 120.493173 -243.027828)
			(xy 120.463608 -243.067172) (xy 120.428115 -243.101264) (xy 120.387612 -243.12922) (xy 120.34315 -243.150318)
			(xy 120.295879 -243.16401) (xy 120.247024 -243.169942) (xy 120.197849 -243.167961) (xy 120.14963 -243.158117)
			(xy 120.103614 -243.140665) (xy 120.060993 -243.116058) (xy 120.022872 -243.084933) (xy 119.990237 -243.048096)
			(xy 119.963934 -243.0065) (xy 119.944643 -242.961224) (xy 119.932866 -242.91344) (xy 119.928906 -242.864386)
			(xy 119.599964 -242.864386) (xy 119.599469 -242.888993) (xy 119.591574 -242.93757) (xy 119.57599 -242.984251)
			(xy 119.553119 -243.027828) (xy 119.523554 -243.067172) (xy 119.488061 -243.101264) (xy 119.447558 -243.12922)
			(xy 119.403096 -243.150318) (xy 119.355825 -243.16401) (xy 119.30697 -243.169942) (xy 119.257795 -243.167961)
			(xy 119.209576 -243.158117) (xy 119.16356 -243.140665) (xy 119.120939 -243.116058) (xy 119.082818 -243.084933)
			(xy 119.050183 -243.048096) (xy 119.02388 -243.0065) (xy 119.004589 -242.961224) (xy 118.992812 -242.91344)
			(xy 118.988852 -242.864386) (xy 118.660164 -242.864386) (xy 118.659669 -242.888993) (xy 118.651774 -242.93757)
			(xy 118.63619 -242.984251) (xy 118.613319 -243.027828) (xy 118.583754 -243.067172) (xy 118.548261 -243.101264)
			(xy 118.507758 -243.12922) (xy 118.463296 -243.150318) (xy 118.416025 -243.16401) (xy 118.36717 -243.169942)
			(xy 118.317995 -243.167961) (xy 118.269776 -243.158117) (xy 118.22376 -243.140665) (xy 118.181139 -243.116058)
			(xy 118.143018 -243.084933) (xy 118.110383 -243.048096) (xy 118.08408 -243.0065) (xy 118.064789 -242.961224)
			(xy 118.053012 -242.91344) (xy 118.049052 -242.864386) (xy 117.72011 -242.864386) (xy 117.719615 -242.888993)
			(xy 117.71172 -242.93757) (xy 117.696136 -242.984251) (xy 117.673265 -243.027828) (xy 117.6437 -243.067172)
			(xy 117.608207 -243.101264) (xy 117.567704 -243.12922) (xy 117.523242 -243.150318) (xy 117.475971 -243.16401)
			(xy 117.427116 -243.169942) (xy 117.377941 -243.167961) (xy 117.329722 -243.158117) (xy 117.283706 -243.140665)
			(xy 117.241085 -243.116058) (xy 117.202964 -243.084933) (xy 117.170329 -243.048096) (xy 117.144026 -243.0065)
			(xy 117.124735 -242.961224) (xy 117.112958 -242.91344) (xy 117.108998 -242.864386) (xy 116.780056 -242.864386)
			(xy 116.779561 -242.888993) (xy 116.771666 -242.93757) (xy 116.756082 -242.984251) (xy 116.733211 -243.027828)
			(xy 116.703646 -243.067172) (xy 116.668153 -243.101264) (xy 116.62765 -243.12922) (xy 116.583188 -243.150318)
			(xy 116.535917 -243.16401) (xy 116.487062 -243.169942) (xy 116.437887 -243.167961) (xy 116.389668 -243.158117)
			(xy 116.343652 -243.140665) (xy 116.301031 -243.116058) (xy 116.26291 -243.084933) (xy 116.230275 -243.048096)
			(xy 116.203972 -243.0065) (xy 116.184681 -242.961224) (xy 116.172904 -242.91344) (xy 116.168944 -242.864386)
			(xy 115.840002 -242.864386) (xy 115.839507 -242.888993) (xy 115.831612 -242.93757) (xy 115.816028 -242.984251)
			(xy 115.793157 -243.027828) (xy 115.763592 -243.067172) (xy 115.728099 -243.101264) (xy 115.687596 -243.12922)
			(xy 115.643134 -243.150318) (xy 115.595863 -243.16401) (xy 115.547008 -243.169942) (xy 115.497833 -243.167961)
			(xy 115.449614 -243.158117) (xy 115.403598 -243.140665) (xy 115.360977 -243.116058) (xy 115.322856 -243.084933)
			(xy 115.290221 -243.048096) (xy 115.263918 -243.0065) (xy 115.244627 -242.961224) (xy 115.23285 -242.91344)
			(xy 115.22889 -242.864386) (xy 111.90986 -242.864386) (xy 111.90986 -243.674392) (xy 112.878882 -243.674392)
			(xy 112.882842 -243.625338) (xy 112.894619 -243.577554) (xy 112.91391 -243.532278) (xy 112.940213 -243.490682)
			(xy 112.972848 -243.453845) (xy 113.010969 -243.42272) (xy 113.05359 -243.398113) (xy 113.099606 -243.380661)
			(xy 113.147825 -243.370817) (xy 113.197 -243.368836) (xy 113.245855 -243.374768) (xy 113.293126 -243.38846)
			(xy 113.337588 -243.409558) (xy 113.378091 -243.437514) (xy 113.413584 -243.471606) (xy 113.443149 -243.51095)
			(xy 113.46602 -243.554527) (xy 113.481604 -243.601208) (xy 113.489499 -243.649785) (xy 113.489994 -243.674392)
			(xy 113.818936 -243.674392) (xy 113.822896 -243.625338) (xy 113.834673 -243.577554) (xy 113.853964 -243.532278)
			(xy 113.880267 -243.490682) (xy 113.912902 -243.453845) (xy 113.951023 -243.42272) (xy 113.993644 -243.398113)
			(xy 114.03966 -243.380661) (xy 114.087879 -243.370817) (xy 114.137054 -243.368836) (xy 114.185909 -243.374768)
			(xy 114.23318 -243.38846) (xy 114.277642 -243.409558) (xy 114.318145 -243.437514) (xy 114.353638 -243.471606)
			(xy 114.383203 -243.51095) (xy 114.406074 -243.554527) (xy 114.421658 -243.601208) (xy 114.429553 -243.649785)
			(xy 114.430048 -243.674392) (xy 114.75899 -243.674392) (xy 114.76295 -243.625338) (xy 114.774727 -243.577554)
			(xy 114.794018 -243.532278) (xy 114.820321 -243.490682) (xy 114.852956 -243.453845) (xy 114.891077 -243.42272)
			(xy 114.933698 -243.398113) (xy 114.979714 -243.380661) (xy 115.027933 -243.370817) (xy 115.077108 -243.368836)
			(xy 115.125963 -243.374768) (xy 115.173234 -243.38846) (xy 115.217696 -243.409558) (xy 115.258199 -243.437514)
			(xy 115.293692 -243.471606) (xy 115.323257 -243.51095) (xy 115.346128 -243.554527) (xy 115.361712 -243.601208)
			(xy 115.369607 -243.649785) (xy 115.370102 -243.674392) (xy 115.699044 -243.674392) (xy 115.703004 -243.625338)
			(xy 115.714781 -243.577554) (xy 115.734072 -243.532278) (xy 115.760375 -243.490682) (xy 115.79301 -243.453845)
			(xy 115.831131 -243.42272) (xy 115.873752 -243.398113) (xy 115.919768 -243.380661) (xy 115.967987 -243.370817)
			(xy 116.017162 -243.368836) (xy 116.066017 -243.374768) (xy 116.113288 -243.38846) (xy 116.15775 -243.409558)
			(xy 116.198253 -243.437514) (xy 116.233746 -243.471606) (xy 116.263311 -243.51095) (xy 116.286182 -243.554527)
			(xy 116.301766 -243.601208) (xy 116.309661 -243.649785) (xy 116.310156 -243.674392) (xy 116.638844 -243.674392)
			(xy 116.642804 -243.625338) (xy 116.654581 -243.577554) (xy 116.673872 -243.532278) (xy 116.700175 -243.490682)
			(xy 116.73281 -243.453845) (xy 116.770931 -243.42272) (xy 116.813552 -243.398113) (xy 116.859568 -243.380661)
			(xy 116.907787 -243.370817) (xy 116.956962 -243.368836) (xy 117.005817 -243.374768) (xy 117.053088 -243.38846)
			(xy 117.09755 -243.409558) (xy 117.138053 -243.437514) (xy 117.173546 -243.471606) (xy 117.203111 -243.51095)
			(xy 117.225982 -243.554527) (xy 117.241566 -243.601208) (xy 117.249461 -243.649785) (xy 117.249956 -243.674392)
			(xy 117.578898 -243.674392) (xy 117.582858 -243.625338) (xy 117.594635 -243.577554) (xy 117.613926 -243.532278)
			(xy 117.640229 -243.490682) (xy 117.672864 -243.453845) (xy 117.710985 -243.42272) (xy 117.753606 -243.398113)
			(xy 117.799622 -243.380661) (xy 117.847841 -243.370817) (xy 117.897016 -243.368836) (xy 117.945871 -243.374768)
			(xy 117.993142 -243.38846) (xy 118.037604 -243.409558) (xy 118.078107 -243.437514) (xy 118.1136 -243.471606)
			(xy 118.143165 -243.51095) (xy 118.166036 -243.554527) (xy 118.18162 -243.601208) (xy 118.189515 -243.649785)
			(xy 118.19001 -243.674392) (xy 118.518952 -243.674392) (xy 118.522912 -243.625338) (xy 118.534689 -243.577554)
			(xy 118.55398 -243.532278) (xy 118.580283 -243.490682) (xy 118.612918 -243.453845) (xy 118.651039 -243.42272)
			(xy 118.69366 -243.398113) (xy 118.739676 -243.380661) (xy 118.787895 -243.370817) (xy 118.83707 -243.368836)
			(xy 118.885925 -243.374768) (xy 118.933196 -243.38846) (xy 118.977658 -243.409558) (xy 119.018161 -243.437514)
			(xy 119.053654 -243.471606) (xy 119.083219 -243.51095) (xy 119.10609 -243.554527) (xy 119.121674 -243.601208)
			(xy 119.129569 -243.649785) (xy 119.130064 -243.674392) (xy 119.459006 -243.674392) (xy 119.462966 -243.625338)
			(xy 119.474743 -243.577554) (xy 119.494034 -243.532278) (xy 119.520337 -243.490682) (xy 119.552972 -243.453845)
			(xy 119.591093 -243.42272) (xy 119.633714 -243.398113) (xy 119.67973 -243.380661) (xy 119.727949 -243.370817)
			(xy 119.777124 -243.368836) (xy 119.825979 -243.374768) (xy 119.87325 -243.38846) (xy 119.917712 -243.409558)
			(xy 119.958215 -243.437514) (xy 119.993708 -243.471606) (xy 120.023273 -243.51095) (xy 120.046144 -243.554527)
			(xy 120.061728 -243.601208) (xy 120.069623 -243.649785) (xy 120.070118 -243.674392) (xy 120.398806 -243.674392)
			(xy 120.402766 -243.625338) (xy 120.414543 -243.577554) (xy 120.433834 -243.532278) (xy 120.460137 -243.490682)
			(xy 120.492772 -243.453845) (xy 120.530893 -243.42272) (xy 120.573514 -243.398113) (xy 120.61953 -243.380661)
			(xy 120.667749 -243.370817) (xy 120.716924 -243.368836) (xy 120.765779 -243.374768) (xy 120.81305 -243.38846)
			(xy 120.857512 -243.409558) (xy 120.898015 -243.437514) (xy 120.933508 -243.471606) (xy 120.963073 -243.51095)
			(xy 120.985944 -243.554527) (xy 121.001528 -243.601208) (xy 121.009423 -243.649785) (xy 121.009918 -243.674392)
			(xy 121.33886 -243.674392) (xy 121.34282 -243.625338) (xy 121.354597 -243.577554) (xy 121.373888 -243.532278)
			(xy 121.400191 -243.490682) (xy 121.432826 -243.453845) (xy 121.470947 -243.42272) (xy 121.513568 -243.398113)
			(xy 121.559584 -243.380661) (xy 121.607803 -243.370817) (xy 121.656978 -243.368836) (xy 121.705833 -243.374768)
			(xy 121.753104 -243.38846) (xy 121.797566 -243.409558) (xy 121.838069 -243.437514) (xy 121.873562 -243.471606)
			(xy 121.903127 -243.51095) (xy 121.925998 -243.554527) (xy 121.941582 -243.601208) (xy 121.949477 -243.649785)
			(xy 121.949972 -243.674392) (xy 122.278914 -243.674392) (xy 122.282874 -243.625338) (xy 122.294651 -243.577554)
			(xy 122.313942 -243.532278) (xy 122.340245 -243.490682) (xy 122.37288 -243.453845) (xy 122.411001 -243.42272)
			(xy 122.453622 -243.398113) (xy 122.499638 -243.380661) (xy 122.547857 -243.370817) (xy 122.597032 -243.368836)
			(xy 122.645887 -243.374768) (xy 122.693158 -243.38846) (xy 122.73762 -243.409558) (xy 122.778123 -243.437514)
			(xy 122.813616 -243.471606) (xy 122.843181 -243.51095) (xy 122.866052 -243.554527) (xy 122.881636 -243.601208)
			(xy 122.889531 -243.649785) (xy 122.890026 -243.674392) (xy 123.218968 -243.674392) (xy 123.222928 -243.625338)
			(xy 123.234705 -243.577554) (xy 123.253996 -243.532278) (xy 123.280299 -243.490682) (xy 123.312934 -243.453845)
			(xy 123.351055 -243.42272) (xy 123.393676 -243.398113) (xy 123.439692 -243.380661) (xy 123.487911 -243.370817)
			(xy 123.537086 -243.368836) (xy 123.585941 -243.374768) (xy 123.633212 -243.38846) (xy 123.677674 -243.409558)
			(xy 123.718177 -243.437514) (xy 123.75367 -243.471606) (xy 123.783235 -243.51095) (xy 123.806106 -243.554527)
			(xy 123.82169 -243.601208) (xy 123.829585 -243.649785) (xy 123.83008 -243.674392) (xy 124.159022 -243.674392)
			(xy 124.162982 -243.625338) (xy 124.174759 -243.577554) (xy 124.19405 -243.532278) (xy 124.220353 -243.490682)
			(xy 124.252988 -243.453845) (xy 124.291109 -243.42272) (xy 124.33373 -243.398113) (xy 124.379746 -243.380661)
			(xy 124.427965 -243.370817) (xy 124.47714 -243.368836) (xy 124.525995 -243.374768) (xy 124.573266 -243.38846)
			(xy 124.617728 -243.409558) (xy 124.658231 -243.437514) (xy 124.693724 -243.471606) (xy 124.723289 -243.51095)
			(xy 124.74616 -243.554527) (xy 124.761744 -243.601208) (xy 124.769639 -243.649785) (xy 124.770134 -243.674392)
			(xy 125.098822 -243.674392) (xy 125.102782 -243.625338) (xy 125.114559 -243.577554) (xy 125.13385 -243.532278)
			(xy 125.160153 -243.490682) (xy 125.192788 -243.453845) (xy 125.230909 -243.42272) (xy 125.27353 -243.398113)
			(xy 125.319546 -243.380661) (xy 125.367765 -243.370817) (xy 125.41694 -243.368836) (xy 125.465795 -243.374768)
			(xy 125.513066 -243.38846) (xy 125.557528 -243.409558) (xy 125.598031 -243.437514) (xy 125.633524 -243.471606)
			(xy 125.663089 -243.51095) (xy 125.68596 -243.554527) (xy 125.701544 -243.601208) (xy 125.709439 -243.649785)
			(xy 125.709934 -243.674392) (xy 125.709439 -243.698999) (xy 125.701544 -243.747576) (xy 125.68596 -243.794257)
			(xy 125.663089 -243.837834) (xy 125.633524 -243.877178) (xy 125.598031 -243.91127) (xy 125.557528 -243.939226)
			(xy 125.513066 -243.960324) (xy 125.465795 -243.974016) (xy 125.41694 -243.979948) (xy 125.367765 -243.977967)
			(xy 125.319546 -243.968123) (xy 125.27353 -243.950671) (xy 125.230909 -243.926064) (xy 125.192788 -243.894939)
			(xy 125.160153 -243.858102) (xy 125.13385 -243.816506) (xy 125.114559 -243.77123) (xy 125.102782 -243.723446)
			(xy 125.098822 -243.674392) (xy 124.770134 -243.674392) (xy 124.769639 -243.698999) (xy 124.761744 -243.747576)
			(xy 124.74616 -243.794257) (xy 124.723289 -243.837834) (xy 124.693724 -243.877178) (xy 124.658231 -243.91127)
			(xy 124.617728 -243.939226) (xy 124.573266 -243.960324) (xy 124.525995 -243.974016) (xy 124.47714 -243.979948)
			(xy 124.427965 -243.977967) (xy 124.379746 -243.968123) (xy 124.33373 -243.950671) (xy 124.291109 -243.926064)
			(xy 124.252988 -243.894939) (xy 124.220353 -243.858102) (xy 124.19405 -243.816506) (xy 124.174759 -243.77123)
			(xy 124.162982 -243.723446) (xy 124.159022 -243.674392) (xy 123.83008 -243.674392) (xy 123.829585 -243.698999)
			(xy 123.82169 -243.747576) (xy 123.806106 -243.794257) (xy 123.783235 -243.837834) (xy 123.75367 -243.877178)
			(xy 123.718177 -243.91127) (xy 123.677674 -243.939226) (xy 123.633212 -243.960324) (xy 123.585941 -243.974016)
			(xy 123.537086 -243.979948) (xy 123.487911 -243.977967) (xy 123.439692 -243.968123) (xy 123.393676 -243.950671)
			(xy 123.351055 -243.926064) (xy 123.312934 -243.894939) (xy 123.280299 -243.858102) (xy 123.253996 -243.816506)
			(xy 123.234705 -243.77123) (xy 123.222928 -243.723446) (xy 123.218968 -243.674392) (xy 122.890026 -243.674392)
			(xy 122.889531 -243.698999) (xy 122.881636 -243.747576) (xy 122.866052 -243.794257) (xy 122.843181 -243.837834)
			(xy 122.813616 -243.877178) (xy 122.778123 -243.91127) (xy 122.73762 -243.939226) (xy 122.693158 -243.960324)
			(xy 122.645887 -243.974016) (xy 122.597032 -243.979948) (xy 122.547857 -243.977967) (xy 122.499638 -243.968123)
			(xy 122.453622 -243.950671) (xy 122.411001 -243.926064) (xy 122.37288 -243.894939) (xy 122.340245 -243.858102)
			(xy 122.313942 -243.816506) (xy 122.294651 -243.77123) (xy 122.282874 -243.723446) (xy 122.278914 -243.674392)
			(xy 121.949972 -243.674392) (xy 121.949477 -243.698999) (xy 121.941582 -243.747576) (xy 121.925998 -243.794257)
			(xy 121.903127 -243.837834) (xy 121.873562 -243.877178) (xy 121.838069 -243.91127) (xy 121.797566 -243.939226)
			(xy 121.753104 -243.960324) (xy 121.705833 -243.974016) (xy 121.656978 -243.979948) (xy 121.607803 -243.977967)
			(xy 121.559584 -243.968123) (xy 121.513568 -243.950671) (xy 121.470947 -243.926064) (xy 121.432826 -243.894939)
			(xy 121.400191 -243.858102) (xy 121.373888 -243.816506) (xy 121.354597 -243.77123) (xy 121.34282 -243.723446)
			(xy 121.33886 -243.674392) (xy 121.009918 -243.674392) (xy 121.009423 -243.698999) (xy 121.001528 -243.747576)
			(xy 120.985944 -243.794257) (xy 120.963073 -243.837834) (xy 120.933508 -243.877178) (xy 120.898015 -243.91127)
			(xy 120.857512 -243.939226) (xy 120.81305 -243.960324) (xy 120.765779 -243.974016) (xy 120.716924 -243.979948)
			(xy 120.667749 -243.977967) (xy 120.61953 -243.968123) (xy 120.573514 -243.950671) (xy 120.530893 -243.926064)
			(xy 120.492772 -243.894939) (xy 120.460137 -243.858102) (xy 120.433834 -243.816506) (xy 120.414543 -243.77123)
			(xy 120.402766 -243.723446) (xy 120.398806 -243.674392) (xy 120.070118 -243.674392) (xy 120.069623 -243.698999)
			(xy 120.061728 -243.747576) (xy 120.046144 -243.794257) (xy 120.023273 -243.837834) (xy 119.993708 -243.877178)
			(xy 119.958215 -243.91127) (xy 119.917712 -243.939226) (xy 119.87325 -243.960324) (xy 119.825979 -243.974016)
			(xy 119.777124 -243.979948) (xy 119.727949 -243.977967) (xy 119.67973 -243.968123) (xy 119.633714 -243.950671)
			(xy 119.591093 -243.926064) (xy 119.552972 -243.894939) (xy 119.520337 -243.858102) (xy 119.494034 -243.816506)
			(xy 119.474743 -243.77123) (xy 119.462966 -243.723446) (xy 119.459006 -243.674392) (xy 119.130064 -243.674392)
			(xy 119.129569 -243.698999) (xy 119.121674 -243.747576) (xy 119.10609 -243.794257) (xy 119.083219 -243.837834)
			(xy 119.053654 -243.877178) (xy 119.018161 -243.91127) (xy 118.977658 -243.939226) (xy 118.933196 -243.960324)
			(xy 118.885925 -243.974016) (xy 118.83707 -243.979948) (xy 118.787895 -243.977967) (xy 118.739676 -243.968123)
			(xy 118.69366 -243.950671) (xy 118.651039 -243.926064) (xy 118.612918 -243.894939) (xy 118.580283 -243.858102)
			(xy 118.55398 -243.816506) (xy 118.534689 -243.77123) (xy 118.522912 -243.723446) (xy 118.518952 -243.674392)
			(xy 118.19001 -243.674392) (xy 118.189515 -243.698999) (xy 118.18162 -243.747576) (xy 118.166036 -243.794257)
			(xy 118.143165 -243.837834) (xy 118.1136 -243.877178) (xy 118.078107 -243.91127) (xy 118.037604 -243.939226)
			(xy 117.993142 -243.960324) (xy 117.945871 -243.974016) (xy 117.897016 -243.979948) (xy 117.847841 -243.977967)
			(xy 117.799622 -243.968123) (xy 117.753606 -243.950671) (xy 117.710985 -243.926064) (xy 117.672864 -243.894939)
			(xy 117.640229 -243.858102) (xy 117.613926 -243.816506) (xy 117.594635 -243.77123) (xy 117.582858 -243.723446)
			(xy 117.578898 -243.674392) (xy 117.249956 -243.674392) (xy 117.249461 -243.698999) (xy 117.241566 -243.747576)
			(xy 117.225982 -243.794257) (xy 117.203111 -243.837834) (xy 117.173546 -243.877178) (xy 117.138053 -243.91127)
			(xy 117.09755 -243.939226) (xy 117.053088 -243.960324) (xy 117.005817 -243.974016) (xy 116.956962 -243.979948)
			(xy 116.907787 -243.977967) (xy 116.859568 -243.968123) (xy 116.813552 -243.950671) (xy 116.770931 -243.926064)
			(xy 116.73281 -243.894939) (xy 116.700175 -243.858102) (xy 116.673872 -243.816506) (xy 116.654581 -243.77123)
			(xy 116.642804 -243.723446) (xy 116.638844 -243.674392) (xy 116.310156 -243.674392) (xy 116.309661 -243.698999)
			(xy 116.301766 -243.747576) (xy 116.286182 -243.794257) (xy 116.263311 -243.837834) (xy 116.233746 -243.877178)
			(xy 116.198253 -243.91127) (xy 116.15775 -243.939226) (xy 116.113288 -243.960324) (xy 116.066017 -243.974016)
			(xy 116.017162 -243.979948) (xy 115.967987 -243.977967) (xy 115.919768 -243.968123) (xy 115.873752 -243.950671)
			(xy 115.831131 -243.926064) (xy 115.79301 -243.894939) (xy 115.760375 -243.858102) (xy 115.734072 -243.816506)
			(xy 115.714781 -243.77123) (xy 115.703004 -243.723446) (xy 115.699044 -243.674392) (xy 115.370102 -243.674392)
			(xy 115.369607 -243.698999) (xy 115.361712 -243.747576) (xy 115.346128 -243.794257) (xy 115.323257 -243.837834)
			(xy 115.293692 -243.877178) (xy 115.258199 -243.91127) (xy 115.217696 -243.939226) (xy 115.173234 -243.960324)
			(xy 115.125963 -243.974016) (xy 115.077108 -243.979948) (xy 115.027933 -243.977967) (xy 114.979714 -243.968123)
			(xy 114.933698 -243.950671) (xy 114.891077 -243.926064) (xy 114.852956 -243.894939) (xy 114.820321 -243.858102)
			(xy 114.794018 -243.816506) (xy 114.774727 -243.77123) (xy 114.76295 -243.723446) (xy 114.75899 -243.674392)
			(xy 114.430048 -243.674392) (xy 114.429553 -243.698999) (xy 114.421658 -243.747576) (xy 114.406074 -243.794257)
			(xy 114.383203 -243.837834) (xy 114.353638 -243.877178) (xy 114.318145 -243.91127) (xy 114.277642 -243.939226)
			(xy 114.23318 -243.960324) (xy 114.185909 -243.974016) (xy 114.137054 -243.979948) (xy 114.087879 -243.977967)
			(xy 114.03966 -243.968123) (xy 113.993644 -243.950671) (xy 113.951023 -243.926064) (xy 113.912902 -243.894939)
			(xy 113.880267 -243.858102) (xy 113.853964 -243.816506) (xy 113.834673 -243.77123) (xy 113.822896 -243.723446)
			(xy 113.818936 -243.674392) (xy 113.489994 -243.674392) (xy 113.489499 -243.698999) (xy 113.481604 -243.747576)
			(xy 113.46602 -243.794257) (xy 113.443149 -243.837834) (xy 113.413584 -243.877178) (xy 113.378091 -243.91127)
			(xy 113.337588 -243.939226) (xy 113.293126 -243.960324) (xy 113.245855 -243.974016) (xy 113.197 -243.979948)
			(xy 113.147825 -243.977967) (xy 113.099606 -243.968123) (xy 113.05359 -243.950671) (xy 113.010969 -243.926064)
			(xy 112.972848 -243.894939) (xy 112.940213 -243.858102) (xy 112.91391 -243.816506) (xy 112.894619 -243.77123)
			(xy 112.882842 -243.723446) (xy 112.878882 -243.674392) (xy 111.90986 -243.674392) (xy 111.90986 -244.484398)
			(xy 113.349036 -244.484398) (xy 113.352996 -244.435344) (xy 113.364773 -244.38756) (xy 113.384064 -244.342284)
			(xy 113.410367 -244.300688) (xy 113.443002 -244.263851) (xy 113.481123 -244.232726) (xy 113.523744 -244.208119)
			(xy 113.56976 -244.190667) (xy 113.617979 -244.180823) (xy 113.667154 -244.178842) (xy 113.716009 -244.184774)
			(xy 113.76328 -244.198466) (xy 113.807742 -244.219564) (xy 113.848245 -244.24752) (xy 113.883738 -244.281612)
			(xy 113.913303 -244.320956) (xy 113.936174 -244.364533) (xy 113.951758 -244.411214) (xy 113.959653 -244.459791)
			(xy 113.960148 -244.484398) (xy 114.288836 -244.484398) (xy 114.292796 -244.435344) (xy 114.304573 -244.38756)
			(xy 114.323864 -244.342284) (xy 114.350167 -244.300688) (xy 114.382802 -244.263851) (xy 114.420923 -244.232726)
			(xy 114.463544 -244.208119) (xy 114.50956 -244.190667) (xy 114.557779 -244.180823) (xy 114.606954 -244.178842)
			(xy 114.655809 -244.184774) (xy 114.70308 -244.198466) (xy 114.747542 -244.219564) (xy 114.788045 -244.24752)
			(xy 114.823538 -244.281612) (xy 114.853103 -244.320956) (xy 114.875974 -244.364533) (xy 114.891558 -244.411214)
			(xy 114.899453 -244.459791) (xy 114.899948 -244.484398) (xy 115.22889 -244.484398) (xy 115.23285 -244.435344)
			(xy 115.244627 -244.38756) (xy 115.263918 -244.342284) (xy 115.290221 -244.300688) (xy 115.322856 -244.263851)
			(xy 115.360977 -244.232726) (xy 115.403598 -244.208119) (xy 115.449614 -244.190667) (xy 115.497833 -244.180823)
			(xy 115.547008 -244.178842) (xy 115.595863 -244.184774) (xy 115.643134 -244.198466) (xy 115.687596 -244.219564)
			(xy 115.728099 -244.24752) (xy 115.763592 -244.281612) (xy 115.793157 -244.320956) (xy 115.816028 -244.364533)
			(xy 115.831612 -244.411214) (xy 115.839507 -244.459791) (xy 115.840002 -244.484398) (xy 116.168944 -244.484398)
			(xy 116.172904 -244.435344) (xy 116.184681 -244.38756) (xy 116.203972 -244.342284) (xy 116.230275 -244.300688)
			(xy 116.26291 -244.263851) (xy 116.301031 -244.232726) (xy 116.343652 -244.208119) (xy 116.389668 -244.190667)
			(xy 116.437887 -244.180823) (xy 116.487062 -244.178842) (xy 116.535917 -244.184774) (xy 116.583188 -244.198466)
			(xy 116.62765 -244.219564) (xy 116.668153 -244.24752) (xy 116.703646 -244.281612) (xy 116.733211 -244.320956)
			(xy 116.756082 -244.364533) (xy 116.771666 -244.411214) (xy 116.779561 -244.459791) (xy 116.780056 -244.484398)
			(xy 117.108998 -244.484398) (xy 117.112958 -244.435344) (xy 117.124735 -244.38756) (xy 117.144026 -244.342284)
			(xy 117.170329 -244.300688) (xy 117.202964 -244.263851) (xy 117.241085 -244.232726) (xy 117.283706 -244.208119)
			(xy 117.329722 -244.190667) (xy 117.377941 -244.180823) (xy 117.427116 -244.178842) (xy 117.475971 -244.184774)
			(xy 117.523242 -244.198466) (xy 117.567704 -244.219564) (xy 117.608207 -244.24752) (xy 117.6437 -244.281612)
			(xy 117.673265 -244.320956) (xy 117.696136 -244.364533) (xy 117.71172 -244.411214) (xy 117.719615 -244.459791)
			(xy 117.72011 -244.484398) (xy 118.049052 -244.484398) (xy 118.053012 -244.435344) (xy 118.064789 -244.38756)
			(xy 118.08408 -244.342284) (xy 118.110383 -244.300688) (xy 118.143018 -244.263851) (xy 118.181139 -244.232726)
			(xy 118.22376 -244.208119) (xy 118.269776 -244.190667) (xy 118.317995 -244.180823) (xy 118.36717 -244.178842)
			(xy 118.416025 -244.184774) (xy 118.463296 -244.198466) (xy 118.507758 -244.219564) (xy 118.548261 -244.24752)
			(xy 118.583754 -244.281612) (xy 118.613319 -244.320956) (xy 118.63619 -244.364533) (xy 118.651774 -244.411214)
			(xy 118.659669 -244.459791) (xy 118.660164 -244.484398) (xy 118.988852 -244.484398) (xy 118.992812 -244.435344)
			(xy 119.004589 -244.38756) (xy 119.02388 -244.342284) (xy 119.050183 -244.300688) (xy 119.082818 -244.263851)
			(xy 119.120939 -244.232726) (xy 119.16356 -244.208119) (xy 119.209576 -244.190667) (xy 119.257795 -244.180823)
			(xy 119.30697 -244.178842) (xy 119.355825 -244.184774) (xy 119.403096 -244.198466) (xy 119.447558 -244.219564)
			(xy 119.488061 -244.24752) (xy 119.523554 -244.281612) (xy 119.553119 -244.320956) (xy 119.57599 -244.364533)
			(xy 119.591574 -244.411214) (xy 119.599469 -244.459791) (xy 119.599964 -244.484398) (xy 119.928906 -244.484398)
			(xy 119.932866 -244.435344) (xy 119.944643 -244.38756) (xy 119.963934 -244.342284) (xy 119.990237 -244.300688)
			(xy 120.022872 -244.263851) (xy 120.060993 -244.232726) (xy 120.103614 -244.208119) (xy 120.14963 -244.190667)
			(xy 120.197849 -244.180823) (xy 120.247024 -244.178842) (xy 120.295879 -244.184774) (xy 120.34315 -244.198466)
			(xy 120.387612 -244.219564) (xy 120.428115 -244.24752) (xy 120.463608 -244.281612) (xy 120.493173 -244.320956)
			(xy 120.516044 -244.364533) (xy 120.531628 -244.411214) (xy 120.539523 -244.459791) (xy 120.540018 -244.484398)
			(xy 120.86896 -244.484398) (xy 120.87292 -244.435344) (xy 120.884697 -244.38756) (xy 120.903988 -244.342284)
			(xy 120.930291 -244.300688) (xy 120.962926 -244.263851) (xy 121.001047 -244.232726) (xy 121.043668 -244.208119)
			(xy 121.089684 -244.190667) (xy 121.137903 -244.180823) (xy 121.187078 -244.178842) (xy 121.235933 -244.184774)
			(xy 121.283204 -244.198466) (xy 121.327666 -244.219564) (xy 121.368169 -244.24752) (xy 121.403662 -244.281612)
			(xy 121.433227 -244.320956) (xy 121.456098 -244.364533) (xy 121.471682 -244.411214) (xy 121.479577 -244.459791)
			(xy 121.480072 -244.484398) (xy 121.809014 -244.484398) (xy 121.812974 -244.435344) (xy 121.824751 -244.38756)
			(xy 121.844042 -244.342284) (xy 121.870345 -244.300688) (xy 121.90298 -244.263851) (xy 121.941101 -244.232726)
			(xy 121.983722 -244.208119) (xy 122.029738 -244.190667) (xy 122.077957 -244.180823) (xy 122.127132 -244.178842)
			(xy 122.175987 -244.184774) (xy 122.223258 -244.198466) (xy 122.26772 -244.219564) (xy 122.308223 -244.24752)
			(xy 122.343716 -244.281612) (xy 122.373281 -244.320956) (xy 122.396152 -244.364533) (xy 122.411736 -244.411214)
			(xy 122.419631 -244.459791) (xy 122.420126 -244.484398) (xy 122.748814 -244.484398) (xy 122.752774 -244.435344)
			(xy 122.764551 -244.38756) (xy 122.783842 -244.342284) (xy 122.810145 -244.300688) (xy 122.84278 -244.263851)
			(xy 122.880901 -244.232726) (xy 122.923522 -244.208119) (xy 122.969538 -244.190667) (xy 123.017757 -244.180823)
			(xy 123.066932 -244.178842) (xy 123.115787 -244.184774) (xy 123.163058 -244.198466) (xy 123.20752 -244.219564)
			(xy 123.248023 -244.24752) (xy 123.283516 -244.281612) (xy 123.313081 -244.320956) (xy 123.335952 -244.364533)
			(xy 123.351536 -244.411214) (xy 123.359431 -244.459791) (xy 123.359926 -244.484398) (xy 123.688868 -244.484398)
			(xy 123.692828 -244.435344) (xy 123.704605 -244.38756) (xy 123.723896 -244.342284) (xy 123.750199 -244.300688)
			(xy 123.782834 -244.263851) (xy 123.820955 -244.232726) (xy 123.863576 -244.208119) (xy 123.909592 -244.190667)
			(xy 123.957811 -244.180823) (xy 124.006986 -244.178842) (xy 124.055841 -244.184774) (xy 124.103112 -244.198466)
			(xy 124.147574 -244.219564) (xy 124.188077 -244.24752) (xy 124.22357 -244.281612) (xy 124.253135 -244.320956)
			(xy 124.276006 -244.364533) (xy 124.29159 -244.411214) (xy 124.299485 -244.459791) (xy 124.29998 -244.484398)
			(xy 124.628922 -244.484398) (xy 124.632882 -244.435344) (xy 124.644659 -244.38756) (xy 124.66395 -244.342284)
			(xy 124.690253 -244.300688) (xy 124.722888 -244.263851) (xy 124.761009 -244.232726) (xy 124.80363 -244.208119)
			(xy 124.849646 -244.190667) (xy 124.897865 -244.180823) (xy 124.94704 -244.178842) (xy 124.995895 -244.184774)
			(xy 125.043166 -244.198466) (xy 125.087628 -244.219564) (xy 125.128131 -244.24752) (xy 125.163624 -244.281612)
			(xy 125.193189 -244.320956) (xy 125.21606 -244.364533) (xy 125.231644 -244.411214) (xy 125.239539 -244.459791)
			(xy 125.240034 -244.484398) (xy 125.568976 -244.484398) (xy 125.572936 -244.435344) (xy 125.584713 -244.38756)
			(xy 125.604004 -244.342284) (xy 125.630307 -244.300688) (xy 125.662942 -244.263851) (xy 125.701063 -244.232726)
			(xy 125.743684 -244.208119) (xy 125.7897 -244.190667) (xy 125.837919 -244.180823) (xy 125.887094 -244.178842)
			(xy 125.935949 -244.184774) (xy 125.98322 -244.198466) (xy 126.027682 -244.219564) (xy 126.068185 -244.24752)
			(xy 126.103678 -244.281612) (xy 126.133243 -244.320956) (xy 126.156114 -244.364533) (xy 126.171698 -244.411214)
			(xy 126.179593 -244.459791) (xy 126.180088 -244.484398) (xy 126.179593 -244.509005) (xy 126.171698 -244.557582)
			(xy 126.156114 -244.604263) (xy 126.133243 -244.64784) (xy 126.103678 -244.687184) (xy 126.068185 -244.721276)
			(xy 126.027682 -244.749232) (xy 125.98322 -244.77033) (xy 125.935949 -244.784022) (xy 125.887094 -244.789954)
			(xy 125.837919 -244.787973) (xy 125.7897 -244.778129) (xy 125.743684 -244.760677) (xy 125.701063 -244.73607)
			(xy 125.662942 -244.704945) (xy 125.630307 -244.668108) (xy 125.604004 -244.626512) (xy 125.584713 -244.581236)
			(xy 125.572936 -244.533452) (xy 125.568976 -244.484398) (xy 125.240034 -244.484398) (xy 125.239539 -244.509005)
			(xy 125.231644 -244.557582) (xy 125.21606 -244.604263) (xy 125.193189 -244.64784) (xy 125.163624 -244.687184)
			(xy 125.128131 -244.721276) (xy 125.087628 -244.749232) (xy 125.043166 -244.77033) (xy 124.995895 -244.784022)
			(xy 124.94704 -244.789954) (xy 124.897865 -244.787973) (xy 124.849646 -244.778129) (xy 124.80363 -244.760677)
			(xy 124.761009 -244.73607) (xy 124.722888 -244.704945) (xy 124.690253 -244.668108) (xy 124.66395 -244.626512)
			(xy 124.644659 -244.581236) (xy 124.632882 -244.533452) (xy 124.628922 -244.484398) (xy 124.29998 -244.484398)
			(xy 124.299485 -244.509005) (xy 124.29159 -244.557582) (xy 124.276006 -244.604263) (xy 124.253135 -244.64784)
			(xy 124.22357 -244.687184) (xy 124.188077 -244.721276) (xy 124.147574 -244.749232) (xy 124.103112 -244.77033)
			(xy 124.055841 -244.784022) (xy 124.006986 -244.789954) (xy 123.957811 -244.787973) (xy 123.909592 -244.778129)
			(xy 123.863576 -244.760677) (xy 123.820955 -244.73607) (xy 123.782834 -244.704945) (xy 123.750199 -244.668108)
			(xy 123.723896 -244.626512) (xy 123.704605 -244.581236) (xy 123.692828 -244.533452) (xy 123.688868 -244.484398)
			(xy 123.359926 -244.484398) (xy 123.359431 -244.509005) (xy 123.351536 -244.557582) (xy 123.335952 -244.604263)
			(xy 123.313081 -244.64784) (xy 123.283516 -244.687184) (xy 123.248023 -244.721276) (xy 123.20752 -244.749232)
			(xy 123.163058 -244.77033) (xy 123.115787 -244.784022) (xy 123.066932 -244.789954) (xy 123.017757 -244.787973)
			(xy 122.969538 -244.778129) (xy 122.923522 -244.760677) (xy 122.880901 -244.73607) (xy 122.84278 -244.704945)
			(xy 122.810145 -244.668108) (xy 122.783842 -244.626512) (xy 122.764551 -244.581236) (xy 122.752774 -244.533452)
			(xy 122.748814 -244.484398) (xy 122.420126 -244.484398) (xy 122.419631 -244.509005) (xy 122.411736 -244.557582)
			(xy 122.396152 -244.604263) (xy 122.373281 -244.64784) (xy 122.343716 -244.687184) (xy 122.308223 -244.721276)
			(xy 122.26772 -244.749232) (xy 122.223258 -244.77033) (xy 122.175987 -244.784022) (xy 122.127132 -244.789954)
			(xy 122.077957 -244.787973) (xy 122.029738 -244.778129) (xy 121.983722 -244.760677) (xy 121.941101 -244.73607)
			(xy 121.90298 -244.704945) (xy 121.870345 -244.668108) (xy 121.844042 -244.626512) (xy 121.824751 -244.581236)
			(xy 121.812974 -244.533452) (xy 121.809014 -244.484398) (xy 121.480072 -244.484398) (xy 121.479577 -244.509005)
			(xy 121.471682 -244.557582) (xy 121.456098 -244.604263) (xy 121.433227 -244.64784) (xy 121.403662 -244.687184)
			(xy 121.368169 -244.721276) (xy 121.327666 -244.749232) (xy 121.283204 -244.77033) (xy 121.235933 -244.784022)
			(xy 121.187078 -244.789954) (xy 121.137903 -244.787973) (xy 121.089684 -244.778129) (xy 121.043668 -244.760677)
			(xy 121.001047 -244.73607) (xy 120.962926 -244.704945) (xy 120.930291 -244.668108) (xy 120.903988 -244.626512)
			(xy 120.884697 -244.581236) (xy 120.87292 -244.533452) (xy 120.86896 -244.484398) (xy 120.540018 -244.484398)
			(xy 120.539523 -244.509005) (xy 120.531628 -244.557582) (xy 120.516044 -244.604263) (xy 120.493173 -244.64784)
			(xy 120.463608 -244.687184) (xy 120.428115 -244.721276) (xy 120.387612 -244.749232) (xy 120.34315 -244.77033)
			(xy 120.295879 -244.784022) (xy 120.247024 -244.789954) (xy 120.197849 -244.787973) (xy 120.14963 -244.778129)
			(xy 120.103614 -244.760677) (xy 120.060993 -244.73607) (xy 120.022872 -244.704945) (xy 119.990237 -244.668108)
			(xy 119.963934 -244.626512) (xy 119.944643 -244.581236) (xy 119.932866 -244.533452) (xy 119.928906 -244.484398)
			(xy 119.599964 -244.484398) (xy 119.599469 -244.509005) (xy 119.591574 -244.557582) (xy 119.57599 -244.604263)
			(xy 119.553119 -244.64784) (xy 119.523554 -244.687184) (xy 119.488061 -244.721276) (xy 119.447558 -244.749232)
			(xy 119.403096 -244.77033) (xy 119.355825 -244.784022) (xy 119.30697 -244.789954) (xy 119.257795 -244.787973)
			(xy 119.209576 -244.778129) (xy 119.16356 -244.760677) (xy 119.120939 -244.73607) (xy 119.082818 -244.704945)
			(xy 119.050183 -244.668108) (xy 119.02388 -244.626512) (xy 119.004589 -244.581236) (xy 118.992812 -244.533452)
			(xy 118.988852 -244.484398) (xy 118.660164 -244.484398) (xy 118.659669 -244.509005) (xy 118.651774 -244.557582)
			(xy 118.63619 -244.604263) (xy 118.613319 -244.64784) (xy 118.583754 -244.687184) (xy 118.548261 -244.721276)
			(xy 118.507758 -244.749232) (xy 118.463296 -244.77033) (xy 118.416025 -244.784022) (xy 118.36717 -244.789954)
			(xy 118.317995 -244.787973) (xy 118.269776 -244.778129) (xy 118.22376 -244.760677) (xy 118.181139 -244.73607)
			(xy 118.143018 -244.704945) (xy 118.110383 -244.668108) (xy 118.08408 -244.626512) (xy 118.064789 -244.581236)
			(xy 118.053012 -244.533452) (xy 118.049052 -244.484398) (xy 117.72011 -244.484398) (xy 117.719615 -244.509005)
			(xy 117.71172 -244.557582) (xy 117.696136 -244.604263) (xy 117.673265 -244.64784) (xy 117.6437 -244.687184)
			(xy 117.608207 -244.721276) (xy 117.567704 -244.749232) (xy 117.523242 -244.77033) (xy 117.475971 -244.784022)
			(xy 117.427116 -244.789954) (xy 117.377941 -244.787973) (xy 117.329722 -244.778129) (xy 117.283706 -244.760677)
			(xy 117.241085 -244.73607) (xy 117.202964 -244.704945) (xy 117.170329 -244.668108) (xy 117.144026 -244.626512)
			(xy 117.124735 -244.581236) (xy 117.112958 -244.533452) (xy 117.108998 -244.484398) (xy 116.780056 -244.484398)
			(xy 116.779561 -244.509005) (xy 116.771666 -244.557582) (xy 116.756082 -244.604263) (xy 116.733211 -244.64784)
			(xy 116.703646 -244.687184) (xy 116.668153 -244.721276) (xy 116.62765 -244.749232) (xy 116.583188 -244.77033)
			(xy 116.535917 -244.784022) (xy 116.487062 -244.789954) (xy 116.437887 -244.787973) (xy 116.389668 -244.778129)
			(xy 116.343652 -244.760677) (xy 116.301031 -244.73607) (xy 116.26291 -244.704945) (xy 116.230275 -244.668108)
			(xy 116.203972 -244.626512) (xy 116.184681 -244.581236) (xy 116.172904 -244.533452) (xy 116.168944 -244.484398)
			(xy 115.840002 -244.484398) (xy 115.839507 -244.509005) (xy 115.831612 -244.557582) (xy 115.816028 -244.604263)
			(xy 115.793157 -244.64784) (xy 115.763592 -244.687184) (xy 115.728099 -244.721276) (xy 115.687596 -244.749232)
			(xy 115.643134 -244.77033) (xy 115.595863 -244.784022) (xy 115.547008 -244.789954) (xy 115.497833 -244.787973)
			(xy 115.449614 -244.778129) (xy 115.403598 -244.760677) (xy 115.360977 -244.73607) (xy 115.322856 -244.704945)
			(xy 115.290221 -244.668108) (xy 115.263918 -244.626512) (xy 115.244627 -244.581236) (xy 115.23285 -244.533452)
			(xy 115.22889 -244.484398) (xy 114.899948 -244.484398) (xy 114.899453 -244.509005) (xy 114.891558 -244.557582)
			(xy 114.875974 -244.604263) (xy 114.853103 -244.64784) (xy 114.823538 -244.687184) (xy 114.788045 -244.721276)
			(xy 114.747542 -244.749232) (xy 114.70308 -244.77033) (xy 114.655809 -244.784022) (xy 114.606954 -244.789954)
			(xy 114.557779 -244.787973) (xy 114.50956 -244.778129) (xy 114.463544 -244.760677) (xy 114.420923 -244.73607)
			(xy 114.382802 -244.704945) (xy 114.350167 -244.668108) (xy 114.323864 -244.626512) (xy 114.304573 -244.581236)
			(xy 114.292796 -244.533452) (xy 114.288836 -244.484398) (xy 113.960148 -244.484398) (xy 113.959653 -244.509005)
			(xy 113.951758 -244.557582) (xy 113.936174 -244.604263) (xy 113.913303 -244.64784) (xy 113.883738 -244.687184)
			(xy 113.848245 -244.721276) (xy 113.807742 -244.749232) (xy 113.76328 -244.77033) (xy 113.716009 -244.784022)
			(xy 113.667154 -244.789954) (xy 113.617979 -244.787973) (xy 113.56976 -244.778129) (xy 113.523744 -244.760677)
			(xy 113.481123 -244.73607) (xy 113.443002 -244.704945) (xy 113.410367 -244.668108) (xy 113.384064 -244.626512)
			(xy 113.364773 -244.581236) (xy 113.352996 -244.533452) (xy 113.349036 -244.484398) (xy 111.90986 -244.484398)
			(xy 111.90986 -245.207282) (xy 111.926116 -245.232174) (xy 111.940086 -245.238524) (xy 111.963991 -245.249697)
			(xy 112.008341 -245.278284) (xy 112.026496 -245.294404) (xy 112.878882 -245.294404) (xy 112.882842 -245.24535)
			(xy 112.894619 -245.197566) (xy 112.91391 -245.15229) (xy 112.940213 -245.110694) (xy 112.972848 -245.073857)
			(xy 113.010969 -245.042732) (xy 113.05359 -245.018125) (xy 113.099606 -245.000673) (xy 113.147825 -244.990829)
			(xy 113.197 -244.988848) (xy 113.245855 -244.99478) (xy 113.293126 -245.008472) (xy 113.337588 -245.02957)
			(xy 113.378091 -245.057526) (xy 113.413584 -245.091618) (xy 113.443149 -245.130962) (xy 113.46602 -245.174539)
			(xy 113.481604 -245.22122) (xy 113.489499 -245.269797) (xy 113.489994 -245.294404) (xy 113.818936 -245.294404)
			(xy 113.822896 -245.24535) (xy 113.834673 -245.197566) (xy 113.853964 -245.15229) (xy 113.880267 -245.110694)
			(xy 113.912902 -245.073857) (xy 113.951023 -245.042732) (xy 113.993644 -245.018125) (xy 114.03966 -245.000673)
			(xy 114.087879 -244.990829) (xy 114.137054 -244.988848) (xy 114.185909 -244.99478) (xy 114.23318 -245.008472)
			(xy 114.277642 -245.02957) (xy 114.318145 -245.057526) (xy 114.353638 -245.091618) (xy 114.383203 -245.130962)
			(xy 114.406074 -245.174539) (xy 114.421658 -245.22122) (xy 114.429553 -245.269797) (xy 114.430048 -245.294404)
			(xy 114.75899 -245.294404) (xy 114.76295 -245.24535) (xy 114.774727 -245.197566) (xy 114.794018 -245.15229)
			(xy 114.820321 -245.110694) (xy 114.852956 -245.073857) (xy 114.891077 -245.042732) (xy 114.933698 -245.018125)
			(xy 114.979714 -245.000673) (xy 115.027933 -244.990829) (xy 115.077108 -244.988848) (xy 115.125963 -244.99478)
			(xy 115.173234 -245.008472) (xy 115.217696 -245.02957) (xy 115.258199 -245.057526) (xy 115.293692 -245.091618)
			(xy 115.323257 -245.130962) (xy 115.346128 -245.174539) (xy 115.361712 -245.22122) (xy 115.369607 -245.269797)
			(xy 115.370102 -245.294404) (xy 115.699044 -245.294404) (xy 115.703004 -245.24535) (xy 115.714781 -245.197566)
			(xy 115.734072 -245.15229) (xy 115.760375 -245.110694) (xy 115.79301 -245.073857) (xy 115.831131 -245.042732)
			(xy 115.873752 -245.018125) (xy 115.919768 -245.000673) (xy 115.967987 -244.990829) (xy 116.017162 -244.988848)
			(xy 116.066017 -244.99478) (xy 116.113288 -245.008472) (xy 116.15775 -245.02957) (xy 116.198253 -245.057526)
			(xy 116.233746 -245.091618) (xy 116.263311 -245.130962) (xy 116.286182 -245.174539) (xy 116.301766 -245.22122)
			(xy 116.309661 -245.269797) (xy 116.310156 -245.294404) (xy 118.518952 -245.294404) (xy 118.522912 -245.24535)
			(xy 118.534689 -245.197566) (xy 118.55398 -245.15229) (xy 118.580283 -245.110694) (xy 118.612918 -245.073857)
			(xy 118.651039 -245.042732) (xy 118.69366 -245.018125) (xy 118.739676 -245.000673) (xy 118.787895 -244.990829)
			(xy 118.83707 -244.988848) (xy 118.885925 -244.99478) (xy 118.933196 -245.008472) (xy 118.977658 -245.02957)
			(xy 119.018161 -245.057526) (xy 119.053654 -245.091618) (xy 119.083219 -245.130962) (xy 119.10609 -245.174539)
			(xy 119.121674 -245.22122) (xy 119.129569 -245.269797) (xy 119.130064 -245.294404) (xy 121.33886 -245.294404)
			(xy 121.34282 -245.24535) (xy 121.354597 -245.197566) (xy 121.373888 -245.15229) (xy 121.400191 -245.110694)
			(xy 121.432826 -245.073857) (xy 121.470947 -245.042732) (xy 121.513568 -245.018125) (xy 121.559584 -245.000673)
			(xy 121.607803 -244.990829) (xy 121.656978 -244.988848) (xy 121.705833 -244.99478) (xy 121.753104 -245.008472)
			(xy 121.797566 -245.02957) (xy 121.838069 -245.057526) (xy 121.873562 -245.091618) (xy 121.903127 -245.130962)
			(xy 121.925998 -245.174539) (xy 121.941582 -245.22122) (xy 121.949477 -245.269797) (xy 121.949972 -245.294404)
			(xy 124.159022 -245.294404) (xy 124.162982 -245.24535) (xy 124.174759 -245.197566) (xy 124.19405 -245.15229)
			(xy 124.220353 -245.110694) (xy 124.252988 -245.073857) (xy 124.291109 -245.042732) (xy 124.33373 -245.018125)
			(xy 124.379746 -245.000673) (xy 124.427965 -244.990829) (xy 124.47714 -244.988848) (xy 124.525995 -244.99478)
			(xy 124.573266 -245.008472) (xy 124.617728 -245.02957) (xy 124.658231 -245.057526) (xy 124.693724 -245.091618)
			(xy 124.723289 -245.130962) (xy 124.74616 -245.174539) (xy 124.761744 -245.22122) (xy 124.769639 -245.269797)
			(xy 124.770134 -245.294404) (xy 124.769639 -245.319011) (xy 124.761744 -245.367588) (xy 124.74616 -245.414269)
			(xy 124.723289 -245.457846) (xy 124.693724 -245.49719) (xy 124.658231 -245.531282) (xy 124.617728 -245.559238)
			(xy 124.573266 -245.580336) (xy 124.525995 -245.594028) (xy 124.47714 -245.59996) (xy 124.427965 -245.597979)
			(xy 124.379746 -245.588135) (xy 124.33373 -245.570683) (xy 124.291109 -245.546076) (xy 124.252988 -245.514951)
			(xy 124.220353 -245.478114) (xy 124.19405 -245.436518) (xy 124.174759 -245.391242) (xy 124.162982 -245.343458)
			(xy 124.159022 -245.294404) (xy 121.949972 -245.294404) (xy 121.949477 -245.319011) (xy 121.941582 -245.367588)
			(xy 121.925998 -245.414269) (xy 121.903127 -245.457846) (xy 121.873562 -245.49719) (xy 121.838069 -245.531282)
			(xy 121.797566 -245.559238) (xy 121.753104 -245.580336) (xy 121.705833 -245.594028) (xy 121.656978 -245.59996)
			(xy 121.607803 -245.597979) (xy 121.559584 -245.588135) (xy 121.513568 -245.570683) (xy 121.470947 -245.546076)
			(xy 121.432826 -245.514951) (xy 121.400191 -245.478114) (xy 121.373888 -245.436518) (xy 121.354597 -245.391242)
			(xy 121.34282 -245.343458) (xy 121.33886 -245.294404) (xy 119.130064 -245.294404) (xy 119.129569 -245.319011)
			(xy 119.121674 -245.367588) (xy 119.10609 -245.414269) (xy 119.083219 -245.457846) (xy 119.053654 -245.49719)
			(xy 119.018161 -245.531282) (xy 118.977658 -245.559238) (xy 118.933196 -245.580336) (xy 118.885925 -245.594028)
			(xy 118.83707 -245.59996) (xy 118.787895 -245.597979) (xy 118.739676 -245.588135) (xy 118.69366 -245.570683)
			(xy 118.651039 -245.546076) (xy 118.612918 -245.514951) (xy 118.580283 -245.478114) (xy 118.55398 -245.436518)
			(xy 118.534689 -245.391242) (xy 118.522912 -245.343458) (xy 118.518952 -245.294404) (xy 116.310156 -245.294404)
			(xy 116.309661 -245.319011) (xy 116.301766 -245.367588) (xy 116.286182 -245.414269) (xy 116.263311 -245.457846)
			(xy 116.233746 -245.49719) (xy 116.198253 -245.531282) (xy 116.15775 -245.559238) (xy 116.113288 -245.580336)
			(xy 116.066017 -245.594028) (xy 116.017162 -245.59996) (xy 115.967987 -245.597979) (xy 115.919768 -245.588135)
			(xy 115.873752 -245.570683) (xy 115.831131 -245.546076) (xy 115.79301 -245.514951) (xy 115.760375 -245.478114)
			(xy 115.734072 -245.436518) (xy 115.714781 -245.391242) (xy 115.703004 -245.343458) (xy 115.699044 -245.294404)
			(xy 115.370102 -245.294404) (xy 115.369607 -245.319011) (xy 115.361712 -245.367588) (xy 115.346128 -245.414269)
			(xy 115.323257 -245.457846) (xy 115.293692 -245.49719) (xy 115.258199 -245.531282) (xy 115.217696 -245.559238)
			(xy 115.173234 -245.580336) (xy 115.125963 -245.594028) (xy 115.077108 -245.59996) (xy 115.027933 -245.597979)
			(xy 114.979714 -245.588135) (xy 114.933698 -245.570683) (xy 114.891077 -245.546076) (xy 114.852956 -245.514951)
			(xy 114.820321 -245.478114) (xy 114.794018 -245.436518) (xy 114.774727 -245.391242) (xy 114.76295 -245.343458)
			(xy 114.75899 -245.294404) (xy 114.430048 -245.294404) (xy 114.429553 -245.319011) (xy 114.421658 -245.367588)
			(xy 114.406074 -245.414269) (xy 114.383203 -245.457846) (xy 114.353638 -245.49719) (xy 114.318145 -245.531282)
			(xy 114.277642 -245.559238) (xy 114.23318 -245.580336) (xy 114.185909 -245.594028) (xy 114.137054 -245.59996)
			(xy 114.087879 -245.597979) (xy 114.03966 -245.588135) (xy 113.993644 -245.570683) (xy 113.951023 -245.546076)
			(xy 113.912902 -245.514951) (xy 113.880267 -245.478114) (xy 113.853964 -245.436518) (xy 113.834673 -245.391242)
			(xy 113.822896 -245.343458) (xy 113.818936 -245.294404) (xy 113.489994 -245.294404) (xy 113.489499 -245.319011)
			(xy 113.481604 -245.367588) (xy 113.46602 -245.414269) (xy 113.443149 -245.457846) (xy 113.413584 -245.49719)
			(xy 113.378091 -245.531282) (xy 113.337588 -245.559238) (xy 113.293126 -245.580336) (xy 113.245855 -245.594028)
			(xy 113.197 -245.59996) (xy 113.147825 -245.597979) (xy 113.099606 -245.588135) (xy 113.05359 -245.570683)
			(xy 113.010969 -245.546076) (xy 112.972848 -245.514951) (xy 112.940213 -245.478114) (xy 112.91391 -245.436518)
			(xy 112.894619 -245.391242) (xy 112.882842 -245.343458) (xy 112.878882 -245.294404) (xy 112.026496 -245.294404)
			(xy 112.047797 -245.313318) (xy 112.081429 -245.353976) (xy 112.108445 -245.399301) (xy 112.128209 -245.448224)
			(xy 112.140257 -245.499596) (xy 112.144304 -245.552206) (xy 112.140255 -245.604815) (xy 112.128206 -245.656186)
			(xy 112.10844 -245.70511) (xy 112.081422 -245.750433) (xy 112.047789 -245.79109) (xy 112.008332 -245.826123)
			(xy 111.963981 -245.854708) (xy 111.940086 -245.865904) (xy 111.926116 -245.872254) (xy 111.90986 -245.897146)
			(xy 111.90986 -245.922038) (xy 111.909429 -245.932104) (xy 111.9017 -245.950695) (xy 111.894874 -245.958106)
			(xy 111.74857 -246.10441) (xy 115.22889 -246.10441) (xy 115.23285 -246.055356) (xy 115.244627 -246.007572)
			(xy 115.263918 -245.962296) (xy 115.290221 -245.9207) (xy 115.322856 -245.883863) (xy 115.360977 -245.852738)
			(xy 115.403598 -245.828131) (xy 115.449614 -245.810679) (xy 115.497833 -245.800835) (xy 115.547008 -245.798854)
			(xy 115.595863 -245.804786) (xy 115.643134 -245.818478) (xy 115.687596 -245.839576) (xy 115.728099 -245.867532)
			(xy 115.763592 -245.901624) (xy 115.793157 -245.940968) (xy 115.816028 -245.984545) (xy 115.831612 -246.031226)
			(xy 115.839507 -246.079803) (xy 115.840002 -246.10441) (xy 116.168944 -246.10441) (xy 116.172904 -246.055356)
			(xy 116.184681 -246.007572) (xy 116.203972 -245.962296) (xy 116.230275 -245.9207) (xy 116.26291 -245.883863)
			(xy 116.301031 -245.852738) (xy 116.343652 -245.828131) (xy 116.389668 -245.810679) (xy 116.437887 -245.800835)
			(xy 116.487062 -245.798854) (xy 116.535917 -245.804786) (xy 116.583188 -245.818478) (xy 116.62765 -245.839576)
			(xy 116.668153 -245.867532) (xy 116.703646 -245.901624) (xy 116.733211 -245.940968) (xy 116.756082 -245.984545)
			(xy 116.771666 -246.031226) (xy 116.779561 -246.079803) (xy 116.780056 -246.10441) (xy 117.108998 -246.10441)
			(xy 117.112958 -246.055356) (xy 117.124735 -246.007572) (xy 117.144026 -245.962296) (xy 117.170329 -245.9207)
			(xy 117.202964 -245.883863) (xy 117.241085 -245.852738) (xy 117.283706 -245.828131) (xy 117.329722 -245.810679)
			(xy 117.377941 -245.800835) (xy 117.427116 -245.798854) (xy 117.475971 -245.804786) (xy 117.523242 -245.818478)
			(xy 117.567704 -245.839576) (xy 117.608207 -245.867532) (xy 117.6437 -245.901624) (xy 117.673265 -245.940968)
			(xy 117.696136 -245.984545) (xy 117.71172 -246.031226) (xy 117.719615 -246.079803) (xy 117.72011 -246.10441)
			(xy 118.049052 -246.10441) (xy 118.053012 -246.055356) (xy 118.064789 -246.007572) (xy 118.08408 -245.962296)
			(xy 118.110383 -245.9207) (xy 118.143018 -245.883863) (xy 118.181139 -245.852738) (xy 118.22376 -245.828131)
			(xy 118.269776 -245.810679) (xy 118.317995 -245.800835) (xy 118.36717 -245.798854) (xy 118.416025 -245.804786)
			(xy 118.463296 -245.818478) (xy 118.507758 -245.839576) (xy 118.548261 -245.867532) (xy 118.583754 -245.901624)
			(xy 118.613319 -245.940968) (xy 118.63619 -245.984545) (xy 118.651774 -246.031226) (xy 118.659669 -246.079803)
			(xy 118.660164 -246.10441) (xy 118.988852 -246.10441) (xy 118.992812 -246.055356) (xy 119.004589 -246.007572)
			(xy 119.02388 -245.962296) (xy 119.050183 -245.9207) (xy 119.082818 -245.883863) (xy 119.120939 -245.852738)
			(xy 119.16356 -245.828131) (xy 119.209576 -245.810679) (xy 119.257795 -245.800835) (xy 119.30697 -245.798854)
			(xy 119.355825 -245.804786) (xy 119.403096 -245.818478) (xy 119.447558 -245.839576) (xy 119.488061 -245.867532)
			(xy 119.523554 -245.901624) (xy 119.553119 -245.940968) (xy 119.57599 -245.984545) (xy 119.591574 -246.031226)
			(xy 119.599469 -246.079803) (xy 119.599964 -246.10441) (xy 119.928906 -246.10441) (xy 119.932866 -246.055356)
			(xy 119.944643 -246.007572) (xy 119.963934 -245.962296) (xy 119.990237 -245.9207) (xy 120.022872 -245.883863)
			(xy 120.060993 -245.852738) (xy 120.103614 -245.828131) (xy 120.14963 -245.810679) (xy 120.197849 -245.800835)
			(xy 120.247024 -245.798854) (xy 120.295879 -245.804786) (xy 120.34315 -245.818478) (xy 120.387612 -245.839576)
			(xy 120.428115 -245.867532) (xy 120.463608 -245.901624) (xy 120.493173 -245.940968) (xy 120.516044 -245.984545)
			(xy 120.531628 -246.031226) (xy 120.539523 -246.079803) (xy 120.540018 -246.10441) (xy 120.86896 -246.10441)
			(xy 120.87292 -246.055356) (xy 120.884697 -246.007572) (xy 120.903988 -245.962296) (xy 120.930291 -245.9207)
			(xy 120.962926 -245.883863) (xy 121.001047 -245.852738) (xy 121.043668 -245.828131) (xy 121.089684 -245.810679)
			(xy 121.137903 -245.800835) (xy 121.187078 -245.798854) (xy 121.235933 -245.804786) (xy 121.283204 -245.818478)
			(xy 121.327666 -245.839576) (xy 121.368169 -245.867532) (xy 121.403662 -245.901624) (xy 121.433227 -245.940968)
			(xy 121.456098 -245.984545) (xy 121.471682 -246.031226) (xy 121.479577 -246.079803) (xy 121.480072 -246.10441)
			(xy 121.809014 -246.10441) (xy 121.812974 -246.055356) (xy 121.824751 -246.007572) (xy 121.844042 -245.962296)
			(xy 121.870345 -245.9207) (xy 121.90298 -245.883863) (xy 121.941101 -245.852738) (xy 121.983722 -245.828131)
			(xy 122.029738 -245.810679) (xy 122.077957 -245.800835) (xy 122.127132 -245.798854) (xy 122.175987 -245.804786)
			(xy 122.223258 -245.818478) (xy 122.26772 -245.839576) (xy 122.308223 -245.867532) (xy 122.343716 -245.901624)
			(xy 122.373281 -245.940968) (xy 122.396152 -245.984545) (xy 122.411736 -246.031226) (xy 122.419631 -246.079803)
			(xy 122.420126 -246.10441) (xy 122.748814 -246.10441) (xy 122.752774 -246.055356) (xy 122.764551 -246.007572)
			(xy 122.783842 -245.962296) (xy 122.810145 -245.9207) (xy 122.84278 -245.883863) (xy 122.880901 -245.852738)
			(xy 122.923522 -245.828131) (xy 122.969538 -245.810679) (xy 123.017757 -245.800835) (xy 123.066932 -245.798854)
			(xy 123.115787 -245.804786) (xy 123.163058 -245.818478) (xy 123.20752 -245.839576) (xy 123.248023 -245.867532)
			(xy 123.283516 -245.901624) (xy 123.313081 -245.940968) (xy 123.335952 -245.984545) (xy 123.351536 -246.031226)
			(xy 123.359431 -246.079803) (xy 123.359926 -246.10441) (xy 123.688868 -246.10441) (xy 123.692828 -246.055356)
			(xy 123.704605 -246.007572) (xy 123.723896 -245.962296) (xy 123.750199 -245.9207) (xy 123.782834 -245.883863)
			(xy 123.820955 -245.852738) (xy 123.863576 -245.828131) (xy 123.909592 -245.810679) (xy 123.957811 -245.800835)
			(xy 124.006986 -245.798854) (xy 124.055841 -245.804786) (xy 124.103112 -245.818478) (xy 124.147574 -245.839576)
			(xy 124.188077 -245.867532) (xy 124.22357 -245.901624) (xy 124.253135 -245.940968) (xy 124.276006 -245.984545)
			(xy 124.29159 -246.031226) (xy 124.299485 -246.079803) (xy 124.29998 -246.10441) (xy 124.628922 -246.10441)
			(xy 124.632882 -246.055356) (xy 124.644659 -246.007572) (xy 124.66395 -245.962296) (xy 124.690253 -245.9207)
			(xy 124.722888 -245.883863) (xy 124.761009 -245.852738) (xy 124.80363 -245.828131) (xy 124.849646 -245.810679)
			(xy 124.897865 -245.800835) (xy 124.94704 -245.798854) (xy 124.995895 -245.804786) (xy 125.043166 -245.818478)
			(xy 125.087628 -245.839576) (xy 125.128131 -245.867532) (xy 125.163624 -245.901624) (xy 125.193189 -245.940968)
			(xy 125.21606 -245.984545) (xy 125.231644 -246.031226) (xy 125.239539 -246.079803) (xy 125.240034 -246.10441)
			(xy 125.568976 -246.10441) (xy 125.572936 -246.055356) (xy 125.584713 -246.007572) (xy 125.604004 -245.962296)
			(xy 125.630307 -245.9207) (xy 125.662942 -245.883863) (xy 125.701063 -245.852738) (xy 125.743684 -245.828131)
			(xy 125.7897 -245.810679) (xy 125.837919 -245.800835) (xy 125.887094 -245.798854) (xy 125.935949 -245.804786)
			(xy 125.98322 -245.818478) (xy 126.027682 -245.839576) (xy 126.068185 -245.867532) (xy 126.103678 -245.901624)
			(xy 126.133243 -245.940968) (xy 126.156114 -245.984545) (xy 126.171698 -246.031226) (xy 126.179593 -246.079803)
			(xy 126.180088 -246.10441) (xy 126.179593 -246.129017) (xy 126.171698 -246.177594) (xy 126.156114 -246.224275)
			(xy 126.133243 -246.267852) (xy 126.103678 -246.307196) (xy 126.068185 -246.341288) (xy 126.027682 -246.369244)
			(xy 125.98322 -246.390342) (xy 125.935949 -246.404034) (xy 125.887094 -246.409966) (xy 125.837919 -246.407985)
			(xy 125.7897 -246.398141) (xy 125.743684 -246.380689) (xy 125.701063 -246.356082) (xy 125.662942 -246.324957)
			(xy 125.630307 -246.28812) (xy 125.604004 -246.246524) (xy 125.584713 -246.201248) (xy 125.572936 -246.153464)
			(xy 125.568976 -246.10441) (xy 125.240034 -246.10441) (xy 125.239539 -246.129017) (xy 125.231644 -246.177594)
			(xy 125.21606 -246.224275) (xy 125.193189 -246.267852) (xy 125.163624 -246.307196) (xy 125.128131 -246.341288)
			(xy 125.087628 -246.369244) (xy 125.043166 -246.390342) (xy 124.995895 -246.404034) (xy 124.94704 -246.409966)
			(xy 124.897865 -246.407985) (xy 124.849646 -246.398141) (xy 124.80363 -246.380689) (xy 124.761009 -246.356082)
			(xy 124.722888 -246.324957) (xy 124.690253 -246.28812) (xy 124.66395 -246.246524) (xy 124.644659 -246.201248)
			(xy 124.632882 -246.153464) (xy 124.628922 -246.10441) (xy 124.29998 -246.10441) (xy 124.299485 -246.129017)
			(xy 124.29159 -246.177594) (xy 124.276006 -246.224275) (xy 124.253135 -246.267852) (xy 124.22357 -246.307196)
			(xy 124.188077 -246.341288) (xy 124.147574 -246.369244) (xy 124.103112 -246.390342) (xy 124.055841 -246.404034)
			(xy 124.006986 -246.409966) (xy 123.957811 -246.407985) (xy 123.909592 -246.398141) (xy 123.863576 -246.380689)
			(xy 123.820955 -246.356082) (xy 123.782834 -246.324957) (xy 123.750199 -246.28812) (xy 123.723896 -246.246524)
			(xy 123.704605 -246.201248) (xy 123.692828 -246.153464) (xy 123.688868 -246.10441) (xy 123.359926 -246.10441)
			(xy 123.359431 -246.129017) (xy 123.351536 -246.177594) (xy 123.335952 -246.224275) (xy 123.313081 -246.267852)
			(xy 123.283516 -246.307196) (xy 123.248023 -246.341288) (xy 123.20752 -246.369244) (xy 123.163058 -246.390342)
			(xy 123.115787 -246.404034) (xy 123.066932 -246.409966) (xy 123.017757 -246.407985) (xy 122.969538 -246.398141)
			(xy 122.923522 -246.380689) (xy 122.880901 -246.356082) (xy 122.84278 -246.324957) (xy 122.810145 -246.28812)
			(xy 122.783842 -246.246524) (xy 122.764551 -246.201248) (xy 122.752774 -246.153464) (xy 122.748814 -246.10441)
			(xy 122.420126 -246.10441) (xy 122.419631 -246.129017) (xy 122.411736 -246.177594) (xy 122.396152 -246.224275)
			(xy 122.373281 -246.267852) (xy 122.343716 -246.307196) (xy 122.308223 -246.341288) (xy 122.26772 -246.369244)
			(xy 122.223258 -246.390342) (xy 122.175987 -246.404034) (xy 122.127132 -246.409966) (xy 122.077957 -246.407985)
			(xy 122.029738 -246.398141) (xy 121.983722 -246.380689) (xy 121.941101 -246.356082) (xy 121.90298 -246.324957)
			(xy 121.870345 -246.28812) (xy 121.844042 -246.246524) (xy 121.824751 -246.201248) (xy 121.812974 -246.153464)
			(xy 121.809014 -246.10441) (xy 121.480072 -246.10441) (xy 121.479577 -246.129017) (xy 121.471682 -246.177594)
			(xy 121.456098 -246.224275) (xy 121.433227 -246.267852) (xy 121.403662 -246.307196) (xy 121.368169 -246.341288)
			(xy 121.327666 -246.369244) (xy 121.283204 -246.390342) (xy 121.235933 -246.404034) (xy 121.187078 -246.409966)
			(xy 121.137903 -246.407985) (xy 121.089684 -246.398141) (xy 121.043668 -246.380689) (xy 121.001047 -246.356082)
			(xy 120.962926 -246.324957) (xy 120.930291 -246.28812) (xy 120.903988 -246.246524) (xy 120.884697 -246.201248)
			(xy 120.87292 -246.153464) (xy 120.86896 -246.10441) (xy 120.540018 -246.10441) (xy 120.539523 -246.129017)
			(xy 120.531628 -246.177594) (xy 120.516044 -246.224275) (xy 120.493173 -246.267852) (xy 120.463608 -246.307196)
			(xy 120.428115 -246.341288) (xy 120.387612 -246.369244) (xy 120.34315 -246.390342) (xy 120.295879 -246.404034)
			(xy 120.247024 -246.409966) (xy 120.197849 -246.407985) (xy 120.14963 -246.398141) (xy 120.103614 -246.380689)
			(xy 120.060993 -246.356082) (xy 120.022872 -246.324957) (xy 119.990237 -246.28812) (xy 119.963934 -246.246524)
			(xy 119.944643 -246.201248) (xy 119.932866 -246.153464) (xy 119.928906 -246.10441) (xy 119.599964 -246.10441)
			(xy 119.599469 -246.129017) (xy 119.591574 -246.177594) (xy 119.57599 -246.224275) (xy 119.553119 -246.267852)
			(xy 119.523554 -246.307196) (xy 119.488061 -246.341288) (xy 119.447558 -246.369244) (xy 119.403096 -246.390342)
			(xy 119.355825 -246.404034) (xy 119.30697 -246.409966) (xy 119.257795 -246.407985) (xy 119.209576 -246.398141)
			(xy 119.16356 -246.380689) (xy 119.120939 -246.356082) (xy 119.082818 -246.324957) (xy 119.050183 -246.28812)
			(xy 119.02388 -246.246524) (xy 119.004589 -246.201248) (xy 118.992812 -246.153464) (xy 118.988852 -246.10441)
			(xy 118.660164 -246.10441) (xy 118.659669 -246.129017) (xy 118.651774 -246.177594) (xy 118.63619 -246.224275)
			(xy 118.613319 -246.267852) (xy 118.583754 -246.307196) (xy 118.548261 -246.341288) (xy 118.507758 -246.369244)
			(xy 118.463296 -246.390342) (xy 118.416025 -246.404034) (xy 118.36717 -246.409966) (xy 118.317995 -246.407985)
			(xy 118.269776 -246.398141) (xy 118.22376 -246.380689) (xy 118.181139 -246.356082) (xy 118.143018 -246.324957)
			(xy 118.110383 -246.28812) (xy 118.08408 -246.246524) (xy 118.064789 -246.201248) (xy 118.053012 -246.153464)
			(xy 118.049052 -246.10441) (xy 117.72011 -246.10441) (xy 117.719615 -246.129017) (xy 117.71172 -246.177594)
			(xy 117.696136 -246.224275) (xy 117.673265 -246.267852) (xy 117.6437 -246.307196) (xy 117.608207 -246.341288)
			(xy 117.567704 -246.369244) (xy 117.523242 -246.390342) (xy 117.475971 -246.404034) (xy 117.427116 -246.409966)
			(xy 117.377941 -246.407985) (xy 117.329722 -246.398141) (xy 117.283706 -246.380689) (xy 117.241085 -246.356082)
			(xy 117.202964 -246.324957) (xy 117.170329 -246.28812) (xy 117.144026 -246.246524) (xy 117.124735 -246.201248)
			(xy 117.112958 -246.153464) (xy 117.108998 -246.10441) (xy 116.780056 -246.10441) (xy 116.779561 -246.129017)
			(xy 116.771666 -246.177594) (xy 116.756082 -246.224275) (xy 116.733211 -246.267852) (xy 116.703646 -246.307196)
			(xy 116.668153 -246.341288) (xy 116.62765 -246.369244) (xy 116.583188 -246.390342) (xy 116.535917 -246.404034)
			(xy 116.487062 -246.409966) (xy 116.437887 -246.407985) (xy 116.389668 -246.398141) (xy 116.343652 -246.380689)
			(xy 116.301031 -246.356082) (xy 116.26291 -246.324957) (xy 116.230275 -246.28812) (xy 116.203972 -246.246524)
			(xy 116.184681 -246.201248) (xy 116.172904 -246.153464) (xy 116.168944 -246.10441) (xy 115.840002 -246.10441)
			(xy 115.839507 -246.129017) (xy 115.831612 -246.177594) (xy 115.816028 -246.224275) (xy 115.793157 -246.267852)
			(xy 115.763592 -246.307196) (xy 115.728099 -246.341288) (xy 115.687596 -246.369244) (xy 115.643134 -246.390342)
			(xy 115.595863 -246.404034) (xy 115.547008 -246.409966) (xy 115.497833 -246.407985) (xy 115.449614 -246.398141)
			(xy 115.403598 -246.380689) (xy 115.360977 -246.356082) (xy 115.322856 -246.324957) (xy 115.290221 -246.28812)
			(xy 115.263918 -246.246524) (xy 115.244627 -246.201248) (xy 115.23285 -246.153464) (xy 115.22889 -246.10441)
			(xy 111.74857 -246.10441) (xy 110.938564 -246.914416) (xy 112.878882 -246.914416) (xy 112.882842 -246.865362)
			(xy 112.894619 -246.817578) (xy 112.91391 -246.772302) (xy 112.940213 -246.730706) (xy 112.972848 -246.693869)
			(xy 113.010969 -246.662744) (xy 113.05359 -246.638137) (xy 113.099606 -246.620685) (xy 113.147825 -246.610841)
			(xy 113.197 -246.60886) (xy 113.245855 -246.614792) (xy 113.293126 -246.628484) (xy 113.337588 -246.649582)
			(xy 113.378091 -246.677538) (xy 113.413584 -246.71163) (xy 113.443149 -246.750974) (xy 113.46602 -246.794551)
			(xy 113.481604 -246.841232) (xy 113.489499 -246.889809) (xy 113.489994 -246.914416) (xy 113.818936 -246.914416)
			(xy 113.822896 -246.865362) (xy 113.834673 -246.817578) (xy 113.853964 -246.772302) (xy 113.880267 -246.730706)
			(xy 113.912902 -246.693869) (xy 113.951023 -246.662744) (xy 113.993644 -246.638137) (xy 114.03966 -246.620685)
			(xy 114.087879 -246.610841) (xy 114.137054 -246.60886) (xy 114.185909 -246.614792) (xy 114.23318 -246.628484)
			(xy 114.277642 -246.649582) (xy 114.318145 -246.677538) (xy 114.353638 -246.71163) (xy 114.383203 -246.750974)
			(xy 114.406074 -246.794551) (xy 114.421658 -246.841232) (xy 114.429553 -246.889809) (xy 114.430048 -246.914416)
			(xy 114.75899 -246.914416) (xy 114.76295 -246.865362) (xy 114.774727 -246.817578) (xy 114.794018 -246.772302)
			(xy 114.820321 -246.730706) (xy 114.852956 -246.693869) (xy 114.891077 -246.662744) (xy 114.933698 -246.638137)
			(xy 114.979714 -246.620685) (xy 115.027933 -246.610841) (xy 115.077108 -246.60886) (xy 115.125963 -246.614792)
			(xy 115.173234 -246.628484) (xy 115.217696 -246.649582) (xy 115.258199 -246.677538) (xy 115.293692 -246.71163)
			(xy 115.323257 -246.750974) (xy 115.346128 -246.794551) (xy 115.361712 -246.841232) (xy 115.369607 -246.889809)
			(xy 115.370102 -246.914416) (xy 115.699044 -246.914416) (xy 115.703004 -246.865362) (xy 115.714781 -246.817578)
			(xy 115.734072 -246.772302) (xy 115.760375 -246.730706) (xy 115.79301 -246.693869) (xy 115.831131 -246.662744)
			(xy 115.873752 -246.638137) (xy 115.919768 -246.620685) (xy 115.967987 -246.610841) (xy 116.017162 -246.60886)
			(xy 116.066017 -246.614792) (xy 116.113288 -246.628484) (xy 116.15775 -246.649582) (xy 116.198253 -246.677538)
			(xy 116.233746 -246.71163) (xy 116.263311 -246.750974) (xy 116.286182 -246.794551) (xy 116.301766 -246.841232)
			(xy 116.309661 -246.889809) (xy 116.310156 -246.914416) (xy 116.638844 -246.914416) (xy 116.642804 -246.865362)
			(xy 116.654581 -246.817578) (xy 116.673872 -246.772302) (xy 116.700175 -246.730706) (xy 116.73281 -246.693869)
			(xy 116.770931 -246.662744) (xy 116.813552 -246.638137) (xy 116.859568 -246.620685) (xy 116.907787 -246.610841)
			(xy 116.956962 -246.60886) (xy 117.005817 -246.614792) (xy 117.053088 -246.628484) (xy 117.09755 -246.649582)
			(xy 117.138053 -246.677538) (xy 117.173546 -246.71163) (xy 117.203111 -246.750974) (xy 117.225982 -246.794551)
			(xy 117.241566 -246.841232) (xy 117.249461 -246.889809) (xy 117.249956 -246.914416) (xy 117.578898 -246.914416)
			(xy 117.582858 -246.865362) (xy 117.594635 -246.817578) (xy 117.613926 -246.772302) (xy 117.640229 -246.730706)
			(xy 117.672864 -246.693869) (xy 117.710985 -246.662744) (xy 117.753606 -246.638137) (xy 117.799622 -246.620685)
			(xy 117.847841 -246.610841) (xy 117.897016 -246.60886) (xy 117.945871 -246.614792) (xy 117.993142 -246.628484)
			(xy 118.037604 -246.649582) (xy 118.078107 -246.677538) (xy 118.1136 -246.71163) (xy 118.143165 -246.750974)
			(xy 118.166036 -246.794551) (xy 118.18162 -246.841232) (xy 118.189515 -246.889809) (xy 118.19001 -246.914416)
			(xy 118.518952 -246.914416) (xy 118.522912 -246.865362) (xy 118.534689 -246.817578) (xy 118.55398 -246.772302)
			(xy 118.580283 -246.730706) (xy 118.612918 -246.693869) (xy 118.651039 -246.662744) (xy 118.69366 -246.638137)
			(xy 118.739676 -246.620685) (xy 118.787895 -246.610841) (xy 118.83707 -246.60886) (xy 118.885925 -246.614792)
			(xy 118.933196 -246.628484) (xy 118.977658 -246.649582) (xy 119.018161 -246.677538) (xy 119.053654 -246.71163)
			(xy 119.083219 -246.750974) (xy 119.10609 -246.794551) (xy 119.121674 -246.841232) (xy 119.129569 -246.889809)
			(xy 119.130064 -246.914416) (xy 119.459006 -246.914416) (xy 119.462966 -246.865362) (xy 119.474743 -246.817578)
			(xy 119.494034 -246.772302) (xy 119.520337 -246.730706) (xy 119.552972 -246.693869) (xy 119.591093 -246.662744)
			(xy 119.633714 -246.638137) (xy 119.67973 -246.620685) (xy 119.727949 -246.610841) (xy 119.777124 -246.60886)
			(xy 119.825979 -246.614792) (xy 119.87325 -246.628484) (xy 119.917712 -246.649582) (xy 119.958215 -246.677538)
			(xy 119.993708 -246.71163) (xy 120.023273 -246.750974) (xy 120.046144 -246.794551) (xy 120.061728 -246.841232)
			(xy 120.069623 -246.889809) (xy 120.070118 -246.914416) (xy 120.398806 -246.914416) (xy 120.402766 -246.865362)
			(xy 120.414543 -246.817578) (xy 120.433834 -246.772302) (xy 120.460137 -246.730706) (xy 120.492772 -246.693869)
			(xy 120.530893 -246.662744) (xy 120.573514 -246.638137) (xy 120.61953 -246.620685) (xy 120.667749 -246.610841)
			(xy 120.716924 -246.60886) (xy 120.765779 -246.614792) (xy 120.81305 -246.628484) (xy 120.857512 -246.649582)
			(xy 120.898015 -246.677538) (xy 120.933508 -246.71163) (xy 120.963073 -246.750974) (xy 120.985944 -246.794551)
			(xy 121.001528 -246.841232) (xy 121.009423 -246.889809) (xy 121.009918 -246.914416) (xy 121.33886 -246.914416)
			(xy 121.34282 -246.865362) (xy 121.354597 -246.817578) (xy 121.373888 -246.772302) (xy 121.400191 -246.730706)
			(xy 121.432826 -246.693869) (xy 121.470947 -246.662744) (xy 121.513568 -246.638137) (xy 121.559584 -246.620685)
			(xy 121.607803 -246.610841) (xy 121.656978 -246.60886) (xy 121.705833 -246.614792) (xy 121.753104 -246.628484)
			(xy 121.797566 -246.649582) (xy 121.838069 -246.677538) (xy 121.873562 -246.71163) (xy 121.903127 -246.750974)
			(xy 121.925998 -246.794551) (xy 121.941582 -246.841232) (xy 121.949477 -246.889809) (xy 121.949972 -246.914416)
			(xy 122.278914 -246.914416) (xy 122.282874 -246.865362) (xy 122.294651 -246.817578) (xy 122.313942 -246.772302)
			(xy 122.340245 -246.730706) (xy 122.37288 -246.693869) (xy 122.411001 -246.662744) (xy 122.453622 -246.638137)
			(xy 122.499638 -246.620685) (xy 122.547857 -246.610841) (xy 122.597032 -246.60886) (xy 122.645887 -246.614792)
			(xy 122.693158 -246.628484) (xy 122.73762 -246.649582) (xy 122.778123 -246.677538) (xy 122.813616 -246.71163)
			(xy 122.843181 -246.750974) (xy 122.866052 -246.794551) (xy 122.881636 -246.841232) (xy 122.889531 -246.889809)
			(xy 122.890026 -246.914416) (xy 123.218968 -246.914416) (xy 123.222928 -246.865362) (xy 123.234705 -246.817578)
			(xy 123.253996 -246.772302) (xy 123.280299 -246.730706) (xy 123.312934 -246.693869) (xy 123.351055 -246.662744)
			(xy 123.393676 -246.638137) (xy 123.439692 -246.620685) (xy 123.487911 -246.610841) (xy 123.537086 -246.60886)
			(xy 123.585941 -246.614792) (xy 123.633212 -246.628484) (xy 123.677674 -246.649582) (xy 123.718177 -246.677538)
			(xy 123.75367 -246.71163) (xy 123.783235 -246.750974) (xy 123.806106 -246.794551) (xy 123.82169 -246.841232)
			(xy 123.829585 -246.889809) (xy 123.83008 -246.914416) (xy 124.159022 -246.914416) (xy 124.162982 -246.865362)
			(xy 124.174759 -246.817578) (xy 124.19405 -246.772302) (xy 124.220353 -246.730706) (xy 124.252988 -246.693869)
			(xy 124.291109 -246.662744) (xy 124.33373 -246.638137) (xy 124.379746 -246.620685) (xy 124.427965 -246.610841)
			(xy 124.47714 -246.60886) (xy 124.525995 -246.614792) (xy 124.573266 -246.628484) (xy 124.617728 -246.649582)
			(xy 124.658231 -246.677538) (xy 124.693724 -246.71163) (xy 124.723289 -246.750974) (xy 124.74616 -246.794551)
			(xy 124.761744 -246.841232) (xy 124.769639 -246.889809) (xy 124.770134 -246.914416) (xy 125.098822 -246.914416)
			(xy 125.102782 -246.865362) (xy 125.114559 -246.817578) (xy 125.13385 -246.772302) (xy 125.160153 -246.730706)
			(xy 125.192788 -246.693869) (xy 125.230909 -246.662744) (xy 125.27353 -246.638137) (xy 125.319546 -246.620685)
			(xy 125.367765 -246.610841) (xy 125.41694 -246.60886) (xy 125.465795 -246.614792) (xy 125.513066 -246.628484)
			(xy 125.557528 -246.649582) (xy 125.598031 -246.677538) (xy 125.633524 -246.71163) (xy 125.663089 -246.750974)
			(xy 125.68596 -246.794551) (xy 125.701544 -246.841232) (xy 125.709439 -246.889809) (xy 125.709934 -246.914416)
			(xy 125.709439 -246.939023) (xy 125.701544 -246.9876) (xy 125.68596 -247.034281) (xy 125.663089 -247.077858)
			(xy 125.633524 -247.117202) (xy 125.598031 -247.151294) (xy 125.557528 -247.17925) (xy 125.513066 -247.200348)
			(xy 125.465795 -247.21404) (xy 125.41694 -247.219972) (xy 125.367765 -247.217991) (xy 125.319546 -247.208147)
			(xy 125.27353 -247.190695) (xy 125.230909 -247.166088) (xy 125.192788 -247.134963) (xy 125.160153 -247.098126)
			(xy 125.13385 -247.05653) (xy 125.114559 -247.011254) (xy 125.102782 -246.96347) (xy 125.098822 -246.914416)
			(xy 124.770134 -246.914416) (xy 124.769639 -246.939023) (xy 124.761744 -246.9876) (xy 124.74616 -247.034281)
			(xy 124.723289 -247.077858) (xy 124.693724 -247.117202) (xy 124.658231 -247.151294) (xy 124.617728 -247.17925)
			(xy 124.573266 -247.200348) (xy 124.525995 -247.21404) (xy 124.47714 -247.219972) (xy 124.427965 -247.217991)
			(xy 124.379746 -247.208147) (xy 124.33373 -247.190695) (xy 124.291109 -247.166088) (xy 124.252988 -247.134963)
			(xy 124.220353 -247.098126) (xy 124.19405 -247.05653) (xy 124.174759 -247.011254) (xy 124.162982 -246.96347)
			(xy 124.159022 -246.914416) (xy 123.83008 -246.914416) (xy 123.829585 -246.939023) (xy 123.82169 -246.9876)
			(xy 123.806106 -247.034281) (xy 123.783235 -247.077858) (xy 123.75367 -247.117202) (xy 123.718177 -247.151294)
			(xy 123.677674 -247.17925) (xy 123.633212 -247.200348) (xy 123.585941 -247.21404) (xy 123.537086 -247.219972)
			(xy 123.487911 -247.217991) (xy 123.439692 -247.208147) (xy 123.393676 -247.190695) (xy 123.351055 -247.166088)
			(xy 123.312934 -247.134963) (xy 123.280299 -247.098126) (xy 123.253996 -247.05653) (xy 123.234705 -247.011254)
			(xy 123.222928 -246.96347) (xy 123.218968 -246.914416) (xy 122.890026 -246.914416) (xy 122.889531 -246.939023)
			(xy 122.881636 -246.9876) (xy 122.866052 -247.034281) (xy 122.843181 -247.077858) (xy 122.813616 -247.117202)
			(xy 122.778123 -247.151294) (xy 122.73762 -247.17925) (xy 122.693158 -247.200348) (xy 122.645887 -247.21404)
			(xy 122.597032 -247.219972) (xy 122.547857 -247.217991) (xy 122.499638 -247.208147) (xy 122.453622 -247.190695)
			(xy 122.411001 -247.166088) (xy 122.37288 -247.134963) (xy 122.340245 -247.098126) (xy 122.313942 -247.05653)
			(xy 122.294651 -247.011254) (xy 122.282874 -246.96347) (xy 122.278914 -246.914416) (xy 121.949972 -246.914416)
			(xy 121.949477 -246.939023) (xy 121.941582 -246.9876) (xy 121.925998 -247.034281) (xy 121.903127 -247.077858)
			(xy 121.873562 -247.117202) (xy 121.838069 -247.151294) (xy 121.797566 -247.17925) (xy 121.753104 -247.200348)
			(xy 121.705833 -247.21404) (xy 121.656978 -247.219972) (xy 121.607803 -247.217991) (xy 121.559584 -247.208147)
			(xy 121.513568 -247.190695) (xy 121.470947 -247.166088) (xy 121.432826 -247.134963) (xy 121.400191 -247.098126)
			(xy 121.373888 -247.05653) (xy 121.354597 -247.011254) (xy 121.34282 -246.96347) (xy 121.33886 -246.914416)
			(xy 121.009918 -246.914416) (xy 121.009423 -246.939023) (xy 121.001528 -246.9876) (xy 120.985944 -247.034281)
			(xy 120.963073 -247.077858) (xy 120.933508 -247.117202) (xy 120.898015 -247.151294) (xy 120.857512 -247.17925)
			(xy 120.81305 -247.200348) (xy 120.765779 -247.21404) (xy 120.716924 -247.219972) (xy 120.667749 -247.217991)
			(xy 120.61953 -247.208147) (xy 120.573514 -247.190695) (xy 120.530893 -247.166088) (xy 120.492772 -247.134963)
			(xy 120.460137 -247.098126) (xy 120.433834 -247.05653) (xy 120.414543 -247.011254) (xy 120.402766 -246.96347)
			(xy 120.398806 -246.914416) (xy 120.070118 -246.914416) (xy 120.069623 -246.939023) (xy 120.061728 -246.9876)
			(xy 120.046144 -247.034281) (xy 120.023273 -247.077858) (xy 119.993708 -247.117202) (xy 119.958215 -247.151294)
			(xy 119.917712 -247.17925) (xy 119.87325 -247.200348) (xy 119.825979 -247.21404) (xy 119.777124 -247.219972)
			(xy 119.727949 -247.217991) (xy 119.67973 -247.208147) (xy 119.633714 -247.190695) (xy 119.591093 -247.166088)
			(xy 119.552972 -247.134963) (xy 119.520337 -247.098126) (xy 119.494034 -247.05653) (xy 119.474743 -247.011254)
			(xy 119.462966 -246.96347) (xy 119.459006 -246.914416) (xy 119.130064 -246.914416) (xy 119.129569 -246.939023)
			(xy 119.121674 -246.9876) (xy 119.10609 -247.034281) (xy 119.083219 -247.077858) (xy 119.053654 -247.117202)
			(xy 119.018161 -247.151294) (xy 118.977658 -247.17925) (xy 118.933196 -247.200348) (xy 118.885925 -247.21404)
			(xy 118.83707 -247.219972) (xy 118.787895 -247.217991) (xy 118.739676 -247.208147) (xy 118.69366 -247.190695)
			(xy 118.651039 -247.166088) (xy 118.612918 -247.134963) (xy 118.580283 -247.098126) (xy 118.55398 -247.05653)
			(xy 118.534689 -247.011254) (xy 118.522912 -246.96347) (xy 118.518952 -246.914416) (xy 118.19001 -246.914416)
			(xy 118.189515 -246.939023) (xy 118.18162 -246.9876) (xy 118.166036 -247.034281) (xy 118.143165 -247.077858)
			(xy 118.1136 -247.117202) (xy 118.078107 -247.151294) (xy 118.037604 -247.17925) (xy 117.993142 -247.200348)
			(xy 117.945871 -247.21404) (xy 117.897016 -247.219972) (xy 117.847841 -247.217991) (xy 117.799622 -247.208147)
			(xy 117.753606 -247.190695) (xy 117.710985 -247.166088) (xy 117.672864 -247.134963) (xy 117.640229 -247.098126)
			(xy 117.613926 -247.05653) (xy 117.594635 -247.011254) (xy 117.582858 -246.96347) (xy 117.578898 -246.914416)
			(xy 117.249956 -246.914416) (xy 117.249461 -246.939023) (xy 117.241566 -246.9876) (xy 117.225982 -247.034281)
			(xy 117.203111 -247.077858) (xy 117.173546 -247.117202) (xy 117.138053 -247.151294) (xy 117.09755 -247.17925)
			(xy 117.053088 -247.200348) (xy 117.005817 -247.21404) (xy 116.956962 -247.219972) (xy 116.907787 -247.217991)
			(xy 116.859568 -247.208147) (xy 116.813552 -247.190695) (xy 116.770931 -247.166088) (xy 116.73281 -247.134963)
			(xy 116.700175 -247.098126) (xy 116.673872 -247.05653) (xy 116.654581 -247.011254) (xy 116.642804 -246.96347)
			(xy 116.638844 -246.914416) (xy 116.310156 -246.914416) (xy 116.309661 -246.939023) (xy 116.301766 -246.9876)
			(xy 116.286182 -247.034281) (xy 116.263311 -247.077858) (xy 116.233746 -247.117202) (xy 116.198253 -247.151294)
			(xy 116.15775 -247.17925) (xy 116.113288 -247.200348) (xy 116.066017 -247.21404) (xy 116.017162 -247.219972)
			(xy 115.967987 -247.217991) (xy 115.919768 -247.208147) (xy 115.873752 -247.190695) (xy 115.831131 -247.166088)
			(xy 115.79301 -247.134963) (xy 115.760375 -247.098126) (xy 115.734072 -247.05653) (xy 115.714781 -247.011254)
			(xy 115.703004 -246.96347) (xy 115.699044 -246.914416) (xy 115.370102 -246.914416) (xy 115.369607 -246.939023)
			(xy 115.361712 -246.9876) (xy 115.346128 -247.034281) (xy 115.323257 -247.077858) (xy 115.293692 -247.117202)
			(xy 115.258199 -247.151294) (xy 115.217696 -247.17925) (xy 115.173234 -247.200348) (xy 115.125963 -247.21404)
			(xy 115.077108 -247.219972) (xy 115.027933 -247.217991) (xy 114.979714 -247.208147) (xy 114.933698 -247.190695)
			(xy 114.891077 -247.166088) (xy 114.852956 -247.134963) (xy 114.820321 -247.098126) (xy 114.794018 -247.05653)
			(xy 114.774727 -247.011254) (xy 114.76295 -246.96347) (xy 114.75899 -246.914416) (xy 114.430048 -246.914416)
			(xy 114.429553 -246.939023) (xy 114.421658 -246.9876) (xy 114.406074 -247.034281) (xy 114.383203 -247.077858)
			(xy 114.353638 -247.117202) (xy 114.318145 -247.151294) (xy 114.277642 -247.17925) (xy 114.23318 -247.200348)
			(xy 114.185909 -247.21404) (xy 114.137054 -247.219972) (xy 114.087879 -247.217991) (xy 114.03966 -247.208147)
			(xy 113.993644 -247.190695) (xy 113.951023 -247.166088) (xy 113.912902 -247.134963) (xy 113.880267 -247.098126)
			(xy 113.853964 -247.05653) (xy 113.834673 -247.011254) (xy 113.822896 -246.96347) (xy 113.818936 -246.914416)
			(xy 113.489994 -246.914416) (xy 113.489499 -246.939023) (xy 113.481604 -246.9876) (xy 113.46602 -247.034281)
			(xy 113.443149 -247.077858) (xy 113.413584 -247.117202) (xy 113.378091 -247.151294) (xy 113.337588 -247.17925)
			(xy 113.293126 -247.200348) (xy 113.245855 -247.21404) (xy 113.197 -247.219972) (xy 113.147825 -247.217991)
			(xy 113.099606 -247.208147) (xy 113.05359 -247.190695) (xy 113.010969 -247.166088) (xy 112.972848 -247.134963)
			(xy 112.940213 -247.098126) (xy 112.91391 -247.05653) (xy 112.894619 -247.011254) (xy 112.882842 -246.96347)
			(xy 112.878882 -246.914416) (xy 110.938564 -246.914416) (xy 110.936786 -246.916194) (xy 110.929929 -246.923588)
			(xy 110.922179 -246.942187) (xy 110.9218 -246.952262) (xy 110.9218 -247.457214) (xy 111.456473 -247.457214)
			(xy 111.460503 -247.404716) (xy 111.4725 -247.353448) (xy 111.492183 -247.304613) (xy 111.519089 -247.259354)
			(xy 111.552589 -247.218733) (xy 111.591897 -247.183702) (xy 111.636092 -247.155082) (xy 111.684137 -247.133543)
			(xy 111.734908 -247.119591) (xy 111.787213 -247.113553) (xy 111.839827 -247.11557) (xy 111.891517 -247.125594)
			(xy 111.94107 -247.143392) (xy 111.987326 -247.168545) (xy 112.0292 -247.200464) (xy 112.065712 -247.238402)
			(xy 112.096004 -247.281468) (xy 112.119367 -247.328653) (xy 112.135253 -247.378852) (xy 112.14329 -247.430888)
			(xy 112.143794 -247.457214) (xy 112.14329 -247.48354) (xy 112.135253 -247.535576) (xy 112.119367 -247.585775)
			(xy 112.096004 -247.63296) (xy 112.065712 -247.676026) (xy 112.0292 -247.713964) (xy 112.01548 -247.724422)
			(xy 113.349036 -247.724422) (xy 113.352996 -247.675368) (xy 113.364773 -247.627584) (xy 113.384064 -247.582308)
			(xy 113.410367 -247.540712) (xy 113.443002 -247.503875) (xy 113.481123 -247.47275) (xy 113.523744 -247.448143)
			(xy 113.56976 -247.430691) (xy 113.617979 -247.420847) (xy 113.667154 -247.418866) (xy 113.716009 -247.424798)
			(xy 113.76328 -247.43849) (xy 113.807742 -247.459588) (xy 113.848245 -247.487544) (xy 113.883738 -247.521636)
			(xy 113.913303 -247.56098) (xy 113.936174 -247.604557) (xy 113.951758 -247.651238) (xy 113.959653 -247.699815)
			(xy 113.960148 -247.724422) (xy 114.288836 -247.724422) (xy 114.292796 -247.675368) (xy 114.304573 -247.627584)
			(xy 114.323864 -247.582308) (xy 114.350167 -247.540712) (xy 114.382802 -247.503875) (xy 114.420923 -247.47275)
			(xy 114.463544 -247.448143) (xy 114.50956 -247.430691) (xy 114.557779 -247.420847) (xy 114.606954 -247.418866)
			(xy 114.655809 -247.424798) (xy 114.70308 -247.43849) (xy 114.747542 -247.459588) (xy 114.788045 -247.487544)
			(xy 114.823538 -247.521636) (xy 114.853103 -247.56098) (xy 114.875974 -247.604557) (xy 114.891558 -247.651238)
			(xy 114.899453 -247.699815) (xy 114.899948 -247.724422) (xy 115.22889 -247.724422) (xy 115.23285 -247.675368)
			(xy 115.244627 -247.627584) (xy 115.263918 -247.582308) (xy 115.290221 -247.540712) (xy 115.322856 -247.503875)
			(xy 115.360977 -247.47275) (xy 115.403598 -247.448143) (xy 115.449614 -247.430691) (xy 115.497833 -247.420847)
			(xy 115.547008 -247.418866) (xy 115.595863 -247.424798) (xy 115.643134 -247.43849) (xy 115.687596 -247.459588)
			(xy 115.728099 -247.487544) (xy 115.763592 -247.521636) (xy 115.793157 -247.56098) (xy 115.816028 -247.604557)
			(xy 115.831612 -247.651238) (xy 115.839507 -247.699815) (xy 115.840002 -247.724422) (xy 116.168944 -247.724422)
			(xy 116.172904 -247.675368) (xy 116.184681 -247.627584) (xy 116.203972 -247.582308) (xy 116.230275 -247.540712)
			(xy 116.26291 -247.503875) (xy 116.301031 -247.47275) (xy 116.343652 -247.448143) (xy 116.389668 -247.430691)
			(xy 116.437887 -247.420847) (xy 116.487062 -247.418866) (xy 116.535917 -247.424798) (xy 116.583188 -247.43849)
			(xy 116.62765 -247.459588) (xy 116.668153 -247.487544) (xy 116.703646 -247.521636) (xy 116.733211 -247.56098)
			(xy 116.756082 -247.604557) (xy 116.771666 -247.651238) (xy 116.779561 -247.699815) (xy 116.780056 -247.724422)
			(xy 117.108998 -247.724422) (xy 117.112958 -247.675368) (xy 117.124735 -247.627584) (xy 117.144026 -247.582308)
			(xy 117.170329 -247.540712) (xy 117.202964 -247.503875) (xy 117.241085 -247.47275) (xy 117.283706 -247.448143)
			(xy 117.329722 -247.430691) (xy 117.377941 -247.420847) (xy 117.427116 -247.418866) (xy 117.475971 -247.424798)
			(xy 117.523242 -247.43849) (xy 117.567704 -247.459588) (xy 117.608207 -247.487544) (xy 117.6437 -247.521636)
			(xy 117.673265 -247.56098) (xy 117.696136 -247.604557) (xy 117.71172 -247.651238) (xy 117.719615 -247.699815)
			(xy 117.72011 -247.724422) (xy 118.049052 -247.724422) (xy 118.053012 -247.675368) (xy 118.064789 -247.627584)
			(xy 118.08408 -247.582308) (xy 118.110383 -247.540712) (xy 118.143018 -247.503875) (xy 118.181139 -247.47275)
			(xy 118.22376 -247.448143) (xy 118.269776 -247.430691) (xy 118.317995 -247.420847) (xy 118.36717 -247.418866)
			(xy 118.416025 -247.424798) (xy 118.463296 -247.43849) (xy 118.507758 -247.459588) (xy 118.548261 -247.487544)
			(xy 118.583754 -247.521636) (xy 118.613319 -247.56098) (xy 118.63619 -247.604557) (xy 118.651774 -247.651238)
			(xy 118.659669 -247.699815) (xy 118.660164 -247.724422) (xy 118.988852 -247.724422) (xy 118.992812 -247.675368)
			(xy 119.004589 -247.627584) (xy 119.02388 -247.582308) (xy 119.050183 -247.540712) (xy 119.082818 -247.503875)
			(xy 119.120939 -247.47275) (xy 119.16356 -247.448143) (xy 119.209576 -247.430691) (xy 119.257795 -247.420847)
			(xy 119.30697 -247.418866) (xy 119.355825 -247.424798) (xy 119.403096 -247.43849) (xy 119.447558 -247.459588)
			(xy 119.488061 -247.487544) (xy 119.523554 -247.521636) (xy 119.553119 -247.56098) (xy 119.57599 -247.604557)
			(xy 119.591574 -247.651238) (xy 119.599469 -247.699815) (xy 119.599964 -247.724422) (xy 119.928906 -247.724422)
			(xy 119.932866 -247.675368) (xy 119.944643 -247.627584) (xy 119.963934 -247.582308) (xy 119.990237 -247.540712)
			(xy 120.022872 -247.503875) (xy 120.060993 -247.47275) (xy 120.103614 -247.448143) (xy 120.14963 -247.430691)
			(xy 120.197849 -247.420847) (xy 120.247024 -247.418866) (xy 120.295879 -247.424798) (xy 120.34315 -247.43849)
			(xy 120.387612 -247.459588) (xy 120.428115 -247.487544) (xy 120.463608 -247.521636) (xy 120.493173 -247.56098)
			(xy 120.516044 -247.604557) (xy 120.531628 -247.651238) (xy 120.539523 -247.699815) (xy 120.540018 -247.724422)
			(xy 120.86896 -247.724422) (xy 120.87292 -247.675368) (xy 120.884697 -247.627584) (xy 120.903988 -247.582308)
			(xy 120.930291 -247.540712) (xy 120.962926 -247.503875) (xy 121.001047 -247.47275) (xy 121.043668 -247.448143)
			(xy 121.089684 -247.430691) (xy 121.137903 -247.420847) (xy 121.187078 -247.418866) (xy 121.235933 -247.424798)
			(xy 121.283204 -247.43849) (xy 121.327666 -247.459588) (xy 121.368169 -247.487544) (xy 121.403662 -247.521636)
			(xy 121.433227 -247.56098) (xy 121.456098 -247.604557) (xy 121.471682 -247.651238) (xy 121.479577 -247.699815)
			(xy 121.480072 -247.724422) (xy 121.809014 -247.724422) (xy 121.812974 -247.675368) (xy 121.824751 -247.627584)
			(xy 121.844042 -247.582308) (xy 121.870345 -247.540712) (xy 121.90298 -247.503875) (xy 121.941101 -247.47275)
			(xy 121.983722 -247.448143) (xy 122.029738 -247.430691) (xy 122.077957 -247.420847) (xy 122.127132 -247.418866)
			(xy 122.175987 -247.424798) (xy 122.223258 -247.43849) (xy 122.26772 -247.459588) (xy 122.308223 -247.487544)
			(xy 122.343716 -247.521636) (xy 122.373281 -247.56098) (xy 122.396152 -247.604557) (xy 122.411736 -247.651238)
			(xy 122.419631 -247.699815) (xy 122.420126 -247.724422) (xy 122.748814 -247.724422) (xy 122.752774 -247.675368)
			(xy 122.764551 -247.627584) (xy 122.783842 -247.582308) (xy 122.810145 -247.540712) (xy 122.84278 -247.503875)
			(xy 122.880901 -247.47275) (xy 122.923522 -247.448143) (xy 122.969538 -247.430691) (xy 123.017757 -247.420847)
			(xy 123.066932 -247.418866) (xy 123.115787 -247.424798) (xy 123.163058 -247.43849) (xy 123.20752 -247.459588)
			(xy 123.248023 -247.487544) (xy 123.283516 -247.521636) (xy 123.313081 -247.56098) (xy 123.335952 -247.604557)
			(xy 123.351536 -247.651238) (xy 123.359431 -247.699815) (xy 123.359926 -247.724422) (xy 123.688868 -247.724422)
			(xy 123.692828 -247.675368) (xy 123.704605 -247.627584) (xy 123.723896 -247.582308) (xy 123.750199 -247.540712)
			(xy 123.782834 -247.503875) (xy 123.820955 -247.47275) (xy 123.863576 -247.448143) (xy 123.909592 -247.430691)
			(xy 123.957811 -247.420847) (xy 124.006986 -247.418866) (xy 124.055841 -247.424798) (xy 124.103112 -247.43849)
			(xy 124.147574 -247.459588) (xy 124.188077 -247.487544) (xy 124.22357 -247.521636) (xy 124.253135 -247.56098)
			(xy 124.276006 -247.604557) (xy 124.29159 -247.651238) (xy 124.299485 -247.699815) (xy 124.29998 -247.724422)
			(xy 124.628922 -247.724422) (xy 124.632882 -247.675368) (xy 124.644659 -247.627584) (xy 124.66395 -247.582308)
			(xy 124.690253 -247.540712) (xy 124.722888 -247.503875) (xy 124.761009 -247.47275) (xy 124.80363 -247.448143)
			(xy 124.849646 -247.430691) (xy 124.897865 -247.420847) (xy 124.94704 -247.418866) (xy 124.995895 -247.424798)
			(xy 125.043166 -247.43849) (xy 125.087628 -247.459588) (xy 125.128131 -247.487544) (xy 125.163624 -247.521636)
			(xy 125.193189 -247.56098) (xy 125.21606 -247.604557) (xy 125.231644 -247.651238) (xy 125.239539 -247.699815)
			(xy 125.240034 -247.724422) (xy 125.568976 -247.724422) (xy 125.572936 -247.675368) (xy 125.584713 -247.627584)
			(xy 125.604004 -247.582308) (xy 125.630307 -247.540712) (xy 125.662942 -247.503875) (xy 125.701063 -247.47275)
			(xy 125.743684 -247.448143) (xy 125.7897 -247.430691) (xy 125.837919 -247.420847) (xy 125.887094 -247.418866)
			(xy 125.935949 -247.424798) (xy 125.98322 -247.43849) (xy 126.027682 -247.459588) (xy 126.068185 -247.487544)
			(xy 126.103678 -247.521636) (xy 126.133243 -247.56098) (xy 126.156114 -247.604557) (xy 126.171698 -247.651238)
			(xy 126.179593 -247.699815) (xy 126.180088 -247.724422) (xy 126.179593 -247.749029) (xy 126.171698 -247.797606)
			(xy 126.156114 -247.844287) (xy 126.133243 -247.887864) (xy 126.103678 -247.927208) (xy 126.068185 -247.9613)
			(xy 126.027682 -247.989256) (xy 125.98322 -248.010354) (xy 125.935949 -248.024046) (xy 125.887094 -248.029978)
			(xy 125.837919 -248.027997) (xy 125.7897 -248.018153) (xy 125.743684 -248.000701) (xy 125.701063 -247.976094)
			(xy 125.662942 -247.944969) (xy 125.630307 -247.908132) (xy 125.604004 -247.866536) (xy 125.584713 -247.82126)
			(xy 125.572936 -247.773476) (xy 125.568976 -247.724422) (xy 125.240034 -247.724422) (xy 125.239539 -247.749029)
			(xy 125.231644 -247.797606) (xy 125.21606 -247.844287) (xy 125.193189 -247.887864) (xy 125.163624 -247.927208)
			(xy 125.128131 -247.9613) (xy 125.087628 -247.989256) (xy 125.043166 -248.010354) (xy 124.995895 -248.024046)
			(xy 124.94704 -248.029978) (xy 124.897865 -248.027997) (xy 124.849646 -248.018153) (xy 124.80363 -248.000701)
			(xy 124.761009 -247.976094) (xy 124.722888 -247.944969) (xy 124.690253 -247.908132) (xy 124.66395 -247.866536)
			(xy 124.644659 -247.82126) (xy 124.632882 -247.773476) (xy 124.628922 -247.724422) (xy 124.29998 -247.724422)
			(xy 124.299485 -247.749029) (xy 124.29159 -247.797606) (xy 124.276006 -247.844287) (xy 124.253135 -247.887864)
			(xy 124.22357 -247.927208) (xy 124.188077 -247.9613) (xy 124.147574 -247.989256) (xy 124.103112 -248.010354)
			(xy 124.055841 -248.024046) (xy 124.006986 -248.029978) (xy 123.957811 -248.027997) (xy 123.909592 -248.018153)
			(xy 123.863576 -248.000701) (xy 123.820955 -247.976094) (xy 123.782834 -247.944969) (xy 123.750199 -247.908132)
			(xy 123.723896 -247.866536) (xy 123.704605 -247.82126) (xy 123.692828 -247.773476) (xy 123.688868 -247.724422)
			(xy 123.359926 -247.724422) (xy 123.359431 -247.749029) (xy 123.351536 -247.797606) (xy 123.335952 -247.844287)
			(xy 123.313081 -247.887864) (xy 123.283516 -247.927208) (xy 123.248023 -247.9613) (xy 123.20752 -247.989256)
			(xy 123.163058 -248.010354) (xy 123.115787 -248.024046) (xy 123.066932 -248.029978) (xy 123.017757 -248.027997)
			(xy 122.969538 -248.018153) (xy 122.923522 -248.000701) (xy 122.880901 -247.976094) (xy 122.84278 -247.944969)
			(xy 122.810145 -247.908132) (xy 122.783842 -247.866536) (xy 122.764551 -247.82126) (xy 122.752774 -247.773476)
			(xy 122.748814 -247.724422) (xy 122.420126 -247.724422) (xy 122.419631 -247.749029) (xy 122.411736 -247.797606)
			(xy 122.396152 -247.844287) (xy 122.373281 -247.887864) (xy 122.343716 -247.927208) (xy 122.308223 -247.9613)
			(xy 122.26772 -247.989256) (xy 122.223258 -248.010354) (xy 122.175987 -248.024046) (xy 122.127132 -248.029978)
			(xy 122.077957 -248.027997) (xy 122.029738 -248.018153) (xy 121.983722 -248.000701) (xy 121.941101 -247.976094)
			(xy 121.90298 -247.944969) (xy 121.870345 -247.908132) (xy 121.844042 -247.866536) (xy 121.824751 -247.82126)
			(xy 121.812974 -247.773476) (xy 121.809014 -247.724422) (xy 121.480072 -247.724422) (xy 121.479577 -247.749029)
			(xy 121.471682 -247.797606) (xy 121.456098 -247.844287) (xy 121.433227 -247.887864) (xy 121.403662 -247.927208)
			(xy 121.368169 -247.9613) (xy 121.327666 -247.989256) (xy 121.283204 -248.010354) (xy 121.235933 -248.024046)
			(xy 121.187078 -248.029978) (xy 121.137903 -248.027997) (xy 121.089684 -248.018153) (xy 121.043668 -248.000701)
			(xy 121.001047 -247.976094) (xy 120.962926 -247.944969) (xy 120.930291 -247.908132) (xy 120.903988 -247.866536)
			(xy 120.884697 -247.82126) (xy 120.87292 -247.773476) (xy 120.86896 -247.724422) (xy 120.540018 -247.724422)
			(xy 120.539523 -247.749029) (xy 120.531628 -247.797606) (xy 120.516044 -247.844287) (xy 120.493173 -247.887864)
			(xy 120.463608 -247.927208) (xy 120.428115 -247.9613) (xy 120.387612 -247.989256) (xy 120.34315 -248.010354)
			(xy 120.295879 -248.024046) (xy 120.247024 -248.029978) (xy 120.197849 -248.027997) (xy 120.14963 -248.018153)
			(xy 120.103614 -248.000701) (xy 120.060993 -247.976094) (xy 120.022872 -247.944969) (xy 119.990237 -247.908132)
			(xy 119.963934 -247.866536) (xy 119.944643 -247.82126) (xy 119.932866 -247.773476) (xy 119.928906 -247.724422)
			(xy 119.599964 -247.724422) (xy 119.599469 -247.749029) (xy 119.591574 -247.797606) (xy 119.57599 -247.844287)
			(xy 119.553119 -247.887864) (xy 119.523554 -247.927208) (xy 119.488061 -247.9613) (xy 119.447558 -247.989256)
			(xy 119.403096 -248.010354) (xy 119.355825 -248.024046) (xy 119.30697 -248.029978) (xy 119.257795 -248.027997)
			(xy 119.209576 -248.018153) (xy 119.16356 -248.000701) (xy 119.120939 -247.976094) (xy 119.082818 -247.944969)
			(xy 119.050183 -247.908132) (xy 119.02388 -247.866536) (xy 119.004589 -247.82126) (xy 118.992812 -247.773476)
			(xy 118.988852 -247.724422) (xy 118.660164 -247.724422) (xy 118.659669 -247.749029) (xy 118.651774 -247.797606)
			(xy 118.63619 -247.844287) (xy 118.613319 -247.887864) (xy 118.583754 -247.927208) (xy 118.548261 -247.9613)
			(xy 118.507758 -247.989256) (xy 118.463296 -248.010354) (xy 118.416025 -248.024046) (xy 118.36717 -248.029978)
			(xy 118.317995 -248.027997) (xy 118.269776 -248.018153) (xy 118.22376 -248.000701) (xy 118.181139 -247.976094)
			(xy 118.143018 -247.944969) (xy 118.110383 -247.908132) (xy 118.08408 -247.866536) (xy 118.064789 -247.82126)
			(xy 118.053012 -247.773476) (xy 118.049052 -247.724422) (xy 117.72011 -247.724422) (xy 117.719615 -247.749029)
			(xy 117.71172 -247.797606) (xy 117.696136 -247.844287) (xy 117.673265 -247.887864) (xy 117.6437 -247.927208)
			(xy 117.608207 -247.9613) (xy 117.567704 -247.989256) (xy 117.523242 -248.010354) (xy 117.475971 -248.024046)
			(xy 117.427116 -248.029978) (xy 117.377941 -248.027997) (xy 117.329722 -248.018153) (xy 117.283706 -248.000701)
			(xy 117.241085 -247.976094) (xy 117.202964 -247.944969) (xy 117.170329 -247.908132) (xy 117.144026 -247.866536)
			(xy 117.124735 -247.82126) (xy 117.112958 -247.773476) (xy 117.108998 -247.724422) (xy 116.780056 -247.724422)
			(xy 116.779561 -247.749029) (xy 116.771666 -247.797606) (xy 116.756082 -247.844287) (xy 116.733211 -247.887864)
			(xy 116.703646 -247.927208) (xy 116.668153 -247.9613) (xy 116.62765 -247.989256) (xy 116.583188 -248.010354)
			(xy 116.535917 -248.024046) (xy 116.487062 -248.029978) (xy 116.437887 -248.027997) (xy 116.389668 -248.018153)
			(xy 116.343652 -248.000701) (xy 116.301031 -247.976094) (xy 116.26291 -247.944969) (xy 116.230275 -247.908132)
			(xy 116.203972 -247.866536) (xy 116.184681 -247.82126) (xy 116.172904 -247.773476) (xy 116.168944 -247.724422)
			(xy 115.840002 -247.724422) (xy 115.839507 -247.749029) (xy 115.831612 -247.797606) (xy 115.816028 -247.844287)
			(xy 115.793157 -247.887864) (xy 115.763592 -247.927208) (xy 115.728099 -247.9613) (xy 115.687596 -247.989256)
			(xy 115.643134 -248.010354) (xy 115.595863 -248.024046) (xy 115.547008 -248.029978) (xy 115.497833 -248.027997)
			(xy 115.449614 -248.018153) (xy 115.403598 -248.000701) (xy 115.360977 -247.976094) (xy 115.322856 -247.944969)
			(xy 115.290221 -247.908132) (xy 115.263918 -247.866536) (xy 115.244627 -247.82126) (xy 115.23285 -247.773476)
			(xy 115.22889 -247.724422) (xy 114.899948 -247.724422) (xy 114.899453 -247.749029) (xy 114.891558 -247.797606)
			(xy 114.875974 -247.844287) (xy 114.853103 -247.887864) (xy 114.823538 -247.927208) (xy 114.788045 -247.9613)
			(xy 114.747542 -247.989256) (xy 114.70308 -248.010354) (xy 114.655809 -248.024046) (xy 114.606954 -248.029978)
			(xy 114.557779 -248.027997) (xy 114.50956 -248.018153) (xy 114.463544 -248.000701) (xy 114.420923 -247.976094)
			(xy 114.382802 -247.944969) (xy 114.350167 -247.908132) (xy 114.323864 -247.866536) (xy 114.304573 -247.82126)
			(xy 114.292796 -247.773476) (xy 114.288836 -247.724422) (xy 113.960148 -247.724422) (xy 113.959653 -247.749029)
			(xy 113.951758 -247.797606) (xy 113.936174 -247.844287) (xy 113.913303 -247.887864) (xy 113.883738 -247.927208)
			(xy 113.848245 -247.9613) (xy 113.807742 -247.989256) (xy 113.76328 -248.010354) (xy 113.716009 -248.024046)
			(xy 113.667154 -248.029978) (xy 113.617979 -248.027997) (xy 113.56976 -248.018153) (xy 113.523744 -248.000701)
			(xy 113.481123 -247.976094) (xy 113.443002 -247.944969) (xy 113.410367 -247.908132) (xy 113.384064 -247.866536)
			(xy 113.364773 -247.82126) (xy 113.352996 -247.773476) (xy 113.349036 -247.724422) (xy 112.01548 -247.724422)
			(xy 111.987326 -247.745883) (xy 111.94107 -247.771036) (xy 111.891517 -247.788834) (xy 111.839827 -247.798858)
			(xy 111.787213 -247.800875) (xy 111.734908 -247.794837) (xy 111.684137 -247.780885) (xy 111.636092 -247.759346)
			(xy 111.591897 -247.730726) (xy 111.552589 -247.695695) (xy 111.519089 -247.655074) (xy 111.492183 -247.609815)
			(xy 111.4725 -247.56098) (xy 111.460503 -247.509712) (xy 111.456473 -247.457214) (xy 110.9218 -247.457214)
			(xy 110.9218 -248.474738) (xy 110.92137 -248.484805) (xy 110.913646 -248.503399) (xy 110.906814 -248.510806)
			(xy 110.883192 -248.534428) (xy 112.878882 -248.534428) (xy 112.882842 -248.485374) (xy 112.894619 -248.43759)
			(xy 112.91391 -248.392314) (xy 112.940213 -248.350718) (xy 112.972848 -248.313881) (xy 113.010969 -248.282756)
			(xy 113.05359 -248.258149) (xy 113.099606 -248.240697) (xy 113.147825 -248.230853) (xy 113.197 -248.228872)
			(xy 113.245855 -248.234804) (xy 113.293126 -248.248496) (xy 113.337588 -248.269594) (xy 113.378091 -248.29755)
			(xy 113.413584 -248.331642) (xy 113.443149 -248.370986) (xy 113.46602 -248.414563) (xy 113.481604 -248.461244)
			(xy 113.489499 -248.509821) (xy 113.489994 -248.534428) (xy 113.818936 -248.534428) (xy 113.822896 -248.485374)
			(xy 113.834673 -248.43759) (xy 113.853964 -248.392314) (xy 113.880267 -248.350718) (xy 113.912902 -248.313881)
			(xy 113.951023 -248.282756) (xy 113.993644 -248.258149) (xy 114.03966 -248.240697) (xy 114.087879 -248.230853)
			(xy 114.137054 -248.228872) (xy 114.185909 -248.234804) (xy 114.23318 -248.248496) (xy 114.277642 -248.269594)
			(xy 114.318145 -248.29755) (xy 114.353638 -248.331642) (xy 114.383203 -248.370986) (xy 114.406074 -248.414563)
			(xy 114.421658 -248.461244) (xy 114.429553 -248.509821) (xy 114.430048 -248.534428) (xy 114.75899 -248.534428)
			(xy 114.76295 -248.485374) (xy 114.774727 -248.43759) (xy 114.794018 -248.392314) (xy 114.820321 -248.350718)
			(xy 114.852956 -248.313881) (xy 114.891077 -248.282756) (xy 114.933698 -248.258149) (xy 114.979714 -248.240697)
			(xy 115.027933 -248.230853) (xy 115.077108 -248.228872) (xy 115.125963 -248.234804) (xy 115.173234 -248.248496)
			(xy 115.217696 -248.269594) (xy 115.258199 -248.29755) (xy 115.293692 -248.331642) (xy 115.323257 -248.370986)
			(xy 115.346128 -248.414563) (xy 115.361712 -248.461244) (xy 115.369607 -248.509821) (xy 115.370102 -248.534428)
			(xy 115.699044 -248.534428) (xy 115.703004 -248.485374) (xy 115.714781 -248.43759) (xy 115.734072 -248.392314)
			(xy 115.760375 -248.350718) (xy 115.79301 -248.313881) (xy 115.831131 -248.282756) (xy 115.873752 -248.258149)
			(xy 115.919768 -248.240697) (xy 115.967987 -248.230853) (xy 116.017162 -248.228872) (xy 116.066017 -248.234804)
			(xy 116.113288 -248.248496) (xy 116.15775 -248.269594) (xy 116.198253 -248.29755) (xy 116.233746 -248.331642)
			(xy 116.263311 -248.370986) (xy 116.286182 -248.414563) (xy 116.301766 -248.461244) (xy 116.309661 -248.509821)
			(xy 116.310156 -248.534428) (xy 118.518952 -248.534428) (xy 118.522912 -248.485374) (xy 118.534689 -248.43759)
			(xy 118.55398 -248.392314) (xy 118.580283 -248.350718) (xy 118.612918 -248.313881) (xy 118.651039 -248.282756)
			(xy 118.69366 -248.258149) (xy 118.739676 -248.240697) (xy 118.787895 -248.230853) (xy 118.83707 -248.228872)
			(xy 118.885925 -248.234804) (xy 118.933196 -248.248496) (xy 118.977658 -248.269594) (xy 119.018161 -248.29755)
			(xy 119.053654 -248.331642) (xy 119.083219 -248.370986) (xy 119.10609 -248.414563) (xy 119.121674 -248.461244)
			(xy 119.129569 -248.509821) (xy 119.130064 -248.534428) (xy 121.33886 -248.534428) (xy 121.34282 -248.485374)
			(xy 121.354597 -248.43759) (xy 121.373888 -248.392314) (xy 121.400191 -248.350718) (xy 121.432826 -248.313881)
			(xy 121.470947 -248.282756) (xy 121.513568 -248.258149) (xy 121.559584 -248.240697) (xy 121.607803 -248.230853)
			(xy 121.656978 -248.228872) (xy 121.705833 -248.234804) (xy 121.753104 -248.248496) (xy 121.797566 -248.269594)
			(xy 121.838069 -248.29755) (xy 121.873562 -248.331642) (xy 121.903127 -248.370986) (xy 121.925998 -248.414563)
			(xy 121.941582 -248.461244) (xy 121.949477 -248.509821) (xy 121.949972 -248.534428) (xy 124.159022 -248.534428)
			(xy 124.162982 -248.485374) (xy 124.174759 -248.43759) (xy 124.19405 -248.392314) (xy 124.220353 -248.350718)
			(xy 124.252988 -248.313881) (xy 124.291109 -248.282756) (xy 124.33373 -248.258149) (xy 124.379746 -248.240697)
			(xy 124.427965 -248.230853) (xy 124.47714 -248.228872) (xy 124.525995 -248.234804) (xy 124.573266 -248.248496)
			(xy 124.617728 -248.269594) (xy 124.658231 -248.29755) (xy 124.693724 -248.331642) (xy 124.723289 -248.370986)
			(xy 124.74616 -248.414563) (xy 124.761744 -248.461244) (xy 124.769639 -248.509821) (xy 124.770134 -248.534428)
			(xy 124.769639 -248.559035) (xy 124.761744 -248.607612) (xy 124.74616 -248.654293) (xy 124.723289 -248.69787)
			(xy 124.693724 -248.737214) (xy 124.658231 -248.771306) (xy 124.617728 -248.799262) (xy 124.573266 -248.82036)
			(xy 124.525995 -248.834052) (xy 124.47714 -248.839984) (xy 124.427965 -248.838003) (xy 124.379746 -248.828159)
			(xy 124.33373 -248.810707) (xy 124.291109 -248.7861) (xy 124.252988 -248.754975) (xy 124.220353 -248.718138)
			(xy 124.19405 -248.676542) (xy 124.174759 -248.631266) (xy 124.162982 -248.583482) (xy 124.159022 -248.534428)
			(xy 121.949972 -248.534428) (xy 121.949477 -248.559035) (xy 121.941582 -248.607612) (xy 121.925998 -248.654293)
			(xy 121.903127 -248.69787) (xy 121.873562 -248.737214) (xy 121.838069 -248.771306) (xy 121.797566 -248.799262)
			(xy 121.753104 -248.82036) (xy 121.705833 -248.834052) (xy 121.656978 -248.839984) (xy 121.607803 -248.838003)
			(xy 121.559584 -248.828159) (xy 121.513568 -248.810707) (xy 121.470947 -248.7861) (xy 121.432826 -248.754975)
			(xy 121.400191 -248.718138) (xy 121.373888 -248.676542) (xy 121.354597 -248.631266) (xy 121.34282 -248.583482)
			(xy 121.33886 -248.534428) (xy 119.130064 -248.534428) (xy 119.129569 -248.559035) (xy 119.121674 -248.607612)
			(xy 119.10609 -248.654293) (xy 119.083219 -248.69787) (xy 119.053654 -248.737214) (xy 119.018161 -248.771306)
			(xy 118.977658 -248.799262) (xy 118.933196 -248.82036) (xy 118.885925 -248.834052) (xy 118.83707 -248.839984)
			(xy 118.787895 -248.838003) (xy 118.739676 -248.828159) (xy 118.69366 -248.810707) (xy 118.651039 -248.7861)
			(xy 118.612918 -248.754975) (xy 118.580283 -248.718138) (xy 118.55398 -248.676542) (xy 118.534689 -248.631266)
			(xy 118.522912 -248.583482) (xy 118.518952 -248.534428) (xy 116.310156 -248.534428) (xy 116.309661 -248.559035)
			(xy 116.301766 -248.607612) (xy 116.286182 -248.654293) (xy 116.263311 -248.69787) (xy 116.233746 -248.737214)
			(xy 116.198253 -248.771306) (xy 116.15775 -248.799262) (xy 116.113288 -248.82036) (xy 116.066017 -248.834052)
			(xy 116.017162 -248.839984) (xy 115.967987 -248.838003) (xy 115.919768 -248.828159) (xy 115.873752 -248.810707)
			(xy 115.831131 -248.7861) (xy 115.79301 -248.754975) (xy 115.760375 -248.718138) (xy 115.734072 -248.676542)
			(xy 115.714781 -248.631266) (xy 115.703004 -248.583482) (xy 115.699044 -248.534428) (xy 115.370102 -248.534428)
			(xy 115.369607 -248.559035) (xy 115.361712 -248.607612) (xy 115.346128 -248.654293) (xy 115.323257 -248.69787)
			(xy 115.293692 -248.737214) (xy 115.258199 -248.771306) (xy 115.217696 -248.799262) (xy 115.173234 -248.82036)
			(xy 115.125963 -248.834052) (xy 115.077108 -248.839984) (xy 115.027933 -248.838003) (xy 114.979714 -248.828159)
			(xy 114.933698 -248.810707) (xy 114.891077 -248.7861) (xy 114.852956 -248.754975) (xy 114.820321 -248.718138)
			(xy 114.794018 -248.676542) (xy 114.774727 -248.631266) (xy 114.76295 -248.583482) (xy 114.75899 -248.534428)
			(xy 114.430048 -248.534428) (xy 114.429553 -248.559035) (xy 114.421658 -248.607612) (xy 114.406074 -248.654293)
			(xy 114.383203 -248.69787) (xy 114.353638 -248.737214) (xy 114.318145 -248.771306) (xy 114.277642 -248.799262)
			(xy 114.23318 -248.82036) (xy 114.185909 -248.834052) (xy 114.137054 -248.839984) (xy 114.087879 -248.838003)
			(xy 114.03966 -248.828159) (xy 113.993644 -248.810707) (xy 113.951023 -248.7861) (xy 113.912902 -248.754975)
			(xy 113.880267 -248.718138) (xy 113.853964 -248.676542) (xy 113.834673 -248.631266) (xy 113.822896 -248.583482)
			(xy 113.818936 -248.534428) (xy 113.489994 -248.534428) (xy 113.489499 -248.559035) (xy 113.481604 -248.607612)
			(xy 113.46602 -248.654293) (xy 113.443149 -248.69787) (xy 113.413584 -248.737214) (xy 113.378091 -248.771306)
			(xy 113.337588 -248.799262) (xy 113.293126 -248.82036) (xy 113.245855 -248.834052) (xy 113.197 -248.839984)
			(xy 113.147825 -248.838003) (xy 113.099606 -248.828159) (xy 113.05359 -248.810707) (xy 113.010969 -248.7861)
			(xy 112.972848 -248.754975) (xy 112.940213 -248.718138) (xy 112.91391 -248.676542) (xy 112.894619 -248.631266)
			(xy 112.882842 -248.583482) (xy 112.878882 -248.534428) (xy 110.883192 -248.534428) (xy 110.387638 -249.029982)
			(xy 110.380237 -249.03682) (xy 110.361639 -249.044535) (xy 110.35157 -249.044968) (xy 109.685582 -249.044968)
			(xy 109.680142 -249.04511) (xy 109.669511 -249.047418) (xy 109.6645 -249.04954) (xy 109.636931 -249.061583)
			(xy 109.579797 -249.080431) (xy 109.520983 -249.093102) (xy 109.461156 -249.09945) (xy 109.431074 -249.099832)
			(xy 109.342174 -249.099832) (xy 109.329853 -249.100623) (xy 109.308076 -249.112168) (xy 109.300518 -249.12193)
			(xy 109.245654 -249.200924) (xy 109.242606 -249.225308) (xy 109.246924 -249.237246) (xy 109.255993 -249.263113)
			(xy 109.26583 -249.317031) (xy 109.266482 -249.344434) (xy 109.266115 -249.362214) (xy 111.456473 -249.362214)
			(xy 111.460503 -249.309716) (xy 111.4725 -249.258448) (xy 111.492183 -249.209613) (xy 111.519089 -249.164354)
			(xy 111.552589 -249.123733) (xy 111.591897 -249.088702) (xy 111.636092 -249.060082) (xy 111.684137 -249.038543)
			(xy 111.734908 -249.024591) (xy 111.787213 -249.018553) (xy 111.839827 -249.02057) (xy 111.891517 -249.030594)
			(xy 111.94107 -249.048392) (xy 111.987326 -249.073545) (xy 112.0292 -249.105464) (xy 112.065712 -249.143402)
			(xy 112.096004 -249.186468) (xy 112.119367 -249.233653) (xy 112.135253 -249.283852) (xy 112.14329 -249.335888)
			(xy 112.143454 -249.344434) (xy 113.349036 -249.344434) (xy 113.352996 -249.29538) (xy 113.364773 -249.247596)
			(xy 113.384064 -249.20232) (xy 113.410367 -249.160724) (xy 113.443002 -249.123887) (xy 113.481123 -249.092762)
			(xy 113.523744 -249.068155) (xy 113.56976 -249.050703) (xy 113.617979 -249.040859) (xy 113.667154 -249.038878)
			(xy 113.716009 -249.04481) (xy 113.76328 -249.058502) (xy 113.807742 -249.0796) (xy 113.848245 -249.107556)
			(xy 113.883738 -249.141648) (xy 113.913303 -249.180992) (xy 113.936174 -249.224569) (xy 113.951758 -249.27125)
			(xy 113.959653 -249.319827) (xy 113.960148 -249.344434) (xy 115.22889 -249.344434) (xy 115.23285 -249.29538)
			(xy 115.244627 -249.247596) (xy 115.263918 -249.20232) (xy 115.290221 -249.160724) (xy 115.322856 -249.123887)
			(xy 115.360977 -249.092762) (xy 115.403598 -249.068155) (xy 115.449614 -249.050703) (xy 115.497833 -249.040859)
			(xy 115.547008 -249.038878) (xy 115.595863 -249.04481) (xy 115.643134 -249.058502) (xy 115.687596 -249.0796)
			(xy 115.728099 -249.107556) (xy 115.763592 -249.141648) (xy 115.793157 -249.180992) (xy 115.816028 -249.224569)
			(xy 115.831612 -249.27125) (xy 115.839507 -249.319827) (xy 115.840002 -249.344434) (xy 117.108998 -249.344434)
			(xy 117.112958 -249.29538) (xy 117.124735 -249.247596) (xy 117.144026 -249.20232) (xy 117.170329 -249.160724)
			(xy 117.202964 -249.123887) (xy 117.241085 -249.092762) (xy 117.283706 -249.068155) (xy 117.329722 -249.050703)
			(xy 117.377941 -249.040859) (xy 117.427116 -249.038878) (xy 117.475971 -249.04481) (xy 117.523242 -249.058502)
			(xy 117.567704 -249.0796) (xy 117.608207 -249.107556) (xy 117.6437 -249.141648) (xy 117.673265 -249.180992)
			(xy 117.696136 -249.224569) (xy 117.71172 -249.27125) (xy 117.719615 -249.319827) (xy 117.72011 -249.344434)
			(xy 118.988852 -249.344434) (xy 118.992812 -249.29538) (xy 119.004589 -249.247596) (xy 119.02388 -249.20232)
			(xy 119.050183 -249.160724) (xy 119.082818 -249.123887) (xy 119.120939 -249.092762) (xy 119.16356 -249.068155)
			(xy 119.209576 -249.050703) (xy 119.257795 -249.040859) (xy 119.30697 -249.038878) (xy 119.355825 -249.04481)
			(xy 119.403096 -249.058502) (xy 119.447558 -249.0796) (xy 119.488061 -249.107556) (xy 119.523554 -249.141648)
			(xy 119.553119 -249.180992) (xy 119.57599 -249.224569) (xy 119.591574 -249.27125) (xy 119.599469 -249.319827)
			(xy 119.599964 -249.344434) (xy 120.86896 -249.344434) (xy 120.87292 -249.29538) (xy 120.884697 -249.247596)
			(xy 120.903988 -249.20232) (xy 120.930291 -249.160724) (xy 120.962926 -249.123887) (xy 121.001047 -249.092762)
			(xy 121.043668 -249.068155) (xy 121.089684 -249.050703) (xy 121.137903 -249.040859) (xy 121.187078 -249.038878)
			(xy 121.235933 -249.04481) (xy 121.283204 -249.058502) (xy 121.327666 -249.0796) (xy 121.368169 -249.107556)
			(xy 121.403662 -249.141648) (xy 121.433227 -249.180992) (xy 121.456098 -249.224569) (xy 121.471682 -249.27125)
			(xy 121.479577 -249.319827) (xy 121.480072 -249.344434) (xy 122.748814 -249.344434) (xy 122.752774 -249.29538)
			(xy 122.764551 -249.247596) (xy 122.783842 -249.20232) (xy 122.810145 -249.160724) (xy 122.84278 -249.123887)
			(xy 122.880901 -249.092762) (xy 122.923522 -249.068155) (xy 122.969538 -249.050703) (xy 123.017757 -249.040859)
			(xy 123.066932 -249.038878) (xy 123.115787 -249.04481) (xy 123.163058 -249.058502) (xy 123.20752 -249.0796)
			(xy 123.248023 -249.107556) (xy 123.283516 -249.141648) (xy 123.313081 -249.180992) (xy 123.335952 -249.224569)
			(xy 123.351536 -249.27125) (xy 123.359431 -249.319827) (xy 123.359926 -249.344434) (xy 124.628922 -249.344434)
			(xy 124.632882 -249.29538) (xy 124.644659 -249.247596) (xy 124.66395 -249.20232) (xy 124.690253 -249.160724)
			(xy 124.722888 -249.123887) (xy 124.761009 -249.092762) (xy 124.80363 -249.068155) (xy 124.849646 -249.050703)
			(xy 124.897865 -249.040859) (xy 124.94704 -249.038878) (xy 124.995895 -249.04481) (xy 125.043166 -249.058502)
			(xy 125.087628 -249.0796) (xy 125.128131 -249.107556) (xy 125.163624 -249.141648) (xy 125.193189 -249.180992)
			(xy 125.21606 -249.224569) (xy 125.231644 -249.27125) (xy 125.239539 -249.319827) (xy 125.240034 -249.344434)
			(xy 125.239539 -249.369041) (xy 125.231644 -249.417618) (xy 125.21606 -249.464299) (xy 125.193189 -249.507876)
			(xy 125.163624 -249.54722) (xy 125.128131 -249.581312) (xy 125.087628 -249.609268) (xy 125.043166 -249.630366)
			(xy 124.995895 -249.644058) (xy 124.94704 -249.64999) (xy 124.897865 -249.648009) (xy 124.849646 -249.638165)
			(xy 124.80363 -249.620713) (xy 124.761009 -249.596106) (xy 124.722888 -249.564981) (xy 124.690253 -249.528144)
			(xy 124.66395 -249.486548) (xy 124.644659 -249.441272) (xy 124.632882 -249.393488) (xy 124.628922 -249.344434)
			(xy 123.359926 -249.344434) (xy 123.359431 -249.369041) (xy 123.351536 -249.417618) (xy 123.335952 -249.464299)
			(xy 123.313081 -249.507876) (xy 123.283516 -249.54722) (xy 123.248023 -249.581312) (xy 123.20752 -249.609268)
			(xy 123.163058 -249.630366) (xy 123.115787 -249.644058) (xy 123.066932 -249.64999) (xy 123.017757 -249.648009)
			(xy 122.969538 -249.638165) (xy 122.923522 -249.620713) (xy 122.880901 -249.596106) (xy 122.84278 -249.564981)
			(xy 122.810145 -249.528144) (xy 122.783842 -249.486548) (xy 122.764551 -249.441272) (xy 122.752774 -249.393488)
			(xy 122.748814 -249.344434) (xy 121.480072 -249.344434) (xy 121.479577 -249.369041) (xy 121.471682 -249.417618)
			(xy 121.456098 -249.464299) (xy 121.433227 -249.507876) (xy 121.403662 -249.54722) (xy 121.368169 -249.581312)
			(xy 121.327666 -249.609268) (xy 121.283204 -249.630366) (xy 121.235933 -249.644058) (xy 121.187078 -249.64999)
			(xy 121.137903 -249.648009) (xy 121.089684 -249.638165) (xy 121.043668 -249.620713) (xy 121.001047 -249.596106)
			(xy 120.962926 -249.564981) (xy 120.930291 -249.528144) (xy 120.903988 -249.486548) (xy 120.884697 -249.441272)
			(xy 120.87292 -249.393488) (xy 120.86896 -249.344434) (xy 119.599964 -249.344434) (xy 119.599469 -249.369041)
			(xy 119.591574 -249.417618) (xy 119.57599 -249.464299) (xy 119.553119 -249.507876) (xy 119.523554 -249.54722)
			(xy 119.488061 -249.581312) (xy 119.447558 -249.609268) (xy 119.403096 -249.630366) (xy 119.355825 -249.644058)
			(xy 119.30697 -249.64999) (xy 119.257795 -249.648009) (xy 119.209576 -249.638165) (xy 119.16356 -249.620713)
			(xy 119.120939 -249.596106) (xy 119.082818 -249.564981) (xy 119.050183 -249.528144) (xy 119.02388 -249.486548)
			(xy 119.004589 -249.441272) (xy 118.992812 -249.393488) (xy 118.988852 -249.344434) (xy 117.72011 -249.344434)
			(xy 117.719615 -249.369041) (xy 117.71172 -249.417618) (xy 117.696136 -249.464299) (xy 117.673265 -249.507876)
			(xy 117.6437 -249.54722) (xy 117.608207 -249.581312) (xy 117.567704 -249.609268) (xy 117.523242 -249.630366)
			(xy 117.475971 -249.644058) (xy 117.427116 -249.64999) (xy 117.377941 -249.648009) (xy 117.329722 -249.638165)
			(xy 117.283706 -249.620713) (xy 117.241085 -249.596106) (xy 117.202964 -249.564981) (xy 117.170329 -249.528144)
			(xy 117.144026 -249.486548) (xy 117.124735 -249.441272) (xy 117.112958 -249.393488) (xy 117.108998 -249.344434)
			(xy 115.840002 -249.344434) (xy 115.839507 -249.369041) (xy 115.831612 -249.417618) (xy 115.816028 -249.464299)
			(xy 115.793157 -249.507876) (xy 115.763592 -249.54722) (xy 115.728099 -249.581312) (xy 115.687596 -249.609268)
			(xy 115.643134 -249.630366) (xy 115.595863 -249.644058) (xy 115.547008 -249.64999) (xy 115.497833 -249.648009)
			(xy 115.449614 -249.638165) (xy 115.403598 -249.620713) (xy 115.360977 -249.596106) (xy 115.322856 -249.564981)
			(xy 115.290221 -249.528144) (xy 115.263918 -249.486548) (xy 115.244627 -249.441272) (xy 115.23285 -249.393488)
			(xy 115.22889 -249.344434) (xy 113.960148 -249.344434) (xy 113.959653 -249.369041) (xy 113.951758 -249.417618)
			(xy 113.936174 -249.464299) (xy 113.913303 -249.507876) (xy 113.883738 -249.54722) (xy 113.848245 -249.581312)
			(xy 113.807742 -249.609268) (xy 113.76328 -249.630366) (xy 113.716009 -249.644058) (xy 113.667154 -249.64999)
			(xy 113.617979 -249.648009) (xy 113.56976 -249.638165) (xy 113.523744 -249.620713) (xy 113.481123 -249.596106)
			(xy 113.443002 -249.564981) (xy 113.410367 -249.528144) (xy 113.384064 -249.486548) (xy 113.364773 -249.441272)
			(xy 113.352996 -249.393488) (xy 113.349036 -249.344434) (xy 112.143454 -249.344434) (xy 112.143794 -249.362214)
			(xy 112.14329 -249.38854) (xy 112.135253 -249.440576) (xy 112.119367 -249.490775) (xy 112.096004 -249.53796)
			(xy 112.065712 -249.581026) (xy 112.0292 -249.618964) (xy 111.987326 -249.650883) (xy 111.94107 -249.676036)
			(xy 111.891517 -249.693834) (xy 111.839827 -249.703858) (xy 111.787213 -249.705875) (xy 111.734908 -249.699837)
			(xy 111.684137 -249.685885) (xy 111.636092 -249.664346) (xy 111.591897 -249.635726) (xy 111.552589 -249.600695)
			(xy 111.519089 -249.560074) (xy 111.492183 -249.514815) (xy 111.4725 -249.46598) (xy 111.460503 -249.414712)
			(xy 111.456473 -249.362214) (xy 109.266115 -249.362214) (xy 109.26596 -249.369689) (xy 109.257647 -249.419511)
			(xy 109.241246 -249.467285) (xy 109.217205 -249.511708) (xy 109.186181 -249.551568) (xy 109.149019 -249.585778)
			(xy 109.106733 -249.613404) (xy 109.060477 -249.633694) (xy 109.011512 -249.646094) (xy 108.961174 -249.650265)
			(xy 108.910836 -249.646094) (xy 108.861871 -249.633694) (xy 108.815615 -249.613404) (xy 108.773329 -249.585778)
			(xy 108.736167 -249.551568) (xy 108.705143 -249.511708) (xy 108.681102 -249.467285) (xy 108.664701 -249.419511)
			(xy 108.656388 -249.369689) (xy 108.655866 -249.344434) (xy 108.656462 -249.317025) (xy 108.666298 -249.263097)
			(xy 108.675424 -249.237246) (xy 108.679742 -249.225308) (xy 108.676694 -249.200924) (xy 108.62183 -249.12193)
			(xy 108.614266 -249.11217) (xy 108.592495 -249.100608) (xy 108.580174 -249.099832) (xy 108.49102 -249.099832)
			(xy 108.460939 -249.099446) (xy 108.401113 -249.093087) (xy 108.3423 -249.080418) (xy 108.285163 -249.061581)
			(xy 108.257594 -249.04954) (xy 108.252585 -249.047414) (xy 108.241952 -249.045115) (xy 108.236512 -249.044968)
			(xy 107.42676 -249.044968) (xy 107.417809 -249.04532) (xy 107.400997 -249.051477) (xy 107.38732 -249.063029)
			(xy 107.382564 -249.070622) (xy 107.337098 -249.150632) (xy 107.337352 -249.17781) (xy 107.34421 -249.189494)
			(xy 107.357463 -249.213142) (xy 107.376288 -249.263972) (xy 107.385821 -249.317331) (xy 107.386374 -249.344434)
			(xy 107.385852 -249.369689) (xy 107.377539 -249.419511) (xy 107.361138 -249.467285) (xy 107.337097 -249.511708)
			(xy 107.306073 -249.551568) (xy 107.268911 -249.585778) (xy 107.226625 -249.613404) (xy 107.180369 -249.633694)
			(xy 107.131404 -249.646094) (xy 107.081066 -249.650265) (xy 107.030728 -249.646094) (xy 106.981763 -249.633694)
			(xy 106.935507 -249.613404) (xy 106.893221 -249.585778) (xy 106.856059 -249.551568) (xy 106.825035 -249.511708)
			(xy 106.800994 -249.467285) (xy 106.784593 -249.419511) (xy 106.77628 -249.369689) (xy 106.775758 -249.344434)
			(xy 106.776352 -249.317337) (xy 106.785915 -249.263992) (xy 106.804714 -249.213162) (xy 106.817922 -249.189494)
			(xy 106.82478 -249.17781) (xy 106.825034 -249.150632) (xy 106.775758 -249.064018) (xy 106.771032 -249.056399)
			(xy 106.757355 -249.044823) (xy 106.740522 -249.038681) (xy 106.731562 -249.038364) (xy 105.550462 -249.038364)
			(xy 105.54151 -249.038716) (xy 105.524698 -249.044872) (xy 105.511019 -249.056424) (xy 105.506266 -249.064018)
			(xy 105.45699 -249.150632) (xy 105.457244 -249.17781) (xy 105.464102 -249.189494) (xy 105.477355 -249.213142)
			(xy 105.496181 -249.263972) (xy 105.505714 -249.317331) (xy 105.506266 -249.344434) (xy 105.505744 -249.369689)
			(xy 105.497431 -249.419511) (xy 105.48103 -249.467285) (xy 105.456989 -249.511708) (xy 105.425965 -249.551568)
			(xy 105.388803 -249.585778) (xy 105.346517 -249.613404) (xy 105.300261 -249.633694) (xy 105.251296 -249.646094)
			(xy 105.200958 -249.650265) (xy 105.15062 -249.646094) (xy 105.101655 -249.633694) (xy 105.055399 -249.613404)
			(xy 105.013113 -249.585778) (xy 104.975951 -249.551568) (xy 104.944927 -249.511708) (xy 104.920886 -249.467285)
			(xy 104.904485 -249.419511) (xy 104.896172 -249.369689) (xy 104.89565 -249.344434) (xy 104.896244 -249.317337)
			(xy 104.905807 -249.263992) (xy 104.924605 -249.213162) (xy 104.937814 -249.189494) (xy 104.944672 -249.17781)
			(xy 104.944926 -249.150632) (xy 104.89565 -249.064018) (xy 104.890923 -249.0564) (xy 104.877246 -249.044826)
			(xy 104.860414 -249.038687) (xy 104.851454 -249.038364) (xy 103.670608 -249.038364) (xy 103.661661 -249.038724)
			(xy 103.644863 -249.044892) (xy 103.631199 -249.056448) (xy 103.626412 -249.064018) (xy 103.577136 -249.150632)
			(xy 103.57739 -249.17781) (xy 103.584248 -249.189494) (xy 103.597499 -249.213143) (xy 103.616322 -249.263973)
			(xy 103.625854 -249.317332) (xy 103.626412 -249.344434) (xy 103.62589 -249.369689) (xy 103.617577 -249.419511)
			(xy 103.601176 -249.467285) (xy 103.577135 -249.511708) (xy 103.546111 -249.551568) (xy 103.508949 -249.585778)
			(xy 103.466663 -249.613404) (xy 103.420407 -249.633694) (xy 103.371442 -249.646094) (xy 103.321104 -249.650265)
			(xy 103.270766 -249.646094) (xy 103.221801 -249.633694) (xy 103.175545 -249.613404) (xy 103.133259 -249.585778)
			(xy 103.096097 -249.551568) (xy 103.065073 -249.511708) (xy 103.041032 -249.467285) (xy 103.024631 -249.419511)
			(xy 103.016318 -249.369689) (xy 103.015796 -249.344434) (xy 103.016391 -249.317337) (xy 103.025955 -249.263993)
			(xy 103.044755 -249.213164) (xy 103.05796 -249.189494) (xy 103.064818 -249.17781) (xy 103.065072 -249.150632)
			(xy 103.015796 -249.064018) (xy 103.011072 -249.056394) (xy 102.997396 -249.044808) (xy 102.980562 -249.038654)
			(xy 102.9716 -249.038364) (xy 101.7905 -249.038364) (xy 101.781545 -249.038709) (xy 101.764723 -249.044858)
			(xy 101.751033 -249.056407) (xy 101.746304 -249.064018) (xy 101.697028 -249.150632) (xy 101.697282 -249.17781)
			(xy 101.70414 -249.189494) (xy 101.717391 -249.213143) (xy 101.736215 -249.263973) (xy 101.745747 -249.317332)
			(xy 101.746304 -249.344434) (xy 101.745782 -249.369689) (xy 101.737469 -249.419511) (xy 101.721068 -249.467285)
			(xy 101.697027 -249.511708) (xy 101.666003 -249.551568) (xy 101.628841 -249.585778) (xy 101.586555 -249.613404)
			(xy 101.540299 -249.633694) (xy 101.491334 -249.646094) (xy 101.440996 -249.650265) (xy 101.390658 -249.646094)
			(xy 101.341693 -249.633694) (xy 101.295437 -249.613404) (xy 101.253151 -249.585778) (xy 101.215989 -249.551568)
			(xy 101.184965 -249.511708) (xy 101.160924 -249.467285) (xy 101.144523 -249.419511) (xy 101.13621 -249.369689)
			(xy 101.135688 -249.344434) (xy 101.136283 -249.317337) (xy 101.145846 -249.263993) (xy 101.164646 -249.213163)
			(xy 101.177852 -249.189494) (xy 101.18471 -249.17781) (xy 101.184964 -249.150632) (xy 101.135688 -249.064018)
			(xy 101.130963 -249.056395) (xy 101.117288 -249.044811) (xy 101.100454 -249.03866) (xy 101.091492 -249.038364)
			(xy 100.31476 -249.038364) (xy 100.304919 -249.038894) (xy 100.286747 -249.046469) (xy 100.279454 -249.053096)
			(xy 100.17633 -249.15622) (xy 100.169614 -249.163456) (xy 100.162016 -249.181662) (xy 100.161598 -249.191526)
			(xy 100.161598 -249.53087) (xy 100.162034 -249.540935) (xy 100.169766 -249.559521) (xy 100.176584 -249.566938)
			(xy 100.76422 -250.15444) (xy 101.605346 -250.15444) (xy 101.609306 -250.105386) (xy 101.621083 -250.057602)
			(xy 101.640374 -250.012326) (xy 101.666677 -249.97073) (xy 101.699312 -249.933893) (xy 101.737433 -249.902768)
			(xy 101.780054 -249.878161) (xy 101.82607 -249.860709) (xy 101.874289 -249.850865) (xy 101.923464 -249.848884)
			(xy 101.972319 -249.854816) (xy 102.01959 -249.868508) (xy 102.064052 -249.889606) (xy 102.104555 -249.917562)
			(xy 102.140048 -249.951654) (xy 102.169613 -249.990998) (xy 102.192484 -250.034575) (xy 102.208068 -250.081256)
			(xy 102.215963 -250.129833) (xy 102.216458 -250.15444) (xy 103.4852 -250.15444) (xy 103.48916 -250.105386)
			(xy 103.500937 -250.057602) (xy 103.520228 -250.012326) (xy 103.546531 -249.97073) (xy 103.579166 -249.933893)
			(xy 103.617287 -249.902768) (xy 103.659908 -249.878161) (xy 103.705924 -249.860709) (xy 103.754143 -249.850865)
			(xy 103.803318 -249.848884) (xy 103.852173 -249.854816) (xy 103.899444 -249.868508) (xy 103.943906 -249.889606)
			(xy 103.984409 -249.917562) (xy 104.019902 -249.951654) (xy 104.049467 -249.990998) (xy 104.072338 -250.034575)
			(xy 104.087922 -250.081256) (xy 104.095817 -250.129833) (xy 104.096312 -250.15444) (xy 105.365308 -250.15444)
			(xy 105.369268 -250.105386) (xy 105.381045 -250.057602) (xy 105.400336 -250.012326) (xy 105.426639 -249.97073)
			(xy 105.459274 -249.933893) (xy 105.497395 -249.902768) (xy 105.540016 -249.878161) (xy 105.586032 -249.860709)
			(xy 105.634251 -249.850865) (xy 105.683426 -249.848884) (xy 105.732281 -249.854816) (xy 105.779552 -249.868508)
			(xy 105.824014 -249.889606) (xy 105.864517 -249.917562) (xy 105.90001 -249.951654) (xy 105.929575 -249.990998)
			(xy 105.952446 -250.034575) (xy 105.96803 -250.081256) (xy 105.975925 -250.129833) (xy 105.97642 -250.15444)
			(xy 107.245162 -250.15444) (xy 107.249122 -250.105386) (xy 107.260899 -250.057602) (xy 107.28019 -250.012326)
			(xy 107.306493 -249.97073) (xy 107.339128 -249.933893) (xy 107.377249 -249.902768) (xy 107.41987 -249.878161)
			(xy 107.465886 -249.860709) (xy 107.514105 -249.850865) (xy 107.56328 -249.848884) (xy 107.612135 -249.854816)
			(xy 107.659406 -249.868508) (xy 107.703868 -249.889606) (xy 107.744371 -249.917562) (xy 107.779864 -249.951654)
			(xy 107.809429 -249.990998) (xy 107.8323 -250.034575) (xy 107.847884 -250.081256) (xy 107.855779 -250.129833)
			(xy 107.856274 -250.15444) (xy 107.855779 -250.179047) (xy 107.847884 -250.227624) (xy 107.8323 -250.274305)
			(xy 107.809429 -250.317882) (xy 107.779864 -250.357226) (xy 107.744371 -250.391318) (xy 107.703868 -250.419274)
			(xy 107.659406 -250.440372) (xy 107.612135 -250.454064) (xy 107.56328 -250.459996) (xy 107.514105 -250.458015)
			(xy 107.465886 -250.448171) (xy 107.41987 -250.430719) (xy 107.377249 -250.406112) (xy 107.339128 -250.374987)
			(xy 107.306493 -250.33815) (xy 107.28019 -250.296554) (xy 107.260899 -250.251278) (xy 107.249122 -250.203494)
			(xy 107.245162 -250.15444) (xy 105.97642 -250.15444) (xy 105.975925 -250.179047) (xy 105.96803 -250.227624)
			(xy 105.952446 -250.274305) (xy 105.929575 -250.317882) (xy 105.90001 -250.357226) (xy 105.864517 -250.391318)
			(xy 105.824014 -250.419274) (xy 105.779552 -250.440372) (xy 105.732281 -250.454064) (xy 105.683426 -250.459996)
			(xy 105.634251 -250.458015) (xy 105.586032 -250.448171) (xy 105.540016 -250.430719) (xy 105.497395 -250.406112)
			(xy 105.459274 -250.374987) (xy 105.426639 -250.33815) (xy 105.400336 -250.296554) (xy 105.381045 -250.251278)
			(xy 105.369268 -250.203494) (xy 105.365308 -250.15444) (xy 104.096312 -250.15444) (xy 104.095817 -250.179047)
			(xy 104.087922 -250.227624) (xy 104.072338 -250.274305) (xy 104.049467 -250.317882) (xy 104.019902 -250.357226)
			(xy 103.984409 -250.391318) (xy 103.943906 -250.419274) (xy 103.899444 -250.440372) (xy 103.852173 -250.454064)
			(xy 103.803318 -250.459996) (xy 103.754143 -250.458015) (xy 103.705924 -250.448171) (xy 103.659908 -250.430719)
			(xy 103.617287 -250.406112) (xy 103.579166 -250.374987) (xy 103.546531 -250.33815) (xy 103.520228 -250.296554)
			(xy 103.500937 -250.251278) (xy 103.48916 -250.203494) (xy 103.4852 -250.15444) (xy 102.216458 -250.15444)
			(xy 102.215963 -250.179047) (xy 102.208068 -250.227624) (xy 102.192484 -250.274305) (xy 102.169613 -250.317882)
			(xy 102.140048 -250.357226) (xy 102.104555 -250.391318) (xy 102.064052 -250.419274) (xy 102.01959 -250.440372)
			(xy 101.972319 -250.454064) (xy 101.923464 -250.459996) (xy 101.874289 -250.458015) (xy 101.82607 -250.448171)
			(xy 101.780054 -250.430719) (xy 101.737433 -250.406112) (xy 101.699312 -250.374987) (xy 101.666677 -250.33815)
			(xy 101.640374 -250.296554) (xy 101.621083 -250.251278) (xy 101.609306 -250.203494) (xy 101.605346 -250.15444)
			(xy 100.76422 -250.15444) (xy 101.288342 -250.678442) (xy 101.317552 -250.684792) (xy 101.331776 -250.679204)
			(xy 101.357607 -250.669948) (xy 101.411534 -250.659844) (xy 101.438964 -250.659138) (xy 101.44379 -250.659138)
			(xy 101.467497 -250.659804) (xy 101.514282 -250.667565) (xy 101.559304 -250.682469) (xy 101.601479 -250.704155)
			(xy 101.639794 -250.732102) (xy 101.673325 -250.765639) (xy 101.701267 -250.803957) (xy 101.722948 -250.846136)
			(xy 101.737845 -250.891159) (xy 101.7456 -250.937945) (xy 101.746304 -250.961652) (xy 101.746304 -250.9647)
			(xy 101.745684 -250.992574) (xy 101.73559 -251.047401) (xy 101.726238 -251.073666) (xy 101.72065 -251.08789)
			(xy 101.727 -251.1171) (xy 101.868478 -251.258578) (xy 101.87588 -251.265415) (xy 101.894478 -251.273124)
			(xy 101.904546 -251.273564) (xy 102.730808 -251.273564)
		)
		(stroke
			(width 0)
			(type solid)
		)
		(fill yes)
		(layer "In11.Cu")
		(net "PVDDCR_CPU0_P1")
	)
	(gr_poly
		(pts
			(xy 350.675702 -251.268484) (xy 350.73336 -251.268484) (xy 350.910652 -251.268484) (xy 350.919548 -251.26804)
			(xy 350.936234 -251.261853) (xy 350.94981 -251.250345) (xy 350.954594 -251.24283) (xy 350.99625 -251.170694)
			(xy 351.000802 -251.161685) (xy 351.003298 -251.141677) (xy 351.001076 -251.131832) (xy 350.997266 -251.117862)
			(xy 350.994218 -251.112528) (xy 350.982163 -251.08968) (xy 350.965057 -251.04094) (xy 350.956381 -250.990019)
			(xy 350.955864 -250.964192) (xy 350.955864 -250.956318) (xy 350.956992 -250.931489) (xy 350.966301 -250.882669)
			(xy 350.983392 -250.836) (xy 351.007814 -250.792714) (xy 351.038922 -250.753954) (xy 351.075896 -250.720742)
			(xy 351.11776 -250.693955) (xy 351.163408 -250.6743) (xy 351.211636 -250.662296) (xy 351.261172 -250.658259)
			(xy 351.310708 -250.662296) (xy 351.358936 -250.6743) (xy 351.404584 -250.693955) (xy 351.446448 -250.720742)
			(xy 351.483422 -250.753954) (xy 351.51453 -250.792714) (xy 351.538952 -250.836) (xy 351.556043 -250.882669)
			(xy 351.565352 -250.931489) (xy 351.56648 -250.956318) (xy 351.56648 -250.961144) (xy 351.56648 -250.964192)
			(xy 351.565963 -250.990021) (xy 351.557306 -251.040946) (xy 351.540189 -251.089684) (xy 351.528126 -251.112528)
			(xy 351.525078 -251.117862) (xy 351.521268 -251.131832) (xy 351.518963 -251.141672) (xy 351.52146 -251.161711)
			(xy 351.526094 -251.170694) (xy 351.56775 -251.243084) (xy 351.572518 -251.250643) (xy 351.586218 -251.262102)
			(xy 351.603015 -251.268174) (xy 351.611946 -251.268484) (xy 351.993962 -251.268484) (xy 351.99955 -251.26823)
			(xy 351.999804 -251.268484) (xy 352.790506 -251.268484) (xy 352.799406 -251.268047) (xy 352.816104 -251.26187)
			(xy 352.829692 -251.250365) (xy 352.834448 -251.24283) (xy 352.876104 -251.170694) (xy 352.880652 -251.161684)
			(xy 352.883145 -251.141678) (xy 352.88093 -251.131832) (xy 352.87712 -251.117862) (xy 352.874072 -251.112528)
			(xy 352.862015 -251.089681) (xy 352.844906 -251.040941) (xy 352.836228 -250.99002) (xy 352.835718 -250.964192)
			(xy 352.835718 -250.956318) (xy 352.836846 -250.931489) (xy 352.846155 -250.882669) (xy 352.863246 -250.836)
			(xy 352.887668 -250.792714) (xy 352.918776 -250.753954) (xy 352.95575 -250.720742) (xy 352.997614 -250.693955)
			(xy 353.043262 -250.6743) (xy 353.09149 -250.662296) (xy 353.141026 -250.658259) (xy 353.190562 -250.662296)
			(xy 353.23879 -250.6743) (xy 353.284438 -250.693955) (xy 353.326302 -250.720742) (xy 353.363276 -250.753954)
			(xy 353.394384 -250.792714) (xy 353.418806 -250.836) (xy 353.435897 -250.882669) (xy 353.445206 -250.931489)
			(xy 353.446334 -250.956318) (xy 353.446334 -250.961144) (xy 353.446334 -250.964192) (xy 353.445817 -250.990021)
			(xy 353.437162 -251.040947) (xy 353.420047 -251.089686) (xy 353.40798 -251.112528) (xy 353.404932 -251.117862)
			(xy 353.401122 -251.131832) (xy 353.398818 -251.141673) (xy 353.401313 -251.161712) (xy 353.405948 -251.170694)
			(xy 353.447604 -251.243084) (xy 353.45237 -251.250648) (xy 353.466068 -251.26212) (xy 353.482866 -251.268206)
			(xy 353.4918 -251.268484) (xy 353.87407 -251.268484) (xy 353.879658 -251.26823) (xy 353.879912 -251.268484)
			(xy 354.670614 -251.268484) (xy 354.679513 -251.268046) (xy 354.69621 -251.261867) (xy 354.709795 -251.250362)
			(xy 354.714556 -251.24283) (xy 354.756212 -251.170694) (xy 354.760766 -251.161686) (xy 354.763264 -251.141676)
			(xy 354.761038 -251.131832) (xy 354.757228 -251.117862) (xy 354.75418 -251.112528) (xy 354.742123 -251.089681)
			(xy 354.725013 -251.040941) (xy 354.716335 -250.99002) (xy 354.715826 -250.964192) (xy 354.715826 -250.956318)
			(xy 354.716954 -250.931489) (xy 354.726263 -250.882669) (xy 354.743354 -250.836) (xy 354.767776 -250.792714)
			(xy 354.798884 -250.753954) (xy 354.835858 -250.720742) (xy 354.877722 -250.693955) (xy 354.92337 -250.6743)
			(xy 354.971598 -250.662296) (xy 355.021134 -250.658259) (xy 355.07067 -250.662296) (xy 355.118898 -250.6743)
			(xy 355.164546 -250.693955) (xy 355.20641 -250.720742) (xy 355.243384 -250.753954) (xy 355.274492 -250.792714)
			(xy 355.298914 -250.836) (xy 355.316005 -250.882669) (xy 355.325314 -250.931489) (xy 355.326442 -250.956318)
			(xy 355.326442 -250.961144) (xy 355.326442 -250.964192) (xy 355.325925 -250.990021) (xy 355.31727 -251.040947)
			(xy 355.300156 -251.089686) (xy 355.288088 -251.112528) (xy 355.28504 -251.117862) (xy 355.28123 -251.131832)
			(xy 355.278926 -251.141673) (xy 355.281422 -251.161712) (xy 355.286056 -251.170694) (xy 355.327712 -251.243084)
			(xy 355.332478 -251.250647) (xy 355.346176 -251.262117) (xy 355.362974 -251.2682) (xy 355.371908 -251.268484)
			(xy 355.753924 -251.268484) (xy 355.759512 -251.26823) (xy 355.759766 -251.268484) (xy 356.288086 -251.268484)
			(xy 356.297065 -251.267463) (xy 356.313461 -251.259897) (xy 356.32009 -251.253752) (xy 356.58806 -250.985782)
			(xy 356.59568 -250.968002) (xy 356.595934 -250.957842) (xy 356.596998 -250.93187) (xy 356.606862 -250.880839)
			(xy 356.625222 -250.832214) (xy 356.651549 -250.787399) (xy 356.685083 -250.747687) (xy 356.724856 -250.714226)
			(xy 356.769719 -250.687981) (xy 356.818378 -250.66971) (xy 356.869427 -250.659939) (xy 356.8954 -250.658884)
			(xy 356.905306 -250.65863) (xy 356.93096 -250.647708) (xy 356.936548 -250.642374) (xy 356.9462 -250.63831)
			(xy 357.154226 -250.63831) (xy 357.164067 -250.637782) (xy 357.182241 -250.630208) (xy 357.189532 -250.623578)
			(xy 357.237792 -250.575318) (xy 357.245677 -250.566675) (xy 357.253222 -250.544561) (xy 357.25227 -250.5329)
			(xy 357.240586 -250.443492) (xy 357.227886 -250.424188) (xy 357.217472 -250.418092) (xy 357.194814 -250.404211)
			(xy 357.154241 -250.369906) (xy 357.120209 -250.329104) (xy 357.093742 -250.283033) (xy 357.075636 -250.233081)
			(xy 357.066438 -250.180752) (xy 357.065834 -250.154186) (xy 357.066281 -250.130195) (xy 357.07379 -250.082803)
			(xy 357.08862 -250.03717) (xy 357.110407 -249.994419) (xy 357.138614 -249.955603) (xy 357.172546 -249.921677)
			(xy 357.211367 -249.893478) (xy 357.254122 -249.871699) (xy 357.299758 -249.856877) (xy 357.347151 -249.849377)
			(xy 357.371142 -249.848878) (xy 357.397211 -249.849403) (xy 357.448593 -249.85825) (xy 357.497725 -249.875697)
			(xy 357.543179 -249.901236) (xy 357.583634 -249.934126) (xy 357.617914 -249.97341) (xy 357.645023 -250.017946)
			(xy 357.664172 -250.06644) (xy 357.674805 -250.117482) (xy 357.676196 -250.143518) (xy 357.67645 -250.149106)
			(xy 357.67645 -250.154186) (xy 357.675969 -250.178631) (xy 357.668181 -250.226898) (xy 357.652801 -250.273307)
			(xy 357.630223 -250.316672) (xy 357.615998 -250.336558) (xy 357.607362 -250.348242) (xy 357.604822 -250.37669)
			(xy 357.650796 -250.468638) (xy 357.655377 -250.476876) (xy 357.669289 -250.489571) (xy 357.686846 -250.496385)
			(xy 357.696262 -250.496832) (xy 360.799634 -250.496832) (xy 360.809069 -250.496465) (xy 360.826667 -250.489657)
			(xy 360.840606 -250.47694) (xy 360.8451 -250.468638) (xy 360.891074 -250.37669) (xy 360.888534 -250.348242)
			(xy 360.879898 -250.336558) (xy 360.865681 -250.316666) (xy 360.843097 -250.273304) (xy 360.827714 -250.226897)
			(xy 360.819923 -250.178631) (xy 360.819446 -250.154186) (xy 360.819446 -250.149106) (xy 360.8197 -250.143518)
			(xy 360.821038 -250.118861) (xy 360.830684 -250.070434) (xy 360.848 -250.024191) (xy 360.872533 -249.981339)
			(xy 360.903644 -249.942994) (xy 360.940522 -249.910158) (xy 360.982204 -249.883685) (xy 361.027604 -249.864267)
			(xy 361.075537 -249.85241) (xy 361.124754 -249.848423) (xy 361.173971 -249.85241) (xy 361.221904 -249.864267)
			(xy 361.267304 -249.883685) (xy 361.308986 -249.910158) (xy 361.345864 -249.942994) (xy 361.376975 -249.981339)
			(xy 361.401508 -250.024191) (xy 361.418824 -250.070434) (xy 361.42847 -250.118861) (xy 361.429808 -250.143518)
			(xy 361.430062 -250.149106) (xy 361.430062 -250.154186) (xy 361.429581 -250.178632) (xy 361.421793 -250.226898)
			(xy 361.406414 -250.273308) (xy 361.383837 -250.316673) (xy 361.36961 -250.336558) (xy 361.360974 -250.348242)
			(xy 361.358434 -250.37669) (xy 361.404408 -250.468638) (xy 361.40899 -250.476875) (xy 361.422902 -250.489566)
			(xy 361.440459 -250.496376) (xy 361.449874 -250.496832) (xy 362.679742 -250.496832) (xy 362.689176 -250.496464)
			(xy 362.706772 -250.489654) (xy 362.720709 -250.476937) (xy 362.725208 -250.468638) (xy 362.771182 -250.37669)
			(xy 362.768642 -250.348242) (xy 362.760006 -250.336558) (xy 362.745793 -250.316664) (xy 362.723216 -250.273301)
			(xy 362.707837 -250.226895) (xy 362.700049 -250.17863) (xy 362.699554 -250.154186) (xy 362.699554 -250.149106)
			(xy 362.699808 -250.143518) (xy 362.701249 -250.117486) (xy 362.711891 -250.066452) (xy 362.731043 -250.017965)
			(xy 362.758148 -249.973433) (xy 362.79242 -249.934149) (xy 362.832864 -249.901254) (xy 362.878305 -249.875702)
			(xy 362.927424 -249.858236) (xy 362.978796 -249.849362) (xy 363.004862 -249.848878) (xy 363.028857 -249.849321)
			(xy 363.076258 -249.856823) (xy 363.121902 -249.871648) (xy 363.164664 -249.893431) (xy 363.203493 -249.921636)
			(xy 363.23743 -249.955568) (xy 363.265641 -249.994391) (xy 363.287432 -250.03715) (xy 363.302265 -250.082791)
			(xy 363.309775 -250.130191) (xy 363.31017 -250.154186) (xy 364.578912 -250.154186) (xy 364.582872 -250.105132)
			(xy 364.594649 -250.057348) (xy 364.61394 -250.012072) (xy 364.640243 -249.970476) (xy 364.672878 -249.933639)
			(xy 364.710999 -249.902514) (xy 364.75362 -249.877907) (xy 364.799636 -249.860455) (xy 364.847855 -249.850611)
			(xy 364.89703 -249.84863) (xy 364.945885 -249.854562) (xy 364.993156 -249.868254) (xy 365.037618 -249.889352)
			(xy 365.078121 -249.917308) (xy 365.113614 -249.9514) (xy 365.143179 -249.990744) (xy 365.16605 -250.034321)
			(xy 365.181634 -250.081002) (xy 365.189529 -250.129579) (xy 365.190024 -250.154186) (xy 365.189529 -250.178793)
			(xy 365.181634 -250.22737) (xy 365.16605 -250.274051) (xy 365.143179 -250.317628) (xy 365.113614 -250.356972)
			(xy 365.078121 -250.391064) (xy 365.037618 -250.41902) (xy 364.993156 -250.440118) (xy 364.945885 -250.45381)
			(xy 364.89703 -250.459742) (xy 364.847855 -250.457761) (xy 364.799636 -250.447917) (xy 364.75362 -250.430465)
			(xy 364.710999 -250.405858) (xy 364.672878 -250.374733) (xy 364.640243 -250.337896) (xy 364.61394 -250.2963)
			(xy 364.594649 -250.251024) (xy 364.582872 -250.20324) (xy 364.578912 -250.154186) (xy 363.31017 -250.154186)
			(xy 363.309689 -250.178636) (xy 363.301898 -250.226911) (xy 363.286514 -250.273328) (xy 363.263929 -250.3167)
			(xy 363.234721 -250.355919) (xy 363.199637 -250.389981) (xy 363.179868 -250.404376) (xy 363.169454 -250.411488)
			(xy 363.158024 -250.433586) (xy 363.158024 -250.446032) (xy 363.158518 -250.456034) (xy 363.166184 -250.47451)
			(xy 363.180337 -250.488647) (xy 363.198822 -250.496293) (xy 363.208824 -250.496832) (xy 363.263942 -250.496832)
			(xy 363.273781 -250.497364) (xy 363.291946 -250.504947) (xy 363.299248 -250.511564) (xy 363.411008 -250.623324)
			(xy 363.418403 -250.630177) (xy 363.437002 -250.637921) (xy 363.447076 -250.63831) (xy 363.518958 -250.63831)
			(xy 363.528796 -250.638844) (xy 363.546959 -250.646429) (xy 363.554264 -250.653042) (xy 363.577886 -250.676664)
			(xy 363.587538 -250.680474) (xy 363.610471 -250.690114) (xy 363.65311 -250.715734) (xy 363.691031 -250.747927)
			(xy 363.723232 -250.785842) (xy 363.74886 -250.828475) (xy 363.75848 -250.851416) (xy 363.76229 -250.861068)
			(xy 364.159546 -251.258324) (xy 364.166943 -251.265172) (xy 364.185542 -251.272901) (xy 364.195614 -251.27331)
			(xy 364.788958 -251.27331) (xy 364.798797 -251.272777) (xy 364.816962 -251.265194) (xy 364.824264 -251.258578)
			(xy 365.037624 -251.045218) (xy 365.044889 -251.037186) (xy 365.052504 -251.016932) (xy 365.052356 -251.006102)
			(xy 365.052102 -251.003816) (xy 365.051848 -251.002292) (xy 365.050755 -250.992805) (xy 365.049614 -250.973741)
			(xy 365.049562 -250.964192) (xy 365.050033 -250.9402) (xy 365.05754 -250.892808) (xy 365.072368 -250.847173)
			(xy 365.094151 -250.804419) (xy 365.122354 -250.765599) (xy 365.156282 -250.731669) (xy 365.1951 -250.703463)
			(xy 365.237853 -250.681676) (xy 365.283486 -250.666845) (xy 365.330878 -250.659335) (xy 365.35487 -250.658884)
			(xy 365.36455 -250.658986) (xy 365.383868 -250.660259) (xy 365.393478 -250.661424) (xy 365.405416 -250.662948)
			(xy 365.427514 -250.655328) (xy 365.6838 -250.399042) (xy 365.69104 -250.392332) (xy 365.709244 -250.384741)
			(xy 365.719106 -250.38431) (xy 366.380776 -250.38431) (xy 366.392871 -250.38357) (xy 366.414356 -250.372437)
			(xy 366.421924 -250.362974) (xy 366.475772 -250.287536) (xy 366.479328 -250.263406) (xy 366.475518 -250.251722)
			(xy 366.468048 -250.228033) (xy 366.460012 -250.17902) (xy 366.459516 -250.154186) (xy 366.459963 -250.130194)
			(xy 366.467472 -250.082802) (xy 366.482302 -250.037168) (xy 366.504088 -249.994415) (xy 366.532295 -249.955597)
			(xy 366.566226 -249.92167) (xy 366.605048 -249.893469) (xy 366.647803 -249.871687) (xy 366.693439 -249.856863)
			(xy 366.740832 -249.84936) (xy 366.764824 -249.848878) (xy 366.79048 -249.849406) (xy 366.84107 -249.857987)
			(xy 366.889513 -249.874905) (xy 366.934446 -249.899683) (xy 366.974605 -249.931623) (xy 367.00886 -249.969827)
			(xy 367.036247 -250.013219) (xy 367.055994 -250.060579) (xy 367.067547 -250.110574) (xy 367.069624 -250.136152)
			(xy 367.069878 -250.142502) (xy 367.070132 -250.154186) (xy 368.338874 -250.154186) (xy 368.342834 -250.105132)
			(xy 368.354611 -250.057348) (xy 368.373902 -250.012072) (xy 368.400205 -249.970476) (xy 368.43284 -249.933639)
			(xy 368.470961 -249.902514) (xy 368.513582 -249.877907) (xy 368.559598 -249.860455) (xy 368.607817 -249.850611)
			(xy 368.656992 -249.84863) (xy 368.705847 -249.854562) (xy 368.753118 -249.868254) (xy 368.79758 -249.889352)
			(xy 368.838083 -249.917308) (xy 368.873576 -249.9514) (xy 368.903141 -249.990744) (xy 368.926012 -250.034321)
			(xy 368.941596 -250.081002) (xy 368.949491 -250.129579) (xy 368.949986 -250.154186) (xy 368.949491 -250.178793)
			(xy 368.941596 -250.22737) (xy 368.926012 -250.274051) (xy 368.903141 -250.317628) (xy 368.873576 -250.356972)
			(xy 368.838083 -250.391064) (xy 368.79758 -250.41902) (xy 368.753118 -250.440118) (xy 368.705847 -250.45381)
			(xy 368.656992 -250.459742) (xy 368.607817 -250.457761) (xy 368.559598 -250.447917) (xy 368.513582 -250.430465)
			(xy 368.470961 -250.405858) (xy 368.43284 -250.374733) (xy 368.400205 -250.337896) (xy 368.373902 -250.2963)
			(xy 368.354611 -250.251024) (xy 368.342834 -250.20324) (xy 368.338874 -250.154186) (xy 367.070132 -250.154186)
			(xy 367.06968 -250.178548) (xy 367.061979 -250.226658) (xy 367.046724 -250.272931) (xy 367.024302 -250.316188)
			(xy 367.010188 -250.33605) (xy 367.005303 -250.343244) (xy 367.000232 -250.359866) (xy 367.000282 -250.368562)
			(xy 367.001552 -250.398534) (xy 367.002397 -250.407902) (xy 367.009951 -250.425109) (xy 367.016284 -250.432062)
			(xy 367.223294 -250.639072) (xy 367.226491 -250.642168) (xy 367.233772 -250.647283) (xy 367.237772 -250.649232)
			(xy 367.260632 -250.659646) (xy 367.26876 -250.660662) (xy 367.294278 -250.664061) (xy 367.343746 -250.678295)
			(xy 367.390128 -250.700619) (xy 367.432112 -250.730402) (xy 367.468509 -250.766802) (xy 367.49829 -250.808787)
			(xy 367.520612 -250.855171) (xy 367.534842 -250.90464) (xy 367.538254 -250.930156) (xy 367.53927 -250.938284)
			(xy 367.549684 -250.961144) (xy 367.551664 -250.965126) (xy 367.556771 -250.972407) (xy 367.559844 -250.975622)
			(xy 367.842546 -251.258324) (xy 367.849943 -251.265172) (xy 367.868542 -251.272901) (xy 367.878614 -251.27331)
			(xy 368.471958 -251.27331) (xy 368.481797 -251.272777) (xy 368.499962 -251.265194) (xy 368.507264 -251.258578)
			(xy 368.789712 -250.97613) (xy 368.792807 -250.972933) (xy 368.797921 -250.965652) (xy 368.799872 -250.961652)
			(xy 368.810286 -250.938792) (xy 368.811302 -250.930664) (xy 368.814669 -250.905084) (xy 368.828873 -250.855486)
			(xy 368.851209 -250.808982) (xy 368.881043 -250.766892) (xy 368.917525 -250.730414) (xy 368.95962 -250.700586)
			(xy 369.006128 -250.678257) (xy 369.055727 -250.664061) (xy 369.081304 -250.660662) (xy 369.089432 -250.659646)
			(xy 369.112292 -250.649232) (xy 369.116273 -250.64725) (xy 369.12355 -250.642139) (xy 369.12677 -250.639072)
			(xy 369.3668 -250.399042) (xy 369.37404 -250.392332) (xy 369.392244 -250.384741) (xy 369.402106 -250.38431)
			(xy 370.140738 -250.38431) (xy 370.152838 -250.383578) (xy 370.174336 -250.372454) (xy 370.181886 -250.362974)
			(xy 370.235734 -250.287536) (xy 370.23929 -250.263406) (xy 370.23548 -250.251722) (xy 370.228011 -250.228033)
			(xy 370.219976 -250.17902) (xy 370.219478 -250.154186) (xy 370.21995 -250.130195) (xy 370.227457 -250.082804)
			(xy 370.242286 -250.037171) (xy 370.26407 -249.994419) (xy 370.292273 -249.955602) (xy 370.326202 -249.921673)
			(xy 370.365019 -249.89347) (xy 370.407771 -249.871686) (xy 370.453404 -249.856857) (xy 370.500795 -249.84935)
			(xy 370.524786 -249.848878) (xy 370.548484 -249.849332) (xy 370.59531 -249.856667) (xy 370.640441 -249.871148)
			(xy 370.682793 -249.892427) (xy 370.72135 -249.919993) (xy 370.755185 -249.953184) (xy 370.783487 -249.991203)
			(xy 370.805576 -250.033139) (xy 370.820921 -250.077983) (xy 370.829155 -250.124659) (xy 370.830094 -250.148344)
			(xy 370.830094 -250.154186) (xy 372.09909 -250.154186) (xy 372.10305 -250.105132) (xy 372.114827 -250.057348)
			(xy 372.134118 -250.012072) (xy 372.160421 -249.970476) (xy 372.193056 -249.933639) (xy 372.231177 -249.902514)
			(xy 372.273798 -249.877907) (xy 372.319814 -249.860455) (xy 372.368033 -249.850611) (xy 372.417208 -249.84863)
			(xy 372.466063 -249.854562) (xy 372.513334 -249.868254) (xy 372.557796 -249.889352) (xy 372.598299 -249.917308)
			(xy 372.633792 -249.9514) (xy 372.663357 -249.990744) (xy 372.686228 -250.034321) (xy 372.701812 -250.081002)
			(xy 372.709707 -250.129579) (xy 372.710202 -250.154186) (xy 372.709707 -250.178793) (xy 372.701812 -250.22737)
			(xy 372.686228 -250.274051) (xy 372.663357 -250.317628) (xy 372.633792 -250.356972) (xy 372.598299 -250.391064)
			(xy 372.557796 -250.41902) (xy 372.513334 -250.440118) (xy 372.466063 -250.45381) (xy 372.417208 -250.459742)
			(xy 372.368033 -250.457761) (xy 372.319814 -250.447917) (xy 372.273798 -250.430465) (xy 372.231177 -250.405858)
			(xy 372.193056 -250.374733) (xy 372.160421 -250.337896) (xy 372.134118 -250.2963) (xy 372.114827 -250.251024)
			(xy 372.10305 -250.20324) (xy 372.09909 -250.154186) (xy 370.830094 -250.154186) (xy 370.830094 -250.15444)
			(xy 370.82952 -250.181875) (xy 370.819726 -250.235864) (xy 370.800444 -250.287234) (xy 370.772293 -250.334332)
			(xy 370.754656 -250.355354) (xy 370.748306 -250.36272) (xy 370.741702 -250.380754) (xy 370.744496 -250.45797)
			(xy 370.745222 -250.46748) (xy 370.752788 -250.484972) (xy 370.759228 -250.492006) (xy 370.92255 -250.655328)
			(xy 370.944394 -250.662694) (xy 370.956332 -250.661424) (xy 370.965878 -250.660258) (xy 370.98507 -250.658988)
			(xy 370.994686 -250.658884) (xy 371.01868 -250.659329) (xy 371.066078 -250.666834) (xy 371.111718 -250.681661)
			(xy 371.154476 -250.703446) (xy 371.193301 -250.731651) (xy 371.227235 -250.765583) (xy 371.255443 -250.804405)
			(xy 371.27723 -250.847162) (xy 371.292061 -250.892801) (xy 371.299569 -250.940198) (xy 371.299994 -250.964192)
			(xy 371.299885 -250.973808) (xy 371.298612 -250.992999) (xy 371.297454 -251.002546) (xy 371.296184 -251.014484)
			(xy 371.30355 -251.036328) (xy 371.398546 -251.131324) (xy 371.405943 -251.138172) (xy 371.424542 -251.145901)
			(xy 371.434614 -251.14631) (xy 372.476014 -251.14631) (xy 372.487251 -251.145722) (xy 372.507555 -251.13609)
			(xy 372.51513 -251.127768) (xy 372.57228 -251.057918) (xy 372.577868 -251.036074) (xy 372.575582 -251.024644)
			(xy 372.572739 -251.009692) (xy 372.569681 -250.97941) (xy 372.569486 -250.964192) (xy 372.569957 -250.940201)
			(xy 372.577464 -250.89281) (xy 372.592292 -250.847177) (xy 372.614076 -250.804425) (xy 372.64228 -250.765607)
			(xy 372.676208 -250.731678) (xy 372.715026 -250.703475) (xy 372.757778 -250.681692) (xy 372.803412 -250.666864)
			(xy 372.850803 -250.659357) (xy 372.874794 -250.658884) (xy 372.899354 -250.659374) (xy 372.947842 -250.667232)
			(xy 372.994448 -250.682747) (xy 373.037971 -250.70552) (xy 373.057928 -250.719844) (xy 373.073168 -250.731274)
			(xy 373.11076 -250.72848) (xy 374.443244 -249.395996) (xy 374.451118 -249.375422) (xy 374.450356 -249.3645)
			(xy 374.449594 -249.34418) (xy 374.450013 -249.321079) (xy 374.456968 -249.275403) (xy 374.470729 -249.231298)
			(xy 374.490983 -249.189771) (xy 374.517267 -249.151774) (xy 374.548979 -249.118173) (xy 374.566942 -249.103642)
			(xy 374.57577 -249.09605) (xy 374.585952 -249.075141) (xy 374.5865 -249.06351) (xy 374.5865 -248.511822)
			(xy 374.586062 -248.501758) (xy 374.578328 -248.483174) (xy 374.571514 -248.475754) (xy 374.438926 -248.343166)
			(xy 374.431527 -248.336324) (xy 374.412928 -248.328606) (xy 374.402858 -248.32818) (xy 372.798086 -248.32818)
			(xy 372.786423 -248.328756) (xy 372.765514 -248.339091) (xy 372.757954 -248.347992) (xy 372.701566 -248.421398)
			(xy 372.696994 -248.444258) (xy 372.700042 -248.455942) (xy 372.704809 -248.475147) (xy 372.709903 -248.514388)
			(xy 372.710202 -248.534174) (xy 372.70968 -248.559429) (xy 372.701367 -248.609251) (xy 372.684966 -248.657025)
			(xy 372.660925 -248.701448) (xy 372.629901 -248.741308) (xy 372.592739 -248.775518) (xy 372.550453 -248.803144)
			(xy 372.504197 -248.823434) (xy 372.455232 -248.835834) (xy 372.404894 -248.840005) (xy 372.354556 -248.835834)
			(xy 372.305591 -248.823434) (xy 372.259335 -248.803144) (xy 372.217049 -248.775518) (xy 372.179887 -248.741308)
			(xy 372.148863 -248.701448) (xy 372.124822 -248.657025) (xy 372.108421 -248.609251) (xy 372.100108 -248.559429)
			(xy 372.099586 -248.534174) (xy 372.099902 -248.51439) (xy 372.104998 -248.475151) (xy 372.109746 -248.455942)
			(xy 372.112794 -248.444258) (xy 372.108222 -248.421398) (xy 372.051834 -248.347992) (xy 372.044247 -248.339133)
			(xy 372.023349 -248.328827) (xy 372.011702 -248.32818) (xy 369.977924 -248.32818) (xy 369.966257 -248.328748)
			(xy 369.945335 -248.339073) (xy 369.937792 -248.347992) (xy 369.881404 -248.421398) (xy 369.876832 -248.444258)
			(xy 369.87988 -248.455942) (xy 369.884648 -248.475147) (xy 369.889743 -248.514388) (xy 369.89004 -248.534174)
			(xy 369.889518 -248.559429) (xy 369.881205 -248.609251) (xy 369.864804 -248.657025) (xy 369.840763 -248.701448)
			(xy 369.809739 -248.741308) (xy 369.772577 -248.775518) (xy 369.730291 -248.803144) (xy 369.684035 -248.823434)
			(xy 369.63507 -248.835834) (xy 369.584732 -248.840005) (xy 369.534394 -248.835834) (xy 369.485429 -248.823434)
			(xy 369.439173 -248.803144) (xy 369.396887 -248.775518) (xy 369.359725 -248.741308) (xy 369.328701 -248.701448)
			(xy 369.30466 -248.657025) (xy 369.288259 -248.609251) (xy 369.279946 -248.559429) (xy 369.279424 -248.534174)
			(xy 369.27974 -248.51439) (xy 369.284837 -248.475151) (xy 369.289584 -248.455942) (xy 369.292632 -248.444258)
			(xy 369.28806 -248.421398) (xy 369.231672 -248.347992) (xy 369.224088 -248.339126) (xy 369.20319 -248.328805)
			(xy 369.19154 -248.32818) (xy 367.158016 -248.32818) (xy 367.14635 -248.32875) (xy 367.12543 -248.339077)
			(xy 367.117884 -248.347992) (xy 367.061496 -248.421398) (xy 367.056924 -248.444258) (xy 367.059972 -248.455942)
			(xy 367.06474 -248.475147) (xy 367.069836 -248.514388) (xy 367.070132 -248.534174) (xy 367.06961 -248.559429)
			(xy 367.061297 -248.609251) (xy 367.044896 -248.657025) (xy 367.020855 -248.701448) (xy 366.989831 -248.741308)
			(xy 366.952669 -248.775518) (xy 366.910383 -248.803144) (xy 366.864127 -248.823434) (xy 366.815162 -248.835834)
			(xy 366.764824 -248.840005) (xy 366.714486 -248.835834) (xy 366.665521 -248.823434) (xy 366.619265 -248.803144)
			(xy 366.576979 -248.775518) (xy 366.539817 -248.741308) (xy 366.508793 -248.701448) (xy 366.484752 -248.657025)
			(xy 366.468351 -248.609251) (xy 366.460038 -248.559429) (xy 366.459516 -248.534174) (xy 366.459832 -248.51439)
			(xy 366.464929 -248.475151) (xy 366.469676 -248.455942) (xy 366.472724 -248.444258) (xy 366.468152 -248.421398)
			(xy 366.411764 -248.347992) (xy 366.404179 -248.339128) (xy 366.383281 -248.32881) (xy 366.371632 -248.32818)
			(xy 364.489492 -248.32818) (xy 364.479422 -248.328604) (xy 364.460818 -248.336318) (xy 364.453424 -248.343166)
			(xy 364.257082 -248.539508) (xy 364.249716 -248.555256) (xy 364.2487 -248.564146) (xy 364.245585 -248.590202)
			(xy 364.231588 -248.640772) (xy 364.209153 -248.688205) (xy 364.178942 -248.731106) (xy 364.141841 -248.768212)
			(xy 364.098945 -248.79843) (xy 364.051515 -248.820872) (xy 364.000947 -248.834876) (xy 363.974888 -248.837958)
			(xy 363.965998 -248.838974) (xy 363.95025 -248.84634) (xy 363.773466 -249.023124) (xy 363.766069 -249.029973)
			(xy 363.74747 -249.037707) (xy 363.737398 -249.03811) (xy 363.723174 -249.03811) (xy 363.713171 -249.038603)
			(xy 363.694689 -249.046267) (xy 363.680547 -249.06042) (xy 363.672896 -249.078906) (xy 363.672374 -249.08891)
			(xy 363.672374 -249.099324) (xy 363.679994 -249.117866) (xy 363.687614 -249.125232) (xy 363.704784 -249.14261)
			(xy 363.733927 -249.181815) (xy 363.756464 -249.225156) (xy 363.771822 -249.27153) (xy 363.77961 -249.319755)
			(xy 363.78007 -249.34418) (xy 365.049066 -249.34418) (xy 365.053026 -249.295126) (xy 365.064803 -249.247342)
			(xy 365.084094 -249.202066) (xy 365.110397 -249.16047) (xy 365.143032 -249.123633) (xy 365.181153 -249.092508)
			(xy 365.223774 -249.067901) (xy 365.26979 -249.050449) (xy 365.318009 -249.040605) (xy 365.367184 -249.038624)
			(xy 365.416039 -249.044556) (xy 365.46331 -249.058248) (xy 365.507772 -249.079346) (xy 365.548275 -249.107302)
			(xy 365.583768 -249.141394) (xy 365.613333 -249.180738) (xy 365.636204 -249.224315) (xy 365.651788 -249.270996)
			(xy 365.659683 -249.319573) (xy 365.660178 -249.34418) (xy 366.92892 -249.34418) (xy 366.93288 -249.295126)
			(xy 366.944657 -249.247342) (xy 366.963948 -249.202066) (xy 366.990251 -249.16047) (xy 367.022886 -249.123633)
			(xy 367.061007 -249.092508) (xy 367.103628 -249.067901) (xy 367.149644 -249.050449) (xy 367.197863 -249.040605)
			(xy 367.247038 -249.038624) (xy 367.295893 -249.044556) (xy 367.343164 -249.058248) (xy 367.387626 -249.079346)
			(xy 367.428129 -249.107302) (xy 367.463622 -249.141394) (xy 367.493187 -249.180738) (xy 367.516058 -249.224315)
			(xy 367.531642 -249.270996) (xy 367.539537 -249.319573) (xy 367.540032 -249.34418) (xy 368.809028 -249.34418)
			(xy 368.812988 -249.295126) (xy 368.824765 -249.247342) (xy 368.844056 -249.202066) (xy 368.870359 -249.16047)
			(xy 368.902994 -249.123633) (xy 368.941115 -249.092508) (xy 368.983736 -249.067901) (xy 369.029752 -249.050449)
			(xy 369.077971 -249.040605) (xy 369.127146 -249.038624) (xy 369.176001 -249.044556) (xy 369.223272 -249.058248)
			(xy 369.267734 -249.079346) (xy 369.308237 -249.107302) (xy 369.34373 -249.141394) (xy 369.373295 -249.180738)
			(xy 369.396166 -249.224315) (xy 369.41175 -249.270996) (xy 369.419645 -249.319573) (xy 369.42014 -249.34418)
			(xy 370.688882 -249.34418) (xy 370.692842 -249.295126) (xy 370.704619 -249.247342) (xy 370.72391 -249.202066)
			(xy 370.750213 -249.16047) (xy 370.782848 -249.123633) (xy 370.820969 -249.092508) (xy 370.86359 -249.067901)
			(xy 370.909606 -249.050449) (xy 370.957825 -249.040605) (xy 371.007 -249.038624) (xy 371.055855 -249.044556)
			(xy 371.103126 -249.058248) (xy 371.147588 -249.079346) (xy 371.188091 -249.107302) (xy 371.223584 -249.141394)
			(xy 371.253149 -249.180738) (xy 371.27602 -249.224315) (xy 371.291604 -249.270996) (xy 371.299499 -249.319573)
			(xy 371.299994 -249.34418) (xy 372.56899 -249.34418) (xy 372.57295 -249.295126) (xy 372.584727 -249.247342)
			(xy 372.604018 -249.202066) (xy 372.630321 -249.16047) (xy 372.662956 -249.123633) (xy 372.701077 -249.092508)
			(xy 372.743698 -249.067901) (xy 372.789714 -249.050449) (xy 372.837933 -249.040605) (xy 372.887108 -249.038624)
			(xy 372.935963 -249.044556) (xy 372.983234 -249.058248) (xy 373.027696 -249.079346) (xy 373.068199 -249.107302)
			(xy 373.103692 -249.141394) (xy 373.133257 -249.180738) (xy 373.156128 -249.224315) (xy 373.171712 -249.270996)
			(xy 373.179607 -249.319573) (xy 373.180102 -249.34418) (xy 373.179607 -249.368787) (xy 373.171712 -249.417364)
			(xy 373.156128 -249.464045) (xy 373.133257 -249.507622) (xy 373.103692 -249.546966) (xy 373.068199 -249.581058)
			(xy 373.027696 -249.609014) (xy 372.983234 -249.630112) (xy 372.935963 -249.643804) (xy 372.887108 -249.649736)
			(xy 372.837933 -249.647755) (xy 372.789714 -249.637911) (xy 372.743698 -249.620459) (xy 372.701077 -249.595852)
			(xy 372.662956 -249.564727) (xy 372.630321 -249.52789) (xy 372.604018 -249.486294) (xy 372.584727 -249.441018)
			(xy 372.57295 -249.393234) (xy 372.56899 -249.34418) (xy 371.299994 -249.34418) (xy 371.299499 -249.368787)
			(xy 371.291604 -249.417364) (xy 371.27602 -249.464045) (xy 371.253149 -249.507622) (xy 371.223584 -249.546966)
			(xy 371.188091 -249.581058) (xy 371.147588 -249.609014) (xy 371.103126 -249.630112) (xy 371.055855 -249.643804)
			(xy 371.007 -249.649736) (xy 370.957825 -249.647755) (xy 370.909606 -249.637911) (xy 370.86359 -249.620459)
			(xy 370.820969 -249.595852) (xy 370.782848 -249.564727) (xy 370.750213 -249.52789) (xy 370.72391 -249.486294)
			(xy 370.704619 -249.441018) (xy 370.692842 -249.393234) (xy 370.688882 -249.34418) (xy 369.42014 -249.34418)
			(xy 369.419645 -249.368787) (xy 369.41175 -249.417364) (xy 369.396166 -249.464045) (xy 369.373295 -249.507622)
			(xy 369.34373 -249.546966) (xy 369.308237 -249.581058) (xy 369.267734 -249.609014) (xy 369.223272 -249.630112)
			(xy 369.176001 -249.643804) (xy 369.127146 -249.649736) (xy 369.077971 -249.647755) (xy 369.029752 -249.637911)
			(xy 368.983736 -249.620459) (xy 368.941115 -249.595852) (xy 368.902994 -249.564727) (xy 368.870359 -249.52789)
			(xy 368.844056 -249.486294) (xy 368.824765 -249.441018) (xy 368.812988 -249.393234) (xy 368.809028 -249.34418)
			(xy 367.540032 -249.34418) (xy 367.539537 -249.368787) (xy 367.531642 -249.417364) (xy 367.516058 -249.464045)
			(xy 367.493187 -249.507622) (xy 367.463622 -249.546966) (xy 367.428129 -249.581058) (xy 367.387626 -249.609014)
			(xy 367.343164 -249.630112) (xy 367.295893 -249.643804) (xy 367.247038 -249.649736) (xy 367.197863 -249.647755)
			(xy 367.149644 -249.637911) (xy 367.103628 -249.620459) (xy 367.061007 -249.595852) (xy 367.022886 -249.564727)
			(xy 366.990251 -249.52789) (xy 366.963948 -249.486294) (xy 366.944657 -249.441018) (xy 366.93288 -249.393234)
			(xy 366.92892 -249.34418) (xy 365.660178 -249.34418) (xy 365.659683 -249.368787) (xy 365.651788 -249.417364)
			(xy 365.636204 -249.464045) (xy 365.613333 -249.507622) (xy 365.583768 -249.546966) (xy 365.548275 -249.581058)
			(xy 365.507772 -249.609014) (xy 365.46331 -249.630112) (xy 365.416039 -249.643804) (xy 365.367184 -249.649736)
			(xy 365.318009 -249.647755) (xy 365.26979 -249.637911) (xy 365.223774 -249.620459) (xy 365.181153 -249.595852)
			(xy 365.143032 -249.564727) (xy 365.110397 -249.52789) (xy 365.084094 -249.486294) (xy 365.064803 -249.441018)
			(xy 365.053026 -249.393234) (xy 365.049066 -249.34418) (xy 363.78007 -249.34418) (xy 363.779548 -249.369435)
			(xy 363.771235 -249.419257) (xy 363.754834 -249.467031) (xy 363.730793 -249.511454) (xy 363.699769 -249.551314)
			(xy 363.662607 -249.585524) (xy 363.620321 -249.61315) (xy 363.574065 -249.63344) (xy 363.5251 -249.64584)
			(xy 363.474762 -249.650011) (xy 363.424424 -249.64584) (xy 363.375459 -249.63344) (xy 363.329203 -249.61315)
			(xy 363.286917 -249.585524) (xy 363.249755 -249.551314) (xy 363.218731 -249.511454) (xy 363.19469 -249.467031)
			(xy 363.178289 -249.419257) (xy 363.169976 -249.369435) (xy 363.169454 -249.34418) (xy 363.170109 -249.315481)
			(xy 363.180857 -249.259099) (xy 363.19079 -249.232166) (xy 363.195616 -249.219466) (xy 363.191806 -249.19305)
			(xy 363.120686 -249.102626) (xy 363.095794 -249.092466) (xy 363.082332 -249.094498) (xy 363.063062 -249.096995)
			(xy 363.024293 -249.099663) (xy 363.004862 -249.099832) (xy 362.70692 -249.099832) (xy 362.666869 -249.09912)
			(xy 362.587575 -249.087774) (xy 362.548932 -249.077226) (xy 362.541988 -249.075495) (xy 362.527682 -249.075495)
			(xy 362.520738 -249.077226) (xy 362.482092 -249.08776) (xy 362.402799 -249.099104) (xy 362.36275 -249.099832)
			(xy 362.064808 -249.099832) (xy 362.045377 -249.099667) (xy 362.006608 -249.096996) (xy 361.987338 -249.094498)
			(xy 361.973876 -249.092466) (xy 361.948984 -249.102626) (xy 361.877864 -249.19305) (xy 361.874054 -249.219466)
			(xy 361.87888 -249.232166) (xy 361.888796 -249.259103) (xy 361.899531 -249.315484) (xy 361.900216 -249.34418)
			(xy 361.899694 -249.369435) (xy 361.891381 -249.419257) (xy 361.87498 -249.467031) (xy 361.850939 -249.511454)
			(xy 361.819915 -249.551314) (xy 361.782753 -249.585524) (xy 361.740467 -249.61315) (xy 361.694211 -249.63344)
			(xy 361.645246 -249.64584) (xy 361.594908 -249.650011) (xy 361.54457 -249.64584) (xy 361.495605 -249.63344)
			(xy 361.449349 -249.61315) (xy 361.407063 -249.585524) (xy 361.369901 -249.551314) (xy 361.338877 -249.511454)
			(xy 361.314836 -249.467031) (xy 361.298435 -249.419257) (xy 361.290122 -249.369435) (xy 361.2896 -249.34418)
			(xy 361.290057 -249.319965) (xy 361.297687 -249.272141) (xy 361.31277 -249.226121) (xy 361.334926 -249.183057)
			(xy 361.363602 -249.14403) (xy 361.398077 -249.110018) (xy 361.437488 -249.081873) (xy 361.480847 -249.060301)
			(xy 361.527067 -249.045842) (xy 361.550966 -249.04192) (xy 361.564682 -249.040142) (xy 361.585764 -249.023378)
			(xy 361.628944 -248.916952) (xy 361.625388 -248.890282) (xy 361.617006 -248.87936) (xy 361.593903 -248.848369)
			(xy 361.555415 -248.781332) (xy 361.540298 -248.745756) (xy 361.535218 -248.733056) (xy 361.513628 -248.716292)
			(xy 361.399582 -248.70029) (xy 361.374182 -248.710704) (xy 361.3658 -248.721372) (xy 361.351258 -248.739421)
			(xy 361.317642 -248.771329) (xy 361.279587 -248.797786) (xy 361.237967 -248.818182) (xy 361.193742 -248.832049)
			(xy 361.147928 -248.839068) (xy 361.124754 -248.839482) (xy 361.099503 -248.838957) (xy 361.049692 -248.830638)
			(xy 361.001928 -248.814234) (xy 360.957516 -248.790194) (xy 360.917666 -248.759172) (xy 360.883465 -248.722014)
			(xy 360.855846 -248.679734) (xy 360.835561 -248.633486) (xy 360.823165 -248.584529) (xy 360.818995 -248.5342)
			(xy 360.823165 -248.483871) (xy 360.835561 -248.434914) (xy 360.855846 -248.388666) (xy 360.883465 -248.346386)
			(xy 360.917666 -248.309228) (xy 360.957516 -248.278206) (xy 361.001928 -248.254166) (xy 361.049692 -248.237762)
			(xy 361.099503 -248.229443) (xy 361.124754 -248.228866) (xy 361.147583 -248.229263) (xy 361.19273 -248.236062)
			(xy 361.236356 -248.249528) (xy 361.257088 -248.259092) (xy 361.26928 -248.264934) (xy 361.296204 -248.262902)
			(xy 361.30738 -248.255536) (xy 361.315439 -248.249547) (xy 361.326566 -248.232857) (xy 361.330468 -248.213182)
			(xy 361.326552 -248.19351) (xy 361.32135 -248.184924) (xy 361.279694 -248.122694) (xy 361.279186 -248.122186)
			(xy 360.74858 -247.350534) (xy 360.74858 -247.350026) (xy 360.057954 -246.328184) (xy 360.051604 -246.320564)
			(xy 359.593388 -245.862348) (xy 359.586276 -245.858792) (xy 359.56227 -245.846155) (xy 359.518231 -245.81448)
			(xy 359.479718 -245.776276) (xy 359.447689 -245.732493) (xy 359.422942 -245.684219) (xy 359.40609 -245.632655)
			(xy 359.397553 -245.579084) (xy 359.397046 -245.55196) (xy 359.3976 -245.524007) (xy 359.406669 -245.468841)
			(xy 359.42456 -245.415874) (xy 359.437178 -245.390924) (xy 359.439972 -245.385336) (xy 359.44302 -245.373398)
			(xy 359.44302 -236.926882) (xy 359.442594 -236.916813) (xy 359.434877 -236.898211) (xy 359.428034 -236.890814)
			(xy 358.782366 -236.245146) (xy 358.774968 -236.2383) (xy 358.756369 -236.230571) (xy 358.746298 -236.23016)
			(xy 358.244648 -236.23016) (xy 358.23374 -236.23061) (xy 358.213848 -236.239552) (xy 358.206294 -236.247432)
			(xy 358.148636 -236.312964) (xy 358.142286 -236.333792) (xy 358.14381 -236.344714) (xy 358.145007 -236.354512)
			(xy 358.146279 -236.374213) (xy 358.14635 -236.384084) (xy 358.145881 -236.408077) (xy 358.138377 -236.455473)
			(xy 358.123551 -236.501112) (xy 358.101769 -236.54387) (xy 358.073567 -236.582694) (xy 358.039639 -236.616629)
			(xy 358.00082 -236.644839) (xy 357.958066 -236.666629) (xy 357.91243 -236.681463) (xy 357.865035 -236.688976)
			(xy 357.841042 -236.689392) (xy 357.816806 -236.688923) (xy 357.768945 -236.681257) (xy 357.722896 -236.666127)
			(xy 357.679814 -236.643913) (xy 357.640783 -236.615173) (xy 357.606781 -236.580628) (xy 357.578663 -236.541146)
			(xy 357.557135 -236.497718) (xy 357.542737 -236.451434) (xy 357.538782 -236.427518) (xy 357.537512 -236.417612)
			(xy 357.528114 -236.401102) (xy 357.458264 -236.345222) (xy 357.44023 -236.339634) (xy 357.430324 -236.340396)
			(xy 357.415554 -236.341529) (xy 357.385955 -236.342801) (xy 357.371142 -236.342936) (xy 357.236522 -236.342936)
			(xy 357.207058 -236.371384) (xy 357.20655 -236.392212) (xy 357.205403 -236.417027) (xy 357.196062 -236.465816)
			(xy 357.178949 -236.512449) (xy 357.154515 -236.555699) (xy 357.123404 -236.594424) (xy 357.086437 -236.627604)
			(xy 357.044587 -236.654364) (xy 356.998957 -236.673999) (xy 356.950752 -236.685991) (xy 356.901242 -236.690024)
			(xy 356.851732 -236.685991) (xy 356.803527 -236.673999) (xy 356.757897 -236.654364) (xy 356.716047 -236.627604)
			(xy 356.67908 -236.594424) (xy 356.647969 -236.555699) (xy 356.623535 -236.512449) (xy 356.606422 -236.465816)
			(xy 356.597081 -236.417027) (xy 356.595934 -236.392212) (xy 356.595426 -236.371384) (xy 356.565962 -236.342936)
			(xy 356.431088 -236.342936) (xy 356.416275 -236.342803) (xy 356.386676 -236.341534) (xy 356.371906 -236.340396)
			(xy 356.362 -236.339634) (xy 356.343966 -236.345222) (xy 356.274116 -236.401102) (xy 356.264718 -236.417612)
			(xy 356.263448 -236.427518) (xy 356.259539 -236.451443) (xy 356.245147 -236.497734) (xy 356.22362 -236.541168)
			(xy 356.195498 -236.580653) (xy 356.161489 -236.615198) (xy 356.122448 -236.643933) (xy 356.079356 -236.666137)
			(xy 356.033296 -236.681251) (xy 355.985426 -236.688895) (xy 355.961188 -236.689392) (xy 355.937196 -236.688945)
			(xy 355.889803 -236.681437) (xy 355.844168 -236.666607) (xy 355.801415 -236.644821) (xy 355.762596 -236.616614)
			(xy 355.728667 -236.582683) (xy 355.700465 -236.543862) (xy 355.678683 -236.501106) (xy 355.663857 -236.45547)
			(xy 355.656353 -236.408076) (xy 355.65588 -236.384084) (xy 355.655962 -236.374213) (xy 355.657235 -236.354514)
			(xy 355.65842 -236.344714) (xy 355.659944 -236.333792) (xy 355.653594 -236.312964) (xy 355.595936 -236.247432)
			(xy 355.588346 -236.239602) (xy 355.568476 -236.230668) (xy 355.557582 -236.23016) (xy 353.544632 -236.23016)
			(xy 353.533725 -236.230613) (xy 353.513838 -236.239559) (xy 353.506278 -236.247432) (xy 353.44862 -236.312964)
			(xy 353.44227 -236.333792) (xy 353.443794 -236.344714) (xy 353.444991 -236.354512) (xy 353.446263 -236.374213)
			(xy 353.446334 -236.384084) (xy 353.445812 -236.409339) (xy 353.437499 -236.459161) (xy 353.421098 -236.506935)
			(xy 353.397057 -236.551358) (xy 353.366033 -236.591218) (xy 353.328871 -236.625428) (xy 353.286585 -236.653054)
			(xy 353.240329 -236.673344) (xy 353.191364 -236.685744) (xy 353.141026 -236.689915) (xy 353.090688 -236.685744)
			(xy 353.041723 -236.673344) (xy 352.995467 -236.653054) (xy 352.953181 -236.625428) (xy 352.916019 -236.591218)
			(xy 352.884995 -236.551358) (xy 352.860954 -236.506935) (xy 352.844553 -236.459161) (xy 352.83624 -236.409339)
			(xy 352.835718 -236.384084) (xy 352.8358 -236.374213) (xy 352.837074 -236.354514) (xy 352.838258 -236.344714)
			(xy 352.839782 -236.333792) (xy 352.833432 -236.312964) (xy 352.775774 -236.247432) (xy 352.768187 -236.239595)
			(xy 352.748317 -236.230647) (xy 352.73742 -236.23016) (xy 350.805242 -236.23016) (xy 350.795178 -236.230595)
			(xy 350.776594 -236.238331) (xy 350.769174 -236.245146) (xy 350.633792 -236.380528) (xy 350.626172 -236.397038)
			(xy 350.625664 -236.406182) (xy 350.623452 -236.430289) (xy 350.612378 -236.477414) (xy 350.594007 -236.522202)
			(xy 350.5688 -236.563529) (xy 350.537389 -236.600363) (xy 350.500559 -236.631779) (xy 350.459234 -236.656991)
			(xy 350.414449 -236.675367) (xy 350.367325 -236.686447) (xy 350.343216 -236.68863) (xy 350.334072 -236.689138)
			(xy 350.317562 -236.696758) (xy 350.072706 -236.941614) (xy 350.070928 -236.981238) (xy 350.083882 -236.996478)
			(xy 350.100867 -237.017331) (xy 350.127982 -237.063774) (xy 350.146534 -237.114252) (xy 350.155948 -237.1672)
			(xy 350.156526 -237.19409) (xy 350.485214 -237.19409) (xy 350.489174 -237.145036) (xy 350.500951 -237.097252)
			(xy 350.520242 -237.051976) (xy 350.546545 -237.01038) (xy 350.57918 -236.973543) (xy 350.617301 -236.942418)
			(xy 350.659922 -236.917811) (xy 350.705938 -236.900359) (xy 350.754157 -236.890515) (xy 350.803332 -236.888534)
			(xy 350.852187 -236.894466) (xy 350.899458 -236.908158) (xy 350.94392 -236.929256) (xy 350.984423 -236.957212)
			(xy 351.019916 -236.991304) (xy 351.049481 -237.030648) (xy 351.072352 -237.074225) (xy 351.087936 -237.120906)
			(xy 351.095831 -237.169483) (xy 351.096326 -237.19409) (xy 351.425268 -237.19409) (xy 351.429228 -237.145036)
			(xy 351.441005 -237.097252) (xy 351.460296 -237.051976) (xy 351.486599 -237.01038) (xy 351.519234 -236.973543)
			(xy 351.557355 -236.942418) (xy 351.599976 -236.917811) (xy 351.645992 -236.900359) (xy 351.694211 -236.890515)
			(xy 351.743386 -236.888534) (xy 351.792241 -236.894466) (xy 351.839512 -236.908158) (xy 351.883974 -236.929256)
			(xy 351.924477 -236.957212) (xy 351.95997 -236.991304) (xy 351.989535 -237.030648) (xy 352.012406 -237.074225)
			(xy 352.02799 -237.120906) (xy 352.035885 -237.169483) (xy 352.03638 -237.19409) (xy 352.365322 -237.19409)
			(xy 352.369282 -237.145036) (xy 352.381059 -237.097252) (xy 352.40035 -237.051976) (xy 352.426653 -237.01038)
			(xy 352.459288 -236.973543) (xy 352.497409 -236.942418) (xy 352.54003 -236.917811) (xy 352.586046 -236.900359)
			(xy 352.634265 -236.890515) (xy 352.68344 -236.888534) (xy 352.732295 -236.894466) (xy 352.779566 -236.908158)
			(xy 352.824028 -236.929256) (xy 352.864531 -236.957212) (xy 352.900024 -236.991304) (xy 352.929589 -237.030648)
			(xy 352.95246 -237.074225) (xy 352.968044 -237.120906) (xy 352.975939 -237.169483) (xy 352.976434 -237.19409)
			(xy 353.305376 -237.19409) (xy 353.309336 -237.145036) (xy 353.321113 -237.097252) (xy 353.340404 -237.051976)
			(xy 353.366707 -237.01038) (xy 353.399342 -236.973543) (xy 353.437463 -236.942418) (xy 353.480084 -236.917811)
			(xy 353.5261 -236.900359) (xy 353.574319 -236.890515) (xy 353.623494 -236.888534) (xy 353.672349 -236.894466)
			(xy 353.71962 -236.908158) (xy 353.764082 -236.929256) (xy 353.804585 -236.957212) (xy 353.840078 -236.991304)
			(xy 353.869643 -237.030648) (xy 353.892514 -237.074225) (xy 353.908098 -237.120906) (xy 353.915993 -237.169483)
			(xy 353.916488 -237.19409) (xy 354.24543 -237.19409) (xy 354.24939 -237.145036) (xy 354.261167 -237.097252)
			(xy 354.280458 -237.051976) (xy 354.306761 -237.01038) (xy 354.339396 -236.973543) (xy 354.377517 -236.942418)
			(xy 354.420138 -236.917811) (xy 354.466154 -236.900359) (xy 354.514373 -236.890515) (xy 354.563548 -236.888534)
			(xy 354.612403 -236.894466) (xy 354.659674 -236.908158) (xy 354.704136 -236.929256) (xy 354.744639 -236.957212)
			(xy 354.780132 -236.991304) (xy 354.809697 -237.030648) (xy 354.832568 -237.074225) (xy 354.848152 -237.120906)
			(xy 354.856047 -237.169483) (xy 354.856542 -237.19409) (xy 355.18523 -237.19409) (xy 355.18919 -237.145036)
			(xy 355.200967 -237.097252) (xy 355.220258 -237.051976) (xy 355.246561 -237.01038) (xy 355.279196 -236.973543)
			(xy 355.317317 -236.942418) (xy 355.359938 -236.917811) (xy 355.405954 -236.900359) (xy 355.454173 -236.890515)
			(xy 355.503348 -236.888534) (xy 355.552203 -236.894466) (xy 355.599474 -236.908158) (xy 355.643936 -236.929256)
			(xy 355.684439 -236.957212) (xy 355.719932 -236.991304) (xy 355.749497 -237.030648) (xy 355.772368 -237.074225)
			(xy 355.787952 -237.120906) (xy 355.795847 -237.169483) (xy 355.796342 -237.19409) (xy 358.005392 -237.19409)
			(xy 358.009352 -237.145036) (xy 358.021129 -237.097252) (xy 358.04042 -237.051976) (xy 358.066723 -237.01038)
			(xy 358.099358 -236.973543) (xy 358.137479 -236.942418) (xy 358.1801 -236.917811) (xy 358.226116 -236.900359)
			(xy 358.274335 -236.890515) (xy 358.32351 -236.888534) (xy 358.372365 -236.894466) (xy 358.419636 -236.908158)
			(xy 358.464098 -236.929256) (xy 358.504601 -236.957212) (xy 358.540094 -236.991304) (xy 358.569659 -237.030648)
			(xy 358.59253 -237.074225) (xy 358.608114 -237.120906) (xy 358.616009 -237.169483) (xy 358.616504 -237.19409)
			(xy 358.616009 -237.218697) (xy 358.608114 -237.267274) (xy 358.59253 -237.313955) (xy 358.569659 -237.357532)
			(xy 358.540094 -237.396876) (xy 358.504601 -237.430968) (xy 358.464098 -237.458924) (xy 358.419636 -237.480022)
			(xy 358.372365 -237.493714) (xy 358.32351 -237.499646) (xy 358.274335 -237.497665) (xy 358.226116 -237.487821)
			(xy 358.1801 -237.470369) (xy 358.137479 -237.445762) (xy 358.099358 -237.414637) (xy 358.066723 -237.3778)
			(xy 358.04042 -237.336204) (xy 358.021129 -237.290928) (xy 358.009352 -237.243144) (xy 358.005392 -237.19409)
			(xy 355.796342 -237.19409) (xy 355.795847 -237.218697) (xy 355.787952 -237.267274) (xy 355.772368 -237.313955)
			(xy 355.749497 -237.357532) (xy 355.719932 -237.396876) (xy 355.684439 -237.430968) (xy 355.643936 -237.458924)
			(xy 355.599474 -237.480022) (xy 355.552203 -237.493714) (xy 355.503348 -237.499646) (xy 355.454173 -237.497665)
			(xy 355.405954 -237.487821) (xy 355.359938 -237.470369) (xy 355.317317 -237.445762) (xy 355.279196 -237.414637)
			(xy 355.246561 -237.3778) (xy 355.220258 -237.336204) (xy 355.200967 -237.290928) (xy 355.18919 -237.243144)
			(xy 355.18523 -237.19409) (xy 354.856542 -237.19409) (xy 354.856047 -237.218697) (xy 354.848152 -237.267274)
			(xy 354.832568 -237.313955) (xy 354.809697 -237.357532) (xy 354.780132 -237.396876) (xy 354.744639 -237.430968)
			(xy 354.704136 -237.458924) (xy 354.659674 -237.480022) (xy 354.612403 -237.493714) (xy 354.563548 -237.499646)
			(xy 354.514373 -237.497665) (xy 354.466154 -237.487821) (xy 354.420138 -237.470369) (xy 354.377517 -237.445762)
			(xy 354.339396 -237.414637) (xy 354.306761 -237.3778) (xy 354.280458 -237.336204) (xy 354.261167 -237.290928)
			(xy 354.24939 -237.243144) (xy 354.24543 -237.19409) (xy 353.916488 -237.19409) (xy 353.915993 -237.218697)
			(xy 353.908098 -237.267274) (xy 353.892514 -237.313955) (xy 353.869643 -237.357532) (xy 353.840078 -237.396876)
			(xy 353.804585 -237.430968) (xy 353.764082 -237.458924) (xy 353.71962 -237.480022) (xy 353.672349 -237.493714)
			(xy 353.623494 -237.499646) (xy 353.574319 -237.497665) (xy 353.5261 -237.487821) (xy 353.480084 -237.470369)
			(xy 353.437463 -237.445762) (xy 353.399342 -237.414637) (xy 353.366707 -237.3778) (xy 353.340404 -237.336204)
			(xy 353.321113 -237.290928) (xy 353.309336 -237.243144) (xy 353.305376 -237.19409) (xy 352.976434 -237.19409)
			(xy 352.975939 -237.218697) (xy 352.968044 -237.267274) (xy 352.95246 -237.313955) (xy 352.929589 -237.357532)
			(xy 352.900024 -237.396876) (xy 352.864531 -237.430968) (xy 352.824028 -237.458924) (xy 352.779566 -237.480022)
			(xy 352.732295 -237.493714) (xy 352.68344 -237.499646) (xy 352.634265 -237.497665) (xy 352.586046 -237.487821)
			(xy 352.54003 -237.470369) (xy 352.497409 -237.445762) (xy 352.459288 -237.414637) (xy 352.426653 -237.3778)
			(xy 352.40035 -237.336204) (xy 352.381059 -237.290928) (xy 352.369282 -237.243144) (xy 352.365322 -237.19409)
			(xy 352.03638 -237.19409) (xy 352.035885 -237.218697) (xy 352.02799 -237.267274) (xy 352.012406 -237.313955)
			(xy 351.989535 -237.357532) (xy 351.95997 -237.396876) (xy 351.924477 -237.430968) (xy 351.883974 -237.458924)
			(xy 351.839512 -237.480022) (xy 351.792241 -237.493714) (xy 351.743386 -237.499646) (xy 351.694211 -237.497665)
			(xy 351.645992 -237.487821) (xy 351.599976 -237.470369) (xy 351.557355 -237.445762) (xy 351.519234 -237.414637)
			(xy 351.486599 -237.3778) (xy 351.460296 -237.336204) (xy 351.441005 -237.290928) (xy 351.429228 -237.243144)
			(xy 351.425268 -237.19409) (xy 351.096326 -237.19409) (xy 351.095831 -237.218697) (xy 351.087936 -237.267274)
			(xy 351.072352 -237.313955) (xy 351.049481 -237.357532) (xy 351.019916 -237.396876) (xy 350.984423 -237.430968)
			(xy 350.94392 -237.458924) (xy 350.899458 -237.480022) (xy 350.852187 -237.493714) (xy 350.803332 -237.499646)
			(xy 350.754157 -237.497665) (xy 350.705938 -237.487821) (xy 350.659922 -237.470369) (xy 350.617301 -237.445762)
			(xy 350.57918 -237.414637) (xy 350.546545 -237.3778) (xy 350.520242 -237.336204) (xy 350.500951 -237.290928)
			(xy 350.489174 -237.243144) (xy 350.485214 -237.19409) (xy 350.156526 -237.19409) (xy 350.156056 -237.218082)
			(xy 350.148551 -237.265476) (xy 350.133725 -237.311113) (xy 350.111942 -237.353868) (xy 350.083739 -237.39269)
			(xy 350.049811 -237.426621) (xy 350.010992 -237.454828) (xy 349.968239 -237.476614) (xy 349.922603 -237.491445)
			(xy 349.87521 -237.498954) (xy 349.851218 -237.499398) (xy 349.826965 -237.498933) (xy 349.779067 -237.491269)
			(xy 349.732984 -237.476129) (xy 349.689873 -237.453895) (xy 349.650819 -237.425126) (xy 349.616803 -237.390545)
			(xy 349.588681 -237.351021) (xy 349.567161 -237.30755) (xy 349.552783 -237.261223) (xy 349.548958 -237.23727)
			(xy 349.547688 -237.227618) (xy 349.53829 -237.211108) (xy 349.46844 -237.155228) (xy 349.450406 -237.14964)
			(xy 349.4405 -237.150402) (xy 349.425664 -237.151475) (xy 349.395938 -237.152616) (xy 349.381064 -237.152688)
			(xy 349.246444 -237.152688) (xy 349.21698 -237.18139) (xy 349.216472 -237.202218) (xy 349.215325 -237.227033)
			(xy 349.205984 -237.275822) (xy 349.188871 -237.322455) (xy 349.164437 -237.365705) (xy 349.133326 -237.40443)
			(xy 349.096359 -237.43761) (xy 349.054509 -237.46437) (xy 349.008879 -237.484005) (xy 348.960674 -237.495997)
			(xy 348.911164 -237.50003) (xy 348.861654 -237.495997) (xy 348.813449 -237.484005) (xy 348.767819 -237.46437)
			(xy 348.725969 -237.43761) (xy 348.689002 -237.40443) (xy 348.657891 -237.365705) (xy 348.633457 -237.322455)
			(xy 348.616344 -237.275822) (xy 348.607003 -237.227033) (xy 348.605856 -237.202218) (xy 348.605348 -237.18139)
			(xy 348.575884 -237.152688) (xy 348.44101 -237.152688) (xy 348.426199 -237.152617) (xy 348.3966 -237.151473)
			(xy 348.381828 -237.150402) (xy 348.371922 -237.14964) (xy 348.353888 -237.155228) (xy 348.284038 -237.211108)
			(xy 348.27464 -237.227618) (xy 348.27337 -237.237524) (xy 348.269461 -237.26145) (xy 348.255069 -237.307741)
			(xy 348.233541 -237.351176) (xy 348.20542 -237.390663) (xy 348.171411 -237.425209) (xy 348.13237 -237.453946)
			(xy 348.089278 -237.476152) (xy 348.043219 -237.491268) (xy 347.995349 -237.498916) (xy 347.97111 -237.499398)
			(xy 347.947357 -237.498947) (xy 347.900423 -237.491592) (xy 347.855194 -237.477059) (xy 347.812761 -237.455697)
			(xy 347.774148 -237.428022) (xy 347.740286 -237.394702) (xy 347.711992 -237.35654) (xy 347.689948 -237.314457)
			(xy 347.674687 -237.269469) (xy 347.666576 -237.22266) (xy 347.665802 -237.198916) (xy 347.665802 -237.188756)
			(xy 347.657928 -237.170468) (xy 347.600016 -237.113318) (xy 347.592578 -237.106708) (xy 347.574144 -237.099272)
			(xy 347.564202 -237.09884) (xy 347.437964 -237.09884) (xy 347.42802 -237.099259) (xy 347.409583 -237.106701)
			(xy 347.40215 -237.113318) (xy 347.344238 -237.170468) (xy 347.336364 -237.188756) (xy 347.336364 -237.198916)
			(xy 347.335537 -237.222658) (xy 347.32744 -237.269468) (xy 347.31219 -237.314459) (xy 347.290155 -237.356544)
			(xy 347.261868 -237.394709) (xy 347.22801 -237.428032) (xy 347.1894 -237.455708) (xy 347.146969 -237.47707)
			(xy 347.101741 -237.491602) (xy 347.054809 -237.498953) (xy 347.031056 -237.499398) (xy 347.00682 -237.49893)
			(xy 346.958956 -237.491266) (xy 346.912905 -237.476138) (xy 346.869821 -237.453925) (xy 346.830787 -237.425185)
			(xy 346.796783 -237.39064) (xy 346.768663 -237.351157) (xy 346.747132 -237.307728) (xy 346.732733 -237.261444)
			(xy 346.728796 -237.237524) (xy 346.727526 -237.227618) (xy 346.718128 -237.211108) (xy 346.648278 -237.155228)
			(xy 346.630244 -237.14964) (xy 346.620338 -237.150402) (xy 346.605566 -237.15147) (xy 346.575967 -237.152613)
			(xy 346.561156 -237.152688) (xy 346.426282 -237.152688) (xy 346.396818 -237.18139) (xy 346.39631 -237.202218)
			(xy 346.395163 -237.227033) (xy 346.385822 -237.275822) (xy 346.368709 -237.322455) (xy 346.344275 -237.365705)
			(xy 346.313164 -237.40443) (xy 346.276197 -237.43761) (xy 346.234347 -237.46437) (xy 346.188717 -237.484005)
			(xy 346.140512 -237.495997) (xy 346.091002 -237.50003) (xy 346.041492 -237.495997) (xy 345.993287 -237.484005)
			(xy 345.947657 -237.46437) (xy 345.905807 -237.43761) (xy 345.86884 -237.40443) (xy 345.837729 -237.365705)
			(xy 345.813295 -237.322455) (xy 345.796182 -237.275822) (xy 345.786841 -237.227033) (xy 345.785694 -237.202218)
			(xy 345.785186 -237.18139) (xy 345.755722 -237.152688) (xy 345.621102 -237.152688) (xy 345.606291 -237.152617)
			(xy 345.576692 -237.151472) (xy 345.56192 -237.150402) (xy 345.552014 -237.14964) (xy 345.53398 -237.155228)
			(xy 345.46413 -237.211108) (xy 345.454732 -237.227618) (xy 345.453462 -237.237524) (xy 345.449553 -237.26145)
			(xy 345.435161 -237.30774) (xy 345.413633 -237.351174) (xy 345.385511 -237.39066) (xy 345.351503 -237.425206)
			(xy 345.312462 -237.453942) (xy 345.26937 -237.476147) (xy 345.22331 -237.491262) (xy 345.17544 -237.498908)
			(xy 345.151202 -237.499398) (xy 345.125958 -237.498905) (xy 345.076159 -237.490591) (xy 345.028408 -237.47419)
			(xy 344.984011 -237.45015) (xy 344.944178 -237.419127) (xy 344.909998 -237.381968) (xy 344.882403 -237.339688)
			(xy 344.871802 -237.316772) (xy 344.866722 -237.305342) (xy 344.84691 -237.289594) (xy 344.752168 -237.271814)
			(xy 344.739768 -237.270112) (xy 344.715902 -237.277554) (xy 344.706702 -237.286038) (xy 344.327226 -237.665514)
			(xy 344.320379 -237.672912) (xy 344.312646 -237.69151) (xy 344.31224 -237.701582) (xy 344.31224 -237.843822)
			(xy 344.312664 -237.853837) (xy 344.320339 -237.87234) (xy 344.334512 -237.886495) (xy 344.353024 -237.894148)
			(xy 344.36304 -237.894622) (xy 344.377518 -237.894622) (xy 344.401902 -237.879636) (xy 344.408506 -237.866682)
			(xy 344.419736 -237.84537) (xy 344.447879 -237.806275) (xy 344.48182 -237.772092) (xy 344.520713 -237.743671)
			(xy 344.563591 -237.721718) (xy 344.609387 -237.706781) (xy 344.656962 -237.69923) (xy 344.681048 -237.698788)
			(xy 344.706301 -237.699313) (xy 344.756117 -237.707633) (xy 344.803885 -237.724039) (xy 344.848301 -237.748082)
			(xy 344.888155 -237.779107) (xy 344.922359 -237.816268) (xy 344.949981 -237.858552) (xy 344.970267 -237.904805)
			(xy 344.982665 -237.953766) (xy 344.986835 -238.004096) (xy 345.315298 -238.004096) (xy 345.319258 -237.955042)
			(xy 345.331035 -237.907258) (xy 345.350326 -237.861982) (xy 345.376629 -237.820386) (xy 345.409264 -237.783549)
			(xy 345.447385 -237.752424) (xy 345.490006 -237.727817) (xy 345.536022 -237.710365) (xy 345.584241 -237.700521)
			(xy 345.633416 -237.69854) (xy 345.682271 -237.704472) (xy 345.729542 -237.718164) (xy 345.774004 -237.739262)
			(xy 345.814507 -237.767218) (xy 345.85 -237.80131) (xy 345.879565 -237.840654) (xy 345.902436 -237.884231)
			(xy 345.91802 -237.930912) (xy 345.925915 -237.979489) (xy 345.92641 -238.004096) (xy 346.255352 -238.004096)
			(xy 346.259312 -237.955042) (xy 346.271089 -237.907258) (xy 346.29038 -237.861982) (xy 346.316683 -237.820386)
			(xy 346.349318 -237.783549) (xy 346.387439 -237.752424) (xy 346.43006 -237.727817) (xy 346.476076 -237.710365)
			(xy 346.524295 -237.700521) (xy 346.57347 -237.69854) (xy 346.622325 -237.704472) (xy 346.669596 -237.718164)
			(xy 346.714058 -237.739262) (xy 346.754561 -237.767218) (xy 346.790054 -237.80131) (xy 346.819619 -237.840654)
			(xy 346.84249 -237.884231) (xy 346.858074 -237.930912) (xy 346.865969 -237.979489) (xy 346.866464 -238.004096)
			(xy 347.195406 -238.004096) (xy 347.199366 -237.955042) (xy 347.211143 -237.907258) (xy 347.230434 -237.861982)
			(xy 347.256737 -237.820386) (xy 347.289372 -237.783549) (xy 347.327493 -237.752424) (xy 347.370114 -237.727817)
			(xy 347.41613 -237.710365) (xy 347.464349 -237.700521) (xy 347.513524 -237.69854) (xy 347.562379 -237.704472)
			(xy 347.60965 -237.718164) (xy 347.654112 -237.739262) (xy 347.694615 -237.767218) (xy 347.730108 -237.80131)
			(xy 347.759673 -237.840654) (xy 347.782544 -237.884231) (xy 347.798128 -237.930912) (xy 347.806023 -237.979489)
			(xy 347.806518 -238.004096) (xy 348.135206 -238.004096) (xy 348.139166 -237.955042) (xy 348.150943 -237.907258)
			(xy 348.170234 -237.861982) (xy 348.196537 -237.820386) (xy 348.229172 -237.783549) (xy 348.267293 -237.752424)
			(xy 348.309914 -237.727817) (xy 348.35593 -237.710365) (xy 348.404149 -237.700521) (xy 348.453324 -237.69854)
			(xy 348.502179 -237.704472) (xy 348.54945 -237.718164) (xy 348.593912 -237.739262) (xy 348.634415 -237.767218)
			(xy 348.669908 -237.80131) (xy 348.699473 -237.840654) (xy 348.722344 -237.884231) (xy 348.737928 -237.930912)
			(xy 348.745823 -237.979489) (xy 348.746318 -238.004096) (xy 349.07526 -238.004096) (xy 349.07922 -237.955042)
			(xy 349.090997 -237.907258) (xy 349.110288 -237.861982) (xy 349.136591 -237.820386) (xy 349.169226 -237.783549)
			(xy 349.207347 -237.752424) (xy 349.249968 -237.727817) (xy 349.295984 -237.710365) (xy 349.344203 -237.700521)
			(xy 349.393378 -237.69854) (xy 349.442233 -237.704472) (xy 349.489504 -237.718164) (xy 349.533966 -237.739262)
			(xy 349.574469 -237.767218) (xy 349.609962 -237.80131) (xy 349.639527 -237.840654) (xy 349.662398 -237.884231)
			(xy 349.677982 -237.930912) (xy 349.685877 -237.979489) (xy 349.686372 -238.004096) (xy 350.015314 -238.004096)
			(xy 350.019274 -237.955042) (xy 350.031051 -237.907258) (xy 350.050342 -237.861982) (xy 350.076645 -237.820386)
			(xy 350.10928 -237.783549) (xy 350.147401 -237.752424) (xy 350.190022 -237.727817) (xy 350.236038 -237.710365)
			(xy 350.284257 -237.700521) (xy 350.333432 -237.69854) (xy 350.382287 -237.704472) (xy 350.429558 -237.718164)
			(xy 350.47402 -237.739262) (xy 350.514523 -237.767218) (xy 350.550016 -237.80131) (xy 350.579581 -237.840654)
			(xy 350.602452 -237.884231) (xy 350.618036 -237.930912) (xy 350.625931 -237.979489) (xy 350.626426 -238.004096)
			(xy 350.955368 -238.004096) (xy 350.959328 -237.955042) (xy 350.971105 -237.907258) (xy 350.990396 -237.861982)
			(xy 351.016699 -237.820386) (xy 351.049334 -237.783549) (xy 351.087455 -237.752424) (xy 351.130076 -237.727817)
			(xy 351.176092 -237.710365) (xy 351.224311 -237.700521) (xy 351.273486 -237.69854) (xy 351.322341 -237.704472)
			(xy 351.369612 -237.718164) (xy 351.414074 -237.739262) (xy 351.454577 -237.767218) (xy 351.49007 -237.80131)
			(xy 351.519635 -237.840654) (xy 351.542506 -237.884231) (xy 351.55809 -237.930912) (xy 351.565985 -237.979489)
			(xy 351.56648 -238.004096) (xy 351.895422 -238.004096) (xy 351.899382 -237.955042) (xy 351.911159 -237.907258)
			(xy 351.93045 -237.861982) (xy 351.956753 -237.820386) (xy 351.989388 -237.783549) (xy 352.027509 -237.752424)
			(xy 352.07013 -237.727817) (xy 352.116146 -237.710365) (xy 352.164365 -237.700521) (xy 352.21354 -237.69854)
			(xy 352.262395 -237.704472) (xy 352.309666 -237.718164) (xy 352.354128 -237.739262) (xy 352.394631 -237.767218)
			(xy 352.430124 -237.80131) (xy 352.459689 -237.840654) (xy 352.48256 -237.884231) (xy 352.498144 -237.930912)
			(xy 352.506039 -237.979489) (xy 352.506534 -238.004096) (xy 352.835222 -238.004096) (xy 352.839182 -237.955042)
			(xy 352.850959 -237.907258) (xy 352.87025 -237.861982) (xy 352.896553 -237.820386) (xy 352.929188 -237.783549)
			(xy 352.967309 -237.752424) (xy 353.00993 -237.727817) (xy 353.055946 -237.710365) (xy 353.104165 -237.700521)
			(xy 353.15334 -237.69854) (xy 353.202195 -237.704472) (xy 353.249466 -237.718164) (xy 353.293928 -237.739262)
			(xy 353.334431 -237.767218) (xy 353.369924 -237.80131) (xy 353.399489 -237.840654) (xy 353.42236 -237.884231)
			(xy 353.437944 -237.930912) (xy 353.445839 -237.979489) (xy 353.446334 -238.004096) (xy 353.775276 -238.004096)
			(xy 353.779236 -237.955042) (xy 353.791013 -237.907258) (xy 353.810304 -237.861982) (xy 353.836607 -237.820386)
			(xy 353.869242 -237.783549) (xy 353.907363 -237.752424) (xy 353.949984 -237.727817) (xy 353.996 -237.710365)
			(xy 354.044219 -237.700521) (xy 354.093394 -237.69854) (xy 354.142249 -237.704472) (xy 354.18952 -237.718164)
			(xy 354.233982 -237.739262) (xy 354.274485 -237.767218) (xy 354.309978 -237.80131) (xy 354.339543 -237.840654)
			(xy 354.362414 -237.884231) (xy 354.377998 -237.930912) (xy 354.385893 -237.979489) (xy 354.386388 -238.004096)
			(xy 354.71533 -238.004096) (xy 354.71929 -237.955042) (xy 354.731067 -237.907258) (xy 354.750358 -237.861982)
			(xy 354.776661 -237.820386) (xy 354.809296 -237.783549) (xy 354.847417 -237.752424) (xy 354.890038 -237.727817)
			(xy 354.936054 -237.710365) (xy 354.984273 -237.700521) (xy 355.033448 -237.69854) (xy 355.082303 -237.704472)
			(xy 355.129574 -237.718164) (xy 355.174036 -237.739262) (xy 355.214539 -237.767218) (xy 355.250032 -237.80131)
			(xy 355.279597 -237.840654) (xy 355.302468 -237.884231) (xy 355.318052 -237.930912) (xy 355.325947 -237.979489)
			(xy 355.326442 -238.004096) (xy 355.655384 -238.004096) (xy 355.659344 -237.955042) (xy 355.671121 -237.907258)
			(xy 355.690412 -237.861982) (xy 355.716715 -237.820386) (xy 355.74935 -237.783549) (xy 355.787471 -237.752424)
			(xy 355.830092 -237.727817) (xy 355.876108 -237.710365) (xy 355.924327 -237.700521) (xy 355.973502 -237.69854)
			(xy 356.022357 -237.704472) (xy 356.069628 -237.718164) (xy 356.11409 -237.739262) (xy 356.154593 -237.767218)
			(xy 356.190086 -237.80131) (xy 356.219651 -237.840654) (xy 356.242522 -237.884231) (xy 356.258106 -237.930912)
			(xy 356.266001 -237.979489) (xy 356.266496 -238.004096) (xy 356.595438 -238.004096) (xy 356.599398 -237.955042)
			(xy 356.611175 -237.907258) (xy 356.630466 -237.861982) (xy 356.656769 -237.820386) (xy 356.689404 -237.783549)
			(xy 356.727525 -237.752424) (xy 356.770146 -237.727817) (xy 356.816162 -237.710365) (xy 356.864381 -237.700521)
			(xy 356.913556 -237.69854) (xy 356.962411 -237.704472) (xy 357.009682 -237.718164) (xy 357.054144 -237.739262)
			(xy 357.094647 -237.767218) (xy 357.13014 -237.80131) (xy 357.159705 -237.840654) (xy 357.182576 -237.884231)
			(xy 357.19816 -237.930912) (xy 357.206055 -237.979489) (xy 357.20655 -238.004096) (xy 357.535238 -238.004096)
			(xy 357.539198 -237.955042) (xy 357.550975 -237.907258) (xy 357.570266 -237.861982) (xy 357.596569 -237.820386)
			(xy 357.629204 -237.783549) (xy 357.667325 -237.752424) (xy 357.709946 -237.727817) (xy 357.755962 -237.710365)
			(xy 357.804181 -237.700521) (xy 357.853356 -237.69854) (xy 357.902211 -237.704472) (xy 357.949482 -237.718164)
			(xy 357.993944 -237.739262) (xy 358.034447 -237.767218) (xy 358.06994 -237.80131) (xy 358.099505 -237.840654)
			(xy 358.122376 -237.884231) (xy 358.13796 -237.930912) (xy 358.145855 -237.979489) (xy 358.14635 -238.004096)
			(xy 358.145855 -238.028703) (xy 358.13796 -238.07728) (xy 358.122376 -238.123961) (xy 358.099505 -238.167538)
			(xy 358.06994 -238.206882) (xy 358.034447 -238.240974) (xy 357.993944 -238.26893) (xy 357.949482 -238.290028)
			(xy 357.902211 -238.30372) (xy 357.853356 -238.309652) (xy 357.804181 -238.307671) (xy 357.755962 -238.297827)
			(xy 357.709946 -238.280375) (xy 357.667325 -238.255768) (xy 357.629204 -238.224643) (xy 357.596569 -238.187806)
			(xy 357.570266 -238.14621) (xy 357.550975 -238.100934) (xy 357.539198 -238.05315) (xy 357.535238 -238.004096)
			(xy 357.20655 -238.004096) (xy 357.206055 -238.028703) (xy 357.19816 -238.07728) (xy 357.182576 -238.123961)
			(xy 357.159705 -238.167538) (xy 357.13014 -238.206882) (xy 357.094647 -238.240974) (xy 357.054144 -238.26893)
			(xy 357.009682 -238.290028) (xy 356.962411 -238.30372) (xy 356.913556 -238.309652) (xy 356.864381 -238.307671)
			(xy 356.816162 -238.297827) (xy 356.770146 -238.280375) (xy 356.727525 -238.255768) (xy 356.689404 -238.224643)
			(xy 356.656769 -238.187806) (xy 356.630466 -238.14621) (xy 356.611175 -238.100934) (xy 356.599398 -238.05315)
			(xy 356.595438 -238.004096) (xy 356.266496 -238.004096) (xy 356.266001 -238.028703) (xy 356.258106 -238.07728)
			(xy 356.242522 -238.123961) (xy 356.219651 -238.167538) (xy 356.190086 -238.206882) (xy 356.154593 -238.240974)
			(xy 356.11409 -238.26893) (xy 356.069628 -238.290028) (xy 356.022357 -238.30372) (xy 355.973502 -238.309652)
			(xy 355.924327 -238.307671) (xy 355.876108 -238.297827) (xy 355.830092 -238.280375) (xy 355.787471 -238.255768)
			(xy 355.74935 -238.224643) (xy 355.716715 -238.187806) (xy 355.690412 -238.14621) (xy 355.671121 -238.100934)
			(xy 355.659344 -238.05315) (xy 355.655384 -238.004096) (xy 355.326442 -238.004096) (xy 355.325947 -238.028703)
			(xy 355.318052 -238.07728) (xy 355.302468 -238.123961) (xy 355.279597 -238.167538) (xy 355.250032 -238.206882)
			(xy 355.214539 -238.240974) (xy 355.174036 -238.26893) (xy 355.129574 -238.290028) (xy 355.082303 -238.30372)
			(xy 355.033448 -238.309652) (xy 354.984273 -238.307671) (xy 354.936054 -238.297827) (xy 354.890038 -238.280375)
			(xy 354.847417 -238.255768) (xy 354.809296 -238.224643) (xy 354.776661 -238.187806) (xy 354.750358 -238.14621)
			(xy 354.731067 -238.100934) (xy 354.71929 -238.05315) (xy 354.71533 -238.004096) (xy 354.386388 -238.004096)
			(xy 354.385893 -238.028703) (xy 354.377998 -238.07728) (xy 354.362414 -238.123961) (xy 354.339543 -238.167538)
			(xy 354.309978 -238.206882) (xy 354.274485 -238.240974) (xy 354.233982 -238.26893) (xy 354.18952 -238.290028)
			(xy 354.142249 -238.30372) (xy 354.093394 -238.309652) (xy 354.044219 -238.307671) (xy 353.996 -238.297827)
			(xy 353.949984 -238.280375) (xy 353.907363 -238.255768) (xy 353.869242 -238.224643) (xy 353.836607 -238.187806)
			(xy 353.810304 -238.14621) (xy 353.791013 -238.100934) (xy 353.779236 -238.05315) (xy 353.775276 -238.004096)
			(xy 353.446334 -238.004096) (xy 353.445839 -238.028703) (xy 353.437944 -238.07728) (xy 353.42236 -238.123961)
			(xy 353.399489 -238.167538) (xy 353.369924 -238.206882) (xy 353.334431 -238.240974) (xy 353.293928 -238.26893)
			(xy 353.249466 -238.290028) (xy 353.202195 -238.30372) (xy 353.15334 -238.309652) (xy 353.104165 -238.307671)
			(xy 353.055946 -238.297827) (xy 353.00993 -238.280375) (xy 352.967309 -238.255768) (xy 352.929188 -238.224643)
			(xy 352.896553 -238.187806) (xy 352.87025 -238.14621) (xy 352.850959 -238.100934) (xy 352.839182 -238.05315)
			(xy 352.835222 -238.004096) (xy 352.506534 -238.004096) (xy 352.506039 -238.028703) (xy 352.498144 -238.07728)
			(xy 352.48256 -238.123961) (xy 352.459689 -238.167538) (xy 352.430124 -238.206882) (xy 352.394631 -238.240974)
			(xy 352.354128 -238.26893) (xy 352.309666 -238.290028) (xy 352.262395 -238.30372) (xy 352.21354 -238.309652)
			(xy 352.164365 -238.307671) (xy 352.116146 -238.297827) (xy 352.07013 -238.280375) (xy 352.027509 -238.255768)
			(xy 351.989388 -238.224643) (xy 351.956753 -238.187806) (xy 351.93045 -238.14621) (xy 351.911159 -238.100934)
			(xy 351.899382 -238.05315) (xy 351.895422 -238.004096) (xy 351.56648 -238.004096) (xy 351.565985 -238.028703)
			(xy 351.55809 -238.07728) (xy 351.542506 -238.123961) (xy 351.519635 -238.167538) (xy 351.49007 -238.206882)
			(xy 351.454577 -238.240974) (xy 351.414074 -238.26893) (xy 351.369612 -238.290028) (xy 351.322341 -238.30372)
			(xy 351.273486 -238.309652) (xy 351.224311 -238.307671) (xy 351.176092 -238.297827) (xy 351.130076 -238.280375)
			(xy 351.087455 -238.255768) (xy 351.049334 -238.224643) (xy 351.016699 -238.187806) (xy 350.990396 -238.14621)
			(xy 350.971105 -238.100934) (xy 350.959328 -238.05315) (xy 350.955368 -238.004096) (xy 350.626426 -238.004096)
			(xy 350.625931 -238.028703) (xy 350.618036 -238.07728) (xy 350.602452 -238.123961) (xy 350.579581 -238.167538)
			(xy 350.550016 -238.206882) (xy 350.514523 -238.240974) (xy 350.47402 -238.26893) (xy 350.429558 -238.290028)
			(xy 350.382287 -238.30372) (xy 350.333432 -238.309652) (xy 350.284257 -238.307671) (xy 350.236038 -238.297827)
			(xy 350.190022 -238.280375) (xy 350.147401 -238.255768) (xy 350.10928 -238.224643) (xy 350.076645 -238.187806)
			(xy 350.050342 -238.14621) (xy 350.031051 -238.100934) (xy 350.019274 -238.05315) (xy 350.015314 -238.004096)
			(xy 349.686372 -238.004096) (xy 349.685877 -238.028703) (xy 349.677982 -238.07728) (xy 349.662398 -238.123961)
			(xy 349.639527 -238.167538) (xy 349.609962 -238.206882) (xy 349.574469 -238.240974) (xy 349.533966 -238.26893)
			(xy 349.489504 -238.290028) (xy 349.442233 -238.30372) (xy 349.393378 -238.309652) (xy 349.344203 -238.307671)
			(xy 349.295984 -238.297827) (xy 349.249968 -238.280375) (xy 349.207347 -238.255768) (xy 349.169226 -238.224643)
			(xy 349.136591 -238.187806) (xy 349.110288 -238.14621) (xy 349.090997 -238.100934) (xy 349.07922 -238.05315)
			(xy 349.07526 -238.004096) (xy 348.746318 -238.004096) (xy 348.745823 -238.028703) (xy 348.737928 -238.07728)
			(xy 348.722344 -238.123961) (xy 348.699473 -238.167538) (xy 348.669908 -238.206882) (xy 348.634415 -238.240974)
			(xy 348.593912 -238.26893) (xy 348.54945 -238.290028) (xy 348.502179 -238.30372) (xy 348.453324 -238.309652)
			(xy 348.404149 -238.307671) (xy 348.35593 -238.297827) (xy 348.309914 -238.280375) (xy 348.267293 -238.255768)
			(xy 348.229172 -238.224643) (xy 348.196537 -238.187806) (xy 348.170234 -238.14621) (xy 348.150943 -238.100934)
			(xy 348.139166 -238.05315) (xy 348.135206 -238.004096) (xy 347.806518 -238.004096) (xy 347.806023 -238.028703)
			(xy 347.798128 -238.07728) (xy 347.782544 -238.123961) (xy 347.759673 -238.167538) (xy 347.730108 -238.206882)
			(xy 347.694615 -238.240974) (xy 347.654112 -238.26893) (xy 347.60965 -238.290028) (xy 347.562379 -238.30372)
			(xy 347.513524 -238.309652) (xy 347.464349 -238.307671) (xy 347.41613 -238.297827) (xy 347.370114 -238.280375)
			(xy 347.327493 -238.255768) (xy 347.289372 -238.224643) (xy 347.256737 -238.187806) (xy 347.230434 -238.14621)
			(xy 347.211143 -238.100934) (xy 347.199366 -238.05315) (xy 347.195406 -238.004096) (xy 346.866464 -238.004096)
			(xy 346.865969 -238.028703) (xy 346.858074 -238.07728) (xy 346.84249 -238.123961) (xy 346.819619 -238.167538)
			(xy 346.790054 -238.206882) (xy 346.754561 -238.240974) (xy 346.714058 -238.26893) (xy 346.669596 -238.290028)
			(xy 346.622325 -238.30372) (xy 346.57347 -238.309652) (xy 346.524295 -238.307671) (xy 346.476076 -238.297827)
			(xy 346.43006 -238.280375) (xy 346.387439 -238.255768) (xy 346.349318 -238.224643) (xy 346.316683 -238.187806)
			(xy 346.29038 -238.14621) (xy 346.271089 -238.100934) (xy 346.259312 -238.05315) (xy 346.255352 -238.004096)
			(xy 345.92641 -238.004096) (xy 345.925915 -238.028703) (xy 345.91802 -238.07728) (xy 345.902436 -238.123961)
			(xy 345.879565 -238.167538) (xy 345.85 -238.206882) (xy 345.814507 -238.240974) (xy 345.774004 -238.26893)
			(xy 345.729542 -238.290028) (xy 345.682271 -238.30372) (xy 345.633416 -238.309652) (xy 345.584241 -238.307671)
			(xy 345.536022 -238.297827) (xy 345.490006 -238.280375) (xy 345.447385 -238.255768) (xy 345.409264 -238.224643)
			(xy 345.376629 -238.187806) (xy 345.350326 -238.14621) (xy 345.331035 -238.100934) (xy 345.319258 -238.05315)
			(xy 345.315298 -238.004096) (xy 344.986835 -238.004096) (xy 344.986835 -238.0041) (xy 344.982665 -238.054434)
			(xy 344.970267 -238.103395) (xy 344.949981 -238.149648) (xy 344.922359 -238.191932) (xy 344.888155 -238.229093)
			(xy 344.848301 -238.260118) (xy 344.803885 -238.284161) (xy 344.756117 -238.300567) (xy 344.706301 -238.308887)
			(xy 344.681048 -238.309404) (xy 344.653693 -238.308773) (xy 344.599866 -238.298987) (xy 344.548641 -238.279772)
			(xy 344.501656 -238.251744) (xy 344.480642 -238.23422) (xy 344.469212 -238.224314) (xy 344.440002 -238.22025)
			(xy 344.341958 -238.2647) (xy 344.333296 -238.269119) (xy 344.319881 -238.283175) (xy 344.31266 -238.301213)
			(xy 344.31224 -238.310928) (xy 344.31224 -238.507016) (xy 344.327988 -238.531654) (xy 344.34145 -238.538004)
			(xy 344.363541 -238.548956) (xy 344.404166 -238.576897) (xy 344.439772 -238.611002) (xy 344.469436 -238.650386)
			(xy 344.492386 -238.694024) (xy 344.508025 -238.740784) (xy 344.515948 -238.789448) (xy 344.515947 -238.814102)
			(xy 346.725252 -238.814102) (xy 346.729212 -238.765048) (xy 346.740989 -238.717264) (xy 346.76028 -238.671988)
			(xy 346.786583 -238.630392) (xy 346.819218 -238.593555) (xy 346.857339 -238.56243) (xy 346.89996 -238.537823)
			(xy 346.945976 -238.520371) (xy 346.994195 -238.510527) (xy 347.04337 -238.508546) (xy 347.092225 -238.514478)
			(xy 347.139496 -238.52817) (xy 347.183958 -238.549268) (xy 347.224461 -238.577224) (xy 347.259954 -238.611316)
			(xy 347.289519 -238.65066) (xy 347.31239 -238.694237) (xy 347.327974 -238.740918) (xy 347.335869 -238.789495)
			(xy 347.336364 -238.814102) (xy 349.545414 -238.814102) (xy 349.549374 -238.765048) (xy 349.561151 -238.717264)
			(xy 349.580442 -238.671988) (xy 349.606745 -238.630392) (xy 349.63938 -238.593555) (xy 349.677501 -238.56243)
			(xy 349.720122 -238.537823) (xy 349.766138 -238.520371) (xy 349.814357 -238.510527) (xy 349.863532 -238.508546)
			(xy 349.912387 -238.514478) (xy 349.959658 -238.52817) (xy 350.00412 -238.549268) (xy 350.044623 -238.577224)
			(xy 350.080116 -238.611316) (xy 350.109681 -238.65066) (xy 350.132552 -238.694237) (xy 350.148136 -238.740918)
			(xy 350.156031 -238.789495) (xy 350.156526 -238.814102) (xy 352.365322 -238.814102) (xy 352.369282 -238.765048)
			(xy 352.381059 -238.717264) (xy 352.40035 -238.671988) (xy 352.426653 -238.630392) (xy 352.459288 -238.593555)
			(xy 352.497409 -238.56243) (xy 352.54003 -238.537823) (xy 352.586046 -238.520371) (xy 352.634265 -238.510527)
			(xy 352.68344 -238.508546) (xy 352.732295 -238.514478) (xy 352.779566 -238.52817) (xy 352.824028 -238.549268)
			(xy 352.864531 -238.577224) (xy 352.900024 -238.611316) (xy 352.929589 -238.65066) (xy 352.95246 -238.694237)
			(xy 352.968044 -238.740918) (xy 352.975939 -238.789495) (xy 352.976434 -238.814102) (xy 355.18523 -238.814102)
			(xy 355.18919 -238.765048) (xy 355.200967 -238.717264) (xy 355.220258 -238.671988) (xy 355.246561 -238.630392)
			(xy 355.279196 -238.593555) (xy 355.317317 -238.56243) (xy 355.359938 -238.537823) (xy 355.405954 -238.520371)
			(xy 355.454173 -238.510527) (xy 355.503348 -238.508546) (xy 355.552203 -238.514478) (xy 355.599474 -238.52817)
			(xy 355.643936 -238.549268) (xy 355.684439 -238.577224) (xy 355.719932 -238.611316) (xy 355.749497 -238.65066)
			(xy 355.772368 -238.694237) (xy 355.787952 -238.740918) (xy 355.795847 -238.789495) (xy 355.796342 -238.814102)
			(xy 356.125284 -238.814102) (xy 356.129244 -238.765048) (xy 356.141021 -238.717264) (xy 356.160312 -238.671988)
			(xy 356.186615 -238.630392) (xy 356.21925 -238.593555) (xy 356.257371 -238.56243) (xy 356.299992 -238.537823)
			(xy 356.346008 -238.520371) (xy 356.394227 -238.510527) (xy 356.443402 -238.508546) (xy 356.492257 -238.514478)
			(xy 356.539528 -238.52817) (xy 356.58399 -238.549268) (xy 356.624493 -238.577224) (xy 356.659986 -238.611316)
			(xy 356.689551 -238.65066) (xy 356.712422 -238.694237) (xy 356.728006 -238.740918) (xy 356.735901 -238.789495)
			(xy 356.736396 -238.814102) (xy 357.065338 -238.814102) (xy 357.069298 -238.765048) (xy 357.081075 -238.717264)
			(xy 357.100366 -238.671988) (xy 357.126669 -238.630392) (xy 357.159304 -238.593555) (xy 357.197425 -238.56243)
			(xy 357.240046 -238.537823) (xy 357.286062 -238.520371) (xy 357.334281 -238.510527) (xy 357.383456 -238.508546)
			(xy 357.432311 -238.514478) (xy 357.479582 -238.52817) (xy 357.524044 -238.549268) (xy 357.564547 -238.577224)
			(xy 357.60004 -238.611316) (xy 357.629605 -238.65066) (xy 357.652476 -238.694237) (xy 357.66806 -238.740918)
			(xy 357.675955 -238.789495) (xy 357.67645 -238.814102) (xy 358.005392 -238.814102) (xy 358.009352 -238.765048)
			(xy 358.021129 -238.717264) (xy 358.04042 -238.671988) (xy 358.066723 -238.630392) (xy 358.099358 -238.593555)
			(xy 358.137479 -238.56243) (xy 358.1801 -238.537823) (xy 358.226116 -238.520371) (xy 358.274335 -238.510527)
			(xy 358.32351 -238.508546) (xy 358.372365 -238.514478) (xy 358.419636 -238.52817) (xy 358.464098 -238.549268)
			(xy 358.504601 -238.577224) (xy 358.540094 -238.611316) (xy 358.569659 -238.65066) (xy 358.59253 -238.694237)
			(xy 358.608114 -238.740918) (xy 358.616009 -238.789495) (xy 358.616504 -238.814102) (xy 358.616009 -238.838709)
			(xy 358.608114 -238.887286) (xy 358.59253 -238.933967) (xy 358.569659 -238.977544) (xy 358.540094 -239.016888)
			(xy 358.504601 -239.05098) (xy 358.464098 -239.078936) (xy 358.419636 -239.100034) (xy 358.372365 -239.113726)
			(xy 358.32351 -239.119658) (xy 358.274335 -239.117677) (xy 358.226116 -239.107833) (xy 358.1801 -239.090381)
			(xy 358.137479 -239.065774) (xy 358.099358 -239.034649) (xy 358.066723 -238.997812) (xy 358.04042 -238.956216)
			(xy 358.021129 -238.91094) (xy 358.009352 -238.863156) (xy 358.005392 -238.814102) (xy 357.67645 -238.814102)
			(xy 357.675955 -238.838709) (xy 357.66806 -238.887286) (xy 357.652476 -238.933967) (xy 357.629605 -238.977544)
			(xy 357.60004 -239.016888) (xy 357.564547 -239.05098) (xy 357.524044 -239.078936) (xy 357.479582 -239.100034)
			(xy 357.432311 -239.113726) (xy 357.383456 -239.119658) (xy 357.334281 -239.117677) (xy 357.286062 -239.107833)
			(xy 357.240046 -239.090381) (xy 357.197425 -239.065774) (xy 357.159304 -239.034649) (xy 357.126669 -238.997812)
			(xy 357.100366 -238.956216) (xy 357.081075 -238.91094) (xy 357.069298 -238.863156) (xy 357.065338 -238.814102)
			(xy 356.736396 -238.814102) (xy 356.735901 -238.838709) (xy 356.728006 -238.887286) (xy 356.712422 -238.933967)
			(xy 356.689551 -238.977544) (xy 356.659986 -239.016888) (xy 356.624493 -239.05098) (xy 356.58399 -239.078936)
			(xy 356.539528 -239.100034) (xy 356.492257 -239.113726) (xy 356.443402 -239.119658) (xy 356.394227 -239.117677)
			(xy 356.346008 -239.107833) (xy 356.299992 -239.090381) (xy 356.257371 -239.065774) (xy 356.21925 -239.034649)
			(xy 356.186615 -238.997812) (xy 356.160312 -238.956216) (xy 356.141021 -238.91094) (xy 356.129244 -238.863156)
			(xy 356.125284 -238.814102) (xy 355.796342 -238.814102) (xy 355.795847 -238.838709) (xy 355.787952 -238.887286)
			(xy 355.772368 -238.933967) (xy 355.749497 -238.977544) (xy 355.719932 -239.016888) (xy 355.684439 -239.05098)
			(xy 355.643936 -239.078936) (xy 355.599474 -239.100034) (xy 355.552203 -239.113726) (xy 355.503348 -239.119658)
			(xy 355.454173 -239.117677) (xy 355.405954 -239.107833) (xy 355.359938 -239.090381) (xy 355.317317 -239.065774)
			(xy 355.279196 -239.034649) (xy 355.246561 -238.997812) (xy 355.220258 -238.956216) (xy 355.200967 -238.91094)
			(xy 355.18919 -238.863156) (xy 355.18523 -238.814102) (xy 352.976434 -238.814102) (xy 352.975939 -238.838709)
			(xy 352.968044 -238.887286) (xy 352.95246 -238.933967) (xy 352.929589 -238.977544) (xy 352.900024 -239.016888)
			(xy 352.864531 -239.05098) (xy 352.824028 -239.078936) (xy 352.779566 -239.100034) (xy 352.732295 -239.113726)
			(xy 352.68344 -239.119658) (xy 352.634265 -239.117677) (xy 352.586046 -239.107833) (xy 352.54003 -239.090381)
			(xy 352.497409 -239.065774) (xy 352.459288 -239.034649) (xy 352.426653 -238.997812) (xy 352.40035 -238.956216)
			(xy 352.381059 -238.91094) (xy 352.369282 -238.863156) (xy 352.365322 -238.814102) (xy 350.156526 -238.814102)
			(xy 350.156031 -238.838709) (xy 350.148136 -238.887286) (xy 350.132552 -238.933967) (xy 350.109681 -238.977544)
			(xy 350.080116 -239.016888) (xy 350.044623 -239.05098) (xy 350.00412 -239.078936) (xy 349.959658 -239.100034)
			(xy 349.912387 -239.113726) (xy 349.863532 -239.119658) (xy 349.814357 -239.117677) (xy 349.766138 -239.107833)
			(xy 349.720122 -239.090381) (xy 349.677501 -239.065774) (xy 349.63938 -239.034649) (xy 349.606745 -238.997812)
			(xy 349.580442 -238.956216) (xy 349.561151 -238.91094) (xy 349.549374 -238.863156) (xy 349.545414 -238.814102)
			(xy 347.336364 -238.814102) (xy 347.335869 -238.838709) (xy 347.327974 -238.887286) (xy 347.31239 -238.933967)
			(xy 347.289519 -238.977544) (xy 347.259954 -239.016888) (xy 347.224461 -239.05098) (xy 347.183958 -239.078936)
			(xy 347.139496 -239.100034) (xy 347.092225 -239.113726) (xy 347.04337 -239.119658) (xy 346.994195 -239.117677)
			(xy 346.945976 -239.107833) (xy 346.89996 -239.090381) (xy 346.857339 -239.065774) (xy 346.819218 -239.034649)
			(xy 346.786583 -238.997812) (xy 346.76028 -238.956216) (xy 346.740989 -238.91094) (xy 346.729212 -238.863156)
			(xy 346.725252 -238.814102) (xy 344.515947 -238.814102) (xy 344.515947 -238.838753) (xy 344.508025 -238.887418)
			(xy 344.492385 -238.934177) (xy 344.469435 -238.977816) (xy 344.439771 -239.017199) (xy 344.404164 -239.051304)
			(xy 344.36354 -239.079245) (xy 344.34145 -239.0902) (xy 344.327988 -239.09655) (xy 344.31224 -239.121188)
			(xy 344.31224 -239.317276) (xy 344.312665 -239.326994) (xy 344.319878 -239.34504) (xy 344.33328 -239.359114)
			(xy 344.341958 -239.363504) (xy 344.440002 -239.407954) (xy 344.469212 -239.40389) (xy 344.480642 -239.393984)
			(xy 344.50166 -239.376466) (xy 344.548641 -239.348435) (xy 344.599866 -239.329224) (xy 344.653694 -239.319449)
			(xy 344.681048 -239.3188) (xy 344.7063 -239.319325) (xy 344.756114 -239.327645) (xy 344.80388 -239.34405)
			(xy 344.848295 -239.368092) (xy 344.888147 -239.399116) (xy 344.92235 -239.436276) (xy 344.949971 -239.478558)
			(xy 344.970256 -239.524809) (xy 344.982653 -239.573768) (xy 344.986823 -239.6241) (xy 344.986822 -239.624108)
			(xy 345.315298 -239.624108) (xy 345.319258 -239.575054) (xy 345.331035 -239.52727) (xy 345.350326 -239.481994)
			(xy 345.376629 -239.440398) (xy 345.409264 -239.403561) (xy 345.447385 -239.372436) (xy 345.490006 -239.347829)
			(xy 345.536022 -239.330377) (xy 345.584241 -239.320533) (xy 345.633416 -239.318552) (xy 345.682271 -239.324484)
			(xy 345.729542 -239.338176) (xy 345.774004 -239.359274) (xy 345.814507 -239.38723) (xy 345.85 -239.421322)
			(xy 345.879565 -239.460666) (xy 345.902436 -239.504243) (xy 345.91802 -239.550924) (xy 345.925915 -239.599501)
			(xy 345.92641 -239.624108) (xy 346.255352 -239.624108) (xy 346.259312 -239.575054) (xy 346.271089 -239.52727)
			(xy 346.29038 -239.481994) (xy 346.316683 -239.440398) (xy 346.349318 -239.403561) (xy 346.387439 -239.372436)
			(xy 346.43006 -239.347829) (xy 346.476076 -239.330377) (xy 346.524295 -239.320533) (xy 346.57347 -239.318552)
			(xy 346.622325 -239.324484) (xy 346.669596 -239.338176) (xy 346.714058 -239.359274) (xy 346.754561 -239.38723)
			(xy 346.790054 -239.421322) (xy 346.819619 -239.460666) (xy 346.84249 -239.504243) (xy 346.858074 -239.550924)
			(xy 346.865969 -239.599501) (xy 346.866464 -239.624108) (xy 347.195406 -239.624108) (xy 347.199366 -239.575054)
			(xy 347.211143 -239.52727) (xy 347.230434 -239.481994) (xy 347.256737 -239.440398) (xy 347.289372 -239.403561)
			(xy 347.327493 -239.372436) (xy 347.370114 -239.347829) (xy 347.41613 -239.330377) (xy 347.464349 -239.320533)
			(xy 347.513524 -239.318552) (xy 347.562379 -239.324484) (xy 347.60965 -239.338176) (xy 347.654112 -239.359274)
			(xy 347.694615 -239.38723) (xy 347.730108 -239.421322) (xy 347.759673 -239.460666) (xy 347.782544 -239.504243)
			(xy 347.798128 -239.550924) (xy 347.806023 -239.599501) (xy 347.806518 -239.624108) (xy 348.135206 -239.624108)
			(xy 348.139166 -239.575054) (xy 348.150943 -239.52727) (xy 348.170234 -239.481994) (xy 348.196537 -239.440398)
			(xy 348.229172 -239.403561) (xy 348.267293 -239.372436) (xy 348.309914 -239.347829) (xy 348.35593 -239.330377)
			(xy 348.404149 -239.320533) (xy 348.453324 -239.318552) (xy 348.502179 -239.324484) (xy 348.54945 -239.338176)
			(xy 348.593912 -239.359274) (xy 348.634415 -239.38723) (xy 348.669908 -239.421322) (xy 348.699473 -239.460666)
			(xy 348.722344 -239.504243) (xy 348.737928 -239.550924) (xy 348.745823 -239.599501) (xy 348.746318 -239.624108)
			(xy 349.07526 -239.624108) (xy 349.07922 -239.575054) (xy 349.090997 -239.52727) (xy 349.110288 -239.481994)
			(xy 349.136591 -239.440398) (xy 349.169226 -239.403561) (xy 349.207347 -239.372436) (xy 349.249968 -239.347829)
			(xy 349.295984 -239.330377) (xy 349.344203 -239.320533) (xy 349.393378 -239.318552) (xy 349.442233 -239.324484)
			(xy 349.489504 -239.338176) (xy 349.533966 -239.359274) (xy 349.574469 -239.38723) (xy 349.609962 -239.421322)
			(xy 349.639527 -239.460666) (xy 349.662398 -239.504243) (xy 349.677982 -239.550924) (xy 349.685877 -239.599501)
			(xy 349.686372 -239.624108) (xy 350.015314 -239.624108) (xy 350.019274 -239.575054) (xy 350.031051 -239.52727)
			(xy 350.050342 -239.481994) (xy 350.076645 -239.440398) (xy 350.10928 -239.403561) (xy 350.147401 -239.372436)
			(xy 350.190022 -239.347829) (xy 350.236038 -239.330377) (xy 350.284257 -239.320533) (xy 350.333432 -239.318552)
			(xy 350.382287 -239.324484) (xy 350.429558 -239.338176) (xy 350.47402 -239.359274) (xy 350.514523 -239.38723)
			(xy 350.550016 -239.421322) (xy 350.579581 -239.460666) (xy 350.602452 -239.504243) (xy 350.618036 -239.550924)
			(xy 350.625931 -239.599501) (xy 350.626426 -239.624108) (xy 350.955368 -239.624108) (xy 350.959328 -239.575054)
			(xy 350.971105 -239.52727) (xy 350.990396 -239.481994) (xy 351.016699 -239.440398) (xy 351.049334 -239.403561)
			(xy 351.087455 -239.372436) (xy 351.130076 -239.347829) (xy 351.176092 -239.330377) (xy 351.224311 -239.320533)
			(xy 351.273486 -239.318552) (xy 351.322341 -239.324484) (xy 351.369612 -239.338176) (xy 351.414074 -239.359274)
			(xy 351.454577 -239.38723) (xy 351.49007 -239.421322) (xy 351.519635 -239.460666) (xy 351.542506 -239.504243)
			(xy 351.55809 -239.550924) (xy 351.565985 -239.599501) (xy 351.56648 -239.624108) (xy 351.895422 -239.624108)
			(xy 351.899382 -239.575054) (xy 351.911159 -239.52727) (xy 351.93045 -239.481994) (xy 351.956753 -239.440398)
			(xy 351.989388 -239.403561) (xy 352.027509 -239.372436) (xy 352.07013 -239.347829) (xy 352.116146 -239.330377)
			(xy 352.164365 -239.320533) (xy 352.21354 -239.318552) (xy 352.262395 -239.324484) (xy 352.309666 -239.338176)
			(xy 352.354128 -239.359274) (xy 352.394631 -239.38723) (xy 352.430124 -239.421322) (xy 352.459689 -239.460666)
			(xy 352.48256 -239.504243) (xy 352.498144 -239.550924) (xy 352.506039 -239.599501) (xy 352.506534 -239.624108)
			(xy 352.835222 -239.624108) (xy 352.839182 -239.575054) (xy 352.850959 -239.52727) (xy 352.87025 -239.481994)
			(xy 352.896553 -239.440398) (xy 352.929188 -239.403561) (xy 352.967309 -239.372436) (xy 353.00993 -239.347829)
			(xy 353.055946 -239.330377) (xy 353.104165 -239.320533) (xy 353.15334 -239.318552) (xy 353.202195 -239.324484)
			(xy 353.249466 -239.338176) (xy 353.293928 -239.359274) (xy 353.334431 -239.38723) (xy 353.369924 -239.421322)
			(xy 353.399489 -239.460666) (xy 353.42236 -239.504243) (xy 353.437944 -239.550924) (xy 353.445839 -239.599501)
			(xy 353.446334 -239.624108) (xy 353.775276 -239.624108) (xy 353.779236 -239.575054) (xy 353.791013 -239.52727)
			(xy 353.810304 -239.481994) (xy 353.836607 -239.440398) (xy 353.869242 -239.403561) (xy 353.907363 -239.372436)
			(xy 353.949984 -239.347829) (xy 353.996 -239.330377) (xy 354.044219 -239.320533) (xy 354.093394 -239.318552)
			(xy 354.142249 -239.324484) (xy 354.18952 -239.338176) (xy 354.233982 -239.359274) (xy 354.274485 -239.38723)
			(xy 354.309978 -239.421322) (xy 354.339543 -239.460666) (xy 354.362414 -239.504243) (xy 354.377998 -239.550924)
			(xy 354.385893 -239.599501) (xy 354.386388 -239.624108) (xy 354.71533 -239.624108) (xy 354.71929 -239.575054)
			(xy 354.731067 -239.52727) (xy 354.750358 -239.481994) (xy 354.776661 -239.440398) (xy 354.809296 -239.403561)
			(xy 354.847417 -239.372436) (xy 354.890038 -239.347829) (xy 354.936054 -239.330377) (xy 354.984273 -239.320533)
			(xy 355.033448 -239.318552) (xy 355.082303 -239.324484) (xy 355.129574 -239.338176) (xy 355.174036 -239.359274)
			(xy 355.214539 -239.38723) (xy 355.250032 -239.421322) (xy 355.279597 -239.460666) (xy 355.302468 -239.504243)
			(xy 355.318052 -239.550924) (xy 355.325947 -239.599501) (xy 355.326442 -239.624108) (xy 355.655384 -239.624108)
			(xy 355.659344 -239.575054) (xy 355.671121 -239.52727) (xy 355.690412 -239.481994) (xy 355.716715 -239.440398)
			(xy 355.74935 -239.403561) (xy 355.787471 -239.372436) (xy 355.830092 -239.347829) (xy 355.876108 -239.330377)
			(xy 355.924327 -239.320533) (xy 355.973502 -239.318552) (xy 356.022357 -239.324484) (xy 356.069628 -239.338176)
			(xy 356.11409 -239.359274) (xy 356.154593 -239.38723) (xy 356.190086 -239.421322) (xy 356.219651 -239.460666)
			(xy 356.242522 -239.504243) (xy 356.258106 -239.550924) (xy 356.266001 -239.599501) (xy 356.266496 -239.624108)
			(xy 356.266001 -239.648715) (xy 356.258106 -239.697292) (xy 356.242522 -239.743973) (xy 356.219651 -239.78755)
			(xy 356.190086 -239.826894) (xy 356.154593 -239.860986) (xy 356.11409 -239.888942) (xy 356.069628 -239.91004)
			(xy 356.022357 -239.923732) (xy 355.973502 -239.929664) (xy 355.924327 -239.927683) (xy 355.876108 -239.917839)
			(xy 355.830092 -239.900387) (xy 355.787471 -239.87578) (xy 355.74935 -239.844655) (xy 355.716715 -239.807818)
			(xy 355.690412 -239.766222) (xy 355.671121 -239.720946) (xy 355.659344 -239.673162) (xy 355.655384 -239.624108)
			(xy 355.326442 -239.624108) (xy 355.325947 -239.648715) (xy 355.318052 -239.697292) (xy 355.302468 -239.743973)
			(xy 355.279597 -239.78755) (xy 355.250032 -239.826894) (xy 355.214539 -239.860986) (xy 355.174036 -239.888942)
			(xy 355.129574 -239.91004) (xy 355.082303 -239.923732) (xy 355.033448 -239.929664) (xy 354.984273 -239.927683)
			(xy 354.936054 -239.917839) (xy 354.890038 -239.900387) (xy 354.847417 -239.87578) (xy 354.809296 -239.844655)
			(xy 354.776661 -239.807818) (xy 354.750358 -239.766222) (xy 354.731067 -239.720946) (xy 354.71929 -239.673162)
			(xy 354.71533 -239.624108) (xy 354.386388 -239.624108) (xy 354.385893 -239.648715) (xy 354.377998 -239.697292)
			(xy 354.362414 -239.743973) (xy 354.339543 -239.78755) (xy 354.309978 -239.826894) (xy 354.274485 -239.860986)
			(xy 354.233982 -239.888942) (xy 354.18952 -239.91004) (xy 354.142249 -239.923732) (xy 354.093394 -239.929664)
			(xy 354.044219 -239.927683) (xy 353.996 -239.917839) (xy 353.949984 -239.900387) (xy 353.907363 -239.87578)
			(xy 353.869242 -239.844655) (xy 353.836607 -239.807818) (xy 353.810304 -239.766222) (xy 353.791013 -239.720946)
			(xy 353.779236 -239.673162) (xy 353.775276 -239.624108) (xy 353.446334 -239.624108) (xy 353.445839 -239.648715)
			(xy 353.437944 -239.697292) (xy 353.42236 -239.743973) (xy 353.399489 -239.78755) (xy 353.369924 -239.826894)
			(xy 353.334431 -239.860986) (xy 353.293928 -239.888942) (xy 353.249466 -239.91004) (xy 353.202195 -239.923732)
			(xy 353.15334 -239.929664) (xy 353.104165 -239.927683) (xy 353.055946 -239.917839) (xy 353.00993 -239.900387)
			(xy 352.967309 -239.87578) (xy 352.929188 -239.844655) (xy 352.896553 -239.807818) (xy 352.87025 -239.766222)
			(xy 352.850959 -239.720946) (xy 352.839182 -239.673162) (xy 352.835222 -239.624108) (xy 352.506534 -239.624108)
			(xy 352.506039 -239.648715) (xy 352.498144 -239.697292) (xy 352.48256 -239.743973) (xy 352.459689 -239.78755)
			(xy 352.430124 -239.826894) (xy 352.394631 -239.860986) (xy 352.354128 -239.888942) (xy 352.309666 -239.91004)
			(xy 352.262395 -239.923732) (xy 352.21354 -239.929664) (xy 352.164365 -239.927683) (xy 352.116146 -239.917839)
			(xy 352.07013 -239.900387) (xy 352.027509 -239.87578) (xy 351.989388 -239.844655) (xy 351.956753 -239.807818)
			(xy 351.93045 -239.766222) (xy 351.911159 -239.720946) (xy 351.899382 -239.673162) (xy 351.895422 -239.624108)
			(xy 351.56648 -239.624108) (xy 351.565985 -239.648715) (xy 351.55809 -239.697292) (xy 351.542506 -239.743973)
			(xy 351.519635 -239.78755) (xy 351.49007 -239.826894) (xy 351.454577 -239.860986) (xy 351.414074 -239.888942)
			(xy 351.369612 -239.91004) (xy 351.322341 -239.923732) (xy 351.273486 -239.929664) (xy 351.224311 -239.927683)
			(xy 351.176092 -239.917839) (xy 351.130076 -239.900387) (xy 351.087455 -239.87578) (xy 351.049334 -239.844655)
			(xy 351.016699 -239.807818) (xy 350.990396 -239.766222) (xy 350.971105 -239.720946) (xy 350.959328 -239.673162)
			(xy 350.955368 -239.624108) (xy 350.626426 -239.624108) (xy 350.625931 -239.648715) (xy 350.618036 -239.697292)
			(xy 350.602452 -239.743973) (xy 350.579581 -239.78755) (xy 350.550016 -239.826894) (xy 350.514523 -239.860986)
			(xy 350.47402 -239.888942) (xy 350.429558 -239.91004) (xy 350.382287 -239.923732) (xy 350.333432 -239.929664)
			(xy 350.284257 -239.927683) (xy 350.236038 -239.917839) (xy 350.190022 -239.900387) (xy 350.147401 -239.87578)
			(xy 350.10928 -239.844655) (xy 350.076645 -239.807818) (xy 350.050342 -239.766222) (xy 350.031051 -239.720946)
			(xy 350.019274 -239.673162) (xy 350.015314 -239.624108) (xy 349.686372 -239.624108) (xy 349.685877 -239.648715)
			(xy 349.677982 -239.697292) (xy 349.662398 -239.743973) (xy 349.639527 -239.78755) (xy 349.609962 -239.826894)
			(xy 349.574469 -239.860986) (xy 349.533966 -239.888942) (xy 349.489504 -239.91004) (xy 349.442233 -239.923732)
			(xy 349.393378 -239.929664) (xy 349.344203 -239.927683) (xy 349.295984 -239.917839) (xy 349.249968 -239.900387)
			(xy 349.207347 -239.87578) (xy 349.169226 -239.844655) (xy 349.136591 -239.807818) (xy 349.110288 -239.766222)
			(xy 349.090997 -239.720946) (xy 349.07922 -239.673162) (xy 349.07526 -239.624108) (xy 348.746318 -239.624108)
			(xy 348.745823 -239.648715) (xy 348.737928 -239.697292) (xy 348.722344 -239.743973) (xy 348.699473 -239.78755)
			(xy 348.669908 -239.826894) (xy 348.634415 -239.860986) (xy 348.593912 -239.888942) (xy 348.54945 -239.91004)
			(xy 348.502179 -239.923732) (xy 348.453324 -239.929664) (xy 348.404149 -239.927683) (xy 348.35593 -239.917839)
			(xy 348.309914 -239.900387) (xy 348.267293 -239.87578) (xy 348.229172 -239.844655) (xy 348.196537 -239.807818)
			(xy 348.170234 -239.766222) (xy 348.150943 -239.720946) (xy 348.139166 -239.673162) (xy 348.135206 -239.624108)
			(xy 347.806518 -239.624108) (xy 347.806023 -239.648715) (xy 347.798128 -239.697292) (xy 347.782544 -239.743973)
			(xy 347.759673 -239.78755) (xy 347.730108 -239.826894) (xy 347.694615 -239.860986) (xy 347.654112 -239.888942)
			(xy 347.60965 -239.91004) (xy 347.562379 -239.923732) (xy 347.513524 -239.929664) (xy 347.464349 -239.927683)
			(xy 347.41613 -239.917839) (xy 347.370114 -239.900387) (xy 347.327493 -239.87578) (xy 347.289372 -239.844655)
			(xy 347.256737 -239.807818) (xy 347.230434 -239.766222) (xy 347.211143 -239.720946) (xy 347.199366 -239.673162)
			(xy 347.195406 -239.624108) (xy 346.866464 -239.624108) (xy 346.865969 -239.648715) (xy 346.858074 -239.697292)
			(xy 346.84249 -239.743973) (xy 346.819619 -239.78755) (xy 346.790054 -239.826894) (xy 346.754561 -239.860986)
			(xy 346.714058 -239.888942) (xy 346.669596 -239.91004) (xy 346.622325 -239.923732) (xy 346.57347 -239.929664)
			(xy 346.524295 -239.927683) (xy 346.476076 -239.917839) (xy 346.43006 -239.900387) (xy 346.387439 -239.87578)
			(xy 346.349318 -239.844655) (xy 346.316683 -239.807818) (xy 346.29038 -239.766222) (xy 346.271089 -239.720946)
			(xy 346.259312 -239.673162) (xy 346.255352 -239.624108) (xy 345.92641 -239.624108) (xy 345.925915 -239.648715)
			(xy 345.91802 -239.697292) (xy 345.902436 -239.743973) (xy 345.879565 -239.78755) (xy 345.85 -239.826894)
			(xy 345.814507 -239.860986) (xy 345.774004 -239.888942) (xy 345.729542 -239.91004) (xy 345.682271 -239.923732)
			(xy 345.633416 -239.929664) (xy 345.584241 -239.927683) (xy 345.536022 -239.917839) (xy 345.490006 -239.900387)
			(xy 345.447385 -239.87578) (xy 345.409264 -239.844655) (xy 345.376629 -239.807818) (xy 345.350326 -239.766222)
			(xy 345.331035 -239.720946) (xy 345.319258 -239.673162) (xy 345.315298 -239.624108) (xy 344.986822 -239.624108)
			(xy 344.982653 -239.674432) (xy 344.970256 -239.723391) (xy 344.949971 -239.769642) (xy 344.92235 -239.811924)
			(xy 344.888147 -239.849084) (xy 344.848295 -239.880108) (xy 344.80388 -239.90415) (xy 344.756114 -239.920555)
			(xy 344.7063 -239.928875) (xy 344.681048 -239.929416) (xy 344.653693 -239.928785) (xy 344.599865 -239.918999)
			(xy 344.54864 -239.899785) (xy 344.501654 -239.871757) (xy 344.480642 -239.854232) (xy 344.469212 -239.844326)
			(xy 344.440002 -239.840262) (xy 344.341958 -239.884712) (xy 344.333297 -239.889132) (xy 344.319886 -239.903188)
			(xy 344.312669 -239.921226) (xy 344.31224 -239.93094) (xy 344.31224 -240.127028) (xy 344.327988 -240.151666)
			(xy 344.34145 -240.158016) (xy 344.36354 -240.168968) (xy 344.404163 -240.196908) (xy 344.439768 -240.231013)
			(xy 344.469429 -240.270396) (xy 344.492378 -240.314033) (xy 344.508016 -240.360791) (xy 344.515937 -240.409454)
			(xy 344.515936 -240.434114) (xy 344.845398 -240.434114) (xy 344.849358 -240.38506) (xy 344.861135 -240.337276)
			(xy 344.880426 -240.292) (xy 344.906729 -240.250404) (xy 344.939364 -240.213567) (xy 344.977485 -240.182442)
			(xy 345.020106 -240.157835) (xy 345.066122 -240.140383) (xy 345.114341 -240.130539) (xy 345.163516 -240.128558)
			(xy 345.212371 -240.13449) (xy 345.259642 -240.148182) (xy 345.304104 -240.16928) (xy 345.344607 -240.197236)
			(xy 345.3801 -240.231328) (xy 345.409665 -240.270672) (xy 345.432536 -240.314249) (xy 345.44812 -240.36093)
			(xy 345.456015 -240.409507) (xy 345.45651 -240.434114) (xy 345.785198 -240.434114) (xy 345.789158 -240.38506)
			(xy 345.800935 -240.337276) (xy 345.820226 -240.292) (xy 345.846529 -240.250404) (xy 345.879164 -240.213567)
			(xy 345.917285 -240.182442) (xy 345.959906 -240.157835) (xy 346.005922 -240.140383) (xy 346.054141 -240.130539)
			(xy 346.103316 -240.128558) (xy 346.152171 -240.13449) (xy 346.199442 -240.148182) (xy 346.243904 -240.16928)
			(xy 346.284407 -240.197236) (xy 346.3199 -240.231328) (xy 346.349465 -240.270672) (xy 346.372336 -240.314249)
			(xy 346.38792 -240.36093) (xy 346.395815 -240.409507) (xy 346.39631 -240.434114) (xy 346.725252 -240.434114)
			(xy 346.729212 -240.38506) (xy 346.740989 -240.337276) (xy 346.76028 -240.292) (xy 346.786583 -240.250404)
			(xy 346.819218 -240.213567) (xy 346.857339 -240.182442) (xy 346.89996 -240.157835) (xy 346.945976 -240.140383)
			(xy 346.994195 -240.130539) (xy 347.04337 -240.128558) (xy 347.092225 -240.13449) (xy 347.139496 -240.148182)
			(xy 347.183958 -240.16928) (xy 347.224461 -240.197236) (xy 347.259954 -240.231328) (xy 347.289519 -240.270672)
			(xy 347.31239 -240.314249) (xy 347.327974 -240.36093) (xy 347.335869 -240.409507) (xy 347.336364 -240.434114)
			(xy 347.665306 -240.434114) (xy 347.669266 -240.38506) (xy 347.681043 -240.337276) (xy 347.700334 -240.292)
			(xy 347.726637 -240.250404) (xy 347.759272 -240.213567) (xy 347.797393 -240.182442) (xy 347.840014 -240.157835)
			(xy 347.88603 -240.140383) (xy 347.934249 -240.130539) (xy 347.983424 -240.128558) (xy 348.032279 -240.13449)
			(xy 348.07955 -240.148182) (xy 348.124012 -240.16928) (xy 348.164515 -240.197236) (xy 348.200008 -240.231328)
			(xy 348.229573 -240.270672) (xy 348.252444 -240.314249) (xy 348.268028 -240.36093) (xy 348.275923 -240.409507)
			(xy 348.276418 -240.434114) (xy 348.60536 -240.434114) (xy 348.60932 -240.38506) (xy 348.621097 -240.337276)
			(xy 348.640388 -240.292) (xy 348.666691 -240.250404) (xy 348.699326 -240.213567) (xy 348.737447 -240.182442)
			(xy 348.780068 -240.157835) (xy 348.826084 -240.140383) (xy 348.874303 -240.130539) (xy 348.923478 -240.128558)
			(xy 348.972333 -240.13449) (xy 349.019604 -240.148182) (xy 349.064066 -240.16928) (xy 349.104569 -240.197236)
			(xy 349.140062 -240.231328) (xy 349.169627 -240.270672) (xy 349.192498 -240.314249) (xy 349.208082 -240.36093)
			(xy 349.215977 -240.409507) (xy 349.216472 -240.434114) (xy 349.545414 -240.434114) (xy 349.549374 -240.38506)
			(xy 349.561151 -240.337276) (xy 349.580442 -240.292) (xy 349.606745 -240.250404) (xy 349.63938 -240.213567)
			(xy 349.677501 -240.182442) (xy 349.720122 -240.157835) (xy 349.766138 -240.140383) (xy 349.814357 -240.130539)
			(xy 349.863532 -240.128558) (xy 349.912387 -240.13449) (xy 349.959658 -240.148182) (xy 350.00412 -240.16928)
			(xy 350.044623 -240.197236) (xy 350.080116 -240.231328) (xy 350.109681 -240.270672) (xy 350.132552 -240.314249)
			(xy 350.148136 -240.36093) (xy 350.156031 -240.409507) (xy 350.156526 -240.434114) (xy 350.485214 -240.434114)
			(xy 350.489174 -240.38506) (xy 350.500951 -240.337276) (xy 350.520242 -240.292) (xy 350.546545 -240.250404)
			(xy 350.57918 -240.213567) (xy 350.617301 -240.182442) (xy 350.659922 -240.157835) (xy 350.705938 -240.140383)
			(xy 350.754157 -240.130539) (xy 350.803332 -240.128558) (xy 350.852187 -240.13449) (xy 350.899458 -240.148182)
			(xy 350.94392 -240.16928) (xy 350.984423 -240.197236) (xy 351.019916 -240.231328) (xy 351.049481 -240.270672)
			(xy 351.072352 -240.314249) (xy 351.087936 -240.36093) (xy 351.095831 -240.409507) (xy 351.096326 -240.434114)
			(xy 351.425268 -240.434114) (xy 351.429228 -240.38506) (xy 351.441005 -240.337276) (xy 351.460296 -240.292)
			(xy 351.486599 -240.250404) (xy 351.519234 -240.213567) (xy 351.557355 -240.182442) (xy 351.599976 -240.157835)
			(xy 351.645992 -240.140383) (xy 351.694211 -240.130539) (xy 351.743386 -240.128558) (xy 351.792241 -240.13449)
			(xy 351.839512 -240.148182) (xy 351.883974 -240.16928) (xy 351.924477 -240.197236) (xy 351.95997 -240.231328)
			(xy 351.989535 -240.270672) (xy 352.012406 -240.314249) (xy 352.02799 -240.36093) (xy 352.035885 -240.409507)
			(xy 352.03638 -240.434114) (xy 352.365322 -240.434114) (xy 352.369282 -240.38506) (xy 352.381059 -240.337276)
			(xy 352.40035 -240.292) (xy 352.426653 -240.250404) (xy 352.459288 -240.213567) (xy 352.497409 -240.182442)
			(xy 352.54003 -240.157835) (xy 352.586046 -240.140383) (xy 352.634265 -240.130539) (xy 352.68344 -240.128558)
			(xy 352.732295 -240.13449) (xy 352.779566 -240.148182) (xy 352.824028 -240.16928) (xy 352.864531 -240.197236)
			(xy 352.900024 -240.231328) (xy 352.929589 -240.270672) (xy 352.95246 -240.314249) (xy 352.968044 -240.36093)
			(xy 352.975939 -240.409507) (xy 352.976434 -240.434114) (xy 353.305376 -240.434114) (xy 353.309336 -240.38506)
			(xy 353.321113 -240.337276) (xy 353.340404 -240.292) (xy 353.366707 -240.250404) (xy 353.399342 -240.213567)
			(xy 353.437463 -240.182442) (xy 353.480084 -240.157835) (xy 353.5261 -240.140383) (xy 353.574319 -240.130539)
			(xy 353.623494 -240.128558) (xy 353.672349 -240.13449) (xy 353.71962 -240.148182) (xy 353.764082 -240.16928)
			(xy 353.804585 -240.197236) (xy 353.840078 -240.231328) (xy 353.869643 -240.270672) (xy 353.892514 -240.314249)
			(xy 353.908098 -240.36093) (xy 353.915993 -240.409507) (xy 353.916488 -240.434114) (xy 354.24543 -240.434114)
			(xy 354.24939 -240.38506) (xy 354.261167 -240.337276) (xy 354.280458 -240.292) (xy 354.306761 -240.250404)
			(xy 354.339396 -240.213567) (xy 354.377517 -240.182442) (xy 354.420138 -240.157835) (xy 354.466154 -240.140383)
			(xy 354.514373 -240.130539) (xy 354.563548 -240.128558) (xy 354.612403 -240.13449) (xy 354.659674 -240.148182)
			(xy 354.704136 -240.16928) (xy 354.744639 -240.197236) (xy 354.780132 -240.231328) (xy 354.809697 -240.270672)
			(xy 354.832568 -240.314249) (xy 354.848152 -240.36093) (xy 354.856047 -240.409507) (xy 354.856542 -240.434114)
			(xy 355.18523 -240.434114) (xy 355.18919 -240.38506) (xy 355.200967 -240.337276) (xy 355.220258 -240.292)
			(xy 355.246561 -240.250404) (xy 355.279196 -240.213567) (xy 355.317317 -240.182442) (xy 355.359938 -240.157835)
			(xy 355.405954 -240.140383) (xy 355.454173 -240.130539) (xy 355.503348 -240.128558) (xy 355.552203 -240.13449)
			(xy 355.599474 -240.148182) (xy 355.643936 -240.16928) (xy 355.684439 -240.197236) (xy 355.719932 -240.231328)
			(xy 355.749497 -240.270672) (xy 355.772368 -240.314249) (xy 355.787952 -240.36093) (xy 355.795847 -240.409507)
			(xy 355.796342 -240.434114) (xy 356.125284 -240.434114) (xy 356.129244 -240.38506) (xy 356.141021 -240.337276)
			(xy 356.160312 -240.292) (xy 356.186615 -240.250404) (xy 356.21925 -240.213567) (xy 356.257371 -240.182442)
			(xy 356.299992 -240.157835) (xy 356.346008 -240.140383) (xy 356.394227 -240.130539) (xy 356.443402 -240.128558)
			(xy 356.492257 -240.13449) (xy 356.539528 -240.148182) (xy 356.58399 -240.16928) (xy 356.624493 -240.197236)
			(xy 356.659986 -240.231328) (xy 356.689551 -240.270672) (xy 356.712422 -240.314249) (xy 356.728006 -240.36093)
			(xy 356.735901 -240.409507) (xy 356.736396 -240.434114) (xy 357.065338 -240.434114) (xy 357.069298 -240.38506)
			(xy 357.081075 -240.337276) (xy 357.100366 -240.292) (xy 357.126669 -240.250404) (xy 357.159304 -240.213567)
			(xy 357.197425 -240.182442) (xy 357.240046 -240.157835) (xy 357.286062 -240.140383) (xy 357.334281 -240.130539)
			(xy 357.383456 -240.128558) (xy 357.432311 -240.13449) (xy 357.479582 -240.148182) (xy 357.524044 -240.16928)
			(xy 357.564547 -240.197236) (xy 357.60004 -240.231328) (xy 357.629605 -240.270672) (xy 357.652476 -240.314249)
			(xy 357.66806 -240.36093) (xy 357.675955 -240.409507) (xy 357.67645 -240.434114) (xy 358.005392 -240.434114)
			(xy 358.009352 -240.38506) (xy 358.021129 -240.337276) (xy 358.04042 -240.292) (xy 358.066723 -240.250404)
			(xy 358.099358 -240.213567) (xy 358.137479 -240.182442) (xy 358.1801 -240.157835) (xy 358.226116 -240.140383)
			(xy 358.274335 -240.130539) (xy 358.32351 -240.128558) (xy 358.372365 -240.13449) (xy 358.419636 -240.148182)
			(xy 358.464098 -240.16928) (xy 358.504601 -240.197236) (xy 358.540094 -240.231328) (xy 358.569659 -240.270672)
			(xy 358.59253 -240.314249) (xy 358.608114 -240.36093) (xy 358.616009 -240.409507) (xy 358.616504 -240.434114)
			(xy 358.616009 -240.458721) (xy 358.608114 -240.507298) (xy 358.59253 -240.553979) (xy 358.569659 -240.597556)
			(xy 358.540094 -240.6369) (xy 358.504601 -240.670992) (xy 358.464098 -240.698948) (xy 358.419636 -240.720046)
			(xy 358.372365 -240.733738) (xy 358.32351 -240.73967) (xy 358.274335 -240.737689) (xy 358.226116 -240.727845)
			(xy 358.1801 -240.710393) (xy 358.137479 -240.685786) (xy 358.099358 -240.654661) (xy 358.066723 -240.617824)
			(xy 358.04042 -240.576228) (xy 358.021129 -240.530952) (xy 358.009352 -240.483168) (xy 358.005392 -240.434114)
			(xy 357.67645 -240.434114) (xy 357.675955 -240.458721) (xy 357.66806 -240.507298) (xy 357.652476 -240.553979)
			(xy 357.629605 -240.597556) (xy 357.60004 -240.6369) (xy 357.564547 -240.670992) (xy 357.524044 -240.698948)
			(xy 357.479582 -240.720046) (xy 357.432311 -240.733738) (xy 357.383456 -240.73967) (xy 357.334281 -240.737689)
			(xy 357.286062 -240.727845) (xy 357.240046 -240.710393) (xy 357.197425 -240.685786) (xy 357.159304 -240.654661)
			(xy 357.126669 -240.617824) (xy 357.100366 -240.576228) (xy 357.081075 -240.530952) (xy 357.069298 -240.483168)
			(xy 357.065338 -240.434114) (xy 356.736396 -240.434114) (xy 356.735901 -240.458721) (xy 356.728006 -240.507298)
			(xy 356.712422 -240.553979) (xy 356.689551 -240.597556) (xy 356.659986 -240.6369) (xy 356.624493 -240.670992)
			(xy 356.58399 -240.698948) (xy 356.539528 -240.720046) (xy 356.492257 -240.733738) (xy 356.443402 -240.73967)
			(xy 356.394227 -240.737689) (xy 356.346008 -240.727845) (xy 356.299992 -240.710393) (xy 356.257371 -240.685786)
			(xy 356.21925 -240.654661) (xy 356.186615 -240.617824) (xy 356.160312 -240.576228) (xy 356.141021 -240.530952)
			(xy 356.129244 -240.483168) (xy 356.125284 -240.434114) (xy 355.796342 -240.434114) (xy 355.795847 -240.458721)
			(xy 355.787952 -240.507298) (xy 355.772368 -240.553979) (xy 355.749497 -240.597556) (xy 355.719932 -240.6369)
			(xy 355.684439 -240.670992) (xy 355.643936 -240.698948) (xy 355.599474 -240.720046) (xy 355.552203 -240.733738)
			(xy 355.503348 -240.73967) (xy 355.454173 -240.737689) (xy 355.405954 -240.727845) (xy 355.359938 -240.710393)
			(xy 355.317317 -240.685786) (xy 355.279196 -240.654661) (xy 355.246561 -240.617824) (xy 355.220258 -240.576228)
			(xy 355.200967 -240.530952) (xy 355.18919 -240.483168) (xy 355.18523 -240.434114) (xy 354.856542 -240.434114)
			(xy 354.856047 -240.458721) (xy 354.848152 -240.507298) (xy 354.832568 -240.553979) (xy 354.809697 -240.597556)
			(xy 354.780132 -240.6369) (xy 354.744639 -240.670992) (xy 354.704136 -240.698948) (xy 354.659674 -240.720046)
			(xy 354.612403 -240.733738) (xy 354.563548 -240.73967) (xy 354.514373 -240.737689) (xy 354.466154 -240.727845)
			(xy 354.420138 -240.710393) (xy 354.377517 -240.685786) (xy 354.339396 -240.654661) (xy 354.306761 -240.617824)
			(xy 354.280458 -240.576228) (xy 354.261167 -240.530952) (xy 354.24939 -240.483168) (xy 354.24543 -240.434114)
			(xy 353.916488 -240.434114) (xy 353.915993 -240.458721) (xy 353.908098 -240.507298) (xy 353.892514 -240.553979)
			(xy 353.869643 -240.597556) (xy 353.840078 -240.6369) (xy 353.804585 -240.670992) (xy 353.764082 -240.698948)
			(xy 353.71962 -240.720046) (xy 353.672349 -240.733738) (xy 353.623494 -240.73967) (xy 353.574319 -240.737689)
			(xy 353.5261 -240.727845) (xy 353.480084 -240.710393) (xy 353.437463 -240.685786) (xy 353.399342 -240.654661)
			(xy 353.366707 -240.617824) (xy 353.340404 -240.576228) (xy 353.321113 -240.530952) (xy 353.309336 -240.483168)
			(xy 353.305376 -240.434114) (xy 352.976434 -240.434114) (xy 352.975939 -240.458721) (xy 352.968044 -240.507298)
			(xy 352.95246 -240.553979) (xy 352.929589 -240.597556) (xy 352.900024 -240.6369) (xy 352.864531 -240.670992)
			(xy 352.824028 -240.698948) (xy 352.779566 -240.720046) (xy 352.732295 -240.733738) (xy 352.68344 -240.73967)
			(xy 352.634265 -240.737689) (xy 352.586046 -240.727845) (xy 352.54003 -240.710393) (xy 352.497409 -240.685786)
			(xy 352.459288 -240.654661) (xy 352.426653 -240.617824) (xy 352.40035 -240.576228) (xy 352.381059 -240.530952)
			(xy 352.369282 -240.483168) (xy 352.365322 -240.434114) (xy 352.03638 -240.434114) (xy 352.035885 -240.458721)
			(xy 352.02799 -240.507298) (xy 352.012406 -240.553979) (xy 351.989535 -240.597556) (xy 351.95997 -240.6369)
			(xy 351.924477 -240.670992) (xy 351.883974 -240.698948) (xy 351.839512 -240.720046) (xy 351.792241 -240.733738)
			(xy 351.743386 -240.73967) (xy 351.694211 -240.737689) (xy 351.645992 -240.727845) (xy 351.599976 -240.710393)
			(xy 351.557355 -240.685786) (xy 351.519234 -240.654661) (xy 351.486599 -240.617824) (xy 351.460296 -240.576228)
			(xy 351.441005 -240.530952) (xy 351.429228 -240.483168) (xy 351.425268 -240.434114) (xy 351.096326 -240.434114)
			(xy 351.095831 -240.458721) (xy 351.087936 -240.507298) (xy 351.072352 -240.553979) (xy 351.049481 -240.597556)
			(xy 351.019916 -240.6369) (xy 350.984423 -240.670992) (xy 350.94392 -240.698948) (xy 350.899458 -240.720046)
			(xy 350.852187 -240.733738) (xy 350.803332 -240.73967) (xy 350.754157 -240.737689) (xy 350.705938 -240.727845)
			(xy 350.659922 -240.710393) (xy 350.617301 -240.685786) (xy 350.57918 -240.654661) (xy 350.546545 -240.617824)
			(xy 350.520242 -240.576228) (xy 350.500951 -240.530952) (xy 350.489174 -240.483168) (xy 350.485214 -240.434114)
			(xy 350.156526 -240.434114) (xy 350.156031 -240.458721) (xy 350.148136 -240.507298) (xy 350.132552 -240.553979)
			(xy 350.109681 -240.597556) (xy 350.080116 -240.6369) (xy 350.044623 -240.670992) (xy 350.00412 -240.698948)
			(xy 349.959658 -240.720046) (xy 349.912387 -240.733738) (xy 349.863532 -240.73967) (xy 349.814357 -240.737689)
			(xy 349.766138 -240.727845) (xy 349.720122 -240.710393) (xy 349.677501 -240.685786) (xy 349.63938 -240.654661)
			(xy 349.606745 -240.617824) (xy 349.580442 -240.576228) (xy 349.561151 -240.530952) (xy 349.549374 -240.483168)
			(xy 349.545414 -240.434114) (xy 349.216472 -240.434114) (xy 349.215977 -240.458721) (xy 349.208082 -240.507298)
			(xy 349.192498 -240.553979) (xy 349.169627 -240.597556) (xy 349.140062 -240.6369) (xy 349.104569 -240.670992)
			(xy 349.064066 -240.698948) (xy 349.019604 -240.720046) (xy 348.972333 -240.733738) (xy 348.923478 -240.73967)
			(xy 348.874303 -240.737689) (xy 348.826084 -240.727845) (xy 348.780068 -240.710393) (xy 348.737447 -240.685786)
			(xy 348.699326 -240.654661) (xy 348.666691 -240.617824) (xy 348.640388 -240.576228) (xy 348.621097 -240.530952)
			(xy 348.60932 -240.483168) (xy 348.60536 -240.434114) (xy 348.276418 -240.434114) (xy 348.275923 -240.458721)
			(xy 348.268028 -240.507298) (xy 348.252444 -240.553979) (xy 348.229573 -240.597556) (xy 348.200008 -240.6369)
			(xy 348.164515 -240.670992) (xy 348.124012 -240.698948) (xy 348.07955 -240.720046) (xy 348.032279 -240.733738)
			(xy 347.983424 -240.73967) (xy 347.934249 -240.737689) (xy 347.88603 -240.727845) (xy 347.840014 -240.710393)
			(xy 347.797393 -240.685786) (xy 347.759272 -240.654661) (xy 347.726637 -240.617824) (xy 347.700334 -240.576228)
			(xy 347.681043 -240.530952) (xy 347.669266 -240.483168) (xy 347.665306 -240.434114) (xy 347.336364 -240.434114)
			(xy 347.335869 -240.458721) (xy 347.327974 -240.507298) (xy 347.31239 -240.553979) (xy 347.289519 -240.597556)
			(xy 347.259954 -240.6369) (xy 347.224461 -240.670992) (xy 347.183958 -240.698948) (xy 347.139496 -240.720046)
			(xy 347.092225 -240.733738) (xy 347.04337 -240.73967) (xy 346.994195 -240.737689) (xy 346.945976 -240.727845)
			(xy 346.89996 -240.710393) (xy 346.857339 -240.685786) (xy 346.819218 -240.654661) (xy 346.786583 -240.617824)
			(xy 346.76028 -240.576228) (xy 346.740989 -240.530952) (xy 346.729212 -240.483168) (xy 346.725252 -240.434114)
			(xy 346.39631 -240.434114) (xy 346.395815 -240.458721) (xy 346.38792 -240.507298) (xy 346.372336 -240.553979)
			(xy 346.349465 -240.597556) (xy 346.3199 -240.6369) (xy 346.284407 -240.670992) (xy 346.243904 -240.698948)
			(xy 346.199442 -240.720046) (xy 346.152171 -240.733738) (xy 346.103316 -240.73967) (xy 346.054141 -240.737689)
			(xy 346.005922 -240.727845) (xy 345.959906 -240.710393) (xy 345.917285 -240.685786) (xy 345.879164 -240.654661)
			(xy 345.846529 -240.617824) (xy 345.820226 -240.576228) (xy 345.800935 -240.530952) (xy 345.789158 -240.483168)
			(xy 345.785198 -240.434114) (xy 345.45651 -240.434114) (xy 345.456015 -240.458721) (xy 345.44812 -240.507298)
			(xy 345.432536 -240.553979) (xy 345.409665 -240.597556) (xy 345.3801 -240.6369) (xy 345.344607 -240.670992)
			(xy 345.304104 -240.698948) (xy 345.259642 -240.720046) (xy 345.212371 -240.733738) (xy 345.163516 -240.73967)
			(xy 345.114341 -240.737689) (xy 345.066122 -240.727845) (xy 345.020106 -240.710393) (xy 344.977485 -240.685786)
			(xy 344.939364 -240.654661) (xy 344.906729 -240.617824) (xy 344.880426 -240.576228) (xy 344.861135 -240.530952)
			(xy 344.849358 -240.483168) (xy 344.845398 -240.434114) (xy 344.515936 -240.434114) (xy 344.515936 -240.458758)
			(xy 344.508013 -240.50742) (xy 344.492373 -240.554178) (xy 344.469423 -240.597814) (xy 344.43976 -240.637196)
			(xy 344.404153 -240.671299) (xy 344.36353 -240.699238) (xy 344.34145 -240.710212) (xy 344.327988 -240.716562)
			(xy 344.31224 -240.7412) (xy 344.31224 -240.937288) (xy 344.312667 -240.947004) (xy 344.319883 -240.965047)
			(xy 344.333285 -240.979118) (xy 344.341958 -240.983516) (xy 344.440002 -241.027966) (xy 344.469212 -241.023902)
			(xy 344.480642 -241.013996) (xy 344.50166 -240.996478) (xy 344.548641 -240.968446) (xy 344.599866 -240.949234)
			(xy 344.653694 -240.939459) (xy 344.681048 -240.938812) (xy 344.706299 -240.939337) (xy 344.756111 -240.947657)
			(xy 344.803875 -240.964061) (xy 344.848288 -240.988102) (xy 344.888139 -241.019125) (xy 344.92234 -241.056283)
			(xy 344.94996 -241.098563) (xy 344.970245 -241.144813) (xy 344.982641 -241.19377) (xy 344.986811 -241.2441)
			(xy 344.986809 -241.24412) (xy 345.315298 -241.24412) (xy 345.319258 -241.195066) (xy 345.331035 -241.147282)
			(xy 345.350326 -241.102006) (xy 345.376629 -241.06041) (xy 345.409264 -241.023573) (xy 345.447385 -240.992448)
			(xy 345.490006 -240.967841) (xy 345.536022 -240.950389) (xy 345.584241 -240.940545) (xy 345.633416 -240.938564)
			(xy 345.682271 -240.944496) (xy 345.729542 -240.958188) (xy 345.774004 -240.979286) (xy 345.814507 -241.007242)
			(xy 345.85 -241.041334) (xy 345.879565 -241.080678) (xy 345.902436 -241.124255) (xy 345.91802 -241.170936)
			(xy 345.925915 -241.219513) (xy 345.92641 -241.24412) (xy 346.255352 -241.24412) (xy 346.259312 -241.195066)
			(xy 346.271089 -241.147282) (xy 346.29038 -241.102006) (xy 346.316683 -241.06041) (xy 346.349318 -241.023573)
			(xy 346.387439 -240.992448) (xy 346.43006 -240.967841) (xy 346.476076 -240.950389) (xy 346.524295 -240.940545)
			(xy 346.57347 -240.938564) (xy 346.622325 -240.944496) (xy 346.669596 -240.958188) (xy 346.714058 -240.979286)
			(xy 346.754561 -241.007242) (xy 346.790054 -241.041334) (xy 346.819619 -241.080678) (xy 346.84249 -241.124255)
			(xy 346.858074 -241.170936) (xy 346.865969 -241.219513) (xy 346.866464 -241.24412) (xy 347.195406 -241.24412)
			(xy 347.199366 -241.195066) (xy 347.211143 -241.147282) (xy 347.230434 -241.102006) (xy 347.256737 -241.06041)
			(xy 347.289372 -241.023573) (xy 347.327493 -240.992448) (xy 347.370114 -240.967841) (xy 347.41613 -240.950389)
			(xy 347.464349 -240.940545) (xy 347.513524 -240.938564) (xy 347.562379 -240.944496) (xy 347.60965 -240.958188)
			(xy 347.654112 -240.979286) (xy 347.694615 -241.007242) (xy 347.730108 -241.041334) (xy 347.759673 -241.080678)
			(xy 347.782544 -241.124255) (xy 347.798128 -241.170936) (xy 347.806023 -241.219513) (xy 347.806518 -241.24412)
			(xy 348.135206 -241.24412) (xy 348.139166 -241.195066) (xy 348.150943 -241.147282) (xy 348.170234 -241.102006)
			(xy 348.196537 -241.06041) (xy 348.229172 -241.023573) (xy 348.267293 -240.992448) (xy 348.309914 -240.967841)
			(xy 348.35593 -240.950389) (xy 348.404149 -240.940545) (xy 348.453324 -240.938564) (xy 348.502179 -240.944496)
			(xy 348.54945 -240.958188) (xy 348.593912 -240.979286) (xy 348.634415 -241.007242) (xy 348.669908 -241.041334)
			(xy 348.699473 -241.080678) (xy 348.722344 -241.124255) (xy 348.737928 -241.170936) (xy 348.745823 -241.219513)
			(xy 348.746318 -241.24412) (xy 349.07526 -241.24412) (xy 349.07922 -241.195066) (xy 349.090997 -241.147282)
			(xy 349.110288 -241.102006) (xy 349.136591 -241.06041) (xy 349.169226 -241.023573) (xy 349.207347 -240.992448)
			(xy 349.249968 -240.967841) (xy 349.295984 -240.950389) (xy 349.344203 -240.940545) (xy 349.393378 -240.938564)
			(xy 349.442233 -240.944496) (xy 349.489504 -240.958188) (xy 349.533966 -240.979286) (xy 349.574469 -241.007242)
			(xy 349.609962 -241.041334) (xy 349.639527 -241.080678) (xy 349.662398 -241.124255) (xy 349.677982 -241.170936)
			(xy 349.685877 -241.219513) (xy 349.686372 -241.24412) (xy 350.015314 -241.24412) (xy 350.019274 -241.195066)
			(xy 350.031051 -241.147282) (xy 350.050342 -241.102006) (xy 350.076645 -241.06041) (xy 350.10928 -241.023573)
			(xy 350.147401 -240.992448) (xy 350.190022 -240.967841) (xy 350.236038 -240.950389) (xy 350.284257 -240.940545)
			(xy 350.333432 -240.938564) (xy 350.382287 -240.944496) (xy 350.429558 -240.958188) (xy 350.47402 -240.979286)
			(xy 350.514523 -241.007242) (xy 350.550016 -241.041334) (xy 350.579581 -241.080678) (xy 350.602452 -241.124255)
			(xy 350.618036 -241.170936) (xy 350.625931 -241.219513) (xy 350.626426 -241.24412) (xy 350.955368 -241.24412)
			(xy 350.959328 -241.195066) (xy 350.971105 -241.147282) (xy 350.990396 -241.102006) (xy 351.016699 -241.06041)
			(xy 351.049334 -241.023573) (xy 351.087455 -240.992448) (xy 351.130076 -240.967841) (xy 351.176092 -240.950389)
			(xy 351.224311 -240.940545) (xy 351.273486 -240.938564) (xy 351.322341 -240.944496) (xy 351.369612 -240.958188)
			(xy 351.414074 -240.979286) (xy 351.454577 -241.007242) (xy 351.49007 -241.041334) (xy 351.519635 -241.080678)
			(xy 351.542506 -241.124255) (xy 351.55809 -241.170936) (xy 351.565985 -241.219513) (xy 351.56648 -241.24412)
			(xy 351.895422 -241.24412) (xy 351.899382 -241.195066) (xy 351.911159 -241.147282) (xy 351.93045 -241.102006)
			(xy 351.956753 -241.06041) (xy 351.989388 -241.023573) (xy 352.027509 -240.992448) (xy 352.07013 -240.967841)
			(xy 352.116146 -240.950389) (xy 352.164365 -240.940545) (xy 352.21354 -240.938564) (xy 352.262395 -240.944496)
			(xy 352.309666 -240.958188) (xy 352.354128 -240.979286) (xy 352.394631 -241.007242) (xy 352.430124 -241.041334)
			(xy 352.459689 -241.080678) (xy 352.48256 -241.124255) (xy 352.498144 -241.170936) (xy 352.506039 -241.219513)
			(xy 352.506534 -241.24412) (xy 352.835222 -241.24412) (xy 352.839182 -241.195066) (xy 352.850959 -241.147282)
			(xy 352.87025 -241.102006) (xy 352.896553 -241.06041) (xy 352.929188 -241.023573) (xy 352.967309 -240.992448)
			(xy 353.00993 -240.967841) (xy 353.055946 -240.950389) (xy 353.104165 -240.940545) (xy 353.15334 -240.938564)
			(xy 353.202195 -240.944496) (xy 353.249466 -240.958188) (xy 353.293928 -240.979286) (xy 353.334431 -241.007242)
			(xy 353.369924 -241.041334) (xy 353.399489 -241.080678) (xy 353.42236 -241.124255) (xy 353.437944 -241.170936)
			(xy 353.445839 -241.219513) (xy 353.446334 -241.24412) (xy 353.775276 -241.24412) (xy 353.779236 -241.195066)
			(xy 353.791013 -241.147282) (xy 353.810304 -241.102006) (xy 353.836607 -241.06041) (xy 353.869242 -241.023573)
			(xy 353.907363 -240.992448) (xy 353.949984 -240.967841) (xy 353.996 -240.950389) (xy 354.044219 -240.940545)
			(xy 354.093394 -240.938564) (xy 354.142249 -240.944496) (xy 354.18952 -240.958188) (xy 354.233982 -240.979286)
			(xy 354.274485 -241.007242) (xy 354.309978 -241.041334) (xy 354.339543 -241.080678) (xy 354.362414 -241.124255)
			(xy 354.377998 -241.170936) (xy 354.385893 -241.219513) (xy 354.386388 -241.24412) (xy 354.71533 -241.24412)
			(xy 354.71929 -241.195066) (xy 354.731067 -241.147282) (xy 354.750358 -241.102006) (xy 354.776661 -241.06041)
			(xy 354.809296 -241.023573) (xy 354.847417 -240.992448) (xy 354.890038 -240.967841) (xy 354.936054 -240.950389)
			(xy 354.984273 -240.940545) (xy 355.033448 -240.938564) (xy 355.082303 -240.944496) (xy 355.129574 -240.958188)
			(xy 355.174036 -240.979286) (xy 355.214539 -241.007242) (xy 355.250032 -241.041334) (xy 355.279597 -241.080678)
			(xy 355.302468 -241.124255) (xy 355.318052 -241.170936) (xy 355.325947 -241.219513) (xy 355.326442 -241.24412)
			(xy 355.655384 -241.24412) (xy 355.659344 -241.195066) (xy 355.671121 -241.147282) (xy 355.690412 -241.102006)
			(xy 355.716715 -241.06041) (xy 355.74935 -241.023573) (xy 355.787471 -240.992448) (xy 355.830092 -240.967841)
			(xy 355.876108 -240.950389) (xy 355.924327 -240.940545) (xy 355.973502 -240.938564) (xy 356.022357 -240.944496)
			(xy 356.069628 -240.958188) (xy 356.11409 -240.979286) (xy 356.154593 -241.007242) (xy 356.190086 -241.041334)
			(xy 356.219651 -241.080678) (xy 356.242522 -241.124255) (xy 356.258106 -241.170936) (xy 356.266001 -241.219513)
			(xy 356.266496 -241.24412) (xy 356.595438 -241.24412) (xy 356.599398 -241.195066) (xy 356.611175 -241.147282)
			(xy 356.630466 -241.102006) (xy 356.656769 -241.06041) (xy 356.689404 -241.023573) (xy 356.727525 -240.992448)
			(xy 356.770146 -240.967841) (xy 356.816162 -240.950389) (xy 356.864381 -240.940545) (xy 356.913556 -240.938564)
			(xy 356.962411 -240.944496) (xy 357.009682 -240.958188) (xy 357.054144 -240.979286) (xy 357.094647 -241.007242)
			(xy 357.13014 -241.041334) (xy 357.159705 -241.080678) (xy 357.182576 -241.124255) (xy 357.19816 -241.170936)
			(xy 357.206055 -241.219513) (xy 357.20655 -241.24412) (xy 357.535238 -241.24412) (xy 357.539198 -241.195066)
			(xy 357.550975 -241.147282) (xy 357.570266 -241.102006) (xy 357.596569 -241.06041) (xy 357.629204 -241.023573)
			(xy 357.667325 -240.992448) (xy 357.709946 -240.967841) (xy 357.755962 -240.950389) (xy 357.804181 -240.940545)
			(xy 357.853356 -240.938564) (xy 357.902211 -240.944496) (xy 357.949482 -240.958188) (xy 357.993944 -240.979286)
			(xy 358.034447 -241.007242) (xy 358.06994 -241.041334) (xy 358.099505 -241.080678) (xy 358.122376 -241.124255)
			(xy 358.13796 -241.170936) (xy 358.145855 -241.219513) (xy 358.14635 -241.24412) (xy 358.145855 -241.268727)
			(xy 358.13796 -241.317304) (xy 358.122376 -241.363985) (xy 358.099505 -241.407562) (xy 358.06994 -241.446906)
			(xy 358.034447 -241.480998) (xy 357.993944 -241.508954) (xy 357.949482 -241.530052) (xy 357.902211 -241.543744)
			(xy 357.853356 -241.549676) (xy 357.804181 -241.547695) (xy 357.755962 -241.537851) (xy 357.709946 -241.520399)
			(xy 357.667325 -241.495792) (xy 357.629204 -241.464667) (xy 357.596569 -241.42783) (xy 357.570266 -241.386234)
			(xy 357.550975 -241.340958) (xy 357.539198 -241.293174) (xy 357.535238 -241.24412) (xy 357.20655 -241.24412)
			(xy 357.206055 -241.268727) (xy 357.19816 -241.317304) (xy 357.182576 -241.363985) (xy 357.159705 -241.407562)
			(xy 357.13014 -241.446906) (xy 357.094647 -241.480998) (xy 357.054144 -241.508954) (xy 357.009682 -241.530052)
			(xy 356.962411 -241.543744) (xy 356.913556 -241.549676) (xy 356.864381 -241.547695) (xy 356.816162 -241.537851)
			(xy 356.770146 -241.520399) (xy 356.727525 -241.495792) (xy 356.689404 -241.464667) (xy 356.656769 -241.42783)
			(xy 356.630466 -241.386234) (xy 356.611175 -241.340958) (xy 356.599398 -241.293174) (xy 356.595438 -241.24412)
			(xy 356.266496 -241.24412) (xy 356.266001 -241.268727) (xy 356.258106 -241.317304) (xy 356.242522 -241.363985)
			(xy 356.219651 -241.407562) (xy 356.190086 -241.446906) (xy 356.154593 -241.480998) (xy 356.11409 -241.508954)
			(xy 356.069628 -241.530052) (xy 356.022357 -241.543744) (xy 355.973502 -241.549676) (xy 355.924327 -241.547695)
			(xy 355.876108 -241.537851) (xy 355.830092 -241.520399) (xy 355.787471 -241.495792) (xy 355.74935 -241.464667)
			(xy 355.716715 -241.42783) (xy 355.690412 -241.386234) (xy 355.671121 -241.340958) (xy 355.659344 -241.293174)
			(xy 355.655384 -241.24412) (xy 355.326442 -241.24412) (xy 355.325947 -241.268727) (xy 355.318052 -241.317304)
			(xy 355.302468 -241.363985) (xy 355.279597 -241.407562) (xy 355.250032 -241.446906) (xy 355.214539 -241.480998)
			(xy 355.174036 -241.508954) (xy 355.129574 -241.530052) (xy 355.082303 -241.543744) (xy 355.033448 -241.549676)
			(xy 354.984273 -241.547695) (xy 354.936054 -241.537851) (xy 354.890038 -241.520399) (xy 354.847417 -241.495792)
			(xy 354.809296 -241.464667) (xy 354.776661 -241.42783) (xy 354.750358 -241.386234) (xy 354.731067 -241.340958)
			(xy 354.71929 -241.293174) (xy 354.71533 -241.24412) (xy 354.386388 -241.24412) (xy 354.385893 -241.268727)
			(xy 354.377998 -241.317304) (xy 354.362414 -241.363985) (xy 354.339543 -241.407562) (xy 354.309978 -241.446906)
			(xy 354.274485 -241.480998) (xy 354.233982 -241.508954) (xy 354.18952 -241.530052) (xy 354.142249 -241.543744)
			(xy 354.093394 -241.549676) (xy 354.044219 -241.547695) (xy 353.996 -241.537851) (xy 353.949984 -241.520399)
			(xy 353.907363 -241.495792) (xy 353.869242 -241.464667) (xy 353.836607 -241.42783) (xy 353.810304 -241.386234)
			(xy 353.791013 -241.340958) (xy 353.779236 -241.293174) (xy 353.775276 -241.24412) (xy 353.446334 -241.24412)
			(xy 353.445839 -241.268727) (xy 353.437944 -241.317304) (xy 353.42236 -241.363985) (xy 353.399489 -241.407562)
			(xy 353.369924 -241.446906) (xy 353.334431 -241.480998) (xy 353.293928 -241.508954) (xy 353.249466 -241.530052)
			(xy 353.202195 -241.543744) (xy 353.15334 -241.549676) (xy 353.104165 -241.547695) (xy 353.055946 -241.537851)
			(xy 353.00993 -241.520399) (xy 352.967309 -241.495792) (xy 352.929188 -241.464667) (xy 352.896553 -241.42783)
			(xy 352.87025 -241.386234) (xy 352.850959 -241.340958) (xy 352.839182 -241.293174) (xy 352.835222 -241.24412)
			(xy 352.506534 -241.24412) (xy 352.506039 -241.268727) (xy 352.498144 -241.317304) (xy 352.48256 -241.363985)
			(xy 352.459689 -241.407562) (xy 352.430124 -241.446906) (xy 352.394631 -241.480998) (xy 352.354128 -241.508954)
			(xy 352.309666 -241.530052) (xy 352.262395 -241.543744) (xy 352.21354 -241.549676) (xy 352.164365 -241.547695)
			(xy 352.116146 -241.537851) (xy 352.07013 -241.520399) (xy 352.027509 -241.495792) (xy 351.989388 -241.464667)
			(xy 351.956753 -241.42783) (xy 351.93045 -241.386234) (xy 351.911159 -241.340958) (xy 351.899382 -241.293174)
			(xy 351.895422 -241.24412) (xy 351.56648 -241.24412) (xy 351.565985 -241.268727) (xy 351.55809 -241.317304)
			(xy 351.542506 -241.363985) (xy 351.519635 -241.407562) (xy 351.49007 -241.446906) (xy 351.454577 -241.480998)
			(xy 351.414074 -241.508954) (xy 351.369612 -241.530052) (xy 351.322341 -241.543744) (xy 351.273486 -241.549676)
			(xy 351.224311 -241.547695) (xy 351.176092 -241.537851) (xy 351.130076 -241.520399) (xy 351.087455 -241.495792)
			(xy 351.049334 -241.464667) (xy 351.016699 -241.42783) (xy 350.990396 -241.386234) (xy 350.971105 -241.340958)
			(xy 350.959328 -241.293174) (xy 350.955368 -241.24412) (xy 350.626426 -241.24412) (xy 350.625931 -241.268727)
			(xy 350.618036 -241.317304) (xy 350.602452 -241.363985) (xy 350.579581 -241.407562) (xy 350.550016 -241.446906)
			(xy 350.514523 -241.480998) (xy 350.47402 -241.508954) (xy 350.429558 -241.530052) (xy 350.382287 -241.543744)
			(xy 350.333432 -241.549676) (xy 350.284257 -241.547695) (xy 350.236038 -241.537851) (xy 350.190022 -241.520399)
			(xy 350.147401 -241.495792) (xy 350.10928 -241.464667) (xy 350.076645 -241.42783) (xy 350.050342 -241.386234)
			(xy 350.031051 -241.340958) (xy 350.019274 -241.293174) (xy 350.015314 -241.24412) (xy 349.686372 -241.24412)
			(xy 349.685877 -241.268727) (xy 349.677982 -241.317304) (xy 349.662398 -241.363985) (xy 349.639527 -241.407562)
			(xy 349.609962 -241.446906) (xy 349.574469 -241.480998) (xy 349.533966 -241.508954) (xy 349.489504 -241.530052)
			(xy 349.442233 -241.543744) (xy 349.393378 -241.549676) (xy 349.344203 -241.547695) (xy 349.295984 -241.537851)
			(xy 349.249968 -241.520399) (xy 349.207347 -241.495792) (xy 349.169226 -241.464667) (xy 349.136591 -241.42783)
			(xy 349.110288 -241.386234) (xy 349.090997 -241.340958) (xy 349.07922 -241.293174) (xy 349.07526 -241.24412)
			(xy 348.746318 -241.24412) (xy 348.745823 -241.268727) (xy 348.737928 -241.317304) (xy 348.722344 -241.363985)
			(xy 348.699473 -241.407562) (xy 348.669908 -241.446906) (xy 348.634415 -241.480998) (xy 348.593912 -241.508954)
			(xy 348.54945 -241.530052) (xy 348.502179 -241.543744) (xy 348.453324 -241.549676) (xy 348.404149 -241.547695)
			(xy 348.35593 -241.537851) (xy 348.309914 -241.520399) (xy 348.267293 -241.495792) (xy 348.229172 -241.464667)
			(xy 348.196537 -241.42783) (xy 348.170234 -241.386234) (xy 348.150943 -241.340958) (xy 348.139166 -241.293174)
			(xy 348.135206 -241.24412) (xy 347.806518 -241.24412) (xy 347.806023 -241.268727) (xy 347.798128 -241.317304)
			(xy 347.782544 -241.363985) (xy 347.759673 -241.407562) (xy 347.730108 -241.446906) (xy 347.694615 -241.480998)
			(xy 347.654112 -241.508954) (xy 347.60965 -241.530052) (xy 347.562379 -241.543744) (xy 347.513524 -241.549676)
			(xy 347.464349 -241.547695) (xy 347.41613 -241.537851) (xy 347.370114 -241.520399) (xy 347.327493 -241.495792)
			(xy 347.289372 -241.464667) (xy 347.256737 -241.42783) (xy 347.230434 -241.386234) (xy 347.211143 -241.340958)
			(xy 347.199366 -241.293174) (xy 347.195406 -241.24412) (xy 346.866464 -241.24412) (xy 346.865969 -241.268727)
			(xy 346.858074 -241.317304) (xy 346.84249 -241.363985) (xy 346.819619 -241.407562) (xy 346.790054 -241.446906)
			(xy 346.754561 -241.480998) (xy 346.714058 -241.508954) (xy 346.669596 -241.530052) (xy 346.622325 -241.543744)
			(xy 346.57347 -241.549676) (xy 346.524295 -241.547695) (xy 346.476076 -241.537851) (xy 346.43006 -241.520399)
			(xy 346.387439 -241.495792) (xy 346.349318 -241.464667) (xy 346.316683 -241.42783) (xy 346.29038 -241.386234)
			(xy 346.271089 -241.340958) (xy 346.259312 -241.293174) (xy 346.255352 -241.24412) (xy 345.92641 -241.24412)
			(xy 345.925915 -241.268727) (xy 345.91802 -241.317304) (xy 345.902436 -241.363985) (xy 345.879565 -241.407562)
			(xy 345.85 -241.446906) (xy 345.814507 -241.480998) (xy 345.774004 -241.508954) (xy 345.729542 -241.530052)
			(xy 345.682271 -241.543744) (xy 345.633416 -241.549676) (xy 345.584241 -241.547695) (xy 345.536022 -241.537851)
			(xy 345.490006 -241.520399) (xy 345.447385 -241.495792) (xy 345.409264 -241.464667) (xy 345.376629 -241.42783)
			(xy 345.350326 -241.386234) (xy 345.331035 -241.340958) (xy 345.319258 -241.293174) (xy 345.315298 -241.24412)
			(xy 344.986809 -241.24412) (xy 344.982641 -241.29443) (xy 344.970245 -241.343387) (xy 344.94996 -241.389637)
			(xy 344.92234 -241.431917) (xy 344.888139 -241.469075) (xy 344.848288 -241.500098) (xy 344.803875 -241.524139)
			(xy 344.756111 -241.540543) (xy 344.706299 -241.548863) (xy 344.681048 -241.549428) (xy 344.653693 -241.548798)
			(xy 344.599865 -241.539012) (xy 344.548639 -241.519799) (xy 344.501653 -241.491772) (xy 344.480642 -241.474244)
			(xy 344.469212 -241.464338) (xy 344.440002 -241.460274) (xy 344.341958 -241.504724) (xy 344.333299 -241.509145)
			(xy 344.31989 -241.523201) (xy 344.312678 -241.541239) (xy 344.31224 -241.550952) (xy 344.31224 -241.74704)
			(xy 344.327988 -241.771678) (xy 344.34145 -241.778028) (xy 344.36354 -241.78898) (xy 344.40416 -241.81692)
			(xy 344.439763 -241.851024) (xy 344.469423 -241.890406) (xy 344.49237 -241.934042) (xy 344.508006 -241.980799)
			(xy 344.515927 -242.02946) (xy 344.515926 -242.054126) (xy 346.725252 -242.054126) (xy 346.729212 -242.005072)
			(xy 346.740989 -241.957288) (xy 346.76028 -241.912012) (xy 346.786583 -241.870416) (xy 346.819218 -241.833579)
			(xy 346.857339 -241.802454) (xy 346.89996 -241.777847) (xy 346.945976 -241.760395) (xy 346.994195 -241.750551)
			(xy 347.04337 -241.74857) (xy 347.092225 -241.754502) (xy 347.139496 -241.768194) (xy 347.183958 -241.789292)
			(xy 347.224461 -241.817248) (xy 347.259954 -241.85134) (xy 347.289519 -241.890684) (xy 347.31239 -241.934261)
			(xy 347.327974 -241.980942) (xy 347.335869 -242.029519) (xy 347.336364 -242.054126) (xy 349.545414 -242.054126)
			(xy 349.549374 -242.005072) (xy 349.561151 -241.957288) (xy 349.580442 -241.912012) (xy 349.606745 -241.870416)
			(xy 349.63938 -241.833579) (xy 349.677501 -241.802454) (xy 349.720122 -241.777847) (xy 349.766138 -241.760395)
			(xy 349.814357 -241.750551) (xy 349.863532 -241.74857) (xy 349.912387 -241.754502) (xy 349.959658 -241.768194)
			(xy 350.00412 -241.789292) (xy 350.044623 -241.817248) (xy 350.080116 -241.85134) (xy 350.109681 -241.890684)
			(xy 350.132552 -241.934261) (xy 350.148136 -241.980942) (xy 350.156031 -242.029519) (xy 350.156526 -242.054126)
			(xy 352.365322 -242.054126) (xy 352.369282 -242.005072) (xy 352.381059 -241.957288) (xy 352.40035 -241.912012)
			(xy 352.426653 -241.870416) (xy 352.459288 -241.833579) (xy 352.497409 -241.802454) (xy 352.54003 -241.777847)
			(xy 352.586046 -241.760395) (xy 352.634265 -241.750551) (xy 352.68344 -241.74857) (xy 352.732295 -241.754502)
			(xy 352.779566 -241.768194) (xy 352.824028 -241.789292) (xy 352.864531 -241.817248) (xy 352.900024 -241.85134)
			(xy 352.929589 -241.890684) (xy 352.95246 -241.934261) (xy 352.968044 -241.980942) (xy 352.975939 -242.029519)
			(xy 352.976434 -242.054126) (xy 355.18523 -242.054126) (xy 355.18919 -242.005072) (xy 355.200967 -241.957288)
			(xy 355.220258 -241.912012) (xy 355.246561 -241.870416) (xy 355.279196 -241.833579) (xy 355.317317 -241.802454)
			(xy 355.359938 -241.777847) (xy 355.405954 -241.760395) (xy 355.454173 -241.750551) (xy 355.503348 -241.74857)
			(xy 355.552203 -241.754502) (xy 355.599474 -241.768194) (xy 355.643936 -241.789292) (xy 355.684439 -241.817248)
			(xy 355.719932 -241.85134) (xy 355.749497 -241.890684) (xy 355.772368 -241.934261) (xy 355.787952 -241.980942)
			(xy 355.795847 -242.029519) (xy 355.796342 -242.054126) (xy 356.125284 -242.054126) (xy 356.129244 -242.005072)
			(xy 356.141021 -241.957288) (xy 356.160312 -241.912012) (xy 356.186615 -241.870416) (xy 356.21925 -241.833579)
			(xy 356.257371 -241.802454) (xy 356.299992 -241.777847) (xy 356.346008 -241.760395) (xy 356.394227 -241.750551)
			(xy 356.443402 -241.74857) (xy 356.492257 -241.754502) (xy 356.539528 -241.768194) (xy 356.58399 -241.789292)
			(xy 356.624493 -241.817248) (xy 356.659986 -241.85134) (xy 356.689551 -241.890684) (xy 356.712422 -241.934261)
			(xy 356.728006 -241.980942) (xy 356.735901 -242.029519) (xy 356.736396 -242.054126) (xy 357.065338 -242.054126)
			(xy 357.069298 -242.005072) (xy 357.081075 -241.957288) (xy 357.100366 -241.912012) (xy 357.126669 -241.870416)
			(xy 357.159304 -241.833579) (xy 357.197425 -241.802454) (xy 357.240046 -241.777847) (xy 357.286062 -241.760395)
			(xy 357.334281 -241.750551) (xy 357.383456 -241.74857) (xy 357.432311 -241.754502) (xy 357.479582 -241.768194)
			(xy 357.524044 -241.789292) (xy 357.564547 -241.817248) (xy 357.60004 -241.85134) (xy 357.629605 -241.890684)
			(xy 357.652476 -241.934261) (xy 357.66806 -241.980942) (xy 357.675955 -242.029519) (xy 357.67645 -242.054126)
			(xy 358.005392 -242.054126) (xy 358.009352 -242.005072) (xy 358.021129 -241.957288) (xy 358.04042 -241.912012)
			(xy 358.066723 -241.870416) (xy 358.099358 -241.833579) (xy 358.137479 -241.802454) (xy 358.1801 -241.777847)
			(xy 358.226116 -241.760395) (xy 358.274335 -241.750551) (xy 358.32351 -241.74857) (xy 358.372365 -241.754502)
			(xy 358.419636 -241.768194) (xy 358.464098 -241.789292) (xy 358.504601 -241.817248) (xy 358.540094 -241.85134)
			(xy 358.569659 -241.890684) (xy 358.59253 -241.934261) (xy 358.608114 -241.980942) (xy 358.616009 -242.029519)
			(xy 358.616504 -242.054126) (xy 358.616009 -242.078733) (xy 358.608114 -242.12731) (xy 358.59253 -242.173991)
			(xy 358.569659 -242.217568) (xy 358.540094 -242.256912) (xy 358.504601 -242.291004) (xy 358.464098 -242.31896)
			(xy 358.419636 -242.340058) (xy 358.372365 -242.35375) (xy 358.32351 -242.359682) (xy 358.274335 -242.357701)
			(xy 358.226116 -242.347857) (xy 358.1801 -242.330405) (xy 358.137479 -242.305798) (xy 358.099358 -242.274673)
			(xy 358.066723 -242.237836) (xy 358.04042 -242.19624) (xy 358.021129 -242.150964) (xy 358.009352 -242.10318)
			(xy 358.005392 -242.054126) (xy 357.67645 -242.054126) (xy 357.675955 -242.078733) (xy 357.66806 -242.12731)
			(xy 357.652476 -242.173991) (xy 357.629605 -242.217568) (xy 357.60004 -242.256912) (xy 357.564547 -242.291004)
			(xy 357.524044 -242.31896) (xy 357.479582 -242.340058) (xy 357.432311 -242.35375) (xy 357.383456 -242.359682)
			(xy 357.334281 -242.357701) (xy 357.286062 -242.347857) (xy 357.240046 -242.330405) (xy 357.197425 -242.305798)
			(xy 357.159304 -242.274673) (xy 357.126669 -242.237836) (xy 357.100366 -242.19624) (xy 357.081075 -242.150964)
			(xy 357.069298 -242.10318) (xy 357.065338 -242.054126) (xy 356.736396 -242.054126) (xy 356.735901 -242.078733)
			(xy 356.728006 -242.12731) (xy 356.712422 -242.173991) (xy 356.689551 -242.217568) (xy 356.659986 -242.256912)
			(xy 356.624493 -242.291004) (xy 356.58399 -242.31896) (xy 356.539528 -242.340058) (xy 356.492257 -242.35375)
			(xy 356.443402 -242.359682) (xy 356.394227 -242.357701) (xy 356.346008 -242.347857) (xy 356.299992 -242.330405)
			(xy 356.257371 -242.305798) (xy 356.21925 -242.274673) (xy 356.186615 -242.237836) (xy 356.160312 -242.19624)
			(xy 356.141021 -242.150964) (xy 356.129244 -242.10318) (xy 356.125284 -242.054126) (xy 355.796342 -242.054126)
			(xy 355.795847 -242.078733) (xy 355.787952 -242.12731) (xy 355.772368 -242.173991) (xy 355.749497 -242.217568)
			(xy 355.719932 -242.256912) (xy 355.684439 -242.291004) (xy 355.643936 -242.31896) (xy 355.599474 -242.340058)
			(xy 355.552203 -242.35375) (xy 355.503348 -242.359682) (xy 355.454173 -242.357701) (xy 355.405954 -242.347857)
			(xy 355.359938 -242.330405) (xy 355.317317 -242.305798) (xy 355.279196 -242.274673) (xy 355.246561 -242.237836)
			(xy 355.220258 -242.19624) (xy 355.200967 -242.150964) (xy 355.18919 -242.10318) (xy 355.18523 -242.054126)
			(xy 352.976434 -242.054126) (xy 352.975939 -242.078733) (xy 352.968044 -242.12731) (xy 352.95246 -242.173991)
			(xy 352.929589 -242.217568) (xy 352.900024 -242.256912) (xy 352.864531 -242.291004) (xy 352.824028 -242.31896)
			(xy 352.779566 -242.340058) (xy 352.732295 -242.35375) (xy 352.68344 -242.359682) (xy 352.634265 -242.357701)
			(xy 352.586046 -242.347857) (xy 352.54003 -242.330405) (xy 352.497409 -242.305798) (xy 352.459288 -242.274673)
			(xy 352.426653 -242.237836) (xy 352.40035 -242.19624) (xy 352.381059 -242.150964) (xy 352.369282 -242.10318)
			(xy 352.365322 -242.054126) (xy 350.156526 -242.054126) (xy 350.156031 -242.078733) (xy 350.148136 -242.12731)
			(xy 350.132552 -242.173991) (xy 350.109681 -242.217568) (xy 350.080116 -242.256912) (xy 350.044623 -242.291004)
			(xy 350.00412 -242.31896) (xy 349.959658 -242.340058) (xy 349.912387 -242.35375) (xy 349.863532 -242.359682)
			(xy 349.814357 -242.357701) (xy 349.766138 -242.347857) (xy 349.720122 -242.330405) (xy 349.677501 -242.305798)
			(xy 349.63938 -242.274673) (xy 349.606745 -242.237836) (xy 349.580442 -242.19624) (xy 349.561151 -242.150964)
			(xy 349.549374 -242.10318) (xy 349.545414 -242.054126) (xy 347.336364 -242.054126) (xy 347.335869 -242.078733)
			(xy 347.327974 -242.12731) (xy 347.31239 -242.173991) (xy 347.289519 -242.217568) (xy 347.259954 -242.256912)
			(xy 347.224461 -242.291004) (xy 347.183958 -242.31896) (xy 347.139496 -242.340058) (xy 347.092225 -242.35375)
			(xy 347.04337 -242.359682) (xy 346.994195 -242.357701) (xy 346.945976 -242.347857) (xy 346.89996 -242.330405)
			(xy 346.857339 -242.305798) (xy 346.819218 -242.274673) (xy 346.786583 -242.237836) (xy 346.76028 -242.19624)
			(xy 346.740989 -242.150964) (xy 346.729212 -242.10318) (xy 346.725252 -242.054126) (xy 344.515926 -242.054126)
			(xy 344.515925 -242.078762) (xy 344.508001 -242.127423) (xy 344.492361 -242.174178) (xy 344.469411 -242.217813)
			(xy 344.439748 -242.257192) (xy 344.404143 -242.291294) (xy 344.36352 -242.319231) (xy 344.34145 -242.330224)
			(xy 344.327988 -242.336574) (xy 344.31224 -242.361212) (xy 344.31224 -242.5573) (xy 344.312669 -242.567015)
			(xy 344.319887 -242.585054) (xy 344.33329 -242.599121) (xy 344.341958 -242.603528) (xy 344.440002 -242.647978)
			(xy 344.469212 -242.643914) (xy 344.480642 -242.634008) (xy 344.501659 -242.616489) (xy 344.548641 -242.588456)
			(xy 344.599865 -242.569244) (xy 344.653694 -242.559468) (xy 344.681048 -242.558824) (xy 344.706298 -242.559349)
			(xy 344.756108 -242.567668) (xy 344.803871 -242.584072) (xy 344.848282 -242.608112) (xy 344.888131 -242.639134)
			(xy 344.922331 -242.67629) (xy 344.949949 -242.718569) (xy 344.970233 -242.764817) (xy 344.982629 -242.813772)
			(xy 344.986799 -242.8641) (xy 344.986796 -242.864132) (xy 345.315298 -242.864132) (xy 345.319258 -242.815078)
			(xy 345.331035 -242.767294) (xy 345.350326 -242.722018) (xy 345.376629 -242.680422) (xy 345.409264 -242.643585)
			(xy 345.447385 -242.61246) (xy 345.490006 -242.587853) (xy 345.536022 -242.570401) (xy 345.584241 -242.560557)
			(xy 345.633416 -242.558576) (xy 345.682271 -242.564508) (xy 345.729542 -242.5782) (xy 345.774004 -242.599298)
			(xy 345.814507 -242.627254) (xy 345.85 -242.661346) (xy 345.879565 -242.70069) (xy 345.902436 -242.744267)
			(xy 345.91802 -242.790948) (xy 345.925915 -242.839525) (xy 345.92641 -242.864132) (xy 346.255352 -242.864132)
			(xy 346.259312 -242.815078) (xy 346.271089 -242.767294) (xy 346.29038 -242.722018) (xy 346.316683 -242.680422)
			(xy 346.349318 -242.643585) (xy 346.387439 -242.61246) (xy 346.43006 -242.587853) (xy 346.476076 -242.570401)
			(xy 346.524295 -242.560557) (xy 346.57347 -242.558576) (xy 346.622325 -242.564508) (xy 346.669596 -242.5782)
			(xy 346.714058 -242.599298) (xy 346.754561 -242.627254) (xy 346.790054 -242.661346) (xy 346.819619 -242.70069)
			(xy 346.84249 -242.744267) (xy 346.858074 -242.790948) (xy 346.865969 -242.839525) (xy 346.866464 -242.864132)
			(xy 347.195406 -242.864132) (xy 347.199366 -242.815078) (xy 347.211143 -242.767294) (xy 347.230434 -242.722018)
			(xy 347.256737 -242.680422) (xy 347.289372 -242.643585) (xy 347.327493 -242.61246) (xy 347.370114 -242.587853)
			(xy 347.41613 -242.570401) (xy 347.464349 -242.560557) (xy 347.513524 -242.558576) (xy 347.562379 -242.564508)
			(xy 347.60965 -242.5782) (xy 347.654112 -242.599298) (xy 347.694615 -242.627254) (xy 347.730108 -242.661346)
			(xy 347.759673 -242.70069) (xy 347.782544 -242.744267) (xy 347.798128 -242.790948) (xy 347.806023 -242.839525)
			(xy 347.806518 -242.864132) (xy 348.135206 -242.864132) (xy 348.139166 -242.815078) (xy 348.150943 -242.767294)
			(xy 348.170234 -242.722018) (xy 348.196537 -242.680422) (xy 348.229172 -242.643585) (xy 348.267293 -242.61246)
			(xy 348.309914 -242.587853) (xy 348.35593 -242.570401) (xy 348.404149 -242.560557) (xy 348.453324 -242.558576)
			(xy 348.502179 -242.564508) (xy 348.54945 -242.5782) (xy 348.593912 -242.599298) (xy 348.634415 -242.627254)
			(xy 348.669908 -242.661346) (xy 348.699473 -242.70069) (xy 348.722344 -242.744267) (xy 348.737928 -242.790948)
			(xy 348.745823 -242.839525) (xy 348.746318 -242.864132) (xy 349.07526 -242.864132) (xy 349.07922 -242.815078)
			(xy 349.090997 -242.767294) (xy 349.110288 -242.722018) (xy 349.136591 -242.680422) (xy 349.169226 -242.643585)
			(xy 349.207347 -242.61246) (xy 349.249968 -242.587853) (xy 349.295984 -242.570401) (xy 349.344203 -242.560557)
			(xy 349.393378 -242.558576) (xy 349.442233 -242.564508) (xy 349.489504 -242.5782) (xy 349.533966 -242.599298)
			(xy 349.574469 -242.627254) (xy 349.609962 -242.661346) (xy 349.639527 -242.70069) (xy 349.662398 -242.744267)
			(xy 349.677982 -242.790948) (xy 349.685877 -242.839525) (xy 349.686372 -242.864132) (xy 350.015314 -242.864132)
			(xy 350.019274 -242.815078) (xy 350.031051 -242.767294) (xy 350.050342 -242.722018) (xy 350.076645 -242.680422)
			(xy 350.10928 -242.643585) (xy 350.147401 -242.61246) (xy 350.190022 -242.587853) (xy 350.236038 -242.570401)
			(xy 350.284257 -242.560557) (xy 350.333432 -242.558576) (xy 350.382287 -242.564508) (xy 350.429558 -242.5782)
			(xy 350.47402 -242.599298) (xy 350.514523 -242.627254) (xy 350.550016 -242.661346) (xy 350.579581 -242.70069)
			(xy 350.602452 -242.744267) (xy 350.618036 -242.790948) (xy 350.625931 -242.839525) (xy 350.626426 -242.864132)
			(xy 350.955368 -242.864132) (xy 350.959328 -242.815078) (xy 350.971105 -242.767294) (xy 350.990396 -242.722018)
			(xy 351.016699 -242.680422) (xy 351.049334 -242.643585) (xy 351.087455 -242.61246) (xy 351.130076 -242.587853)
			(xy 351.176092 -242.570401) (xy 351.224311 -242.560557) (xy 351.273486 -242.558576) (xy 351.322341 -242.564508)
			(xy 351.369612 -242.5782) (xy 351.414074 -242.599298) (xy 351.454577 -242.627254) (xy 351.49007 -242.661346)
			(xy 351.519635 -242.70069) (xy 351.542506 -242.744267) (xy 351.55809 -242.790948) (xy 351.565985 -242.839525)
			(xy 351.56648 -242.864132) (xy 351.895422 -242.864132) (xy 351.899382 -242.815078) (xy 351.911159 -242.767294)
			(xy 351.93045 -242.722018) (xy 351.956753 -242.680422) (xy 351.989388 -242.643585) (xy 352.027509 -242.61246)
			(xy 352.07013 -242.587853) (xy 352.116146 -242.570401) (xy 352.164365 -242.560557) (xy 352.21354 -242.558576)
			(xy 352.262395 -242.564508) (xy 352.309666 -242.5782) (xy 352.354128 -242.599298) (xy 352.394631 -242.627254)
			(xy 352.430124 -242.661346) (xy 352.459689 -242.70069) (xy 352.48256 -242.744267) (xy 352.498144 -242.790948)
			(xy 352.506039 -242.839525) (xy 352.506534 -242.864132) (xy 352.835222 -242.864132) (xy 352.839182 -242.815078)
			(xy 352.850959 -242.767294) (xy 352.87025 -242.722018) (xy 352.896553 -242.680422) (xy 352.929188 -242.643585)
			(xy 352.967309 -242.61246) (xy 353.00993 -242.587853) (xy 353.055946 -242.570401) (xy 353.104165 -242.560557)
			(xy 353.15334 -242.558576) (xy 353.202195 -242.564508) (xy 353.249466 -242.5782) (xy 353.293928 -242.599298)
			(xy 353.334431 -242.627254) (xy 353.369924 -242.661346) (xy 353.399489 -242.70069) (xy 353.42236 -242.744267)
			(xy 353.437944 -242.790948) (xy 353.445839 -242.839525) (xy 353.446334 -242.864132) (xy 353.775276 -242.864132)
			(xy 353.779236 -242.815078) (xy 353.791013 -242.767294) (xy 353.810304 -242.722018) (xy 353.836607 -242.680422)
			(xy 353.869242 -242.643585) (xy 353.907363 -242.61246) (xy 353.949984 -242.587853) (xy 353.996 -242.570401)
			(xy 354.044219 -242.560557) (xy 354.093394 -242.558576) (xy 354.142249 -242.564508) (xy 354.18952 -242.5782)
			(xy 354.233982 -242.599298) (xy 354.274485 -242.627254) (xy 354.309978 -242.661346) (xy 354.339543 -242.70069)
			(xy 354.362414 -242.744267) (xy 354.377998 -242.790948) (xy 354.385893 -242.839525) (xy 354.386388 -242.864132)
			(xy 354.71533 -242.864132) (xy 354.71929 -242.815078) (xy 354.731067 -242.767294) (xy 354.750358 -242.722018)
			(xy 354.776661 -242.680422) (xy 354.809296 -242.643585) (xy 354.847417 -242.61246) (xy 354.890038 -242.587853)
			(xy 354.936054 -242.570401) (xy 354.984273 -242.560557) (xy 355.033448 -242.558576) (xy 355.082303 -242.564508)
			(xy 355.129574 -242.5782) (xy 355.174036 -242.599298) (xy 355.214539 -242.627254) (xy 355.250032 -242.661346)
			(xy 355.279597 -242.70069) (xy 355.302468 -242.744267) (xy 355.318052 -242.790948) (xy 355.325947 -242.839525)
			(xy 355.326442 -242.864132) (xy 355.655384 -242.864132) (xy 355.659344 -242.815078) (xy 355.671121 -242.767294)
			(xy 355.690412 -242.722018) (xy 355.716715 -242.680422) (xy 355.74935 -242.643585) (xy 355.787471 -242.61246)
			(xy 355.830092 -242.587853) (xy 355.876108 -242.570401) (xy 355.924327 -242.560557) (xy 355.973502 -242.558576)
			(xy 356.022357 -242.564508) (xy 356.069628 -242.5782) (xy 356.11409 -242.599298) (xy 356.154593 -242.627254)
			(xy 356.190086 -242.661346) (xy 356.219651 -242.70069) (xy 356.242522 -242.744267) (xy 356.258106 -242.790948)
			(xy 356.266001 -242.839525) (xy 356.266496 -242.864132) (xy 356.266001 -242.888739) (xy 356.258106 -242.937316)
			(xy 356.242522 -242.983997) (xy 356.219651 -243.027574) (xy 356.190086 -243.066918) (xy 356.154593 -243.10101)
			(xy 356.11409 -243.128966) (xy 356.069628 -243.150064) (xy 356.022357 -243.163756) (xy 355.973502 -243.169688)
			(xy 355.924327 -243.167707) (xy 355.876108 -243.157863) (xy 355.830092 -243.140411) (xy 355.787471 -243.115804)
			(xy 355.74935 -243.084679) (xy 355.716715 -243.047842) (xy 355.690412 -243.006246) (xy 355.671121 -242.96097)
			(xy 355.659344 -242.913186) (xy 355.655384 -242.864132) (xy 355.326442 -242.864132) (xy 355.325947 -242.888739)
			(xy 355.318052 -242.937316) (xy 355.302468 -242.983997) (xy 355.279597 -243.027574) (xy 355.250032 -243.066918)
			(xy 355.214539 -243.10101) (xy 355.174036 -243.128966) (xy 355.129574 -243.150064) (xy 355.082303 -243.163756)
			(xy 355.033448 -243.169688) (xy 354.984273 -243.167707) (xy 354.936054 -243.157863) (xy 354.890038 -243.140411)
			(xy 354.847417 -243.115804) (xy 354.809296 -243.084679) (xy 354.776661 -243.047842) (xy 354.750358 -243.006246)
			(xy 354.731067 -242.96097) (xy 354.71929 -242.913186) (xy 354.71533 -242.864132) (xy 354.386388 -242.864132)
			(xy 354.385893 -242.888739) (xy 354.377998 -242.937316) (xy 354.362414 -242.983997) (xy 354.339543 -243.027574)
			(xy 354.309978 -243.066918) (xy 354.274485 -243.10101) (xy 354.233982 -243.128966) (xy 354.18952 -243.150064)
			(xy 354.142249 -243.163756) (xy 354.093394 -243.169688) (xy 354.044219 -243.167707) (xy 353.996 -243.157863)
			(xy 353.949984 -243.140411) (xy 353.907363 -243.115804) (xy 353.869242 -243.084679) (xy 353.836607 -243.047842)
			(xy 353.810304 -243.006246) (xy 353.791013 -242.96097) (xy 353.779236 -242.913186) (xy 353.775276 -242.864132)
			(xy 353.446334 -242.864132) (xy 353.445839 -242.888739) (xy 353.437944 -242.937316) (xy 353.42236 -242.983997)
			(xy 353.399489 -243.027574) (xy 353.369924 -243.066918) (xy 353.334431 -243.10101) (xy 353.293928 -243.128966)
			(xy 353.249466 -243.150064) (xy 353.202195 -243.163756) (xy 353.15334 -243.169688) (xy 353.104165 -243.167707)
			(xy 353.055946 -243.157863) (xy 353.00993 -243.140411) (xy 352.967309 -243.115804) (xy 352.929188 -243.084679)
			(xy 352.896553 -243.047842) (xy 352.87025 -243.006246) (xy 352.850959 -242.96097) (xy 352.839182 -242.913186)
			(xy 352.835222 -242.864132) (xy 352.506534 -242.864132) (xy 352.506039 -242.888739) (xy 352.498144 -242.937316)
			(xy 352.48256 -242.983997) (xy 352.459689 -243.027574) (xy 352.430124 -243.066918) (xy 352.394631 -243.10101)
			(xy 352.354128 -243.128966) (xy 352.309666 -243.150064) (xy 352.262395 -243.163756) (xy 352.21354 -243.169688)
			(xy 352.164365 -243.167707) (xy 352.116146 -243.157863) (xy 352.07013 -243.140411) (xy 352.027509 -243.115804)
			(xy 351.989388 -243.084679) (xy 351.956753 -243.047842) (xy 351.93045 -243.006246) (xy 351.911159 -242.96097)
			(xy 351.899382 -242.913186) (xy 351.895422 -242.864132) (xy 351.56648 -242.864132) (xy 351.565985 -242.888739)
			(xy 351.55809 -242.937316) (xy 351.542506 -242.983997) (xy 351.519635 -243.027574) (xy 351.49007 -243.066918)
			(xy 351.454577 -243.10101) (xy 351.414074 -243.128966) (xy 351.369612 -243.150064) (xy 351.322341 -243.163756)
			(xy 351.273486 -243.169688) (xy 351.224311 -243.167707) (xy 351.176092 -243.157863) (xy 351.130076 -243.140411)
			(xy 351.087455 -243.115804) (xy 351.049334 -243.084679) (xy 351.016699 -243.047842) (xy 350.990396 -243.006246)
			(xy 350.971105 -242.96097) (xy 350.959328 -242.913186) (xy 350.955368 -242.864132) (xy 350.626426 -242.864132)
			(xy 350.625931 -242.888739) (xy 350.618036 -242.937316) (xy 350.602452 -242.983997) (xy 350.579581 -243.027574)
			(xy 350.550016 -243.066918) (xy 350.514523 -243.10101) (xy 350.47402 -243.128966) (xy 350.429558 -243.150064)
			(xy 350.382287 -243.163756) (xy 350.333432 -243.169688) (xy 350.284257 -243.167707) (xy 350.236038 -243.157863)
			(xy 350.190022 -243.140411) (xy 350.147401 -243.115804) (xy 350.10928 -243.084679) (xy 350.076645 -243.047842)
			(xy 350.050342 -243.006246) (xy 350.031051 -242.96097) (xy 350.019274 -242.913186) (xy 350.015314 -242.864132)
			(xy 349.686372 -242.864132) (xy 349.685877 -242.888739) (xy 349.677982 -242.937316) (xy 349.662398 -242.983997)
			(xy 349.639527 -243.027574) (xy 349.609962 -243.066918) (xy 349.574469 -243.10101) (xy 349.533966 -243.128966)
			(xy 349.489504 -243.150064) (xy 349.442233 -243.163756) (xy 349.393378 -243.169688) (xy 349.344203 -243.167707)
			(xy 349.295984 -243.157863) (xy 349.249968 -243.140411) (xy 349.207347 -243.115804) (xy 349.169226 -243.084679)
			(xy 349.136591 -243.047842) (xy 349.110288 -243.006246) (xy 349.090997 -242.96097) (xy 349.07922 -242.913186)
			(xy 349.07526 -242.864132) (xy 348.746318 -242.864132) (xy 348.745823 -242.888739) (xy 348.737928 -242.937316)
			(xy 348.722344 -242.983997) (xy 348.699473 -243.027574) (xy 348.669908 -243.066918) (xy 348.634415 -243.10101)
			(xy 348.593912 -243.128966) (xy 348.54945 -243.150064) (xy 348.502179 -243.163756) (xy 348.453324 -243.169688)
			(xy 348.404149 -243.167707) (xy 348.35593 -243.157863) (xy 348.309914 -243.140411) (xy 348.267293 -243.115804)
			(xy 348.229172 -243.084679) (xy 348.196537 -243.047842) (xy 348.170234 -243.006246) (xy 348.150943 -242.96097)
			(xy 348.139166 -242.913186) (xy 348.135206 -242.864132) (xy 347.806518 -242.864132) (xy 347.806023 -242.888739)
			(xy 347.798128 -242.937316) (xy 347.782544 -242.983997) (xy 347.759673 -243.027574) (xy 347.730108 -243.066918)
			(xy 347.694615 -243.10101) (xy 347.654112 -243.128966) (xy 347.60965 -243.150064) (xy 347.562379 -243.163756)
			(xy 347.513524 -243.169688) (xy 347.464349 -243.167707) (xy 347.41613 -243.157863) (xy 347.370114 -243.140411)
			(xy 347.327493 -243.115804) (xy 347.289372 -243.084679) (xy 347.256737 -243.047842) (xy 347.230434 -243.006246)
			(xy 347.211143 -242.96097) (xy 347.199366 -242.913186) (xy 347.195406 -242.864132) (xy 346.866464 -242.864132)
			(xy 346.865969 -242.888739) (xy 346.858074 -242.937316) (xy 346.84249 -242.983997) (xy 346.819619 -243.027574)
			(xy 346.790054 -243.066918) (xy 346.754561 -243.10101) (xy 346.714058 -243.128966) (xy 346.669596 -243.150064)
			(xy 346.622325 -243.163756) (xy 346.57347 -243.169688) (xy 346.524295 -243.167707) (xy 346.476076 -243.157863)
			(xy 346.43006 -243.140411) (xy 346.387439 -243.115804) (xy 346.349318 -243.084679) (xy 346.316683 -243.047842)
			(xy 346.29038 -243.006246) (xy 346.271089 -242.96097) (xy 346.259312 -242.913186) (xy 346.255352 -242.864132)
			(xy 345.92641 -242.864132) (xy 345.925915 -242.888739) (xy 345.91802 -242.937316) (xy 345.902436 -242.983997)
			(xy 345.879565 -243.027574) (xy 345.85 -243.066918) (xy 345.814507 -243.10101) (xy 345.774004 -243.128966)
			(xy 345.729542 -243.150064) (xy 345.682271 -243.163756) (xy 345.633416 -243.169688) (xy 345.584241 -243.167707)
			(xy 345.536022 -243.157863) (xy 345.490006 -243.140411) (xy 345.447385 -243.115804) (xy 345.409264 -243.084679)
			(xy 345.376629 -243.047842) (xy 345.350326 -243.006246) (xy 345.331035 -242.96097) (xy 345.319258 -242.913186)
			(xy 345.315298 -242.864132) (xy 344.986796 -242.864132) (xy 344.982629 -242.914428) (xy 344.970233 -242.963383)
			(xy 344.949949 -243.009631) (xy 344.922331 -243.05191) (xy 344.888131 -243.089067) (xy 344.848282 -243.120088)
			(xy 344.80387 -243.144128) (xy 344.756108 -243.160532) (xy 344.706298 -243.168851) (xy 344.681048 -243.16944)
			(xy 344.653693 -243.16881) (xy 344.599865 -243.159025) (xy 344.548638 -243.139812) (xy 344.501651 -243.111785)
			(xy 344.480642 -243.094256) (xy 344.469212 -243.08435) (xy 344.440002 -243.080286) (xy 344.341958 -243.124736)
			(xy 344.3333 -243.129157) (xy 344.319895 -243.143214) (xy 344.312686 -243.161251) (xy 344.31224 -243.170964)
			(xy 344.31224 -243.367052) (xy 344.327988 -243.39169) (xy 344.34145 -243.39804) (xy 344.363539 -243.408992)
			(xy 344.404157 -243.436932) (xy 344.439758 -243.471035) (xy 344.469417 -243.510416) (xy 344.492362 -243.554051)
			(xy 344.507997 -243.600806) (xy 344.515916 -243.649466) (xy 344.515915 -243.674138) (xy 344.845398 -243.674138)
			(xy 344.849358 -243.625084) (xy 344.861135 -243.5773) (xy 344.880426 -243.532024) (xy 344.906729 -243.490428)
			(xy 344.939364 -243.453591) (xy 344.977485 -243.422466) (xy 345.020106 -243.397859) (xy 345.066122 -243.380407)
			(xy 345.114341 -243.370563) (xy 345.163516 -243.368582) (xy 345.212371 -243.374514) (xy 345.259642 -243.388206)
			(xy 345.304104 -243.409304) (xy 345.344607 -243.43726) (xy 345.3801 -243.471352) (xy 345.409665 -243.510696)
			(xy 345.432536 -243.554273) (xy 345.44812 -243.600954) (xy 345.456015 -243.649531) (xy 345.45651 -243.674138)
			(xy 345.785198 -243.674138) (xy 345.789158 -243.625084) (xy 345.800935 -243.5773) (xy 345.820226 -243.532024)
			(xy 345.846529 -243.490428) (xy 345.879164 -243.453591) (xy 345.917285 -243.422466) (xy 345.959906 -243.397859)
			(xy 346.005922 -243.380407) (xy 346.054141 -243.370563) (xy 346.103316 -243.368582) (xy 346.152171 -243.374514)
			(xy 346.199442 -243.388206) (xy 346.243904 -243.409304) (xy 346.284407 -243.43726) (xy 346.3199 -243.471352)
			(xy 346.349465 -243.510696) (xy 346.372336 -243.554273) (xy 346.38792 -243.600954) (xy 346.395815 -243.649531)
			(xy 346.39631 -243.674138) (xy 346.725252 -243.674138) (xy 346.729212 -243.625084) (xy 346.740989 -243.5773)
			(xy 346.76028 -243.532024) (xy 346.786583 -243.490428) (xy 346.819218 -243.453591) (xy 346.857339 -243.422466)
			(xy 346.89996 -243.397859) (xy 346.945976 -243.380407) (xy 346.994195 -243.370563) (xy 347.04337 -243.368582)
			(xy 347.092225 -243.374514) (xy 347.139496 -243.388206) (xy 347.183958 -243.409304) (xy 347.224461 -243.43726)
			(xy 347.259954 -243.471352) (xy 347.289519 -243.510696) (xy 347.31239 -243.554273) (xy 347.327974 -243.600954)
			(xy 347.335869 -243.649531) (xy 347.336364 -243.674138) (xy 347.665306 -243.674138) (xy 347.669266 -243.625084)
			(xy 347.681043 -243.5773) (xy 347.700334 -243.532024) (xy 347.726637 -243.490428) (xy 347.759272 -243.453591)
			(xy 347.797393 -243.422466) (xy 347.840014 -243.397859) (xy 347.88603 -243.380407) (xy 347.934249 -243.370563)
			(xy 347.983424 -243.368582) (xy 348.032279 -243.374514) (xy 348.07955 -243.388206) (xy 348.124012 -243.409304)
			(xy 348.164515 -243.43726) (xy 348.200008 -243.471352) (xy 348.229573 -243.510696) (xy 348.252444 -243.554273)
			(xy 348.268028 -243.600954) (xy 348.275923 -243.649531) (xy 348.276418 -243.674138) (xy 348.60536 -243.674138)
			(xy 348.60932 -243.625084) (xy 348.621097 -243.5773) (xy 348.640388 -243.532024) (xy 348.666691 -243.490428)
			(xy 348.699326 -243.453591) (xy 348.737447 -243.422466) (xy 348.780068 -243.397859) (xy 348.826084 -243.380407)
			(xy 348.874303 -243.370563) (xy 348.923478 -243.368582) (xy 348.972333 -243.374514) (xy 349.019604 -243.388206)
			(xy 349.064066 -243.409304) (xy 349.104569 -243.43726) (xy 349.140062 -243.471352) (xy 349.169627 -243.510696)
			(xy 349.192498 -243.554273) (xy 349.208082 -243.600954) (xy 349.215977 -243.649531) (xy 349.216472 -243.674138)
			(xy 349.545414 -243.674138) (xy 349.549374 -243.625084) (xy 349.561151 -243.5773) (xy 349.580442 -243.532024)
			(xy 349.606745 -243.490428) (xy 349.63938 -243.453591) (xy 349.677501 -243.422466) (xy 349.720122 -243.397859)
			(xy 349.766138 -243.380407) (xy 349.814357 -243.370563) (xy 349.863532 -243.368582) (xy 349.912387 -243.374514)
			(xy 349.959658 -243.388206) (xy 350.00412 -243.409304) (xy 350.044623 -243.43726) (xy 350.080116 -243.471352)
			(xy 350.109681 -243.510696) (xy 350.132552 -243.554273) (xy 350.148136 -243.600954) (xy 350.156031 -243.649531)
			(xy 350.156526 -243.674138) (xy 350.485214 -243.674138) (xy 350.489174 -243.625084) (xy 350.500951 -243.5773)
			(xy 350.520242 -243.532024) (xy 350.546545 -243.490428) (xy 350.57918 -243.453591) (xy 350.617301 -243.422466)
			(xy 350.659922 -243.397859) (xy 350.705938 -243.380407) (xy 350.754157 -243.370563) (xy 350.803332 -243.368582)
			(xy 350.852187 -243.374514) (xy 350.899458 -243.388206) (xy 350.94392 -243.409304) (xy 350.984423 -243.43726)
			(xy 351.019916 -243.471352) (xy 351.049481 -243.510696) (xy 351.072352 -243.554273) (xy 351.087936 -243.600954)
			(xy 351.095831 -243.649531) (xy 351.096326 -243.674138) (xy 351.425268 -243.674138) (xy 351.429228 -243.625084)
			(xy 351.441005 -243.5773) (xy 351.460296 -243.532024) (xy 351.486599 -243.490428) (xy 351.519234 -243.453591)
			(xy 351.557355 -243.422466) (xy 351.599976 -243.397859) (xy 351.645992 -243.380407) (xy 351.694211 -243.370563)
			(xy 351.743386 -243.368582) (xy 351.792241 -243.374514) (xy 351.839512 -243.388206) (xy 351.883974 -243.409304)
			(xy 351.924477 -243.43726) (xy 351.95997 -243.471352) (xy 351.989535 -243.510696) (xy 352.012406 -243.554273)
			(xy 352.02799 -243.600954) (xy 352.035885 -243.649531) (xy 352.03638 -243.674138) (xy 352.365322 -243.674138)
			(xy 352.369282 -243.625084) (xy 352.381059 -243.5773) (xy 352.40035 -243.532024) (xy 352.426653 -243.490428)
			(xy 352.459288 -243.453591) (xy 352.497409 -243.422466) (xy 352.54003 -243.397859) (xy 352.586046 -243.380407)
			(xy 352.634265 -243.370563) (xy 352.68344 -243.368582) (xy 352.732295 -243.374514) (xy 352.779566 -243.388206)
			(xy 352.824028 -243.409304) (xy 352.864531 -243.43726) (xy 352.900024 -243.471352) (xy 352.929589 -243.510696)
			(xy 352.95246 -243.554273) (xy 352.968044 -243.600954) (xy 352.975939 -243.649531) (xy 352.976434 -243.674138)
			(xy 353.305376 -243.674138) (xy 353.309336 -243.625084) (xy 353.321113 -243.5773) (xy 353.340404 -243.532024)
			(xy 353.366707 -243.490428) (xy 353.399342 -243.453591) (xy 353.437463 -243.422466) (xy 353.480084 -243.397859)
			(xy 353.5261 -243.380407) (xy 353.574319 -243.370563) (xy 353.623494 -243.368582) (xy 353.672349 -243.374514)
			(xy 353.71962 -243.388206) (xy 353.764082 -243.409304) (xy 353.804585 -243.43726) (xy 353.840078 -243.471352)
			(xy 353.869643 -243.510696) (xy 353.892514 -243.554273) (xy 353.908098 -243.600954) (xy 353.915993 -243.649531)
			(xy 353.916488 -243.674138) (xy 354.24543 -243.674138) (xy 354.24939 -243.625084) (xy 354.261167 -243.5773)
			(xy 354.280458 -243.532024) (xy 354.306761 -243.490428) (xy 354.339396 -243.453591) (xy 354.377517 -243.422466)
			(xy 354.420138 -243.397859) (xy 354.466154 -243.380407) (xy 354.514373 -243.370563) (xy 354.563548 -243.368582)
			(xy 354.612403 -243.374514) (xy 354.659674 -243.388206) (xy 354.704136 -243.409304) (xy 354.744639 -243.43726)
			(xy 354.780132 -243.471352) (xy 354.809697 -243.510696) (xy 354.832568 -243.554273) (xy 354.848152 -243.600954)
			(xy 354.856047 -243.649531) (xy 354.856542 -243.674138) (xy 355.18523 -243.674138) (xy 355.18919 -243.625084)
			(xy 355.200967 -243.5773) (xy 355.220258 -243.532024) (xy 355.246561 -243.490428) (xy 355.279196 -243.453591)
			(xy 355.317317 -243.422466) (xy 355.359938 -243.397859) (xy 355.405954 -243.380407) (xy 355.454173 -243.370563)
			(xy 355.503348 -243.368582) (xy 355.552203 -243.374514) (xy 355.599474 -243.388206) (xy 355.643936 -243.409304)
			(xy 355.684439 -243.43726) (xy 355.719932 -243.471352) (xy 355.749497 -243.510696) (xy 355.772368 -243.554273)
			(xy 355.787952 -243.600954) (xy 355.795847 -243.649531) (xy 355.796342 -243.674138) (xy 356.125284 -243.674138)
			(xy 356.129244 -243.625084) (xy 356.141021 -243.5773) (xy 356.160312 -243.532024) (xy 356.186615 -243.490428)
			(xy 356.21925 -243.453591) (xy 356.257371 -243.422466) (xy 356.299992 -243.397859) (xy 356.346008 -243.380407)
			(xy 356.394227 -243.370563) (xy 356.443402 -243.368582) (xy 356.492257 -243.374514) (xy 356.539528 -243.388206)
			(xy 356.58399 -243.409304) (xy 356.624493 -243.43726) (xy 356.659986 -243.471352) (xy 356.689551 -243.510696)
			(xy 356.712422 -243.554273) (xy 356.728006 -243.600954) (xy 356.735901 -243.649531) (xy 356.736396 -243.674138)
			(xy 357.065338 -243.674138) (xy 357.069298 -243.625084) (xy 357.081075 -243.5773) (xy 357.100366 -243.532024)
			(xy 357.126669 -243.490428) (xy 357.159304 -243.453591) (xy 357.197425 -243.422466) (xy 357.240046 -243.397859)
			(xy 357.286062 -243.380407) (xy 357.334281 -243.370563) (xy 357.383456 -243.368582) (xy 357.432311 -243.374514)
			(xy 357.479582 -243.388206) (xy 357.524044 -243.409304) (xy 357.564547 -243.43726) (xy 357.60004 -243.471352)
			(xy 357.629605 -243.510696) (xy 357.652476 -243.554273) (xy 357.66806 -243.600954) (xy 357.675955 -243.649531)
			(xy 357.67645 -243.674138) (xy 358.005392 -243.674138) (xy 358.009352 -243.625084) (xy 358.021129 -243.5773)
			(xy 358.04042 -243.532024) (xy 358.066723 -243.490428) (xy 358.099358 -243.453591) (xy 358.137479 -243.422466)
			(xy 358.1801 -243.397859) (xy 358.226116 -243.380407) (xy 358.274335 -243.370563) (xy 358.32351 -243.368582)
			(xy 358.372365 -243.374514) (xy 358.419636 -243.388206) (xy 358.464098 -243.409304) (xy 358.504601 -243.43726)
			(xy 358.540094 -243.471352) (xy 358.569659 -243.510696) (xy 358.59253 -243.554273) (xy 358.608114 -243.600954)
			(xy 358.616009 -243.649531) (xy 358.616504 -243.674138) (xy 358.616009 -243.698745) (xy 358.608114 -243.747322)
			(xy 358.59253 -243.794003) (xy 358.569659 -243.83758) (xy 358.540094 -243.876924) (xy 358.504601 -243.911016)
			(xy 358.464098 -243.938972) (xy 358.419636 -243.96007) (xy 358.372365 -243.973762) (xy 358.32351 -243.979694)
			(xy 358.274335 -243.977713) (xy 358.226116 -243.967869) (xy 358.1801 -243.950417) (xy 358.137479 -243.92581)
			(xy 358.099358 -243.894685) (xy 358.066723 -243.857848) (xy 358.04042 -243.816252) (xy 358.021129 -243.770976)
			(xy 358.009352 -243.723192) (xy 358.005392 -243.674138) (xy 357.67645 -243.674138) (xy 357.675955 -243.698745)
			(xy 357.66806 -243.747322) (xy 357.652476 -243.794003) (xy 357.629605 -243.83758) (xy 357.60004 -243.876924)
			(xy 357.564547 -243.911016) (xy 357.524044 -243.938972) (xy 357.479582 -243.96007) (xy 357.432311 -243.973762)
			(xy 357.383456 -243.979694) (xy 357.334281 -243.977713) (xy 357.286062 -243.967869) (xy 357.240046 -243.950417)
			(xy 357.197425 -243.92581) (xy 357.159304 -243.894685) (xy 357.126669 -243.857848) (xy 357.100366 -243.816252)
			(xy 357.081075 -243.770976) (xy 357.069298 -243.723192) (xy 357.065338 -243.674138) (xy 356.736396 -243.674138)
			(xy 356.735901 -243.698745) (xy 356.728006 -243.747322) (xy 356.712422 -243.794003) (xy 356.689551 -243.83758)
			(xy 356.659986 -243.876924) (xy 356.624493 -243.911016) (xy 356.58399 -243.938972) (xy 356.539528 -243.96007)
			(xy 356.492257 -243.973762) (xy 356.443402 -243.979694) (xy 356.394227 -243.977713) (xy 356.346008 -243.967869)
			(xy 356.299992 -243.950417) (xy 356.257371 -243.92581) (xy 356.21925 -243.894685) (xy 356.186615 -243.857848)
			(xy 356.160312 -243.816252) (xy 356.141021 -243.770976) (xy 356.129244 -243.723192) (xy 356.125284 -243.674138)
			(xy 355.796342 -243.674138) (xy 355.795847 -243.698745) (xy 355.787952 -243.747322) (xy 355.772368 -243.794003)
			(xy 355.749497 -243.83758) (xy 355.719932 -243.876924) (xy 355.684439 -243.911016) (xy 355.643936 -243.938972)
			(xy 355.599474 -243.96007) (xy 355.552203 -243.973762) (xy 355.503348 -243.979694) (xy 355.454173 -243.977713)
			(xy 355.405954 -243.967869) (xy 355.359938 -243.950417) (xy 355.317317 -243.92581) (xy 355.279196 -243.894685)
			(xy 355.246561 -243.857848) (xy 355.220258 -243.816252) (xy 355.200967 -243.770976) (xy 355.18919 -243.723192)
			(xy 355.18523 -243.674138) (xy 354.856542 -243.674138) (xy 354.856047 -243.698745) (xy 354.848152 -243.747322)
			(xy 354.832568 -243.794003) (xy 354.809697 -243.83758) (xy 354.780132 -243.876924) (xy 354.744639 -243.911016)
			(xy 354.704136 -243.938972) (xy 354.659674 -243.96007) (xy 354.612403 -243.973762) (xy 354.563548 -243.979694)
			(xy 354.514373 -243.977713) (xy 354.466154 -243.967869) (xy 354.420138 -243.950417) (xy 354.377517 -243.92581)
			(xy 354.339396 -243.894685) (xy 354.306761 -243.857848) (xy 354.280458 -243.816252) (xy 354.261167 -243.770976)
			(xy 354.24939 -243.723192) (xy 354.24543 -243.674138) (xy 353.916488 -243.674138) (xy 353.915993 -243.698745)
			(xy 353.908098 -243.747322) (xy 353.892514 -243.794003) (xy 353.869643 -243.83758) (xy 353.840078 -243.876924)
			(xy 353.804585 -243.911016) (xy 353.764082 -243.938972) (xy 353.71962 -243.96007) (xy 353.672349 -243.973762)
			(xy 353.623494 -243.979694) (xy 353.574319 -243.977713) (xy 353.5261 -243.967869) (xy 353.480084 -243.950417)
			(xy 353.437463 -243.92581) (xy 353.399342 -243.894685) (xy 353.366707 -243.857848) (xy 353.340404 -243.816252)
			(xy 353.321113 -243.770976) (xy 353.309336 -243.723192) (xy 353.305376 -243.674138) (xy 352.976434 -243.674138)
			(xy 352.975939 -243.698745) (xy 352.968044 -243.747322) (xy 352.95246 -243.794003) (xy 352.929589 -243.83758)
			(xy 352.900024 -243.876924) (xy 352.864531 -243.911016) (xy 352.824028 -243.938972) (xy 352.779566 -243.96007)
			(xy 352.732295 -243.973762) (xy 352.68344 -243.979694) (xy 352.634265 -243.977713) (xy 352.586046 -243.967869)
			(xy 352.54003 -243.950417) (xy 352.497409 -243.92581) (xy 352.459288 -243.894685) (xy 352.426653 -243.857848)
			(xy 352.40035 -243.816252) (xy 352.381059 -243.770976) (xy 352.369282 -243.723192) (xy 352.365322 -243.674138)
			(xy 352.03638 -243.674138) (xy 352.035885 -243.698745) (xy 352.02799 -243.747322) (xy 352.012406 -243.794003)
			(xy 351.989535 -243.83758) (xy 351.95997 -243.876924) (xy 351.924477 -243.911016) (xy 351.883974 -243.938972)
			(xy 351.839512 -243.96007) (xy 351.792241 -243.973762) (xy 351.743386 -243.979694) (xy 351.694211 -243.977713)
			(xy 351.645992 -243.967869) (xy 351.599976 -243.950417) (xy 351.557355 -243.92581) (xy 351.519234 -243.894685)
			(xy 351.486599 -243.857848) (xy 351.460296 -243.816252) (xy 351.441005 -243.770976) (xy 351.429228 -243.723192)
			(xy 351.425268 -243.674138) (xy 351.096326 -243.674138) (xy 351.095831 -243.698745) (xy 351.087936 -243.747322)
			(xy 351.072352 -243.794003) (xy 351.049481 -243.83758) (xy 351.019916 -243.876924) (xy 350.984423 -243.911016)
			(xy 350.94392 -243.938972) (xy 350.899458 -243.96007) (xy 350.852187 -243.973762) (xy 350.803332 -243.979694)
			(xy 350.754157 -243.977713) (xy 350.705938 -243.967869) (xy 350.659922 -243.950417) (xy 350.617301 -243.92581)
			(xy 350.57918 -243.894685) (xy 350.546545 -243.857848) (xy 350.520242 -243.816252) (xy 350.500951 -243.770976)
			(xy 350.489174 -243.723192) (xy 350.485214 -243.674138) (xy 350.156526 -243.674138) (xy 350.156031 -243.698745)
			(xy 350.148136 -243.747322) (xy 350.132552 -243.794003) (xy 350.109681 -243.83758) (xy 350.080116 -243.876924)
			(xy 350.044623 -243.911016) (xy 350.00412 -243.938972) (xy 349.959658 -243.96007) (xy 349.912387 -243.973762)
			(xy 349.863532 -243.979694) (xy 349.814357 -243.977713) (xy 349.766138 -243.967869) (xy 349.720122 -243.950417)
			(xy 349.677501 -243.92581) (xy 349.63938 -243.894685) (xy 349.606745 -243.857848) (xy 349.580442 -243.816252)
			(xy 349.561151 -243.770976) (xy 349.549374 -243.723192) (xy 349.545414 -243.674138) (xy 349.216472 -243.674138)
			(xy 349.215977 -243.698745) (xy 349.208082 -243.747322) (xy 349.192498 -243.794003) (xy 349.169627 -243.83758)
			(xy 349.140062 -243.876924) (xy 349.104569 -243.911016) (xy 349.064066 -243.938972) (xy 349.019604 -243.96007)
			(xy 348.972333 -243.973762) (xy 348.923478 -243.979694) (xy 348.874303 -243.977713) (xy 348.826084 -243.967869)
			(xy 348.780068 -243.950417) (xy 348.737447 -243.92581) (xy 348.699326 -243.894685) (xy 348.666691 -243.857848)
			(xy 348.640388 -243.816252) (xy 348.621097 -243.770976) (xy 348.60932 -243.723192) (xy 348.60536 -243.674138)
			(xy 348.276418 -243.674138) (xy 348.275923 -243.698745) (xy 348.268028 -243.747322) (xy 348.252444 -243.794003)
			(xy 348.229573 -243.83758) (xy 348.200008 -243.876924) (xy 348.164515 -243.911016) (xy 348.124012 -243.938972)
			(xy 348.07955 -243.96007) (xy 348.032279 -243.973762) (xy 347.983424 -243.979694) (xy 347.934249 -243.977713)
			(xy 347.88603 -243.967869) (xy 347.840014 -243.950417) (xy 347.797393 -243.92581) (xy 347.759272 -243.894685)
			(xy 347.726637 -243.857848) (xy 347.700334 -243.816252) (xy 347.681043 -243.770976) (xy 347.669266 -243.723192)
			(xy 347.665306 -243.674138) (xy 347.336364 -243.674138) (xy 347.335869 -243.698745) (xy 347.327974 -243.747322)
			(xy 347.31239 -243.794003) (xy 347.289519 -243.83758) (xy 347.259954 -243.876924) (xy 347.224461 -243.911016)
			(xy 347.183958 -243.938972) (xy 347.139496 -243.96007) (xy 347.092225 -243.973762) (xy 347.04337 -243.979694)
			(xy 346.994195 -243.977713) (xy 346.945976 -243.967869) (xy 346.89996 -243.950417) (xy 346.857339 -243.92581)
			(xy 346.819218 -243.894685) (xy 346.786583 -243.857848) (xy 346.76028 -243.816252) (xy 346.740989 -243.770976)
			(xy 346.729212 -243.723192) (xy 346.725252 -243.674138) (xy 346.39631 -243.674138) (xy 346.395815 -243.698745)
			(xy 346.38792 -243.747322) (xy 346.372336 -243.794003) (xy 346.349465 -243.83758) (xy 346.3199 -243.876924)
			(xy 346.284407 -243.911016) (xy 346.243904 -243.938972) (xy 346.199442 -243.96007) (xy 346.152171 -243.973762)
			(xy 346.103316 -243.979694) (xy 346.054141 -243.977713) (xy 346.005922 -243.967869) (xy 345.959906 -243.950417)
			(xy 345.917285 -243.92581) (xy 345.879164 -243.894685) (xy 345.846529 -243.857848) (xy 345.820226 -243.816252)
			(xy 345.800935 -243.770976) (xy 345.789158 -243.723192) (xy 345.785198 -243.674138) (xy 345.45651 -243.674138)
			(xy 345.456015 -243.698745) (xy 345.44812 -243.747322) (xy 345.432536 -243.794003) (xy 345.409665 -243.83758)
			(xy 345.3801 -243.876924) (xy 345.344607 -243.911016) (xy 345.304104 -243.938972) (xy 345.259642 -243.96007)
			(xy 345.212371 -243.973762) (xy 345.163516 -243.979694) (xy 345.114341 -243.977713) (xy 345.066122 -243.967869)
			(xy 345.020106 -243.950417) (xy 344.977485 -243.92581) (xy 344.939364 -243.894685) (xy 344.906729 -243.857848)
			(xy 344.880426 -243.816252) (xy 344.861135 -243.770976) (xy 344.849358 -243.723192) (xy 344.845398 -243.674138)
			(xy 344.515915 -243.674138) (xy 344.515914 -243.698766) (xy 344.507989 -243.747425) (xy 344.492349 -243.794179)
			(xy 344.469399 -243.837811) (xy 344.439737 -243.877189) (xy 344.404132 -243.911289) (xy 344.36351 -243.939224)
			(xy 344.34145 -243.950236) (xy 344.327988 -243.956586) (xy 344.31224 -243.981224) (xy 344.31224 -244.177312)
			(xy 344.312671 -244.187026) (xy 344.319892 -244.205062) (xy 344.333296 -244.219125) (xy 344.341958 -244.22354)
			(xy 344.440002 -244.26799) (xy 344.469212 -244.263926) (xy 344.480642 -244.25402) (xy 344.501661 -244.236505)
			(xy 344.548644 -244.20848) (xy 344.599868 -244.189274) (xy 344.653695 -244.179501) (xy 344.681048 -244.178836)
			(xy 344.706297 -244.179361) (xy 344.756106 -244.18768) (xy 344.803866 -244.204083) (xy 344.848275 -244.228122)
			(xy 344.888123 -244.259142) (xy 344.922321 -244.296298) (xy 344.949939 -244.338575) (xy 344.970222 -244.384821)
			(xy 344.982617 -244.433774) (xy 344.986787 -244.4841) (xy 344.986783 -244.484144) (xy 345.315298 -244.484144)
			(xy 345.319258 -244.43509) (xy 345.331035 -244.387306) (xy 345.350326 -244.34203) (xy 345.376629 -244.300434)
			(xy 345.409264 -244.263597) (xy 345.447385 -244.232472) (xy 345.490006 -244.207865) (xy 345.536022 -244.190413)
			(xy 345.584241 -244.180569) (xy 345.633416 -244.178588) (xy 345.682271 -244.18452) (xy 345.729542 -244.198212)
			(xy 345.774004 -244.21931) (xy 345.814507 -244.247266) (xy 345.85 -244.281358) (xy 345.879565 -244.320702)
			(xy 345.902436 -244.364279) (xy 345.91802 -244.41096) (xy 345.925915 -244.459537) (xy 345.92641 -244.484144)
			(xy 346.255352 -244.484144) (xy 346.259312 -244.43509) (xy 346.271089 -244.387306) (xy 346.29038 -244.34203)
			(xy 346.316683 -244.300434) (xy 346.349318 -244.263597) (xy 346.387439 -244.232472) (xy 346.43006 -244.207865)
			(xy 346.476076 -244.190413) (xy 346.524295 -244.180569) (xy 346.57347 -244.178588) (xy 346.622325 -244.18452)
			(xy 346.669596 -244.198212) (xy 346.714058 -244.21931) (xy 346.754561 -244.247266) (xy 346.790054 -244.281358)
			(xy 346.819619 -244.320702) (xy 346.84249 -244.364279) (xy 346.858074 -244.41096) (xy 346.865969 -244.459537)
			(xy 346.866464 -244.484144) (xy 347.195406 -244.484144) (xy 347.199366 -244.43509) (xy 347.211143 -244.387306)
			(xy 347.230434 -244.34203) (xy 347.256737 -244.300434) (xy 347.289372 -244.263597) (xy 347.327493 -244.232472)
			(xy 347.370114 -244.207865) (xy 347.41613 -244.190413) (xy 347.464349 -244.180569) (xy 347.513524 -244.178588)
			(xy 347.562379 -244.18452) (xy 347.60965 -244.198212) (xy 347.654112 -244.21931) (xy 347.694615 -244.247266)
			(xy 347.730108 -244.281358) (xy 347.759673 -244.320702) (xy 347.782544 -244.364279) (xy 347.798128 -244.41096)
			(xy 347.806023 -244.459537) (xy 347.806518 -244.484144) (xy 348.135206 -244.484144) (xy 348.139166 -244.43509)
			(xy 348.150943 -244.387306) (xy 348.170234 -244.34203) (xy 348.196537 -244.300434) (xy 348.229172 -244.263597)
			(xy 348.267293 -244.232472) (xy 348.309914 -244.207865) (xy 348.35593 -244.190413) (xy 348.404149 -244.180569)
			(xy 348.453324 -244.178588) (xy 348.502179 -244.18452) (xy 348.54945 -244.198212) (xy 348.593912 -244.21931)
			(xy 348.634415 -244.247266) (xy 348.669908 -244.281358) (xy 348.699473 -244.320702) (xy 348.722344 -244.364279)
			(xy 348.737928 -244.41096) (xy 348.745823 -244.459537) (xy 348.746318 -244.484144) (xy 349.07526 -244.484144)
			(xy 349.07922 -244.43509) (xy 349.090997 -244.387306) (xy 349.110288 -244.34203) (xy 349.136591 -244.300434)
			(xy 349.169226 -244.263597) (xy 349.207347 -244.232472) (xy 349.249968 -244.207865) (xy 349.295984 -244.190413)
			(xy 349.344203 -244.180569) (xy 349.393378 -244.178588) (xy 349.442233 -244.18452) (xy 349.489504 -244.198212)
			(xy 349.533966 -244.21931) (xy 349.574469 -244.247266) (xy 349.609962 -244.281358) (xy 349.639527 -244.320702)
			(xy 349.662398 -244.364279) (xy 349.677982 -244.41096) (xy 349.685877 -244.459537) (xy 349.686372 -244.484144)
			(xy 350.015314 -244.484144) (xy 350.019274 -244.43509) (xy 350.031051 -244.387306) (xy 350.050342 -244.34203)
			(xy 350.076645 -244.300434) (xy 350.10928 -244.263597) (xy 350.147401 -244.232472) (xy 350.190022 -244.207865)
			(xy 350.236038 -244.190413) (xy 350.284257 -244.180569) (xy 350.333432 -244.178588) (xy 350.382287 -244.18452)
			(xy 350.429558 -244.198212) (xy 350.47402 -244.21931) (xy 350.514523 -244.247266) (xy 350.550016 -244.281358)
			(xy 350.579581 -244.320702) (xy 350.602452 -244.364279) (xy 350.618036 -244.41096) (xy 350.625931 -244.459537)
			(xy 350.626426 -244.484144) (xy 350.955368 -244.484144) (xy 350.959328 -244.43509) (xy 350.971105 -244.387306)
			(xy 350.990396 -244.34203) (xy 351.016699 -244.300434) (xy 351.049334 -244.263597) (xy 351.087455 -244.232472)
			(xy 351.130076 -244.207865) (xy 351.176092 -244.190413) (xy 351.224311 -244.180569) (xy 351.273486 -244.178588)
			(xy 351.322341 -244.18452) (xy 351.369612 -244.198212) (xy 351.414074 -244.21931) (xy 351.454577 -244.247266)
			(xy 351.49007 -244.281358) (xy 351.519635 -244.320702) (xy 351.542506 -244.364279) (xy 351.55809 -244.41096)
			(xy 351.565985 -244.459537) (xy 351.56648 -244.484144) (xy 351.895422 -244.484144) (xy 351.899382 -244.43509)
			(xy 351.911159 -244.387306) (xy 351.93045 -244.34203) (xy 351.956753 -244.300434) (xy 351.989388 -244.263597)
			(xy 352.027509 -244.232472) (xy 352.07013 -244.207865) (xy 352.116146 -244.190413) (xy 352.164365 -244.180569)
			(xy 352.21354 -244.178588) (xy 352.262395 -244.18452) (xy 352.309666 -244.198212) (xy 352.354128 -244.21931)
			(xy 352.394631 -244.247266) (xy 352.430124 -244.281358) (xy 352.459689 -244.320702) (xy 352.48256 -244.364279)
			(xy 352.498144 -244.41096) (xy 352.506039 -244.459537) (xy 352.506534 -244.484144) (xy 352.835222 -244.484144)
			(xy 352.839182 -244.43509) (xy 352.850959 -244.387306) (xy 352.87025 -244.34203) (xy 352.896553 -244.300434)
			(xy 352.929188 -244.263597) (xy 352.967309 -244.232472) (xy 353.00993 -244.207865) (xy 353.055946 -244.190413)
			(xy 353.104165 -244.180569) (xy 353.15334 -244.178588) (xy 353.202195 -244.18452) (xy 353.249466 -244.198212)
			(xy 353.293928 -244.21931) (xy 353.334431 -244.247266) (xy 353.369924 -244.281358) (xy 353.399489 -244.320702)
			(xy 353.42236 -244.364279) (xy 353.437944 -244.41096) (xy 353.445839 -244.459537) (xy 353.446334 -244.484144)
			(xy 353.775276 -244.484144) (xy 353.779236 -244.43509) (xy 353.791013 -244.387306) (xy 353.810304 -244.34203)
			(xy 353.836607 -244.300434) (xy 353.869242 -244.263597) (xy 353.907363 -244.232472) (xy 353.949984 -244.207865)
			(xy 353.996 -244.190413) (xy 354.044219 -244.180569) (xy 354.093394 -244.178588) (xy 354.142249 -244.18452)
			(xy 354.18952 -244.198212) (xy 354.233982 -244.21931) (xy 354.274485 -244.247266) (xy 354.309978 -244.281358)
			(xy 354.339543 -244.320702) (xy 354.362414 -244.364279) (xy 354.377998 -244.41096) (xy 354.385893 -244.459537)
			(xy 354.386388 -244.484144) (xy 354.71533 -244.484144) (xy 354.71929 -244.43509) (xy 354.731067 -244.387306)
			(xy 354.750358 -244.34203) (xy 354.776661 -244.300434) (xy 354.809296 -244.263597) (xy 354.847417 -244.232472)
			(xy 354.890038 -244.207865) (xy 354.936054 -244.190413) (xy 354.984273 -244.180569) (xy 355.033448 -244.178588)
			(xy 355.082303 -244.18452) (xy 355.129574 -244.198212) (xy 355.174036 -244.21931) (xy 355.214539 -244.247266)
			(xy 355.250032 -244.281358) (xy 355.279597 -244.320702) (xy 355.302468 -244.364279) (xy 355.318052 -244.41096)
			(xy 355.325947 -244.459537) (xy 355.326442 -244.484144) (xy 355.655384 -244.484144) (xy 355.659344 -244.43509)
			(xy 355.671121 -244.387306) (xy 355.690412 -244.34203) (xy 355.716715 -244.300434) (xy 355.74935 -244.263597)
			(xy 355.787471 -244.232472) (xy 355.830092 -244.207865) (xy 355.876108 -244.190413) (xy 355.924327 -244.180569)
			(xy 355.973502 -244.178588) (xy 356.022357 -244.18452) (xy 356.069628 -244.198212) (xy 356.11409 -244.21931)
			(xy 356.154593 -244.247266) (xy 356.190086 -244.281358) (xy 356.219651 -244.320702) (xy 356.242522 -244.364279)
			(xy 356.258106 -244.41096) (xy 356.266001 -244.459537) (xy 356.266496 -244.484144) (xy 356.595438 -244.484144)
			(xy 356.599398 -244.43509) (xy 356.611175 -244.387306) (xy 356.630466 -244.34203) (xy 356.656769 -244.300434)
			(xy 356.689404 -244.263597) (xy 356.727525 -244.232472) (xy 356.770146 -244.207865) (xy 356.816162 -244.190413)
			(xy 356.864381 -244.180569) (xy 356.913556 -244.178588) (xy 356.962411 -244.18452) (xy 357.009682 -244.198212)
			(xy 357.054144 -244.21931) (xy 357.094647 -244.247266) (xy 357.13014 -244.281358) (xy 357.159705 -244.320702)
			(xy 357.182576 -244.364279) (xy 357.19816 -244.41096) (xy 357.206055 -244.459537) (xy 357.20655 -244.484144)
			(xy 357.535238 -244.484144) (xy 357.539198 -244.43509) (xy 357.550975 -244.387306) (xy 357.570266 -244.34203)
			(xy 357.596569 -244.300434) (xy 357.629204 -244.263597) (xy 357.667325 -244.232472) (xy 357.709946 -244.207865)
			(xy 357.755962 -244.190413) (xy 357.804181 -244.180569) (xy 357.853356 -244.178588) (xy 357.902211 -244.18452)
			(xy 357.949482 -244.198212) (xy 357.993944 -244.21931) (xy 358.034447 -244.247266) (xy 358.06994 -244.281358)
			(xy 358.099505 -244.320702) (xy 358.122376 -244.364279) (xy 358.13796 -244.41096) (xy 358.145855 -244.459537)
			(xy 358.14635 -244.484144) (xy 358.145855 -244.508751) (xy 358.13796 -244.557328) (xy 358.122376 -244.604009)
			(xy 358.099505 -244.647586) (xy 358.06994 -244.68693) (xy 358.034447 -244.721022) (xy 357.993944 -244.748978)
			(xy 357.949482 -244.770076) (xy 357.902211 -244.783768) (xy 357.853356 -244.7897) (xy 357.804181 -244.787719)
			(xy 357.755962 -244.777875) (xy 357.709946 -244.760423) (xy 357.667325 -244.735816) (xy 357.629204 -244.704691)
			(xy 357.596569 -244.667854) (xy 357.570266 -244.626258) (xy 357.550975 -244.580982) (xy 357.539198 -244.533198)
			(xy 357.535238 -244.484144) (xy 357.20655 -244.484144) (xy 357.206055 -244.508751) (xy 357.19816 -244.557328)
			(xy 357.182576 -244.604009) (xy 357.159705 -244.647586) (xy 357.13014 -244.68693) (xy 357.094647 -244.721022)
			(xy 357.054144 -244.748978) (xy 357.009682 -244.770076) (xy 356.962411 -244.783768) (xy 356.913556 -244.7897)
			(xy 356.864381 -244.787719) (xy 356.816162 -244.777875) (xy 356.770146 -244.760423) (xy 356.727525 -244.735816)
			(xy 356.689404 -244.704691) (xy 356.656769 -244.667854) (xy 356.630466 -244.626258) (xy 356.611175 -244.580982)
			(xy 356.599398 -244.533198) (xy 356.595438 -244.484144) (xy 356.266496 -244.484144) (xy 356.266001 -244.508751)
			(xy 356.258106 -244.557328) (xy 356.242522 -244.604009) (xy 356.219651 -244.647586) (xy 356.190086 -244.68693)
			(xy 356.154593 -244.721022) (xy 356.11409 -244.748978) (xy 356.069628 -244.770076) (xy 356.022357 -244.783768)
			(xy 355.973502 -244.7897) (xy 355.924327 -244.787719) (xy 355.876108 -244.777875) (xy 355.830092 -244.760423)
			(xy 355.787471 -244.735816) (xy 355.74935 -244.704691) (xy 355.716715 -244.667854) (xy 355.690412 -244.626258)
			(xy 355.671121 -244.580982) (xy 355.659344 -244.533198) (xy 355.655384 -244.484144) (xy 355.326442 -244.484144)
			(xy 355.325947 -244.508751) (xy 355.318052 -244.557328) (xy 355.302468 -244.604009) (xy 355.279597 -244.647586)
			(xy 355.250032 -244.68693) (xy 355.214539 -244.721022) (xy 355.174036 -244.748978) (xy 355.129574 -244.770076)
			(xy 355.082303 -244.783768) (xy 355.033448 -244.7897) (xy 354.984273 -244.787719) (xy 354.936054 -244.777875)
			(xy 354.890038 -244.760423) (xy 354.847417 -244.735816) (xy 354.809296 -244.704691) (xy 354.776661 -244.667854)
			(xy 354.750358 -244.626258) (xy 354.731067 -244.580982) (xy 354.71929 -244.533198) (xy 354.71533 -244.484144)
			(xy 354.386388 -244.484144) (xy 354.385893 -244.508751) (xy 354.377998 -244.557328) (xy 354.362414 -244.604009)
			(xy 354.339543 -244.647586) (xy 354.309978 -244.68693) (xy 354.274485 -244.721022) (xy 354.233982 -244.748978)
			(xy 354.18952 -244.770076) (xy 354.142249 -244.783768) (xy 354.093394 -244.7897) (xy 354.044219 -244.787719)
			(xy 353.996 -244.777875) (xy 353.949984 -244.760423) (xy 353.907363 -244.735816) (xy 353.869242 -244.704691)
			(xy 353.836607 -244.667854) (xy 353.810304 -244.626258) (xy 353.791013 -244.580982) (xy 353.779236 -244.533198)
			(xy 353.775276 -244.484144) (xy 353.446334 -244.484144) (xy 353.445839 -244.508751) (xy 353.437944 -244.557328)
			(xy 353.42236 -244.604009) (xy 353.399489 -244.647586) (xy 353.369924 -244.68693) (xy 353.334431 -244.721022)
			(xy 353.293928 -244.748978) (xy 353.249466 -244.770076) (xy 353.202195 -244.783768) (xy 353.15334 -244.7897)
			(xy 353.104165 -244.787719) (xy 353.055946 -244.777875) (xy 353.00993 -244.760423) (xy 352.967309 -244.735816)
			(xy 352.929188 -244.704691) (xy 352.896553 -244.667854) (xy 352.87025 -244.626258) (xy 352.850959 -244.580982)
			(xy 352.839182 -244.533198) (xy 352.835222 -244.484144) (xy 352.506534 -244.484144) (xy 352.506039 -244.508751)
			(xy 352.498144 -244.557328) (xy 352.48256 -244.604009) (xy 352.459689 -244.647586) (xy 352.430124 -244.68693)
			(xy 352.394631 -244.721022) (xy 352.354128 -244.748978) (xy 352.309666 -244.770076) (xy 352.262395 -244.783768)
			(xy 352.21354 -244.7897) (xy 352.164365 -244.787719) (xy 352.116146 -244.777875) (xy 352.07013 -244.760423)
			(xy 352.027509 -244.735816) (xy 351.989388 -244.704691) (xy 351.956753 -244.667854) (xy 351.93045 -244.626258)
			(xy 351.911159 -244.580982) (xy 351.899382 -244.533198) (xy 351.895422 -244.484144) (xy 351.56648 -244.484144)
			(xy 351.565985 -244.508751) (xy 351.55809 -244.557328) (xy 351.542506 -244.604009) (xy 351.519635 -244.647586)
			(xy 351.49007 -244.68693) (xy 351.454577 -244.721022) (xy 351.414074 -244.748978) (xy 351.369612 -244.770076)
			(xy 351.322341 -244.783768) (xy 351.273486 -244.7897) (xy 351.224311 -244.787719) (xy 351.176092 -244.777875)
			(xy 351.130076 -244.760423) (xy 351.087455 -244.735816) (xy 351.049334 -244.704691) (xy 351.016699 -244.667854)
			(xy 350.990396 -244.626258) (xy 350.971105 -244.580982) (xy 350.959328 -244.533198) (xy 350.955368 -244.484144)
			(xy 350.626426 -244.484144) (xy 350.625931 -244.508751) (xy 350.618036 -244.557328) (xy 350.602452 -244.604009)
			(xy 350.579581 -244.647586) (xy 350.550016 -244.68693) (xy 350.514523 -244.721022) (xy 350.47402 -244.748978)
			(xy 350.429558 -244.770076) (xy 350.382287 -244.783768) (xy 350.333432 -244.7897) (xy 350.284257 -244.787719)
			(xy 350.236038 -244.777875) (xy 350.190022 -244.760423) (xy 350.147401 -244.735816) (xy 350.10928 -244.704691)
			(xy 350.076645 -244.667854) (xy 350.050342 -244.626258) (xy 350.031051 -244.580982) (xy 350.019274 -244.533198)
			(xy 350.015314 -244.484144) (xy 349.686372 -244.484144) (xy 349.685877 -244.508751) (xy 349.677982 -244.557328)
			(xy 349.662398 -244.604009) (xy 349.639527 -244.647586) (xy 349.609962 -244.68693) (xy 349.574469 -244.721022)
			(xy 349.533966 -244.748978) (xy 349.489504 -244.770076) (xy 349.442233 -244.783768) (xy 349.393378 -244.7897)
			(xy 349.344203 -244.787719) (xy 349.295984 -244.777875) (xy 349.249968 -244.760423) (xy 349.207347 -244.735816)
			(xy 349.169226 -244.704691) (xy 349.136591 -244.667854) (xy 349.110288 -244.626258) (xy 349.090997 -244.580982)
			(xy 349.07922 -244.533198) (xy 349.07526 -244.484144) (xy 348.746318 -244.484144) (xy 348.745823 -244.508751)
			(xy 348.737928 -244.557328) (xy 348.722344 -244.604009) (xy 348.699473 -244.647586) (xy 348.669908 -244.68693)
			(xy 348.634415 -244.721022) (xy 348.593912 -244.748978) (xy 348.54945 -244.770076) (xy 348.502179 -244.783768)
			(xy 348.453324 -244.7897) (xy 348.404149 -244.787719) (xy 348.35593 -244.777875) (xy 348.309914 -244.760423)
			(xy 348.267293 -244.735816) (xy 348.229172 -244.704691) (xy 348.196537 -244.667854) (xy 348.170234 -244.626258)
			(xy 348.150943 -244.580982) (xy 348.139166 -244.533198) (xy 348.135206 -244.484144) (xy 347.806518 -244.484144)
			(xy 347.806023 -244.508751) (xy 347.798128 -244.557328) (xy 347.782544 -244.604009) (xy 347.759673 -244.647586)
			(xy 347.730108 -244.68693) (xy 347.694615 -244.721022) (xy 347.654112 -244.748978) (xy 347.60965 -244.770076)
			(xy 347.562379 -244.783768) (xy 347.513524 -244.7897) (xy 347.464349 -244.787719) (xy 347.41613 -244.777875)
			(xy 347.370114 -244.760423) (xy 347.327493 -244.735816) (xy 347.289372 -244.704691) (xy 347.256737 -244.667854)
			(xy 347.230434 -244.626258) (xy 347.211143 -244.580982) (xy 347.199366 -244.533198) (xy 347.195406 -244.484144)
			(xy 346.866464 -244.484144) (xy 346.865969 -244.508751) (xy 346.858074 -244.557328) (xy 346.84249 -244.604009)
			(xy 346.819619 -244.647586) (xy 346.790054 -244.68693) (xy 346.754561 -244.721022) (xy 346.714058 -244.748978)
			(xy 346.669596 -244.770076) (xy 346.622325 -244.783768) (xy 346.57347 -244.7897) (xy 346.524295 -244.787719)
			(xy 346.476076 -244.777875) (xy 346.43006 -244.760423) (xy 346.387439 -244.735816) (xy 346.349318 -244.704691)
			(xy 346.316683 -244.667854) (xy 346.29038 -244.626258) (xy 346.271089 -244.580982) (xy 346.259312 -244.533198)
			(xy 346.255352 -244.484144) (xy 345.92641 -244.484144) (xy 345.925915 -244.508751) (xy 345.91802 -244.557328)
			(xy 345.902436 -244.604009) (xy 345.879565 -244.647586) (xy 345.85 -244.68693) (xy 345.814507 -244.721022)
			(xy 345.774004 -244.748978) (xy 345.729542 -244.770076) (xy 345.682271 -244.783768) (xy 345.633416 -244.7897)
			(xy 345.584241 -244.787719) (xy 345.536022 -244.777875) (xy 345.490006 -244.760423) (xy 345.447385 -244.735816)
			(xy 345.409264 -244.704691) (xy 345.376629 -244.667854) (xy 345.350326 -244.626258) (xy 345.331035 -244.580982)
			(xy 345.319258 -244.533198) (xy 345.315298 -244.484144) (xy 344.986783 -244.484144) (xy 344.982617 -244.534426)
			(xy 344.970222 -244.583379) (xy 344.949939 -244.629625) (xy 344.922321 -244.671902) (xy 344.888123 -244.709058)
			(xy 344.848275 -244.740078) (xy 344.803866 -244.764117) (xy 344.756106 -244.78052) (xy 344.706297 -244.788839)
			(xy 344.681048 -244.789452) (xy 344.656965 -244.788994) (xy 344.609399 -244.781422) (xy 344.563612 -244.766474)
			(xy 344.520741 -244.744521) (xy 344.481849 -244.716108) (xy 344.447902 -244.681939) (xy 344.419742 -244.642864)
			(xy 344.408506 -244.621558) (xy 344.401902 -244.608604) (xy 344.377518 -244.593618) (xy 344.36304 -244.593618)
			(xy 344.353015 -244.594031) (xy 344.334487 -244.601694) (xy 344.320307 -244.615869) (xy 344.312635 -244.634393)
			(xy 344.31224 -244.644418) (xy 344.31224 -244.738398) (xy 344.312664 -244.748467) (xy 344.320382 -244.767069)
			(xy 344.327226 -244.774466) (xy 344.716354 -245.163594) (xy 344.723206 -245.17099) (xy 344.73095 -245.189588)
			(xy 344.73134 -245.199662) (xy 344.73134 -245.29415) (xy 346.725252 -245.29415) (xy 346.729212 -245.245096)
			(xy 346.740989 -245.197312) (xy 346.76028 -245.152036) (xy 346.786583 -245.11044) (xy 346.819218 -245.073603)
			(xy 346.857339 -245.042478) (xy 346.89996 -245.017871) (xy 346.945976 -245.000419) (xy 346.994195 -244.990575)
			(xy 347.04337 -244.988594) (xy 347.092225 -244.994526) (xy 347.139496 -245.008218) (xy 347.183958 -245.029316)
			(xy 347.224461 -245.057272) (xy 347.259954 -245.091364) (xy 347.289519 -245.130708) (xy 347.31239 -245.174285)
			(xy 347.327974 -245.220966) (xy 347.335869 -245.269543) (xy 347.336364 -245.29415) (xy 349.545414 -245.29415)
			(xy 349.549374 -245.245096) (xy 349.561151 -245.197312) (xy 349.580442 -245.152036) (xy 349.606745 -245.11044)
			(xy 349.63938 -245.073603) (xy 349.677501 -245.042478) (xy 349.720122 -245.017871) (xy 349.766138 -245.000419)
			(xy 349.814357 -244.990575) (xy 349.863532 -244.988594) (xy 349.912387 -244.994526) (xy 349.959658 -245.008218)
			(xy 350.00412 -245.029316) (xy 350.044623 -245.057272) (xy 350.080116 -245.091364) (xy 350.109681 -245.130708)
			(xy 350.132552 -245.174285) (xy 350.148136 -245.220966) (xy 350.156031 -245.269543) (xy 350.156526 -245.29415)
			(xy 352.365322 -245.29415) (xy 352.369282 -245.245096) (xy 352.381059 -245.197312) (xy 352.40035 -245.152036)
			(xy 352.426653 -245.11044) (xy 352.459288 -245.073603) (xy 352.497409 -245.042478) (xy 352.54003 -245.017871)
			(xy 352.586046 -245.000419) (xy 352.634265 -244.990575) (xy 352.68344 -244.988594) (xy 352.732295 -244.994526)
			(xy 352.779566 -245.008218) (xy 352.824028 -245.029316) (xy 352.864531 -245.057272) (xy 352.900024 -245.091364)
			(xy 352.929589 -245.130708) (xy 352.95246 -245.174285) (xy 352.968044 -245.220966) (xy 352.975939 -245.269543)
			(xy 352.976434 -245.29415) (xy 355.18523 -245.29415) (xy 355.18919 -245.245096) (xy 355.200967 -245.197312)
			(xy 355.220258 -245.152036) (xy 355.246561 -245.11044) (xy 355.279196 -245.073603) (xy 355.317317 -245.042478)
			(xy 355.359938 -245.017871) (xy 355.405954 -245.000419) (xy 355.454173 -244.990575) (xy 355.503348 -244.988594)
			(xy 355.552203 -244.994526) (xy 355.599474 -245.008218) (xy 355.643936 -245.029316) (xy 355.684439 -245.057272)
			(xy 355.719932 -245.091364) (xy 355.749497 -245.130708) (xy 355.772368 -245.174285) (xy 355.787952 -245.220966)
			(xy 355.795847 -245.269543) (xy 355.796342 -245.29415) (xy 356.125284 -245.29415) (xy 356.129244 -245.245096)
			(xy 356.141021 -245.197312) (xy 356.160312 -245.152036) (xy 356.186615 -245.11044) (xy 356.21925 -245.073603)
			(xy 356.257371 -245.042478) (xy 356.299992 -245.017871) (xy 356.346008 -245.000419) (xy 356.394227 -244.990575)
			(xy 356.443402 -244.988594) (xy 356.492257 -244.994526) (xy 356.539528 -245.008218) (xy 356.58399 -245.029316)
			(xy 356.624493 -245.057272) (xy 356.659986 -245.091364) (xy 356.689551 -245.130708) (xy 356.712422 -245.174285)
			(xy 356.728006 -245.220966) (xy 356.735901 -245.269543) (xy 356.736396 -245.29415) (xy 357.065338 -245.29415)
			(xy 357.069298 -245.245096) (xy 357.081075 -245.197312) (xy 357.100366 -245.152036) (xy 357.126669 -245.11044)
			(xy 357.159304 -245.073603) (xy 357.197425 -245.042478) (xy 357.240046 -245.017871) (xy 357.286062 -245.000419)
			(xy 357.334281 -244.990575) (xy 357.383456 -244.988594) (xy 357.432311 -244.994526) (xy 357.479582 -245.008218)
			(xy 357.524044 -245.029316) (xy 357.564547 -245.057272) (xy 357.60004 -245.091364) (xy 357.629605 -245.130708)
			(xy 357.652476 -245.174285) (xy 357.66806 -245.220966) (xy 357.675955 -245.269543) (xy 357.67645 -245.29415)
			(xy 358.005392 -245.29415) (xy 358.009352 -245.245096) (xy 358.021129 -245.197312) (xy 358.04042 -245.152036)
			(xy 358.066723 -245.11044) (xy 358.099358 -245.073603) (xy 358.137479 -245.042478) (xy 358.1801 -245.017871)
			(xy 358.226116 -245.000419) (xy 358.274335 -244.990575) (xy 358.32351 -244.988594) (xy 358.372365 -244.994526)
			(xy 358.419636 -245.008218) (xy 358.464098 -245.029316) (xy 358.504601 -245.057272) (xy 358.540094 -245.091364)
			(xy 358.569659 -245.130708) (xy 358.59253 -245.174285) (xy 358.608114 -245.220966) (xy 358.616009 -245.269543)
			(xy 358.616504 -245.29415) (xy 358.616009 -245.318757) (xy 358.608114 -245.367334) (xy 358.59253 -245.414015)
			(xy 358.569659 -245.457592) (xy 358.540094 -245.496936) (xy 358.504601 -245.531028) (xy 358.464098 -245.558984)
			(xy 358.419636 -245.580082) (xy 358.372365 -245.593774) (xy 358.32351 -245.599706) (xy 358.274335 -245.597725)
			(xy 358.226116 -245.587881) (xy 358.1801 -245.570429) (xy 358.137479 -245.545822) (xy 358.099358 -245.514697)
			(xy 358.066723 -245.47786) (xy 358.04042 -245.436264) (xy 358.021129 -245.390988) (xy 358.009352 -245.343204)
			(xy 358.005392 -245.29415) (xy 357.67645 -245.29415) (xy 357.675955 -245.318757) (xy 357.66806 -245.367334)
			(xy 357.652476 -245.414015) (xy 357.629605 -245.457592) (xy 357.60004 -245.496936) (xy 357.564547 -245.531028)
			(xy 357.524044 -245.558984) (xy 357.479582 -245.580082) (xy 357.432311 -245.593774) (xy 357.383456 -245.599706)
			(xy 357.334281 -245.597725) (xy 357.286062 -245.587881) (xy 357.240046 -245.570429) (xy 357.197425 -245.545822)
			(xy 357.159304 -245.514697) (xy 357.126669 -245.47786) (xy 357.100366 -245.436264) (xy 357.081075 -245.390988)
			(xy 357.069298 -245.343204) (xy 357.065338 -245.29415) (xy 356.736396 -245.29415) (xy 356.735901 -245.318757)
			(xy 356.728006 -245.367334) (xy 356.712422 -245.414015) (xy 356.689551 -245.457592) (xy 356.659986 -245.496936)
			(xy 356.624493 -245.531028) (xy 356.58399 -245.558984) (xy 356.539528 -245.580082) (xy 356.492257 -245.593774)
			(xy 356.443402 -245.599706) (xy 356.394227 -245.597725) (xy 356.346008 -245.587881) (xy 356.299992 -245.570429)
			(xy 356.257371 -245.545822) (xy 356.21925 -245.514697) (xy 356.186615 -245.47786) (xy 356.160312 -245.436264)
			(xy 356.141021 -245.390988) (xy 356.129244 -245.343204) (xy 356.125284 -245.29415) (xy 355.796342 -245.29415)
			(xy 355.795847 -245.318757) (xy 355.787952 -245.367334) (xy 355.772368 -245.414015) (xy 355.749497 -245.457592)
			(xy 355.719932 -245.496936) (xy 355.684439 -245.531028) (xy 355.643936 -245.558984) (xy 355.599474 -245.580082)
			(xy 355.552203 -245.593774) (xy 355.503348 -245.599706) (xy 355.454173 -245.597725) (xy 355.405954 -245.587881)
			(xy 355.359938 -245.570429) (xy 355.317317 -245.545822) (xy 355.279196 -245.514697) (xy 355.246561 -245.47786)
			(xy 355.220258 -245.436264) (xy 355.200967 -245.390988) (xy 355.18919 -245.343204) (xy 355.18523 -245.29415)
			(xy 352.976434 -245.29415) (xy 352.975939 -245.318757) (xy 352.968044 -245.367334) (xy 352.95246 -245.414015)
			(xy 352.929589 -245.457592) (xy 352.900024 -245.496936) (xy 352.864531 -245.531028) (xy 352.824028 -245.558984)
			(xy 352.779566 -245.580082) (xy 352.732295 -245.593774) (xy 352.68344 -245.599706) (xy 352.634265 -245.597725)
			(xy 352.586046 -245.587881) (xy 352.54003 -245.570429) (xy 352.497409 -245.545822) (xy 352.459288 -245.514697)
			(xy 352.426653 -245.47786) (xy 352.40035 -245.436264) (xy 352.381059 -245.390988) (xy 352.369282 -245.343204)
			(xy 352.365322 -245.29415) (xy 350.156526 -245.29415) (xy 350.156031 -245.318757) (xy 350.148136 -245.367334)
			(xy 350.132552 -245.414015) (xy 350.109681 -245.457592) (xy 350.080116 -245.496936) (xy 350.044623 -245.531028)
			(xy 350.00412 -245.558984) (xy 349.959658 -245.580082) (xy 349.912387 -245.593774) (xy 349.863532 -245.599706)
			(xy 349.814357 -245.597725) (xy 349.766138 -245.587881) (xy 349.720122 -245.570429) (xy 349.677501 -245.545822)
			(xy 349.63938 -245.514697) (xy 349.606745 -245.47786) (xy 349.580442 -245.436264) (xy 349.561151 -245.390988)
			(xy 349.549374 -245.343204) (xy 349.545414 -245.29415) (xy 347.336364 -245.29415) (xy 347.335869 -245.318757)
			(xy 347.327974 -245.367334) (xy 347.31239 -245.414015) (xy 347.289519 -245.457592) (xy 347.259954 -245.496936)
			(xy 347.224461 -245.531028) (xy 347.183958 -245.558984) (xy 347.139496 -245.580082) (xy 347.092225 -245.593774)
			(xy 347.04337 -245.599706) (xy 346.994195 -245.597725) (xy 346.945976 -245.587881) (xy 346.89996 -245.570429)
			(xy 346.857339 -245.545822) (xy 346.819218 -245.514697) (xy 346.786583 -245.47786) (xy 346.76028 -245.436264)
			(xy 346.740989 -245.390988) (xy 346.729212 -245.343204) (xy 346.725252 -245.29415) (xy 344.73134 -245.29415)
			(xy 344.73134 -245.779798) (xy 344.751406 -245.806468) (xy 344.767662 -245.811294) (xy 344.791015 -245.818726)
			(xy 344.83517 -245.839979) (xy 344.875366 -245.868007) (xy 344.910573 -245.902093) (xy 344.939887 -245.941361)
			(xy 344.962558 -245.984805) (xy 344.978004 -246.031311) (xy 344.985828 -246.079686) (xy 344.985829 -246.104156)
			(xy 345.315298 -246.104156) (xy 345.319258 -246.055102) (xy 345.331035 -246.007318) (xy 345.350326 -245.962042)
			(xy 345.376629 -245.920446) (xy 345.409264 -245.883609) (xy 345.447385 -245.852484) (xy 345.490006 -245.827877)
			(xy 345.536022 -245.810425) (xy 345.584241 -245.800581) (xy 345.633416 -245.7986) (xy 345.682271 -245.804532)
			(xy 345.729542 -245.818224) (xy 345.774004 -245.839322) (xy 345.814507 -245.867278) (xy 345.85 -245.90137)
			(xy 345.879565 -245.940714) (xy 345.902436 -245.984291) (xy 345.91802 -246.030972) (xy 345.925915 -246.079549)
			(xy 345.92641 -246.104156) (xy 346.255352 -246.104156) (xy 346.259312 -246.055102) (xy 346.271089 -246.007318)
			(xy 346.29038 -245.962042) (xy 346.316683 -245.920446) (xy 346.349318 -245.883609) (xy 346.387439 -245.852484)
			(xy 346.43006 -245.827877) (xy 346.476076 -245.810425) (xy 346.524295 -245.800581) (xy 346.57347 -245.7986)
			(xy 346.622325 -245.804532) (xy 346.669596 -245.818224) (xy 346.714058 -245.839322) (xy 346.754561 -245.867278)
			(xy 346.790054 -245.90137) (xy 346.819619 -245.940714) (xy 346.84249 -245.984291) (xy 346.858074 -246.030972)
			(xy 346.865969 -246.079549) (xy 346.866464 -246.104156) (xy 347.195406 -246.104156) (xy 347.199366 -246.055102)
			(xy 347.211143 -246.007318) (xy 347.230434 -245.962042) (xy 347.256737 -245.920446) (xy 347.289372 -245.883609)
			(xy 347.327493 -245.852484) (xy 347.370114 -245.827877) (xy 347.41613 -245.810425) (xy 347.464349 -245.800581)
			(xy 347.513524 -245.7986) (xy 347.562379 -245.804532) (xy 347.60965 -245.818224) (xy 347.654112 -245.839322)
			(xy 347.694615 -245.867278) (xy 347.730108 -245.90137) (xy 347.759673 -245.940714) (xy 347.782544 -245.984291)
			(xy 347.798128 -246.030972) (xy 347.806023 -246.079549) (xy 347.806518 -246.104156) (xy 348.135206 -246.104156)
			(xy 348.139166 -246.055102) (xy 348.150943 -246.007318) (xy 348.170234 -245.962042) (xy 348.196537 -245.920446)
			(xy 348.229172 -245.883609) (xy 348.267293 -245.852484) (xy 348.309914 -245.827877) (xy 348.35593 -245.810425)
			(xy 348.404149 -245.800581) (xy 348.453324 -245.7986) (xy 348.502179 -245.804532) (xy 348.54945 -245.818224)
			(xy 348.593912 -245.839322) (xy 348.634415 -245.867278) (xy 348.669908 -245.90137) (xy 348.699473 -245.940714)
			(xy 348.722344 -245.984291) (xy 348.737928 -246.030972) (xy 348.745823 -246.079549) (xy 348.746318 -246.104156)
			(xy 349.07526 -246.104156) (xy 349.07922 -246.055102) (xy 349.090997 -246.007318) (xy 349.110288 -245.962042)
			(xy 349.136591 -245.920446) (xy 349.169226 -245.883609) (xy 349.207347 -245.852484) (xy 349.249968 -245.827877)
			(xy 349.295984 -245.810425) (xy 349.344203 -245.800581) (xy 349.393378 -245.7986) (xy 349.442233 -245.804532)
			(xy 349.489504 -245.818224) (xy 349.533966 -245.839322) (xy 349.574469 -245.867278) (xy 349.609962 -245.90137)
			(xy 349.639527 -245.940714) (xy 349.662398 -245.984291) (xy 349.677982 -246.030972) (xy 349.685877 -246.079549)
			(xy 349.686372 -246.104156) (xy 350.015314 -246.104156) (xy 350.019274 -246.055102) (xy 350.031051 -246.007318)
			(xy 350.050342 -245.962042) (xy 350.076645 -245.920446) (xy 350.10928 -245.883609) (xy 350.147401 -245.852484)
			(xy 350.190022 -245.827877) (xy 350.236038 -245.810425) (xy 350.284257 -245.800581) (xy 350.333432 -245.7986)
			(xy 350.382287 -245.804532) (xy 350.429558 -245.818224) (xy 350.47402 -245.839322) (xy 350.514523 -245.867278)
			(xy 350.550016 -245.90137) (xy 350.579581 -245.940714) (xy 350.602452 -245.984291) (xy 350.618036 -246.030972)
			(xy 350.625931 -246.079549) (xy 350.626426 -246.104156) (xy 350.955368 -246.104156) (xy 350.959328 -246.055102)
			(xy 350.971105 -246.007318) (xy 350.990396 -245.962042) (xy 351.016699 -245.920446) (xy 351.049334 -245.883609)
			(xy 351.087455 -245.852484) (xy 351.130076 -245.827877) (xy 351.176092 -245.810425) (xy 351.224311 -245.800581)
			(xy 351.273486 -245.7986) (xy 351.322341 -245.804532) (xy 351.369612 -245.818224) (xy 351.414074 -245.839322)
			(xy 351.454577 -245.867278) (xy 351.49007 -245.90137) (xy 351.519635 -245.940714) (xy 351.542506 -245.984291)
			(xy 351.55809 -246.030972) (xy 351.565985 -246.079549) (xy 351.56648 -246.104156) (xy 351.895422 -246.104156)
			(xy 351.899382 -246.055102) (xy 351.911159 -246.007318) (xy 351.93045 -245.962042) (xy 351.956753 -245.920446)
			(xy 351.989388 -245.883609) (xy 352.027509 -245.852484) (xy 352.07013 -245.827877) (xy 352.116146 -245.810425)
			(xy 352.164365 -245.800581) (xy 352.21354 -245.7986) (xy 352.262395 -245.804532) (xy 352.309666 -245.818224)
			(xy 352.354128 -245.839322) (xy 352.394631 -245.867278) (xy 352.430124 -245.90137) (xy 352.459689 -245.940714)
			(xy 352.48256 -245.984291) (xy 352.498144 -246.030972) (xy 352.506039 -246.079549) (xy 352.506534 -246.104156)
			(xy 352.835222 -246.104156) (xy 352.839182 -246.055102) (xy 352.850959 -246.007318) (xy 352.87025 -245.962042)
			(xy 352.896553 -245.920446) (xy 352.929188 -245.883609) (xy 352.967309 -245.852484) (xy 353.00993 -245.827877)
			(xy 353.055946 -245.810425) (xy 353.104165 -245.800581) (xy 353.15334 -245.7986) (xy 353.202195 -245.804532)
			(xy 353.249466 -245.818224) (xy 353.293928 -245.839322) (xy 353.334431 -245.867278) (xy 353.369924 -245.90137)
			(xy 353.399489 -245.940714) (xy 353.42236 -245.984291) (xy 353.437944 -246.030972) (xy 353.445839 -246.079549)
			(xy 353.446334 -246.104156) (xy 353.775276 -246.104156) (xy 353.779236 -246.055102) (xy 353.791013 -246.007318)
			(xy 353.810304 -245.962042) (xy 353.836607 -245.920446) (xy 353.869242 -245.883609) (xy 353.907363 -245.852484)
			(xy 353.949984 -245.827877) (xy 353.996 -245.810425) (xy 354.044219 -245.800581) (xy 354.093394 -245.7986)
			(xy 354.142249 -245.804532) (xy 354.18952 -245.818224) (xy 354.233982 -245.839322) (xy 354.274485 -245.867278)
			(xy 354.309978 -245.90137) (xy 354.339543 -245.940714) (xy 354.362414 -245.984291) (xy 354.377998 -246.030972)
			(xy 354.385893 -246.079549) (xy 354.386388 -246.104156) (xy 354.71533 -246.104156) (xy 354.71929 -246.055102)
			(xy 354.731067 -246.007318) (xy 354.750358 -245.962042) (xy 354.776661 -245.920446) (xy 354.809296 -245.883609)
			(xy 354.847417 -245.852484) (xy 354.890038 -245.827877) (xy 354.936054 -245.810425) (xy 354.984273 -245.800581)
			(xy 355.033448 -245.7986) (xy 355.082303 -245.804532) (xy 355.129574 -245.818224) (xy 355.174036 -245.839322)
			(xy 355.214539 -245.867278) (xy 355.250032 -245.90137) (xy 355.279597 -245.940714) (xy 355.302468 -245.984291)
			(xy 355.318052 -246.030972) (xy 355.325947 -246.079549) (xy 355.326442 -246.104156) (xy 355.655384 -246.104156)
			(xy 355.659344 -246.055102) (xy 355.671121 -246.007318) (xy 355.690412 -245.962042) (xy 355.716715 -245.920446)
			(xy 355.74935 -245.883609) (xy 355.787471 -245.852484) (xy 355.830092 -245.827877) (xy 355.876108 -245.810425)
			(xy 355.924327 -245.800581) (xy 355.973502 -245.7986) (xy 356.022357 -245.804532) (xy 356.069628 -245.818224)
			(xy 356.11409 -245.839322) (xy 356.154593 -245.867278) (xy 356.190086 -245.90137) (xy 356.219651 -245.940714)
			(xy 356.242522 -245.984291) (xy 356.258106 -246.030972) (xy 356.266001 -246.079549) (xy 356.266496 -246.104156)
			(xy 356.266001 -246.128763) (xy 356.258106 -246.17734) (xy 356.242522 -246.224021) (xy 356.219651 -246.267598)
			(xy 356.190086 -246.306942) (xy 356.154593 -246.341034) (xy 356.11409 -246.36899) (xy 356.069628 -246.390088)
			(xy 356.022357 -246.40378) (xy 355.973502 -246.409712) (xy 355.924327 -246.407731) (xy 355.876108 -246.397887)
			(xy 355.830092 -246.380435) (xy 355.787471 -246.355828) (xy 355.74935 -246.324703) (xy 355.716715 -246.287866)
			(xy 355.690412 -246.24627) (xy 355.671121 -246.200994) (xy 355.659344 -246.15321) (xy 355.655384 -246.104156)
			(xy 355.326442 -246.104156) (xy 355.325947 -246.128763) (xy 355.318052 -246.17734) (xy 355.302468 -246.224021)
			(xy 355.279597 -246.267598) (xy 355.250032 -246.306942) (xy 355.214539 -246.341034) (xy 355.174036 -246.36899)
			(xy 355.129574 -246.390088) (xy 355.082303 -246.40378) (xy 355.033448 -246.409712) (xy 354.984273 -246.407731)
			(xy 354.936054 -246.397887) (xy 354.890038 -246.380435) (xy 354.847417 -246.355828) (xy 354.809296 -246.324703)
			(xy 354.776661 -246.287866) (xy 354.750358 -246.24627) (xy 354.731067 -246.200994) (xy 354.71929 -246.15321)
			(xy 354.71533 -246.104156) (xy 354.386388 -246.104156) (xy 354.385893 -246.128763) (xy 354.377998 -246.17734)
			(xy 354.362414 -246.224021) (xy 354.339543 -246.267598) (xy 354.309978 -246.306942) (xy 354.274485 -246.341034)
			(xy 354.233982 -246.36899) (xy 354.18952 -246.390088) (xy 354.142249 -246.40378) (xy 354.093394 -246.409712)
			(xy 354.044219 -246.407731) (xy 353.996 -246.397887) (xy 353.949984 -246.380435) (xy 353.907363 -246.355828)
			(xy 353.869242 -246.324703) (xy 353.836607 -246.287866) (xy 353.810304 -246.24627) (xy 353.791013 -246.200994)
			(xy 353.779236 -246.15321) (xy 353.775276 -246.104156) (xy 353.446334 -246.104156) (xy 353.445839 -246.128763)
			(xy 353.437944 -246.17734) (xy 353.42236 -246.224021) (xy 353.399489 -246.267598) (xy 353.369924 -246.306942)
			(xy 353.334431 -246.341034) (xy 353.293928 -246.36899) (xy 353.249466 -246.390088) (xy 353.202195 -246.40378)
			(xy 353.15334 -246.409712) (xy 353.104165 -246.407731) (xy 353.055946 -246.397887) (xy 353.00993 -246.380435)
			(xy 352.967309 -246.355828) (xy 352.929188 -246.324703) (xy 352.896553 -246.287866) (xy 352.87025 -246.24627)
			(xy 352.850959 -246.200994) (xy 352.839182 -246.15321) (xy 352.835222 -246.104156) (xy 352.506534 -246.104156)
			(xy 352.506039 -246.128763) (xy 352.498144 -246.17734) (xy 352.48256 -246.224021) (xy 352.459689 -246.267598)
			(xy 352.430124 -246.306942) (xy 352.394631 -246.341034) (xy 352.354128 -246.36899) (xy 352.309666 -246.390088)
			(xy 352.262395 -246.40378) (xy 352.21354 -246.409712) (xy 352.164365 -246.407731) (xy 352.116146 -246.397887)
			(xy 352.07013 -246.380435) (xy 352.027509 -246.355828) (xy 351.989388 -246.324703) (xy 351.956753 -246.287866)
			(xy 351.93045 -246.24627) (xy 351.911159 -246.200994) (xy 351.899382 -246.15321) (xy 351.895422 -246.104156)
			(xy 351.56648 -246.104156) (xy 351.565985 -246.128763) (xy 351.55809 -246.17734) (xy 351.542506 -246.224021)
			(xy 351.519635 -246.267598) (xy 351.49007 -246.306942) (xy 351.454577 -246.341034) (xy 351.414074 -246.36899)
			(xy 351.369612 -246.390088) (xy 351.322341 -246.40378) (xy 351.273486 -246.409712) (xy 351.224311 -246.407731)
			(xy 351.176092 -246.397887) (xy 351.130076 -246.380435) (xy 351.087455 -246.355828) (xy 351.049334 -246.324703)
			(xy 351.016699 -246.287866) (xy 350.990396 -246.24627) (xy 350.971105 -246.200994) (xy 350.959328 -246.15321)
			(xy 350.955368 -246.104156) (xy 350.626426 -246.104156) (xy 350.625931 -246.128763) (xy 350.618036 -246.17734)
			(xy 350.602452 -246.224021) (xy 350.579581 -246.267598) (xy 350.550016 -246.306942) (xy 350.514523 -246.341034)
			(xy 350.47402 -246.36899) (xy 350.429558 -246.390088) (xy 350.382287 -246.40378) (xy 350.333432 -246.409712)
			(xy 350.284257 -246.407731) (xy 350.236038 -246.397887) (xy 350.190022 -246.380435) (xy 350.147401 -246.355828)
			(xy 350.10928 -246.324703) (xy 350.076645 -246.287866) (xy 350.050342 -246.24627) (xy 350.031051 -246.200994)
			(xy 350.019274 -246.15321) (xy 350.015314 -246.104156) (xy 349.686372 -246.104156) (xy 349.685877 -246.128763)
			(xy 349.677982 -246.17734) (xy 349.662398 -246.224021) (xy 349.639527 -246.267598) (xy 349.609962 -246.306942)
			(xy 349.574469 -246.341034) (xy 349.533966 -246.36899) (xy 349.489504 -246.390088) (xy 349.442233 -246.40378)
			(xy 349.393378 -246.409712) (xy 349.344203 -246.407731) (xy 349.295984 -246.397887) (xy 349.249968 -246.380435)
			(xy 349.207347 -246.355828) (xy 349.169226 -246.324703) (xy 349.136591 -246.287866) (xy 349.110288 -246.24627)
			(xy 349.090997 -246.200994) (xy 349.07922 -246.15321) (xy 349.07526 -246.104156) (xy 348.746318 -246.104156)
			(xy 348.745823 -246.128763) (xy 348.737928 -246.17734) (xy 348.722344 -246.224021) (xy 348.699473 -246.267598)
			(xy 348.669908 -246.306942) (xy 348.634415 -246.341034) (xy 348.593912 -246.36899) (xy 348.54945 -246.390088)
			(xy 348.502179 -246.40378) (xy 348.453324 -246.409712) (xy 348.404149 -246.407731) (xy 348.35593 -246.397887)
			(xy 348.309914 -246.380435) (xy 348.267293 -246.355828) (xy 348.229172 -246.324703) (xy 348.196537 -246.287866)
			(xy 348.170234 -246.24627) (xy 348.150943 -246.200994) (xy 348.139166 -246.15321) (xy 348.135206 -246.104156)
			(xy 347.806518 -246.104156) (xy 347.806023 -246.128763) (xy 347.798128 -246.17734) (xy 347.782544 -246.224021)
			(xy 347.759673 -246.267598) (xy 347.730108 -246.306942) (xy 347.694615 -246.341034) (xy 347.654112 -246.36899)
			(xy 347.60965 -246.390088) (xy 347.562379 -246.40378) (xy 347.513524 -246.409712) (xy 347.464349 -246.407731)
			(xy 347.41613 -246.397887) (xy 347.370114 -246.380435) (xy 347.327493 -246.355828) (xy 347.289372 -246.324703)
			(xy 347.256737 -246.287866) (xy 347.230434 -246.24627) (xy 347.211143 -246.200994) (xy 347.199366 -246.15321)
			(xy 347.195406 -246.104156) (xy 346.866464 -246.104156) (xy 346.865969 -246.128763) (xy 346.858074 -246.17734)
			(xy 346.84249 -246.224021) (xy 346.819619 -246.267598) (xy 346.790054 -246.306942) (xy 346.754561 -246.341034)
			(xy 346.714058 -246.36899) (xy 346.669596 -246.390088) (xy 346.622325 -246.40378) (xy 346.57347 -246.409712)
			(xy 346.524295 -246.407731) (xy 346.476076 -246.397887) (xy 346.43006 -246.380435) (xy 346.387439 -246.355828)
			(xy 346.349318 -246.324703) (xy 346.316683 -246.287866) (xy 346.29038 -246.24627) (xy 346.271089 -246.200994)
			(xy 346.259312 -246.15321) (xy 346.255352 -246.104156) (xy 345.92641 -246.104156) (xy 345.925915 -246.128763)
			(xy 345.91802 -246.17734) (xy 345.902436 -246.224021) (xy 345.879565 -246.267598) (xy 345.85 -246.306942)
			(xy 345.814507 -246.341034) (xy 345.774004 -246.36899) (xy 345.729542 -246.390088) (xy 345.682271 -246.40378)
			(xy 345.633416 -246.409712) (xy 345.584241 -246.407731) (xy 345.536022 -246.397887) (xy 345.490006 -246.380435)
			(xy 345.447385 -246.355828) (xy 345.409264 -246.324703) (xy 345.376629 -246.287866) (xy 345.350326 -246.24627)
			(xy 345.331035 -246.200994) (xy 345.319258 -246.15321) (xy 345.315298 -246.104156) (xy 344.985829 -246.104156)
			(xy 344.98583 -246.128689) (xy 344.97801 -246.177065) (xy 344.962568 -246.223572) (xy 344.939901 -246.267018)
			(xy 344.910589 -246.306288) (xy 344.875385 -246.340377) (xy 344.835191 -246.368409) (xy 344.791038 -246.389665)
			(xy 344.767662 -246.397018) (xy 344.751406 -246.401844) (xy 344.73134 -246.428514) (xy 344.73134 -246.914162)
			(xy 344.845398 -246.914162) (xy 344.849358 -246.865108) (xy 344.861135 -246.817324) (xy 344.880426 -246.772048)
			(xy 344.906729 -246.730452) (xy 344.939364 -246.693615) (xy 344.977485 -246.66249) (xy 345.020106 -246.637883)
			(xy 345.066122 -246.620431) (xy 345.114341 -246.610587) (xy 345.163516 -246.608606) (xy 345.212371 -246.614538)
			(xy 345.259642 -246.62823) (xy 345.304104 -246.649328) (xy 345.344607 -246.677284) (xy 345.3801 -246.711376)
			(xy 345.409665 -246.75072) (xy 345.432536 -246.794297) (xy 345.44812 -246.840978) (xy 345.456015 -246.889555)
			(xy 345.45651 -246.914162) (xy 345.785198 -246.914162) (xy 345.789158 -246.865108) (xy 345.800935 -246.817324)
			(xy 345.820226 -246.772048) (xy 345.846529 -246.730452) (xy 345.879164 -246.693615) (xy 345.917285 -246.66249)
			(xy 345.959906 -246.637883) (xy 346.005922 -246.620431) (xy 346.054141 -246.610587) (xy 346.103316 -246.608606)
			(xy 346.152171 -246.614538) (xy 346.199442 -246.62823) (xy 346.243904 -246.649328) (xy 346.284407 -246.677284)
			(xy 346.3199 -246.711376) (xy 346.349465 -246.75072) (xy 346.372336 -246.794297) (xy 346.38792 -246.840978)
			(xy 346.395815 -246.889555) (xy 346.39631 -246.914162) (xy 346.725252 -246.914162) (xy 346.729212 -246.865108)
			(xy 346.740989 -246.817324) (xy 346.76028 -246.772048) (xy 346.786583 -246.730452) (xy 346.819218 -246.693615)
			(xy 346.857339 -246.66249) (xy 346.89996 -246.637883) (xy 346.945976 -246.620431) (xy 346.994195 -246.610587)
			(xy 347.04337 -246.608606) (xy 347.092225 -246.614538) (xy 347.139496 -246.62823) (xy 347.183958 -246.649328)
			(xy 347.224461 -246.677284) (xy 347.259954 -246.711376) (xy 347.289519 -246.75072) (xy 347.31239 -246.794297)
			(xy 347.327974 -246.840978) (xy 347.335869 -246.889555) (xy 347.336364 -246.914162) (xy 347.665306 -246.914162)
			(xy 347.669266 -246.865108) (xy 347.681043 -246.817324) (xy 347.700334 -246.772048) (xy 347.726637 -246.730452)
			(xy 347.759272 -246.693615) (xy 347.797393 -246.66249) (xy 347.840014 -246.637883) (xy 347.88603 -246.620431)
			(xy 347.934249 -246.610587) (xy 347.983424 -246.608606) (xy 348.032279 -246.614538) (xy 348.07955 -246.62823)
			(xy 348.124012 -246.649328) (xy 348.164515 -246.677284) (xy 348.200008 -246.711376) (xy 348.229573 -246.75072)
			(xy 348.252444 -246.794297) (xy 348.268028 -246.840978) (xy 348.275923 -246.889555) (xy 348.276418 -246.914162)
			(xy 348.60536 -246.914162) (xy 348.60932 -246.865108) (xy 348.621097 -246.817324) (xy 348.640388 -246.772048)
			(xy 348.666691 -246.730452) (xy 348.699326 -246.693615) (xy 348.737447 -246.66249) (xy 348.780068 -246.637883)
			(xy 348.826084 -246.620431) (xy 348.874303 -246.610587) (xy 348.923478 -246.608606) (xy 348.972333 -246.614538)
			(xy 349.019604 -246.62823) (xy 349.064066 -246.649328) (xy 349.104569 -246.677284) (xy 349.140062 -246.711376)
			(xy 349.169627 -246.75072) (xy 349.192498 -246.794297) (xy 349.208082 -246.840978) (xy 349.215977 -246.889555)
			(xy 349.216472 -246.914162) (xy 349.545414 -246.914162) (xy 349.549374 -246.865108) (xy 349.561151 -246.817324)
			(xy 349.580442 -246.772048) (xy 349.606745 -246.730452) (xy 349.63938 -246.693615) (xy 349.677501 -246.66249)
			(xy 349.720122 -246.637883) (xy 349.766138 -246.620431) (xy 349.814357 -246.610587) (xy 349.863532 -246.608606)
			(xy 349.912387 -246.614538) (xy 349.959658 -246.62823) (xy 350.00412 -246.649328) (xy 350.044623 -246.677284)
			(xy 350.080116 -246.711376) (xy 350.109681 -246.75072) (xy 350.132552 -246.794297) (xy 350.148136 -246.840978)
			(xy 350.156031 -246.889555) (xy 350.156526 -246.914162) (xy 350.485214 -246.914162) (xy 350.489174 -246.865108)
			(xy 350.500951 -246.817324) (xy 350.520242 -246.772048) (xy 350.546545 -246.730452) (xy 350.57918 -246.693615)
			(xy 350.617301 -246.66249) (xy 350.659922 -246.637883) (xy 350.705938 -246.620431) (xy 350.754157 -246.610587)
			(xy 350.803332 -246.608606) (xy 350.852187 -246.614538) (xy 350.899458 -246.62823) (xy 350.94392 -246.649328)
			(xy 350.984423 -246.677284) (xy 351.019916 -246.711376) (xy 351.049481 -246.75072) (xy 351.072352 -246.794297)
			(xy 351.087936 -246.840978) (xy 351.095831 -246.889555) (xy 351.096326 -246.914162) (xy 351.425268 -246.914162)
			(xy 351.429228 -246.865108) (xy 351.441005 -246.817324) (xy 351.460296 -246.772048) (xy 351.486599 -246.730452)
			(xy 351.519234 -246.693615) (xy 351.557355 -246.66249) (xy 351.599976 -246.637883) (xy 351.645992 -246.620431)
			(xy 351.694211 -246.610587) (xy 351.743386 -246.608606) (xy 351.792241 -246.614538) (xy 351.839512 -246.62823)
			(xy 351.883974 -246.649328) (xy 351.924477 -246.677284) (xy 351.95997 -246.711376) (xy 351.989535 -246.75072)
			(xy 352.012406 -246.794297) (xy 352.02799 -246.840978) (xy 352.035885 -246.889555) (xy 352.03638 -246.914162)
			(xy 352.365322 -246.914162) (xy 352.369282 -246.865108) (xy 352.381059 -246.817324) (xy 352.40035 -246.772048)
			(xy 352.426653 -246.730452) (xy 352.459288 -246.693615) (xy 352.497409 -246.66249) (xy 352.54003 -246.637883)
			(xy 352.586046 -246.620431) (xy 352.634265 -246.610587) (xy 352.68344 -246.608606) (xy 352.732295 -246.614538)
			(xy 352.779566 -246.62823) (xy 352.824028 -246.649328) (xy 352.864531 -246.677284) (xy 352.900024 -246.711376)
			(xy 352.929589 -246.75072) (xy 352.95246 -246.794297) (xy 352.968044 -246.840978) (xy 352.975939 -246.889555)
			(xy 352.976434 -246.914162) (xy 353.305376 -246.914162) (xy 353.309336 -246.865108) (xy 353.321113 -246.817324)
			(xy 353.340404 -246.772048) (xy 353.366707 -246.730452) (xy 353.399342 -246.693615) (xy 353.437463 -246.66249)
			(xy 353.480084 -246.637883) (xy 353.5261 -246.620431) (xy 353.574319 -246.610587) (xy 353.623494 -246.608606)
			(xy 353.672349 -246.614538) (xy 353.71962 -246.62823) (xy 353.764082 -246.649328) (xy 353.804585 -246.677284)
			(xy 353.840078 -246.711376) (xy 353.869643 -246.75072) (xy 353.892514 -246.794297) (xy 353.908098 -246.840978)
			(xy 353.915993 -246.889555) (xy 353.916488 -246.914162) (xy 354.24543 -246.914162) (xy 354.24939 -246.865108)
			(xy 354.261167 -246.817324) (xy 354.280458 -246.772048) (xy 354.306761 -246.730452) (xy 354.339396 -246.693615)
			(xy 354.377517 -246.66249) (xy 354.420138 -246.637883) (xy 354.466154 -246.620431) (xy 354.514373 -246.610587)
			(xy 354.563548 -246.608606) (xy 354.612403 -246.614538) (xy 354.659674 -246.62823) (xy 354.704136 -246.649328)
			(xy 354.744639 -246.677284) (xy 354.780132 -246.711376) (xy 354.809697 -246.75072) (xy 354.832568 -246.794297)
			(xy 354.848152 -246.840978) (xy 354.856047 -246.889555) (xy 354.856542 -246.914162) (xy 355.18523 -246.914162)
			(xy 355.18919 -246.865108) (xy 355.200967 -246.817324) (xy 355.220258 -246.772048) (xy 355.246561 -246.730452)
			(xy 355.279196 -246.693615) (xy 355.317317 -246.66249) (xy 355.359938 -246.637883) (xy 355.405954 -246.620431)
			(xy 355.454173 -246.610587) (xy 355.503348 -246.608606) (xy 355.552203 -246.614538) (xy 355.599474 -246.62823)
			(xy 355.643936 -246.649328) (xy 355.684439 -246.677284) (xy 355.719932 -246.711376) (xy 355.749497 -246.75072)
			(xy 355.772368 -246.794297) (xy 355.787952 -246.840978) (xy 355.795847 -246.889555) (xy 355.796342 -246.914162)
			(xy 356.125284 -246.914162) (xy 356.129244 -246.865108) (xy 356.141021 -246.817324) (xy 356.160312 -246.772048)
			(xy 356.186615 -246.730452) (xy 356.21925 -246.693615) (xy 356.257371 -246.66249) (xy 356.299992 -246.637883)
			(xy 356.346008 -246.620431) (xy 356.394227 -246.610587) (xy 356.443402 -246.608606) (xy 356.492257 -246.614538)
			(xy 356.539528 -246.62823) (xy 356.58399 -246.649328) (xy 356.624493 -246.677284) (xy 356.659986 -246.711376)
			(xy 356.689551 -246.75072) (xy 356.712422 -246.794297) (xy 356.728006 -246.840978) (xy 356.735901 -246.889555)
			(xy 356.736396 -246.914162) (xy 357.065338 -246.914162) (xy 357.069298 -246.865108) (xy 357.081075 -246.817324)
			(xy 357.100366 -246.772048) (xy 357.126669 -246.730452) (xy 357.159304 -246.693615) (xy 357.197425 -246.66249)
			(xy 357.240046 -246.637883) (xy 357.286062 -246.620431) (xy 357.334281 -246.610587) (xy 357.383456 -246.608606)
			(xy 357.432311 -246.614538) (xy 357.479582 -246.62823) (xy 357.524044 -246.649328) (xy 357.564547 -246.677284)
			(xy 357.60004 -246.711376) (xy 357.629605 -246.75072) (xy 357.652476 -246.794297) (xy 357.66806 -246.840978)
			(xy 357.675955 -246.889555) (xy 357.67645 -246.914162) (xy 358.005392 -246.914162) (xy 358.009352 -246.865108)
			(xy 358.021129 -246.817324) (xy 358.04042 -246.772048) (xy 358.066723 -246.730452) (xy 358.099358 -246.693615)
			(xy 358.137479 -246.66249) (xy 358.1801 -246.637883) (xy 358.226116 -246.620431) (xy 358.274335 -246.610587)
			(xy 358.32351 -246.608606) (xy 358.372365 -246.614538) (xy 358.419636 -246.62823) (xy 358.464098 -246.649328)
			(xy 358.504601 -246.677284) (xy 358.540094 -246.711376) (xy 358.569659 -246.75072) (xy 358.59253 -246.794297)
			(xy 358.608114 -246.840978) (xy 358.616009 -246.889555) (xy 358.616504 -246.914162) (xy 358.616009 -246.938769)
			(xy 358.608114 -246.987346) (xy 358.59253 -247.034027) (xy 358.569659 -247.077604) (xy 358.540094 -247.116948)
			(xy 358.504601 -247.15104) (xy 358.464098 -247.178996) (xy 358.419636 -247.200094) (xy 358.372365 -247.213786)
			(xy 358.32351 -247.219718) (xy 358.274335 -247.217737) (xy 358.226116 -247.207893) (xy 358.1801 -247.190441)
			(xy 358.137479 -247.165834) (xy 358.099358 -247.134709) (xy 358.066723 -247.097872) (xy 358.04042 -247.056276)
			(xy 358.021129 -247.011) (xy 358.009352 -246.963216) (xy 358.005392 -246.914162) (xy 357.67645 -246.914162)
			(xy 357.675955 -246.938769) (xy 357.66806 -246.987346) (xy 357.652476 -247.034027) (xy 357.629605 -247.077604)
			(xy 357.60004 -247.116948) (xy 357.564547 -247.15104) (xy 357.524044 -247.178996) (xy 357.479582 -247.200094)
			(xy 357.432311 -247.213786) (xy 357.383456 -247.219718) (xy 357.334281 -247.217737) (xy 357.286062 -247.207893)
			(xy 357.240046 -247.190441) (xy 357.197425 -247.165834) (xy 357.159304 -247.134709) (xy 357.126669 -247.097872)
			(xy 357.100366 -247.056276) (xy 357.081075 -247.011) (xy 357.069298 -246.963216) (xy 357.065338 -246.914162)
			(xy 356.736396 -246.914162) (xy 356.735901 -246.938769) (xy 356.728006 -246.987346) (xy 356.712422 -247.034027)
			(xy 356.689551 -247.077604) (xy 356.659986 -247.116948) (xy 356.624493 -247.15104) (xy 356.58399 -247.178996)
			(xy 356.539528 -247.200094) (xy 356.492257 -247.213786) (xy 356.443402 -247.219718) (xy 356.394227 -247.217737)
			(xy 356.346008 -247.207893) (xy 356.299992 -247.190441) (xy 356.257371 -247.165834) (xy 356.21925 -247.134709)
			(xy 356.186615 -247.097872) (xy 356.160312 -247.056276) (xy 356.141021 -247.011) (xy 356.129244 -246.963216)
			(xy 356.125284 -246.914162) (xy 355.796342 -246.914162) (xy 355.795847 -246.938769) (xy 355.787952 -246.987346)
			(xy 355.772368 -247.034027) (xy 355.749497 -247.077604) (xy 355.719932 -247.116948) (xy 355.684439 -247.15104)
			(xy 355.643936 -247.178996) (xy 355.599474 -247.200094) (xy 355.552203 -247.213786) (xy 355.503348 -247.219718)
			(xy 355.454173 -247.217737) (xy 355.405954 -247.207893) (xy 355.359938 -247.190441) (xy 355.317317 -247.165834)
			(xy 355.279196 -247.134709) (xy 355.246561 -247.097872) (xy 355.220258 -247.056276) (xy 355.200967 -247.011)
			(xy 355.18919 -246.963216) (xy 355.18523 -246.914162) (xy 354.856542 -246.914162) (xy 354.856047 -246.938769)
			(xy 354.848152 -246.987346) (xy 354.832568 -247.034027) (xy 354.809697 -247.077604) (xy 354.780132 -247.116948)
			(xy 354.744639 -247.15104) (xy 354.704136 -247.178996) (xy 354.659674 -247.200094) (xy 354.612403 -247.213786)
			(xy 354.563548 -247.219718) (xy 354.514373 -247.217737) (xy 354.466154 -247.207893) (xy 354.420138 -247.190441)
			(xy 354.377517 -247.165834) (xy 354.339396 -247.134709) (xy 354.306761 -247.097872) (xy 354.280458 -247.056276)
			(xy 354.261167 -247.011) (xy 354.24939 -246.963216) (xy 354.24543 -246.914162) (xy 353.916488 -246.914162)
			(xy 353.915993 -246.938769) (xy 353.908098 -246.987346) (xy 353.892514 -247.034027) (xy 353.869643 -247.077604)
			(xy 353.840078 -247.116948) (xy 353.804585 -247.15104) (xy 353.764082 -247.178996) (xy 353.71962 -247.200094)
			(xy 353.672349 -247.213786) (xy 353.623494 -247.219718) (xy 353.574319 -247.217737) (xy 353.5261 -247.207893)
			(xy 353.480084 -247.190441) (xy 353.437463 -247.165834) (xy 353.399342 -247.134709) (xy 353.366707 -247.097872)
			(xy 353.340404 -247.056276) (xy 353.321113 -247.011) (xy 353.309336 -246.963216) (xy 353.305376 -246.914162)
			(xy 352.976434 -246.914162) (xy 352.975939 -246.938769) (xy 352.968044 -246.987346) (xy 352.95246 -247.034027)
			(xy 352.929589 -247.077604) (xy 352.900024 -247.116948) (xy 352.864531 -247.15104) (xy 352.824028 -247.178996)
			(xy 352.779566 -247.200094) (xy 352.732295 -247.213786) (xy 352.68344 -247.219718) (xy 352.634265 -247.217737)
			(xy 352.586046 -247.207893) (xy 352.54003 -247.190441) (xy 352.497409 -247.165834) (xy 352.459288 -247.134709)
			(xy 352.426653 -247.097872) (xy 352.40035 -247.056276) (xy 352.381059 -247.011) (xy 352.369282 -246.963216)
			(xy 352.365322 -246.914162) (xy 352.03638 -246.914162) (xy 352.035885 -246.938769) (xy 352.02799 -246.987346)
			(xy 352.012406 -247.034027) (xy 351.989535 -247.077604) (xy 351.95997 -247.116948) (xy 351.924477 -247.15104)
			(xy 351.883974 -247.178996) (xy 351.839512 -247.200094) (xy 351.792241 -247.213786) (xy 351.743386 -247.219718)
			(xy 351.694211 -247.217737) (xy 351.645992 -247.207893) (xy 351.599976 -247.190441) (xy 351.557355 -247.165834)
			(xy 351.519234 -247.134709) (xy 351.486599 -247.097872) (xy 351.460296 -247.056276) (xy 351.441005 -247.011)
			(xy 351.429228 -246.963216) (xy 351.425268 -246.914162) (xy 351.096326 -246.914162) (xy 351.095831 -246.938769)
			(xy 351.087936 -246.987346) (xy 351.072352 -247.034027) (xy 351.049481 -247.077604) (xy 351.019916 -247.116948)
			(xy 350.984423 -247.15104) (xy 350.94392 -247.178996) (xy 350.899458 -247.200094) (xy 350.852187 -247.213786)
			(xy 350.803332 -247.219718) (xy 350.754157 -247.217737) (xy 350.705938 -247.207893) (xy 350.659922 -247.190441)
			(xy 350.617301 -247.165834) (xy 350.57918 -247.134709) (xy 350.546545 -247.097872) (xy 350.520242 -247.056276)
			(xy 350.500951 -247.011) (xy 350.489174 -246.963216) (xy 350.485214 -246.914162) (xy 350.156526 -246.914162)
			(xy 350.156031 -246.938769) (xy 350.148136 -246.987346) (xy 350.132552 -247.034027) (xy 350.109681 -247.077604)
			(xy 350.080116 -247.116948) (xy 350.044623 -247.15104) (xy 350.00412 -247.178996) (xy 349.959658 -247.200094)
			(xy 349.912387 -247.213786) (xy 349.863532 -247.219718) (xy 349.814357 -247.217737) (xy 349.766138 -247.207893)
			(xy 349.720122 -247.190441) (xy 349.677501 -247.165834) (xy 349.63938 -247.134709) (xy 349.606745 -247.097872)
			(xy 349.580442 -247.056276) (xy 349.561151 -247.011) (xy 349.549374 -246.963216) (xy 349.545414 -246.914162)
			(xy 349.216472 -246.914162) (xy 349.215977 -246.938769) (xy 349.208082 -246.987346) (xy 349.192498 -247.034027)
			(xy 349.169627 -247.077604) (xy 349.140062 -247.116948) (xy 349.104569 -247.15104) (xy 349.064066 -247.178996)
			(xy 349.019604 -247.200094) (xy 348.972333 -247.213786) (xy 348.923478 -247.219718) (xy 348.874303 -247.217737)
			(xy 348.826084 -247.207893) (xy 348.780068 -247.190441) (xy 348.737447 -247.165834) (xy 348.699326 -247.134709)
			(xy 348.666691 -247.097872) (xy 348.640388 -247.056276) (xy 348.621097 -247.011) (xy 348.60932 -246.963216)
			(xy 348.60536 -246.914162) (xy 348.276418 -246.914162) (xy 348.275923 -246.938769) (xy 348.268028 -246.987346)
			(xy 348.252444 -247.034027) (xy 348.229573 -247.077604) (xy 348.200008 -247.116948) (xy 348.164515 -247.15104)
			(xy 348.124012 -247.178996) (xy 348.07955 -247.200094) (xy 348.032279 -247.213786) (xy 347.983424 -247.219718)
			(xy 347.934249 -247.217737) (xy 347.88603 -247.207893) (xy 347.840014 -247.190441) (xy 347.797393 -247.165834)
			(xy 347.759272 -247.134709) (xy 347.726637 -247.097872) (xy 347.700334 -247.056276) (xy 347.681043 -247.011)
			(xy 347.669266 -246.963216) (xy 347.665306 -246.914162) (xy 347.336364 -246.914162) (xy 347.335869 -246.938769)
			(xy 347.327974 -246.987346) (xy 347.31239 -247.034027) (xy 347.289519 -247.077604) (xy 347.259954 -247.116948)
			(xy 347.224461 -247.15104) (xy 347.183958 -247.178996) (xy 347.139496 -247.200094) (xy 347.092225 -247.213786)
			(xy 347.04337 -247.219718) (xy 346.994195 -247.217737) (xy 346.945976 -247.207893) (xy 346.89996 -247.190441)
			(xy 346.857339 -247.165834) (xy 346.819218 -247.134709) (xy 346.786583 -247.097872) (xy 346.76028 -247.056276)
			(xy 346.740989 -247.011) (xy 346.729212 -246.963216) (xy 346.725252 -246.914162) (xy 346.39631 -246.914162)
			(xy 346.395815 -246.938769) (xy 346.38792 -246.987346) (xy 346.372336 -247.034027) (xy 346.349465 -247.077604)
			(xy 346.3199 -247.116948) (xy 346.284407 -247.15104) (xy 346.243904 -247.178996) (xy 346.199442 -247.200094)
			(xy 346.152171 -247.213786) (xy 346.103316 -247.219718) (xy 346.054141 -247.217737) (xy 346.005922 -247.207893)
			(xy 345.959906 -247.190441) (xy 345.917285 -247.165834) (xy 345.879164 -247.134709) (xy 345.846529 -247.097872)
			(xy 345.820226 -247.056276) (xy 345.800935 -247.011) (xy 345.789158 -246.963216) (xy 345.785198 -246.914162)
			(xy 345.45651 -246.914162) (xy 345.456015 -246.938769) (xy 345.44812 -246.987346) (xy 345.432536 -247.034027)
			(xy 345.409665 -247.077604) (xy 345.3801 -247.116948) (xy 345.344607 -247.15104) (xy 345.304104 -247.178996)
			(xy 345.259642 -247.200094) (xy 345.212371 -247.213786) (xy 345.163516 -247.219718) (xy 345.114341 -247.217737)
			(xy 345.066122 -247.207893) (xy 345.020106 -247.190441) (xy 344.977485 -247.165834) (xy 344.939364 -247.134709)
			(xy 344.906729 -247.097872) (xy 344.880426 -247.056276) (xy 344.861135 -247.011) (xy 344.849358 -246.963216)
			(xy 344.845398 -246.914162) (xy 344.73134 -246.914162) (xy 344.73134 -247.39981) (xy 344.751406 -247.42648)
			(xy 344.767662 -247.431306) (xy 344.791014 -247.438738) (xy 344.835167 -247.45999) (xy 344.875361 -247.488018)
			(xy 344.910566 -247.522103) (xy 344.93988 -247.56137) (xy 344.962549 -247.604813) (xy 344.977993 -247.651317)
			(xy 344.985817 -247.69969) (xy 344.985817 -247.724168) (xy 345.315298 -247.724168) (xy 345.319258 -247.675114)
			(xy 345.331035 -247.62733) (xy 345.350326 -247.582054) (xy 345.376629 -247.540458) (xy 345.409264 -247.503621)
			(xy 345.447385 -247.472496) (xy 345.490006 -247.447889) (xy 345.536022 -247.430437) (xy 345.584241 -247.420593)
			(xy 345.633416 -247.418612) (xy 345.682271 -247.424544) (xy 345.729542 -247.438236) (xy 345.774004 -247.459334)
			(xy 345.814507 -247.48729) (xy 345.85 -247.521382) (xy 345.879565 -247.560726) (xy 345.902436 -247.604303)
			(xy 345.91802 -247.650984) (xy 345.925915 -247.699561) (xy 345.92641 -247.724168) (xy 346.255352 -247.724168)
			(xy 346.259312 -247.675114) (xy 346.271089 -247.62733) (xy 346.29038 -247.582054) (xy 346.316683 -247.540458)
			(xy 346.349318 -247.503621) (xy 346.387439 -247.472496) (xy 346.43006 -247.447889) (xy 346.476076 -247.430437)
			(xy 346.524295 -247.420593) (xy 346.57347 -247.418612) (xy 346.622325 -247.424544) (xy 346.669596 -247.438236)
			(xy 346.714058 -247.459334) (xy 346.754561 -247.48729) (xy 346.790054 -247.521382) (xy 346.819619 -247.560726)
			(xy 346.84249 -247.604303) (xy 346.858074 -247.650984) (xy 346.865969 -247.699561) (xy 346.866464 -247.724168)
			(xy 347.195406 -247.724168) (xy 347.199366 -247.675114) (xy 347.211143 -247.62733) (xy 347.230434 -247.582054)
			(xy 347.256737 -247.540458) (xy 347.289372 -247.503621) (xy 347.327493 -247.472496) (xy 347.370114 -247.447889)
			(xy 347.41613 -247.430437) (xy 347.464349 -247.420593) (xy 347.513524 -247.418612) (xy 347.562379 -247.424544)
			(xy 347.60965 -247.438236) (xy 347.654112 -247.459334) (xy 347.694615 -247.48729) (xy 347.730108 -247.521382)
			(xy 347.759673 -247.560726) (xy 347.782544 -247.604303) (xy 347.798128 -247.650984) (xy 347.806023 -247.699561)
			(xy 347.806518 -247.724168) (xy 348.135206 -247.724168) (xy 348.139166 -247.675114) (xy 348.150943 -247.62733)
			(xy 348.170234 -247.582054) (xy 348.196537 -247.540458) (xy 348.229172 -247.503621) (xy 348.267293 -247.472496)
			(xy 348.309914 -247.447889) (xy 348.35593 -247.430437) (xy 348.404149 -247.420593) (xy 348.453324 -247.418612)
			(xy 348.502179 -247.424544) (xy 348.54945 -247.438236) (xy 348.593912 -247.459334) (xy 348.634415 -247.48729)
			(xy 348.669908 -247.521382) (xy 348.699473 -247.560726) (xy 348.722344 -247.604303) (xy 348.737928 -247.650984)
			(xy 348.745823 -247.699561) (xy 348.746318 -247.724168) (xy 349.07526 -247.724168) (xy 349.07922 -247.675114)
			(xy 349.090997 -247.62733) (xy 349.110288 -247.582054) (xy 349.136591 -247.540458) (xy 349.169226 -247.503621)
			(xy 349.207347 -247.472496) (xy 349.249968 -247.447889) (xy 349.295984 -247.430437) (xy 349.344203 -247.420593)
			(xy 349.393378 -247.418612) (xy 349.442233 -247.424544) (xy 349.489504 -247.438236) (xy 349.533966 -247.459334)
			(xy 349.574469 -247.48729) (xy 349.609962 -247.521382) (xy 349.639527 -247.560726) (xy 349.662398 -247.604303)
			(xy 349.677982 -247.650984) (xy 349.685877 -247.699561) (xy 349.686372 -247.724168) (xy 350.015314 -247.724168)
			(xy 350.019274 -247.675114) (xy 350.031051 -247.62733) (xy 350.050342 -247.582054) (xy 350.076645 -247.540458)
			(xy 350.10928 -247.503621) (xy 350.147401 -247.472496) (xy 350.190022 -247.447889) (xy 350.236038 -247.430437)
			(xy 350.284257 -247.420593) (xy 350.333432 -247.418612) (xy 350.382287 -247.424544) (xy 350.429558 -247.438236)
			(xy 350.47402 -247.459334) (xy 350.514523 -247.48729) (xy 350.550016 -247.521382) (xy 350.579581 -247.560726)
			(xy 350.602452 -247.604303) (xy 350.618036 -247.650984) (xy 350.625931 -247.699561) (xy 350.626426 -247.724168)
			(xy 350.955368 -247.724168) (xy 350.959328 -247.675114) (xy 350.971105 -247.62733) (xy 350.990396 -247.582054)
			(xy 351.016699 -247.540458) (xy 351.049334 -247.503621) (xy 351.087455 -247.472496) (xy 351.130076 -247.447889)
			(xy 351.176092 -247.430437) (xy 351.224311 -247.420593) (xy 351.273486 -247.418612) (xy 351.322341 -247.424544)
			(xy 351.369612 -247.438236) (xy 351.414074 -247.459334) (xy 351.454577 -247.48729) (xy 351.49007 -247.521382)
			(xy 351.519635 -247.560726) (xy 351.542506 -247.604303) (xy 351.55809 -247.650984) (xy 351.565985 -247.699561)
			(xy 351.56648 -247.724168) (xy 351.895422 -247.724168) (xy 351.899382 -247.675114) (xy 351.911159 -247.62733)
			(xy 351.93045 -247.582054) (xy 351.956753 -247.540458) (xy 351.989388 -247.503621) (xy 352.027509 -247.472496)
			(xy 352.07013 -247.447889) (xy 352.116146 -247.430437) (xy 352.164365 -247.420593) (xy 352.21354 -247.418612)
			(xy 352.262395 -247.424544) (xy 352.309666 -247.438236) (xy 352.354128 -247.459334) (xy 352.394631 -247.48729)
			(xy 352.430124 -247.521382) (xy 352.459689 -247.560726) (xy 352.48256 -247.604303) (xy 352.498144 -247.650984)
			(xy 352.506039 -247.699561) (xy 352.506534 -247.724168) (xy 352.835222 -247.724168) (xy 352.839182 -247.675114)
			(xy 352.850959 -247.62733) (xy 352.87025 -247.582054) (xy 352.896553 -247.540458) (xy 352.929188 -247.503621)
			(xy 352.967309 -247.472496) (xy 353.00993 -247.447889) (xy 353.055946 -247.430437) (xy 353.104165 -247.420593)
			(xy 353.15334 -247.418612) (xy 353.202195 -247.424544) (xy 353.249466 -247.438236) (xy 353.293928 -247.459334)
			(xy 353.334431 -247.48729) (xy 353.369924 -247.521382) (xy 353.399489 -247.560726) (xy 353.42236 -247.604303)
			(xy 353.437944 -247.650984) (xy 353.445839 -247.699561) (xy 353.446334 -247.724168) (xy 353.775276 -247.724168)
			(xy 353.779236 -247.675114) (xy 353.791013 -247.62733) (xy 353.810304 -247.582054) (xy 353.836607 -247.540458)
			(xy 353.869242 -247.503621) (xy 353.907363 -247.472496) (xy 353.949984 -247.447889) (xy 353.996 -247.430437)
			(xy 354.044219 -247.420593) (xy 354.093394 -247.418612) (xy 354.142249 -247.424544) (xy 354.18952 -247.438236)
			(xy 354.233982 -247.459334) (xy 354.274485 -247.48729) (xy 354.309978 -247.521382) (xy 354.339543 -247.560726)
			(xy 354.362414 -247.604303) (xy 354.377998 -247.650984) (xy 354.385893 -247.699561) (xy 354.386388 -247.724168)
			(xy 354.71533 -247.724168) (xy 354.71929 -247.675114) (xy 354.731067 -247.62733) (xy 354.750358 -247.582054)
			(xy 354.776661 -247.540458) (xy 354.809296 -247.503621) (xy 354.847417 -247.472496) (xy 354.890038 -247.447889)
			(xy 354.936054 -247.430437) (xy 354.984273 -247.420593) (xy 355.033448 -247.418612) (xy 355.082303 -247.424544)
			(xy 355.129574 -247.438236) (xy 355.174036 -247.459334) (xy 355.214539 -247.48729) (xy 355.250032 -247.521382)
			(xy 355.279597 -247.560726) (xy 355.302468 -247.604303) (xy 355.318052 -247.650984) (xy 355.325947 -247.699561)
			(xy 355.326442 -247.724168) (xy 355.655384 -247.724168) (xy 355.659344 -247.675114) (xy 355.671121 -247.62733)
			(xy 355.690412 -247.582054) (xy 355.716715 -247.540458) (xy 355.74935 -247.503621) (xy 355.787471 -247.472496)
			(xy 355.830092 -247.447889) (xy 355.876108 -247.430437) (xy 355.924327 -247.420593) (xy 355.973502 -247.418612)
			(xy 356.022357 -247.424544) (xy 356.069628 -247.438236) (xy 356.11409 -247.459334) (xy 356.154593 -247.48729)
			(xy 356.190086 -247.521382) (xy 356.219651 -247.560726) (xy 356.242522 -247.604303) (xy 356.258106 -247.650984)
			(xy 356.266001 -247.699561) (xy 356.266496 -247.724168) (xy 356.595438 -247.724168) (xy 356.599398 -247.675114)
			(xy 356.611175 -247.62733) (xy 356.630466 -247.582054) (xy 356.656769 -247.540458) (xy 356.689404 -247.503621)
			(xy 356.727525 -247.472496) (xy 356.770146 -247.447889) (xy 356.816162 -247.430437) (xy 356.864381 -247.420593)
			(xy 356.913556 -247.418612) (xy 356.962411 -247.424544) (xy 357.009682 -247.438236) (xy 357.054144 -247.459334)
			(xy 357.094647 -247.48729) (xy 357.13014 -247.521382) (xy 357.159705 -247.560726) (xy 357.182576 -247.604303)
			(xy 357.19816 -247.650984) (xy 357.206055 -247.699561) (xy 357.20655 -247.724168) (xy 357.535238 -247.724168)
			(xy 357.539198 -247.675114) (xy 357.550975 -247.62733) (xy 357.570266 -247.582054) (xy 357.596569 -247.540458)
			(xy 357.629204 -247.503621) (xy 357.667325 -247.472496) (xy 357.709946 -247.447889) (xy 357.755962 -247.430437)
			(xy 357.804181 -247.420593) (xy 357.853356 -247.418612) (xy 357.902211 -247.424544) (xy 357.949482 -247.438236)
			(xy 357.988941 -247.45696) (xy 359.396541 -247.45696) (xy 359.400571 -247.404462) (xy 359.412568 -247.353194)
			(xy 359.432251 -247.304359) (xy 359.459157 -247.2591) (xy 359.492657 -247.218479) (xy 359.531965 -247.183448)
			(xy 359.57616 -247.154828) (xy 359.624205 -247.133289) (xy 359.674976 -247.119337) (xy 359.727281 -247.113299)
			(xy 359.779895 -247.115316) (xy 359.831585 -247.12534) (xy 359.881138 -247.143138) (xy 359.927394 -247.168291)
			(xy 359.969268 -247.20021) (xy 360.00578 -247.238148) (xy 360.036072 -247.281214) (xy 360.059435 -247.328399)
			(xy 360.075321 -247.378598) (xy 360.083358 -247.430634) (xy 360.083862 -247.45696) (xy 360.083358 -247.483286)
			(xy 360.075321 -247.535322) (xy 360.059435 -247.585521) (xy 360.036072 -247.632706) (xy 360.00578 -247.675772)
			(xy 359.969268 -247.71371) (xy 359.927394 -247.745629) (xy 359.881138 -247.770782) (xy 359.831585 -247.78858)
			(xy 359.779895 -247.798604) (xy 359.727281 -247.800621) (xy 359.674976 -247.794583) (xy 359.624205 -247.780631)
			(xy 359.57616 -247.759092) (xy 359.531965 -247.730472) (xy 359.492657 -247.695441) (xy 359.459157 -247.65482)
			(xy 359.432251 -247.609561) (xy 359.412568 -247.560726) (xy 359.400571 -247.509458) (xy 359.396541 -247.45696)
			(xy 357.988941 -247.45696) (xy 357.993944 -247.459334) (xy 358.034447 -247.48729) (xy 358.06994 -247.521382)
			(xy 358.099505 -247.560726) (xy 358.122376 -247.604303) (xy 358.13796 -247.650984) (xy 358.145855 -247.699561)
			(xy 358.14635 -247.724168) (xy 358.145855 -247.748775) (xy 358.13796 -247.797352) (xy 358.122376 -247.844033)
			(xy 358.099505 -247.88761) (xy 358.06994 -247.926954) (xy 358.034447 -247.961046) (xy 357.993944 -247.989002)
			(xy 357.949482 -248.0101) (xy 357.902211 -248.023792) (xy 357.853356 -248.029724) (xy 357.804181 -248.027743)
			(xy 357.755962 -248.017899) (xy 357.709946 -248.000447) (xy 357.667325 -247.97584) (xy 357.629204 -247.944715)
			(xy 357.596569 -247.907878) (xy 357.570266 -247.866282) (xy 357.550975 -247.821006) (xy 357.539198 -247.773222)
			(xy 357.535238 -247.724168) (xy 357.20655 -247.724168) (xy 357.206055 -247.748775) (xy 357.19816 -247.797352)
			(xy 357.182576 -247.844033) (xy 357.159705 -247.88761) (xy 357.13014 -247.926954) (xy 357.094647 -247.961046)
			(xy 357.054144 -247.989002) (xy 357.009682 -248.0101) (xy 356.962411 -248.023792) (xy 356.913556 -248.029724)
			(xy 356.864381 -248.027743) (xy 356.816162 -248.017899) (xy 356.770146 -248.000447) (xy 356.727525 -247.97584)
			(xy 356.689404 -247.944715) (xy 356.656769 -247.907878) (xy 356.630466 -247.866282) (xy 356.611175 -247.821006)
			(xy 356.599398 -247.773222) (xy 356.595438 -247.724168) (xy 356.266496 -247.724168) (xy 356.266001 -247.748775)
			(xy 356.258106 -247.797352) (xy 356.242522 -247.844033) (xy 356.219651 -247.88761) (xy 356.190086 -247.926954)
			(xy 356.154593 -247.961046) (xy 356.11409 -247.989002) (xy 356.069628 -248.0101) (xy 356.022357 -248.023792)
			(xy 355.973502 -248.029724) (xy 355.924327 -248.027743) (xy 355.876108 -248.017899) (xy 355.830092 -248.000447)
			(xy 355.787471 -247.97584) (xy 355.74935 -247.944715) (xy 355.716715 -247.907878) (xy 355.690412 -247.866282)
			(xy 355.671121 -247.821006) (xy 355.659344 -247.773222) (xy 355.655384 -247.724168) (xy 355.326442 -247.724168)
			(xy 355.325947 -247.748775) (xy 355.318052 -247.797352) (xy 355.302468 -247.844033) (xy 355.279597 -247.88761)
			(xy 355.250032 -247.926954) (xy 355.214539 -247.961046) (xy 355.174036 -247.989002) (xy 355.129574 -248.0101)
			(xy 355.082303 -248.023792) (xy 355.033448 -248.029724) (xy 354.984273 -248.027743) (xy 354.936054 -248.017899)
			(xy 354.890038 -248.000447) (xy 354.847417 -247.97584) (xy 354.809296 -247.944715) (xy 354.776661 -247.907878)
			(xy 354.750358 -247.866282) (xy 354.731067 -247.821006) (xy 354.71929 -247.773222) (xy 354.71533 -247.724168)
			(xy 354.386388 -247.724168) (xy 354.385893 -247.748775) (xy 354.377998 -247.797352) (xy 354.362414 -247.844033)
			(xy 354.339543 -247.88761) (xy 354.309978 -247.926954) (xy 354.274485 -247.961046) (xy 354.233982 -247.989002)
			(xy 354.18952 -248.0101) (xy 354.142249 -248.023792) (xy 354.093394 -248.029724) (xy 354.044219 -248.027743)
			(xy 353.996 -248.017899) (xy 353.949984 -248.000447) (xy 353.907363 -247.97584) (xy 353.869242 -247.944715)
			(xy 353.836607 -247.907878) (xy 353.810304 -247.866282) (xy 353.791013 -247.821006) (xy 353.779236 -247.773222)
			(xy 353.775276 -247.724168) (xy 353.446334 -247.724168) (xy 353.445839 -247.748775) (xy 353.437944 -247.797352)
			(xy 353.42236 -247.844033) (xy 353.399489 -247.88761) (xy 353.369924 -247.926954) (xy 353.334431 -247.961046)
			(xy 353.293928 -247.989002) (xy 353.249466 -248.0101) (xy 353.202195 -248.023792) (xy 353.15334 -248.029724)
			(xy 353.104165 -248.027743) (xy 353.055946 -248.017899) (xy 353.00993 -248.000447) (xy 352.967309 -247.97584)
			(xy 352.929188 -247.944715) (xy 352.896553 -247.907878) (xy 352.87025 -247.866282) (xy 352.850959 -247.821006)
			(xy 352.839182 -247.773222) (xy 352.835222 -247.724168) (xy 352.506534 -247.724168) (xy 352.506039 -247.748775)
			(xy 352.498144 -247.797352) (xy 352.48256 -247.844033) (xy 352.459689 -247.88761) (xy 352.430124 -247.926954)
			(xy 352.394631 -247.961046) (xy 352.354128 -247.989002) (xy 352.309666 -248.0101) (xy 352.262395 -248.023792)
			(xy 352.21354 -248.029724) (xy 352.164365 -248.027743) (xy 352.116146 -248.017899) (xy 352.07013 -248.000447)
			(xy 352.027509 -247.97584) (xy 351.989388 -247.944715) (xy 351.956753 -247.907878) (xy 351.93045 -247.866282)
			(xy 351.911159 -247.821006) (xy 351.899382 -247.773222) (xy 351.895422 -247.724168) (xy 351.56648 -247.724168)
			(xy 351.565985 -247.748775) (xy 351.55809 -247.797352) (xy 351.542506 -247.844033) (xy 351.519635 -247.88761)
			(xy 351.49007 -247.926954) (xy 351.454577 -247.961046) (xy 351.414074 -247.989002) (xy 351.369612 -248.0101)
			(xy 351.322341 -248.023792) (xy 351.273486 -248.029724) (xy 351.224311 -248.027743) (xy 351.176092 -248.017899)
			(xy 351.130076 -248.000447) (xy 351.087455 -247.97584) (xy 351.049334 -247.944715) (xy 351.016699 -247.907878)
			(xy 350.990396 -247.866282) (xy 350.971105 -247.821006) (xy 350.959328 -247.773222) (xy 350.955368 -247.724168)
			(xy 350.626426 -247.724168) (xy 350.625931 -247.748775) (xy 350.618036 -247.797352) (xy 350.602452 -247.844033)
			(xy 350.579581 -247.88761) (xy 350.550016 -247.926954) (xy 350.514523 -247.961046) (xy 350.47402 -247.989002)
			(xy 350.429558 -248.0101) (xy 350.382287 -248.023792) (xy 350.333432 -248.029724) (xy 350.284257 -248.027743)
			(xy 350.236038 -248.017899) (xy 350.190022 -248.000447) (xy 350.147401 -247.97584) (xy 350.10928 -247.944715)
			(xy 350.076645 -247.907878) (xy 350.050342 -247.866282) (xy 350.031051 -247.821006) (xy 350.019274 -247.773222)
			(xy 350.015314 -247.724168) (xy 349.686372 -247.724168) (xy 349.685877 -247.748775) (xy 349.677982 -247.797352)
			(xy 349.662398 -247.844033) (xy 349.639527 -247.88761) (xy 349.609962 -247.926954) (xy 349.574469 -247.961046)
			(xy 349.533966 -247.989002) (xy 349.489504 -248.0101) (xy 349.442233 -248.023792) (xy 349.393378 -248.029724)
			(xy 349.344203 -248.027743) (xy 349.295984 -248.017899) (xy 349.249968 -248.000447) (xy 349.207347 -247.97584)
			(xy 349.169226 -247.944715) (xy 349.136591 -247.907878) (xy 349.110288 -247.866282) (xy 349.090997 -247.821006)
			(xy 349.07922 -247.773222) (xy 349.07526 -247.724168) (xy 348.746318 -247.724168) (xy 348.745823 -247.748775)
			(xy 348.737928 -247.797352) (xy 348.722344 -247.844033) (xy 348.699473 -247.88761) (xy 348.669908 -247.926954)
			(xy 348.634415 -247.961046) (xy 348.593912 -247.989002) (xy 348.54945 -248.0101) (xy 348.502179 -248.023792)
			(xy 348.453324 -248.029724) (xy 348.404149 -248.027743) (xy 348.35593 -248.017899) (xy 348.309914 -248.000447)
			(xy 348.267293 -247.97584) (xy 348.229172 -247.944715) (xy 348.196537 -247.907878) (xy 348.170234 -247.866282)
			(xy 348.150943 -247.821006) (xy 348.139166 -247.773222) (xy 348.135206 -247.724168) (xy 347.806518 -247.724168)
			(xy 347.806023 -247.748775) (xy 347.798128 -247.797352) (xy 347.782544 -247.844033) (xy 347.759673 -247.88761)
			(xy 347.730108 -247.926954) (xy 347.694615 -247.961046) (xy 347.654112 -247.989002) (xy 347.60965 -248.0101)
			(xy 347.562379 -248.023792) (xy 347.513524 -248.029724) (xy 347.464349 -248.027743) (xy 347.41613 -248.017899)
			(xy 347.370114 -248.000447) (xy 347.327493 -247.97584) (xy 347.289372 -247.944715) (xy 347.256737 -247.907878)
			(xy 347.230434 -247.866282) (xy 347.211143 -247.821006) (xy 347.199366 -247.773222) (xy 347.195406 -247.724168)
			(xy 346.866464 -247.724168) (xy 346.865969 -247.748775) (xy 346.858074 -247.797352) (xy 346.84249 -247.844033)
			(xy 346.819619 -247.88761) (xy 346.790054 -247.926954) (xy 346.754561 -247.961046) (xy 346.714058 -247.989002)
			(xy 346.669596 -248.0101) (xy 346.622325 -248.023792) (xy 346.57347 -248.029724) (xy 346.524295 -248.027743)
			(xy 346.476076 -248.017899) (xy 346.43006 -248.000447) (xy 346.387439 -247.97584) (xy 346.349318 -247.944715)
			(xy 346.316683 -247.907878) (xy 346.29038 -247.866282) (xy 346.271089 -247.821006) (xy 346.259312 -247.773222)
			(xy 346.255352 -247.724168) (xy 345.92641 -247.724168) (xy 345.925915 -247.748775) (xy 345.91802 -247.797352)
			(xy 345.902436 -247.844033) (xy 345.879565 -247.88761) (xy 345.85 -247.926954) (xy 345.814507 -247.961046)
			(xy 345.774004 -247.989002) (xy 345.729542 -248.0101) (xy 345.682271 -248.023792) (xy 345.633416 -248.029724)
			(xy 345.584241 -248.027743) (xy 345.536022 -248.017899) (xy 345.490006 -248.000447) (xy 345.447385 -247.97584)
			(xy 345.409264 -247.944715) (xy 345.376629 -247.907878) (xy 345.350326 -247.866282) (xy 345.331035 -247.821006)
			(xy 345.319258 -247.773222) (xy 345.315298 -247.724168) (xy 344.985817 -247.724168) (xy 344.985818 -247.748692)
			(xy 344.977998 -247.797065) (xy 344.962556 -247.843571) (xy 344.939889 -247.887015) (xy 344.910578 -247.926283)
			(xy 344.875375 -247.96037) (xy 344.835182 -247.9884) (xy 344.791031 -248.009656) (xy 344.767662 -248.01703)
			(xy 344.751406 -248.021856) (xy 344.73134 -248.048526) (xy 344.73134 -248.456958) (xy 344.731775 -248.467023)
			(xy 344.739509 -248.485608) (xy 344.746326 -248.493026) (xy 344.990674 -248.737374) (xy 344.998075 -248.744212)
			(xy 345.016674 -248.751923) (xy 345.026742 -248.75236) (xy 346.641166 -248.75236) (xy 346.653102 -248.751715)
			(xy 346.674428 -248.740986) (xy 346.68206 -248.731786) (xy 346.73794 -248.656856) (xy 346.742004 -248.633234)
			(xy 346.738448 -248.62155) (xy 346.732506 -248.600197) (xy 346.726134 -248.556335) (xy 346.725748 -248.534174)
			(xy 346.72627 -248.508919) (xy 346.734583 -248.459097) (xy 346.750984 -248.411323) (xy 346.775025 -248.3669)
			(xy 346.806049 -248.32704) (xy 346.843211 -248.29283) (xy 346.885497 -248.265204) (xy 346.931753 -248.244914)
			(xy 346.980718 -248.232514) (xy 347.031056 -248.228343) (xy 347.081394 -248.232514) (xy 347.130359 -248.244914)
			(xy 347.176615 -248.265204) (xy 347.218901 -248.29283) (xy 347.256063 -248.32704) (xy 347.287087 -248.3669)
			(xy 347.311128 -248.411323) (xy 347.327529 -248.459097) (xy 347.335842 -248.508919) (xy 347.336364 -248.534174)
			(xy 349.545414 -248.534174) (xy 349.549374 -248.48512) (xy 349.561151 -248.437336) (xy 349.580442 -248.39206)
			(xy 349.606745 -248.350464) (xy 349.63938 -248.313627) (xy 349.677501 -248.282502) (xy 349.720122 -248.257895)
			(xy 349.766138 -248.240443) (xy 349.814357 -248.230599) (xy 349.863532 -248.228618) (xy 349.912387 -248.23455)
			(xy 349.959658 -248.248242) (xy 350.00412 -248.26934) (xy 350.044623 -248.297296) (xy 350.080116 -248.331388)
			(xy 350.109681 -248.370732) (xy 350.132552 -248.414309) (xy 350.148136 -248.46099) (xy 350.156031 -248.509567)
			(xy 350.156526 -248.534174) (xy 352.365322 -248.534174) (xy 352.369282 -248.48512) (xy 352.381059 -248.437336)
			(xy 352.40035 -248.39206) (xy 352.426653 -248.350464) (xy 352.459288 -248.313627) (xy 352.497409 -248.282502)
			(xy 352.54003 -248.257895) (xy 352.586046 -248.240443) (xy 352.634265 -248.230599) (xy 352.68344 -248.228618)
			(xy 352.732295 -248.23455) (xy 352.779566 -248.248242) (xy 352.824028 -248.26934) (xy 352.864531 -248.297296)
			(xy 352.900024 -248.331388) (xy 352.929589 -248.370732) (xy 352.95246 -248.414309) (xy 352.968044 -248.46099)
			(xy 352.975939 -248.509567) (xy 352.976434 -248.534174) (xy 355.18523 -248.534174) (xy 355.18919 -248.48512)
			(xy 355.200967 -248.437336) (xy 355.220258 -248.39206) (xy 355.246561 -248.350464) (xy 355.279196 -248.313627)
			(xy 355.317317 -248.282502) (xy 355.359938 -248.257895) (xy 355.405954 -248.240443) (xy 355.454173 -248.230599)
			(xy 355.503348 -248.228618) (xy 355.552203 -248.23455) (xy 355.599474 -248.248242) (xy 355.643936 -248.26934)
			(xy 355.684439 -248.297296) (xy 355.719932 -248.331388) (xy 355.749497 -248.370732) (xy 355.772368 -248.414309)
			(xy 355.787952 -248.46099) (xy 355.795847 -248.509567) (xy 355.796342 -248.534174) (xy 356.125284 -248.534174)
			(xy 356.129244 -248.48512) (xy 356.141021 -248.437336) (xy 356.160312 -248.39206) (xy 356.186615 -248.350464)
			(xy 356.21925 -248.313627) (xy 356.257371 -248.282502) (xy 356.299992 -248.257895) (xy 356.346008 -248.240443)
			(xy 356.394227 -248.230599) (xy 356.443402 -248.228618) (xy 356.492257 -248.23455) (xy 356.539528 -248.248242)
			(xy 356.58399 -248.26934) (xy 356.624493 -248.297296) (xy 356.659986 -248.331388) (xy 356.689551 -248.370732)
			(xy 356.712422 -248.414309) (xy 356.728006 -248.46099) (xy 356.735901 -248.509567) (xy 356.736396 -248.534174)
			(xy 357.065338 -248.534174) (xy 357.069298 -248.48512) (xy 357.081075 -248.437336) (xy 357.100366 -248.39206)
			(xy 357.126669 -248.350464) (xy 357.159304 -248.313627) (xy 357.197425 -248.282502) (xy 357.240046 -248.257895)
			(xy 357.286062 -248.240443) (xy 357.334281 -248.230599) (xy 357.383456 -248.228618) (xy 357.432311 -248.23455)
			(xy 357.479582 -248.248242) (xy 357.524044 -248.26934) (xy 357.564547 -248.297296) (xy 357.60004 -248.331388)
			(xy 357.629605 -248.370732) (xy 357.652476 -248.414309) (xy 357.66806 -248.46099) (xy 357.675955 -248.509567)
			(xy 357.67645 -248.534174) (xy 358.005392 -248.534174) (xy 358.009352 -248.48512) (xy 358.021129 -248.437336)
			(xy 358.04042 -248.39206) (xy 358.066723 -248.350464) (xy 358.099358 -248.313627) (xy 358.137479 -248.282502)
			(xy 358.1801 -248.257895) (xy 358.226116 -248.240443) (xy 358.274335 -248.230599) (xy 358.32351 -248.228618)
			(xy 358.372365 -248.23455) (xy 358.419636 -248.248242) (xy 358.464098 -248.26934) (xy 358.504601 -248.297296)
			(xy 358.540094 -248.331388) (xy 358.569659 -248.370732) (xy 358.59253 -248.414309) (xy 358.608114 -248.46099)
			(xy 358.616009 -248.509567) (xy 358.616504 -248.534174) (xy 358.616009 -248.558781) (xy 358.608114 -248.607358)
			(xy 358.59253 -248.654039) (xy 358.569659 -248.697616) (xy 358.540094 -248.73696) (xy 358.504601 -248.771052)
			(xy 358.464098 -248.799008) (xy 358.419636 -248.820106) (xy 358.372365 -248.833798) (xy 358.32351 -248.83973)
			(xy 358.274335 -248.837749) (xy 358.226116 -248.827905) (xy 358.1801 -248.810453) (xy 358.137479 -248.785846)
			(xy 358.099358 -248.754721) (xy 358.066723 -248.717884) (xy 358.04042 -248.676288) (xy 358.021129 -248.631012)
			(xy 358.009352 -248.583228) (xy 358.005392 -248.534174) (xy 357.67645 -248.534174) (xy 357.675955 -248.558781)
			(xy 357.66806 -248.607358) (xy 357.652476 -248.654039) (xy 357.629605 -248.697616) (xy 357.60004 -248.73696)
			(xy 357.564547 -248.771052) (xy 357.524044 -248.799008) (xy 357.479582 -248.820106) (xy 357.432311 -248.833798)
			(xy 357.383456 -248.83973) (xy 357.334281 -248.837749) (xy 357.286062 -248.827905) (xy 357.240046 -248.810453)
			(xy 357.197425 -248.785846) (xy 357.159304 -248.754721) (xy 357.126669 -248.717884) (xy 357.100366 -248.676288)
			(xy 357.081075 -248.631012) (xy 357.069298 -248.583228) (xy 357.065338 -248.534174) (xy 356.736396 -248.534174)
			(xy 356.735901 -248.558781) (xy 356.728006 -248.607358) (xy 356.712422 -248.654039) (xy 356.689551 -248.697616)
			(xy 356.659986 -248.73696) (xy 356.624493 -248.771052) (xy 356.58399 -248.799008) (xy 356.539528 -248.820106)
			(xy 356.492257 -248.833798) (xy 356.443402 -248.83973) (xy 356.394227 -248.837749) (xy 356.346008 -248.827905)
			(xy 356.299992 -248.810453) (xy 356.257371 -248.785846) (xy 356.21925 -248.754721) (xy 356.186615 -248.717884)
			(xy 356.160312 -248.676288) (xy 356.141021 -248.631012) (xy 356.129244 -248.583228) (xy 356.125284 -248.534174)
			(xy 355.796342 -248.534174) (xy 355.795847 -248.558781) (xy 355.787952 -248.607358) (xy 355.772368 -248.654039)
			(xy 355.749497 -248.697616) (xy 355.719932 -248.73696) (xy 355.684439 -248.771052) (xy 355.643936 -248.799008)
			(xy 355.599474 -248.820106) (xy 355.552203 -248.833798) (xy 355.503348 -248.83973) (xy 355.454173 -248.837749)
			(xy 355.405954 -248.827905) (xy 355.359938 -248.810453) (xy 355.317317 -248.785846) (xy 355.279196 -248.754721)
			(xy 355.246561 -248.717884) (xy 355.220258 -248.676288) (xy 355.200967 -248.631012) (xy 355.18919 -248.583228)
			(xy 355.18523 -248.534174) (xy 352.976434 -248.534174) (xy 352.975939 -248.558781) (xy 352.968044 -248.607358)
			(xy 352.95246 -248.654039) (xy 352.929589 -248.697616) (xy 352.900024 -248.73696) (xy 352.864531 -248.771052)
			(xy 352.824028 -248.799008) (xy 352.779566 -248.820106) (xy 352.732295 -248.833798) (xy 352.68344 -248.83973)
			(xy 352.634265 -248.837749) (xy 352.586046 -248.827905) (xy 352.54003 -248.810453) (xy 352.497409 -248.785846)
			(xy 352.459288 -248.754721) (xy 352.426653 -248.717884) (xy 352.40035 -248.676288) (xy 352.381059 -248.631012)
			(xy 352.369282 -248.583228) (xy 352.365322 -248.534174) (xy 350.156526 -248.534174) (xy 350.156031 -248.558781)
			(xy 350.148136 -248.607358) (xy 350.132552 -248.654039) (xy 350.109681 -248.697616) (xy 350.080116 -248.73696)
			(xy 350.044623 -248.771052) (xy 350.00412 -248.799008) (xy 349.959658 -248.820106) (xy 349.912387 -248.833798)
			(xy 349.863532 -248.83973) (xy 349.814357 -248.837749) (xy 349.766138 -248.827905) (xy 349.720122 -248.810453)
			(xy 349.677501 -248.785846) (xy 349.63938 -248.754721) (xy 349.606745 -248.717884) (xy 349.580442 -248.676288)
			(xy 349.561151 -248.631012) (xy 349.549374 -248.583228) (xy 349.545414 -248.534174) (xy 347.336364 -248.534174)
			(xy 347.33588 -248.559226) (xy 347.327748 -248.608665) (xy 347.311665 -248.656117) (xy 347.300296 -248.678446)
			(xy 347.292168 -248.693178) (xy 347.296994 -248.726198) (xy 347.646244 -249.075448) (xy 347.652086 -249.07875)
			(xy 347.67556 -249.092792) (xy 347.717537 -249.127853) (xy 347.7526 -249.169829) (xy 347.76664 -249.193304)
			(xy 347.769942 -249.199146) (xy 347.914976 -249.34418) (xy 349.07526 -249.34418) (xy 349.07922 -249.295126)
			(xy 349.090997 -249.247342) (xy 349.110288 -249.202066) (xy 349.136591 -249.16047) (xy 349.169226 -249.123633)
			(xy 349.207347 -249.092508) (xy 349.249968 -249.067901) (xy 349.295984 -249.050449) (xy 349.344203 -249.040605)
			(xy 349.393378 -249.038624) (xy 349.442233 -249.044556) (xy 349.489504 -249.058248) (xy 349.533966 -249.079346)
			(xy 349.574469 -249.107302) (xy 349.609962 -249.141394) (xy 349.639527 -249.180738) (xy 349.662398 -249.224315)
			(xy 349.677982 -249.270996) (xy 349.685877 -249.319573) (xy 349.686372 -249.34418) (xy 350.955368 -249.34418)
			(xy 350.959328 -249.295126) (xy 350.971105 -249.247342) (xy 350.990396 -249.202066) (xy 351.016699 -249.16047)
			(xy 351.049334 -249.123633) (xy 351.087455 -249.092508) (xy 351.130076 -249.067901) (xy 351.176092 -249.050449)
			(xy 351.224311 -249.040605) (xy 351.273486 -249.038624) (xy 351.322341 -249.044556) (xy 351.369612 -249.058248)
			(xy 351.414074 -249.079346) (xy 351.454577 -249.107302) (xy 351.49007 -249.141394) (xy 351.519635 -249.180738)
			(xy 351.542506 -249.224315) (xy 351.55809 -249.270996) (xy 351.565985 -249.319573) (xy 351.56648 -249.34418)
			(xy 352.835222 -249.34418) (xy 352.839182 -249.295126) (xy 352.850959 -249.247342) (xy 352.87025 -249.202066)
			(xy 352.896553 -249.16047) (xy 352.929188 -249.123633) (xy 352.967309 -249.092508) (xy 353.00993 -249.067901)
			(xy 353.055946 -249.050449) (xy 353.104165 -249.040605) (xy 353.15334 -249.038624) (xy 353.202195 -249.044556)
			(xy 353.249466 -249.058248) (xy 353.293928 -249.079346) (xy 353.334431 -249.107302) (xy 353.369924 -249.141394)
			(xy 353.399489 -249.180738) (xy 353.42236 -249.224315) (xy 353.437944 -249.270996) (xy 353.445839 -249.319573)
			(xy 353.446334 -249.34418) (xy 354.71533 -249.34418) (xy 354.71929 -249.295126) (xy 354.731067 -249.247342)
			(xy 354.750358 -249.202066) (xy 354.776661 -249.16047) (xy 354.809296 -249.123633) (xy 354.847417 -249.092508)
			(xy 354.890038 -249.067901) (xy 354.936054 -249.050449) (xy 354.984273 -249.040605) (xy 355.033448 -249.038624)
			(xy 355.082303 -249.044556) (xy 355.129574 -249.058248) (xy 355.174036 -249.079346) (xy 355.214539 -249.107302)
			(xy 355.250032 -249.141394) (xy 355.279597 -249.180738) (xy 355.302468 -249.224315) (xy 355.318052 -249.270996)
			(xy 355.325947 -249.319573) (xy 355.326442 -249.34418) (xy 356.595438 -249.34418) (xy 356.599398 -249.295126)
			(xy 356.611175 -249.247342) (xy 356.630466 -249.202066) (xy 356.656769 -249.16047) (xy 356.689404 -249.123633)
			(xy 356.727525 -249.092508) (xy 356.770146 -249.067901) (xy 356.816162 -249.050449) (xy 356.864381 -249.040605)
			(xy 356.913556 -249.038624) (xy 356.962411 -249.044556) (xy 357.009682 -249.058248) (xy 357.054144 -249.079346)
			(xy 357.094647 -249.107302) (xy 357.13014 -249.141394) (xy 357.159705 -249.180738) (xy 357.182576 -249.224315)
			(xy 357.19816 -249.270996) (xy 357.206055 -249.319573) (xy 357.20655 -249.34418) (xy 357.206192 -249.36196)
			(xy 359.396541 -249.36196) (xy 359.400571 -249.309462) (xy 359.412568 -249.258194) (xy 359.432251 -249.209359)
			(xy 359.459157 -249.1641) (xy 359.492657 -249.123479) (xy 359.531965 -249.088448) (xy 359.57616 -249.059828)
			(xy 359.624205 -249.038289) (xy 359.674976 -249.024337) (xy 359.727281 -249.018299) (xy 359.779895 -249.020316)
			(xy 359.831585 -249.03034) (xy 359.881138 -249.048138) (xy 359.927394 -249.073291) (xy 359.969268 -249.10521)
			(xy 360.00578 -249.143148) (xy 360.036072 -249.186214) (xy 360.059435 -249.233399) (xy 360.075321 -249.283598)
			(xy 360.083358 -249.335634) (xy 360.083862 -249.36196) (xy 360.083358 -249.388286) (xy 360.075321 -249.440322)
			(xy 360.059435 -249.490521) (xy 360.036072 -249.537706) (xy 360.00578 -249.580772) (xy 359.969268 -249.61871)
			(xy 359.927394 -249.650629) (xy 359.881138 -249.675782) (xy 359.831585 -249.69358) (xy 359.779895 -249.703604)
			(xy 359.727281 -249.705621) (xy 359.674976 -249.699583) (xy 359.624205 -249.685631) (xy 359.57616 -249.664092)
			(xy 359.531965 -249.635472) (xy 359.492657 -249.600441) (xy 359.459157 -249.55982) (xy 359.432251 -249.514561)
			(xy 359.412568 -249.465726) (xy 359.400571 -249.414458) (xy 359.396541 -249.36196) (xy 357.206192 -249.36196)
			(xy 357.206055 -249.368787) (xy 357.19816 -249.417364) (xy 357.182576 -249.464045) (xy 357.159705 -249.507622)
			(xy 357.13014 -249.546966) (xy 357.094647 -249.581058) (xy 357.054144 -249.609014) (xy 357.009682 -249.630112)
			(xy 356.962411 -249.643804) (xy 356.913556 -249.649736) (xy 356.864381 -249.647755) (xy 356.816162 -249.637911)
			(xy 356.770146 -249.620459) (xy 356.727525 -249.595852) (xy 356.689404 -249.564727) (xy 356.656769 -249.52789)
			(xy 356.630466 -249.486294) (xy 356.611175 -249.441018) (xy 356.599398 -249.393234) (xy 356.595438 -249.34418)
			(xy 355.326442 -249.34418) (xy 355.325947 -249.368787) (xy 355.318052 -249.417364) (xy 355.302468 -249.464045)
			(xy 355.279597 -249.507622) (xy 355.250032 -249.546966) (xy 355.214539 -249.581058) (xy 355.174036 -249.609014)
			(xy 355.129574 -249.630112) (xy 355.082303 -249.643804) (xy 355.033448 -249.649736) (xy 354.984273 -249.647755)
			(xy 354.936054 -249.637911) (xy 354.890038 -249.620459) (xy 354.847417 -249.595852) (xy 354.809296 -249.564727)
			(xy 354.776661 -249.52789) (xy 354.750358 -249.486294) (xy 354.731067 -249.441018) (xy 354.71929 -249.393234)
			(xy 354.71533 -249.34418) (xy 353.446334 -249.34418) (xy 353.445839 -249.368787) (xy 353.437944 -249.417364)
			(xy 353.42236 -249.464045) (xy 353.399489 -249.507622) (xy 353.369924 -249.546966) (xy 353.334431 -249.581058)
			(xy 353.293928 -249.609014) (xy 353.249466 -249.630112) (xy 353.202195 -249.643804) (xy 353.15334 -249.649736)
			(xy 353.104165 -249.647755) (xy 353.055946 -249.637911) (xy 353.00993 -249.620459) (xy 352.967309 -249.595852)
			(xy 352.929188 -249.564727) (xy 352.896553 -249.52789) (xy 352.87025 -249.486294) (xy 352.850959 -249.441018)
			(xy 352.839182 -249.393234) (xy 352.835222 -249.34418) (xy 351.56648 -249.34418) (xy 351.565985 -249.368787)
			(xy 351.55809 -249.417364) (xy 351.542506 -249.464045) (xy 351.519635 -249.507622) (xy 351.49007 -249.546966)
			(xy 351.454577 -249.581058) (xy 351.414074 -249.609014) (xy 351.369612 -249.630112) (xy 351.322341 -249.643804)
			(xy 351.273486 -249.649736) (xy 351.224311 -249.647755) (xy 351.176092 -249.637911) (xy 351.130076 -249.620459)
			(xy 351.087455 -249.595852) (xy 351.049334 -249.564727) (xy 351.016699 -249.52789) (xy 350.990396 -249.486294)
			(xy 350.971105 -249.441018) (xy 350.959328 -249.393234) (xy 350.955368 -249.34418) (xy 349.686372 -249.34418)
			(xy 349.685877 -249.368787) (xy 349.677982 -249.417364) (xy 349.662398 -249.464045) (xy 349.639527 -249.507622)
			(xy 349.609962 -249.546966) (xy 349.574469 -249.581058) (xy 349.533966 -249.609014) (xy 349.489504 -249.630112)
			(xy 349.442233 -249.643804) (xy 349.393378 -249.649736) (xy 349.344203 -249.647755) (xy 349.295984 -249.637911)
			(xy 349.249968 -249.620459) (xy 349.207347 -249.595852) (xy 349.169226 -249.564727) (xy 349.136591 -249.52789)
			(xy 349.110288 -249.486294) (xy 349.090997 -249.441018) (xy 349.07922 -249.393234) (xy 349.07526 -249.34418)
			(xy 347.914976 -249.34418) (xy 348.094046 -249.52325) (xy 348.101666 -249.541792) (xy 348.101666 -249.551698)
			(xy 348.70429 -250.154186) (xy 349.545414 -250.154186) (xy 349.549374 -250.105132) (xy 349.561151 -250.057348)
			(xy 349.580442 -250.012072) (xy 349.606745 -249.970476) (xy 349.63938 -249.933639) (xy 349.677501 -249.902514)
			(xy 349.720122 -249.877907) (xy 349.766138 -249.860455) (xy 349.814357 -249.850611) (xy 349.863532 -249.84863)
			(xy 349.912387 -249.854562) (xy 349.959658 -249.868254) (xy 350.00412 -249.889352) (xy 350.044623 -249.917308)
			(xy 350.080116 -249.9514) (xy 350.109681 -249.990744) (xy 350.132552 -250.034321) (xy 350.148136 -250.081002)
			(xy 350.156031 -250.129579) (xy 350.156526 -250.154186) (xy 351.425268 -250.154186) (xy 351.429228 -250.105132)
			(xy 351.441005 -250.057348) (xy 351.460296 -250.012072) (xy 351.486599 -249.970476) (xy 351.519234 -249.933639)
			(xy 351.557355 -249.902514) (xy 351.599976 -249.877907) (xy 351.645992 -249.860455) (xy 351.694211 -249.850611)
			(xy 351.743386 -249.84863) (xy 351.792241 -249.854562) (xy 351.839512 -249.868254) (xy 351.883974 -249.889352)
			(xy 351.924477 -249.917308) (xy 351.95997 -249.9514) (xy 351.989535 -249.990744) (xy 352.012406 -250.034321)
			(xy 352.02799 -250.081002) (xy 352.035885 -250.129579) (xy 352.03638 -250.154186) (xy 353.305376 -250.154186)
			(xy 353.309336 -250.105132) (xy 353.321113 -250.057348) (xy 353.340404 -250.012072) (xy 353.366707 -249.970476)
			(xy 353.399342 -249.933639) (xy 353.437463 -249.902514) (xy 353.480084 -249.877907) (xy 353.5261 -249.860455)
			(xy 353.574319 -249.850611) (xy 353.623494 -249.84863) (xy 353.672349 -249.854562) (xy 353.71962 -249.868254)
			(xy 353.764082 -249.889352) (xy 353.804585 -249.917308) (xy 353.840078 -249.9514) (xy 353.869643 -249.990744)
			(xy 353.892514 -250.034321) (xy 353.908098 -250.081002) (xy 353.915993 -250.129579) (xy 353.916488 -250.154186)
			(xy 355.18523 -250.154186) (xy 355.18919 -250.105132) (xy 355.200967 -250.057348) (xy 355.220258 -250.012072)
			(xy 355.246561 -249.970476) (xy 355.279196 -249.933639) (xy 355.317317 -249.902514) (xy 355.359938 -249.877907)
			(xy 355.405954 -249.860455) (xy 355.454173 -249.850611) (xy 355.503348 -249.84863) (xy 355.552203 -249.854562)
			(xy 355.599474 -249.868254) (xy 355.643936 -249.889352) (xy 355.684439 -249.917308) (xy 355.719932 -249.9514)
			(xy 355.749497 -249.990744) (xy 355.772368 -250.034321) (xy 355.787952 -250.081002) (xy 355.795847 -250.129579)
			(xy 355.796342 -250.154186) (xy 355.795847 -250.178793) (xy 355.787952 -250.22737) (xy 355.772368 -250.274051)
			(xy 355.749497 -250.317628) (xy 355.719932 -250.356972) (xy 355.684439 -250.391064) (xy 355.643936 -250.41902)
			(xy 355.599474 -250.440118) (xy 355.552203 -250.45381) (xy 355.503348 -250.459742) (xy 355.454173 -250.457761)
			(xy 355.405954 -250.447917) (xy 355.359938 -250.430465) (xy 355.317317 -250.405858) (xy 355.279196 -250.374733)
			(xy 355.246561 -250.337896) (xy 355.220258 -250.2963) (xy 355.200967 -250.251024) (xy 355.18919 -250.20324)
			(xy 355.18523 -250.154186) (xy 353.916488 -250.154186) (xy 353.915993 -250.178793) (xy 353.908098 -250.22737)
			(xy 353.892514 -250.274051) (xy 353.869643 -250.317628) (xy 353.840078 -250.356972) (xy 353.804585 -250.391064)
			(xy 353.764082 -250.41902) (xy 353.71962 -250.440118) (xy 353.672349 -250.45381) (xy 353.623494 -250.459742)
			(xy 353.574319 -250.457761) (xy 353.5261 -250.447917) (xy 353.480084 -250.430465) (xy 353.437463 -250.405858)
			(xy 353.399342 -250.374733) (xy 353.366707 -250.337896) (xy 353.340404 -250.2963) (xy 353.321113 -250.251024)
			(xy 353.309336 -250.20324) (xy 353.305376 -250.154186) (xy 352.03638 -250.154186) (xy 352.035885 -250.178793)
			(xy 352.02799 -250.22737) (xy 352.012406 -250.274051) (xy 351.989535 -250.317628) (xy 351.95997 -250.356972)
			(xy 351.924477 -250.391064) (xy 351.883974 -250.41902) (xy 351.839512 -250.440118) (xy 351.792241 -250.45381)
			(xy 351.743386 -250.459742) (xy 351.694211 -250.457761) (xy 351.645992 -250.447917) (xy 351.599976 -250.430465)
			(xy 351.557355 -250.405858) (xy 351.519234 -250.374733) (xy 351.486599 -250.337896) (xy 351.460296 -250.2963)
			(xy 351.441005 -250.251024) (xy 351.429228 -250.20324) (xy 351.425268 -250.154186) (xy 350.156526 -250.154186)
			(xy 350.156031 -250.178793) (xy 350.148136 -250.22737) (xy 350.132552 -250.274051) (xy 350.109681 -250.317628)
			(xy 350.080116 -250.356972) (xy 350.044623 -250.391064) (xy 350.00412 -250.41902) (xy 349.959658 -250.440118)
			(xy 349.912387 -250.45381) (xy 349.863532 -250.459742) (xy 349.814357 -250.457761) (xy 349.766138 -250.447917)
			(xy 349.720122 -250.430465) (xy 349.677501 -250.405858) (xy 349.63938 -250.374733) (xy 349.606745 -250.337896)
			(xy 349.580442 -250.2963) (xy 349.561151 -250.251024) (xy 349.549374 -250.20324) (xy 349.545414 -250.154186)
			(xy 348.70429 -250.154186) (xy 349.22841 -250.678188) (xy 349.25762 -250.684538) (xy 349.271844 -250.67895)
			(xy 349.297676 -250.669701) (xy 349.351604 -250.659611) (xy 349.379032 -250.658884) (xy 349.383858 -250.658884)
			(xy 349.407568 -250.659547) (xy 349.45436 -250.667305) (xy 349.499389 -250.682204) (xy 349.541573 -250.703888)
			(xy 349.579896 -250.731834) (xy 349.613437 -250.76537) (xy 349.641389 -250.803689) (xy 349.663078 -250.84587)
			(xy 349.677985 -250.890897) (xy 349.685749 -250.937687) (xy 349.686372 -250.961398) (xy 349.686372 -250.964446)
			(xy 349.685748 -250.992319) (xy 349.675645 -251.047142) (xy 349.666306 -251.073412) (xy 349.660718 -251.087636)
			(xy 349.667068 -251.116846) (xy 349.808546 -251.258324) (xy 349.815943 -251.265172) (xy 349.834542 -251.272901)
			(xy 349.844614 -251.27331) (xy 350.670876 -251.27331)
		)
		(stroke
			(width 0)
			(type solid)
		)
		(fill yes)
		(layer "In11.Cu")
		(net "PVDDCR_CPU0_P0")
	)
	(gr_poly
		(pts
			(xy 46.127416 -421.704008) (xy 46.138257 -421.703514) (xy 46.158005 -421.694568) (xy 46.165516 -421.686736)
			(xy 46.223174 -421.621204) (xy 46.229524 -421.600376) (xy 46.228 -421.589454) (xy 46.226094 -421.573521)
			(xy 46.224062 -421.541492) (xy 46.223936 -421.525446) (xy 46.223936 -421.525192) (xy 46.22448 -421.49118)
			(xy 46.233549 -421.423763) (xy 46.251524 -421.358156) (xy 46.278084 -421.295531) (xy 46.312755 -421.237006)
			(xy 46.33341 -421.209978) (xy 46.340003 -421.200616) (xy 46.345003 -421.178305) (xy 46.339834 -421.156032)
			(xy 46.333156 -421.146732) (xy 46.312008 -421.119542) (xy 46.276464 -421.060539) (xy 46.249219 -420.997274)
			(xy 46.230773 -420.930907) (xy 46.221463 -420.862657) (xy 46.220888 -420.828216) (xy 46.221492 -420.79365)
			(xy 46.230897 -420.725161) (xy 46.249481 -420.658574) (xy 46.276903 -420.595113) (xy 46.312659 -420.535946)
			(xy 46.333918 -420.508684) (xy 46.339258 -420.501555) (xy 46.345042 -420.484719) (xy 46.344695 -420.466921)
			(xy 46.338259 -420.450324) (xy 46.332648 -420.443406) (xy 46.312974 -420.420211) (xy 46.278707 -420.369957)
			(xy 46.250684 -420.315973) (xy 46.229303 -420.25903) (xy 46.214872 -420.199942) (xy 46.207596 -420.139554)
			(xy 46.207172 -420.109142) (xy 46.207662 -420.077017) (xy 46.215754 -420.013278) (xy 46.231816 -419.951068)
			(xy 46.25559 -419.891378) (xy 46.286698 -419.835161) (xy 46.324644 -419.783313) (xy 46.346364 -419.759638)
			(xy 46.352096 -419.75305) (xy 46.359116 -419.737075) (xy 46.36008 -419.728396) (xy 46.362366 -419.698678)
			(xy 46.362638 -419.690061) (xy 46.358106 -419.673437) (xy 46.353476 -419.666166) (xy 46.336267 -419.640561)
			(xy 46.307496 -419.585985) (xy 46.285538 -419.528329) (xy 46.270716 -419.468441) (xy 46.263247 -419.4072)
			(xy 46.262798 -419.376352) (xy 46.263265 -419.345623) (xy 46.270678 -419.284614) (xy 46.285391 -419.224943)
			(xy 46.307189 -419.16748) (xy 46.335753 -419.113064) (xy 46.370669 -419.062487) (xy 46.411425 -419.016487)
			(xy 46.457429 -418.975735) (xy 46.50801 -418.940825) (xy 46.562429 -418.912266) (xy 46.619894 -418.890475)
			(xy 46.679567 -418.875768) (xy 46.740577 -418.868362) (xy 46.771306 -418.867844) (xy 46.801826 -418.868296)
			(xy 46.862426 -418.875604) (xy 46.921716 -418.890116) (xy 46.978842 -418.911621) (xy 47.032982 -418.939811)
			(xy 47.083358 -418.97428) (xy 47.106586 -418.994082) (xy 47.117762 -419.003988) (xy 47.14748 -419.008306)
			(xy 47.245524 -418.963856) (xy 47.254195 -418.959441) (xy 47.26763 -418.945389) (xy 47.274873 -418.927348)
			(xy 47.275242 -418.917628) (xy 47.275242 -413.358076) (xy 47.270924 -413.34817) (xy 47.261317 -413.325387)
			(xy 47.247764 -413.277838) (xy 47.240897 -413.228873) (xy 47.240444 -413.204152) (xy 47.240861 -413.179427)
			(xy 47.247706 -413.130454) (xy 47.261284 -413.082906) (xy 47.270924 -413.060134) (xy 47.275242 -413.050228)
			(xy 47.275242 -412.971996) (xy 47.274803 -412.962206) (xy 47.267499 -412.944039) (xy 47.261018 -412.93669)
			(xy 47.239682 -412.914846) (xy 47.233033 -412.908561) (xy 47.216502 -412.900748) (xy 47.207424 -412.899606)
			(xy 47.181689 -412.896917) (xy 47.131444 -412.88456) (xy 47.083739 -412.864526) (xy 47.039737 -412.837305)
			(xy 47.000513 -412.803561) (xy 46.967025 -412.764118) (xy 46.940091 -412.719939) (xy 46.920369 -412.672104)
			(xy 46.90834 -412.621781) (xy 46.904297 -412.570197) (xy 46.90834 -412.518614) (xy 46.920371 -412.468291)
			(xy 46.940094 -412.420456) (xy 46.967028 -412.376278) (xy 47.000517 -412.336835) (xy 47.039741 -412.303092)
			(xy 47.083744 -412.275871) (xy 47.131449 -412.255838) (xy 47.181694 -412.243482) (xy 47.207424 -412.24073)
			(xy 47.216513 -412.239621) (xy 47.233061 -412.231814) (xy 47.239682 -412.22549) (xy 47.261018 -412.203646)
			(xy 47.267501 -412.196295) (xy 47.274817 -412.178132) (xy 47.275242 -412.16834) (xy 47.275242 -412.090108)
			(xy 47.270924 -412.080202) (xy 47.261315 -412.05742) (xy 47.247757 -412.00987) (xy 47.240886 -411.960906)
			(xy 47.240444 -411.936184) (xy 47.240866 -411.91146) (xy 47.247719 -411.86249) (xy 47.261305 -411.814946)
			(xy 47.270924 -411.792166) (xy 47.275242 -411.78226) (xy 47.275242 -405.252428) (xy 47.270924 -405.242522)
			(xy 47.261314 -405.21974) (xy 47.247754 -405.172191) (xy 47.24088 -405.123226) (xy 47.240444 -405.098504)
			(xy 47.240865 -405.07378) (xy 47.247715 -405.024809) (xy 47.261299 -404.977264) (xy 47.270924 -404.954486)
			(xy 47.275242 -404.94458) (xy 47.275242 -404.866348) (xy 47.274794 -404.856562) (xy 47.267478 -404.838407)
			(xy 47.261018 -404.831042) (xy 47.239682 -404.809198) (xy 47.23303 -404.802918) (xy 47.216499 -404.795113)
			(xy 47.207424 -404.793958) (xy 47.181684 -404.791269) (xy 47.131432 -404.778911) (xy 47.083719 -404.758874)
			(xy 47.03971 -404.731649) (xy 47.000479 -404.6979) (xy 46.966986 -404.658452) (xy 46.940047 -404.614267)
			(xy 46.920321 -404.566424) (xy 46.908289 -404.516093) (xy 46.904245 -404.464502) (xy 46.908289 -404.41291)
			(xy 46.92032 -404.362579) (xy 46.940046 -404.314736) (xy 46.966984 -404.270551) (xy 47.000477 -404.231102)
			(xy 47.039707 -404.197353) (xy 47.083716 -404.170127) (xy 47.131429 -404.15009) (xy 47.181681 -404.137731)
			(xy 47.207424 -404.135082) (xy 47.216512 -404.133971) (xy 47.233054 -404.126159) (xy 47.239682 -404.119842)
			(xy 47.261018 -404.097998) (xy 47.267509 -404.09065) (xy 47.274844 -404.072487) (xy 47.275242 -404.062692)
			(xy 47.275242 -403.98446) (xy 47.270924 -403.974554) (xy 47.261318 -403.951771) (xy 47.247767 -403.904221)
			(xy 47.240902 -403.855257) (xy 47.240444 -403.830536) (xy 47.240862 -403.805811) (xy 47.247709 -403.756839)
			(xy 47.261289 -403.709292) (xy 47.270924 -403.686518) (xy 47.275242 -403.676612) (xy 47.275242 -395.867382)
			(xy 47.27567 -395.857314) (xy 47.283393 -395.838719) (xy 47.290228 -395.831314) (xy 48.813466 -394.308076)
			(xy 48.820666 -394.300138) (xy 48.828413 -394.280185) (xy 48.828452 -394.269468) (xy 48.824642 -394.194284)
			(xy 48.823609 -394.183851) (xy 48.814292 -394.165095) (xy 48.806608 -394.157962) (xy 48.806354 -394.157708)
			(xy 48.787838 -394.14193) (xy 48.755191 -394.105866) (xy 48.72818 -394.065408) (xy 48.70739 -394.021429)
			(xy 48.693268 -393.974878) (xy 48.68612 -393.926761) (xy 48.685704 -393.902438) (xy 48.686253 -393.874949)
			(xy 48.69535 -393.820729) (xy 48.713282 -393.768759) (xy 48.739558 -393.720467) (xy 48.756062 -393.698476)
			(xy 48.761448 -393.690924) (xy 48.766901 -393.673209) (xy 48.76673 -393.663932) (xy 48.761904 -393.587224)
			(xy 48.754284 -393.57046) (xy 48.74768 -393.563856) (xy 48.726699 -393.542232) (xy 48.691137 -393.493599)
			(xy 48.663658 -393.439982) (xy 48.644946 -393.382714) (xy 48.635464 -393.323216) (xy 48.634904 -393.293092)
			(xy 48.634904 -392.428984) (xy 48.635342 -392.402655) (xy 48.642576 -392.350496) (xy 48.65692 -392.299829)
			(xy 48.678098 -392.251617) (xy 48.70571 -392.206779) (xy 48.739229 -392.166167) (xy 48.758348 -392.14806)
			(xy 48.764957 -392.141395) (xy 48.77328 -392.124588) (xy 48.774604 -392.115294) (xy 48.78197 -392.038332)
			(xy 48.77689 -392.020044) (xy 48.771302 -392.012678) (xy 48.757215 -391.992839) (xy 48.734847 -391.949633)
			(xy 48.719604 -391.903429) (xy 48.711872 -391.855394) (xy 48.711358 -391.831068) (xy 48.711358 -391.830814)
			(xy 48.71188 -391.805559) (xy 48.720193 -391.755737) (xy 48.736594 -391.707963) (xy 48.760635 -391.66354)
			(xy 48.791659 -391.62368) (xy 48.828821 -391.58947) (xy 48.871107 -391.561844) (xy 48.917363 -391.541554)
			(xy 48.966328 -391.529154) (xy 49.016666 -391.524983) (xy 49.067004 -391.529154) (xy 49.115969 -391.541554)
			(xy 49.162225 -391.561844) (xy 49.204511 -391.58947) (xy 49.241673 -391.62368) (xy 49.272697 -391.66354)
			(xy 49.296738 -391.707963) (xy 49.313139 -391.755737) (xy 49.321452 -391.805559) (xy 49.321974 -391.830814)
			(xy 49.321496 -391.855216) (xy 49.313736 -391.903398) (xy 49.298418 -391.949735) (xy 49.275929 -391.993048)
			(xy 49.261776 -392.012932) (xy 49.256188 -392.020298) (xy 49.251108 -392.038586) (xy 49.258474 -392.115548)
			(xy 49.259686 -392.124873) (xy 49.268037 -392.141709) (xy 49.27473 -392.148314) (xy 49.293776 -392.166449)
			(xy 49.32721 -392.207044) (xy 49.354755 -392.251843) (xy 49.375891 -392.299999) (xy 49.390218 -392.3506)
			(xy 49.397466 -392.402689) (xy 49.39792 -392.428984) (xy 49.39792 -393.293092) (xy 49.397351 -393.323216)
			(xy 49.387879 -393.382714) (xy 49.369168 -393.439982) (xy 49.341685 -393.493595) (xy 49.306113 -393.54222)
			(xy 49.285144 -393.563856) (xy 49.27854 -393.57046) (xy 49.27092 -393.587224) (xy 49.266094 -393.663932)
			(xy 49.265904 -393.673208) (xy 49.271381 -393.690918) (xy 49.276762 -393.698476) (xy 49.295122 -393.722988)
			(xy 49.323377 -393.777317) (xy 49.332896 -393.806426) (xy 49.337722 -393.822682) (xy 49.364646 -393.842494)
			(xy 49.8602 -393.842494) (xy 49.870471 -393.842024) (xy 49.889371 -393.833974) (xy 49.903604 -393.819161)
			(xy 49.907698 -393.809728) (xy 49.918314 -393.783502) (xy 49.947178 -393.734845) (xy 49.965102 -393.712954)
			(xy 49.971452 -393.705334) (xy 49.977802 -393.687046) (xy 49.97323 -393.606782) (xy 49.972209 -393.597068)
			(xy 49.963845 -393.579435) (xy 49.956974 -393.572492) (xy 49.938074 -393.554379) (xy 49.90491 -393.513874)
			(xy 49.87759 -393.469218) (xy 49.856626 -393.421249) (xy 49.842413 -393.370865) (xy 49.835215 -393.319013)
			(xy 49.8348 -393.292838) (xy 49.8348 -392.429238) (xy 49.835243 -392.40288) (xy 49.842499 -392.350667)
			(xy 49.856879 -392.29995) (xy 49.878109 -392.251698) (xy 49.905783 -392.206831) (xy 49.939373 -392.166203)
			(xy 49.958498 -392.14806) (xy 49.965356 -392.14171) (xy 49.973738 -392.124946) (xy 49.981104 -392.047476)
			(xy 49.981597 -392.038302) (xy 49.976789 -392.020584) (xy 49.971706 -392.012932) (xy 49.971452 -392.012678)
			(xy 49.957295 -391.992833) (xy 49.934808 -391.949585) (xy 49.91949 -391.90331) (xy 49.911731 -391.855186)
			(xy 49.911254 -391.830814) (xy 49.911776 -391.805559) (xy 49.920089 -391.755737) (xy 49.93649 -391.707963)
			(xy 49.960531 -391.66354) (xy 49.991555 -391.62368) (xy 50.028717 -391.58947) (xy 50.071003 -391.561844)
			(xy 50.117259 -391.541554) (xy 50.166224 -391.529154) (xy 50.216562 -391.524983) (xy 50.2669 -391.529154)
			(xy 50.315865 -391.541554) (xy 50.362121 -391.561844) (xy 50.404407 -391.58947) (xy 50.441569 -391.62368)
			(xy 50.472593 -391.66354) (xy 50.496634 -391.707963) (xy 50.513035 -391.755737) (xy 50.521348 -391.805559)
			(xy 50.52187 -391.830814) (xy 50.521402 -391.855145) (xy 50.513686 -391.90319) (xy 50.498436 -391.949399)
			(xy 50.47604 -391.9926) (xy 50.461926 -392.012424) (xy 50.461418 -392.012932) (xy 50.456084 -392.020298)
			(xy 50.451258 -392.038332) (xy 50.458624 -392.115548) (xy 50.459872 -392.124767) (xy 50.468092 -392.141436)
			(xy 50.474626 -392.14806) (xy 50.49375 -392.166201) (xy 50.527325 -392.206838) (xy 50.554988 -392.251708)
			(xy 50.576212 -392.299959) (xy 50.590592 -392.350672) (xy 50.597856 -392.402882) (xy 50.598324 -392.429238)
			(xy 50.598324 -393.292838) (xy 50.597876 -393.319012) (xy 50.590691 -393.370865) (xy 50.576487 -393.42125)
			(xy 50.555531 -393.469221) (xy 50.528216 -393.513879) (xy 50.495056 -393.554385) (xy 50.47615 -393.572492)
			(xy 50.469287 -393.579439) (xy 50.460934 -393.597072) (xy 50.459894 -393.606782) (xy 50.455322 -393.687046)
			(xy 50.461672 -393.705334) (xy 50.468022 -393.712954) (xy 50.48593 -393.734856) (xy 50.514784 -393.783514)
			(xy 50.525426 -393.809728) (xy 50.529513 -393.819163) (xy 50.54375 -393.833972) (xy 50.562652 -393.842016)
			(xy 50.572924 -393.842494) (xy 51.044602 -393.842494) (xy 51.056037 -393.841864) (xy 51.076656 -393.831969)
			(xy 51.090965 -393.814128) (xy 51.094132 -393.803124) (xy 51.099413 -393.781866) (xy 51.114817 -393.740861)
			(xy 51.135479 -393.702238) (xy 51.14798 -393.684252) (xy 51.14798 -393.683744) (xy 51.15306 -393.676632)
			(xy 51.157886 -393.660122) (xy 51.15306 -393.586716) (xy 51.15213 -393.57797) (xy 51.145117 -393.561855)
			(xy 51.139344 -393.55522) (xy 51.13909 -393.554966) (xy 51.119606 -393.533594) (xy 51.086659 -393.486068)
			(xy 51.061263 -393.434113) (xy 51.044 -393.378919) (xy 51.035265 -393.321753) (xy 51.034696 -393.292838)
			(xy 51.034696 -392.429238) (xy 51.035139 -392.40288) (xy 51.042395 -392.350666) (xy 51.056775 -392.29995)
			(xy 51.078004 -392.251698) (xy 51.105678 -392.20683) (xy 51.139268 -392.166203) (xy 51.158394 -392.14806)
			(xy 51.165252 -392.14171) (xy 51.173634 -392.124946) (xy 51.181 -392.047476) (xy 51.181493 -392.038302)
			(xy 51.176685 -392.020584) (xy 51.171602 -392.012932) (xy 51.171348 -392.012678) (xy 51.157191 -391.992833)
			(xy 51.134705 -391.949585) (xy 51.119387 -391.90331) (xy 51.111628 -391.855186) (xy 51.11115 -391.830814)
			(xy 51.111672 -391.805559) (xy 51.119985 -391.755737) (xy 51.136386 -391.707963) (xy 51.160427 -391.66354)
			(xy 51.191451 -391.62368) (xy 51.228613 -391.58947) (xy 51.270899 -391.561844) (xy 51.317155 -391.541554)
			(xy 51.36612 -391.529154) (xy 51.416458 -391.524983) (xy 51.466796 -391.529154) (xy 51.515761 -391.541554)
			(xy 51.562017 -391.561844) (xy 51.604303 -391.58947) (xy 51.641465 -391.62368) (xy 51.672489 -391.66354)
			(xy 51.69653 -391.707963) (xy 51.712931 -391.755737) (xy 51.721244 -391.805559) (xy 51.721766 -391.830814)
			(xy 51.721298 -391.855145) (xy 51.713582 -391.90319) (xy 51.698332 -391.949399) (xy 51.675935 -391.9926)
			(xy 51.661822 -392.012424) (xy 51.661314 -392.012932) (xy 51.65598 -392.020298) (xy 51.651154 -392.038332)
			(xy 51.65852 -392.115548) (xy 51.659768 -392.124767) (xy 51.667988 -392.141437) (xy 51.674522 -392.14806)
			(xy 51.693646 -392.166201) (xy 51.727222 -392.206837) (xy 51.754885 -392.251708) (xy 51.776109 -392.299959)
			(xy 51.790489 -392.350672) (xy 51.797753 -392.402882) (xy 51.79822 -392.429238) (xy 51.79822 -393.292838)
			(xy 51.797663 -393.321751) (xy 51.788899 -393.37891) (xy 51.771623 -393.434097) (xy 51.746228 -393.48605)
			(xy 51.713295 -393.533583) (xy 51.693826 -393.554966) (xy 51.693572 -393.55522) (xy 51.687825 -393.561873)
			(xy 51.680797 -393.577976) (xy 51.679856 -393.586716) (xy 51.675792 -393.651232) (xy 51.675534 -393.659933)
			(xy 51.680209 -393.676688) (xy 51.684936 -393.683998) (xy 51.697456 -393.702021) (xy 51.718144 -393.740722)
			(xy 51.733538 -393.781816) (xy 51.738784 -393.803124) (xy 51.742848 -393.820396) (xy 51.770534 -393.842494)
			(xy 52.260246 -393.842494) (xy 52.270512 -393.842016) (xy 52.289397 -393.833956) (xy 52.303616 -393.819142)
			(xy 52.307744 -393.809728) (xy 52.318362 -393.783503) (xy 52.347228 -393.734848) (xy 52.365148 -393.712954)
			(xy 52.371498 -393.705334) (xy 52.377848 -393.687046) (xy 52.373276 -393.606782) (xy 52.372257 -393.597066)
			(xy 52.363898 -393.579429) (xy 52.35702 -393.572492) (xy 52.33815 -393.554365) (xy 52.305048 -393.513841)
			(xy 52.277788 -393.469177) (xy 52.256883 -393.421209) (xy 52.242722 -393.370836) (xy 52.235573 -393.319001)
			(xy 52.2351 -393.292838) (xy 52.2351 -392.428984) (xy 52.235538 -392.402655) (xy 52.242772 -392.350496)
			(xy 52.257115 -392.299829) (xy 52.278294 -392.251617) (xy 52.305905 -392.206778) (xy 52.339424 -392.166166)
			(xy 52.358544 -392.14806) (xy 52.365402 -392.14171) (xy 52.373784 -392.124946) (xy 52.38115 -392.047476)
			(xy 52.381643 -392.038301) (xy 52.376839 -392.020581) (xy 52.371752 -392.012932) (xy 52.371498 -392.012678)
			(xy 52.357339 -391.992834) (xy 52.334849 -391.949586) (xy 52.319529 -391.903311) (xy 52.311769 -391.855187)
			(xy 52.3113 -391.830814) (xy 52.311822 -391.805559) (xy 52.320135 -391.755737) (xy 52.336536 -391.707963)
			(xy 52.360577 -391.66354) (xy 52.391601 -391.62368) (xy 52.428763 -391.58947) (xy 52.471049 -391.561844)
			(xy 52.517305 -391.541554) (xy 52.56627 -391.529154) (xy 52.616608 -391.524983) (xy 52.666946 -391.529154)
			(xy 52.715911 -391.541554) (xy 52.762167 -391.561844) (xy 52.804453 -391.58947) (xy 52.841615 -391.62368)
			(xy 52.872639 -391.66354) (xy 52.89668 -391.707963) (xy 52.913081 -391.755737) (xy 52.921394 -391.805559)
			(xy 52.921916 -391.830814) (xy 52.921448 -391.855145) (xy 52.913733 -391.903191) (xy 52.898485 -391.949402)
			(xy 52.876091 -391.992604) (xy 52.861972 -392.012424) (xy 52.861464 -392.012932) (xy 52.85613 -392.020298)
			(xy 52.851304 -392.038332) (xy 52.85867 -392.115548) (xy 52.859916 -392.124768) (xy 52.86813 -392.141444)
			(xy 52.874672 -392.14806) (xy 52.893756 -392.166198) (xy 52.927259 -392.206815) (xy 52.95486 -392.25165)
			(xy 52.976038 -392.299854) (xy 52.990389 -392.35051) (xy 52.997641 -392.402659) (xy 52.998116 -392.428984)
			(xy 52.998116 -393.292838) (xy 52.997689 -393.319004) (xy 52.990547 -393.370846) (xy 52.976387 -393.421227)
			(xy 52.955477 -393.469199) (xy 52.928207 -393.513865) (xy 52.89509 -393.554385) (xy 52.876196 -393.572492)
			(xy 52.869339 -393.579442) (xy 52.860995 -393.597075) (xy 52.85994 -393.606782) (xy 52.855368 -393.687046)
			(xy 52.861718 -393.705334) (xy 52.868068 -393.712954) (xy 52.885979 -393.734854) (xy 52.914837 -393.783511)
			(xy 52.925472 -393.809728) (xy 52.929556 -393.819169) (xy 52.94379 -393.833994) (xy 52.962694 -393.842057)
			(xy 52.97297 -393.842494) (xy 53.460142 -393.842494) (xy 53.470409 -393.842016) (xy 53.489295 -393.833957)
			(xy 53.503515 -393.819144) (xy 53.50764 -393.809728) (xy 53.518257 -393.783503) (xy 53.547124 -393.734848)
			(xy 53.565044 -393.712954) (xy 53.571394 -393.705334) (xy 53.577744 -393.687046) (xy 53.573172 -393.606782)
			(xy 53.572152 -393.597067) (xy 53.563793 -393.57943) (xy 53.556916 -393.572492) (xy 53.538046 -393.554365)
			(xy 53.504944 -393.51384) (xy 53.477685 -393.469176) (xy 53.45678 -393.421208) (xy 53.44262 -393.370835)
			(xy 53.43547 -393.319001) (xy 53.434996 -393.292838) (xy 53.434996 -392.428984) (xy 53.435434 -392.402656)
			(xy 53.44267 -392.350498) (xy 53.457016 -392.299833) (xy 53.478198 -392.251625) (xy 53.505814 -392.206791)
			(xy 53.539338 -392.166185) (xy 53.55844 -392.14806) (xy 53.565298 -392.14171) (xy 53.57368 -392.124946)
			(xy 53.581046 -392.047476) (xy 53.581539 -392.038301) (xy 53.576735 -392.020582) (xy 53.571648 -392.012932)
			(xy 53.571394 -392.012678) (xy 53.557235 -391.992834) (xy 53.534745 -391.949586) (xy 53.519425 -391.903311)
			(xy 53.511665 -391.855187) (xy 53.511196 -391.830814) (xy 53.511718 -391.805559) (xy 53.520031 -391.755737)
			(xy 53.536432 -391.707963) (xy 53.560473 -391.66354) (xy 53.591497 -391.62368) (xy 53.628659 -391.58947)
			(xy 53.670945 -391.561844) (xy 53.717201 -391.541554) (xy 53.766166 -391.529154) (xy 53.816504 -391.524983)
			(xy 53.866842 -391.529154) (xy 53.915807 -391.541554) (xy 53.962063 -391.561844) (xy 54.004349 -391.58947)
			(xy 54.041511 -391.62368) (xy 54.072535 -391.66354) (xy 54.096576 -391.707963) (xy 54.112977 -391.755737)
			(xy 54.12129 -391.805559) (xy 54.121812 -391.830814) (xy 54.121344 -391.855145) (xy 54.113629 -391.903191)
			(xy 54.098381 -391.949401) (xy 54.075987 -391.992604) (xy 54.061868 -392.012424) (xy 54.06136 -392.012932)
			(xy 54.056026 -392.020298) (xy 54.0512 -392.038332) (xy 54.058566 -392.115548) (xy 54.059812 -392.124768)
			(xy 54.068025 -392.141444) (xy 54.074568 -392.14806) (xy 54.093653 -392.166198) (xy 54.127155 -392.206814)
			(xy 54.154757 -392.25165) (xy 54.175935 -392.299853) (xy 54.190286 -392.35051) (xy 54.197538 -392.402659)
			(xy 54.198012 -392.428984) (xy 54.198012 -393.292838) (xy 54.197585 -393.319004) (xy 54.190443 -393.370846)
			(xy 54.176283 -393.421226) (xy 54.155372 -393.469199) (xy 54.128102 -393.513864) (xy 54.094985 -393.554384)
			(xy 54.076092 -393.572492) (xy 54.069236 -393.579442) (xy 54.060892 -393.597075) (xy 54.059836 -393.606782)
			(xy 54.055264 -393.687046) (xy 54.061614 -393.705334) (xy 54.067964 -393.712954) (xy 54.085875 -393.734854)
			(xy 54.114733 -393.783511) (xy 54.125368 -393.809728) (xy 54.129451 -393.81917) (xy 54.143686 -393.833995)
			(xy 54.16259 -393.842059) (xy 54.172866 -393.842494) (xy 54.644798 -393.842494) (xy 54.656234 -393.841864)
			(xy 54.676854 -393.83197) (xy 54.691165 -393.814129) (xy 54.694328 -393.803124) (xy 54.699609 -393.781866)
			(xy 54.715012 -393.740861) (xy 54.735674 -393.702238) (xy 54.748176 -393.684252) (xy 54.748176 -393.683744)
			(xy 54.753256 -393.676632) (xy 54.758082 -393.660122) (xy 54.753256 -393.586716) (xy 54.752326 -393.57797)
			(xy 54.745312 -393.561856) (xy 54.73954 -393.55522) (xy 54.739286 -393.554966) (xy 54.719803 -393.533594)
			(xy 54.686856 -393.486068) (xy 54.66146 -393.434112) (xy 54.644197 -393.378919) (xy 54.635462 -393.321753)
			(xy 54.634892 -393.292838) (xy 54.634892 -392.429238) (xy 54.635335 -392.40288) (xy 54.642591 -392.350666)
			(xy 54.656971 -392.29995) (xy 54.6782 -392.251698) (xy 54.705874 -392.20683) (xy 54.739464 -392.166202)
			(xy 54.75859 -392.14806) (xy 54.765448 -392.14171) (xy 54.77383 -392.124946) (xy 54.781196 -392.047476)
			(xy 54.781689 -392.038302) (xy 54.776881 -392.020584) (xy 54.771798 -392.012932) (xy 54.771544 -392.012678)
			(xy 54.757387 -391.992833) (xy 54.734901 -391.949585) (xy 54.719584 -391.903309) (xy 54.711825 -391.855186)
			(xy 54.711346 -391.830814) (xy 54.711868 -391.805559) (xy 54.720181 -391.755737) (xy 54.736582 -391.707963)
			(xy 54.760623 -391.66354) (xy 54.791647 -391.62368) (xy 54.828809 -391.58947) (xy 54.871095 -391.561844)
			(xy 54.917351 -391.541554) (xy 54.966316 -391.529154) (xy 55.016654 -391.524983) (xy 55.066992 -391.529154)
			(xy 55.115957 -391.541554) (xy 55.162213 -391.561844) (xy 55.204499 -391.58947) (xy 55.241661 -391.62368)
			(xy 55.272685 -391.66354) (xy 55.296726 -391.707963) (xy 55.313127 -391.755737) (xy 55.32144 -391.805559)
			(xy 55.321962 -391.830814) (xy 55.321494 -391.855145) (xy 55.313778 -391.90319) (xy 55.298528 -391.949399)
			(xy 55.276131 -391.992599) (xy 55.262018 -392.012424) (xy 55.26151 -392.012932) (xy 55.256176 -392.020298)
			(xy 55.25135 -392.038332) (xy 55.258716 -392.115548) (xy 55.259964 -392.124767) (xy 55.268183 -392.141437)
			(xy 55.274718 -392.14806) (xy 55.293843 -392.166201) (xy 55.327418 -392.206837) (xy 55.355082 -392.251708)
			(xy 55.376306 -392.299959) (xy 55.390687 -392.350672) (xy 55.39795 -392.402882) (xy 55.398416 -392.429238)
			(xy 55.398416 -393.292838) (xy 55.397859 -393.321751) (xy 55.389095 -393.37891) (xy 55.371818 -393.434096)
			(xy 55.346424 -393.486049) (xy 55.313491 -393.533582) (xy 55.294022 -393.554966) (xy 55.293768 -393.55522)
			(xy 55.288021 -393.561873) (xy 55.280994 -393.577976) (xy 55.280052 -393.586716) (xy 55.275988 -393.651232)
			(xy 55.27573 -393.659933) (xy 55.280405 -393.676689) (xy 55.285132 -393.683998) (xy 55.297652 -393.702021)
			(xy 55.31834 -393.740721) (xy 55.333734 -393.781816) (xy 55.33898 -393.803124) (xy 55.343044 -393.820396)
			(xy 55.37073 -393.842494) (xy 55.868316 -393.842494) (xy 55.89524 -393.822682) (xy 55.900066 -393.806426)
			(xy 55.909594 -393.777321) (xy 55.937852 -393.722996) (xy 55.9562 -393.698476) (xy 55.961592 -393.690925)
			(xy 55.967051 -393.673209) (xy 55.966868 -393.663932) (xy 55.962042 -393.587224) (xy 55.954422 -393.57046)
			(xy 55.947818 -393.563856) (xy 55.926797 -393.542223) (xy 55.891164 -393.493557) (xy 55.863631 -393.439891)
			(xy 55.844884 -393.382561) (xy 55.835389 -393.322996) (xy 55.834788 -393.292838) (xy 55.834788 -392.429238)
			(xy 55.835231 -392.40288) (xy 55.842487 -392.350666) (xy 55.856867 -392.29995) (xy 55.878096 -392.251697)
			(xy 55.905769 -392.206829) (xy 55.939359 -392.166201) (xy 55.958486 -392.14806) (xy 55.965344 -392.14171)
			(xy 55.973726 -392.124946) (xy 55.981092 -392.047476) (xy 55.981585 -392.038302) (xy 55.976776 -392.020584)
			(xy 55.971694 -392.012932) (xy 55.97144 -392.012678) (xy 55.957283 -391.992833) (xy 55.934798 -391.949585)
			(xy 55.91948 -391.903309) (xy 55.911722 -391.855186) (xy 55.911242 -391.830814) (xy 55.911764 -391.805559)
			(xy 55.920077 -391.755737) (xy 55.936478 -391.707963) (xy 55.960519 -391.66354) (xy 55.991543 -391.62368)
			(xy 56.028705 -391.58947) (xy 56.070991 -391.561844) (xy 56.117247 -391.541554) (xy 56.166212 -391.529154)
			(xy 56.21655 -391.524983) (xy 56.266888 -391.529154) (xy 56.315853 -391.541554) (xy 56.362109 -391.561844)
			(xy 56.404395 -391.58947) (xy 56.441557 -391.62368) (xy 56.472581 -391.66354) (xy 56.496622 -391.707963)
			(xy 56.513023 -391.755737) (xy 56.521336 -391.805559) (xy 56.521858 -391.830814) (xy 56.52139 -391.855145)
			(xy 56.513674 -391.90319) (xy 56.498423 -391.949399) (xy 56.476026 -391.992599) (xy 56.461914 -392.012424)
			(xy 56.461406 -392.012932) (xy 56.456072 -392.020298) (xy 56.451246 -392.038332) (xy 56.458612 -392.115548)
			(xy 56.45986 -392.124767) (xy 56.468078 -392.141438) (xy 56.474614 -392.14806) (xy 56.493739 -392.166201)
			(xy 56.527315 -392.206837) (xy 56.554979 -392.251708) (xy 56.576203 -392.299959) (xy 56.590584 -392.350672)
			(xy 56.597848 -392.402882) (xy 56.598312 -392.429238) (xy 56.598312 -393.292838) (xy 56.597744 -393.322999)
			(xy 56.588256 -393.38257) (xy 56.569508 -393.439905) (xy 56.541966 -393.493572) (xy 56.506318 -393.542234)
			(xy 56.485282 -393.563856) (xy 56.478678 -393.57046) (xy 56.471058 -393.587224) (xy 56.466232 -393.663932)
			(xy 56.466042 -393.673207) (xy 56.471522 -393.690915) (xy 56.4769 -393.698476) (xy 56.495259 -393.722989)
			(xy 56.52351 -393.777319) (xy 56.533034 -393.806426) (xy 56.53786 -393.822682) (xy 56.564784 -393.842494)
			(xy 57.060338 -393.842494) (xy 57.070605 -393.842017) (xy 57.089492 -393.833959) (xy 57.103714 -393.819146)
			(xy 57.107836 -393.809728) (xy 57.118453 -393.783503) (xy 57.147319 -393.734848) (xy 57.16524 -393.712954)
			(xy 57.17159 -393.705334) (xy 57.17794 -393.687046) (xy 57.173368 -393.606782) (xy 57.172348 -393.597067)
			(xy 57.163988 -393.57943) (xy 57.157112 -393.572492) (xy 57.138242 -393.554364) (xy 57.105141 -393.51384)
			(xy 57.077882 -393.469176) (xy 57.056977 -393.421208) (xy 57.042817 -393.370835) (xy 57.035667 -393.319001)
			(xy 57.035192 -393.292838) (xy 57.035192 -392.428984) (xy 57.035628 -392.402685) (xy 57.042847 -392.350586)
			(xy 57.057161 -392.299974) (xy 57.078297 -392.25181) (xy 57.105853 -392.20701) (xy 57.139307 -392.166423)
			(xy 57.158382 -392.148314) (xy 57.164995 -392.14165) (xy 57.17333 -392.124845) (xy 57.174638 -392.115548)
			(xy 57.182004 -392.038586) (xy 57.176924 -392.020298) (xy 57.171336 -392.012932) (xy 57.157175 -391.993053)
			(xy 57.134684 -391.949739) (xy 57.119364 -391.903401) (xy 57.111604 -391.855217) (xy 57.111138 -391.830814)
			(xy 57.11166 -391.805559) (xy 57.119973 -391.755737) (xy 57.136374 -391.707963) (xy 57.160415 -391.66354)
			(xy 57.191439 -391.62368) (xy 57.228601 -391.58947) (xy 57.270887 -391.561844) (xy 57.317143 -391.541554)
			(xy 57.366108 -391.529154) (xy 57.416446 -391.524983) (xy 57.466784 -391.529154) (xy 57.515749 -391.541554)
			(xy 57.562005 -391.561844) (xy 57.604291 -391.58947) (xy 57.641453 -391.62368) (xy 57.672477 -391.66354)
			(xy 57.696518 -391.707963) (xy 57.712919 -391.755737) (xy 57.721232 -391.805559) (xy 57.721754 -391.830814)
			(xy 57.721754 -391.831068) (xy 57.721282 -391.855397) (xy 57.713558 -391.903438) (xy 57.698301 -391.949642)
			(xy 57.675898 -391.992837) (xy 57.66181 -392.012678) (xy 57.656222 -392.020044) (xy 57.651142 -392.038332)
			(xy 57.658508 -392.115294) (xy 57.659729 -392.124614) (xy 57.668094 -392.141434) (xy 57.674764 -392.14806)
			(xy 57.693849 -392.166198) (xy 57.727352 -392.206814) (xy 57.754954 -392.251649) (xy 57.776132 -392.299853)
			(xy 57.790483 -392.35051) (xy 57.797736 -392.402659) (xy 57.798208 -392.428984) (xy 57.798208 -393.292838)
			(xy 57.797781 -393.319004) (xy 57.790639 -393.370846) (xy 57.776479 -393.421226) (xy 57.755568 -393.469199)
			(xy 57.728298 -393.513864) (xy 57.69518 -393.554384) (xy 57.676288 -393.572492) (xy 57.669432 -393.579442)
			(xy 57.661089 -393.597075) (xy 57.660032 -393.606782) (xy 57.65546 -393.687046) (xy 57.66181 -393.705334)
			(xy 57.66816 -393.712954) (xy 57.686071 -393.734854) (xy 57.71493 -393.783511) (xy 57.725564 -393.809728)
			(xy 57.729652 -393.819159) (xy 57.743891 -393.833958) (xy 57.762793 -393.841988) (xy 57.773062 -393.842494)
			(xy 58.260234 -393.842494) (xy 58.270501 -393.842018) (xy 58.28939 -393.83396) (xy 58.303613 -393.819147)
			(xy 58.307732 -393.809728) (xy 58.318349 -393.783503) (xy 58.347215 -393.734848) (xy 58.365136 -393.712954)
			(xy 58.371486 -393.705334) (xy 58.377836 -393.687046) (xy 58.373264 -393.606782) (xy 58.372244 -393.597067)
			(xy 58.363884 -393.579431) (xy 58.357008 -393.572492) (xy 58.338139 -393.554364) (xy 58.305037 -393.51384)
			(xy 58.277779 -393.469176) (xy 58.256874 -393.421208) (xy 58.242714 -393.370835) (xy 58.235564 -393.319001)
			(xy 58.235088 -393.292838) (xy 58.235088 -392.428984) (xy 58.235526 -392.402655) (xy 58.242762 -392.350498)
			(xy 58.257107 -392.299833) (xy 58.27829 -392.251624) (xy 58.305905 -392.20679) (xy 58.339429 -392.166183)
			(xy 58.358532 -392.14806) (xy 58.36539 -392.14171) (xy 58.373772 -392.124946) (xy 58.381138 -392.047476)
			(xy 58.381631 -392.038301) (xy 58.376827 -392.020582) (xy 58.37174 -392.012932) (xy 58.371486 -392.012678)
			(xy 58.357327 -391.992834) (xy 58.334838 -391.949586) (xy 58.319519 -391.903311) (xy 58.311759 -391.855187)
			(xy 58.311288 -391.830814) (xy 58.31181 -391.805559) (xy 58.320123 -391.755737) (xy 58.336524 -391.707963)
			(xy 58.360565 -391.66354) (xy 58.391589 -391.62368) (xy 58.428751 -391.58947) (xy 58.471037 -391.561844)
			(xy 58.517293 -391.541554) (xy 58.566258 -391.529154) (xy 58.616596 -391.524983) (xy 58.666934 -391.529154)
			(xy 58.715899 -391.541554) (xy 58.762155 -391.561844) (xy 58.804441 -391.58947) (xy 58.841603 -391.62368)
			(xy 58.872627 -391.66354) (xy 58.896668 -391.707963) (xy 58.913069 -391.755737) (xy 58.921382 -391.805559)
			(xy 58.921904 -391.830814) (xy 58.921436 -391.855145) (xy 58.913721 -391.903191) (xy 58.898472 -391.949401)
			(xy 58.876078 -391.992603) (xy 58.86196 -392.012424) (xy 58.861452 -392.012932) (xy 58.856118 -392.020298)
			(xy 58.851292 -392.038332) (xy 58.858658 -392.115548) (xy 58.859904 -392.124768) (xy 58.868116 -392.141445)
			(xy 58.87466 -392.14806) (xy 58.893745 -392.166198) (xy 58.927248 -392.206814) (xy 58.954851 -392.251649)
			(xy 58.976029 -392.299853) (xy 58.99038 -392.35051) (xy 58.997633 -392.402659) (xy 58.998104 -392.428984)
			(xy 58.998104 -393.292838) (xy 58.997677 -393.319004) (xy 58.990535 -393.370846) (xy 58.976375 -393.421226)
			(xy 58.955464 -393.469198) (xy 58.928193 -393.513863) (xy 58.895075 -393.554383) (xy 58.876184 -393.572492)
			(xy 58.869328 -393.579443) (xy 58.860986 -393.597075) (xy 58.859928 -393.606782) (xy 58.855356 -393.687046)
			(xy 58.861706 -393.705334) (xy 58.868056 -393.712954) (xy 58.885967 -393.734854) (xy 58.914826 -393.783511)
			(xy 58.92546 -393.809728) (xy 58.929548 -393.81916) (xy 58.943787 -393.833959) (xy 58.962689 -393.841991)
			(xy 58.972958 -393.842494) (xy 59.460384 -393.842494) (xy 59.470657 -393.842027) (xy 59.489562 -393.83398)
			(xy 59.5038 -393.819167) (xy 59.507882 -393.809728) (xy 59.518498 -393.783502) (xy 59.54736 -393.734844)
			(xy 59.565286 -393.712954) (xy 59.571636 -393.705334) (xy 59.577986 -393.687046) (xy 59.573414 -393.606782)
			(xy 59.572392 -393.597068) (xy 59.564026 -393.579438) (xy 59.557158 -393.572492) (xy 59.538258 -393.554378)
			(xy 59.505096 -393.513873) (xy 59.477777 -393.469217) (xy 59.456814 -393.421248) (xy 59.442601 -393.370865)
			(xy 59.435404 -393.319012) (xy 59.434984 -393.292838) (xy 59.434984 -392.429238) (xy 59.435449 -392.402915)
			(xy 59.442726 -392.350773) (xy 59.457092 -392.300125) (xy 59.478276 -392.251928) (xy 59.505875 -392.207095)
			(xy 59.539368 -392.166476) (xy 59.558428 -392.148314) (xy 59.565047 -392.141653) (xy 59.573391 -392.124848)
			(xy 59.574684 -392.115548) (xy 59.58205 -392.038586) (xy 59.57697 -392.020298) (xy 59.571382 -392.012932)
			(xy 59.557219 -391.993054) (xy 59.534725 -391.949741) (xy 59.519402 -391.903402) (xy 59.511641 -391.855217)
			(xy 59.511184 -391.830814) (xy 59.511706 -391.805559) (xy 59.520019 -391.755737) (xy 59.53642 -391.707963)
			(xy 59.560461 -391.66354) (xy 59.591485 -391.62368) (xy 59.628647 -391.58947) (xy 59.670933 -391.561844)
			(xy 59.717189 -391.541554) (xy 59.766154 -391.529154) (xy 59.816492 -391.524983) (xy 59.86683 -391.529154)
			(xy 59.915795 -391.541554) (xy 59.962051 -391.561844) (xy 60.004337 -391.58947) (xy 60.041499 -391.62368)
			(xy 60.072523 -391.66354) (xy 60.096564 -391.707963) (xy 60.112965 -391.755737) (xy 60.121278 -391.805559)
			(xy 60.1218 -391.830814) (xy 60.1218 -391.831068) (xy 60.121328 -391.855397) (xy 60.113605 -391.903439)
			(xy 60.09835 -391.949645) (xy 60.07595 -391.992841) (xy 60.061856 -392.012678) (xy 60.056268 -392.020044)
			(xy 60.051188 -392.038332) (xy 60.058554 -392.115294) (xy 60.059773 -392.124616) (xy 60.068132 -392.141442)
			(xy 60.07481 -392.14806) (xy 60.093935 -392.166201) (xy 60.127511 -392.206837) (xy 60.155175 -392.251707)
			(xy 60.1764 -392.299958) (xy 60.190781 -392.350672) (xy 60.198045 -392.402882) (xy 60.198508 -392.429238)
			(xy 60.198508 -393.292838) (xy 60.19806 -393.319012) (xy 60.190874 -393.370865) (xy 60.17667 -393.421249)
			(xy 60.155713 -393.46922) (xy 60.128398 -393.513877) (xy 60.095237 -393.554382) (xy 60.076334 -393.572492)
			(xy 60.069473 -393.57944) (xy 60.061123 -393.597073) (xy 60.060078 -393.606782) (xy 60.055506 -393.687046)
			(xy 60.061856 -393.705334) (xy 60.068206 -393.712954) (xy 60.086115 -393.734855) (xy 60.11497 -393.783514)
			(xy 60.12561 -393.809728) (xy 60.129696 -393.819165) (xy 60.143932 -393.833979) (xy 60.162835 -393.842028)
			(xy 60.173108 -393.842494) (xy 60.66028 -393.842494) (xy 60.670554 -393.842028) (xy 60.68946 -393.833981)
			(xy 60.703699 -393.819168) (xy 60.707778 -393.809728) (xy 60.718394 -393.783502) (xy 60.747256 -393.734844)
			(xy 60.765182 -393.712954) (xy 60.771532 -393.705334) (xy 60.777882 -393.687046) (xy 60.77331 -393.606782)
			(xy 60.772288 -393.597068) (xy 60.763922 -393.579438) (xy 60.757054 -393.572492) (xy 60.738155 -393.554378)
			(xy 60.704992 -393.513873) (xy 60.677674 -393.469217) (xy 60.656711 -393.421248) (xy 60.642499 -393.370865)
			(xy 60.635302 -393.319012) (xy 60.63488 -393.292838) (xy 60.63488 -392.429238) (xy 60.635323 -392.40288)
			(xy 60.642579 -392.350666) (xy 60.656959 -392.299949) (xy 60.678187 -392.251697) (xy 60.70586 -392.206828)
			(xy 60.739449 -392.166199) (xy 60.758578 -392.14806) (xy 60.765436 -392.14171) (xy 60.773818 -392.124946)
			(xy 60.781184 -392.047476) (xy 60.781677 -392.038302) (xy 60.776868 -392.020585) (xy 60.771786 -392.012932)
			(xy 60.771532 -392.012678) (xy 60.757376 -391.992833) (xy 60.734891 -391.949584) (xy 60.719574 -391.903309)
			(xy 60.711815 -391.855186) (xy 60.711334 -391.830814) (xy 60.711856 -391.805559) (xy 60.720169 -391.755737)
			(xy 60.73657 -391.707963) (xy 60.760611 -391.66354) (xy 60.791635 -391.62368) (xy 60.828797 -391.58947)
			(xy 60.871083 -391.561844) (xy 60.917339 -391.541554) (xy 60.966304 -391.529154) (xy 61.016642 -391.524983)
			(xy 61.06698 -391.529154) (xy 61.115945 -391.541554) (xy 61.162201 -391.561844) (xy 61.204487 -391.58947)
			(xy 61.241649 -391.62368) (xy 61.272673 -391.66354) (xy 61.296714 -391.707963) (xy 61.313115 -391.755737)
			(xy 61.321428 -391.805559) (xy 61.32195 -391.830814) (xy 61.321482 -391.855144) (xy 61.313766 -391.903189)
			(xy 61.298515 -391.949399) (xy 61.276117 -391.992598) (xy 61.262006 -392.012424) (xy 61.261498 -392.012932)
			(xy 61.256164 -392.020298) (xy 61.251338 -392.038332) (xy 61.258704 -392.115548) (xy 61.259952 -392.124767)
			(xy 61.268169 -392.141439) (xy 61.274706 -392.14806) (xy 61.293831 -392.166201) (xy 61.327408 -392.206837)
			(xy 61.355072 -392.251707) (xy 61.376297 -392.299958) (xy 61.390678 -392.350671) (xy 61.397942 -392.402882)
			(xy 61.398404 -392.429238) (xy 61.398404 -393.292838) (xy 61.397956 -393.319012) (xy 61.39077 -393.370865)
			(xy 61.376566 -393.421249) (xy 61.355609 -393.46922) (xy 61.328294 -393.513877) (xy 61.295132 -393.554382)
			(xy 61.27623 -393.572492) (xy 61.26937 -393.57944) (xy 61.26102 -393.597073) (xy 61.259974 -393.606782)
			(xy 61.255402 -393.687046) (xy 61.261752 -393.705334) (xy 61.268102 -393.712954) (xy 61.286011 -393.734855)
			(xy 61.314867 -393.783513) (xy 61.325506 -393.809728) (xy 61.329591 -393.819166) (xy 61.343828 -393.83398)
			(xy 61.362731 -393.842031) (xy 61.373004 -393.842494) (xy 61.844682 -393.842494) (xy 61.85612 -393.841868)
			(xy 61.876746 -393.831977) (xy 61.891062 -393.814134) (xy 61.894212 -393.803124) (xy 61.899493 -393.781866)
			(xy 61.914896 -393.740861) (xy 61.935556 -393.702237) (xy 61.94806 -393.684252) (xy 61.94806 -393.683744)
			(xy 61.95314 -393.676632) (xy 61.957966 -393.660122) (xy 61.95314 -393.586716) (xy 61.95221 -393.57797)
			(xy 61.945194 -393.561857) (xy 61.939424 -393.55522) (xy 61.93917 -393.554966) (xy 61.919687 -393.533594)
			(xy 61.886742 -393.486067) (xy 61.861347 -393.434112) (xy 61.844085 -393.378919) (xy 61.835351 -393.321753)
			(xy 61.834776 -393.292838) (xy 61.834776 -392.429238) (xy 61.835219 -392.40288) (xy 61.842475 -392.350666)
			(xy 61.856854 -392.299949) (xy 61.878083 -392.251696) (xy 61.905755 -392.206828) (xy 61.939345 -392.166199)
			(xy 61.958474 -392.14806) (xy 61.965332 -392.14171) (xy 61.973714 -392.124946) (xy 61.98108 -392.047476)
			(xy 61.981573 -392.038302) (xy 61.976763 -392.020585) (xy 61.971682 -392.012932) (xy 61.971428 -392.012678)
			(xy 61.957272 -391.992833) (xy 61.934787 -391.949584) (xy 61.91947 -391.903309) (xy 61.911712 -391.855186)
			(xy 61.91123 -391.830814) (xy 61.911752 -391.805559) (xy 61.920065 -391.755737) (xy 61.936466 -391.707963)
			(xy 61.960507 -391.66354) (xy 61.991531 -391.62368) (xy 62.028693 -391.58947) (xy 62.070979 -391.561844)
			(xy 62.117235 -391.541554) (xy 62.1662 -391.529154) (xy 62.216538 -391.524983) (xy 62.266876 -391.529154)
			(xy 62.315841 -391.541554) (xy 62.362097 -391.561844) (xy 62.404383 -391.58947) (xy 62.441545 -391.62368)
			(xy 62.472569 -391.66354) (xy 62.49661 -391.707963) (xy 62.513011 -391.755737) (xy 62.521324 -391.805559)
			(xy 62.521846 -391.830814) (xy 62.521378 -391.855144) (xy 62.513661 -391.903189) (xy 62.498411 -391.949398)
			(xy 62.476013 -391.992598) (xy 62.461902 -392.012424) (xy 62.461394 -392.012932) (xy 62.45606 -392.020298)
			(xy 62.451234 -392.038332) (xy 62.4586 -392.115548) (xy 62.459847 -392.124767) (xy 62.468064 -392.14144)
			(xy 62.474602 -392.14806) (xy 62.493727 -392.166201) (xy 62.527305 -392.206836) (xy 62.554969 -392.251707)
			(xy 62.576194 -392.299958) (xy 62.590575 -392.350671) (xy 62.597839 -392.402882) (xy 62.5983 -392.429238)
			(xy 62.5983 -393.292838) (xy 62.597743 -393.321751) (xy 62.588978 -393.37891) (xy 62.571701 -393.434095)
			(xy 62.546306 -393.486048) (xy 62.513372 -393.53358) (xy 62.493906 -393.554966) (xy 62.493652 -393.55522)
			(xy 62.487906 -393.561874) (xy 62.480882 -393.577977) (xy 62.479936 -393.586716) (xy 62.475872 -393.651232)
			(xy 62.475614 -393.659933) (xy 62.480287 -393.676689) (xy 62.485016 -393.683998) (xy 62.497537 -393.70202)
			(xy 62.518225 -393.740721) (xy 62.533621 -393.781815) (xy 62.538864 -393.803124) (xy 62.542928 -393.820396)
			(xy 62.570614 -393.842494) (xy 63.060072 -393.842494) (xy 63.070347 -393.842029) (xy 63.089255 -393.833984)
			(xy 63.103497 -393.819172) (xy 63.10757 -393.809728) (xy 63.118188 -393.783504) (xy 63.147057 -393.73485)
			(xy 63.164974 -393.712954) (xy 63.171324 -393.705334) (xy 63.177674 -393.687046) (xy 63.173102 -393.606782)
			(xy 63.17208 -393.597069) (xy 63.163713 -393.579439) (xy 63.156846 -393.572492) (xy 63.137947 -393.554378)
			(xy 63.104785 -393.513872) (xy 63.077467 -393.469216) (xy 63.056506 -393.421247) (xy 63.042293 -393.370864)
			(xy 63.035096 -393.319012) (xy 63.034672 -393.292838) (xy 63.034672 -392.429238) (xy 63.035115 -392.40288)
			(xy 63.042371 -392.350666) (xy 63.05675 -392.299949) (xy 63.077978 -392.251696) (xy 63.105651 -392.206827)
			(xy 63.13924 -392.166198) (xy 63.15837 -392.14806) (xy 63.165228 -392.14171) (xy 63.17361 -392.124946)
			(xy 63.180976 -392.047476) (xy 63.181469 -392.038302) (xy 63.176659 -392.020585) (xy 63.171578 -392.012932)
			(xy 63.171324 -392.012678) (xy 63.157168 -391.992833) (xy 63.134684 -391.949584) (xy 63.119367 -391.903309)
			(xy 63.111609 -391.855186) (xy 63.111126 -391.830814) (xy 63.111648 -391.805559) (xy 63.119961 -391.755737)
			(xy 63.136362 -391.707963) (xy 63.160403 -391.66354) (xy 63.191427 -391.62368) (xy 63.228589 -391.58947)
			(xy 63.270875 -391.561844) (xy 63.317131 -391.541554) (xy 63.366096 -391.529154) (xy 63.416434 -391.524983)
			(xy 63.466772 -391.529154) (xy 63.515737 -391.541554) (xy 63.561993 -391.561844) (xy 63.604279 -391.58947)
			(xy 63.641441 -391.62368) (xy 63.672465 -391.66354) (xy 63.696506 -391.707963) (xy 63.712907 -391.755737)
			(xy 63.72122 -391.805559) (xy 63.721742 -391.830814) (xy 63.721274 -391.855144) (xy 63.713557 -391.903189)
			(xy 63.698306 -391.949398) (xy 63.675908 -391.992598) (xy 63.661798 -392.012424) (xy 63.66129 -392.012932)
			(xy 63.655956 -392.020298) (xy 63.65113 -392.038332) (xy 63.658496 -392.115548) (xy 63.659743 -392.124768)
			(xy 63.66796 -392.14144) (xy 63.674498 -392.14806) (xy 63.693623 -392.166201) (xy 63.727201 -392.206836)
			(xy 63.754866 -392.251706) (xy 63.776091 -392.299958) (xy 63.790473 -392.350671) (xy 63.797737 -392.402881)
			(xy 63.798196 -392.429238) (xy 63.798196 -393.292838) (xy 63.797748 -393.319012) (xy 63.790562 -393.370865)
			(xy 63.776357 -393.421249) (xy 63.7554 -393.469219) (xy 63.728085 -393.513876) (xy 63.694922 -393.55438)
			(xy 63.676022 -393.572492) (xy 63.669162 -393.579441) (xy 63.660814 -393.597073) (xy 63.659766 -393.606782)
			(xy 63.655194 -393.687046) (xy 63.661544 -393.705334) (xy 63.667894 -393.712954) (xy 63.685803 -393.734855)
			(xy 63.71466 -393.783513) (xy 63.725298 -393.809728) (xy 63.729383 -393.819166) (xy 63.743619 -393.833983)
			(xy 63.762522 -393.842037) (xy 63.772796 -393.842494) (xy 64.260222 -393.842494) (xy 64.270491 -393.84202)
			(xy 64.289383 -393.833965) (xy 64.30361 -393.819152) (xy 64.30772 -393.809728) (xy 64.318337 -393.783503)
			(xy 64.347202 -393.734847) (xy 64.365124 -393.712954) (xy 64.371474 -393.705334) (xy 64.377824 -393.687046)
			(xy 64.373252 -393.606782) (xy 64.372232 -393.597067) (xy 64.36387 -393.579432) (xy 64.356996 -393.572492)
			(xy 64.338127 -393.554364) (xy 64.305026 -393.51384) (xy 64.277769 -393.469175) (xy 64.256864 -393.421207)
			(xy 64.242705 -393.370835) (xy 64.235556 -393.319) (xy 64.235076 -393.292838) (xy 64.235076 -392.428984)
			(xy 64.235514 -392.402655) (xy 64.24275 -392.350498) (xy 64.257095 -392.299832) (xy 64.278277 -392.251623)
			(xy 64.305892 -392.206788) (xy 64.339415 -392.166181) (xy 64.35852 -392.14806) (xy 64.365378 -392.14171)
			(xy 64.37376 -392.124946) (xy 64.381126 -392.047476) (xy 64.381619 -392.038301) (xy 64.376814 -392.020583)
			(xy 64.371728 -392.012932) (xy 64.371474 -392.012678) (xy 64.357316 -391.992834) (xy 64.334828 -391.949586)
			(xy 64.319509 -391.90331) (xy 64.311749 -391.855187) (xy 64.311276 -391.830814) (xy 64.311798 -391.805559)
			(xy 64.320111 -391.755737) (xy 64.336512 -391.707963) (xy 64.360553 -391.66354) (xy 64.391577 -391.62368)
			(xy 64.428739 -391.58947) (xy 64.471025 -391.561844) (xy 64.517281 -391.541554) (xy 64.566246 -391.529154)
			(xy 64.616584 -391.524983) (xy 64.666922 -391.529154) (xy 64.715887 -391.541554) (xy 64.762143 -391.561844)
			(xy 64.804429 -391.58947) (xy 64.841591 -391.62368) (xy 64.872615 -391.66354) (xy 64.896656 -391.707963)
			(xy 64.913057 -391.755737) (xy 64.92137 -391.805559) (xy 64.921892 -391.830814) (xy 64.921424 -391.855145)
			(xy 64.913709 -391.90319) (xy 64.89846 -391.9494) (xy 64.876064 -391.992602) (xy 64.861948 -392.012424)
			(xy 64.86144 -392.012932) (xy 64.856106 -392.020298) (xy 64.85128 -392.038332) (xy 64.858646 -392.115548)
			(xy 64.859892 -392.124769) (xy 64.868102 -392.141447) (xy 64.874648 -392.14806) (xy 64.893733 -392.166198)
			(xy 64.927238 -392.206813) (xy 64.954841 -392.251648) (xy 64.97602 -392.299852) (xy 64.990372 -392.350509)
			(xy 64.997625 -392.402659) (xy 64.998092 -392.428984) (xy 64.998092 -393.292838) (xy 64.997665 -393.319004)
			(xy 64.990522 -393.370846) (xy 64.976362 -393.421225) (xy 64.955451 -393.469197) (xy 64.92818 -393.513862)
			(xy 64.895061 -393.55438) (xy 64.876172 -393.572492) (xy 64.869318 -393.579443) (xy 64.860978 -393.597076)
			(xy 64.859916 -393.606782) (xy 64.855344 -393.687046) (xy 64.861694 -393.705334) (xy 64.868044 -393.712954)
			(xy 64.885956 -393.734854) (xy 64.914816 -393.78351) (xy 64.925448 -393.809728) (xy 64.929535 -393.819161)
			(xy 64.943774 -393.833964) (xy 64.962676 -393.842) (xy 64.972946 -393.842494) (xy 65.468246 -393.842494)
			(xy 65.49517 -393.822682) (xy 65.499996 -393.806426) (xy 65.509525 -393.777322) (xy 65.537784 -393.722998)
			(xy 65.55613 -393.698476) (xy 65.561519 -393.690924) (xy 65.566975 -393.673209) (xy 65.566798 -393.663932)
			(xy 65.561972 -393.587224) (xy 65.554352 -393.57046) (xy 65.547748 -393.563856) (xy 65.526768 -393.542232)
			(xy 65.491209 -393.493598) (xy 65.463733 -393.439981) (xy 65.445022 -393.382712) (xy 65.435541 -393.323216)
			(xy 65.434972 -393.293092) (xy 65.434972 -392.428984) (xy 65.43541 -392.402655) (xy 65.442645 -392.350498)
			(xy 65.456991 -392.299832) (xy 65.478172 -392.251623) (xy 65.505787 -392.206788) (xy 65.53931 -392.16618)
			(xy 65.558416 -392.14806) (xy 65.565274 -392.14171) (xy 65.573656 -392.124946) (xy 65.581022 -392.047476)
			(xy 65.581515 -392.038301) (xy 65.576709 -392.020583) (xy 65.571624 -392.012932) (xy 65.57137 -392.012678)
			(xy 65.557212 -391.992834) (xy 65.534724 -391.949586) (xy 65.519405 -391.90331) (xy 65.511646 -391.855187)
			(xy 65.511172 -391.830814) (xy 65.511694 -391.805559) (xy 65.520007 -391.755737) (xy 65.536408 -391.707963)
			(xy 65.560449 -391.66354) (xy 65.591473 -391.62368) (xy 65.628635 -391.58947) (xy 65.670921 -391.561844)
			(xy 65.717177 -391.541554) (xy 65.766142 -391.529154) (xy 65.81648 -391.524983) (xy 65.866818 -391.529154)
			(xy 65.915783 -391.541554) (xy 65.962039 -391.561844) (xy 66.004325 -391.58947) (xy 66.041487 -391.62368)
			(xy 66.072511 -391.66354) (xy 66.096552 -391.707963) (xy 66.112953 -391.755737) (xy 66.121266 -391.805559)
			(xy 66.121788 -391.830814) (xy 66.12132 -391.855145) (xy 66.113604 -391.90319) (xy 66.098355 -391.9494)
			(xy 66.07596 -391.992602) (xy 66.061844 -392.012424) (xy 66.061336 -392.012932) (xy 66.056002 -392.020298)
			(xy 66.051176 -392.038332) (xy 66.058542 -392.115548) (xy 66.059787 -392.124769) (xy 66.067997 -392.141448)
			(xy 66.074544 -392.14806) (xy 66.09363 -392.166198) (xy 66.127134 -392.206813) (xy 66.154738 -392.251648)
			(xy 66.175917 -392.299852) (xy 66.190269 -392.350509) (xy 66.197522 -392.402659) (xy 66.197988 -392.428984)
			(xy 66.197988 -392.724737) (xy 67.384461 -392.724737) (xy 67.387066 -392.661703) (xy 67.397448 -392.599474)
			(xy 67.415448 -392.539008) (xy 67.440789 -392.481233) (xy 67.473082 -392.427036) (xy 67.511831 -392.37725)
			(xy 67.556441 -392.332639) (xy 67.606226 -392.293889) (xy 67.660422 -392.261594) (xy 67.718197 -392.236252)
			(xy 67.778663 -392.218251) (xy 67.840891 -392.207867) (xy 67.903925 -392.20526) (xy 67.966798 -392.210471)
			(xy 68.028544 -392.223418) (xy 68.088214 -392.243904) (xy 68.144891 -392.271614) (xy 68.197706 -392.306121)
			(xy 68.245847 -392.346897) (xy 68.288574 -392.393314) (xy 68.325231 -392.444659) (xy 68.355256 -392.500145)
			(xy 68.378187 -392.558919) (xy 68.393671 -392.620077) (xy 68.401472 -392.682682) (xy 68.401946 -392.714226)
			(xy 68.401411 -392.747119) (xy 68.392874 -392.81235) (xy 68.384928 -392.844274) (xy 68.381534 -392.859219)
			(xy 68.382844 -392.889825) (xy 68.39316 -392.918669) (xy 68.411556 -392.943163) (xy 68.436382 -392.96111)
			(xy 68.46541 -392.970897) (xy 68.496034 -392.971648) (xy 68.510912 -392.967972) (xy 68.536352 -392.96122)
			(xy 68.588482 -392.953955) (xy 68.614798 -392.953494) (xy 68.615306 -392.953494) (xy 68.642557 -392.953984)
			(xy 68.696503 -392.961741) (xy 68.748797 -392.977097) (xy 68.798373 -392.999738) (xy 68.844222 -393.029205)
			(xy 68.885411 -393.064896) (xy 68.921101 -393.106086) (xy 68.950566 -393.151936) (xy 68.973206 -393.201512)
			(xy 68.988561 -393.253806) (xy 68.996316 -393.307753) (xy 68.996316 -393.362254) (xy 68.988559 -393.416201)
			(xy 68.973204 -393.468494) (xy 68.950563 -393.51807) (xy 68.921097 -393.56392) (xy 68.885406 -393.605109)
			(xy 68.844216 -393.640799) (xy 68.798367 -393.670265) (xy 68.74879 -393.692905) (xy 68.696497 -393.70826)
			(xy 68.64255 -393.716016) (xy 68.588049 -393.716016) (xy 68.534102 -393.70826) (xy 68.481808 -393.692905)
			(xy 68.432232 -393.670264) (xy 68.386383 -393.640799) (xy 68.345193 -393.605108) (xy 68.309502 -393.563919)
			(xy 68.280036 -393.518069) (xy 68.257396 -393.468493) (xy 68.242041 -393.416199) (xy 68.234284 -393.362253)
			(xy 68.233798 -393.335002) (xy 68.233798 -393.334748) (xy 68.233903 -393.322714) (xy 68.235427 -393.298693)
			(xy 68.236846 -393.286742) (xy 68.238241 -393.271484) (xy 68.232882 -393.241331) (xy 68.218837 -393.214116)
			(xy 68.197363 -393.19228) (xy 68.170387 -393.17778) (xy 68.140328 -393.171918) (xy 68.109881 -393.175217)
			(xy 68.095622 -393.180824) (xy 68.063582 -393.194079) (xy 67.996802 -393.212738) (xy 67.928107 -393.22215)
			(xy 67.893438 -393.222734) (xy 67.861894 -393.222273) (xy 67.799289 -393.214473) (xy 67.73813 -393.19899)
			(xy 67.679356 -393.176061) (xy 67.62387 -393.146038) (xy 67.572523 -393.109381) (xy 67.526105 -393.066655)
			(xy 67.485328 -393.018516) (xy 67.45082 -392.965702) (xy 67.423109 -392.909025) (xy 67.402622 -392.849355)
			(xy 67.389673 -392.78761) (xy 67.384461 -392.724737) (xy 66.197988 -392.724737) (xy 66.197988 -393.293092)
			(xy 66.19742 -393.323216) (xy 66.187948 -393.382716) (xy 66.16924 -393.439986) (xy 66.14176 -393.493602)
			(xy 66.106193 -393.542232) (xy 66.085212 -393.563856) (xy 66.078608 -393.57046) (xy 66.070988 -393.587224)
			(xy 66.066162 -393.663932) (xy 66.065971 -393.673208) (xy 66.071445 -393.69092) (xy 66.07683 -393.698476)
			(xy 66.095192 -393.722987) (xy 66.123449 -393.777316) (xy 66.132964 -393.806426) (xy 66.13779 -393.822682)
			(xy 66.164714 -393.842494) (xy 69.165724 -393.842494) (xy 69.178139 -393.841871) (xy 69.200098 -393.830283)
			(xy 69.207634 -393.820396) (xy 69.26199 -393.740894) (xy 69.265038 -393.716002) (xy 69.260466 -393.704318)
			(xy 69.249616 -393.674974) (xy 69.234357 -393.6143) (xy 69.226667 -393.552212) (xy 69.226176 -393.52093)
			(xy 69.226637 -393.490209) (xy 69.234034 -393.429213) (xy 69.248724 -393.369553) (xy 69.270493 -393.312096)
			(xy 69.299024 -393.257679) (xy 69.316092 -393.232132) (xy 69.321492 -393.223447) (xy 69.325566 -393.203425)
			(xy 69.321512 -393.183399) (xy 69.316092 -393.174728) (xy 69.299035 -393.149174) (xy 69.270503 -393.094758)
			(xy 69.248733 -393.037303) (xy 69.234039 -392.977645) (xy 69.226637 -392.916651) (xy 69.226176 -392.88593)
			(xy 69.22662 -392.855196) (xy 69.234025 -392.794177) (xy 69.248732 -392.734495) (xy 69.270526 -392.677021)
			(xy 69.299088 -392.622593) (xy 69.334003 -392.572005) (xy 69.374761 -392.525994) (xy 69.420769 -392.485232)
			(xy 69.471354 -392.450312) (xy 69.525779 -392.421745) (xy 69.583251 -392.399946) (xy 69.642932 -392.385234)
			(xy 69.70395 -392.377823) (xy 69.734684 -392.377422) (xy 69.765405 -392.377884) (xy 69.826401 -392.385281)
			(xy 69.886061 -392.399971) (xy 69.943518 -392.42174) (xy 69.997935 -392.450269) (xy 70.023482 -392.467338)
			(xy 70.032167 -392.472731) (xy 70.052184 -392.476792) (xy 70.072201 -392.472731) (xy 70.080886 -392.467338)
			(xy 70.10644 -392.45028) (xy 70.160855 -392.421749) (xy 70.21831 -392.399978) (xy 70.277969 -392.385286)
			(xy 70.338963 -392.377886) (xy 70.400405 -392.377886) (xy 70.461399 -392.385286) (xy 70.521058 -392.399978)
			(xy 70.578513 -392.421749) (xy 70.632928 -392.45028) (xy 70.658482 -392.467338) (xy 70.667167 -392.472731)
			(xy 70.687184 -392.476792) (xy 70.707201 -392.472731) (xy 70.715886 -392.467338) (xy 70.74144 -392.45028)
			(xy 70.795855 -392.421748) (xy 70.85331 -392.399976) (xy 70.912969 -392.385283) (xy 70.973963 -392.377882)
			(xy 71.004684 -392.377422) (xy 71.025512 -392.37793) (xy 71.02602 -392.37793) (xy 71.036455 -392.377796)
			(xy 71.055869 -392.370194) (xy 71.063612 -392.363198) (xy 71.116952 -392.309858) (xy 71.12395 -392.302112)
			(xy 71.131574 -392.282703) (xy 71.131684 -392.272266) (xy 71.131684 -392.272012) (xy 71.131176 -392.25093)
			(xy 71.131637 -392.220209) (xy 71.139034 -392.159213) (xy 71.153724 -392.099553) (xy 71.175493 -392.042096)
			(xy 71.204024 -391.987679) (xy 71.221092 -391.962132) (xy 71.226492 -391.953447) (xy 71.230566 -391.933425)
			(xy 71.226512 -391.913399) (xy 71.221092 -391.904728) (xy 71.204035 -391.879174) (xy 71.175503 -391.824758)
			(xy 71.153733 -391.767303) (xy 71.139039 -391.707645) (xy 71.131637 -391.646651) (xy 71.131176 -391.61593)
			(xy 71.131714 -391.582703) (xy 71.140368 -391.516815) (xy 71.157533 -391.452617) (xy 71.182916 -391.391202)
			(xy 71.216083 -391.333617) (xy 71.256471 -391.280845) (xy 71.30339 -391.233784) (xy 71.35604 -391.193237)
			(xy 71.413524 -391.159896) (xy 71.474863 -391.134328) (xy 71.539009 -391.11697) (xy 71.571866 -391.111994)
			(xy 71.572374 -391.111994) (xy 71.583296 -391.11047) (xy 71.602092 -391.098278) (xy 71.65594 -391.013188)
			(xy 71.658734 -390.990836) (xy 71.655178 -390.980168) (xy 71.643919 -390.942491) (xy 71.631801 -390.864798)
			(xy 71.631048 -390.825482) (xy 71.631048 -390.825228) (xy 71.63151 -390.794495) (xy 71.638915 -390.733477)
			(xy 71.653622 -390.673796) (xy 71.675414 -390.616322) (xy 71.703975 -390.561895) (xy 71.738889 -390.511307)
			(xy 71.779645 -390.465296) (xy 71.82565 -390.424533) (xy 71.876233 -390.389613) (xy 71.930657 -390.361044)
			(xy 71.988127 -390.339243) (xy 72.047806 -390.324528) (xy 72.108823 -390.317114) (xy 72.139556 -390.31672)
			(xy 72.170278 -390.31718) (xy 72.231274 -390.324575) (xy 72.290937 -390.339262) (xy 72.348396 -390.361027)
			(xy 72.402815 -390.389555) (xy 72.428354 -390.406636) (xy 72.437039 -390.412029) (xy 72.457056 -390.41609)
			(xy 72.477073 -390.412029) (xy 72.485758 -390.406636) (xy 72.511312 -390.389576) (xy 72.565726 -390.361041)
			(xy 72.623181 -390.339267) (xy 72.68284 -390.324571) (xy 72.743835 -390.317166) (xy 72.774556 -390.31672)
			(xy 72.805289 -390.317163) (xy 72.866308 -390.324567) (xy 72.925989 -390.339273) (xy 72.983462 -390.361067)
			(xy 73.037889 -390.389629) (xy 73.088476 -390.424544) (xy 73.134486 -390.465303) (xy 73.175246 -390.511311)
			(xy 73.210163 -390.561897) (xy 73.238727 -390.616323) (xy 73.260522 -390.673795) (xy 73.27523 -390.733476)
			(xy 73.282636 -390.794495) (xy 73.283064 -390.825228) (xy 73.28249 -390.860073) (xy 73.272972 -390.929111)
			(xy 73.254118 -390.996203) (xy 73.226281 -391.060093) (xy 73.208642 -391.09015) (xy 73.204154 -391.098141)
			(xy 73.200628 -391.116111) (xy 73.201784 -391.125202) (xy 73.213214 -391.191242) (xy 73.215062 -391.200065)
			(xy 73.224057 -391.21567) (xy 73.23074 -391.221722) (xy 73.230994 -391.221976) (xy 73.253318 -391.240678)
			(xy 73.293976 -391.282377) (xy 73.329602 -391.32845) (xy 73.359729 -391.378293) (xy 73.372218 -391.404602)
			(xy 73.372218 -391.40511) (xy 73.378568 -391.418318) (xy 73.40346 -391.43432) (xy 73.510902 -391.43432)
			(xy 73.520579 -391.433886) (xy 73.538559 -391.426722) (xy 73.552637 -391.413439) (xy 73.55713 -391.404856)
			(xy 73.570764 -391.376153) (xy 73.604142 -391.322078) (xy 73.644001 -391.272587) (xy 73.689719 -391.228451)
			(xy 73.714864 -391.209022) (xy 73.721959 -391.203257) (xy 73.731842 -391.187892) (xy 73.734168 -391.17905)
			(xy 73.740518 -391.149078) (xy 73.74202 -391.14019) (xy 73.73943 -391.122361) (xy 73.735438 -391.11428)
			(xy 73.721051 -391.086238) (xy 73.700659 -391.026607) (xy 73.690346 -390.964435) (xy 73.689718 -390.932924)
			(xy 73.690195 -390.905556) (xy 73.698029 -390.851383) (xy 73.713525 -390.798886) (xy 73.736365 -390.749143)
			(xy 73.76608 -390.703175) (xy 73.783698 -390.682226) (xy 73.783698 -390.681972) (xy 73.783952 -390.681972)
			(xy 73.789538 -390.674886) (xy 73.795776 -390.657968) (xy 73.796144 -390.648952) (xy 73.796144 -390.581896)
			(xy 73.795785 -390.572879) (xy 73.789541 -390.555961) (xy 73.783952 -390.548876) (xy 73.783698 -390.548622)
			(xy 73.766055 -390.527691) (xy 73.736326 -390.481725) (xy 73.71348 -390.431978) (xy 73.697987 -390.379475)
			(xy 73.690166 -390.325295) (xy 73.689718 -390.297924) (xy 73.690204 -390.270673) (xy 73.69796 -390.216725)
			(xy 73.713315 -390.16443) (xy 73.735957 -390.114853) (xy 73.765423 -390.069003) (xy 73.801114 -390.027812)
			(xy 73.842305 -389.992121) (xy 73.888155 -389.962655) (xy 73.937732 -389.940013) (xy 73.990027 -389.924658)
			(xy 74.043975 -389.916902) (xy 74.098477 -389.916902) (xy 74.152425 -389.924658) (xy 74.20472 -389.940013)
			(xy 74.254297 -389.962655) (xy 74.300147 -389.992121) (xy 74.341338 -390.027812) (xy 74.377029 -390.069003)
			(xy 74.406495 -390.114853) (xy 74.429137 -390.16443) (xy 74.444492 -390.216725) (xy 74.452248 -390.270673)
			(xy 74.452734 -390.297924) (xy 74.45226 -390.325293) (xy 74.444432 -390.379469) (xy 74.428941 -390.431969)
			(xy 74.406103 -390.481715) (xy 74.376389 -390.527687) (xy 74.358754 -390.548622) (xy 74.358754 -390.548876)
			(xy 74.3585 -390.548876) (xy 74.352911 -390.555962) (xy 74.346661 -390.572879) (xy 74.346308 -390.581896)
			(xy 74.346308 -390.648952) (xy 74.346676 -390.657965) (xy 74.352937 -390.674869) (xy 74.3585 -390.681972)
			(xy 74.358754 -390.682226) (xy 74.373782 -390.69996) (xy 74.399885 -390.738424) (xy 74.410824 -390.758934)
			(xy 74.416412 -390.769856) (xy 74.43597 -390.78408) (xy 74.529442 -390.798558) (xy 74.541387 -390.799766)
			(xy 74.564185 -390.792342) (xy 74.57313 -390.784334) (xy 75.381866 -389.975598) (xy 75.388716 -389.968201)
			(xy 75.396455 -389.949603) (xy 75.396852 -389.93953) (xy 75.396852 -385.938014) (xy 75.396412 -385.927952)
			(xy 75.38867 -385.909375) (xy 75.381866 -385.901946) (xy 69.871082 -380.391162) (xy 69.863685 -380.384312)
			(xy 69.845087 -380.376574) (xy 69.835014 -380.376176) (xy 46.113954 -380.376176) (xy 46.103887 -380.376607)
			(xy 46.085292 -380.38433) (xy 46.077886 -380.391162) (xy 43.774614 -382.694688) (xy 43.767764 -382.702085)
			(xy 43.760023 -382.720683) (xy 43.759628 -382.730756) (xy 43.759628 -382.849374) (xy 43.759199 -382.881186)
			(xy 43.753326 -382.933291) (xy 45.029061 -382.933291) (xy 45.029061 -382.881309) (xy 45.037193 -382.829966)
			(xy 45.053258 -382.780528) (xy 45.076858 -382.734211) (xy 45.107414 -382.692157) (xy 45.144172 -382.655401)
			(xy 45.186228 -382.624848) (xy 45.232546 -382.60125) (xy 45.281985 -382.585189) (xy 45.333329 -382.57706)
			(xy 45.35932 -382.576578) (xy 45.382553 -382.576987) (xy 45.428564 -382.583482) (xy 45.473211 -382.596356)
			(xy 45.515616 -382.615355) (xy 45.554942 -382.640105) (xy 45.572934 -382.65481) (xy 45.579792 -382.660652)
			(xy 45.59681 -382.667002) (xy 45.68063 -382.667002) (xy 45.697648 -382.660652) (xy 45.704506 -382.65481)
			(xy 45.722483 -382.640086) (xy 45.761816 -382.615342) (xy 45.804224 -382.596345) (xy 45.848874 -382.58347)
			(xy 45.894886 -382.57697) (xy 45.91812 -382.576578) (xy 45.946714 -382.577193) (xy 46.003048 -382.587041)
			(xy 46.056851 -382.606423) (xy 46.106524 -382.634762) (xy 46.12894 -382.652524) (xy 46.129194 -382.652778)
			(xy 46.136189 -382.658055) (xy 46.152695 -382.663896) (xy 46.161452 -382.664208) (xy 46.226476 -382.664208)
			(xy 46.235075 -382.663841) (xy 46.251301 -382.658141) (xy 46.258226 -382.653032) (xy 46.258734 -382.652524)
			(xy 46.281067 -382.634911) (xy 46.330526 -382.606833) (xy 46.384066 -382.587648) (xy 46.440101 -382.577923)
			(xy 46.468538 -382.57734) (xy 46.494527 -382.577757) (xy 46.545864 -382.585893) (xy 46.595297 -382.60196)
			(xy 46.641608 -382.625561) (xy 46.683657 -382.656116) (xy 46.720409 -382.692872) (xy 46.750959 -382.734925)
			(xy 46.774555 -382.781238) (xy 46.790616 -382.830673) (xy 46.798256 -382.878917) (xy 47.486318 -382.878917)
			(xy 47.486318 -382.826943) (xy 47.494448 -382.775608) (xy 47.510509 -382.726178) (xy 47.534105 -382.679868)
			(xy 47.564655 -382.63782) (xy 47.601406 -382.601069) (xy 47.643454 -382.570519) (xy 47.689764 -382.546923)
			(xy 47.739194 -382.530862) (xy 47.790529 -382.522732) (xy 47.842503 -382.522732) (xy 47.893838 -382.530862)
			(xy 47.943268 -382.546923) (xy 47.989578 -382.570519) (xy 48.031626 -382.601069) (xy 48.068377 -382.63782)
			(xy 48.098927 -382.679868) (xy 48.122523 -382.726178) (xy 48.138584 -382.775608) (xy 48.146714 -382.826943)
			(xy 48.147224 -382.85293) (xy 48.146714 -382.878917) (xy 48.686468 -382.878917) (xy 48.686468 -382.826943)
			(xy 48.694598 -382.775608) (xy 48.710659 -382.726178) (xy 48.734255 -382.679868) (xy 48.764805 -382.63782)
			(xy 48.801556 -382.601069) (xy 48.843604 -382.570519) (xy 48.889914 -382.546923) (xy 48.939344 -382.530862)
			(xy 48.990679 -382.522732) (xy 49.042653 -382.522732) (xy 49.093988 -382.530862) (xy 49.143418 -382.546923)
			(xy 49.189728 -382.570519) (xy 49.231776 -382.601069) (xy 49.268527 -382.63782) (xy 49.299077 -382.679868)
			(xy 49.322673 -382.726178) (xy 49.338734 -382.775608) (xy 49.346864 -382.826943) (xy 49.347374 -382.85293)
			(xy 49.346864 -382.878917) (xy 49.886364 -382.878917) (xy 49.886364 -382.826943) (xy 49.894494 -382.775608)
			(xy 49.910555 -382.726178) (xy 49.934151 -382.679868) (xy 49.964701 -382.63782) (xy 50.001452 -382.601069)
			(xy 50.0435 -382.570519) (xy 50.08981 -382.546923) (xy 50.13924 -382.530862) (xy 50.190575 -382.522732)
			(xy 50.242549 -382.522732) (xy 50.293884 -382.530862) (xy 50.343314 -382.546923) (xy 50.389624 -382.570519)
			(xy 50.431672 -382.601069) (xy 50.468423 -382.63782) (xy 50.498973 -382.679868) (xy 50.522569 -382.726178)
			(xy 50.53863 -382.775608) (xy 50.54676 -382.826943) (xy 50.54727 -382.85293) (xy 50.54676 -382.878917)
			(xy 51.08626 -382.878917) (xy 51.08626 -382.826943) (xy 51.09439 -382.775608) (xy 51.110451 -382.726178)
			(xy 51.134047 -382.679868) (xy 51.164597 -382.63782) (xy 51.201348 -382.601069) (xy 51.243396 -382.570519)
			(xy 51.289706 -382.546923) (xy 51.339136 -382.530862) (xy 51.390471 -382.522732) (xy 51.442445 -382.522732)
			(xy 51.49378 -382.530862) (xy 51.54321 -382.546923) (xy 51.58952 -382.570519) (xy 51.631568 -382.601069)
			(xy 51.668319 -382.63782) (xy 51.698869 -382.679868) (xy 51.722465 -382.726178) (xy 51.738526 -382.775608)
			(xy 51.746656 -382.826943) (xy 51.747166 -382.85293) (xy 51.746656 -382.878917) (xy 52.28641 -382.878917)
			(xy 52.28641 -382.826943) (xy 52.29454 -382.775608) (xy 52.310601 -382.726178) (xy 52.334197 -382.679868)
			(xy 52.364747 -382.63782) (xy 52.401498 -382.601069) (xy 52.443546 -382.570519) (xy 52.489856 -382.546923)
			(xy 52.539286 -382.530862) (xy 52.590621 -382.522732) (xy 52.642595 -382.522732) (xy 52.69393 -382.530862)
			(xy 52.74336 -382.546923) (xy 52.78967 -382.570519) (xy 52.831718 -382.601069) (xy 52.868469 -382.63782)
			(xy 52.899019 -382.679868) (xy 52.922615 -382.726178) (xy 52.938676 -382.775608) (xy 52.946806 -382.826943)
			(xy 52.947316 -382.85293) (xy 52.946806 -382.878917) (xy 53.486306 -382.878917) (xy 53.486306 -382.826943)
			(xy 53.494436 -382.775608) (xy 53.510497 -382.726178) (xy 53.534093 -382.679868) (xy 53.564643 -382.63782)
			(xy 53.601394 -382.601069) (xy 53.643442 -382.570519) (xy 53.689752 -382.546923) (xy 53.739182 -382.530862)
			(xy 53.790517 -382.522732) (xy 53.842491 -382.522732) (xy 53.893826 -382.530862) (xy 53.943256 -382.546923)
			(xy 53.989566 -382.570519) (xy 54.031614 -382.601069) (xy 54.068365 -382.63782) (xy 54.098915 -382.679868)
			(xy 54.122511 -382.726178) (xy 54.138572 -382.775608) (xy 54.146702 -382.826943) (xy 54.147212 -382.85293)
			(xy 54.146702 -382.878917) (xy 54.686456 -382.878917) (xy 54.686456 -382.826943) (xy 54.694586 -382.775608)
			(xy 54.710647 -382.726178) (xy 54.734243 -382.679868) (xy 54.764793 -382.63782) (xy 54.801544 -382.601069)
			(xy 54.843592 -382.570519) (xy 54.889902 -382.546923) (xy 54.939332 -382.530862) (xy 54.990667 -382.522732)
			(xy 55.042641 -382.522732) (xy 55.093976 -382.530862) (xy 55.143406 -382.546923) (xy 55.189716 -382.570519)
			(xy 55.231764 -382.601069) (xy 55.268515 -382.63782) (xy 55.299065 -382.679868) (xy 55.322661 -382.726178)
			(xy 55.338722 -382.775608) (xy 55.346852 -382.826943) (xy 55.347362 -382.85293) (xy 55.346852 -382.878917)
			(xy 55.886352 -382.878917) (xy 55.886352 -382.826943) (xy 55.894482 -382.775608) (xy 55.910543 -382.726178)
			(xy 55.934139 -382.679868) (xy 55.964689 -382.63782) (xy 56.00144 -382.601069) (xy 56.043488 -382.570519)
			(xy 56.089798 -382.546923) (xy 56.139228 -382.530862) (xy 56.190563 -382.522732) (xy 56.242537 -382.522732)
			(xy 56.293872 -382.530862) (xy 56.343302 -382.546923) (xy 56.389612 -382.570519) (xy 56.43166 -382.601069)
			(xy 56.468411 -382.63782) (xy 56.498961 -382.679868) (xy 56.522557 -382.726178) (xy 56.538618 -382.775608)
			(xy 56.546748 -382.826943) (xy 56.547258 -382.85293) (xy 56.546748 -382.878917) (xy 57.086248 -382.878917)
			(xy 57.086248 -382.826943) (xy 57.094378 -382.775608) (xy 57.110439 -382.726178) (xy 57.134035 -382.679868)
			(xy 57.164585 -382.63782) (xy 57.201336 -382.601069) (xy 57.243384 -382.570519) (xy 57.289694 -382.546923)
			(xy 57.339124 -382.530862) (xy 57.390459 -382.522732) (xy 57.442433 -382.522732) (xy 57.493768 -382.530862)
			(xy 57.543198 -382.546923) (xy 57.589508 -382.570519) (xy 57.631556 -382.601069) (xy 57.668307 -382.63782)
			(xy 57.698857 -382.679868) (xy 57.722453 -382.726178) (xy 57.738514 -382.775608) (xy 57.746644 -382.826943)
			(xy 57.747154 -382.85293) (xy 57.746644 -382.878917) (xy 58.286398 -382.878917) (xy 58.286398 -382.826943)
			(xy 58.294528 -382.775608) (xy 58.310589 -382.726178) (xy 58.334185 -382.679868) (xy 58.364735 -382.63782)
			(xy 58.401486 -382.601069) (xy 58.443534 -382.570519) (xy 58.489844 -382.546923) (xy 58.539274 -382.530862)
			(xy 58.590609 -382.522732) (xy 58.642583 -382.522732) (xy 58.693918 -382.530862) (xy 58.743348 -382.546923)
			(xy 58.789658 -382.570519) (xy 58.831706 -382.601069) (xy 58.868457 -382.63782) (xy 58.899007 -382.679868)
			(xy 58.922603 -382.726178) (xy 58.938664 -382.775608) (xy 58.946794 -382.826943) (xy 58.947304 -382.85293)
			(xy 58.946794 -382.878917) (xy 59.486294 -382.878917) (xy 59.486294 -382.826943) (xy 59.494424 -382.775608)
			(xy 59.510485 -382.726178) (xy 59.534081 -382.679868) (xy 59.564631 -382.63782) (xy 59.601382 -382.601069)
			(xy 59.64343 -382.570519) (xy 59.68974 -382.546923) (xy 59.73917 -382.530862) (xy 59.790505 -382.522732)
			(xy 59.842479 -382.522732) (xy 59.893814 -382.530862) (xy 59.943244 -382.546923) (xy 59.989554 -382.570519)
			(xy 60.031602 -382.601069) (xy 60.068353 -382.63782) (xy 60.098903 -382.679868) (xy 60.122499 -382.726178)
			(xy 60.13856 -382.775608) (xy 60.14669 -382.826943) (xy 60.1472 -382.85293) (xy 60.14669 -382.878917)
			(xy 60.686444 -382.878917) (xy 60.686444 -382.826943) (xy 60.694574 -382.775608) (xy 60.710635 -382.726178)
			(xy 60.734231 -382.679868) (xy 60.764781 -382.63782) (xy 60.801532 -382.601069) (xy 60.84358 -382.570519)
			(xy 60.88989 -382.546923) (xy 60.93932 -382.530862) (xy 60.990655 -382.522732) (xy 61.042629 -382.522732)
			(xy 61.093964 -382.530862) (xy 61.143394 -382.546923) (xy 61.189704 -382.570519) (xy 61.231752 -382.601069)
			(xy 61.268503 -382.63782) (xy 61.299053 -382.679868) (xy 61.322649 -382.726178) (xy 61.33871 -382.775608)
			(xy 61.34684 -382.826943) (xy 61.34735 -382.85293) (xy 61.34684 -382.878917) (xy 61.88634 -382.878917)
			(xy 61.88634 -382.826943) (xy 61.89447 -382.775608) (xy 61.910531 -382.726178) (xy 61.934127 -382.679868)
			(xy 61.964677 -382.63782) (xy 62.001428 -382.601069) (xy 62.043476 -382.570519) (xy 62.089786 -382.546923)
			(xy 62.139216 -382.530862) (xy 62.190551 -382.522732) (xy 62.242525 -382.522732) (xy 62.29386 -382.530862)
			(xy 62.34329 -382.546923) (xy 62.3896 -382.570519) (xy 62.431648 -382.601069) (xy 62.468399 -382.63782)
			(xy 62.498949 -382.679868) (xy 62.522545 -382.726178) (xy 62.538606 -382.775608) (xy 62.546736 -382.826943)
			(xy 62.547246 -382.85293) (xy 62.546736 -382.878917) (xy 63.086236 -382.878917) (xy 63.086236 -382.826943)
			(xy 63.094366 -382.775608) (xy 63.110427 -382.726178) (xy 63.134023 -382.679868) (xy 63.164573 -382.63782)
			(xy 63.201324 -382.601069) (xy 63.243372 -382.570519) (xy 63.289682 -382.546923) (xy 63.339112 -382.530862)
			(xy 63.390447 -382.522732) (xy 63.442421 -382.522732) (xy 63.493756 -382.530862) (xy 63.543186 -382.546923)
			(xy 63.589496 -382.570519) (xy 63.631544 -382.601069) (xy 63.668295 -382.63782) (xy 63.698845 -382.679868)
			(xy 63.722441 -382.726178) (xy 63.738502 -382.775608) (xy 63.746632 -382.826943) (xy 63.747142 -382.85293)
			(xy 63.746632 -382.878917) (xy 64.286386 -382.878917) (xy 64.286386 -382.826943) (xy 64.294516 -382.775608)
			(xy 64.310577 -382.726178) (xy 64.334173 -382.679868) (xy 64.364723 -382.63782) (xy 64.401474 -382.601069)
			(xy 64.443522 -382.570519) (xy 64.489832 -382.546923) (xy 64.539262 -382.530862) (xy 64.590597 -382.522732)
			(xy 64.642571 -382.522732) (xy 64.693906 -382.530862) (xy 64.743336 -382.546923) (xy 64.789646 -382.570519)
			(xy 64.831694 -382.601069) (xy 64.868445 -382.63782) (xy 64.898995 -382.679868) (xy 64.922591 -382.726178)
			(xy 64.938652 -382.775608) (xy 64.946782 -382.826943) (xy 64.947292 -382.85293) (xy 64.946782 -382.878917)
			(xy 65.486282 -382.878917) (xy 65.486282 -382.826943) (xy 65.494412 -382.775608) (xy 65.510473 -382.726178)
			(xy 65.534069 -382.679868) (xy 65.564619 -382.63782) (xy 65.60137 -382.601069) (xy 65.643418 -382.570519)
			(xy 65.689728 -382.546923) (xy 65.739158 -382.530862) (xy 65.790493 -382.522732) (xy 65.842467 -382.522732)
			(xy 65.893802 -382.530862) (xy 65.943232 -382.546923) (xy 65.989542 -382.570519) (xy 66.03159 -382.601069)
			(xy 66.068341 -382.63782) (xy 66.098891 -382.679868) (xy 66.122487 -382.726178) (xy 66.138548 -382.775608)
			(xy 66.146678 -382.826943) (xy 66.147188 -382.85293) (xy 66.146678 -382.878917) (xy 66.144259 -382.894193)
			(xy 66.553245 -382.894193) (xy 66.553245 -382.842207) (xy 66.561378 -382.79086) (xy 66.577444 -382.741418)
			(xy 66.601047 -382.695099) (xy 66.631606 -382.653042) (xy 66.668368 -382.616284) (xy 66.710428 -382.585729)
			(xy 66.75675 -382.562131) (xy 66.806193 -382.54607) (xy 66.857541 -382.537943) (xy 66.883534 -382.537462)
			(xy 66.907307 -382.537892) (xy 66.954366 -382.544688) (xy 66.999963 -382.558162) (xy 67.043156 -382.578037)
			(xy 67.083052 -382.603902) (xy 67.101212 -382.61925) (xy 67.108343 -382.624921) (xy 67.125385 -382.631313)
			(xy 67.134486 -382.631696) (xy 67.165982 -382.631696) (xy 67.175082 -382.631293) (xy 67.192132 -382.624925)
			(xy 67.199256 -382.61925) (xy 67.217435 -382.603926) (xy 67.257331 -382.578066) (xy 67.300519 -382.558187)
			(xy 67.34611 -382.544698) (xy 67.393162 -382.537879) (xy 67.416934 -382.537462) (xy 67.442917 -382.538034)
			(xy 67.494243 -382.546168) (xy 67.543664 -382.562231) (xy 67.589965 -382.585826) (xy 67.632005 -382.616374)
			(xy 67.668748 -382.653121) (xy 67.699292 -382.695164) (xy 67.722882 -382.741467) (xy 67.73894 -382.79089)
			(xy 67.747069 -382.842217) (xy 67.747069 -382.894183) (xy 67.73894 -382.94551) (xy 67.722882 -382.994933)
			(xy 67.699292 -383.041236) (xy 67.668748 -383.083279) (xy 67.632005 -383.120026) (xy 67.589965 -383.150574)
			(xy 67.543664 -383.174169) (xy 67.494243 -383.190232) (xy 67.442917 -383.198366) (xy 67.416934 -383.198878)
			(xy 67.39316 -383.198457) (xy 67.346102 -383.191658) (xy 67.300505 -383.17818) (xy 67.257312 -383.158303)
			(xy 67.217416 -383.132438) (xy 67.199256 -383.11709) (xy 67.19214 -383.111399) (xy 67.175086 -383.10502)
			(xy 67.165982 -383.104644) (xy 67.134486 -383.104644) (xy 67.125384 -383.105023) (xy 67.108333 -383.111407)
			(xy 67.101212 -383.11709) (xy 67.083051 -383.132435) (xy 67.043149 -383.158291) (xy 66.999956 -383.178166)
			(xy 66.954362 -383.191649) (xy 66.907307 -383.198464) (xy 66.883534 -383.198878) (xy 66.857541 -383.198457)
			(xy 66.806193 -383.19033) (xy 66.75675 -383.174269) (xy 66.710428 -383.150671) (xy 66.668368 -383.120116)
			(xy 66.631606 -383.083358) (xy 66.601047 -383.041301) (xy 66.577444 -382.994982) (xy 66.561378 -382.94554)
			(xy 66.553245 -382.894193) (xy 66.144259 -382.894193) (xy 66.138548 -382.930252) (xy 66.122487 -382.979682)
			(xy 66.098891 -383.025992) (xy 66.068341 -383.06804) (xy 66.03159 -383.104791) (xy 65.989542 -383.135341)
			(xy 65.943232 -383.158937) (xy 65.893802 -383.174998) (xy 65.842467 -383.183128) (xy 65.790493 -383.183128)
			(xy 65.739158 -383.174998) (xy 65.689728 -383.158937) (xy 65.643418 -383.135341) (xy 65.60137 -383.104791)
			(xy 65.564619 -383.06804) (xy 65.534069 -383.025992) (xy 65.510473 -382.979682) (xy 65.494412 -382.930252)
			(xy 65.486282 -382.878917) (xy 64.946782 -382.878917) (xy 64.938652 -382.930252) (xy 64.922591 -382.979682)
			(xy 64.898995 -383.025992) (xy 64.868445 -383.06804) (xy 64.831694 -383.104791) (xy 64.789646 -383.135341)
			(xy 64.743336 -383.158937) (xy 64.693906 -383.174998) (xy 64.642571 -383.183128) (xy 64.590597 -383.183128)
			(xy 64.539262 -383.174998) (xy 64.489832 -383.158937) (xy 64.443522 -383.135341) (xy 64.401474 -383.104791)
			(xy 64.364723 -383.06804) (xy 64.334173 -383.025992) (xy 64.310577 -382.979682) (xy 64.294516 -382.930252)
			(xy 64.286386 -382.878917) (xy 63.746632 -382.878917) (xy 63.738502 -382.930252) (xy 63.722441 -382.979682)
			(xy 63.698845 -383.025992) (xy 63.668295 -383.06804) (xy 63.631544 -383.104791) (xy 63.589496 -383.135341)
			(xy 63.543186 -383.158937) (xy 63.493756 -383.174998) (xy 63.442421 -383.183128) (xy 63.390447 -383.183128)
			(xy 63.339112 -383.174998) (xy 63.289682 -383.158937) (xy 63.243372 -383.135341) (xy 63.201324 -383.104791)
			(xy 63.164573 -383.06804) (xy 63.134023 -383.025992) (xy 63.110427 -382.979682) (xy 63.094366 -382.930252)
			(xy 63.086236 -382.878917) (xy 62.546736 -382.878917) (xy 62.538606 -382.930252) (xy 62.522545 -382.979682)
			(xy 62.498949 -383.025992) (xy 62.468399 -383.06804) (xy 62.431648 -383.104791) (xy 62.3896 -383.135341)
			(xy 62.34329 -383.158937) (xy 62.29386 -383.174998) (xy 62.242525 -383.183128) (xy 62.190551 -383.183128)
			(xy 62.139216 -383.174998) (xy 62.089786 -383.158937) (xy 62.043476 -383.135341) (xy 62.001428 -383.104791)
			(xy 61.964677 -383.06804) (xy 61.934127 -383.025992) (xy 61.910531 -382.979682) (xy 61.89447 -382.930252)
			(xy 61.88634 -382.878917) (xy 61.34684 -382.878917) (xy 61.33871 -382.930252) (xy 61.322649 -382.979682)
			(xy 61.299053 -383.025992) (xy 61.268503 -383.06804) (xy 61.231752 -383.104791) (xy 61.189704 -383.135341)
			(xy 61.143394 -383.158937) (xy 61.093964 -383.174998) (xy 61.042629 -383.183128) (xy 60.990655 -383.183128)
			(xy 60.93932 -383.174998) (xy 60.88989 -383.158937) (xy 60.84358 -383.135341) (xy 60.801532 -383.104791)
			(xy 60.764781 -383.06804) (xy 60.734231 -383.025992) (xy 60.710635 -382.979682) (xy 60.694574 -382.930252)
			(xy 60.686444 -382.878917) (xy 60.14669 -382.878917) (xy 60.13856 -382.930252) (xy 60.122499 -382.979682)
			(xy 60.098903 -383.025992) (xy 60.068353 -383.06804) (xy 60.031602 -383.104791) (xy 59.989554 -383.135341)
			(xy 59.943244 -383.158937) (xy 59.893814 -383.174998) (xy 59.842479 -383.183128) (xy 59.790505 -383.183128)
			(xy 59.73917 -383.174998) (xy 59.68974 -383.158937) (xy 59.64343 -383.135341) (xy 59.601382 -383.104791)
			(xy 59.564631 -383.06804) (xy 59.534081 -383.025992) (xy 59.510485 -382.979682) (xy 59.494424 -382.930252)
			(xy 59.486294 -382.878917) (xy 58.946794 -382.878917) (xy 58.938664 -382.930252) (xy 58.922603 -382.979682)
			(xy 58.899007 -383.025992) (xy 58.868457 -383.06804) (xy 58.831706 -383.104791) (xy 58.789658 -383.135341)
			(xy 58.743348 -383.158937) (xy 58.693918 -383.174998) (xy 58.642583 -383.183128) (xy 58.590609 -383.183128)
			(xy 58.539274 -383.174998) (xy 58.489844 -383.158937) (xy 58.443534 -383.135341) (xy 58.401486 -383.104791)
			(xy 58.364735 -383.06804) (xy 58.334185 -383.025992) (xy 58.310589 -382.979682) (xy 58.294528 -382.930252)
			(xy 58.286398 -382.878917) (xy 57.746644 -382.878917) (xy 57.738514 -382.930252) (xy 57.722453 -382.979682)
			(xy 57.698857 -383.025992) (xy 57.668307 -383.06804) (xy 57.631556 -383.104791) (xy 57.589508 -383.135341)
			(xy 57.543198 -383.158937) (xy 57.493768 -383.174998) (xy 57.442433 -383.183128) (xy 57.390459 -383.183128)
			(xy 57.339124 -383.174998) (xy 57.289694 -383.158937) (xy 57.243384 -383.135341) (xy 57.201336 -383.104791)
			(xy 57.164585 -383.06804) (xy 57.134035 -383.025992) (xy 57.110439 -382.979682) (xy 57.094378 -382.930252)
			(xy 57.086248 -382.878917) (xy 56.546748 -382.878917) (xy 56.538618 -382.930252) (xy 56.522557 -382.979682)
			(xy 56.498961 -383.025992) (xy 56.468411 -383.06804) (xy 56.43166 -383.104791) (xy 56.389612 -383.135341)
			(xy 56.343302 -383.158937) (xy 56.293872 -383.174998) (xy 56.242537 -383.183128) (xy 56.190563 -383.183128)
			(xy 56.139228 -383.174998) (xy 56.089798 -383.158937) (xy 56.043488 -383.135341) (xy 56.00144 -383.104791)
			(xy 55.964689 -383.06804) (xy 55.934139 -383.025992) (xy 55.910543 -382.979682) (xy 55.894482 -382.930252)
			(xy 55.886352 -382.878917) (xy 55.346852 -382.878917) (xy 55.338722 -382.930252) (xy 55.322661 -382.979682)
			(xy 55.299065 -383.025992) (xy 55.268515 -383.06804) (xy 55.231764 -383.104791) (xy 55.189716 -383.135341)
			(xy 55.143406 -383.158937) (xy 55.093976 -383.174998) (xy 55.042641 -383.183128) (xy 54.990667 -383.183128)
			(xy 54.939332 -383.174998) (xy 54.889902 -383.158937) (xy 54.843592 -383.135341) (xy 54.801544 -383.104791)
			(xy 54.764793 -383.06804) (xy 54.734243 -383.025992) (xy 54.710647 -382.979682) (xy 54.694586 -382.930252)
			(xy 54.686456 -382.878917) (xy 54.146702 -382.878917) (xy 54.138572 -382.930252) (xy 54.122511 -382.979682)
			(xy 54.098915 -383.025992) (xy 54.068365 -383.06804) (xy 54.031614 -383.104791) (xy 53.989566 -383.135341)
			(xy 53.943256 -383.158937) (xy 53.893826 -383.174998) (xy 53.842491 -383.183128) (xy 53.790517 -383.183128)
			(xy 53.739182 -383.174998) (xy 53.689752 -383.158937) (xy 53.643442 -383.135341) (xy 53.601394 -383.104791)
			(xy 53.564643 -383.06804) (xy 53.534093 -383.025992) (xy 53.510497 -382.979682) (xy 53.494436 -382.930252)
			(xy 53.486306 -382.878917) (xy 52.946806 -382.878917) (xy 52.938676 -382.930252) (xy 52.922615 -382.979682)
			(xy 52.899019 -383.025992) (xy 52.868469 -383.06804) (xy 52.831718 -383.104791) (xy 52.78967 -383.135341)
			(xy 52.74336 -383.158937) (xy 52.69393 -383.174998) (xy 52.642595 -383.183128) (xy 52.590621 -383.183128)
			(xy 52.539286 -383.174998) (xy 52.489856 -383.158937) (xy 52.443546 -383.135341) (xy 52.401498 -383.104791)
			(xy 52.364747 -383.06804) (xy 52.334197 -383.025992) (xy 52.310601 -382.979682) (xy 52.29454 -382.930252)
			(xy 52.28641 -382.878917) (xy 51.746656 -382.878917) (xy 51.738526 -382.930252) (xy 51.722465 -382.979682)
			(xy 51.698869 -383.025992) (xy 51.668319 -383.06804) (xy 51.631568 -383.104791) (xy 51.58952 -383.135341)
			(xy 51.54321 -383.158937) (xy 51.49378 -383.174998) (xy 51.442445 -383.183128) (xy 51.390471 -383.183128)
			(xy 51.339136 -383.174998) (xy 51.289706 -383.158937) (xy 51.243396 -383.135341) (xy 51.201348 -383.104791)
			(xy 51.164597 -383.06804) (xy 51.134047 -383.025992) (xy 51.110451 -382.979682) (xy 51.09439 -382.930252)
			(xy 51.08626 -382.878917) (xy 50.54676 -382.878917) (xy 50.53863 -382.930252) (xy 50.522569 -382.979682)
			(xy 50.498973 -383.025992) (xy 50.468423 -383.06804) (xy 50.431672 -383.104791) (xy 50.389624 -383.135341)
			(xy 50.343314 -383.158937) (xy 50.293884 -383.174998) (xy 50.242549 -383.183128) (xy 50.190575 -383.183128)
			(xy 50.13924 -383.174998) (xy 50.08981 -383.158937) (xy 50.0435 -383.135341) (xy 50.001452 -383.104791)
			(xy 49.964701 -383.06804) (xy 49.934151 -383.025992) (xy 49.910555 -382.979682) (xy 49.894494 -382.930252)
			(xy 49.886364 -382.878917) (xy 49.346864 -382.878917) (xy 49.338734 -382.930252) (xy 49.322673 -382.979682)
			(xy 49.299077 -383.025992) (xy 49.268527 -383.06804) (xy 49.231776 -383.104791) (xy 49.189728 -383.135341)
			(xy 49.143418 -383.158937) (xy 49.093988 -383.174998) (xy 49.042653 -383.183128) (xy 48.990679 -383.183128)
			(xy 48.939344 -383.174998) (xy 48.889914 -383.158937) (xy 48.843604 -383.135341) (xy 48.801556 -383.104791)
			(xy 48.764805 -383.06804) (xy 48.734255 -383.025992) (xy 48.710659 -382.979682) (xy 48.694598 -382.930252)
			(xy 48.686468 -382.878917) (xy 48.146714 -382.878917) (xy 48.138584 -382.930252) (xy 48.122523 -382.979682)
			(xy 48.098927 -383.025992) (xy 48.068377 -383.06804) (xy 48.031626 -383.104791) (xy 47.989578 -383.135341)
			(xy 47.943268 -383.158937) (xy 47.893838 -383.174998) (xy 47.842503 -383.183128) (xy 47.790529 -383.183128)
			(xy 47.739194 -383.174998) (xy 47.689764 -383.158937) (xy 47.643454 -383.135341) (xy 47.601406 -383.104791)
			(xy 47.564655 -383.06804) (xy 47.534105 -383.025992) (xy 47.510509 -382.979682) (xy 47.494448 -382.930252)
			(xy 47.486318 -382.878917) (xy 46.798256 -382.878917) (xy 46.798746 -382.882011) (xy 46.798746 -382.933989)
			(xy 46.790616 -382.985327) (xy 46.774555 -383.034762) (xy 46.750959 -383.081075) (xy 46.720409 -383.123128)
			(xy 46.683657 -383.159884) (xy 46.641608 -383.190439) (xy 46.595297 -383.21404) (xy 46.545864 -383.230107)
			(xy 46.494527 -383.238243) (xy 46.468538 -383.238756) (xy 46.439944 -383.238156) (xy 46.38361 -383.228303)
			(xy 46.329806 -383.208916) (xy 46.280134 -383.180573) (xy 46.257718 -383.16281) (xy 46.257464 -383.162556)
			(xy 46.250451 -383.157307) (xy 46.233959 -383.151448) (xy 46.225206 -383.151126) (xy 46.160182 -383.151126)
			(xy 46.151581 -383.151467) (xy 46.135354 -383.157184) (xy 46.128432 -383.162302) (xy 46.127924 -383.16281)
			(xy 46.105575 -383.180402) (xy 46.056121 -383.208483) (xy 46.002587 -383.227674) (xy 45.946555 -383.237406)
			(xy 45.91812 -383.237994) (xy 45.894885 -383.237627) (xy 45.848873 -383.231122) (xy 45.804225 -383.218239)
			(xy 45.76182 -383.199231) (xy 45.722496 -383.174472) (xy 45.704506 -383.159762) (xy 45.697648 -383.15392)
			(xy 45.68063 -383.14757) (xy 45.59681 -383.14757) (xy 45.579792 -383.15392) (xy 45.572934 -383.159762)
			(xy 45.554939 -383.174463) (xy 45.515612 -383.199212) (xy 45.473208 -383.218213) (xy 45.428562 -383.231094)
			(xy 45.382553 -383.237599) (xy 45.35932 -383.237994) (xy 45.333329 -383.23754) (xy 45.281985 -383.229411)
			(xy 45.232546 -383.21335) (xy 45.186228 -383.189752) (xy 45.144172 -383.159199) (xy 45.107414 -383.122443)
			(xy 45.076858 -383.080389) (xy 45.053258 -383.034072) (xy 45.037193 -382.984634) (xy 45.029061 -382.933291)
			(xy 43.753326 -382.933291) (xy 43.752073 -382.94441) (xy 43.737909 -383.006438) (xy 43.716885 -383.066488)
			(xy 43.689266 -383.123805) (xy 43.655398 -383.177666) (xy 43.615709 -383.227394) (xy 43.593512 -383.250186)
			(xy 43.100498 -383.7432) (xy 43.683934 -383.7432) (xy 43.688005 -383.687578) (xy 43.700131 -383.633141)
			(xy 43.720054 -383.58105) (xy 43.74735 -383.532415) (xy 43.781436 -383.488272) (xy 43.821585 -383.449563)
			(xy 43.866943 -383.417112) (xy 43.916543 -383.391611) (xy 43.969327 -383.373604) (xy 44.02417 -383.363474)
			(xy 44.079904 -383.361437) (xy 44.135341 -383.367537) (xy 44.189298 -383.381643) (xy 44.240627 -383.403455)
			(xy 44.288233 -383.432509) (xy 44.331101 -383.468184) (xy 44.368318 -383.509721) (xy 44.399091 -383.556234)
			(xy 44.422763 -383.606731) (xy 44.438831 -383.660138) (xy 44.446951 -383.715314) (xy 44.44746 -383.7432)
			(xy 44.446951 -383.771086) (xy 44.438831 -383.826262) (xy 44.422763 -383.879669) (xy 44.399091 -383.930166)
			(xy 44.368318 -383.976679) (xy 44.331101 -384.018216) (xy 44.288233 -384.053891) (xy 44.240627 -384.082945)
			(xy 44.189298 -384.104757) (xy 44.135341 -384.118863) (xy 44.079904 -384.124963) (xy 44.02417 -384.122926)
			(xy 43.969327 -384.112796) (xy 43.916543 -384.094789) (xy 43.866943 -384.069288) (xy 43.821585 -384.036837)
			(xy 43.781436 -383.998128) (xy 43.74735 -383.953985) (xy 43.720054 -383.90535) (xy 43.700131 -383.853259)
			(xy 43.688005 -383.798822) (xy 43.683934 -383.7432) (xy 43.100498 -383.7432) (xy 42.181018 -384.66268)
			(xy 43.683934 -384.66268) (xy 43.688005 -384.607058) (xy 43.700131 -384.552621) (xy 43.720054 -384.50053)
			(xy 43.74735 -384.451895) (xy 43.781436 -384.407752) (xy 43.821585 -384.369043) (xy 43.866943 -384.336592)
			(xy 43.916543 -384.311091) (xy 43.969327 -384.293084) (xy 44.02417 -384.282954) (xy 44.079904 -384.280917)
			(xy 44.135341 -384.287017) (xy 44.189298 -384.301123) (xy 44.240627 -384.322935) (xy 44.288233 -384.351989)
			(xy 44.330712 -384.38734) (xy 44.944012 -384.38734) (xy 44.944012 -384.327404) (xy 44.951835 -384.267982)
			(xy 44.967348 -384.210089) (xy 44.990284 -384.154716) (xy 45.020251 -384.10281) (xy 45.056738 -384.05526)
			(xy 45.099118 -384.01288) (xy 45.146668 -383.976393) (xy 45.198574 -383.946426) (xy 45.253947 -383.92349)
			(xy 45.31184 -383.907977) (xy 45.371262 -383.900154) (xy 45.431198 -383.900154) (xy 45.49062 -383.907977)
			(xy 45.548513 -383.92349) (xy 45.603886 -383.946426) (xy 45.655792 -383.976393) (xy 45.703342 -384.01288)
			(xy 45.745722 -384.05526) (xy 45.782209 -384.10281) (xy 45.812176 -384.154716) (xy 45.835112 -384.210089)
			(xy 45.850625 -384.267982) (xy 45.858448 -384.327404) (xy 45.858938 -384.357372) (xy 45.858448 -384.38734)
			(xy 45.850625 -384.446762) (xy 45.835112 -384.504655) (xy 45.812176 -384.560028) (xy 45.782209 -384.611934)
			(xy 45.745722 -384.659484) (xy 45.703342 -384.701864) (xy 45.655792 -384.738351) (xy 45.603886 -384.768318)
			(xy 45.548513 -384.791254) (xy 45.49062 -384.806767) (xy 45.431198 -384.81459) (xy 45.371262 -384.81459)
			(xy 45.31184 -384.806767) (xy 45.253947 -384.791254) (xy 45.198574 -384.768318) (xy 45.146668 -384.738351)
			(xy 45.099118 -384.701864) (xy 45.056738 -384.659484) (xy 45.020251 -384.611934) (xy 44.990284 -384.560028)
			(xy 44.967348 -384.504655) (xy 44.951835 -384.446762) (xy 44.944012 -384.38734) (xy 44.330712 -384.38734)
			(xy 44.331101 -384.387664) (xy 44.368318 -384.429201) (xy 44.399091 -384.475714) (xy 44.422763 -384.526211)
			(xy 44.438831 -384.579618) (xy 44.446951 -384.634794) (xy 44.44746 -384.66268) (xy 44.446951 -384.690566)
			(xy 44.438831 -384.745742) (xy 44.422763 -384.799149) (xy 44.399091 -384.849646) (xy 44.368318 -384.896159)
			(xy 44.331101 -384.937696) (xy 44.288233 -384.973371) (xy 44.240627 -385.002425) (xy 44.189298 -385.024237)
			(xy 44.135341 -385.038343) (xy 44.079904 -385.044443) (xy 44.02417 -385.042406) (xy 43.969327 -385.032276)
			(xy 43.916543 -385.014269) (xy 43.866943 -384.988768) (xy 43.821585 -384.956317) (xy 43.781436 -384.917608)
			(xy 43.74735 -384.873465) (xy 43.720054 -384.82483) (xy 43.700131 -384.772739) (xy 43.688005 -384.718302)
			(xy 43.683934 -384.66268) (xy 42.181018 -384.66268) (xy 41.52646 -385.317238) (xy 41.518883 -385.325773)
			(xy 41.511387 -385.347298) (xy 41.513887 -385.369953) (xy 41.519348 -385.379976) (xy 41.533083 -385.402779)
			(xy 41.554745 -385.451406) (xy 41.569424 -385.502575) (xy 41.576836 -385.555289) (xy 41.57726 -385.581906)
			(xy 41.57726 -385.58216) (xy 41.576799 -385.609413) (xy 41.576793 -385.609452) (xy 43.684938 -385.609452)
			(xy 43.684938 -385.554948) (xy 43.692694 -385.500999) (xy 43.708048 -385.448703) (xy 43.730688 -385.399123)
			(xy 43.760153 -385.35327) (xy 43.795843 -385.312077) (xy 43.837032 -385.276382) (xy 43.882881 -385.246911)
			(xy 43.932457 -385.224265) (xy 43.984752 -385.208904) (xy 44.0387 -385.201141) (xy 44.065952 -385.200652)
			(xy 44.094586 -385.20116) (xy 44.151211 -385.209726) (xy 44.205919 -385.226659) (xy 44.257482 -385.251578)
			(xy 44.304742 -385.283923) (xy 44.346638 -385.322968) (xy 44.382227 -385.367836) (xy 44.396914 -385.392422)
			(xy 44.401766 -385.400103) (xy 44.41569 -385.411748) (xy 44.432792 -385.41783) (xy 44.441872 -385.418076)
			(xy 44.544996 -385.416044) (xy 44.568364 -385.401566) (xy 44.574968 -385.389374) (xy 44.589932 -385.362137)
			(xy 44.626059 -385.311572) (xy 44.668698 -385.266364) (xy 44.717065 -385.227344) (xy 44.770269 -385.19523)
			(xy 44.82733 -385.170615) (xy 44.887199 -385.15395) (xy 44.948772 -385.145544) (xy 44.979844 -385.145026)
			(xy 45.009814 -385.145441) (xy 45.069241 -385.15327) (xy 45.127137 -385.168789) (xy 45.182513 -385.191733)
			(xy 45.23442 -385.221707) (xy 45.28197 -385.258201) (xy 45.324351 -385.300588) (xy 45.360836 -385.348145)
			(xy 45.390802 -385.400057) (xy 45.413736 -385.455437) (xy 45.429245 -385.513336) (xy 45.437064 -385.572764)
			(xy 45.437552 -385.602734) (xy 45.437054 -385.633614) (xy 45.428738 -385.694812) (xy 45.412263 -385.754335)
			(xy 45.387927 -385.811099) (xy 45.356174 -385.864071) (xy 45.347002 -385.87553) (xy 46.834044 -385.87553)
			(xy 46.834629 -385.849546) (xy 46.842754 -385.798217) (xy 46.858808 -385.748791) (xy 46.882396 -385.702485)
			(xy 46.912937 -385.660439) (xy 46.949679 -385.623687) (xy 46.991718 -385.593136) (xy 47.038019 -385.569537)
			(xy 47.087441 -385.553472) (xy 47.138768 -385.545335) (xy 47.164752 -385.544822) (xy 47.181185 -385.545046)
			(xy 47.213885 -385.548355) (xy 47.23003 -385.551426) (xy 47.238533 -385.552855) (xy 47.255601 -385.55046)
			(xy 47.270889 -385.542506) (xy 47.27702 -385.53644) (xy 47.345346 -385.464304) (xy 47.35195 -385.438904)
			(xy 47.348648 -385.426204) (xy 47.341641 -385.397762) (xy 47.334124 -385.339669) (xy 47.333662 -385.31038)
			(xy 47.334179 -385.279492) (xy 47.342485 -385.218276) (xy 47.358944 -385.158732) (xy 47.383258 -385.10194)
			(xy 47.398686 -385.075176) (xy 47.404069 -385.065255) (xy 47.406423 -385.042832) (xy 47.403258 -385.031996)
			(xy 47.37735 -384.958336) (xy 47.3731 -384.947976) (xy 47.357408 -384.932035) (xy 47.347124 -384.927602)
			(xy 47.323727 -384.918457) (xy 47.279832 -384.894029) (xy 47.240138 -384.863241) (xy 47.20556 -384.826801)
			(xy 47.176893 -384.78555) (xy 47.154798 -384.740435) (xy 47.139783 -384.692497) (xy 47.132194 -384.642839)
			(xy 47.131732 -384.617722) (xy 47.132242 -384.591735) (xy 47.140372 -384.5404) (xy 47.156433 -384.49097)
			(xy 47.180029 -384.44466) (xy 47.210579 -384.402612) (xy 47.24733 -384.365861) (xy 47.289378 -384.335311)
			(xy 47.335688 -384.311715) (xy 47.385118 -384.295654) (xy 47.436453 -384.287524) (xy 47.488427 -384.287524)
			(xy 47.539762 -384.295654) (xy 47.589192 -384.311715) (xy 47.635502 -384.335311) (xy 47.67755 -384.365861)
			(xy 47.714301 -384.402612) (xy 47.744851 -384.44466) (xy 47.768447 -384.49097) (xy 47.784508 -384.5404)
			(xy 47.792638 -384.591735) (xy 47.793148 -384.617722) (xy 48.331628 -384.617722) (xy 48.332138 -384.591735)
			(xy 48.340268 -384.5404) (xy 48.356329 -384.49097) (xy 48.379925 -384.44466) (xy 48.410475 -384.402612)
			(xy 48.447226 -384.365861) (xy 48.489274 -384.335311) (xy 48.535584 -384.311715) (xy 48.585014 -384.295654)
			(xy 48.636349 -384.287524) (xy 48.688323 -384.287524) (xy 48.739658 -384.295654) (xy 48.789088 -384.311715)
			(xy 48.835398 -384.335311) (xy 48.877446 -384.365861) (xy 48.914197 -384.402612) (xy 48.944747 -384.44466)
			(xy 48.968343 -384.49097) (xy 48.984404 -384.5404) (xy 48.992534 -384.591735) (xy 48.993044 -384.617722)
			(xy 49.531778 -384.617722) (xy 49.532288 -384.591735) (xy 49.540418 -384.5404) (xy 49.556479 -384.49097)
			(xy 49.580075 -384.44466) (xy 49.610625 -384.402612) (xy 49.647376 -384.365861) (xy 49.689424 -384.335311)
			(xy 49.735734 -384.311715) (xy 49.785164 -384.295654) (xy 49.836499 -384.287524) (xy 49.888473 -384.287524)
			(xy 49.939808 -384.295654) (xy 49.989238 -384.311715) (xy 50.035548 -384.335311) (xy 50.077596 -384.365861)
			(xy 50.114347 -384.402612) (xy 50.144897 -384.44466) (xy 50.168493 -384.49097) (xy 50.184554 -384.5404)
			(xy 50.192684 -384.591735) (xy 50.193194 -384.617722) (xy 50.731674 -384.617722) (xy 50.732184 -384.591735)
			(xy 50.740314 -384.5404) (xy 50.756375 -384.49097) (xy 50.779971 -384.44466) (xy 50.810521 -384.402612)
			(xy 50.847272 -384.365861) (xy 50.88932 -384.335311) (xy 50.93563 -384.311715) (xy 50.98506 -384.295654)
			(xy 51.036395 -384.287524) (xy 51.088369 -384.287524) (xy 51.139704 -384.295654) (xy 51.189134 -384.311715)
			(xy 51.235444 -384.335311) (xy 51.277492 -384.365861) (xy 51.314243 -384.402612) (xy 51.344793 -384.44466)
			(xy 51.368389 -384.49097) (xy 51.38445 -384.5404) (xy 51.39258 -384.591735) (xy 51.39309 -384.617722)
			(xy 51.931824 -384.617722) (xy 51.932334 -384.591735) (xy 51.940464 -384.5404) (xy 51.956525 -384.49097)
			(xy 51.980121 -384.44466) (xy 52.010671 -384.402612) (xy 52.047422 -384.365861) (xy 52.08947 -384.335311)
			(xy 52.13578 -384.311715) (xy 52.18521 -384.295654) (xy 52.236545 -384.287524) (xy 52.288519 -384.287524)
			(xy 52.339854 -384.295654) (xy 52.389284 -384.311715) (xy 52.435594 -384.335311) (xy 52.477642 -384.365861)
			(xy 52.514393 -384.402612) (xy 52.544943 -384.44466) (xy 52.568539 -384.49097) (xy 52.5846 -384.5404)
			(xy 52.59273 -384.591735) (xy 52.59324 -384.617722) (xy 53.13172 -384.617722) (xy 53.13223 -384.591735)
			(xy 53.14036 -384.5404) (xy 53.156421 -384.49097) (xy 53.180017 -384.44466) (xy 53.210567 -384.402612)
			(xy 53.247318 -384.365861) (xy 53.289366 -384.335311) (xy 53.335676 -384.311715) (xy 53.385106 -384.295654)
			(xy 53.436441 -384.287524) (xy 53.488415 -384.287524) (xy 53.53975 -384.295654) (xy 53.58918 -384.311715)
			(xy 53.63549 -384.335311) (xy 53.677538 -384.365861) (xy 53.714289 -384.402612) (xy 53.744839 -384.44466)
			(xy 53.768435 -384.49097) (xy 53.784496 -384.5404) (xy 53.792626 -384.591735) (xy 53.793136 -384.617722)
			(xy 54.331616 -384.617722) (xy 54.332126 -384.591735) (xy 54.340256 -384.5404) (xy 54.356317 -384.49097)
			(xy 54.379913 -384.44466) (xy 54.410463 -384.402612) (xy 54.447214 -384.365861) (xy 54.489262 -384.335311)
			(xy 54.535572 -384.311715) (xy 54.585002 -384.295654) (xy 54.636337 -384.287524) (xy 54.688311 -384.287524)
			(xy 54.739646 -384.295654) (xy 54.789076 -384.311715) (xy 54.835386 -384.335311) (xy 54.877434 -384.365861)
			(xy 54.914185 -384.402612) (xy 54.944735 -384.44466) (xy 54.968331 -384.49097) (xy 54.984392 -384.5404)
			(xy 54.992522 -384.591735) (xy 54.993032 -384.617722) (xy 55.531766 -384.617722) (xy 55.532276 -384.591735)
			(xy 55.540406 -384.5404) (xy 55.556467 -384.49097) (xy 55.580063 -384.44466) (xy 55.610613 -384.402612)
			(xy 55.647364 -384.365861) (xy 55.689412 -384.335311) (xy 55.735722 -384.311715) (xy 55.785152 -384.295654)
			(xy 55.836487 -384.287524) (xy 55.888461 -384.287524) (xy 55.939796 -384.295654) (xy 55.989226 -384.311715)
			(xy 56.035536 -384.335311) (xy 56.077584 -384.365861) (xy 56.114335 -384.402612) (xy 56.144885 -384.44466)
			(xy 56.168481 -384.49097) (xy 56.184542 -384.5404) (xy 56.192672 -384.591735) (xy 56.193182 -384.617722)
			(xy 56.731662 -384.617722) (xy 56.732172 -384.591735) (xy 56.740302 -384.5404) (xy 56.756363 -384.49097)
			(xy 56.779959 -384.44466) (xy 56.810509 -384.402612) (xy 56.84726 -384.365861) (xy 56.889308 -384.335311)
			(xy 56.935618 -384.311715) (xy 56.985048 -384.295654) (xy 57.036383 -384.287524) (xy 57.088357 -384.287524)
			(xy 57.139692 -384.295654) (xy 57.189122 -384.311715) (xy 57.235432 -384.335311) (xy 57.27748 -384.365861)
			(xy 57.314231 -384.402612) (xy 57.344781 -384.44466) (xy 57.368377 -384.49097) (xy 57.384438 -384.5404)
			(xy 57.392568 -384.591735) (xy 57.393078 -384.617722) (xy 57.931812 -384.617722) (xy 57.932322 -384.591735)
			(xy 57.940452 -384.5404) (xy 57.956513 -384.49097) (xy 57.980109 -384.44466) (xy 58.010659 -384.402612)
			(xy 58.04741 -384.365861) (xy 58.089458 -384.335311) (xy 58.135768 -384.311715) (xy 58.185198 -384.295654)
			(xy 58.236533 -384.287524) (xy 58.288507 -384.287524) (xy 58.339842 -384.295654) (xy 58.389272 -384.311715)
			(xy 58.435582 -384.335311) (xy 58.47763 -384.365861) (xy 58.514381 -384.402612) (xy 58.544931 -384.44466)
			(xy 58.568527 -384.49097) (xy 58.584588 -384.5404) (xy 58.592718 -384.591735) (xy 58.593228 -384.617722)
			(xy 59.131708 -384.617722) (xy 59.132218 -384.591735) (xy 59.140348 -384.5404) (xy 59.156409 -384.49097)
			(xy 59.180005 -384.44466) (xy 59.210555 -384.402612) (xy 59.247306 -384.365861) (xy 59.289354 -384.335311)
			(xy 59.335664 -384.311715) (xy 59.385094 -384.295654) (xy 59.436429 -384.287524) (xy 59.488403 -384.287524)
			(xy 59.539738 -384.295654) (xy 59.589168 -384.311715) (xy 59.635478 -384.335311) (xy 59.677526 -384.365861)
			(xy 59.714277 -384.402612) (xy 59.744827 -384.44466) (xy 59.768423 -384.49097) (xy 59.784484 -384.5404)
			(xy 59.792614 -384.591735) (xy 59.793124 -384.617722) (xy 60.331604 -384.617722) (xy 60.332114 -384.591735)
			(xy 60.340244 -384.5404) (xy 60.356305 -384.49097) (xy 60.379901 -384.44466) (xy 60.410451 -384.402612)
			(xy 60.447202 -384.365861) (xy 60.48925 -384.335311) (xy 60.53556 -384.311715) (xy 60.58499 -384.295654)
			(xy 60.636325 -384.287524) (xy 60.688299 -384.287524) (xy 60.739634 -384.295654) (xy 60.789064 -384.311715)
			(xy 60.835374 -384.335311) (xy 60.877422 -384.365861) (xy 60.914173 -384.402612) (xy 60.944723 -384.44466)
			(xy 60.968319 -384.49097) (xy 60.98438 -384.5404) (xy 60.99251 -384.591735) (xy 60.99302 -384.617722)
			(xy 61.531754 -384.617722) (xy 61.532264 -384.591735) (xy 61.540394 -384.5404) (xy 61.556455 -384.49097)
			(xy 61.580051 -384.44466) (xy 61.610601 -384.402612) (xy 61.647352 -384.365861) (xy 61.6894 -384.335311)
			(xy 61.73571 -384.311715) (xy 61.78514 -384.295654) (xy 61.836475 -384.287524) (xy 61.888449 -384.287524)
			(xy 61.939784 -384.295654) (xy 61.989214 -384.311715) (xy 62.035524 -384.335311) (xy 62.077572 -384.365861)
			(xy 62.114323 -384.402612) (xy 62.144873 -384.44466) (xy 62.168469 -384.49097) (xy 62.18453 -384.5404)
			(xy 62.19266 -384.591735) (xy 62.19317 -384.617722) (xy 62.73165 -384.617722) (xy 62.73216 -384.591735)
			(xy 62.74029 -384.5404) (xy 62.756351 -384.49097) (xy 62.779947 -384.44466) (xy 62.810497 -384.402612)
			(xy 62.847248 -384.365861) (xy 62.889296 -384.335311) (xy 62.935606 -384.311715) (xy 62.985036 -384.295654)
			(xy 63.036371 -384.287524) (xy 63.088345 -384.287524) (xy 63.13968 -384.295654) (xy 63.18911 -384.311715)
			(xy 63.23542 -384.335311) (xy 63.277468 -384.365861) (xy 63.314219 -384.402612) (xy 63.344769 -384.44466)
			(xy 63.368365 -384.49097) (xy 63.384426 -384.5404) (xy 63.392556 -384.591735) (xy 63.393066 -384.617722)
			(xy 63.9318 -384.617722) (xy 63.93231 -384.591735) (xy 63.94044 -384.5404) (xy 63.956501 -384.49097)
			(xy 63.980097 -384.44466) (xy 64.010647 -384.402612) (xy 64.047398 -384.365861) (xy 64.089446 -384.335311)
			(xy 64.135756 -384.311715) (xy 64.185186 -384.295654) (xy 64.236521 -384.287524) (xy 64.288495 -384.287524)
			(xy 64.33983 -384.295654) (xy 64.38926 -384.311715) (xy 64.43557 -384.335311) (xy 64.477618 -384.365861)
			(xy 64.514369 -384.402612) (xy 64.544919 -384.44466) (xy 64.568515 -384.49097) (xy 64.584576 -384.5404)
			(xy 64.592706 -384.591735) (xy 64.593216 -384.617722) (xy 65.131696 -384.617722) (xy 65.132206 -384.591735)
			(xy 65.140336 -384.5404) (xy 65.156397 -384.49097) (xy 65.179993 -384.44466) (xy 65.210543 -384.402612)
			(xy 65.247294 -384.365861) (xy 65.289342 -384.335311) (xy 65.335652 -384.311715) (xy 65.385082 -384.295654)
			(xy 65.436417 -384.287524) (xy 65.488391 -384.287524) (xy 65.539726 -384.295654) (xy 65.589156 -384.311715)
			(xy 65.635466 -384.335311) (xy 65.677514 -384.365861) (xy 65.714265 -384.402612) (xy 65.744815 -384.44466)
			(xy 65.768411 -384.49097) (xy 65.784472 -384.5404) (xy 65.792602 -384.591735) (xy 65.793112 -384.617722)
			(xy 65.793112 -384.61823) (xy 65.792548 -384.645204) (xy 65.78374 -384.69843) (xy 65.775586 -384.724148)
			(xy 65.771776 -384.73507) (xy 65.774316 -384.757422) (xy 65.821052 -384.833876) (xy 65.827357 -384.843067)
			(xy 65.845935 -384.855328) (xy 65.856866 -384.857498) (xy 65.85712 -384.857498) (xy 65.886437 -384.862214)
			(xy 65.943607 -384.878261) (xy 65.998221 -384.90157) (xy 66.049361 -384.931747) (xy 66.096167 -384.968288)
			(xy 66.137852 -385.010576) (xy 66.173716 -385.057902) (xy 66.203157 -385.10947) (xy 66.219502 -385.149344)
			(xy 67.30238 -385.149344) (xy 67.302813 -385.120709) (xy 67.309969 -385.063887) (xy 67.32415 -385.008399)
			(xy 67.345135 -384.955112) (xy 67.372597 -384.904854) (xy 67.388994 -384.881374) (xy 67.394673 -384.872857)
			(xy 67.399287 -384.85293) (xy 67.395716 -384.83279) (xy 67.390518 -384.82397) (xy 67.373052 -384.796017)
			(xy 67.345438 -384.736167) (xy 67.326692 -384.672977) (xy 67.317199 -384.607752) (xy 67.316604 -384.574796)
			(xy 67.316604 -384.574542) (xy 67.317011 -384.545299) (xy 67.324444 -384.487287) (xy 67.339208 -384.430695)
			(xy 67.361062 -384.376445) (xy 67.38965 -384.325422) (xy 67.424505 -384.278457) (xy 67.46506 -384.236315)
			(xy 67.510654 -384.199684) (xy 67.560543 -384.16916) (xy 67.613914 -384.145241) (xy 67.669898 -384.128317)
			(xy 67.727582 -384.118664) (xy 67.756786 -384.117088) (xy 67.766438 -384.116834) (xy 67.78371 -384.109214)
			(xy 67.83959 -384.05308) (xy 67.846001 -384.046103) (xy 67.853565 -384.028743) (xy 67.854322 -384.019298)
			(xy 67.854322 -384.019044) (xy 67.855953 -383.986497) (xy 67.866441 -383.922179) (xy 67.88506 -383.859728)
			(xy 67.911504 -383.800167) (xy 67.945341 -383.744472) (xy 67.986015 -383.693557) (xy 68.032861 -383.648255)
			(xy 68.08511 -383.609308) (xy 68.141907 -383.577356) (xy 68.20232 -383.552921) (xy 68.265359 -383.536404)
			(xy 68.329992 -383.528076) (xy 68.362576 -383.527554) (xy 68.39616 -383.528073) (xy 68.462746 -383.536906)
			(xy 68.527587 -383.554434) (xy 68.589554 -383.580352) (xy 68.647566 -383.614207) (xy 68.700612 -383.655411)
			(xy 68.747768 -383.703243) (xy 68.788211 -383.756872) (xy 68.821236 -383.815361) (xy 68.834254 -383.846324)
			(xy 68.834254 -383.846578) (xy 68.838201 -383.855277) (xy 68.851367 -383.869101) (xy 68.86869 -383.877121)
			(xy 68.878196 -383.878074) (xy 68.984622 -383.884678) (xy 69.010276 -383.870454) (xy 69.017388 -383.8575)
			(xy 69.034289 -383.828144) (xy 69.074702 -383.773782) (xy 69.12197 -383.725263) (xy 69.175258 -383.683444)
			(xy 69.233624 -383.649065) (xy 69.296035 -383.622735) (xy 69.361388 -383.604918) (xy 69.428527 -383.59593)
			(xy 69.462396 -383.595372) (xy 69.501649 -383.596125) (xy 69.579214 -383.608253) (xy 69.616828 -383.619502)
			(xy 69.617082 -383.619502) (xy 69.625331 -383.62173) (xy 69.642399 -383.621202) (xy 69.658348 -383.615101)
			(xy 69.665088 -383.60985) (xy 69.730874 -383.55397) (xy 69.737188 -383.548165) (xy 69.745821 -383.533355)
			(xy 69.749068 -383.516524) (xy 69.748146 -383.507996) (xy 69.748146 -383.507742) (xy 69.746254 -383.493977)
			(xy 69.744219 -383.466264) (xy 69.744082 -383.45237) (xy 69.744082 -383.452116) (xy 69.744568 -383.424865)
			(xy 69.752324 -383.370917) (xy 69.767679 -383.318622) (xy 69.790321 -383.269045) (xy 69.819787 -383.223195)
			(xy 69.855478 -383.182004) (xy 69.896669 -383.146313) (xy 69.942519 -383.116847) (xy 69.992096 -383.094205)
			(xy 70.044391 -383.07885) (xy 70.098339 -383.071094) (xy 70.152841 -383.071094) (xy 70.206789 -383.07885)
			(xy 70.259084 -383.094205) (xy 70.308661 -383.116847) (xy 70.354511 -383.146313) (xy 70.395702 -383.182004)
			(xy 70.431393 -383.223195) (xy 70.460859 -383.269045) (xy 70.483501 -383.318622) (xy 70.498856 -383.370917)
			(xy 70.506612 -383.424865) (xy 70.507098 -383.452116) (xy 70.506397 -383.483698) (xy 70.495932 -383.545992)
			(xy 70.48627 -383.576068) (xy 70.483761 -383.584404) (xy 70.483898 -383.601803) (xy 70.486524 -383.610104)
			(xy 70.497192 -383.638552) (xy 70.500545 -383.646604) (xy 70.511705 -383.65999) (xy 70.519036 -383.664714)
			(xy 70.547363 -383.681911) (xy 70.599746 -383.7225) (xy 70.646414 -383.769547) (xy 70.686578 -383.822256)
			(xy 70.719558 -383.879734) (xy 70.744795 -383.941008) (xy 70.761862 -384.00504) (xy 70.77047 -384.070746)
			(xy 70.771004 -384.10388) (xy 70.770562 -384.133989) (xy 70.763432 -384.193785) (xy 70.749291 -384.25232)
			(xy 70.728338 -384.308777) (xy 70.700867 -384.362365) (xy 70.66726 -384.412335) (xy 70.627989 -384.457987)
			(xy 70.583603 -384.498684) (xy 70.559422 -384.51663) (xy 70.549968 -384.524267) (xy 70.538959 -384.545894)
			(xy 70.53834 -384.558032) (xy 70.53834 -384.640328) (xy 70.538963 -384.65246) (xy 70.549988 -384.674073)
			(xy 70.559422 -384.68173) (xy 70.583629 -384.699644) (xy 70.628029 -384.740334) (xy 70.667309 -384.785986)
			(xy 70.700919 -384.835959) (xy 70.728388 -384.889554) (xy 70.749332 -384.946019) (xy 70.763457 -385.004564)
			(xy 70.770564 -385.064368) (xy 70.771004 -385.09448) (xy 70.770544 -385.125212) (xy 70.763137 -385.186228)
			(xy 70.74843 -385.245906) (xy 70.726636 -385.303376) (xy 70.698074 -385.3578) (xy 70.66316 -385.408384)
			(xy 70.622403 -385.454391) (xy 70.576397 -385.49515) (xy 70.525814 -385.530066) (xy 70.47139 -385.55863)
			(xy 70.413921 -385.580425) (xy 70.354243 -385.595134) (xy 70.293228 -385.602543) (xy 70.262496 -385.602988)
			(xy 70.230372 -385.60248) (xy 70.166638 -385.594377) (xy 70.104431 -385.578313) (xy 70.044742 -385.554543)
			(xy 69.988521 -385.523446) (xy 69.936664 -385.485518) (xy 69.912992 -385.463796) (xy 69.90566 -385.457433)
			(xy 69.887639 -385.450253) (xy 69.87794 -385.449826) (xy 69.846952 -385.449826) (xy 69.837248 -385.45023)
			(xy 69.819222 -385.457415) (xy 69.8119 -385.463796) (xy 69.796152 -385.478274) (xy 69.787516 -385.48564)
			(xy 69.778372 -385.506722) (xy 69.781166 -385.596892) (xy 69.782163 -385.608214) (xy 69.792578 -385.628385)
			(xy 69.801232 -385.635754) (xy 69.827565 -385.656419) (xy 69.8751 -385.703547) (xy 69.916039 -385.756507)
			(xy 69.949672 -385.814381) (xy 69.975419 -385.876169) (xy 69.992834 -385.940802) (xy 70.001615 -386.007161)
			(xy 70.002146 -386.04063) (xy 70.001672 -386.07136) (xy 69.994261 -386.132372) (xy 69.97955 -386.192046)
			(xy 69.957754 -386.249512) (xy 69.929191 -386.303932) (xy 69.894278 -386.354512) (xy 69.853522 -386.400516)
			(xy 69.807519 -386.441273) (xy 69.756939 -386.476187) (xy 69.702519 -386.504751) (xy 69.645054 -386.526548)
			(xy 69.58538 -386.54126) (xy 69.524368 -386.548672) (xy 69.493638 -386.549138) (xy 69.462135 -386.548674)
			(xy 69.399613 -386.54088) (xy 69.338534 -386.525419) (xy 69.279833 -386.502528) (xy 69.224412 -386.472559)
			(xy 69.19849 -386.45465) (xy 69.191268 -386.449948) (xy 69.174714 -386.445205) (xy 69.157526 -386.446264)
			(xy 69.149468 -386.449316) (xy 69.057266 -386.488178) (xy 69.041264 -386.508752) (xy 69.039232 -386.52196)
			(xy 69.033741 -386.554298) (xy 69.015513 -386.617309) (xy 68.989337 -386.677453) (xy 68.955646 -386.733734)
			(xy 68.915 -386.785217) (xy 68.868073 -386.831047) (xy 68.815644 -386.870465) (xy 68.758582 -386.902816)
			(xy 68.697836 -386.927563) (xy 68.634412 -386.944295) (xy 68.569363 -386.952736) (xy 68.536566 -386.953252)
			(xy 68.505161 -386.952758) (xy 68.442831 -386.945019) (xy 68.381928 -386.929662) (xy 68.32338 -386.906922)
			(xy 68.268079 -386.877144) (xy 68.216865 -386.840783) (xy 68.17052 -386.798391) (xy 68.129748 -386.750614)
			(xy 68.09517 -386.698179) (xy 68.067314 -386.641885) (xy 68.046602 -386.58259) (xy 68.03335 -386.521194)
			(xy 68.03009 -386.489956) (xy 68.029328 -386.48005) (xy 68.020438 -386.462778) (xy 67.959986 -386.409946)
			(xy 67.952306 -386.403812) (xy 67.933746 -386.397404) (xy 67.923918 -386.3975) (xy 67.899788 -386.398008)
			(xy 67.869057 -386.397555) (xy 67.808043 -386.390145) (xy 67.748366 -386.375435) (xy 67.690898 -386.353639)
			(xy 67.636476 -386.325075) (xy 67.585894 -386.29016) (xy 67.539889 -386.249402) (xy 67.499133 -386.203396)
			(xy 67.464218 -386.152813) (xy 67.435656 -386.098391) (xy 67.413861 -386.040922) (xy 67.399152 -385.981246)
			(xy 67.391744 -385.920231) (xy 67.39128 -385.8895) (xy 67.391725 -385.858718) (xy 67.399116 -385.797601)
			(xy 67.41384 -385.737825) (xy 67.435679 -385.680266) (xy 67.464314 -385.625769) (xy 67.48145 -385.600194)
			(xy 67.486524 -385.592198) (xy 67.490977 -385.573807) (xy 67.490086 -385.56438) (xy 67.485768 -385.533646)
			(xy 67.484118 -385.524379) (xy 67.474987 -385.507936) (xy 67.467988 -385.501642) (xy 67.446154 -385.482963)
			(xy 67.406851 -385.441046) (xy 67.373104 -385.394539) (xy 67.345446 -385.344173) (xy 67.324311 -385.29074)
			(xy 67.310031 -385.235082) (xy 67.302832 -385.178074) (xy 67.30238 -385.149344) (xy 66.219502 -385.149344)
			(xy 66.225679 -385.164413) (xy 66.240903 -385.221808) (xy 66.248575 -385.28069) (xy 66.249042 -385.31038)
			(xy 66.248515 -385.341443) (xy 66.240103 -385.402996) (xy 66.232278 -385.433062) (xy 66.229484 -385.442968)
			(xy 66.232024 -385.463288) (xy 66.274188 -385.536186) (xy 66.279592 -385.544785) (xy 66.295714 -385.557106)
			(xy 66.30543 -385.560062) (xy 66.305684 -385.560062) (xy 66.3348 -385.56804) (xy 66.390765 -385.590678)
			(xy 66.44327 -385.620476) (xy 66.491403 -385.656917) (xy 66.534328 -385.699368) (xy 66.571301 -385.747093)
			(xy 66.60168 -385.799263) (xy 66.624939 -385.854975) (xy 66.640673 -385.913259) (xy 66.648609 -385.973106)
			(xy 66.649092 -386.003292) (xy 66.648992 -386.017042) (xy 66.647337 -386.044493) (xy 66.64579 -386.058156)
			(xy 66.645054 -386.066845) (xy 66.648829 -386.083858) (xy 66.653156 -386.09143) (xy 66.669158 -386.11683)
			(xy 66.673941 -386.123856) (xy 66.687174 -386.134504) (xy 66.695066 -386.137658) (xy 66.718832 -386.146605)
			(xy 66.763482 -386.170793) (xy 66.803909 -386.201522) (xy 66.839162 -386.238072) (xy 66.868412 -386.279583)
			(xy 66.890971 -386.325078) (xy 66.906308 -386.373487) (xy 66.914063 -386.423672) (xy 66.914522 -386.449062)
			(xy 66.91399 -386.47505) (xy 66.905865 -386.526385) (xy 66.889809 -386.575818) (xy 66.866217 -386.62213)
			(xy 66.83567 -386.664182) (xy 66.798921 -386.700936) (xy 66.756875 -386.73149) (xy 66.710566 -386.755089)
			(xy 66.661136 -386.771153) (xy 66.609801 -386.779286) (xy 66.583814 -386.77977) (xy 66.558917 -386.779305)
			(xy 66.509686 -386.771836) (xy 66.462132 -386.757065) (xy 66.417333 -386.735327) (xy 66.376303 -386.707113)
			(xy 66.339971 -386.673063) (xy 66.309158 -386.633946) (xy 66.284563 -386.59065) (xy 66.266743 -386.544153)
			(xy 66.26098 -386.519928) (xy 66.258822 -386.511661) (xy 66.249872 -386.49712) (xy 66.243454 -386.49148)
			(xy 66.205862 -386.460746) (xy 66.191384 -386.461) (xy 66.161416 -386.460533) (xy 66.101992 -386.452708)
			(xy 66.044098 -386.437193) (xy 65.988724 -386.414254) (xy 65.936819 -386.384285) (xy 65.889269 -386.347796)
			(xy 65.846888 -386.305413) (xy 65.810402 -386.257861) (xy 65.780435 -386.205954) (xy 65.757499 -386.150579)
			(xy 65.741988 -386.092684) (xy 65.734166 -386.03326) (xy 65.733676 -386.003292) (xy 65.734196 -385.972229)
			(xy 65.742613 -385.910675) (xy 65.75044 -385.88061) (xy 65.753234 -385.870704) (xy 65.750694 -385.850384)
			(xy 65.70853 -385.777486) (xy 65.70314 -385.768876) (xy 65.68701 -385.756558) (xy 65.677288 -385.75361)
			(xy 65.677034 -385.75361) (xy 65.647914 -385.745645) (xy 65.591947 -385.723007) (xy 65.53944 -385.693209)
			(xy 65.491307 -385.656767) (xy 65.448381 -385.614315) (xy 65.411408 -385.566588) (xy 65.381029 -385.514415)
			(xy 65.357772 -385.458702) (xy 65.342041 -385.400415) (xy 65.334107 -385.340566) (xy 65.333626 -385.31038)
			(xy 65.334148 -385.279492) (xy 65.342454 -385.218276) (xy 65.358911 -385.158732) (xy 65.383223 -385.101941)
			(xy 65.39865 -385.075176) (xy 65.404033 -385.065255) (xy 65.406388 -385.042832) (xy 65.403222 -385.031996)
			(xy 65.377314 -384.958336) (xy 65.373079 -384.947968) (xy 65.357377 -384.932031) (xy 65.347088 -384.927602)
			(xy 65.323705 -384.918422) (xy 65.279808 -384.894003) (xy 65.240112 -384.863221) (xy 65.205531 -384.826787)
			(xy 65.176861 -384.78554) (xy 65.154764 -384.740429) (xy 65.139748 -384.692494) (xy 65.132158 -384.642838)
			(xy 65.131696 -384.617722) (xy 64.593216 -384.617722) (xy 64.593216 -384.61823) (xy 64.592651 -384.645204)
			(xy 64.583844 -384.69843) (xy 64.57569 -384.724148) (xy 64.57188 -384.73507) (xy 64.57442 -384.757422)
			(xy 64.621156 -384.833876) (xy 64.627459 -384.843068) (xy 64.646038 -384.855329) (xy 64.65697 -384.857498)
			(xy 64.657224 -384.857498) (xy 64.686541 -384.862211) (xy 64.743712 -384.878258) (xy 64.798326 -384.901567)
			(xy 64.849465 -384.931746) (xy 64.896271 -384.968286) (xy 64.937956 -385.010575) (xy 64.973821 -385.057901)
			(xy 65.003261 -385.109469) (xy 65.025783 -385.164412) (xy 65.041007 -385.221807) (xy 65.048679 -385.28069)
			(xy 65.049146 -385.31038) (xy 65.049146 -385.310888) (xy 65.048597 -385.341887) (xy 65.040191 -385.403312)
			(xy 65.032382 -385.433316) (xy 65.029588 -385.443222) (xy 65.032128 -385.463542) (xy 65.074038 -385.536186)
			(xy 65.079513 -385.544801) (xy 65.095759 -385.557125) (xy 65.105534 -385.560062) (xy 65.13464 -385.568074)
			(xy 65.190606 -385.590706) (xy 65.243112 -385.620499) (xy 65.291246 -385.656934) (xy 65.334173 -385.699382)
			(xy 65.371147 -385.747103) (xy 65.401528 -385.799271) (xy 65.424787 -385.854979) (xy 65.440522 -385.913262)
			(xy 65.448458 -385.973107) (xy 65.448942 -386.003292) (xy 65.448817 -386.017427) (xy 65.447035 -386.045641)
			(xy 65.445386 -386.05968) (xy 65.444599 -386.068288) (xy 65.448245 -386.085174) (xy 65.452498 -386.0927)
			(xy 65.468246 -386.1181) (xy 65.472938 -386.125174) (xy 65.486056 -386.135935) (xy 65.4939 -386.139182)
			(xy 65.517275 -386.148381) (xy 65.561172 -386.172798) (xy 65.600868 -386.203577) (xy 65.635449 -386.240008)
			(xy 65.66412 -386.281252) (xy 65.686219 -386.32636) (xy 65.701237 -386.374293) (xy 65.708829 -386.423947)
			(xy 65.709292 -386.449062) (xy 65.709292 -386.449316) (xy 65.708846 -386.473517) (xy 65.701779 -386.521401)
			(xy 65.687799 -386.567741) (xy 65.667205 -386.611544) (xy 65.654174 -386.631942) (xy 65.649446 -386.639854)
			(xy 65.645404 -386.657821) (xy 65.6463 -386.666994) (xy 65.650872 -386.697982) (xy 65.652661 -386.707241)
			(xy 65.661917 -386.723654) (xy 65.668906 -386.729986) (xy 65.690975 -386.748679) (xy 65.730714 -386.7907)
			(xy 65.764842 -386.837393) (xy 65.792813 -386.888015) (xy 65.814183 -386.941758) (xy 65.828611 -386.997765)
			(xy 65.835866 -387.055144) (xy 65.836292 -387.084062) (xy 69.88378 -387.084062) (xy 69.887851 -387.02844)
			(xy 69.899977 -386.974003) (xy 69.9199 -386.921912) (xy 69.947196 -386.873277) (xy 69.981282 -386.829134)
			(xy 70.021431 -386.790425) (xy 70.066789 -386.757974) (xy 70.116389 -386.732473) (xy 70.169173 -386.714466)
			(xy 70.224016 -386.704336) (xy 70.27975 -386.702299) (xy 70.335187 -386.708399) (xy 70.389144 -386.722505)
			(xy 70.440473 -386.744317) (xy 70.488079 -386.773371) (xy 70.530947 -386.809046) (xy 70.568164 -386.850583)
			(xy 70.598937 -386.897096) (xy 70.622609 -386.947593) (xy 70.638677 -387.001) (xy 70.646797 -387.056176)
			(xy 70.647306 -387.084062) (xy 70.646797 -387.111948) (xy 70.638677 -387.167124) (xy 70.622609 -387.220531)
			(xy 70.598937 -387.271028) (xy 70.568164 -387.317541) (xy 70.530947 -387.359078) (xy 70.488079 -387.394753)
			(xy 70.440473 -387.423807) (xy 70.389144 -387.445619) (xy 70.335187 -387.459725) (xy 70.27975 -387.465825)
			(xy 70.224016 -387.463788) (xy 70.169173 -387.453658) (xy 70.116389 -387.435651) (xy 70.066789 -387.41015)
			(xy 70.021431 -387.377699) (xy 69.981282 -387.33899) (xy 69.947196 -387.294847) (xy 69.9199 -387.246212)
			(xy 69.899977 -387.194121) (xy 69.887851 -387.139684) (xy 69.88378 -387.084062) (xy 65.836292 -387.084062)
			(xy 65.835706 -387.117426) (xy 65.826061 -387.183451) (xy 65.806927 -387.247375) (xy 65.793366 -387.277864)
			(xy 65.789173 -387.288304) (xy 65.789279 -387.31077) (xy 65.798989 -387.331029) (xy 65.807336 -387.33857)
			(xy 65.829574 -387.357254) (xy 65.869636 -387.399309) (xy 65.904057 -387.446094) (xy 65.932282 -387.496857)
			(xy 65.953859 -387.550783) (xy 65.968441 -387.607005) (xy 65.975793 -387.664621) (xy 65.976246 -387.693662)
			(xy 65.975771 -387.722667) (xy 65.96846 -387.780214) (xy 65.964766 -387.7945) (xy 71.957182 -387.7945)
			(xy 71.961253 -387.738878) (xy 71.973379 -387.684441) (xy 71.993302 -387.63235) (xy 72.020598 -387.583715)
			(xy 72.054684 -387.539572) (xy 72.094833 -387.500863) (xy 72.140191 -387.468412) (xy 72.189791 -387.442911)
			(xy 72.242575 -387.424904) (xy 72.297418 -387.414774) (xy 72.353152 -387.412737) (xy 72.408589 -387.418837)
			(xy 72.462546 -387.432943) (xy 72.513875 -387.454755) (xy 72.561481 -387.483809) (xy 72.604349 -387.519484)
			(xy 72.641566 -387.561021) (xy 72.672339 -387.607534) (xy 72.696011 -387.658031) (xy 72.712079 -387.711438)
			(xy 72.720199 -387.766614) (xy 72.72062 -387.789674) (xy 73.302114 -387.789674) (xy 73.302678 -387.754718)
			(xy 73.312243 -387.685464) (xy 73.331204 -387.618173) (xy 73.359203 -387.554113) (xy 73.395713 -387.494491)
			(xy 73.41743 -387.467094) (xy 73.422674 -387.460154) (xy 73.428515 -387.443782) (xy 73.42886 -387.43509)
			(xy 73.42886 -387.280658) (xy 73.428465 -387.271976) (xy 73.42263 -387.255617) (xy 73.41743 -387.248654)
			(xy 73.395746 -387.221233) (xy 73.359243 -387.161613) (xy 73.331244 -387.097559) (xy 73.312277 -387.030274)
			(xy 73.302698 -386.961027) (xy 73.302114 -386.926074) (xy 73.302532 -386.895342) (xy 73.309944 -386.834325)
			(xy 73.324656 -386.774647) (xy 73.346455 -386.717178) (xy 73.375021 -386.662755) (xy 73.40994 -386.612172)
			(xy 73.450701 -386.566167) (xy 73.49671 -386.52541) (xy 73.547296 -386.490497) (xy 73.601722 -386.461935)
			(xy 73.659193 -386.440142) (xy 73.718873 -386.425435) (xy 73.77989 -386.418029) (xy 73.810622 -386.417566)
			(xy 73.810876 -386.417566) (xy 73.831738 -386.417784) (xy 73.87332 -386.421214) (xy 73.893934 -386.424424)
			(xy 73.902879 -386.425547) (xy 73.920575 -386.422159) (xy 73.928478 -386.41782) (xy 73.985374 -386.383784)
			(xy 73.992855 -386.37889) (xy 74.004047 -386.364965) (xy 74.007218 -386.356606) (xy 74.007218 -386.356098)
			(xy 74.016011 -386.331098) (xy 74.039519 -386.283603) (xy 74.069378 -386.239821) (xy 74.105011 -386.200596)
			(xy 74.145733 -386.166683) (xy 74.190759 -386.138735) (xy 74.239221 -386.117292) (xy 74.290186 -386.102765)
			(xy 74.342671 -386.095436) (xy 74.369168 -386.094986) (xy 74.39642 -386.095485) (xy 74.450369 -386.103238)
			(xy 74.502666 -386.118589) (xy 74.552246 -386.141228) (xy 74.598099 -386.170692) (xy 74.639291 -386.206382)
			(xy 74.674986 -386.247571) (xy 74.704454 -386.293421) (xy 74.727098 -386.342998) (xy 74.742454 -386.395294)
			(xy 74.750212 -386.449242) (xy 74.750676 -386.476494) (xy 74.750108 -386.504464) (xy 74.741967 -386.559807)
			(xy 74.725828 -386.613368) (xy 74.702039 -386.663996) (xy 74.671109 -386.710607) (xy 74.633703 -386.752199)
			(xy 74.590622 -386.787882) (xy 74.542791 -386.816888) (xy 74.491236 -386.838596) (xy 74.437063 -386.852541)
			(xy 74.4093 -386.85597) (xy 74.400156 -386.856732) (xy 74.3839 -386.86486) (xy 74.332084 -386.91947)
			(xy 74.326209 -386.926188) (xy 74.319192 -386.942587) (xy 74.318368 -386.951474) (xy 74.318368 -386.951728)
			(xy 74.316278 -386.984047) (xy 74.304867 -387.047799) (xy 74.285445 -387.109584) (xy 74.258328 -387.1684)
			(xy 74.223955 -387.223292) (xy 74.203814 -387.248654) (xy 74.198596 -387.255612) (xy 74.192738 -387.27197)
			(xy 74.192384 -387.280658) (xy 74.192384 -387.43509) (xy 74.192768 -387.443773) (xy 74.198612 -387.460131)
			(xy 74.203814 -387.467094) (xy 74.225526 -387.494494) (xy 74.262024 -387.554119) (xy 74.290016 -387.61818)
			(xy 74.308977 -387.685469) (xy 74.318549 -387.754719) (xy 74.31913 -387.789674) (xy 74.31913 -387.790182)
			(xy 74.318652 -387.821336) (xy 74.311005 -387.883172) (xy 74.295861 -387.943611) (xy 74.273445 -388.001747)
			(xy 74.259186 -388.02945) (xy 74.254868 -388.037578) (xy 74.252328 -388.055866) (xy 74.271378 -388.138924)
			(xy 74.281538 -388.15391) (xy 74.288904 -388.159498) (xy 74.30943 -388.174952) (xy 74.346567 -388.210457)
			(xy 74.378602 -388.250627) (xy 74.404954 -388.294733) (xy 74.425147 -388.341977) (xy 74.438815 -388.391505)
			(xy 74.445711 -388.442419) (xy 74.44613 -388.468108) (xy 74.445686 -388.495479) (xy 74.437865 -388.54966)
			(xy 74.422372 -388.602164) (xy 74.399525 -388.651911) (xy 74.369794 -388.697876) (xy 74.35215 -388.718806)
			(xy 74.351896 -388.71906) (xy 74.34632 -388.726154) (xy 74.340067 -388.743065) (xy 74.339704 -388.75208)
			(xy 74.339704 -388.819136) (xy 74.340043 -388.828155) (xy 74.346303 -388.845072) (xy 74.351896 -388.852156)
			(xy 74.35215 -388.852156) (xy 74.35215 -388.85241) (xy 74.369799 -388.873334) (xy 74.399511 -388.919308)
			(xy 74.422346 -388.969058) (xy 74.437835 -389.02156) (xy 74.445659 -389.075738) (xy 74.44613 -389.103108)
			(xy 74.445644 -389.130359) (xy 74.437888 -389.184307) (xy 74.422533 -389.236602) (xy 74.399891 -389.286179)
			(xy 74.370425 -389.332029) (xy 74.334734 -389.37322) (xy 74.293543 -389.408911) (xy 74.247693 -389.438377)
			(xy 74.198116 -389.461019) (xy 74.145821 -389.476374) (xy 74.091873 -389.48413) (xy 74.037371 -389.48413)
			(xy 73.983423 -389.476374) (xy 73.931128 -389.461019) (xy 73.881551 -389.438377) (xy 73.835701 -389.408911)
			(xy 73.79451 -389.37322) (xy 73.758819 -389.332029) (xy 73.729353 -389.286179) (xy 73.706711 -389.236602)
			(xy 73.691356 -389.184307) (xy 73.6836 -389.130359) (xy 73.683114 -389.103108) (xy 73.683581 -389.075738)
			(xy 73.691398 -389.021559) (xy 73.706887 -388.969055) (xy 73.729728 -388.919308) (xy 73.759453 -388.873342)
			(xy 73.777094 -388.85241) (xy 73.777348 -388.852156) (xy 73.782923 -388.845062) (xy 73.789175 -388.828151)
			(xy 73.78954 -388.819136) (xy 73.78954 -388.75208) (xy 73.789205 -388.743061) (xy 73.782944 -388.726143)
			(xy 73.777348 -388.71906) (xy 73.777094 -388.71906) (xy 73.777094 -388.718806) (xy 73.759443 -388.697883)
			(xy 73.729733 -388.651908) (xy 73.7069 -388.602158) (xy 73.691411 -388.549655) (xy 73.683586 -388.495478)
			(xy 73.683114 -388.468108) (xy 73.683114 -388.467854) (xy 73.683411 -388.446393) (xy 73.688249 -388.403746)
			(xy 73.692766 -388.382764) (xy 73.694798 -388.37362) (xy 73.692512 -388.35584) (xy 73.656444 -388.288276)
			(xy 73.651851 -388.280484) (xy 73.638329 -388.268496) (xy 73.630028 -388.264908) (xy 73.629774 -388.264908)
			(xy 73.601252 -388.253536) (xy 73.546906 -388.224955) (xy 73.496399 -388.190037) (xy 73.450465 -388.149289)
			(xy 73.409774 -388.103304) (xy 73.374918 -388.052754) (xy 73.346405 -387.998373) (xy 73.324649 -387.940954)
			(xy 73.309968 -387.881332) (xy 73.302575 -387.820375) (xy 73.302114 -387.789674) (xy 72.72062 -387.789674)
			(xy 72.720708 -387.7945) (xy 72.720199 -387.822386) (xy 72.712079 -387.877562) (xy 72.696011 -387.930969)
			(xy 72.672339 -387.981466) (xy 72.641566 -388.027979) (xy 72.604349 -388.069516) (xy 72.561481 -388.105191)
			(xy 72.513875 -388.134245) (xy 72.462546 -388.156057) (xy 72.408589 -388.170163) (xy 72.353152 -388.176263)
			(xy 72.297418 -388.174226) (xy 72.242575 -388.164096) (xy 72.189791 -388.146089) (xy 72.140191 -388.120588)
			(xy 72.094833 -388.088137) (xy 72.054684 -388.049428) (xy 72.020598 -388.005285) (xy 71.993302 -387.95665)
			(xy 71.973379 -387.904559) (xy 71.961253 -387.850122) (xy 71.957182 -387.7945) (xy 65.964766 -387.7945)
			(xy 65.953938 -387.836377) (xy 65.932438 -387.890255) (xy 65.904303 -387.940986) (xy 65.869985 -387.987756)
			(xy 65.830034 -388.029815) (xy 65.807844 -388.0485) (xy 65.800986 -388.054088) (xy 65.791588 -388.069582)
			(xy 65.777872 -388.143242) (xy 65.776677 -388.152003) (xy 65.779669 -388.169415) (xy 65.783714 -388.177278)
			(xy 65.783714 -388.177532) (xy 65.796287 -388.20072) (xy 65.814162 -388.25034) (xy 65.820987 -388.289292)
			(xy 67.369182 -388.289292) (xy 67.369672 -388.259324) (xy 67.377495 -388.199902) (xy 67.393008 -388.142009)
			(xy 67.415944 -388.086636) (xy 67.445911 -388.03473) (xy 67.482398 -387.98718) (xy 67.524778 -387.9448)
			(xy 67.572328 -387.908313) (xy 67.624234 -387.878346) (xy 67.679607 -387.85541) (xy 67.7375 -387.839897)
			(xy 67.796922 -387.832074) (xy 67.856858 -387.832074) (xy 67.91628 -387.839897) (xy 67.974173 -387.85541)
			(xy 68.029546 -387.878346) (xy 68.081452 -387.908313) (xy 68.129002 -387.9448) (xy 68.171382 -387.98718)
			(xy 68.207869 -388.03473) (xy 68.237836 -388.086636) (xy 68.260772 -388.142009) (xy 68.276285 -388.199902)
			(xy 68.284108 -388.259324) (xy 68.284598 -388.289292) (xy 68.284046 -388.321117) (xy 68.275228 -388.384152)
			(xy 68.25776 -388.445358) (xy 68.231981 -388.503553) (xy 68.198386 -388.557615) (xy 68.178426 -388.582408)
			(xy 68.17233 -388.589774) (xy 68.166488 -388.606792) (xy 68.169028 -388.693152) (xy 68.17614 -388.71017)
			(xy 68.18249 -388.717028) (xy 68.194974 -388.730558) (xy 68.21799 -388.759293) (xy 68.228464 -388.774432)
			(xy 68.233955 -388.781865) (xy 68.249089 -388.792447) (xy 68.266998 -388.796955) (xy 68.276216 -388.796276)
			(xy 68.379848 -388.784592) (xy 68.401946 -388.767574) (xy 68.40728 -388.754366) (xy 68.418162 -388.727878)
			(xy 68.44664 -388.678199) (xy 68.482224 -388.633336) (xy 68.524114 -388.594295) (xy 68.571369 -388.561953)
			(xy 68.622927 -388.537039) (xy 68.67763 -388.52011) (xy 68.734249 -388.511548) (xy 68.76288 -388.511034)
			(xy 68.79025 -388.511504) (xy 68.844429 -388.519319) (xy 68.896933 -388.534807) (xy 68.94668 -388.557648)
			(xy 68.992647 -388.587373) (xy 69.013578 -388.605014) (xy 69.013832 -388.605268) (xy 69.020928 -388.61084)
			(xy 69.037838 -388.617094) (xy 69.046852 -388.61746) (xy 69.113908 -388.61746) (xy 69.122926 -388.617116)
			(xy 69.139844 -388.61086) (xy 69.146928 -388.605268) (xy 69.146928 -388.605014) (xy 69.147182 -388.605014)
			(xy 69.168115 -388.587373) (xy 69.214083 -388.557649) (xy 69.263829 -388.534803) (xy 69.316331 -388.519307)
			(xy 69.370509 -388.511478) (xy 69.425251 -388.511478) (xy 69.479429 -388.519307) (xy 69.531931 -388.534803)
			(xy 69.581677 -388.557649) (xy 69.627645 -388.587373) (xy 69.648578 -388.605014) (xy 69.648832 -388.605268)
			(xy 69.655928 -388.61084) (xy 69.672838 -388.617094) (xy 69.681852 -388.61746) (xy 69.748908 -388.61746)
			(xy 69.757926 -388.617116) (xy 69.774844 -388.61086) (xy 69.781928 -388.605268) (xy 69.781928 -388.605014)
			(xy 69.782182 -388.605014) (xy 69.803112 -388.587372) (xy 69.849085 -388.55766) (xy 69.898833 -388.534825)
			(xy 69.951334 -388.519334) (xy 70.005511 -388.511507) (xy 70.03288 -388.511034) (xy 70.060137 -388.511412)
			(xy 70.114096 -388.519167) (xy 70.166402 -388.534523) (xy 70.21599 -388.557167) (xy 70.261851 -388.586638)
			(xy 70.30305 -388.622335) (xy 70.33875 -388.663533) (xy 70.368223 -388.709392) (xy 70.39087 -388.758979)
			(xy 70.40243 -388.798348) (xy 71.741308 -388.798348) (xy 71.741308 -388.743852) (xy 71.749064 -388.68991)
			(xy 71.764417 -388.63762) (xy 71.787055 -388.588048) (xy 71.816517 -388.542202) (xy 71.852204 -388.501016)
			(xy 71.893389 -388.465327) (xy 71.939234 -388.435863) (xy 71.988805 -388.413222) (xy 72.041094 -388.397867)
			(xy 72.095036 -388.390109) (xy 72.122284 -388.389622) (xy 72.149654 -388.390092) (xy 72.203833 -388.397908)
			(xy 72.256337 -388.413396) (xy 72.306083 -388.436237) (xy 72.35205 -388.465961) (xy 72.372982 -388.483602)
			(xy 72.373236 -388.483856) (xy 72.380332 -388.489429) (xy 72.397242 -388.495682) (xy 72.406256 -388.496048)
			(xy 72.473312 -388.496048) (xy 72.482331 -388.495708) (xy 72.499248 -388.48945) (xy 72.506332 -388.483856)
			(xy 72.506332 -388.483602) (xy 72.506586 -388.483602) (xy 72.527513 -388.465956) (xy 72.573487 -388.436245)
			(xy 72.623236 -388.413411) (xy 72.675738 -388.397921) (xy 72.729914 -388.390095) (xy 72.757284 -388.389622)
			(xy 72.78454 -388.390024) (xy 72.838497 -388.39778) (xy 72.890801 -388.413135) (xy 72.940387 -388.435779)
			(xy 72.986246 -388.465249) (xy 73.027443 -388.500945) (xy 73.063142 -388.542142) (xy 73.092613 -388.587999)
			(xy 73.115259 -388.637584) (xy 73.130617 -388.689888) (xy 73.138375 -388.743844) (xy 73.138375 -388.798356)
			(xy 73.130617 -388.852312) (xy 73.115259 -388.904616) (xy 73.092613 -388.954201) (xy 73.063142 -389.000058)
			(xy 73.027443 -389.041255) (xy 72.986246 -389.076951) (xy 72.940387 -389.106421) (xy 72.890801 -389.129065)
			(xy 72.838497 -389.14442) (xy 72.78454 -389.152176) (xy 72.757284 -389.152638) (xy 72.729913 -389.152196)
			(xy 72.675732 -389.144375) (xy 72.623228 -389.128881) (xy 72.573481 -389.106033) (xy 72.527516 -389.076303)
			(xy 72.506586 -389.058658) (xy 72.506332 -389.058404) (xy 72.49924 -389.052825) (xy 72.482327 -389.046574)
			(xy 72.473312 -389.046212) (xy 72.406256 -389.046212) (xy 72.397242 -389.046593) (xy 72.380324 -389.052824)
			(xy 72.373236 -389.058404) (xy 72.373236 -389.058658) (xy 72.372982 -389.058658) (xy 72.352024 -389.076266)
			(xy 72.306059 -389.105984) (xy 72.256318 -389.128826) (xy 72.203823 -389.144325) (xy 72.149652 -389.15216)
			(xy 72.122284 -389.152638) (xy 72.095036 -389.152091) (xy 72.041094 -389.144333) (xy 71.988805 -389.128978)
			(xy 71.939234 -389.106337) (xy 71.893389 -389.076873) (xy 71.852204 -389.041184) (xy 71.816517 -388.999998)
			(xy 71.787055 -388.954152) (xy 71.764417 -388.90458) (xy 71.749064 -388.85229) (xy 71.741308 -388.798348)
			(xy 70.40243 -388.798348) (xy 70.406229 -388.811285) (xy 70.413987 -388.865243) (xy 70.413987 -388.919757)
			(xy 70.406229 -388.973715) (xy 70.39087 -389.026021) (xy 70.368223 -389.075608) (xy 70.33875 -389.121467)
			(xy 70.30305 -389.162665) (xy 70.261851 -389.198362) (xy 70.21599 -389.227833) (xy 70.166402 -389.250477)
			(xy 70.114096 -389.265833) (xy 70.060137 -389.273588) (xy 70.03288 -389.27405) (xy 70.005509 -389.273608)
			(xy 69.951328 -389.265786) (xy 69.898824 -389.250292) (xy 69.849078 -389.227445) (xy 69.803112 -389.197714)
			(xy 69.782182 -389.18007) (xy 69.781928 -389.179816) (xy 69.774836 -389.174237) (xy 69.757924 -389.167985)
			(xy 69.748908 -389.167624) (xy 69.681852 -389.167624) (xy 69.672837 -389.168001) (xy 69.65592 -389.174234)
			(xy 69.648832 -389.179816) (xy 69.648832 -389.18007) (xy 69.648578 -389.18007) (xy 69.627645 -389.197711)
			(xy 69.581677 -389.227435) (xy 69.531931 -389.250281) (xy 69.479429 -389.265777) (xy 69.425251 -389.273606)
			(xy 69.370509 -389.273606) (xy 69.316331 -389.265777) (xy 69.263829 -389.250281) (xy 69.214083 -389.227435)
			(xy 69.168115 -389.197711) (xy 69.147182 -389.18007) (xy 69.146928 -389.179816) (xy 69.139836 -389.174237)
			(xy 69.122924 -389.167985) (xy 69.113908 -389.167624) (xy 69.046852 -389.167624) (xy 69.037837 -389.168001)
			(xy 69.02092 -389.174234) (xy 69.013832 -389.179816) (xy 69.013832 -389.18007) (xy 69.013578 -389.18007)
			(xy 68.992623 -389.197681) (xy 68.946657 -389.227398) (xy 68.896916 -389.25024) (xy 68.84442 -389.265738)
			(xy 68.790248 -389.273573) (xy 68.76288 -389.27405) (xy 68.734278 -389.273565) (xy 68.677713 -389.265027)
			(xy 68.623056 -389.248145) (xy 68.571529 -389.223297) (xy 68.524287 -389.19104) (xy 68.482385 -389.152095)
			(xy 68.464176 -389.130032) (xy 68.455286 -389.118856) (xy 68.42887 -389.10895) (xy 68.326762 -389.128508)
			(xy 68.317747 -389.130652) (xy 68.301996 -389.140388) (xy 68.290708 -389.155067) (xy 68.287646 -389.163814)
			(xy 68.27754 -389.195157) (xy 68.249571 -389.254777) (xy 68.213335 -389.309765) (xy 68.191888 -389.334756)
			(xy 68.185966 -389.341915) (xy 68.17933 -389.359254) (xy 68.178934 -389.368538) (xy 68.178934 -389.435848)
			(xy 68.179397 -389.445118) (xy 68.186026 -389.462436) (xy 68.191888 -389.46963) (xy 68.213475 -389.494858)
			(xy 68.249845 -389.550409) (xy 68.277809 -389.61063) (xy 68.296781 -389.674259) (xy 68.306363 -389.739961)
			(xy 68.30695 -389.77316) (xy 68.306388 -389.804758) (xy 68.29766 -389.867349) (xy 68.28042 -389.928149)
			(xy 68.254993 -389.986005) (xy 68.238878 -390.01319) (xy 68.234345 -390.021419) (xy 68.230893 -390.039866)
			(xy 68.23432 -390.058317) (xy 68.238878 -390.06653) (xy 68.255031 -390.093697) (xy 68.280491 -390.151547)
			(xy 68.297733 -390.212354) (xy 68.306425 -390.274958) (xy 68.30695 -390.30656) (xy 68.306427 -390.338186)
			(xy 68.302684 -390.365051) (xy 70.12228 -390.365051) (xy 70.12228 -390.310549) (xy 70.130036 -390.256603)
			(xy 70.14539 -390.20431) (xy 70.16803 -390.154733) (xy 70.197496 -390.108884) (xy 70.233186 -390.067694)
			(xy 70.274374 -390.032003) (xy 70.320223 -390.002536) (xy 70.369798 -389.979895) (xy 70.422091 -389.964538)
			(xy 70.476037 -389.956781) (xy 70.503288 -389.956294) (xy 70.530658 -389.956769) (xy 70.584837 -389.964585)
			(xy 70.63734 -389.980072) (xy 70.687087 -390.002912) (xy 70.733054 -390.032634) (xy 70.753986 -390.050274)
			(xy 70.75424 -390.050528) (xy 70.761337 -390.056099) (xy 70.778246 -390.062354) (xy 70.78726 -390.06272)
			(xy 70.854316 -390.06272) (xy 70.863333 -390.062366) (xy 70.88025 -390.056116) (xy 70.887336 -390.050528)
			(xy 70.887336 -390.050274) (xy 70.88759 -390.050274) (xy 70.908512 -390.032622) (xy 70.954488 -390.002913)
			(xy 71.004238 -389.98008) (xy 71.056741 -389.964592) (xy 71.110918 -389.956767) (xy 71.138288 -389.956294)
			(xy 71.165542 -389.956753) (xy 71.219494 -389.964508) (xy 71.271794 -389.979863) (xy 71.321376 -390.002505)
			(xy 71.36723 -390.031973) (xy 71.408425 -390.067667) (xy 71.44412 -390.10886) (xy 71.473589 -390.154714)
			(xy 71.496233 -390.204295) (xy 71.511589 -390.256594) (xy 71.519347 -390.310546) (xy 71.519347 -390.365054)
			(xy 71.511589 -390.419006) (xy 71.496233 -390.471305) (xy 71.473589 -390.520886) (xy 71.44412 -390.56674)
			(xy 71.408425 -390.607933) (xy 71.36723 -390.643627) (xy 71.321376 -390.673095) (xy 71.271794 -390.695737)
			(xy 71.219494 -390.711092) (xy 71.165542 -390.718847) (xy 71.138288 -390.71931) (xy 71.110918 -390.718849)
			(xy 71.056738 -390.711029) (xy 71.004235 -390.695539) (xy 70.954489 -390.672696) (xy 70.908522 -390.642971)
			(xy 70.88759 -390.62533) (xy 70.887336 -390.625076) (xy 70.880245 -390.619496) (xy 70.863332 -390.613246)
			(xy 70.854316 -390.612884) (xy 70.78726 -390.612884) (xy 70.778242 -390.613225) (xy 70.761325 -390.619484)
			(xy 70.75424 -390.625076) (xy 70.75424 -390.62533) (xy 70.753986 -390.62533) (xy 70.733036 -390.642947)
			(xy 70.687068 -390.672661) (xy 70.637325 -390.695501) (xy 70.584828 -390.710997) (xy 70.530656 -390.718832)
			(xy 70.503288 -390.71931) (xy 70.476037 -390.718819) (xy 70.422091 -390.711062) (xy 70.369798 -390.695705)
			(xy 70.320223 -390.673064) (xy 70.274374 -390.643597) (xy 70.233186 -390.607906) (xy 70.197496 -390.566716)
			(xy 70.16803 -390.520867) (xy 70.14539 -390.47129) (xy 70.130036 -390.418997) (xy 70.12228 -390.365051)
			(xy 68.302684 -390.365051) (xy 68.297698 -390.400834) (xy 68.280429 -390.461684) (xy 68.254949 -390.519577)
			(xy 68.221742 -390.573412) (xy 68.181441 -390.622164) (xy 68.134813 -390.664905) (xy 68.082746 -390.70082)
			(xy 68.054728 -390.7155) (xy 68.045363 -390.720766) (xy 68.031829 -390.737427) (xy 68.026303 -390.758169)
			(xy 68.02755 -390.76884) (xy 68.02934 -390.781336) (xy 68.031249 -390.806509) (xy 68.03136 -390.819132)
			(xy 68.03085 -390.845119) (xy 68.02272 -390.896454) (xy 68.006659 -390.945884) (xy 67.983063 -390.992194)
			(xy 67.952513 -391.034242) (xy 67.915762 -391.070993) (xy 67.873714 -391.101543) (xy 67.827404 -391.125139)
			(xy 67.777974 -391.1412) (xy 67.726639 -391.14933) (xy 67.674665 -391.14933) (xy 67.62333 -391.1412)
			(xy 67.5739 -391.125139) (xy 67.52759 -391.101543) (xy 67.485542 -391.070993) (xy 67.448791 -391.034242)
			(xy 67.418241 -390.992194) (xy 67.394645 -390.945884) (xy 67.378584 -390.896454) (xy 67.370454 -390.845119)
			(xy 67.369944 -390.819132) (xy 67.370336 -390.795394) (xy 67.377133 -390.748406) (xy 67.390579 -390.702873)
			(xy 67.410396 -390.659729) (xy 67.436178 -390.619863) (xy 67.451478 -390.601708) (xy 67.458142 -390.593332)
			(xy 67.464473 -390.572909) (xy 67.461908 -390.551682) (xy 67.456812 -390.542272) (xy 67.441322 -390.51546)
			(xy 67.416915 -390.458552) (xy 67.40039 -390.398877) (xy 67.392048 -390.33752) (xy 67.391534 -390.30656)
			(xy 67.392107 -390.274963) (xy 67.400832 -390.212372) (xy 67.418069 -390.151572) (xy 67.443493 -390.093716)
			(xy 67.459606 -390.06653) (xy 67.464205 -390.058333) (xy 67.467635 -390.039866) (xy 67.46418 -390.021403)
			(xy 67.459606 -390.01319) (xy 67.44346 -389.986019) (xy 67.417998 -389.928171) (xy 67.400755 -389.867365)
			(xy 67.39206 -389.804762) (xy 67.391534 -389.77316) (xy 67.392106 -389.739926) (xy 67.401714 -389.674156)
			(xy 67.420737 -389.610468) (xy 67.448774 -389.550203) (xy 67.485236 -389.494628) (xy 67.50685 -389.469376)
			(xy 67.512763 -389.462211) (xy 67.519403 -389.444876) (xy 67.519804 -389.435594) (xy 67.519804 -389.368284)
			(xy 67.519365 -389.359012) (xy 67.512719 -389.341694) (xy 67.50685 -389.334502) (xy 67.485284 -389.309257)
			(xy 67.44891 -389.253711) (xy 67.420941 -389.193495) (xy 67.401964 -389.129869) (xy 67.392377 -389.06417)
			(xy 67.391788 -389.030972) (xy 67.392323 -388.999147) (xy 67.401145 -388.93611) (xy 67.418617 -388.874905)
			(xy 67.444401 -388.81671) (xy 67.477998 -388.762649) (xy 67.49796 -388.737856) (xy 67.504056 -388.73049)
			(xy 67.509898 -388.713472) (xy 67.507358 -388.627112) (xy 67.500246 -388.610094) (xy 67.493896 -388.603236)
			(xy 67.474416 -388.58196) (xy 67.440421 -388.535353) (xy 67.412554 -388.484843) (xy 67.391258 -388.43123)
			(xy 67.37687 -388.375366) (xy 67.36962 -388.318136) (xy 67.369182 -388.289292) (xy 65.820987 -388.289292)
			(xy 65.823264 -388.302291) (xy 65.823846 -388.328662) (xy 65.823777 -388.338021) (xy 65.822634 -388.356703)
			(xy 65.82156 -388.366) (xy 65.820544 -388.374636) (xy 65.824354 -388.391908) (xy 65.868042 -388.46125)
			(xy 65.882012 -388.471918) (xy 65.890394 -388.474712) (xy 65.914413 -388.483204) (xy 65.959587 -388.506751)
			(xy 66.000393 -388.537245) (xy 66.035774 -388.573895) (xy 66.064812 -388.615751) (xy 66.086752 -388.661726)
			(xy 66.094356 -388.68604) (xy 66.09588 -388.691882) (xy 66.416174 -389.245602) (xy 66.420238 -389.24992)
			(xy 66.4364 -389.267584) (xy 66.463719 -389.306902) (xy 66.484786 -389.349895) (xy 66.499119 -389.395576)
			(xy 66.506389 -389.442898) (xy 66.506852 -389.466836) (xy 66.506852 -389.467344) (xy 66.506423 -389.492136)
			(xy 66.49866 -389.541108) (xy 66.483332 -389.588262) (xy 66.460816 -389.632439) (xy 66.431668 -389.672549)
			(xy 66.396604 -389.707607) (xy 66.356488 -389.736748) (xy 66.312307 -389.759255) (xy 66.265149 -389.774574)
			(xy 66.216176 -389.782327) (xy 66.191384 -389.782812) (xy 66.165989 -389.782326) (xy 66.115855 -389.774193)
			(xy 66.067669 -389.758139) (xy 66.022675 -389.734578) (xy 65.982032 -389.704119) (xy 65.94679 -389.667546)
			(xy 65.917856 -389.625803) (xy 65.895978 -389.579967) (xy 65.888362 -389.555736) (xy 65.886838 -389.549894)
			(xy 65.566544 -388.996174) (xy 65.56248 -388.991856) (xy 65.546273 -388.97415) (xy 65.51885 -388.934759)
			(xy 65.497708 -388.891668) (xy 65.483335 -388.845874) (xy 65.476062 -388.798431) (xy 65.475612 -388.774432)
			(xy 65.475754 -388.76238) (xy 65.47766 -388.73835) (xy 65.479422 -388.726426) (xy 65.480394 -388.717667)
			(xy 65.477025 -388.700386) (xy 65.472818 -388.692644) (xy 65.440052 -388.637272) (xy 65.435362 -388.629985)
			(xy 65.422117 -388.618825) (xy 65.414144 -388.615428) (xy 65.413636 -388.615428) (xy 65.391912 -388.607009)
			(xy 65.351108 -388.584529) (xy 65.31419 -388.556113) (xy 65.282014 -388.522421) (xy 65.255328 -388.484234)
			(xy 65.23475 -388.442438) (xy 65.220757 -388.398002) (xy 65.213673 -388.351956) (xy 65.21323 -388.328662)
			(xy 65.213792 -388.302289) (xy 65.222876 -388.25033) (xy 65.240766 -388.20071) (xy 65.253362 -388.177532)
			(xy 65.253362 -388.177278) (xy 65.257376 -388.169404) (xy 65.260372 -388.152002) (xy 65.259204 -388.143242)
			(xy 65.245488 -388.069582) (xy 65.23609 -388.054088) (xy 65.229232 -388.0485) (xy 65.207068 -388.029786)
			(xy 65.167119 -387.987727) (xy 65.1328 -387.940961) (xy 65.10466 -387.890236) (xy 65.083149 -387.836364)
			(xy 65.068612 -387.780208) (xy 65.061281 -387.722666) (xy 65.06083 -387.693662) (xy 65.06083 -387.693408)
			(xy 65.061412 -387.660086) (xy 65.071078 -387.594148) (xy 65.090207 -387.530309) (xy 65.103756 -387.49986)
			(xy 65.108014 -387.489442) (xy 65.10788 -387.46696) (xy 65.098144 -387.446695) (xy 65.089786 -387.439154)
			(xy 65.067516 -387.420507) (xy 65.027455 -387.378446) (xy 64.993037 -387.331655) (xy 64.964815 -387.280885)
			(xy 64.943243 -387.226953) (xy 64.928668 -387.170725) (xy 64.921324 -387.113105) (xy 64.920876 -387.084062)
			(xy 64.920876 -387.083808) (xy 64.921315 -387.054909) (xy 64.928602 -386.997571) (xy 64.943047 -386.941606)
			(xy 64.964421 -386.887905) (xy 64.992384 -386.83732) (xy 65.026492 -386.790658) (xy 65.066202 -386.74866)
			(xy 65.088262 -386.729986) (xy 65.095349 -386.723737) (xy 65.104609 -386.70728) (xy 65.106296 -386.697982)
			(xy 65.110868 -386.666994) (xy 65.111781 -386.657821) (xy 65.107735 -386.639849) (xy 65.102994 -386.631942)
			(xy 65.086679 -386.606124) (xy 65.062907 -386.549873) (xy 65.05575 -386.520182) (xy 65.053608 -386.511955)
			(xy 65.044782 -386.497438) (xy 65.038478 -386.491734) (xy 65.00114 -386.461) (xy 64.991234 -386.461)
			(xy 64.961265 -386.460507) (xy 64.901841 -386.452688) (xy 64.843945 -386.437178) (xy 64.788569 -386.414244)
			(xy 64.736661 -386.384278) (xy 64.689108 -386.347792) (xy 64.646725 -386.305411) (xy 64.610237 -386.257861)
			(xy 64.580267 -386.205954) (xy 64.55733 -386.15058) (xy 64.541817 -386.092685) (xy 64.533995 -386.033261)
			(xy 64.533526 -386.003292) (xy 64.534048 -385.972229) (xy 64.542463 -385.910675) (xy 64.55029 -385.88061)
			(xy 64.553084 -385.870704) (xy 64.550544 -385.850384) (xy 64.508126 -385.777232) (xy 64.502675 -385.76872)
			(xy 64.486557 -385.756546) (xy 64.476884 -385.75361) (xy 64.447805 -385.745544) (xy 64.391878 -385.722884)
			(xy 64.339412 -385.693073) (xy 64.291316 -385.656629) (xy 64.248424 -385.614183) (xy 64.21148 -385.56647)
			(xy 64.181123 -385.514318) (xy 64.15788 -385.45863) (xy 64.142154 -385.400371) (xy 64.134217 -385.340552)
			(xy 64.13373 -385.31038) (xy 64.134252 -385.279492) (xy 64.142557 -385.218276) (xy 64.159015 -385.158732)
			(xy 64.183327 -385.10194) (xy 64.198754 -385.075176) (xy 64.204137 -385.065255) (xy 64.206492 -385.042832)
			(xy 64.203326 -385.031996) (xy 64.177418 -384.958336) (xy 64.173182 -384.947969) (xy 64.15748 -384.932031)
			(xy 64.147192 -384.927602) (xy 64.12381 -384.91842) (xy 64.079913 -384.894001) (xy 64.040216 -384.86322)
			(xy 64.005635 -384.826786) (xy 63.976966 -384.785539) (xy 63.954868 -384.740429) (xy 63.939852 -384.692494)
			(xy 63.932262 -384.642838) (xy 63.9318 -384.617722) (xy 63.393066 -384.617722) (xy 63.393066 -384.61823)
			(xy 63.392499 -384.645204) (xy 63.383693 -384.69843) (xy 63.37554 -384.724148) (xy 63.37173 -384.73507)
			(xy 63.37427 -384.757422) (xy 63.421006 -384.833876) (xy 63.427287 -384.843086) (xy 63.445882 -384.855337)
			(xy 63.45682 -384.857498) (xy 63.457074 -384.857498) (xy 63.486398 -384.862172) (xy 63.543569 -384.878225)
			(xy 63.598182 -384.90154) (xy 63.649321 -384.931723) (xy 63.696126 -384.968268) (xy 63.73781 -385.010561)
			(xy 63.773674 -385.05789) (xy 63.803113 -385.109461) (xy 63.825634 -385.164407) (xy 63.840858 -385.221804)
			(xy 63.848529 -385.280689) (xy 63.848996 -385.31038) (xy 63.848471 -385.341443) (xy 63.840058 -385.402997)
			(xy 63.832232 -385.433062) (xy 63.829438 -385.442968) (xy 63.831978 -385.463288) (xy 63.874142 -385.536186)
			(xy 63.879525 -385.544801) (xy 63.895661 -385.557114) (xy 63.905384 -385.560062) (xy 63.905638 -385.560062)
			(xy 63.934745 -385.568071) (xy 63.990711 -385.590704) (xy 64.043217 -385.620497) (xy 64.091351 -385.656933)
			(xy 64.134277 -385.69938) (xy 64.171251 -385.747102) (xy 64.201632 -385.79927) (xy 64.224891 -385.854979)
			(xy 64.240626 -385.913262) (xy 64.248562 -385.973107) (xy 64.249046 -386.003292) (xy 64.248921 -386.017427)
			(xy 64.247139 -386.045641) (xy 64.24549 -386.05968) (xy 64.244703 -386.068288) (xy 64.248348 -386.085174)
			(xy 64.252602 -386.0927) (xy 64.26835 -386.1181) (xy 64.273072 -386.12515) (xy 64.286169 -386.135925)
			(xy 64.294004 -386.139182) (xy 64.31738 -386.148379) (xy 64.361276 -386.172797) (xy 64.400972 -386.203575)
			(xy 64.435554 -386.240007) (xy 64.464224 -386.281252) (xy 64.486323 -386.32636) (xy 64.501341 -386.374293)
			(xy 64.508933 -386.423947) (xy 64.509396 -386.449062) (xy 64.509396 -386.449316) (xy 64.508949 -386.473517)
			(xy 64.501882 -386.521401) (xy 64.487902 -386.567741) (xy 64.467308 -386.611544) (xy 64.454278 -386.631942)
			(xy 64.449551 -386.639854) (xy 64.445508 -386.657821) (xy 64.446404 -386.666994) (xy 64.450976 -386.697982)
			(xy 64.452764 -386.707241) (xy 64.462021 -386.723654) (xy 64.46901 -386.729986) (xy 64.49108 -386.748678)
			(xy 64.530819 -386.790699) (xy 64.564946 -386.837393) (xy 64.592918 -386.888014) (xy 64.614288 -386.941758)
			(xy 64.628715 -386.997765) (xy 64.63597 -387.055144) (xy 64.636396 -387.084062) (xy 64.635809 -387.117426)
			(xy 64.626165 -387.183451) (xy 64.607031 -387.247375) (xy 64.59347 -387.277864) (xy 64.589276 -387.288303)
			(xy 64.589382 -387.31077) (xy 64.599093 -387.331029) (xy 64.60744 -387.33857) (xy 64.629658 -387.357278)
			(xy 64.669725 -387.399326) (xy 64.70415 -387.446105) (xy 64.732379 -387.496864) (xy 64.75396 -387.550788)
			(xy 64.768544 -387.607008) (xy 64.775897 -387.664622) (xy 64.77635 -387.693662) (xy 64.775874 -387.722667)
			(xy 64.768563 -387.780214) (xy 64.754041 -387.836377) (xy 64.732541 -387.890255) (xy 64.704406 -387.940985)
			(xy 64.670088 -387.987755) (xy 64.630137 -388.029815) (xy 64.607948 -388.0485) (xy 64.60109 -388.054088)
			(xy 64.591692 -388.069582) (xy 64.577976 -388.143242) (xy 64.576781 -388.152003) (xy 64.579772 -388.169416)
			(xy 64.583818 -388.177278) (xy 64.583818 -388.177532) (xy 64.596391 -388.20072) (xy 64.614266 -388.25034)
			(xy 64.623368 -388.302291) (xy 64.62395 -388.328662) (xy 64.623881 -388.338021) (xy 64.622738 -388.356703)
			(xy 64.621664 -388.366) (xy 64.620648 -388.374636) (xy 64.624458 -388.391908) (xy 64.668146 -388.46125)
			(xy 64.682116 -388.471918) (xy 64.690498 -388.474712) (xy 64.714595 -388.483193) (xy 64.759886 -388.506818)
			(xy 64.800781 -388.537429) (xy 64.836213 -388.574226) (xy 64.865256 -388.616249) (xy 64.887152 -388.662401)
			(xy 64.894714 -388.686802) (xy 64.896238 -388.692644) (xy 65.216024 -389.245602) (xy 65.220088 -389.24992)
			(xy 65.236278 -389.26764) (xy 65.263704 -389.307028) (xy 65.28485 -389.350114) (xy 65.299227 -389.395906)
			(xy 65.306504 -389.443346) (xy 65.306956 -389.467344) (xy 65.306524 -389.492123) (xy 65.298769 -389.54107)
			(xy 65.283457 -389.588203) (xy 65.260964 -389.632362) (xy 65.231843 -389.672461) (xy 65.196812 -389.707515)
			(xy 65.156731 -389.73666) (xy 65.112586 -389.759181) (xy 65.065463 -389.774522) (xy 65.01652 -389.782308)
			(xy 64.991742 -389.782812) (xy 64.991234 -389.782812) (xy 64.965841 -389.782282) (xy 64.915708 -389.774156)
			(xy 64.867524 -389.75811) (xy 64.822529 -389.734556) (xy 64.781886 -389.704103) (xy 64.746643 -389.667535)
			(xy 64.717708 -389.625797) (xy 64.695829 -389.579965) (xy 64.688212 -389.555736) (xy 64.686688 -389.549894)
			(xy 64.36614 -388.995412) (xy 64.362076 -388.991094) (xy 64.345977 -388.973421) (xy 64.318727 -388.934143)
			(xy 64.297715 -388.891204) (xy 64.283422 -388.845586) (xy 64.276175 -388.798334) (xy 64.275716 -388.774432)
			(xy 64.275858 -388.76238) (xy 64.277764 -388.73835) (xy 64.279526 -388.726426) (xy 64.280497 -388.717667)
			(xy 64.277129 -388.700386) (xy 64.272922 -388.692644) (xy 64.240156 -388.637272) (xy 64.235465 -388.629986)
			(xy 64.22222 -388.618825) (xy 64.214248 -388.615428) (xy 64.21374 -388.615428) (xy 64.192017 -388.607007)
			(xy 64.151212 -388.584527) (xy 64.114294 -388.556112) (xy 64.082119 -388.52242) (xy 64.055432 -388.484234)
			(xy 64.034854 -388.442438) (xy 64.020861 -388.398001) (xy 64.013777 -388.351956) (xy 64.013334 -388.328662)
			(xy 64.013895 -388.302289) (xy 64.022979 -388.25033) (xy 64.04087 -388.20071) (xy 64.053466 -388.177532)
			(xy 64.053466 -388.177278) (xy 64.05748 -388.169404) (xy 64.060476 -388.152002) (xy 64.059308 -388.143242)
			(xy 64.045592 -388.069582) (xy 64.036194 -388.054088) (xy 64.029336 -388.0485) (xy 64.007173 -388.029785)
			(xy 63.967224 -387.987726) (xy 63.932905 -387.94096) (xy 63.904764 -387.890236) (xy 63.883253 -387.836364)
			(xy 63.868716 -387.780208) (xy 63.861385 -387.722666) (xy 63.860934 -387.693662) (xy 63.860934 -387.693408)
			(xy 63.861516 -387.660086) (xy 63.871182 -387.594148) (xy 63.890311 -387.530309) (xy 63.90386 -387.49986)
			(xy 63.908117 -387.489442) (xy 63.907983 -387.46696) (xy 63.898248 -387.446695) (xy 63.88989 -387.439154)
			(xy 63.867621 -387.420506) (xy 63.827559 -387.378445) (xy 63.793141 -387.331654) (xy 63.764919 -387.280885)
			(xy 63.743347 -387.226953) (xy 63.728772 -387.170725) (xy 63.721428 -387.113105) (xy 63.72098 -387.084062)
			(xy 63.72098 -387.083808) (xy 63.721418 -387.054909) (xy 63.728704 -386.997571) (xy 63.743149 -386.941606)
			(xy 63.764524 -386.887904) (xy 63.792487 -386.83732) (xy 63.826595 -386.790658) (xy 63.866305 -386.74866)
			(xy 63.888366 -386.729986) (xy 63.895453 -386.723737) (xy 63.904713 -386.70728) (xy 63.9064 -386.697982)
			(xy 63.910972 -386.666994) (xy 63.911884 -386.657821) (xy 63.907839 -386.639849) (xy 63.903098 -386.631942)
			(xy 63.886784 -386.606124) (xy 63.863011 -386.549873) (xy 63.855854 -386.520182) (xy 63.853711 -386.511956)
			(xy 63.844886 -386.497438) (xy 63.838582 -386.491734) (xy 63.801244 -386.461) (xy 63.791338 -386.461)
			(xy 63.76137 -386.460503) (xy 63.701945 -386.452684) (xy 63.644049 -386.437175) (xy 63.588673 -386.414242)
			(xy 63.536765 -386.384276) (xy 63.489212 -386.347791) (xy 63.446829 -386.30541) (xy 63.410341 -386.25786)
			(xy 63.380371 -386.205954) (xy 63.357434 -386.150579) (xy 63.341921 -386.092685) (xy 63.334099 -386.03326)
			(xy 63.33363 -386.003292) (xy 63.334151 -385.972229) (xy 63.342567 -385.910675) (xy 63.350394 -385.88061)
			(xy 63.353188 -385.870704) (xy 63.350648 -385.850384) (xy 63.308484 -385.777486) (xy 63.303072 -385.768892)
			(xy 63.286957 -385.756566) (xy 63.277242 -385.75361) (xy 63.276988 -385.75361) (xy 63.247878 -385.745609)
			(xy 63.19191 -385.722978) (xy 63.139403 -385.693185) (xy 63.091268 -385.656749) (xy 63.048341 -385.6143)
			(xy 63.011366 -385.566577) (xy 62.980986 -385.514408) (xy 62.957728 -385.458697) (xy 62.941996 -385.400412)
			(xy 62.934062 -385.340565) (xy 62.93358 -385.31038) (xy 62.934109 -385.279492) (xy 62.942413 -385.218277)
			(xy 62.958869 -385.158733) (xy 62.983178 -385.101941) (xy 62.998604 -385.075176) (xy 63.003987 -385.065256)
			(xy 63.00634 -385.042832) (xy 63.003176 -385.031996) (xy 62.977268 -384.958336) (xy 62.97301 -384.94798)
			(xy 62.957323 -384.932038) (xy 62.947042 -384.927602) (xy 62.923649 -384.918447) (xy 62.879753 -384.894022)
			(xy 62.840059 -384.863235) (xy 62.80548 -384.826797) (xy 62.776812 -384.785547) (xy 62.754716 -384.740434)
			(xy 62.739701 -384.692496) (xy 62.732112 -384.642839) (xy 62.73165 -384.617722) (xy 62.19317 -384.617722)
			(xy 62.19317 -384.61823) (xy 62.192603 -384.645204) (xy 62.183797 -384.69843) (xy 62.175644 -384.724148)
			(xy 62.171834 -384.73507) (xy 62.174374 -384.757422) (xy 62.22111 -384.833876) (xy 62.227389 -384.843088)
			(xy 62.245986 -384.855338) (xy 62.256924 -384.857498) (xy 62.257178 -384.857498) (xy 62.286502 -384.862168)
			(xy 62.343673 -384.878223) (xy 62.398287 -384.901538) (xy 62.449426 -384.931722) (xy 62.496231 -384.968267)
			(xy 62.537915 -385.01056) (xy 62.573778 -385.057889) (xy 62.603217 -385.109461) (xy 62.625738 -385.164407)
			(xy 62.640962 -385.221804) (xy 62.648633 -385.280689) (xy 62.6491 -385.31038) (xy 62.6491 -385.310888)
			(xy 62.648553 -385.341887) (xy 62.640146 -385.403312) (xy 62.632336 -385.433316) (xy 62.629542 -385.443222)
			(xy 62.632082 -385.463542) (xy 62.673992 -385.536186) (xy 62.679445 -385.544818) (xy 62.695707 -385.557134)
			(xy 62.705488 -385.560062) (xy 62.734604 -385.568038) (xy 62.79057 -385.590676) (xy 62.843075 -385.620475)
			(xy 62.891207 -385.656916) (xy 62.934133 -385.699367) (xy 62.971106 -385.747092) (xy 63.001485 -385.799263)
			(xy 63.024743 -385.854974) (xy 63.040477 -385.913259) (xy 63.048413 -385.973106) (xy 63.048896 -386.003292)
			(xy 63.048771 -386.017427) (xy 63.046989 -386.045641) (xy 63.04534 -386.05968) (xy 63.044545 -386.068288)
			(xy 63.048195 -386.085175) (xy 63.052452 -386.0927) (xy 63.0682 -386.1181) (xy 63.072907 -386.125162)
			(xy 63.086014 -386.13593) (xy 63.093854 -386.139182) (xy 63.117241 -386.148352) (xy 63.161136 -386.172776)
			(xy 63.20083 -386.20356) (xy 63.235409 -386.239996) (xy 63.264078 -386.281244) (xy 63.286175 -386.326355)
			(xy 63.301192 -386.37429) (xy 63.308783 -386.423946) (xy 63.309246 -386.449062) (xy 63.309246 -386.449316)
			(xy 63.308808 -386.473518) (xy 63.30174 -386.521402) (xy 63.287757 -386.567742) (xy 63.26716 -386.611544)
			(xy 63.254128 -386.631942) (xy 63.249397 -386.639852) (xy 63.245358 -386.657821) (xy 63.246254 -386.666994)
			(xy 63.250826 -386.697982) (xy 63.252599 -386.707245) (xy 63.261865 -386.723657) (xy 63.26886 -386.729986)
			(xy 63.290919 -386.74869) (xy 63.330661 -386.790708) (xy 63.364791 -386.837399) (xy 63.392764 -386.888018)
			(xy 63.414136 -386.94176) (xy 63.428564 -386.997766) (xy 63.43582 -387.055144) (xy 63.436246 -387.084062)
			(xy 63.435655 -387.117425) (xy 63.426011 -387.183451) (xy 63.406879 -387.247375) (xy 63.39332 -387.277864)
			(xy 63.389142 -387.288308) (xy 63.389249 -387.310768) (xy 63.39895 -387.331026) (xy 63.40729 -387.33857)
			(xy 63.429518 -387.357265) (xy 63.469583 -387.399317) (xy 63.504005 -387.446099) (xy 63.532233 -387.49686)
			(xy 63.553811 -387.550785) (xy 63.568394 -387.607007) (xy 63.575747 -387.664621) (xy 63.5762 -387.693662)
			(xy 63.575742 -387.722668) (xy 63.56843 -387.780216) (xy 63.553906 -387.83638) (xy 63.532403 -387.890259)
			(xy 63.504266 -387.940989) (xy 63.469944 -387.987758) (xy 63.429989 -388.029816) (xy 63.407798 -388.0485)
			(xy 63.40094 -388.054088) (xy 63.391542 -388.069582) (xy 63.377826 -388.143242) (xy 63.376625 -388.152002)
			(xy 63.379619 -388.169416) (xy 63.383668 -388.177278) (xy 63.383668 -388.177532) (xy 63.396237 -388.200722)
			(xy 63.414115 -388.250341) (xy 63.423218 -388.302292) (xy 63.4238 -388.328662) (xy 63.423732 -388.338021)
			(xy 63.422588 -388.356703) (xy 63.421514 -388.366) (xy 63.420498 -388.374636) (xy 63.424308 -388.391908)
			(xy 63.467996 -388.46125) (xy 63.481966 -388.471918) (xy 63.490348 -388.474712) (xy 63.514378 -388.483175)
			(xy 63.55955 -388.506729) (xy 63.600355 -388.53723) (xy 63.635734 -388.573886) (xy 63.664769 -388.615746)
			(xy 63.686707 -388.661724) (xy 63.69431 -388.68604) (xy 63.695834 -388.691882) (xy 64.016128 -389.245602)
			(xy 64.020192 -389.24992) (xy 64.036382 -389.26764) (xy 64.063809 -389.307027) (xy 64.084954 -389.350114)
			(xy 64.099331 -389.395906) (xy 64.106608 -389.443346) (xy 64.10706 -389.467344) (xy 64.106624 -389.492123)
			(xy 64.098869 -389.541069) (xy 64.083557 -389.588202) (xy 64.061064 -389.63236) (xy 64.031945 -389.67246)
			(xy 63.996914 -389.707513) (xy 63.956833 -389.736659) (xy 63.912689 -389.759179) (xy 63.865566 -389.774522)
			(xy 63.816624 -389.782308) (xy 63.791846 -389.782812) (xy 63.791338 -389.782812) (xy 63.765945 -389.782278)
			(xy 63.715813 -389.774153) (xy 63.667628 -389.758107) (xy 63.622634 -389.734554) (xy 63.58199 -389.704101)
			(xy 63.546747 -389.667534) (xy 63.517812 -389.625797) (xy 63.495933 -389.579965) (xy 63.488316 -389.555736)
			(xy 63.486792 -389.549894) (xy 63.166498 -388.996174) (xy 63.162434 -388.991856) (xy 63.146271 -388.974125)
			(xy 63.118904 -388.934722) (xy 63.097815 -388.891631) (xy 63.083488 -388.845846) (xy 63.076254 -388.79842)
			(xy 63.07582 -388.774432) (xy 63.075901 -388.762384) (xy 63.077683 -388.738355) (xy 63.079376 -388.726426)
			(xy 63.08034 -388.717667) (xy 63.076975 -388.700387) (xy 63.072772 -388.692644) (xy 63.040006 -388.637272)
			(xy 63.035299 -388.629998) (xy 63.022065 -388.618831) (xy 63.014098 -388.615428) (xy 63.01359 -388.615428)
			(xy 62.991878 -388.60698) (xy 62.951072 -388.584506) (xy 62.914152 -388.556096) (xy 62.881974 -388.522409)
			(xy 62.855286 -388.484226) (xy 62.834706 -388.442433) (xy 62.820712 -388.397999) (xy 62.813627 -388.351955)
			(xy 62.813184 -388.328662) (xy 62.813752 -388.302289) (xy 62.822834 -388.250331) (xy 62.840722 -388.20071)
			(xy 62.853316 -388.177532) (xy 62.853316 -388.177278) (xy 62.857328 -388.169403) (xy 62.860326 -388.152001)
			(xy 62.859158 -388.143242) (xy 62.845442 -388.069582) (xy 62.836044 -388.054088) (xy 62.829186 -388.0485)
			(xy 62.807012 -388.029797) (xy 62.767066 -387.987735) (xy 62.732749 -387.940966) (xy 62.704611 -387.89024)
			(xy 62.683102 -387.836367) (xy 62.668565 -387.780209) (xy 62.661235 -387.722666) (xy 62.660784 -387.693662)
			(xy 62.660784 -387.693408) (xy 62.661361 -387.660086) (xy 62.671028 -387.594147) (xy 62.69016 -387.530308)
			(xy 62.70371 -387.49986) (xy 62.707951 -387.489438) (xy 62.707816 -387.466962) (xy 62.698091 -387.446698)
			(xy 62.68974 -387.439154) (xy 62.667481 -387.420493) (xy 62.627417 -387.378437) (xy 62.592997 -387.331648)
			(xy 62.564773 -387.280881) (xy 62.543199 -387.226951) (xy 62.528623 -387.170724) (xy 62.521278 -387.113105)
			(xy 62.52083 -387.084062) (xy 62.52083 -387.083808) (xy 62.52125 -387.054908) (xy 62.528537 -386.997569)
			(xy 62.542984 -386.941603) (xy 62.564361 -386.8879) (xy 62.592328 -386.837316) (xy 62.626439 -386.790655)
			(xy 62.666153 -386.748658) (xy 62.688216 -386.729986) (xy 62.695295 -386.723729) (xy 62.704561 -386.707278)
			(xy 62.70625 -386.697982) (xy 62.710822 -386.666994) (xy 62.711726 -386.657821) (xy 62.707685 -386.63985)
			(xy 62.702948 -386.631942) (xy 62.686638 -386.606121) (xy 62.662862 -386.549872) (xy 62.655704 -386.520182)
			(xy 62.653575 -386.511951) (xy 62.644741 -386.497435) (xy 62.638432 -386.491734) (xy 62.601094 -386.461)
			(xy 62.591188 -386.461) (xy 62.56122 -386.460529) (xy 62.501796 -386.452704) (xy 62.443902 -386.43719)
			(xy 62.388529 -386.414252) (xy 62.336623 -386.384283) (xy 62.289073 -386.347795) (xy 62.246692 -386.305412)
			(xy 62.210206 -386.25786) (xy 62.180239 -386.205953) (xy 62.157303 -386.150579) (xy 62.141792 -386.092684)
			(xy 62.13397 -386.03326) (xy 62.13348 -386.003292) (xy 62.134 -385.972229) (xy 62.142417 -385.910675)
			(xy 62.150244 -385.88061) (xy 62.153038 -385.870704) (xy 62.150498 -385.850384) (xy 62.10808 -385.777232)
			(xy 62.102607 -385.768736) (xy 62.086505 -385.756554) (xy 62.076838 -385.75361) (xy 62.047751 -385.745575)
			(xy 61.991824 -385.722909) (xy 61.939358 -385.693093) (xy 61.891264 -385.656645) (xy 61.848373 -385.614195)
			(xy 61.81143 -385.566479) (xy 61.781075 -385.514325) (xy 61.757833 -385.458634) (xy 61.742108 -385.400374)
			(xy 61.734171 -385.340553) (xy 61.733684 -385.31038) (xy 61.734212 -385.279492) (xy 61.742517 -385.218277)
			(xy 61.758973 -385.158733) (xy 61.783282 -385.101941) (xy 61.798708 -385.075176) (xy 61.804091 -385.065256)
			(xy 61.806444 -385.042832) (xy 61.80328 -385.031996) (xy 61.777372 -384.958336) (xy 61.773112 -384.947981)
			(xy 61.757427 -384.932038) (xy 61.747146 -384.927602) (xy 61.723754 -384.918445) (xy 61.679858 -384.89402)
			(xy 61.640164 -384.863234) (xy 61.605584 -384.826797) (xy 61.576917 -384.785546) (xy 61.554821 -384.740433)
			(xy 61.539805 -384.692496) (xy 61.532216 -384.642839) (xy 61.531754 -384.617722) (xy 60.99302 -384.617722)
			(xy 60.99302 -384.61823) (xy 60.992455 -384.645204) (xy 60.983648 -384.69843) (xy 60.975494 -384.724148)
			(xy 60.971684 -384.73507) (xy 60.974224 -384.757422) (xy 61.02096 -384.833876) (xy 61.027261 -384.84307)
			(xy 61.045842 -384.85533) (xy 61.056774 -384.857498) (xy 61.057028 -384.857498) (xy 61.086346 -384.862208)
			(xy 61.143516 -384.878256) (xy 61.19813 -384.901565) (xy 61.24927 -384.931744) (xy 61.296076 -384.968285)
			(xy 61.337761 -385.010574) (xy 61.373625 -385.0579) (xy 61.403065 -385.109468) (xy 61.425587 -385.164412)
			(xy 61.440811 -385.221807) (xy 61.448483 -385.28069) (xy 61.44895 -385.31038) (xy 61.448423 -385.341443)
			(xy 61.440011 -385.402996) (xy 61.432186 -385.433062) (xy 61.429392 -385.442968) (xy 61.431932 -385.463288)
			(xy 61.474096 -385.536186) (xy 61.479497 -385.544787) (xy 61.495621 -385.557107) (xy 61.505338 -385.560062)
			(xy 61.505592 -385.560062) (xy 61.534709 -385.568035) (xy 61.590675 -385.590674) (xy 61.64318 -385.620473)
			(xy 61.691312 -385.656914) (xy 61.734237 -385.699366) (xy 61.77121 -385.747091) (xy 61.801589 -385.799262)
			(xy 61.824847 -385.854974) (xy 61.840581 -385.913259) (xy 61.848517 -385.973106) (xy 61.849 -386.003292)
			(xy 61.848875 -386.017427) (xy 61.847093 -386.045641) (xy 61.845444 -386.05968) (xy 61.844648 -386.068288)
			(xy 61.848298 -386.085175) (xy 61.852556 -386.0927) (xy 61.868304 -386.1181) (xy 61.873009 -386.125163)
			(xy 61.886118 -386.13593) (xy 61.893958 -386.139182) (xy 61.917345 -386.14835) (xy 61.96124 -386.172774)
			(xy 62.000935 -386.203559) (xy 62.035514 -386.239995) (xy 62.064182 -386.281243) (xy 62.086279 -386.326355)
			(xy 62.101296 -386.37429) (xy 62.108887 -386.423946) (xy 62.10935 -386.449062) (xy 62.10935 -386.449316)
			(xy 62.108911 -386.473518) (xy 62.101843 -386.521402) (xy 62.087861 -386.567742) (xy 62.067264 -386.611544)
			(xy 62.054232 -386.631942) (xy 62.049501 -386.639852) (xy 62.045462 -386.657821) (xy 62.046358 -386.666994)
			(xy 62.05093 -386.697982) (xy 62.052731 -386.707238) (xy 62.06198 -386.723651) (xy 62.068964 -386.729986)
			(xy 62.091024 -386.748689) (xy 62.130766 -386.790707) (xy 62.164895 -386.837398) (xy 62.192869 -386.888018)
			(xy 62.21424 -386.94176) (xy 62.228668 -386.997766) (xy 62.235924 -387.055144) (xy 62.23635 -387.084062)
			(xy 62.235759 -387.117425) (xy 62.226115 -387.183451) (xy 62.206983 -387.247375) (xy 62.193424 -387.277864)
			(xy 62.189245 -387.288307) (xy 62.189351 -387.310768) (xy 62.199053 -387.331026) (xy 62.207394 -387.33857)
			(xy 62.229623 -387.357264) (xy 62.269687 -387.399316) (xy 62.30411 -387.446099) (xy 62.332337 -387.49686)
			(xy 62.353916 -387.550785) (xy 62.368498 -387.607006) (xy 62.375851 -387.664621) (xy 62.376304 -387.693662)
			(xy 62.375845 -387.722668) (xy 62.368533 -387.780216) (xy 62.354009 -387.83638) (xy 62.332507 -387.890259)
			(xy 62.304369 -387.940989) (xy 62.270048 -387.987758) (xy 62.230093 -388.029817) (xy 62.207902 -388.0485)
			(xy 62.201044 -388.054088) (xy 62.191646 -388.069582) (xy 62.17793 -388.143242) (xy 62.176728 -388.152002)
			(xy 62.179723 -388.169416) (xy 62.183772 -388.177278) (xy 62.183772 -388.177532) (xy 62.196342 -388.200722)
			(xy 62.214219 -388.250341) (xy 62.223322 -388.302292) (xy 62.223904 -388.328662) (xy 62.223835 -388.338021)
			(xy 62.222692 -388.356703) (xy 62.221618 -388.366) (xy 62.220602 -388.374636) (xy 62.224412 -388.391908)
			(xy 62.2681 -388.46125) (xy 62.28207 -388.471918) (xy 62.290452 -388.474712) (xy 62.31454 -388.483218)
			(xy 62.359832 -388.506836) (xy 62.400729 -388.537442) (xy 62.436162 -388.574234) (xy 62.465207 -388.616253)
			(xy 62.487105 -388.662402) (xy 62.494668 -388.686802) (xy 62.496192 -388.692644) (xy 62.815978 -389.245602)
			(xy 62.820042 -389.24992) (xy 62.836205 -389.267583) (xy 62.863523 -389.306902) (xy 62.88459 -389.349895)
			(xy 62.898923 -389.395576) (xy 62.906193 -389.442898) (xy 62.906656 -389.466836) (xy 62.906656 -389.467344)
			(xy 62.906223 -389.492135) (xy 62.89846 -389.541107) (xy 62.883132 -389.588261) (xy 62.860617 -389.632438)
			(xy 62.831469 -389.672548) (xy 62.796405 -389.707605) (xy 62.75629 -389.736746) (xy 62.712109 -389.759254)
			(xy 62.664952 -389.774573) (xy 62.615979 -389.782327) (xy 62.591188 -389.782812) (xy 62.565793 -389.782322)
			(xy 62.515659 -389.77419) (xy 62.467473 -389.758136) (xy 62.422479 -389.734576) (xy 62.381836 -389.704118)
			(xy 62.346594 -389.667545) (xy 62.31766 -389.625803) (xy 62.295782 -389.579967) (xy 62.288166 -389.555736)
			(xy 62.286642 -389.549894) (xy 61.966094 -388.995412) (xy 61.96203 -388.991094) (xy 61.945927 -388.973437)
			(xy 61.91874 -388.934136) (xy 61.897789 -388.891186) (xy 61.883554 -388.845569) (xy 61.876359 -388.798326)
			(xy 61.875924 -388.774432) (xy 61.876005 -388.762384) (xy 61.877787 -388.738355) (xy 61.87948 -388.726426)
			(xy 61.880444 -388.717667) (xy 61.877079 -388.700387) (xy 61.872876 -388.692644) (xy 61.84011 -388.637272)
			(xy 61.835401 -388.629999) (xy 61.822169 -388.618832) (xy 61.814202 -388.615428) (xy 61.813694 -388.615428)
			(xy 61.791983 -388.606978) (xy 61.751177 -388.584505) (xy 61.714256 -388.556095) (xy 61.682079 -388.522408)
			(xy 61.65539 -388.484225) (xy 61.63481 -388.442432) (xy 61.620816 -388.397998) (xy 61.613731 -388.351955)
			(xy 61.613288 -388.328662) (xy 61.613855 -388.302289) (xy 61.622938 -388.250331) (xy 61.640826 -388.20071)
			(xy 61.65342 -388.177532) (xy 61.65342 -388.177278) (xy 61.657432 -388.169403) (xy 61.66043 -388.152001)
			(xy 61.659262 -388.143242) (xy 61.645546 -388.069582) (xy 61.636148 -388.054088) (xy 61.62929 -388.0485)
			(xy 61.607117 -388.029796) (xy 61.567171 -387.987734) (xy 61.532854 -387.940966) (xy 61.504715 -387.890239)
			(xy 61.483206 -387.836366) (xy 61.468669 -387.780209) (xy 61.461339 -387.722666) (xy 61.460888 -387.693662)
			(xy 61.460888 -387.693408) (xy 61.461465 -387.660086) (xy 61.471132 -387.594147) (xy 61.490264 -387.530308)
			(xy 61.503814 -387.49986) (xy 61.508087 -387.489446) (xy 61.507953 -387.466959) (xy 61.498208 -387.446692)
			(xy 61.489844 -387.439154) (xy 61.467586 -387.420492) (xy 61.427522 -387.378436) (xy 61.393101 -387.331648)
			(xy 61.364877 -387.280881) (xy 61.343303 -387.22695) (xy 61.328727 -387.170724) (xy 61.321382 -387.113105)
			(xy 61.320934 -387.084062) (xy 61.320934 -387.083808) (xy 61.321352 -387.054908) (xy 61.32864 -386.997568)
			(xy 61.343087 -386.941602) (xy 61.364464 -386.8879) (xy 61.392431 -386.837316) (xy 61.426543 -386.790655)
			(xy 61.466257 -386.748658) (xy 61.48832 -386.729986) (xy 61.4954 -386.723729) (xy 61.504665 -386.707278)
			(xy 61.506354 -386.697982) (xy 61.510926 -386.666994) (xy 61.511829 -386.657821) (xy 61.507788 -386.63985)
			(xy 61.503052 -386.631942) (xy 61.486742 -386.606121) (xy 61.462966 -386.549872) (xy 61.455808 -386.520182)
			(xy 61.453677 -386.511951) (xy 61.444845 -386.497435) (xy 61.438536 -386.491734) (xy 61.401198 -386.461)
			(xy 61.391292 -386.461) (xy 61.361324 -386.460525) (xy 61.3019 -386.452701) (xy 61.244007 -386.437187)
			(xy 61.188633 -386.41425) (xy 61.136727 -386.384281) (xy 61.089177 -386.347793) (xy 61.046796 -386.305411)
			(xy 61.01031 -386.25786) (xy 60.980343 -386.205953) (xy 60.957407 -386.150578) (xy 60.941896 -386.092684)
			(xy 60.934074 -386.03326) (xy 60.933584 -386.003292) (xy 60.934104 -385.972229) (xy 60.942521 -385.910675)
			(xy 60.950348 -385.88061) (xy 60.953142 -385.870704) (xy 60.950602 -385.850384) (xy 60.908438 -385.777486)
			(xy 60.903045 -385.768878) (xy 60.886917 -385.756559) (xy 60.877196 -385.75361) (xy 60.876942 -385.75361)
			(xy 60.847824 -385.74564) (xy 60.791856 -385.723003) (xy 60.73935 -385.693206) (xy 60.691216 -385.656765)
			(xy 60.64829 -385.614313) (xy 60.611316 -385.566587) (xy 60.580938 -385.514414) (xy 60.557681 -385.458701)
			(xy 60.541949 -385.400415) (xy 60.534015 -385.340566) (xy 60.533534 -385.31038) (xy 60.534055 -385.279492)
			(xy 60.542361 -385.218276) (xy 60.558819 -385.158732) (xy 60.58313 -385.10194) (xy 60.598558 -385.075176)
			(xy 60.603941 -385.065255) (xy 60.606296 -385.042832) (xy 60.60313 -385.031996) (xy 60.577222 -384.958336)
			(xy 60.572984 -384.94797) (xy 60.557284 -384.932032) (xy 60.546996 -384.927602) (xy 60.523615 -384.918418)
			(xy 60.479717 -384.893999) (xy 60.440021 -384.863219) (xy 60.40544 -384.826785) (xy 60.37677 -384.785539)
			(xy 60.354672 -384.740428) (xy 60.339656 -384.692493) (xy 60.332066 -384.642838) (xy 60.331604 -384.617722)
			(xy 59.793124 -384.617722) (xy 59.793124 -384.61823) (xy 59.792559 -384.645204) (xy 59.783752 -384.69843)
			(xy 59.775598 -384.724148) (xy 59.771788 -384.73507) (xy 59.774328 -384.757422) (xy 59.821064 -384.833876)
			(xy 59.827363 -384.843071) (xy 59.845945 -384.85533) (xy 59.856878 -384.857498) (xy 59.857132 -384.857498)
			(xy 59.88645 -384.862204) (xy 59.943621 -384.878253) (xy 59.998235 -384.901563) (xy 60.049374 -384.931742)
			(xy 60.09618 -384.968283) (xy 60.137865 -385.010573) (xy 60.173729 -385.057899) (xy 60.203169 -385.109468)
			(xy 60.225691 -385.164411) (xy 60.240915 -385.221807) (xy 60.248587 -385.28069) (xy 60.249054 -385.31038)
			(xy 60.248527 -385.341443) (xy 60.240115 -385.402996) (xy 60.23229 -385.433062) (xy 60.229496 -385.442968)
			(xy 60.232036 -385.463288) (xy 60.2742 -385.536186) (xy 60.2796 -385.544788) (xy 60.295724 -385.557107)
			(xy 60.305442 -385.560062) (xy 60.305696 -385.560062) (xy 60.334814 -385.568032) (xy 60.39078 -385.590672)
			(xy 60.443284 -385.620471) (xy 60.491417 -385.656913) (xy 60.534341 -385.699365) (xy 60.571314 -385.747091)
			(xy 60.601693 -385.799262) (xy 60.624951 -385.854973) (xy 60.640685 -385.913259) (xy 60.648621 -385.973106)
			(xy 60.649104 -386.003292) (xy 60.648979 -386.017427) (xy 60.647197 -386.045641) (xy 60.645548 -386.05968)
			(xy 60.644752 -386.068288) (xy 60.648403 -386.085175) (xy 60.65266 -386.0927) (xy 60.668662 -386.1181)
			(xy 60.673327 -386.125123) (xy 60.686305 -386.135873) (xy 60.694062 -386.139182) (xy 60.717417 -386.148393)
			(xy 60.76126 -386.172852) (xy 60.800902 -386.203655) (xy 60.835436 -386.240094) (xy 60.864066 -386.281333)
			(xy 60.886136 -386.326425) (xy 60.90114 -386.374334) (xy 60.908731 -386.42396) (xy 60.9092 -386.449062)
			(xy 60.9092 -386.449316) (xy 60.908753 -386.473517) (xy 60.901686 -386.521401) (xy 60.887706 -386.567741)
			(xy 60.867112 -386.611544) (xy 60.854082 -386.631942) (xy 60.849355 -386.639854) (xy 60.845312 -386.657821)
			(xy 60.846208 -386.666994) (xy 60.85078 -386.697982) (xy 60.852567 -386.707242) (xy 60.861825 -386.723654)
			(xy 60.868814 -386.729986) (xy 60.890884 -386.748677) (xy 60.930623 -386.790698) (xy 60.964751 -386.837392)
			(xy 60.992722 -386.888014) (xy 61.014092 -386.941757) (xy 61.028519 -386.997765) (xy 61.035774 -387.055144)
			(xy 61.0362 -387.084062) (xy 61.035613 -387.117426) (xy 61.025969 -387.183451) (xy 61.006835 -387.247375)
			(xy 60.993274 -387.277864) (xy 60.989078 -387.288303) (xy 60.989185 -387.31077) (xy 60.998896 -387.331029)
			(xy 61.007244 -387.33857) (xy 61.029463 -387.357277) (xy 61.06953 -387.399325) (xy 61.103954 -387.446105)
			(xy 61.132184 -387.496864) (xy 61.153764 -387.550787) (xy 61.168348 -387.607008) (xy 61.175701 -387.664621)
			(xy 61.176154 -387.693662) (xy 61.175676 -387.722667) (xy 61.168366 -387.780214) (xy 61.153844 -387.836377)
			(xy 61.132344 -387.890255) (xy 61.104209 -387.940985) (xy 61.069892 -387.987755) (xy 61.029941 -388.029815)
			(xy 61.007752 -388.0485) (xy 61.000894 -388.054088) (xy 60.991496 -388.069582) (xy 60.97778 -388.143242)
			(xy 60.976584 -388.152003) (xy 60.979576 -388.169416) (xy 60.983622 -388.177278) (xy 60.983622 -388.177532)
			(xy 60.996196 -388.200719) (xy 61.014071 -388.25034) (xy 61.023172 -388.302291) (xy 61.023754 -388.328662)
			(xy 61.023685 -388.338021) (xy 61.022542 -388.356703) (xy 61.021468 -388.366) (xy 61.020452 -388.374636)
			(xy 61.024262 -388.391908) (xy 61.06795 -388.46125) (xy 61.08192 -388.471918) (xy 61.090302 -388.474712)
			(xy 61.114323 -388.4832) (xy 61.159496 -388.506748) (xy 61.200302 -388.537243) (xy 61.235683 -388.573894)
			(xy 61.26472 -388.61575) (xy 61.28666 -388.661725) (xy 61.294264 -388.68604) (xy 61.295788 -388.691882)
			(xy 61.616082 -389.245602) (xy 61.620146 -389.24992) (xy 61.636309 -389.267583) (xy 61.663627 -389.306901)
			(xy 61.684694 -389.349894) (xy 61.699027 -389.395576) (xy 61.706297 -389.442898) (xy 61.70676 -389.466836)
			(xy 61.70676 -389.467344) (xy 61.706323 -389.492135) (xy 61.69856 -389.541106) (xy 61.683233 -389.58826)
			(xy 61.660718 -389.632436) (xy 61.63157 -389.672547) (xy 61.596507 -389.707604) (xy 61.556392 -389.736745)
			(xy 61.512212 -389.759252) (xy 61.465056 -389.774572) (xy 61.416083 -389.782327) (xy 61.391292 -389.782812)
			(xy 61.365897 -389.782319) (xy 61.315763 -389.774187) (xy 61.267578 -389.758134) (xy 61.222583 -389.734575)
			(xy 61.181941 -389.704116) (xy 61.146698 -389.667544) (xy 61.117765 -389.625802) (xy 61.095887 -389.579967)
			(xy 61.08827 -389.555736) (xy 61.086746 -389.549894) (xy 60.766452 -388.996174) (xy 60.762388 -388.991856)
			(xy 60.746183 -388.974149) (xy 60.718759 -388.934758) (xy 60.697617 -388.891668) (xy 60.683243 -388.845874)
			(xy 60.67597 -388.798431) (xy 60.67552 -388.774432) (xy 60.675662 -388.76238) (xy 60.677568 -388.73835)
			(xy 60.67933 -388.726426) (xy 60.680301 -388.717667) (xy 60.676933 -388.700386) (xy 60.672726 -388.692644)
			(xy 60.63996 -388.637272) (xy 60.635268 -388.629987) (xy 60.622024 -388.618826) (xy 60.614052 -388.615428)
			(xy 60.613544 -388.615428) (xy 60.591822 -388.607005) (xy 60.551017 -388.584525) (xy 60.514099 -388.556111)
			(xy 60.481923 -388.522419) (xy 60.455237 -388.484233) (xy 60.434658 -388.442437) (xy 60.420665 -388.398001)
			(xy 60.413581 -388.351956) (xy 60.413138 -388.328662) (xy 60.413699 -388.302289) (xy 60.422783 -388.25033)
			(xy 60.440674 -388.20071) (xy 60.45327 -388.177532) (xy 60.45327 -388.177278) (xy 60.457284 -388.169404)
			(xy 60.46028 -388.152002) (xy 60.459112 -388.143242) (xy 60.445396 -388.069582) (xy 60.435998 -388.054088)
			(xy 60.42914 -388.0485) (xy 60.406978 -388.029784) (xy 60.367029 -387.987726) (xy 60.332709 -387.94096)
			(xy 60.304569 -387.890235) (xy 60.283058 -387.836364) (xy 60.26852 -387.780208) (xy 60.261189 -387.722666)
			(xy 60.260738 -387.693662) (xy 60.260738 -387.693408) (xy 60.261319 -387.660086) (xy 60.270986 -387.594148)
			(xy 60.290115 -387.530309) (xy 60.303664 -387.49986) (xy 60.30792 -387.489442) (xy 60.307786 -387.46696)
			(xy 60.298052 -387.446695) (xy 60.289694 -387.439154) (xy 60.267426 -387.420505) (xy 60.227364 -387.378445)
			(xy 60.192945 -387.331654) (xy 60.164723 -387.280885) (xy 60.143151 -387.226953) (xy 60.128576 -387.170725)
			(xy 60.121232 -387.113105) (xy 60.120784 -387.084062) (xy 60.120784 -387.083808) (xy 60.12122 -387.054909)
			(xy 60.128507 -386.997571) (xy 60.142952 -386.941606) (xy 60.164327 -386.887904) (xy 60.192291 -386.83732)
			(xy 60.226399 -386.790658) (xy 60.266109 -386.74866) (xy 60.28817 -386.729986) (xy 60.295241 -386.723721)
			(xy 60.304512 -386.707277) (xy 60.306204 -386.697982) (xy 60.310776 -386.666994) (xy 60.311687 -386.657821)
			(xy 60.307643 -386.639849) (xy 60.302902 -386.631942) (xy 60.286588 -386.606123) (xy 60.262815 -386.549873)
			(xy 60.255658 -386.520182) (xy 60.253514 -386.511956) (xy 60.24469 -386.497439) (xy 60.238386 -386.491734)
			(xy 60.201048 -386.461) (xy 60.191396 -386.461) (xy 60.161427 -386.460543) (xy 60.102001 -386.452718)
			(xy 60.044104 -386.437205) (xy 59.988728 -386.414266) (xy 59.93682 -386.384296) (xy 59.889268 -386.347807)
			(xy 59.846885 -386.305423) (xy 59.810397 -386.25787) (xy 59.780428 -386.205961) (xy 59.757492 -386.150584)
			(xy 59.741979 -386.092688) (xy 59.734157 -386.033261) (xy 59.733688 -386.003292) (xy 59.734208 -385.972229)
			(xy 59.742624 -385.910675) (xy 59.750452 -385.88061) (xy 59.753246 -385.870704) (xy 59.750706 -385.850384)
			(xy 59.708542 -385.777486) (xy 59.703147 -385.768879) (xy 59.68702 -385.75656) (xy 59.6773 -385.75361)
			(xy 59.677046 -385.75361) (xy 59.647928 -385.745637) (xy 59.591961 -385.723001) (xy 59.539454 -385.693204)
			(xy 59.49132 -385.656763) (xy 59.448394 -385.614312) (xy 59.411421 -385.566586) (xy 59.381042 -385.514414)
			(xy 59.357785 -385.458701) (xy 59.342053 -385.400415) (xy 59.334119 -385.340566) (xy 59.333638 -385.31038)
			(xy 59.334158 -385.279492) (xy 59.342464 -385.218276) (xy 59.358922 -385.158732) (xy 59.383234 -385.10194)
			(xy 59.398662 -385.075176) (xy 59.404045 -385.065255) (xy 59.4064 -385.042832) (xy 59.403234 -385.031996)
			(xy 59.377326 -384.958336) (xy 59.373086 -384.947971) (xy 59.357387 -384.932032) (xy 59.3471 -384.927602)
			(xy 59.32372 -384.918416) (xy 59.279822 -384.893998) (xy 59.240126 -384.863217) (xy 59.205544 -384.826785)
			(xy 59.176874 -384.785538) (xy 59.154777 -384.740428) (xy 59.13976 -384.692493) (xy 59.13217 -384.642838)
			(xy 59.131708 -384.617722) (xy 58.593228 -384.617722) (xy 58.593228 -384.61823) (xy 58.592663 -384.645204)
			(xy 58.583856 -384.69843) (xy 58.575702 -384.724148) (xy 58.571892 -384.73507) (xy 58.574432 -384.757422)
			(xy 58.621168 -384.833876) (xy 58.627466 -384.843073) (xy 58.646049 -384.855331) (xy 58.656982 -384.857498)
			(xy 58.657236 -384.857498) (xy 58.686524 -384.862311) (xy 58.743658 -384.878384) (xy 58.798235 -384.901708)
			(xy 58.849338 -384.931893) (xy 58.896109 -384.968432) (xy 58.937764 -385.010711) (xy 58.973603 -385.05802)
			(xy 59.003024 -385.109566) (xy 59.025534 -385.164484) (xy 59.040755 -385.221851) (xy 59.048431 -385.280704)
			(xy 59.048904 -385.31038) (xy 59.048379 -385.341443) (xy 59.039966 -385.402997) (xy 59.03214 -385.433062)
			(xy 59.029346 -385.442968) (xy 59.031886 -385.463288) (xy 59.07405 -385.536186) (xy 59.079429 -385.544803)
			(xy 59.095568 -385.557115) (xy 59.105292 -385.560062) (xy 59.105546 -385.560062) (xy 59.134654 -385.568066)
			(xy 59.190621 -385.590699) (xy 59.243126 -385.620493) (xy 59.29126 -385.65693) (xy 59.334186 -385.699378)
			(xy 59.37116 -385.7471) (xy 59.401541 -385.799269) (xy 59.4248 -385.854978) (xy 59.440534 -385.913261)
			(xy 59.448471 -385.973107) (xy 59.448954 -386.003292) (xy 59.448829 -386.017427) (xy 59.447047 -386.045641)
			(xy 59.445398 -386.05968) (xy 59.444609 -386.068288) (xy 59.448256 -386.085174) (xy 59.45251 -386.0927)
			(xy 59.468258 -386.1181) (xy 59.472978 -386.125152) (xy 59.486076 -386.135926) (xy 59.493912 -386.139182)
			(xy 59.517289 -386.148375) (xy 59.561186 -386.172793) (xy 59.600882 -386.203573) (xy 59.635463 -386.240005)
			(xy 59.664133 -386.28125) (xy 59.686231 -386.326359) (xy 59.701249 -386.374293) (xy 59.708841 -386.423946)
			(xy 59.709304 -386.449062) (xy 59.709304 -386.449316) (xy 59.708856 -386.473517) (xy 59.701789 -386.521401)
			(xy 59.68781 -386.567741) (xy 59.667216 -386.611544) (xy 59.654186 -386.631942) (xy 59.649459 -386.639855)
			(xy 59.645416 -386.657821) (xy 59.646312 -386.666994) (xy 59.650884 -386.697982) (xy 59.652669 -386.707242)
			(xy 59.661928 -386.723654) (xy 59.668918 -386.729986) (xy 59.690989 -386.748676) (xy 59.730728 -386.790698)
			(xy 59.764855 -386.837392) (xy 59.792826 -386.888014) (xy 59.814196 -386.941757) (xy 59.828623 -386.997765)
			(xy 59.835878 -387.055144) (xy 59.836304 -387.084062) (xy 59.835717 -387.117426) (xy 59.826072 -387.183451)
			(xy 59.806939 -387.247375) (xy 59.793378 -387.277864) (xy 59.789181 -387.288303) (xy 59.789287 -387.31077)
			(xy 59.799 -387.33103) (xy 59.807348 -387.33857) (xy 59.829567 -387.357276) (xy 59.869634 -387.399324)
			(xy 59.904059 -387.446104) (xy 59.932288 -387.496864) (xy 59.953868 -387.550787) (xy 59.968452 -387.607008)
			(xy 59.975805 -387.664621) (xy 59.976258 -387.693662) (xy 59.975779 -387.722667) (xy 59.968468 -387.780214)
			(xy 59.953947 -387.836376) (xy 59.932446 -387.890254) (xy 59.904313 -387.940985) (xy 59.869995 -387.987755)
			(xy 59.830045 -388.029815) (xy 59.807856 -388.0485) (xy 59.800998 -388.054088) (xy 59.7916 -388.069582)
			(xy 59.777884 -388.143242) (xy 59.776688 -388.152003) (xy 59.77968 -388.169416) (xy 59.783726 -388.177278)
			(xy 59.783726 -388.177532) (xy 59.7963 -388.200719) (xy 59.814175 -388.25034) (xy 59.823276 -388.302291)
			(xy 59.823858 -388.328662) (xy 59.823789 -388.338021) (xy 59.822646 -388.356703) (xy 59.821572 -388.366)
			(xy 59.820556 -388.374636) (xy 59.824366 -388.391908) (xy 59.868054 -388.46125) (xy 59.882024 -388.471918)
			(xy 59.890406 -388.474712) (xy 59.914428 -388.483198) (xy 59.959601 -388.506746) (xy 60.000407 -388.537242)
			(xy 60.035787 -388.573893) (xy 60.064824 -388.61575) (xy 60.086764 -388.661725) (xy 60.094368 -388.68604)
			(xy 60.095892 -388.691882) (xy 60.416186 -389.245602) (xy 60.42025 -389.24992) (xy 60.436414 -389.267582)
			(xy 60.463732 -389.306901) (xy 60.484799 -389.349894) (xy 60.499131 -389.395576) (xy 60.506401 -389.442898)
			(xy 60.506864 -389.466836) (xy 60.506864 -389.467344) (xy 60.506423 -389.492135) (xy 60.49866 -389.541106)
			(xy 60.483333 -389.588259) (xy 60.460819 -389.632435) (xy 60.431671 -389.672545) (xy 60.396609 -389.707603)
			(xy 60.356494 -389.736744) (xy 60.312315 -389.759251) (xy 60.265159 -389.774571) (xy 60.216187 -389.782326)
			(xy 60.191396 -389.782812) (xy 60.166002 -389.782315) (xy 60.115868 -389.774184) (xy 60.067682 -389.758132)
			(xy 60.022688 -389.734573) (xy 59.982045 -389.704115) (xy 59.946802 -389.667543) (xy 59.917869 -389.625802)
			(xy 59.895991 -389.579967) (xy 59.888374 -389.555736) (xy 59.88685 -389.549894) (xy 59.566556 -388.996174)
			(xy 59.562492 -388.991856) (xy 59.546288 -388.974149) (xy 59.518864 -388.934757) (xy 59.497721 -388.891668)
			(xy 59.483348 -388.845873) (xy 59.476074 -388.798431) (xy 59.475624 -388.774432) (xy 59.475766 -388.76238)
			(xy 59.477672 -388.73835) (xy 59.479434 -388.726426) (xy 59.480404 -388.717667) (xy 59.477036 -388.700386)
			(xy 59.47283 -388.692644) (xy 59.440064 -388.637272) (xy 59.43537 -388.629988) (xy 59.422128 -388.618826)
			(xy 59.414156 -388.615428) (xy 59.413648 -388.615428) (xy 59.391927 -388.607003) (xy 59.351122 -388.584524)
			(xy 59.314203 -388.556109) (xy 59.282028 -388.522418) (xy 59.255341 -388.484232) (xy 59.234762 -388.442437)
			(xy 59.220769 -388.398001) (xy 59.213685 -388.351955) (xy 59.213242 -388.328662) (xy 59.213802 -388.302289)
			(xy 59.222887 -388.25033) (xy 59.240778 -388.20071) (xy 59.253374 -388.177532) (xy 59.253374 -388.177278)
			(xy 59.257384 -388.169402) (xy 59.260385 -388.152001) (xy 59.259216 -388.143242) (xy 59.2455 -388.069582)
			(xy 59.236102 -388.054088) (xy 59.229244 -388.0485) (xy 59.207083 -388.029783) (xy 59.167133 -387.987725)
			(xy 59.132814 -387.940959) (xy 59.104673 -387.890235) (xy 59.083162 -387.836364) (xy 59.068624 -387.780208)
			(xy 59.061293 -387.722666) (xy 59.060842 -387.693662) (xy 59.060842 -387.693408) (xy 59.061423 -387.660086)
			(xy 59.071089 -387.594148) (xy 59.090219 -387.530309) (xy 59.103768 -387.49986) (xy 59.108023 -387.489442)
			(xy 59.107889 -387.46696) (xy 59.098155 -387.446695) (xy 59.089798 -387.439154) (xy 59.067531 -387.420504)
			(xy 59.027469 -387.378444) (xy 58.99305 -387.331654) (xy 58.964828 -387.280884) (xy 58.943256 -387.226953)
			(xy 58.92868 -387.170725) (xy 58.921336 -387.113105) (xy 58.920888 -387.084062) (xy 58.920888 -387.083808)
			(xy 58.921323 -387.054908) (xy 58.928609 -386.99757) (xy 58.943055 -386.941605) (xy 58.96443 -386.887904)
			(xy 58.992394 -386.83732) (xy 59.026503 -386.790657) (xy 59.066213 -386.748659) (xy 59.088274 -386.729986)
			(xy 59.095346 -386.723722) (xy 59.104617 -386.707277) (xy 59.106308 -386.697982) (xy 59.11088 -386.666994)
			(xy 59.111791 -386.657821) (xy 59.107746 -386.639849) (xy 59.103006 -386.631942) (xy 59.086692 -386.606123)
			(xy 59.062919 -386.549873) (xy 59.055762 -386.520182) (xy 59.053617 -386.511956) (xy 59.044793 -386.497439)
			(xy 59.03849 -386.491734) (xy 59.001152 -386.461) (xy 58.991246 -386.461) (xy 58.961278 -386.460496)
			(xy 58.901853 -386.452678) (xy 58.843958 -386.43717) (xy 58.788582 -386.414237) (xy 58.736674 -386.384272)
			(xy 58.689121 -386.347787) (xy 58.646738 -386.305408) (xy 58.610249 -386.257858) (xy 58.58028 -386.205952)
			(xy 58.557342 -386.150578) (xy 58.541829 -386.092684) (xy 58.534007 -386.03326) (xy 58.533538 -386.003292)
			(xy 58.534059 -385.972229) (xy 58.542475 -385.910675) (xy 58.550302 -385.88061) (xy 58.553096 -385.870704)
			(xy 58.550556 -385.850384) (xy 58.508392 -385.777486) (xy 58.502977 -385.768895) (xy 58.486864 -385.756567)
			(xy 58.47715 -385.75361) (xy 58.476896 -385.75361) (xy 58.447788 -385.745604) (xy 58.39182 -385.722973)
			(xy 58.339312 -385.693182) (xy 58.291177 -385.656746) (xy 58.248249 -385.614298) (xy 58.211275 -385.566576)
			(xy 58.180895 -385.514406) (xy 58.157636 -385.458696) (xy 58.141904 -385.400412) (xy 58.13397 -385.340565)
			(xy 58.133488 -385.31038) (xy 58.133488 -385.309872) (xy 58.133984 -385.279013) (xy 58.142302 -385.217859)
			(xy 58.158768 -385.158378) (xy 58.183084 -385.101652) (xy 58.198512 -385.074922) (xy 58.204354 -385.06527)
			(xy 58.206894 -385.042918) (xy 58.177176 -384.958336) (xy 58.172914 -384.947982) (xy 58.15723 -384.932039)
			(xy 58.14695 -384.927602) (xy 58.123592 -384.918398) (xy 58.079748 -384.893939) (xy 58.040105 -384.863136)
			(xy 58.005571 -384.826695) (xy 57.976941 -384.785455) (xy 57.954871 -384.740362) (xy 57.939869 -384.692451)
			(xy 57.93228 -384.642824) (xy 57.931812 -384.617722) (xy 57.393078 -384.617722) (xy 57.393078 -384.61823)
			(xy 57.39251 -384.645204) (xy 57.383705 -384.69843) (xy 57.375552 -384.724148) (xy 57.371742 -384.73507)
			(xy 57.374282 -384.757422) (xy 57.421018 -384.833876) (xy 57.427338 -384.843054) (xy 57.445905 -384.855322)
			(xy 57.456832 -384.857498) (xy 57.457086 -384.857498) (xy 57.486411 -384.862162) (xy 57.543582 -384.878218)
			(xy 57.598196 -384.901533) (xy 57.649335 -384.931718) (xy 57.696139 -384.968264) (xy 57.737823 -385.010558)
			(xy 57.773686 -385.057888) (xy 57.803125 -385.109459) (xy 57.825646 -385.164406) (xy 57.84087 -385.221804)
			(xy 57.848541 -385.280689) (xy 57.849008 -385.31038) (xy 57.848483 -385.341443) (xy 57.84007 -385.402997)
			(xy 57.832244 -385.433062) (xy 57.82945 -385.442968) (xy 57.83199 -385.463288) (xy 57.874154 -385.536186)
			(xy 57.879532 -385.544805) (xy 57.895672 -385.557116) (xy 57.905396 -385.560062) (xy 57.90565 -385.560062)
			(xy 57.934759 -385.568063) (xy 57.990725 -385.590697) (xy 58.043231 -385.620491) (xy 58.091364 -385.656929)
			(xy 58.134291 -385.699377) (xy 58.171265 -385.7471) (xy 58.201645 -385.799268) (xy 58.224904 -385.854978)
			(xy 58.240638 -385.913261) (xy 58.248575 -385.973107) (xy 58.249058 -386.003292) (xy 58.248933 -386.017427)
			(xy 58.247151 -386.045641) (xy 58.245502 -386.05968) (xy 58.244713 -386.068288) (xy 58.24836 -386.085174)
			(xy 58.252614 -386.0927) (xy 58.268616 -386.1181) (xy 58.273296 -386.125112) (xy 58.286264 -386.135868)
			(xy 58.294016 -386.139182) (xy 58.317361 -386.148417) (xy 58.361205 -386.172871) (xy 58.400849 -386.203669)
			(xy 58.435385 -386.240104) (xy 58.464017 -386.28134) (xy 58.486089 -386.32643) (xy 58.501093 -386.374337)
			(xy 58.508685 -386.423961) (xy 58.509154 -386.449062) (xy 58.509154 -386.449316) (xy 58.508714 -386.473518)
			(xy 58.501646 -386.521402) (xy 58.487664 -386.567742) (xy 58.467068 -386.611544) (xy 58.454036 -386.631942)
			(xy 58.449306 -386.639853) (xy 58.445266 -386.657821) (xy 58.446162 -386.666994) (xy 58.450734 -386.697982)
			(xy 58.452534 -386.707238) (xy 58.461783 -386.723651) (xy 58.468768 -386.729986) (xy 58.490829 -386.748688)
			(xy 58.53057 -386.790706) (xy 58.5647 -386.837398) (xy 58.592673 -386.888018) (xy 58.614044 -386.94176)
			(xy 58.628472 -386.997766) (xy 58.635728 -387.055144) (xy 58.636154 -387.084062) (xy 58.635562 -387.117425)
			(xy 58.625919 -387.183451) (xy 58.606787 -387.247375) (xy 58.593228 -387.277864) (xy 58.589047 -387.288307)
			(xy 58.589154 -387.310768) (xy 58.598856 -387.331027) (xy 58.607198 -387.33857) (xy 58.629428 -387.357263)
			(xy 58.669492 -387.399315) (xy 58.703914 -387.446098) (xy 58.732141 -387.49686) (xy 58.75372 -387.550785)
			(xy 58.768302 -387.607006) (xy 58.775655 -387.664621) (xy 58.776108 -387.693662) (xy 58.775647 -387.722668)
			(xy 58.768336 -387.780216) (xy 58.753812 -387.83638) (xy 58.73231 -387.890258) (xy 58.704172 -387.940989)
			(xy 58.669852 -387.987758) (xy 58.629897 -388.029816) (xy 58.607706 -388.0485) (xy 58.600848 -388.054088)
			(xy 58.59145 -388.069582) (xy 58.577734 -388.143242) (xy 58.576531 -388.152002) (xy 58.579527 -388.169416)
			(xy 58.583576 -388.177278) (xy 58.583576 -388.177532) (xy 58.596146 -388.200721) (xy 58.614023 -388.250341)
			(xy 58.623126 -388.302292) (xy 58.623708 -388.328662) (xy 58.623639 -388.338021) (xy 58.622496 -388.356703)
			(xy 58.621422 -388.366) (xy 58.620406 -388.374636) (xy 58.624216 -388.391908) (xy 58.667904 -388.46125)
			(xy 58.681874 -388.471918) (xy 58.690256 -388.474712) (xy 58.714287 -388.483171) (xy 58.759459 -388.506726)
			(xy 58.800264 -388.537228) (xy 58.835642 -388.573884) (xy 58.864677 -388.615745) (xy 58.886615 -388.661724)
			(xy 58.894218 -388.68604) (xy 58.895742 -388.691882) (xy 59.216036 -389.245602) (xy 59.2201 -389.24992)
			(xy 59.236292 -389.267639) (xy 59.263718 -389.307027) (xy 59.284863 -389.350113) (xy 59.299239 -389.395905)
			(xy 59.306516 -389.443346) (xy 59.306968 -389.467344) (xy 59.306524 -389.492122) (xy 59.298769 -389.541068)
			(xy 59.283458 -389.5882) (xy 59.260966 -389.632358) (xy 59.231847 -389.672457) (xy 59.196817 -389.70751)
			(xy 59.156737 -389.736656) (xy 59.112594 -389.759177) (xy 59.065473 -389.77452) (xy 59.016532 -389.782307)
			(xy 58.991754 -389.782812) (xy 58.991246 -389.782812) (xy 58.965853 -389.782271) (xy 58.915721 -389.774148)
			(xy 58.867537 -389.758103) (xy 58.822542 -389.734551) (xy 58.781899 -389.704099) (xy 58.746656 -389.667533)
			(xy 58.717721 -389.625796) (xy 58.695841 -389.579965) (xy 58.688224 -389.555736) (xy 58.6867 -389.549894)
			(xy 58.366406 -388.996174) (xy 58.362342 -388.991856) (xy 58.346181 -388.974124) (xy 58.318813 -388.934721)
			(xy 58.297723 -388.891631) (xy 58.283396 -388.845846) (xy 58.276162 -388.79842) (xy 58.275728 -388.774432)
			(xy 58.275809 -388.762384) (xy 58.277591 -388.738355) (xy 58.279284 -388.726426) (xy 58.280247 -388.717667)
			(xy 58.276883 -388.700387) (xy 58.27268 -388.692644) (xy 58.239914 -388.637272) (xy 58.235204 -388.63)
			(xy 58.221973 -388.618832) (xy 58.214006 -388.615428) (xy 58.213498 -388.615428) (xy 58.191788 -388.606975)
			(xy 58.150981 -388.584503) (xy 58.114061 -388.556094) (xy 58.081883 -388.522407) (xy 58.055194 -388.484225)
			(xy 58.034614 -388.442432) (xy 58.02062 -388.397998) (xy 58.013535 -388.351955) (xy 58.013092 -388.328662)
			(xy 58.013659 -388.302289) (xy 58.022742 -388.250331) (xy 58.04063 -388.20071) (xy 58.053224 -388.177532)
			(xy 58.053224 -388.177278) (xy 58.057236 -388.169403) (xy 58.060234 -388.152001) (xy 58.059066 -388.143242)
			(xy 58.04535 -388.069582) (xy 58.035952 -388.054088) (xy 58.029094 -388.0485) (xy 58.006922 -388.029795)
			(xy 57.966975 -387.987734) (xy 57.932658 -387.940965) (xy 57.90452 -387.890239) (xy 57.88301 -387.836366)
			(xy 57.868473 -387.780209) (xy 57.861143 -387.722666) (xy 57.860692 -387.693662) (xy 57.860692 -387.693408)
			(xy 57.861268 -387.660086) (xy 57.870936 -387.594147) (xy 57.890067 -387.530308) (xy 57.903618 -387.49986)
			(xy 57.907889 -387.489446) (xy 57.907755 -387.466959) (xy 57.898012 -387.446692) (xy 57.889648 -387.439154)
			(xy 57.867391 -387.420491) (xy 57.827326 -387.378435) (xy 57.792905 -387.331647) (xy 57.764681 -387.28088)
			(xy 57.743107 -387.22695) (xy 57.728531 -387.170724) (xy 57.721186 -387.113105) (xy 57.720738 -387.084062)
			(xy 57.720738 -387.083808) (xy 57.721155 -387.054908) (xy 57.728442 -386.997568) (xy 57.742889 -386.941602)
			(xy 57.764267 -386.8879) (xy 57.792234 -386.837316) (xy 57.826346 -386.790654) (xy 57.866061 -386.748658)
			(xy 57.888124 -386.729986) (xy 57.895204 -386.72373) (xy 57.904469 -386.707278) (xy 57.906158 -386.697982)
			(xy 57.91073 -386.666994) (xy 57.911633 -386.657821) (xy 57.907593 -386.63985) (xy 57.902856 -386.631942)
			(xy 57.886546 -386.606121) (xy 57.86277 -386.549872) (xy 57.855612 -386.520182) (xy 57.85348 -386.511952)
			(xy 57.844648 -386.497436) (xy 57.83834 -386.491734) (xy 57.801002 -386.461) (xy 57.79135 -386.461)
			(xy 57.761381 -386.460565) (xy 57.701956 -386.452735) (xy 57.644062 -386.437217) (xy 57.588688 -386.414274)
			(xy 57.536782 -386.384301) (xy 57.489232 -386.34781) (xy 57.446852 -386.305424) (xy 57.410367 -386.25787)
			(xy 57.3804 -386.20596) (xy 57.357465 -386.150583) (xy 57.341954 -386.092687) (xy 57.334132 -386.033261)
			(xy 57.333642 -386.003292) (xy 57.334163 -385.972229) (xy 57.342579 -385.910675) (xy 57.350406 -385.88061)
			(xy 57.3532 -385.870704) (xy 57.35066 -385.850384) (xy 57.308496 -385.777486) (xy 57.303079 -385.768896)
			(xy 57.286968 -385.756568) (xy 57.277254 -385.75361) (xy 57.277 -385.75361) (xy 57.247874 -385.745668)
			(xy 57.191907 -385.723026) (xy 57.139401 -385.693224) (xy 57.091268 -385.656779) (xy 57.048343 -385.614324)
			(xy 57.011371 -385.566595) (xy 56.980994 -385.51442) (xy 56.957737 -385.458705) (xy 56.942006 -385.400417)
			(xy 56.934073 -385.340567) (xy 56.933592 -385.31038) (xy 56.934119 -385.279492) (xy 56.942424 -385.218277)
			(xy 56.95888 -385.158733) (xy 56.98319 -385.101941) (xy 56.998616 -385.075176) (xy 57.003998 -385.065255)
			(xy 57.006356 -385.042832) (xy 57.003188 -385.031996) (xy 56.97728 -384.958336) (xy 56.973017 -384.947983)
			(xy 56.957334 -384.93204) (xy 56.947054 -384.927602) (xy 56.923664 -384.918441) (xy 56.879768 -384.894017)
			(xy 56.840073 -384.863232) (xy 56.805493 -384.826795) (xy 56.776825 -384.785545) (xy 56.754729 -384.740432)
			(xy 56.739713 -384.692496) (xy 56.732124 -384.642839) (xy 56.731662 -384.617722) (xy 56.193182 -384.617722)
			(xy 56.193182 -384.61823) (xy 56.192614 -384.645204) (xy 56.183809 -384.69843) (xy 56.175656 -384.724148)
			(xy 56.171846 -384.73507) (xy 56.174386 -384.757422) (xy 56.221122 -384.833876) (xy 56.22744 -384.843056)
			(xy 56.246008 -384.855323) (xy 56.256936 -384.857498) (xy 56.25719 -384.857498) (xy 56.286503 -384.862237)
			(xy 56.343673 -384.878281) (xy 56.398287 -384.901586) (xy 56.449427 -384.931761) (xy 56.496234 -384.968298)
			(xy 56.53792 -385.010584) (xy 56.573785 -385.057908) (xy 56.603226 -385.109474) (xy 56.625748 -385.164416)
			(xy 56.640973 -385.22181) (xy 56.648645 -385.280691) (xy 56.649112 -385.31038) (xy 56.649112 -385.310888)
			(xy 56.648564 -385.341887) (xy 56.640158 -385.403312) (xy 56.632348 -385.433316) (xy 56.629554 -385.443222)
			(xy 56.632094 -385.463542) (xy 56.674004 -385.536186) (xy 56.679492 -385.544791) (xy 56.695729 -385.557121)
			(xy 56.7055 -385.560062) (xy 56.734619 -385.56803) (xy 56.790584 -385.59067) (xy 56.843089 -385.620469)
			(xy 56.891221 -385.656911) (xy 56.934146 -385.699364) (xy 56.971118 -385.74709) (xy 57.001497 -385.799261)
			(xy 57.024755 -385.854973) (xy 57.040489 -385.913258) (xy 57.048425 -385.973106) (xy 57.048908 -386.003292)
			(xy 57.048783 -386.017427) (xy 57.047001 -386.045641) (xy 57.045352 -386.05968) (xy 57.044556 -386.068288)
			(xy 57.048206 -386.085175) (xy 57.052464 -386.0927) (xy 57.068212 -386.1181) (xy 57.072915 -386.125165)
			(xy 57.086025 -386.135931) (xy 57.093866 -386.139182) (xy 57.117255 -386.148346) (xy 57.16115 -386.172771)
			(xy 57.200844 -386.203556) (xy 57.235423 -386.239993) (xy 57.264091 -386.281242) (xy 57.286187 -386.326354)
			(xy 57.301204 -386.37429) (xy 57.308795 -386.423946) (xy 57.309258 -386.449062) (xy 57.309258 -386.449316)
			(xy 57.308818 -386.473518) (xy 57.30175 -386.521402) (xy 57.287768 -386.567742) (xy 57.267172 -386.611544)
			(xy 57.25414 -386.631942) (xy 57.24941 -386.639853) (xy 57.245371 -386.657821) (xy 57.246266 -386.666994)
			(xy 57.250838 -386.697982) (xy 57.252637 -386.707238) (xy 57.261887 -386.723652) (xy 57.268872 -386.729986)
			(xy 57.290934 -386.748687) (xy 57.330675 -386.790706) (xy 57.364804 -386.837397) (xy 57.392777 -386.888017)
			(xy 57.414148 -386.941759) (xy 57.428576 -386.997766) (xy 57.435832 -387.055144) (xy 57.436258 -387.084062)
			(xy 57.435666 -387.117425) (xy 57.426023 -387.18345) (xy 57.406891 -387.247375) (xy 57.393332 -387.277864)
			(xy 57.38915 -387.288307) (xy 57.389257 -387.310769) (xy 57.39896 -387.331027) (xy 57.407302 -387.33857)
			(xy 57.429533 -387.357262) (xy 57.469597 -387.399315) (xy 57.504019 -387.446098) (xy 57.532246 -387.49686)
			(xy 57.553824 -387.550785) (xy 57.568406 -387.607006) (xy 57.575759 -387.664621) (xy 57.576212 -387.693662)
			(xy 57.57575 -387.722668) (xy 57.568438 -387.780216) (xy 57.553915 -387.836379) (xy 57.532413 -387.890258)
			(xy 57.504276 -387.940988) (xy 57.469955 -387.987758) (xy 57.430001 -388.029816) (xy 57.40781 -388.0485)
			(xy 57.400952 -388.054088) (xy 57.391554 -388.069582) (xy 57.377838 -388.143242) (xy 57.376647 -388.152003)
			(xy 57.379637 -388.169415) (xy 57.38368 -388.177278) (xy 57.38368 -388.177532) (xy 57.39625 -388.200721)
			(xy 57.414127 -388.250341) (xy 57.42323 -388.302292) (xy 57.423812 -388.328662) (xy 57.423743 -388.338021)
			(xy 57.4226 -388.356703) (xy 57.421526 -388.366) (xy 57.42051 -388.374636) (xy 57.42432 -388.391908)
			(xy 57.468008 -388.46125) (xy 57.481978 -388.471918) (xy 57.49036 -388.474712) (xy 57.514392 -388.483169)
			(xy 57.559564 -388.506725) (xy 57.600368 -388.537227) (xy 57.635747 -388.573884) (xy 57.664781 -388.615745)
			(xy 57.686719 -388.661724) (xy 57.694322 -388.68604) (xy 57.695846 -388.691882) (xy 58.01614 -389.245602)
			(xy 58.020204 -389.24992) (xy 58.036396 -389.267638) (xy 58.063822 -389.307026) (xy 58.084967 -389.350113)
			(xy 58.099343 -389.395905) (xy 58.10662 -389.443346) (xy 58.107072 -389.467344) (xy 58.106624 -389.492122)
			(xy 58.098869 -389.541067) (xy 58.083558 -389.588199) (xy 58.061067 -389.632357) (xy 58.031948 -389.672456)
			(xy 57.996919 -389.707509) (xy 57.95684 -389.736655) (xy 57.912697 -389.759176) (xy 57.865576 -389.774519)
			(xy 57.816636 -389.782307) (xy 57.791858 -389.782812) (xy 57.79135 -389.782812) (xy 57.765957 -389.782268)
			(xy 57.715826 -389.774145) (xy 57.667641 -389.7581) (xy 57.622647 -389.734549) (xy 57.582003 -389.704097)
			(xy 57.54676 -389.667532) (xy 57.517825 -389.625795) (xy 57.495945 -389.579965) (xy 57.488328 -389.555736)
			(xy 57.486804 -389.549894) (xy 57.16651 -388.996174) (xy 57.162446 -388.991856) (xy 57.146285 -388.974123)
			(xy 57.118918 -388.934721) (xy 57.097827 -388.891631) (xy 57.0835 -388.845845) (xy 57.076266 -388.798419)
			(xy 57.075832 -388.774432) (xy 57.075913 -388.762384) (xy 57.077695 -388.738355) (xy 57.079388 -388.726426)
			(xy 57.080351 -388.717667) (xy 57.076987 -388.700387) (xy 57.072784 -388.692644) (xy 57.040018 -388.637272)
			(xy 57.035307 -388.630001) (xy 57.022076 -388.618833) (xy 57.01411 -388.615428) (xy 57.013602 -388.615428)
			(xy 56.991893 -388.606973) (xy 56.951086 -388.584501) (xy 56.914165 -388.556093) (xy 56.881988 -388.522406)
			(xy 56.855299 -388.484224) (xy 56.834718 -388.442431) (xy 56.820724 -388.397998) (xy 56.813639 -388.351955)
			(xy 56.813196 -388.328662) (xy 56.813762 -388.302289) (xy 56.822845 -388.250331) (xy 56.840733 -388.20071)
			(xy 56.853328 -388.177532) (xy 56.853328 -388.177278) (xy 56.85734 -388.169403) (xy 56.860338 -388.152001)
			(xy 56.85917 -388.143242) (xy 56.845454 -388.069582) (xy 56.836056 -388.054088) (xy 56.829198 -388.0485)
			(xy 56.807027 -388.029794) (xy 56.76708 -387.987733) (xy 56.732763 -387.940965) (xy 56.704624 -387.890239)
			(xy 56.683114 -387.836366) (xy 56.668577 -387.780209) (xy 56.661247 -387.722666) (xy 56.660796 -387.693662)
			(xy 56.660796 -387.693408) (xy 56.661372 -387.660086) (xy 56.67104 -387.594147) (xy 56.690171 -387.530308)
			(xy 56.703722 -387.49986) (xy 56.707992 -387.489445) (xy 56.707858 -387.466959) (xy 56.698115 -387.446692)
			(xy 56.689752 -387.439154) (xy 56.667496 -387.420491) (xy 56.627431 -387.378434) (xy 56.59301 -387.331647)
			(xy 56.564785 -387.28088) (xy 56.543212 -387.22695) (xy 56.528635 -387.170724) (xy 56.52129 -387.113105)
			(xy 56.520842 -387.084062) (xy 56.520842 -387.083808) (xy 56.521257 -387.054908) (xy 56.528545 -386.997568)
			(xy 56.542992 -386.941602) (xy 56.56437 -386.887899) (xy 56.592337 -386.837315) (xy 56.62645 -386.790654)
			(xy 56.666165 -386.748658) (xy 56.688228 -386.729986) (xy 56.695309 -386.723731) (xy 56.704573 -386.707279)
			(xy 56.706262 -386.697982) (xy 56.710834 -386.666994) (xy 56.711736 -386.657821) (xy 56.707696 -386.63985)
			(xy 56.70296 -386.631942) (xy 56.686651 -386.606121) (xy 56.662874 -386.549872) (xy 56.655716 -386.520182)
			(xy 56.653583 -386.511952) (xy 56.644752 -386.497436) (xy 56.638444 -386.491734) (xy 56.601106 -386.461)
			(xy 56.5912 -386.461) (xy 56.561231 -386.460539) (xy 56.501805 -386.452715) (xy 56.443908 -386.437202)
			(xy 56.388532 -386.414264) (xy 56.336624 -386.384294) (xy 56.289072 -386.347806) (xy 56.246689 -386.305422)
			(xy 56.210201 -386.257869) (xy 56.180232 -386.20596) (xy 56.157296 -386.150584) (xy 56.141783 -386.092687)
			(xy 56.133961 -386.033261) (xy 56.133492 -386.003292) (xy 56.134012 -385.972229) (xy 56.142428 -385.910675)
			(xy 56.150256 -385.88061) (xy 56.15305 -385.870704) (xy 56.15051 -385.850384) (xy 56.108092 -385.777232)
			(xy 56.102654 -385.76871) (xy 56.086527 -385.75654) (xy 56.07685 -385.75361) (xy 56.047765 -385.745567)
			(xy 55.991838 -385.722902) (xy 55.939372 -385.693088) (xy 55.891277 -385.656641) (xy 55.848387 -385.614192)
			(xy 55.811443 -385.566477) (xy 55.781088 -385.514323) (xy 55.757846 -385.458633) (xy 55.74212 -385.400373)
			(xy 55.734183 -385.340552) (xy 55.733696 -385.31038) (xy 55.734222 -385.279492) (xy 55.742527 -385.218277)
			(xy 55.758984 -385.158733) (xy 55.783294 -385.101941) (xy 55.79872 -385.075176) (xy 55.804102 -385.065255)
			(xy 55.806459 -385.042832) (xy 55.803292 -385.031996) (xy 55.777384 -384.958336) (xy 55.773119 -384.947984)
			(xy 55.757437 -384.93204) (xy 55.747158 -384.927602) (xy 55.723768 -384.918439) (xy 55.679872 -384.894015)
			(xy 55.640177 -384.86323) (xy 55.605598 -384.826794) (xy 55.576929 -384.785544) (xy 55.554833 -384.740432)
			(xy 55.539817 -384.692495) (xy 55.532228 -384.642839) (xy 55.531766 -384.617722) (xy 54.993032 -384.617722)
			(xy 54.993032 -384.61823) (xy 54.992467 -384.645204) (xy 54.98366 -384.69843) (xy 54.975506 -384.724148)
			(xy 54.971696 -384.73507) (xy 54.974236 -384.757422) (xy 55.020972 -384.833876) (xy 55.027268 -384.843074)
			(xy 55.045852 -384.855332) (xy 55.056786 -384.857498) (xy 55.05704 -384.857498) (xy 55.086359 -384.862198)
			(xy 55.14353 -384.878248) (xy 55.198144 -384.901559) (xy 55.249283 -384.931739) (xy 55.296089 -384.968281)
			(xy 55.337774 -385.01057) (xy 55.373638 -385.057898) (xy 55.403078 -385.109466) (xy 55.425599 -385.164411)
			(xy 55.440823 -385.221806) (xy 55.448495 -385.28069) (xy 55.448962 -385.31038) (xy 55.448435 -385.341443)
			(xy 55.440023 -385.402996) (xy 55.432198 -385.433062) (xy 55.429404 -385.442968) (xy 55.431944 -385.463288)
			(xy 55.474108 -385.536186) (xy 55.479504 -385.544791) (xy 55.495631 -385.557109) (xy 55.50535 -385.560062)
			(xy 55.505604 -385.560062) (xy 55.534704 -385.568094) (xy 55.590671 -385.590722) (xy 55.643177 -385.620512)
			(xy 55.691312 -385.656945) (xy 55.73424 -385.699389) (xy 55.771215 -385.747109) (xy 55.801596 -385.799275)
			(xy 55.824856 -385.854982) (xy 55.840591 -385.913264) (xy 55.848528 -385.973108) (xy 55.849012 -386.003292)
			(xy 55.848887 -386.017427) (xy 55.847105 -386.045641) (xy 55.845456 -386.05968) (xy 55.844673 -386.068288)
			(xy 55.848317 -386.085174) (xy 55.852568 -386.0927) (xy 55.868316 -386.1181) (xy 55.873018 -386.125166)
			(xy 55.886129 -386.135932) (xy 55.89397 -386.139182) (xy 55.91736 -386.148344) (xy 55.961255 -386.172769)
			(xy 56.000948 -386.203555) (xy 56.035527 -386.239992) (xy 56.064195 -386.281241) (xy 56.086291 -386.326353)
			(xy 56.101308 -386.374289) (xy 56.108899 -386.423945) (xy 56.109362 -386.449062) (xy 56.109362 -386.449316)
			(xy 56.108921 -386.473518) (xy 56.101853 -386.521402) (xy 56.087872 -386.567742) (xy 56.067276 -386.611544)
			(xy 56.054244 -386.631942) (xy 56.049514 -386.639853) (xy 56.045475 -386.657821) (xy 56.04637 -386.666994)
			(xy 56.050942 -386.697982) (xy 56.052739 -386.707239) (xy 56.06199 -386.723652) (xy 56.068976 -386.729986)
			(xy 56.091039 -386.748686) (xy 56.130779 -386.790705) (xy 56.164908 -386.837397) (xy 56.192881 -386.888017)
			(xy 56.214252 -386.941759) (xy 56.22868 -386.997766) (xy 56.235936 -387.055144) (xy 56.236362 -387.084062)
			(xy 56.235769 -387.117425) (xy 56.226126 -387.18345) (xy 56.206995 -387.247375) (xy 56.193436 -387.277864)
			(xy 56.189253 -387.288306) (xy 56.189359 -387.310769) (xy 56.199063 -387.331027) (xy 56.207406 -387.33857)
			(xy 56.229638 -387.357261) (xy 56.269701 -387.399314) (xy 56.304123 -387.446097) (xy 56.33235 -387.496859)
			(xy 56.353928 -387.550784) (xy 56.368511 -387.607006) (xy 56.375863 -387.664621) (xy 56.376316 -387.693662)
			(xy 56.375852 -387.722668) (xy 56.368541 -387.780216) (xy 56.354018 -387.836379) (xy 56.332516 -387.890258)
			(xy 56.304379 -387.940988) (xy 56.270059 -387.987757) (xy 56.230105 -388.029816) (xy 56.207914 -388.0485)
			(xy 56.201056 -388.054088) (xy 56.191658 -388.069582) (xy 56.177942 -388.143242) (xy 56.176751 -388.152003)
			(xy 56.179741 -388.169415) (xy 56.183784 -388.177278) (xy 56.183784 -388.177532) (xy 56.196355 -388.200721)
			(xy 56.214231 -388.250341) (xy 56.223334 -388.302292) (xy 56.223916 -388.328662) (xy 56.223847 -388.338021)
			(xy 56.222704 -388.356703) (xy 56.22163 -388.366) (xy 56.220614 -388.374636) (xy 56.224424 -388.391908)
			(xy 56.268112 -388.46125) (xy 56.282082 -388.471918) (xy 56.290464 -388.474712) (xy 56.314554 -388.483211)
			(xy 56.359846 -388.506832) (xy 56.400743 -388.537438) (xy 56.436176 -388.574232) (xy 56.46522 -388.616252)
			(xy 56.487117 -388.662402) (xy 56.49468 -388.686802) (xy 56.496204 -388.692644) (xy 56.81599 -389.245602)
			(xy 56.820054 -389.24992) (xy 56.836219 -389.267582) (xy 56.863536 -389.306901) (xy 56.884603 -389.349894)
			(xy 56.898935 -389.395576) (xy 56.906205 -389.442898) (xy 56.906668 -389.466836) (xy 56.906668 -389.467344)
			(xy 56.906223 -389.492135) (xy 56.89846 -389.541105) (xy 56.883133 -389.588259) (xy 56.860619 -389.632434)
			(xy 56.831473 -389.672544) (xy 56.796411 -389.707601) (xy 56.756296 -389.736742) (xy 56.712118 -389.75925)
			(xy 56.664962 -389.77457) (xy 56.615991 -389.782326) (xy 56.5912 -389.782812) (xy 56.565806 -389.782312)
			(xy 56.515672 -389.774181) (xy 56.467486 -389.758129) (xy 56.422492 -389.734571) (xy 56.381849 -389.704114)
			(xy 56.346607 -389.667543) (xy 56.317673 -389.625801) (xy 56.295795 -389.579967) (xy 56.288178 -389.555736)
			(xy 56.286654 -389.549894) (xy 55.966106 -388.995412) (xy 55.962042 -388.991094) (xy 55.945941 -388.973435)
			(xy 55.918754 -388.934135) (xy 55.897802 -388.891186) (xy 55.883566 -388.845568) (xy 55.876371 -388.798326)
			(xy 55.875936 -388.774432) (xy 55.876017 -388.762384) (xy 55.877799 -388.738355) (xy 55.879492 -388.726426)
			(xy 55.880454 -388.717667) (xy 55.87709 -388.700387) (xy 55.872888 -388.692644) (xy 55.840122 -388.637272)
			(xy 55.835409 -388.630002) (xy 55.82218 -388.618833) (xy 55.814214 -388.615428) (xy 55.813706 -388.615428)
			(xy 55.791998 -388.606971) (xy 55.751191 -388.5845) (xy 55.71427 -388.556091) (xy 55.682092 -388.522405)
			(xy 55.655403 -388.484223) (xy 55.634823 -388.442431) (xy 55.620828 -388.397998) (xy 55.613743 -388.351954)
			(xy 55.6133 -388.328662) (xy 55.613866 -388.302289) (xy 55.622949 -388.250331) (xy 55.640837 -388.20071)
			(xy 55.653432 -388.177532) (xy 55.653432 -388.177278) (xy 55.657444 -388.169403) (xy 55.660442 -388.152001)
			(xy 55.659274 -388.143242) (xy 55.645558 -388.069582) (xy 55.63616 -388.054088) (xy 55.629302 -388.0485)
			(xy 55.607132 -388.029793) (xy 55.567185 -387.987732) (xy 55.532867 -387.940964) (xy 55.504728 -387.890238)
			(xy 55.483218 -387.836366) (xy 55.468682 -387.780209) (xy 55.461351 -387.722666) (xy 55.4609 -387.693662)
			(xy 55.4609 -387.693408) (xy 55.461476 -387.660086) (xy 55.471143 -387.594147) (xy 55.490275 -387.530308)
			(xy 55.503826 -387.49986) (xy 55.508094 -387.489445) (xy 55.507961 -387.466959) (xy 55.498219 -387.446693)
			(xy 55.489856 -387.439154) (xy 55.467601 -387.42049) (xy 55.427536 -387.378434) (xy 55.393114 -387.331647)
			(xy 55.36489 -387.28088) (xy 55.343316 -387.22695) (xy 55.328739 -387.170723) (xy 55.321394 -387.113105)
			(xy 55.320946 -387.084062) (xy 55.320946 -387.083808) (xy 55.32136 -387.054908) (xy 55.328647 -386.997568)
			(xy 55.343095 -386.941602) (xy 55.364473 -386.887899) (xy 55.39244 -386.837315) (xy 55.426553 -386.790654)
			(xy 55.466269 -386.748658) (xy 55.488332 -386.729986) (xy 55.495414 -386.723731) (xy 55.504677 -386.707279)
			(xy 55.506366 -386.697982) (xy 55.510938 -386.666994) (xy 55.511855 -386.657821) (xy 55.507807 -386.639848)
			(xy 55.503064 -386.631942) (xy 55.486755 -386.60612) (xy 55.462978 -386.549872) (xy 55.45582 -386.520182)
			(xy 55.453686 -386.511953) (xy 55.444855 -386.497436) (xy 55.438548 -386.491734) (xy 55.40121 -386.461)
			(xy 55.391304 -386.461) (xy 55.361335 -386.460535) (xy 55.301909 -386.452712) (xy 55.244013 -386.437199)
			(xy 55.188637 -386.414262) (xy 55.136728 -386.384292) (xy 55.089176 -386.347804) (xy 55.046793 -386.305421)
			(xy 55.010305 -386.257868) (xy 54.980337 -386.20596) (xy 54.9574 -386.150583) (xy 54.941887 -386.092687)
			(xy 54.934065 -386.033261) (xy 54.933596 -386.003292) (xy 54.934116 -385.972229) (xy 54.942532 -385.910675)
			(xy 54.95036 -385.88061) (xy 54.953154 -385.870704) (xy 54.950614 -385.850384) (xy 54.90845 -385.777486)
			(xy 54.903052 -385.768882) (xy 54.886927 -385.756561) (xy 54.877208 -385.75361) (xy 54.876954 -385.75361)
			(xy 54.847838 -385.745632) (xy 54.79187 -385.722997) (xy 54.739363 -385.6932) (xy 54.691229 -385.656761)
			(xy 54.648303 -385.61431) (xy 54.611329 -385.566584) (xy 54.58095 -385.514413) (xy 54.557693 -385.4587)
			(xy 54.541961 -385.400414) (xy 54.534027 -385.340566) (xy 54.533546 -385.31038) (xy 54.534065 -385.279492)
			(xy 54.542371 -385.218276) (xy 54.55883 -385.158732) (xy 54.583142 -385.10194) (xy 54.59857 -385.075176)
			(xy 54.603953 -385.065255) (xy 54.606307 -385.042832) (xy 54.603142 -385.031996) (xy 54.577234 -384.958336)
			(xy 54.572991 -384.947973) (xy 54.557294 -384.932034) (xy 54.547008 -384.927602) (xy 54.523629 -384.918412)
			(xy 54.479732 -384.893994) (xy 54.440035 -384.863215) (xy 54.405453 -384.826783) (xy 54.376783 -384.785537)
			(xy 54.354685 -384.740427) (xy 54.339668 -384.692493) (xy 54.332078 -384.642838) (xy 54.331616 -384.617722)
			(xy 53.793136 -384.617722) (xy 53.793136 -384.61823) (xy 53.79257 -384.645204) (xy 53.783764 -384.69843)
			(xy 53.77561 -384.724148) (xy 53.7718 -384.73507) (xy 53.77434 -384.757422) (xy 53.821076 -384.833876)
			(xy 53.82737 -384.843076) (xy 53.845956 -384.855332) (xy 53.85689 -384.857498) (xy 53.857144 -384.857498)
			(xy 53.886464 -384.862195) (xy 53.943634 -384.878245) (xy 53.998248 -384.901556) (xy 54.049388 -384.931737)
			(xy 54.096193 -384.968279) (xy 54.137878 -385.010569) (xy 54.173742 -385.057897) (xy 54.203182 -385.109466)
			(xy 54.225703 -385.16441) (xy 54.240927 -385.221806) (xy 54.248599 -385.280689) (xy 54.249066 -385.31038)
			(xy 54.248539 -385.341443) (xy 54.240127 -385.402996) (xy 54.232302 -385.433062) (xy 54.229508 -385.442968)
			(xy 54.232048 -385.463288) (xy 54.274212 -385.536186) (xy 54.279607 -385.544792) (xy 54.295735 -385.557109)
			(xy 54.305454 -385.560062) (xy 54.305708 -385.560062) (xy 54.334809 -385.568091) (xy 54.390776 -385.59072)
			(xy 54.443282 -385.62051) (xy 54.491417 -385.656943) (xy 54.534344 -385.699388) (xy 54.571319 -385.747108)
			(xy 54.6017 -385.799274) (xy 54.62496 -385.854982) (xy 54.640695 -385.913263) (xy 54.648632 -385.973108)
			(xy 54.649116 -386.003292) (xy 54.648991 -386.017427) (xy 54.647209 -386.045641) (xy 54.64556 -386.05968)
			(xy 54.644777 -386.068288) (xy 54.64842 -386.085174) (xy 54.652672 -386.0927) (xy 54.668674 -386.1181)
			(xy 54.673335 -386.125126) (xy 54.686316 -386.135874) (xy 54.694074 -386.139182) (xy 54.717432 -386.148386)
			(xy 54.761274 -386.172846) (xy 54.800917 -386.203651) (xy 54.835449 -386.240091) (xy 54.864079 -386.281331)
			(xy 54.886149 -386.326424) (xy 54.901152 -386.374334) (xy 54.908744 -386.42396) (xy 54.909212 -386.449062)
			(xy 54.909212 -386.449316) (xy 54.908763 -386.473517) (xy 54.901696 -386.521401) (xy 54.887717 -386.56774)
			(xy 54.867124 -386.611543) (xy 54.854094 -386.631942) (xy 54.849367 -386.639855) (xy 54.845324 -386.657821)
			(xy 54.84622 -386.666994) (xy 54.850792 -386.697982) (xy 54.852575 -386.707243) (xy 54.861835 -386.723655)
			(xy 54.868826 -386.729986) (xy 54.890899 -386.748674) (xy 54.930637 -386.790696) (xy 54.964764 -386.837391)
			(xy 54.992735 -386.888013) (xy 55.014104 -386.941757) (xy 55.028531 -386.997764) (xy 55.035786 -387.055144)
			(xy 55.036212 -387.084062) (xy 55.035624 -387.117426) (xy 55.02598 -387.183451) (xy 55.006846 -387.247375)
			(xy 54.993286 -387.277864) (xy 54.989086 -387.288302) (xy 54.989193 -387.31077) (xy 54.998906 -387.33103)
			(xy 55.007256 -387.33857) (xy 55.029477 -387.357274) (xy 55.069543 -387.399323) (xy 55.103968 -387.446103)
			(xy 55.132196 -387.496863) (xy 55.153776 -387.550787) (xy 55.16836 -387.607007) (xy 55.175713 -387.664621)
			(xy 55.176166 -387.693662) (xy 55.175684 -387.722667) (xy 55.168373 -387.780214) (xy 55.153852 -387.836376)
			(xy 55.132352 -387.890254) (xy 55.104219 -387.940984) (xy 55.069902 -387.987754) (xy 55.029953 -388.029815)
			(xy 55.007764 -388.0485) (xy 55.000906 -388.054088) (xy 54.991508 -388.069582) (xy 54.977792 -388.143242)
			(xy 54.976595 -388.152003) (xy 54.979587 -388.169416) (xy 54.983634 -388.177278) (xy 54.983634 -388.177532)
			(xy 54.996209 -388.200719) (xy 55.014083 -388.25034) (xy 55.023184 -388.302291) (xy 55.023766 -388.328662)
			(xy 55.023697 -388.338021) (xy 55.022554 -388.356703) (xy 55.02148 -388.366) (xy 55.020464 -388.374636)
			(xy 55.024274 -388.391908) (xy 55.067962 -388.46125) (xy 55.081932 -388.471918) (xy 55.090314 -388.474712)
			(xy 55.114337 -388.483194) (xy 55.15951 -388.506743) (xy 55.200316 -388.537239) (xy 55.235696 -388.573892)
			(xy 55.264733 -388.615749) (xy 55.286672 -388.661725) (xy 55.294276 -388.68604) (xy 55.2958 -388.691882)
			(xy 55.616094 -389.245602) (xy 55.620158 -389.24992) (xy 55.636323 -389.267581) (xy 55.663641 -389.3069)
			(xy 55.684707 -389.349894) (xy 55.699039 -389.395576) (xy 55.706309 -389.442898) (xy 55.706772 -389.466836)
			(xy 55.706772 -389.467344) (xy 55.706323 -389.492135) (xy 55.69856 -389.541105) (xy 55.683234 -389.588258)
			(xy 55.66072 -389.632433) (xy 55.631574 -389.672543) (xy 55.596512 -389.7076) (xy 55.556399 -389.736741)
			(xy 55.512221 -389.759249) (xy 55.465066 -389.77457) (xy 55.416095 -389.782326) (xy 55.391304 -389.782812)
			(xy 55.36591 -389.782308) (xy 55.315776 -389.774178) (xy 55.267591 -389.758127) (xy 55.222596 -389.734569)
			(xy 55.181954 -389.704112) (xy 55.146711 -389.667542) (xy 55.117777 -389.625801) (xy 55.095899 -389.579966)
			(xy 55.088282 -389.555736) (xy 55.086758 -389.549894) (xy 54.766464 -388.996174) (xy 54.7624 -388.991856)
			(xy 54.746197 -388.974147) (xy 54.718772 -388.934757) (xy 54.69763 -388.891667) (xy 54.683256 -388.845873)
			(xy 54.675982 -388.79843) (xy 54.675532 -388.774432) (xy 54.675674 -388.76238) (xy 54.67758 -388.73835)
			(xy 54.679342 -388.726426) (xy 54.680311 -388.717667) (xy 54.676944 -388.700387) (xy 54.672738 -388.692644)
			(xy 54.639972 -388.637272) (xy 54.635276 -388.62999) (xy 54.622035 -388.618827) (xy 54.614064 -388.615428)
			(xy 54.613556 -388.615428) (xy 54.591837 -388.606998) (xy 54.551031 -388.58452) (xy 54.514113 -388.556107)
			(xy 54.481937 -388.522417) (xy 54.45525 -388.484231) (xy 54.434671 -388.442436) (xy 54.420677 -388.398)
			(xy 54.413593 -388.351955) (xy 54.41315 -388.328662) (xy 54.413722 -388.302289) (xy 54.422804 -388.250331)
			(xy 54.440689 -388.200711) (xy 54.453282 -388.177532) (xy 54.453282 -388.177278) (xy 54.457292 -388.169402)
			(xy 54.460293 -388.152001) (xy 54.459124 -388.143242) (xy 54.445408 -388.069582) (xy 54.43601 -388.054088)
			(xy 54.429152 -388.0485) (xy 54.406971 -388.029806) (xy 54.367027 -387.987741) (xy 54.332711 -387.94097)
			(xy 54.304575 -387.890242) (xy 54.283066 -387.836368) (xy 54.268531 -387.78021) (xy 54.2612 -387.722666)
			(xy 54.26075 -387.693662) (xy 54.26075 -387.693408) (xy 54.26133 -387.660086) (xy 54.270997 -387.594148)
			(xy 54.290127 -387.530309) (xy 54.303676 -387.49986) (xy 54.307928 -387.489441) (xy 54.307794 -387.466961)
			(xy 54.298062 -387.446696) (xy 54.289706 -387.439154) (xy 54.26744 -387.420502) (xy 54.227378 -387.378443)
			(xy 54.192959 -387.331653) (xy 54.164736 -387.280884) (xy 54.143164 -387.226952) (xy 54.128588 -387.170725)
			(xy 54.121244 -387.113105) (xy 54.120796 -387.084062) (xy 54.120796 -387.083808) (xy 54.121228 -387.054908)
			(xy 54.128515 -386.99757) (xy 54.142961 -386.941605) (xy 54.164336 -386.887903) (xy 54.1923 -386.837319)
			(xy 54.22641 -386.790657) (xy 54.266121 -386.748659) (xy 54.288182 -386.729986) (xy 54.295255 -386.723723)
			(xy 54.304525 -386.707277) (xy 54.306216 -386.697982) (xy 54.310788 -386.666994) (xy 54.311697 -386.657821)
			(xy 54.307654 -386.639849) (xy 54.302914 -386.631942) (xy 54.286601 -386.606123) (xy 54.262827 -386.549873)
			(xy 54.25567 -386.520182) (xy 54.253522 -386.511957) (xy 54.2447 -386.497439) (xy 54.238398 -386.491734)
			(xy 54.20106 -386.461) (xy 54.191408 -386.461) (xy 54.161439 -386.460531) (xy 54.102013 -386.452709)
			(xy 54.044117 -386.437196) (xy 53.988741 -386.414259) (xy 53.936833 -386.38429) (xy 53.88928 -386.347802)
			(xy 53.846898 -386.30542) (xy 53.81041 -386.257867) (xy 53.780441 -386.205959) (xy 53.757504 -386.150583)
			(xy 53.741991 -386.092687) (xy 53.734169 -386.033261) (xy 53.7337 -386.003292) (xy 53.73422 -385.972229)
			(xy 53.742636 -385.910675) (xy 53.750464 -385.88061) (xy 53.753258 -385.870704) (xy 53.750718 -385.850384)
			(xy 53.708554 -385.777486) (xy 53.703154 -385.768883) (xy 53.687031 -385.756562) (xy 53.677312 -385.75361)
			(xy 53.677058 -385.75361) (xy 53.647943 -385.745629) (xy 53.591975 -385.722994) (xy 53.539468 -385.693198)
			(xy 53.491334 -385.656759) (xy 53.448408 -385.614308) (xy 53.411434 -385.566583) (xy 53.381055 -385.514412)
			(xy 53.357797 -385.4587) (xy 53.342065 -385.400414) (xy 53.334132 -385.340566) (xy 53.33365 -385.31038)
			(xy 53.334169 -385.279492) (xy 53.342475 -385.218276) (xy 53.358933 -385.158732) (xy 53.383246 -385.10194)
			(xy 53.398674 -385.075176) (xy 53.404057 -385.065255) (xy 53.406412 -385.042832) (xy 53.403246 -385.031996)
			(xy 53.377338 -384.958336) (xy 53.373093 -384.947974) (xy 53.357397 -384.932034) (xy 53.347112 -384.927602)
			(xy 53.323734 -384.918409) (xy 53.279836 -384.893993) (xy 53.240139 -384.863214) (xy 53.205557 -384.826782)
			(xy 53.176887 -384.785536) (xy 53.154789 -384.740427) (xy 53.139772 -384.692492) (xy 53.132182 -384.642838)
			(xy 53.13172 -384.617722) (xy 52.59324 -384.617722) (xy 52.59324 -384.61823) (xy 52.592674 -384.645204)
			(xy 52.583868 -384.69843) (xy 52.575714 -384.724148) (xy 52.571904 -384.73507) (xy 52.574444 -384.757422)
			(xy 52.62118 -384.833876) (xy 52.627472 -384.843077) (xy 52.646059 -384.855333) (xy 52.656994 -384.857498)
			(xy 52.657248 -384.857498) (xy 52.686538 -384.862302) (xy 52.743672 -384.878376) (xy 52.798248 -384.901702)
			(xy 52.849351 -384.931888) (xy 52.896122 -384.968427) (xy 52.937777 -385.010707) (xy 52.973616 -385.058018)
			(xy 53.003037 -385.109565) (xy 53.025547 -385.164483) (xy 53.040767 -385.22185) (xy 53.048443 -385.280704)
			(xy 53.048916 -385.31038) (xy 53.04839 -385.341443) (xy 53.039978 -385.402996) (xy 53.032152 -385.433062)
			(xy 53.029358 -385.442968) (xy 53.031898 -385.463288) (xy 53.074062 -385.536186) (xy 53.079436 -385.544807)
			(xy 53.095579 -385.557117) (xy 53.105304 -385.560062) (xy 53.105558 -385.560062) (xy 53.134669 -385.568058)
			(xy 53.190635 -385.590693) (xy 53.24314 -385.620488) (xy 53.291274 -385.656926) (xy 53.3342 -385.699375)
			(xy 53.371173 -385.747098) (xy 53.401553 -385.799267) (xy 53.424812 -385.854977) (xy 53.440546 -385.913261)
			(xy 53.448483 -385.973107) (xy 53.448966 -386.003292) (xy 53.448841 -386.017427) (xy 53.447059 -386.045641)
			(xy 53.44541 -386.05968) (xy 53.44462 -386.068288) (xy 53.448267 -386.085174) (xy 53.452522 -386.0927)
			(xy 53.46827 -386.1181) (xy 53.472986 -386.125155) (xy 53.486087 -386.135927) (xy 53.493924 -386.139182)
			(xy 53.517304 -386.148368) (xy 53.5612 -386.172788) (xy 53.600895 -386.203569) (xy 53.635476 -386.240002)
			(xy 53.664146 -386.281249) (xy 53.686244 -386.326358) (xy 53.701261 -386.374292) (xy 53.708853 -386.423946)
			(xy 53.709316 -386.449062) (xy 53.709316 -386.449316) (xy 53.708866 -386.473517) (xy 53.7018 -386.521401)
			(xy 53.68782 -386.56774) (xy 53.667228 -386.611543) (xy 53.654198 -386.631942) (xy 53.649472 -386.639855)
			(xy 53.645429 -386.657821) (xy 53.646324 -386.666994) (xy 53.650896 -386.697982) (xy 53.652678 -386.707243)
			(xy 53.661939 -386.723655) (xy 53.66893 -386.729986) (xy 53.691004 -386.748673) (xy 53.730742 -386.790696)
			(xy 53.764868 -386.83739) (xy 53.792839 -386.888013) (xy 53.814208 -386.941757) (xy 53.828635 -386.997764)
			(xy 53.83589 -387.055144) (xy 53.836316 -387.084062) (xy 53.835728 -387.117425) (xy 53.826083 -387.183451)
			(xy 53.80695 -387.247375) (xy 53.79339 -387.277864) (xy 53.789222 -387.28831) (xy 53.789329 -387.310767)
			(xy 53.799023 -387.331024) (xy 53.80736 -387.33857) (xy 53.829582 -387.357273) (xy 53.869648 -387.399322)
			(xy 53.904072 -387.446103) (xy 53.932301 -387.496863) (xy 53.95388 -387.550787) (xy 53.968464 -387.607007)
			(xy 53.975817 -387.664621) (xy 53.97627 -387.693662) (xy 53.975787 -387.722667) (xy 53.968476 -387.780213)
			(xy 53.953955 -387.836376) (xy 53.932455 -387.890253) (xy 53.904322 -387.940984) (xy 53.870006 -387.987754)
			(xy 53.830057 -388.029815) (xy 53.807868 -388.0485) (xy 53.80101 -388.054088) (xy 53.791612 -388.069582)
			(xy 53.777896 -388.143242) (xy 53.776698 -388.152003) (xy 53.779691 -388.169416) (xy 53.783738 -388.177278)
			(xy 53.783738 -388.177532) (xy 53.796313 -388.200719) (xy 53.814187 -388.25034) (xy 53.823288 -388.302291)
			(xy 53.82387 -388.328662) (xy 53.823801 -388.338021) (xy 53.822658 -388.356703) (xy 53.821584 -388.366)
			(xy 53.820568 -388.374636) (xy 53.824378 -388.391908) (xy 53.868066 -388.46125) (xy 53.882036 -388.471918)
			(xy 53.890418 -388.474712) (xy 53.914442 -388.483192) (xy 53.959615 -388.506741) (xy 54.000421 -388.537238)
			(xy 54.035801 -388.573891) (xy 54.064837 -388.615749) (xy 54.086777 -388.661725) (xy 54.09438 -388.68604)
			(xy 54.095904 -388.691882) (xy 54.416198 -389.245602) (xy 54.420262 -389.24992) (xy 54.436428 -389.26758)
			(xy 54.463745 -389.3069) (xy 54.484811 -389.349894) (xy 54.499143 -389.395575) (xy 54.506413 -389.442898)
			(xy 54.506876 -389.466836) (xy 54.506876 -389.467344) (xy 54.506423 -389.492134) (xy 54.49866 -389.541104)
			(xy 54.483334 -389.588257) (xy 54.460821 -389.632432) (xy 54.431675 -389.672541) (xy 54.396614 -389.707598)
			(xy 54.356501 -389.73674) (xy 54.312323 -389.759248) (xy 54.265169 -389.774569) (xy 54.216198 -389.782325)
			(xy 54.191408 -389.782812) (xy 54.166014 -389.782304) (xy 54.115881 -389.774175) (xy 54.067695 -389.758125)
			(xy 54.022701 -389.734568) (xy 53.982058 -389.704111) (xy 53.946815 -389.667541) (xy 53.917881 -389.6258)
			(xy 53.896003 -389.579966) (xy 53.888386 -389.555736) (xy 53.886862 -389.549894) (xy 53.566568 -388.996174)
			(xy 53.562504 -388.991856) (xy 53.546302 -388.974147) (xy 53.518877 -388.934756) (xy 53.497734 -388.891667)
			(xy 53.48336 -388.845873) (xy 53.476086 -388.79843) (xy 53.475636 -388.774432) (xy 53.475778 -388.76238)
			(xy 53.477684 -388.73835) (xy 53.479446 -388.726426) (xy 53.480414 -388.717667) (xy 53.477047 -388.700387)
			(xy 53.472842 -388.692644) (xy 53.440076 -388.637272) (xy 53.435378 -388.629991) (xy 53.422138 -388.618828)
			(xy 53.414168 -388.615428) (xy 53.41366 -388.615428) (xy 53.391942 -388.606996) (xy 53.351136 -388.584519)
			(xy 53.314217 -388.556106) (xy 53.282041 -388.522416) (xy 53.255354 -388.484231) (xy 53.234775 -388.442436)
			(xy 53.220781 -388.398) (xy 53.213697 -388.351955) (xy 53.213254 -388.328662) (xy 53.213826 -388.302289)
			(xy 53.222907 -388.250331) (xy 53.240793 -388.200711) (xy 53.253386 -388.177532) (xy 53.253386 -388.177278)
			(xy 53.257397 -388.169402) (xy 53.260397 -388.152001) (xy 53.259228 -388.143242) (xy 53.245512 -388.069582)
			(xy 53.236114 -388.054088) (xy 53.229256 -388.0485) (xy 53.207076 -388.029805) (xy 53.167131 -387.98774)
			(xy 53.132816 -387.94097) (xy 53.104679 -387.890242) (xy 53.083171 -387.836368) (xy 53.068635 -387.78021)
			(xy 53.061305 -387.722666) (xy 53.060854 -387.693662) (xy 53.060854 -387.693408) (xy 53.061434 -387.660086)
			(xy 53.0711 -387.594147) (xy 53.090231 -387.530309) (xy 53.10378 -387.49986) (xy 53.108031 -387.489441)
			(xy 53.107896 -387.466961) (xy 53.098165 -387.446696) (xy 53.08981 -387.439154) (xy 53.067545 -387.420501)
			(xy 53.027482 -387.378442) (xy 52.993063 -387.331652) (xy 52.96484 -387.280883) (xy 52.943268 -387.226952)
			(xy 52.928692 -387.170725) (xy 52.921348 -387.113105) (xy 52.9209 -387.084062) (xy 52.9209 -387.083808)
			(xy 52.921331 -387.054908) (xy 52.928617 -386.99757) (xy 52.943063 -386.941605) (xy 52.964439 -386.887903)
			(xy 52.992404 -386.837319) (xy 53.026513 -386.790657) (xy 53.066225 -386.748659) (xy 53.088286 -386.729986)
			(xy 53.09536 -386.723724) (xy 53.104629 -386.707277) (xy 53.10632 -386.697982) (xy 53.110892 -386.666994)
			(xy 53.111801 -386.657821) (xy 53.107757 -386.639849) (xy 53.103018 -386.631942) (xy 53.086705 -386.606123)
			(xy 53.062931 -386.549873) (xy 53.055774 -386.520182) (xy 53.053625 -386.511957) (xy 53.044804 -386.49744)
			(xy 53.038502 -386.491734) (xy 53.001164 -386.461) (xy 52.991258 -386.461) (xy 52.961289 -386.460557)
			(xy 52.901865 -386.452729) (xy 52.84397 -386.437211) (xy 52.788596 -386.41427) (xy 52.736691 -386.384297)
			(xy 52.689141 -386.347806) (xy 52.646761 -386.305422) (xy 52.610275 -386.257868) (xy 52.580308 -386.205959)
			(xy 52.557373 -386.150582) (xy 52.541862 -386.092686) (xy 52.53404 -386.033261) (xy 52.53355 -386.003292)
			(xy 52.534071 -385.972229) (xy 52.542487 -385.910675) (xy 52.550314 -385.88061) (xy 52.553108 -385.870704)
			(xy 52.550568 -385.850384) (xy 52.508404 -385.777486) (xy 52.502984 -385.768898) (xy 52.486875 -385.756569)
			(xy 52.477162 -385.75361) (xy 52.476908 -385.75361) (xy 52.447783 -385.745662) (xy 52.391816 -385.723021)
			(xy 52.33931 -385.69322) (xy 52.291177 -385.656776) (xy 52.248252 -385.614322) (xy 52.21128 -385.566593)
			(xy 52.180902 -385.514419) (xy 52.157646 -385.458705) (xy 52.141914 -385.400417) (xy 52.133981 -385.340567)
			(xy 52.1335 -385.31038) (xy 52.1335 -385.309872) (xy 52.134009 -385.279014) (xy 52.142324 -385.21786)
			(xy 52.158788 -385.15838) (xy 52.183099 -385.101653) (xy 52.198524 -385.074922) (xy 52.204366 -385.06527)
			(xy 52.206906 -385.042918) (xy 52.177188 -384.958336) (xy 52.172921 -384.947985) (xy 52.157241 -384.932041)
			(xy 52.146962 -384.927602) (xy 52.123606 -384.918392) (xy 52.079763 -384.893934) (xy 52.040119 -384.863132)
			(xy 52.005585 -384.826693) (xy 51.976954 -384.785453) (xy 51.954884 -384.740361) (xy 51.939882 -384.692451)
			(xy 51.932292 -384.642824) (xy 51.931824 -384.617722) (xy 51.39309 -384.617722) (xy 51.39309 -384.61823)
			(xy 51.392527 -384.645204) (xy 51.383719 -384.69843) (xy 51.375564 -384.724148) (xy 51.371754 -384.73507)
			(xy 51.374294 -384.757422) (xy 51.42103 -384.833876) (xy 51.427345 -384.843059) (xy 51.445915 -384.855324)
			(xy 51.456844 -384.857498) (xy 51.457098 -384.857498) (xy 51.486412 -384.862231) (xy 51.543582 -384.878276)
			(xy 51.598196 -384.901582) (xy 51.649336 -384.931757) (xy 51.696142 -384.968296) (xy 51.737828 -385.010582)
			(xy 51.773693 -385.057906) (xy 51.803134 -385.109473) (xy 51.825656 -385.164415) (xy 51.840881 -385.221809)
			(xy 51.848553 -385.28069) (xy 51.84902 -385.31038) (xy 51.848494 -385.341443) (xy 51.840082 -385.402996)
			(xy 51.832256 -385.433062) (xy 51.829462 -385.442968) (xy 51.832002 -385.463288) (xy 51.874166 -385.536186)
			(xy 51.879539 -385.544808) (xy 51.895683 -385.557118) (xy 51.905408 -385.560062) (xy 51.905662 -385.560062)
			(xy 51.934773 -385.568055) (xy 51.99074 -385.59069) (xy 52.043245 -385.620486) (xy 52.091378 -385.656924)
			(xy 52.134304 -385.699374) (xy 52.171278 -385.747097) (xy 52.201657 -385.799267) (xy 52.224916 -385.854977)
			(xy 52.24065 -385.91326) (xy 52.248587 -385.973107) (xy 52.24907 -386.003292) (xy 52.248944 -386.017427)
			(xy 52.247163 -386.045641) (xy 52.245514 -386.05968) (xy 52.244723 -386.068288) (xy 52.248371 -386.085175)
			(xy 52.252626 -386.0927) (xy 52.268628 -386.1181) (xy 52.273304 -386.125115) (xy 52.286275 -386.135869)
			(xy 52.294028 -386.139182) (xy 52.317376 -386.148411) (xy 52.361219 -386.172866) (xy 52.400863 -386.203665)
			(xy 52.435398 -386.240102) (xy 52.46403 -386.281339) (xy 52.486101 -386.326429) (xy 52.501105 -386.374336)
			(xy 52.508697 -386.423961) (xy 52.509166 -386.449062) (xy 52.509166 -386.449316) (xy 52.508724 -386.473517)
			(xy 52.501657 -386.521402) (xy 52.487675 -386.567742) (xy 52.467079 -386.611544) (xy 52.454048 -386.631942)
			(xy 52.449319 -386.639853) (xy 52.445279 -386.657821) (xy 52.446174 -386.666994) (xy 52.450746 -386.697982)
			(xy 52.452542 -386.707239) (xy 52.461794 -386.723652) (xy 52.46878 -386.729986) (xy 52.490843 -386.748685)
			(xy 52.530584 -386.790704) (xy 52.564713 -386.837396) (xy 52.592686 -386.888017) (xy 52.614056 -386.941759)
			(xy 52.628484 -386.997766) (xy 52.63574 -387.055144) (xy 52.636166 -387.084062) (xy 52.635573 -387.117425)
			(xy 52.62593 -387.18345) (xy 52.606799 -387.247375) (xy 52.59324 -387.277864) (xy 52.589055 -387.288306)
			(xy 52.589162 -387.310769) (xy 52.598867 -387.331027) (xy 52.60721 -387.33857) (xy 52.629442 -387.35726)
			(xy 52.669506 -387.399313) (xy 52.703928 -387.446097) (xy 52.732154 -387.496859) (xy 52.753732 -387.550784)
			(xy 52.768315 -387.607006) (xy 52.775667 -387.664621) (xy 52.77612 -387.693662) (xy 52.775655 -387.722667)
			(xy 52.768343 -387.780216) (xy 52.75382 -387.836379) (xy 52.732318 -387.890257) (xy 52.704182 -387.940988)
			(xy 52.669862 -387.987757) (xy 52.629909 -388.029816) (xy 52.607718 -388.0485) (xy 52.60086 -388.054088)
			(xy 52.591462 -388.069582) (xy 52.577746 -388.143242) (xy 52.576555 -388.152003) (xy 52.579545 -388.169415)
			(xy 52.583588 -388.177278) (xy 52.583588 -388.177532) (xy 52.596159 -388.200721) (xy 52.614036 -388.250341)
			(xy 52.623138 -388.302292) (xy 52.62372 -388.328662) (xy 52.623651 -388.338021) (xy 52.622508 -388.356703)
			(xy 52.621434 -388.366) (xy 52.620418 -388.374636) (xy 52.624228 -388.391908) (xy 52.667916 -388.46125)
			(xy 52.681886 -388.471918) (xy 52.690268 -388.474712) (xy 52.714282 -388.483218) (xy 52.759456 -388.506761)
			(xy 52.800264 -388.537252) (xy 52.835646 -388.5739) (xy 52.864684 -388.615753) (xy 52.886626 -388.661726)
			(xy 52.89423 -388.68604) (xy 52.895754 -388.691882) (xy 53.216048 -389.245602) (xy 53.220112 -389.24992)
			(xy 53.236306 -389.267637) (xy 53.263731 -389.307025) (xy 53.284875 -389.350113) (xy 53.299252 -389.395905)
			(xy 53.306528 -389.443346) (xy 53.30698 -389.467344) (xy 53.306524 -389.492122) (xy 53.29877 -389.541066)
			(xy 53.283459 -389.588197) (xy 53.260968 -389.632355) (xy 53.23185 -389.672453) (xy 53.196822 -389.707506)
			(xy 53.156744 -389.736652) (xy 53.112602 -389.759174) (xy 53.065483 -389.774518) (xy 53.016543 -389.782306)
			(xy 52.991766 -389.782812) (xy 52.991258 -389.782812) (xy 52.965862 -389.782348) (xy 52.915727 -389.774211)
			(xy 52.867541 -389.758154) (xy 52.822546 -389.73459) (xy 52.781904 -389.704127) (xy 52.746662 -389.667552)
			(xy 52.717729 -389.625806) (xy 52.695852 -389.579968) (xy 52.688236 -389.555736) (xy 52.686712 -389.549894)
			(xy 52.366418 -388.996174) (xy 52.362354 -388.991856) (xy 52.346195 -388.974122) (xy 52.318826 -388.93472)
			(xy 52.297736 -388.89163) (xy 52.283408 -388.845845) (xy 52.276174 -388.798419) (xy 52.27574 -388.774432)
			(xy 52.275821 -388.762384) (xy 52.277603 -388.738355) (xy 52.279296 -388.726426) (xy 52.280258 -388.717667)
			(xy 52.276894 -388.700387) (xy 52.272692 -388.692644) (xy 52.239926 -388.637272) (xy 52.235212 -388.630003)
			(xy 52.221983 -388.618834) (xy 52.214018 -388.615428) (xy 52.21351 -388.615428) (xy 52.191803 -388.606969)
			(xy 52.150996 -388.584498) (xy 52.114075 -388.55609) (xy 52.081896 -388.522405) (xy 52.055207 -388.484223)
			(xy 52.034627 -388.442431) (xy 52.020632 -388.397997) (xy 52.013547 -388.351954) (xy 52.013104 -388.328662)
			(xy 52.013669 -388.302289) (xy 52.022752 -388.25033) (xy 52.040641 -388.20071) (xy 52.053236 -388.177532)
			(xy 52.053236 -388.177278) (xy 52.057249 -388.169404) (xy 52.060246 -388.152001) (xy 52.059078 -388.143242)
			(xy 52.045362 -388.069582) (xy 52.035964 -388.054088) (xy 52.029106 -388.0485) (xy 52.006937 -388.029792)
			(xy 51.966989 -387.987731) (xy 51.932671 -387.940964) (xy 51.904532 -387.890238) (xy 51.883022 -387.836366)
			(xy 51.868486 -387.780209) (xy 51.861155 -387.722666) (xy 51.860704 -387.693662) (xy 51.860704 -387.693408)
			(xy 51.861288 -387.660086) (xy 51.870954 -387.594148) (xy 51.890082 -387.530309) (xy 51.90363 -387.49986)
			(xy 51.907897 -387.489445) (xy 51.907763 -387.466959) (xy 51.898022 -387.446693) (xy 51.88966 -387.439154)
			(xy 51.867405 -387.420489) (xy 51.82734 -387.378433) (xy 51.792919 -387.331646) (xy 51.764694 -387.28088)
			(xy 51.74312 -387.22695) (xy 51.728543 -387.170723) (xy 51.721198 -387.113105) (xy 51.72075 -387.084062)
			(xy 51.72075 -387.083808) (xy 51.721199 -387.054909) (xy 51.728485 -386.997572) (xy 51.742929 -386.941608)
			(xy 51.764302 -386.887907) (xy 51.792263 -386.837322) (xy 51.826369 -386.79066) (xy 51.866077 -386.74866)
			(xy 51.888136 -386.729986) (xy 51.895218 -386.723732) (xy 51.904481 -386.707279) (xy 51.90617 -386.697982)
			(xy 51.910742 -386.666994) (xy 51.911658 -386.657821) (xy 51.907611 -386.639848) (xy 51.902868 -386.631942)
			(xy 51.88656 -386.60612) (xy 51.862783 -386.549872) (xy 51.855624 -386.520182) (xy 51.853489 -386.511953)
			(xy 51.844659 -386.497436) (xy 51.838352 -386.491734) (xy 51.801014 -386.461) (xy 51.791362 -386.461)
			(xy 51.761393 -386.460553) (xy 51.701969 -386.452725) (xy 51.644074 -386.437208) (xy 51.588701 -386.414267)
			(xy 51.536795 -386.384295) (xy 51.489245 -386.347805) (xy 51.446865 -386.30542) (xy 51.410379 -386.257867)
			(xy 51.380412 -386.205958) (xy 51.357477 -386.150582) (xy 51.341966 -386.092686) (xy 51.334144 -386.033261)
			(xy 51.333654 -386.003292) (xy 51.334175 -385.972229) (xy 51.342591 -385.910675) (xy 51.350418 -385.88061)
			(xy 51.353212 -385.870704) (xy 51.350672 -385.850384) (xy 51.308508 -385.777486) (xy 51.303086 -385.7689)
			(xy 51.286978 -385.75657) (xy 51.277266 -385.75361) (xy 51.277012 -385.75361) (xy 51.247888 -385.74566)
			(xy 51.191921 -385.723019) (xy 51.139415 -385.693219) (xy 51.091282 -385.656775) (xy 51.048356 -385.614321)
			(xy 51.011384 -385.566593) (xy 50.981006 -385.514419) (xy 50.95775 -385.458704) (xy 50.942019 -385.400417)
			(xy 50.934085 -385.340567) (xy 50.933604 -385.31038) (xy 50.934129 -385.279492) (xy 50.942434 -385.218277)
			(xy 50.958891 -385.158733) (xy 50.983201 -385.101941) (xy 50.998628 -385.075176) (xy 51.00401 -385.065255)
			(xy 51.006367 -385.042832) (xy 51.0032 -385.031996) (xy 50.977292 -384.958336) (xy 50.973023 -384.947986)
			(xy 50.957344 -384.932041) (xy 50.947066 -384.927602) (xy 50.923678 -384.918434) (xy 50.879782 -384.894012)
			(xy 50.840086 -384.863228) (xy 50.805506 -384.826792) (xy 50.776838 -384.785543) (xy 50.754741 -384.740431)
			(xy 50.739725 -384.692495) (xy 50.732136 -384.642839) (xy 50.731674 -384.617722) (xy 50.193194 -384.617722)
			(xy 50.193194 -384.61823) (xy 50.192631 -384.645204) (xy 50.183823 -384.69843) (xy 50.175668 -384.724148)
			(xy 50.171858 -384.73507) (xy 50.174398 -384.757422) (xy 50.221134 -384.833876) (xy 50.227447 -384.84306)
			(xy 50.246019 -384.855325) (xy 50.256948 -384.857498) (xy 50.257202 -384.857498) (xy 50.286516 -384.862228)
			(xy 50.343687 -384.878273) (xy 50.398301 -384.901579) (xy 50.449441 -384.931756) (xy 50.496247 -384.968294)
			(xy 50.537933 -385.010581) (xy 50.573797 -385.057906) (xy 50.603238 -385.109472) (xy 50.62576 -385.164415)
			(xy 50.640985 -385.221809) (xy 50.648657 -385.28069) (xy 50.649124 -385.31038) (xy 50.649124 -385.310888)
			(xy 50.648576 -385.341887) (xy 50.64017 -385.403312) (xy 50.63236 -385.433316) (xy 50.629566 -385.443222)
			(xy 50.632106 -385.463542) (xy 50.674016 -385.536186) (xy 50.679499 -385.544795) (xy 50.695739 -385.557122)
			(xy 50.705512 -385.560062) (xy 50.734614 -385.568089) (xy 50.790581 -385.590718) (xy 50.843087 -385.620508)
			(xy 50.891221 -385.656942) (xy 50.934148 -385.699387) (xy 50.971124 -385.747107) (xy 51.001505 -385.799274)
			(xy 51.024765 -385.854981) (xy 51.040499 -385.913263) (xy 51.048436 -385.973108) (xy 51.04892 -386.003292)
			(xy 51.048795 -386.017427) (xy 51.047013 -386.045641) (xy 51.045364 -386.05968) (xy 51.04458 -386.068288)
			(xy 51.048224 -386.085174) (xy 51.052476 -386.0927) (xy 51.068224 -386.1181) (xy 51.072923 -386.125168)
			(xy 51.086036 -386.135933) (xy 51.093878 -386.139182) (xy 51.117248 -386.148393) (xy 51.161145 -386.172807)
			(xy 51.200843 -386.203583) (xy 51.235425 -386.240013) (xy 51.264096 -386.281256) (xy 51.286196 -386.326362)
			(xy 51.301215 -386.374294) (xy 51.308807 -386.423947) (xy 51.30927 -386.449062) (xy 51.30927 -386.449316)
			(xy 51.308828 -386.473517) (xy 51.30176 -386.521402) (xy 51.287779 -386.567741) (xy 51.267183 -386.611544)
			(xy 51.254152 -386.631942) (xy 51.249423 -386.639853) (xy 51.245383 -386.657821) (xy 51.246278 -386.666994)
			(xy 51.25085 -386.697982) (xy 51.252645 -386.707239) (xy 51.261898 -386.723652) (xy 51.268884 -386.729986)
			(xy 51.290948 -386.748684) (xy 51.330689 -386.790703) (xy 51.364817 -386.837396) (xy 51.39279 -386.888017)
			(xy 51.414161 -386.941759) (xy 51.428589 -386.997766) (xy 51.435844 -387.055144) (xy 51.43627 -387.084062)
			(xy 51.435686 -387.117426) (xy 51.426041 -387.183451) (xy 51.406906 -387.247375) (xy 51.393344 -387.277864)
			(xy 51.389158 -387.288306) (xy 51.389265 -387.310769) (xy 51.39897 -387.331028) (xy 51.407314 -387.33857)
			(xy 51.429547 -387.357259) (xy 51.469611 -387.399313) (xy 51.504032 -387.446096) (xy 51.532259 -387.496859)
			(xy 51.553836 -387.550784) (xy 51.568419 -387.607006) (xy 51.575771 -387.664621) (xy 51.576224 -387.693662)
			(xy 51.575757 -387.722667) (xy 51.568446 -387.780215) (xy 51.553923 -387.836379) (xy 51.532421 -387.890257)
			(xy 51.504285 -387.940988) (xy 51.469966 -387.987757) (xy 51.430012 -388.029816) (xy 51.407822 -388.0485)
			(xy 51.400964 -388.054088) (xy 51.391566 -388.069582) (xy 51.37785 -388.143242) (xy 51.376658 -388.152003)
			(xy 51.379648 -388.169415) (xy 51.383692 -388.177278) (xy 51.383692 -388.177532) (xy 51.396263 -388.200721)
			(xy 51.41414 -388.250341) (xy 51.423242 -388.302292) (xy 51.423824 -388.328662) (xy 51.423755 -388.338021)
			(xy 51.422612 -388.356703) (xy 51.421538 -388.366) (xy 51.420522 -388.374636) (xy 51.424332 -388.391908)
			(xy 51.46802 -388.46125) (xy 51.48199 -388.471918) (xy 51.490372 -388.474712) (xy 51.514387 -388.483216)
			(xy 51.559561 -388.50676) (xy 51.600368 -388.537251) (xy 51.63575 -388.573899) (xy 51.664789 -388.615753)
			(xy 51.68673 -388.661726) (xy 51.694334 -388.68604) (xy 51.695858 -388.691882) (xy 52.016152 -389.245602)
			(xy 52.020216 -389.24992) (xy 52.03641 -389.267636) (xy 52.063835 -389.307025) (xy 52.08498 -389.350113)
			(xy 52.099356 -389.395905) (xy 52.106632 -389.443346) (xy 52.107084 -389.467344) (xy 52.106624 -389.492121)
			(xy 52.09887 -389.541066) (xy 52.083559 -389.588196) (xy 52.061069 -389.632353) (xy 52.031952 -389.672452)
			(xy 51.996924 -389.707505) (xy 51.956846 -389.736651) (xy 51.912705 -389.759173) (xy 51.865586 -389.774517)
			(xy 51.816647 -389.782306) (xy 51.79187 -389.782812) (xy 51.791362 -389.782812) (xy 51.765966 -389.782345)
			(xy 51.715831 -389.774208) (xy 51.667645 -389.758151) (xy 51.622651 -389.734588) (xy 51.582008 -389.704126)
			(xy 51.546766 -389.667551) (xy 51.517833 -389.625806) (xy 51.495956 -389.579968) (xy 51.48834 -389.555736)
			(xy 51.486816 -389.549894) (xy 51.166522 -388.996174) (xy 51.162458 -388.991856) (xy 51.146299 -388.974121)
			(xy 51.118931 -388.93472) (xy 51.09784 -388.89163) (xy 51.083512 -388.845845) (xy 51.076278 -388.798419)
			(xy 51.075844 -388.774432) (xy 51.075925 -388.762384) (xy 51.077707 -388.738355) (xy 51.0794 -388.726426)
			(xy 51.080374 -388.717668) (xy 51.077004 -388.700386) (xy 51.072796 -388.692644) (xy 51.04003 -388.637272)
			(xy 51.035315 -388.630004) (xy 51.022087 -388.618834) (xy 51.014122 -388.615428) (xy 51.013614 -388.615428)
			(xy 50.991907 -388.606967) (xy 50.9511 -388.584496) (xy 50.914179 -388.556089) (xy 50.882001 -388.522404)
			(xy 50.855312 -388.484222) (xy 50.834731 -388.44243) (xy 50.820736 -388.397997) (xy 50.813651 -388.351954)
			(xy 50.813208 -388.328662) (xy 50.813773 -388.302289) (xy 50.822856 -388.25033) (xy 50.840745 -388.20071)
			(xy 50.85334 -388.177532) (xy 50.85334 -388.177278) (xy 50.857353 -388.169404) (xy 50.86035 -388.152001)
			(xy 50.859182 -388.143242) (xy 50.845466 -388.069582) (xy 50.836068 -388.054088) (xy 50.82921 -388.0485)
			(xy 50.807041 -388.029791) (xy 50.767094 -387.987731) (xy 50.732776 -387.940963) (xy 50.704637 -387.890238)
			(xy 50.683127 -387.836365) (xy 50.66859 -387.780209) (xy 50.661259 -387.722666) (xy 50.660808 -387.693662)
			(xy 50.660808 -387.693408) (xy 50.661392 -387.660086) (xy 50.671058 -387.594148) (xy 50.690186 -387.530309)
			(xy 50.703734 -387.49986) (xy 50.708 -387.489444) (xy 50.707866 -387.466959) (xy 50.698126 -387.446693)
			(xy 50.689764 -387.439154) (xy 50.667489 -387.420512) (xy 50.627429 -387.37845) (xy 50.593012 -387.331658)
			(xy 50.564791 -387.280887) (xy 50.54322 -387.226954) (xy 50.528646 -387.170726) (xy 50.521302 -387.113105)
			(xy 50.520854 -387.084062) (xy 50.520854 -387.083808) (xy 50.521301 -387.054909) (xy 50.528587 -386.997572)
			(xy 50.543032 -386.941608) (xy 50.564405 -386.887906) (xy 50.592367 -386.837322) (xy 50.626473 -386.790659)
			(xy 50.66618 -386.74866) (xy 50.68824 -386.729986) (xy 50.695323 -386.723733) (xy 50.704585 -386.707279)
			(xy 50.706274 -386.697982) (xy 50.710846 -386.666994) (xy 50.711762 -386.657821) (xy 50.707715 -386.639848)
			(xy 50.702972 -386.631942) (xy 50.686664 -386.60612) (xy 50.662887 -386.549872) (xy 50.655728 -386.520182)
			(xy 50.653592 -386.511953) (xy 50.644763 -386.497437) (xy 50.638456 -386.491734) (xy 50.601118 -386.461)
			(xy 50.591212 -386.461) (xy 50.561243 -386.460528) (xy 50.501817 -386.452706) (xy 50.443921 -386.437193)
			(xy 50.388545 -386.414257) (xy 50.336637 -386.384289) (xy 50.289085 -386.347801) (xy 50.246702 -386.305418)
			(xy 50.210214 -386.257866) (xy 50.180245 -386.205958) (xy 50.157308 -386.150583) (xy 50.141795 -386.092687)
			(xy 50.133973 -386.033261) (xy 50.133504 -386.003292) (xy 50.134023 -385.972229) (xy 50.14244 -385.910675)
			(xy 50.150268 -385.88061) (xy 50.153062 -385.870704) (xy 50.150522 -385.850384) (xy 50.108104 -385.777232)
			(xy 50.102662 -385.768713) (xy 50.086538 -385.756542) (xy 50.076862 -385.75361) (xy 50.047779 -385.745559)
			(xy 49.991852 -385.722896) (xy 49.939386 -385.693083) (xy 49.891291 -385.656637) (xy 49.8484 -385.614189)
			(xy 49.811456 -385.566475) (xy 49.7811 -385.514321) (xy 49.757858 -385.458632) (xy 49.742132 -385.400373)
			(xy 49.734195 -385.340552) (xy 49.733708 -385.31038) (xy 49.734233 -385.279492) (xy 49.742538 -385.218276)
			(xy 49.758995 -385.158733) (xy 49.783305 -385.101941) (xy 49.798732 -385.075176) (xy 49.804115 -385.065255)
			(xy 49.806471 -385.042832) (xy 49.803304 -385.031996) (xy 49.777396 -384.958336) (xy 49.773169 -384.947964)
			(xy 49.757461 -384.932028) (xy 49.74717 -384.927602) (xy 49.723783 -384.918432) (xy 49.679887 -384.89401)
			(xy 49.640191 -384.863227) (xy 49.605611 -384.826791) (xy 49.576942 -384.785543) (xy 49.554845 -384.740431)
			(xy 49.539829 -384.692495) (xy 49.53224 -384.642839) (xy 49.531778 -384.617722) (xy 48.993044 -384.617722)
			(xy 48.993044 -384.61823) (xy 48.992478 -384.645204) (xy 48.983672 -384.69843) (xy 48.975518 -384.724148)
			(xy 48.971708 -384.73507) (xy 48.974248 -384.757422) (xy 49.020984 -384.833876) (xy 49.027274 -384.843078)
			(xy 49.045863 -384.855334) (xy 49.056798 -384.857498) (xy 49.057052 -384.857498) (xy 49.086373 -384.862189)
			(xy 49.143544 -384.87824) (xy 49.198157 -384.901552) (xy 49.249297 -384.931733) (xy 49.296102 -384.968276)
			(xy 49.337787 -385.010567) (xy 49.37365 -385.057895) (xy 49.40309 -385.109465) (xy 49.425611 -385.164409)
			(xy 49.440836 -385.221806) (xy 49.448507 -385.280689) (xy 49.448974 -385.31038) (xy 49.448447 -385.341443)
			(xy 49.440035 -385.402996) (xy 49.43221 -385.433062) (xy 49.429416 -385.442968) (xy 49.431956 -385.463288)
			(xy 49.47412 -385.536186) (xy 49.479511 -385.544794) (xy 49.495642 -385.557111) (xy 49.505362 -385.560062)
			(xy 49.505616 -385.560062) (xy 49.534719 -385.568086) (xy 49.590685 -385.590716) (xy 49.643191 -385.620506)
			(xy 49.691326 -385.656941) (xy 49.734253 -385.699386) (xy 49.771228 -385.747107) (xy 49.801609 -385.799273)
			(xy 49.824869 -385.854981) (xy 49.840603 -385.913263) (xy 49.84854 -385.973108) (xy 49.849024 -386.003292)
			(xy 49.848899 -386.017427) (xy 49.847117 -386.045641) (xy 49.845468 -386.05968) (xy 49.844683 -386.068288)
			(xy 49.848328 -386.085174) (xy 49.85258 -386.0927) (xy 49.868328 -386.1181) (xy 49.873026 -386.125169)
			(xy 49.88614 -386.135933) (xy 49.893982 -386.139182) (xy 49.917353 -386.148391) (xy 49.96125 -386.172806)
			(xy 50.000947 -386.203582) (xy 50.03553 -386.240012) (xy 50.064201 -386.281255) (xy 50.0863 -386.326362)
			(xy 50.101319 -386.374294) (xy 50.108911 -386.423947) (xy 50.109374 -386.449062) (xy 50.109374 -386.449316)
			(xy 50.108931 -386.473517) (xy 50.101864 -386.521402) (xy 50.087882 -386.567741) (xy 50.067287 -386.611544)
			(xy 50.054256 -386.631942) (xy 50.049527 -386.639853) (xy 50.045487 -386.657821) (xy 50.046382 -386.666994)
			(xy 50.050954 -386.697982) (xy 50.052748 -386.70724) (xy 50.062001 -386.723653) (xy 50.068988 -386.729986)
			(xy 50.091053 -386.748683) (xy 50.130793 -386.790703) (xy 50.164922 -386.837395) (xy 50.192894 -386.888016)
			(xy 50.214265 -386.941759) (xy 50.228693 -386.997765) (xy 50.235948 -387.055144) (xy 50.236374 -387.084062)
			(xy 50.235789 -387.117426) (xy 50.226144 -387.183451) (xy 50.207009 -387.247375) (xy 50.193448 -387.277864)
			(xy 50.189261 -387.288305) (xy 50.189367 -387.310769) (xy 50.199074 -387.331028) (xy 50.207418 -387.33857)
			(xy 50.229652 -387.357258) (xy 50.269715 -387.399312) (xy 50.304137 -387.446096) (xy 50.332363 -387.496858)
			(xy 50.35394 -387.550784) (xy 50.368523 -387.607006) (xy 50.375875 -387.664621) (xy 50.376328 -387.693662)
			(xy 50.37586 -387.722667) (xy 50.368549 -387.780215) (xy 50.354026 -387.836378) (xy 50.332524 -387.890257)
			(xy 50.304388 -387.940987) (xy 50.270069 -387.987757) (xy 50.230116 -388.029816) (xy 50.207926 -388.0485)
			(xy 50.201068 -388.054088) (xy 50.19167 -388.069582) (xy 50.177954 -388.143242) (xy 50.176762 -388.152003)
			(xy 50.179752 -388.169415) (xy 50.183796 -388.177278) (xy 50.183796 -388.177532) (xy 50.196368 -388.200721)
			(xy 50.214244 -388.250341) (xy 50.223346 -388.302292) (xy 50.223928 -388.328662) (xy 50.223859 -388.338021)
			(xy 50.222716 -388.356703) (xy 50.221642 -388.366) (xy 50.220626 -388.374636) (xy 50.224436 -388.391908)
			(xy 50.268124 -388.46125) (xy 50.282094 -388.471918) (xy 50.290476 -388.474712) (xy 50.314569 -388.483205)
			(xy 50.35986 -388.506827) (xy 50.400756 -388.537435) (xy 50.436189 -388.57423) (xy 50.465233 -388.616251)
			(xy 50.48713 -388.662401) (xy 50.494692 -388.686802) (xy 50.496216 -388.692644) (xy 50.816002 -389.245602)
			(xy 50.820066 -389.24992) (xy 50.836233 -389.26758) (xy 50.86355 -389.3069) (xy 50.884615 -389.349893)
			(xy 50.898947 -389.395575) (xy 50.906217 -389.442898) (xy 50.90668 -389.466836) (xy 50.90668 -389.467344)
			(xy 50.906223 -389.492134) (xy 50.898461 -389.541103) (xy 50.883134 -389.588256) (xy 50.860622 -389.63243)
			(xy 50.831476 -389.67254) (xy 50.796416 -389.707597) (xy 50.756303 -389.736738) (xy 50.712126 -389.759247)
			(xy 50.664972 -389.774568) (xy 50.616002 -389.782325) (xy 50.591212 -389.782812) (xy 50.565818 -389.782301)
			(xy 50.515685 -389.774172) (xy 50.4675 -389.758123) (xy 50.422505 -389.734566) (xy 50.381862 -389.70411)
			(xy 50.346619 -389.66754) (xy 50.317685 -389.6258) (xy 50.295807 -389.579966) (xy 50.28819 -389.555736)
			(xy 50.286666 -389.549894) (xy 49.966118 -388.995412) (xy 49.962054 -388.991094) (xy 49.945955 -388.973433)
			(xy 49.918767 -388.934134) (xy 49.897815 -388.891185) (xy 49.883578 -388.845568) (xy 49.876383 -388.798326)
			(xy 49.875948 -388.774432) (xy 49.876029 -388.762384) (xy 49.877811 -388.738355) (xy 49.879504 -388.726426)
			(xy 49.880478 -388.717668) (xy 49.877108 -388.700386) (xy 49.8729 -388.692644) (xy 49.840134 -388.637272)
			(xy 49.835417 -388.630005) (xy 49.822191 -388.618835) (xy 49.814226 -388.615428) (xy 49.813718 -388.615428)
			(xy 49.792012 -388.606965) (xy 49.751205 -388.584495) (xy 49.714284 -388.556088) (xy 49.682105 -388.522403)
			(xy 49.655416 -388.484222) (xy 49.634835 -388.44243) (xy 49.62084 -388.397997) (xy 49.613755 -388.351954)
			(xy 49.613312 -388.328662) (xy 49.613876 -388.302289) (xy 49.62296 -388.25033) (xy 49.640849 -388.20071)
			(xy 49.653444 -388.177532) (xy 49.653444 -388.177278) (xy 49.657457 -388.169404) (xy 49.660454 -388.152001)
			(xy 49.659286 -388.143242) (xy 49.64557 -388.069582) (xy 49.636172 -388.054088) (xy 49.629314 -388.0485)
			(xy 49.607146 -388.029791) (xy 49.567198 -387.98773) (xy 49.53288 -387.940963) (xy 49.504741 -387.890237)
			(xy 49.483231 -387.836365) (xy 49.468694 -387.780209) (xy 49.461363 -387.722666) (xy 49.460912 -387.693662)
			(xy 49.460912 -387.693408) (xy 49.461496 -387.660086) (xy 49.471161 -387.594148) (xy 49.49029 -387.530309)
			(xy 49.503838 -387.49986) (xy 49.508102 -387.489444) (xy 49.507968 -387.46696) (xy 49.498229 -387.446693)
			(xy 49.489868 -387.439154) (xy 49.467594 -387.420511) (xy 49.427534 -387.378449) (xy 49.393117 -387.331657)
			(xy 49.364896 -387.280887) (xy 49.343324 -387.226954) (xy 49.32875 -387.170726) (xy 49.321406 -387.113105)
			(xy 49.320958 -387.084062) (xy 49.320958 -387.083808) (xy 49.321404 -387.054909) (xy 49.32869 -386.997572)
			(xy 49.343134 -386.941607) (xy 49.364508 -386.887906) (xy 49.39247 -386.837322) (xy 49.426576 -386.790659)
			(xy 49.466284 -386.74866) (xy 49.488344 -386.729986) (xy 49.495428 -386.723734) (xy 49.50469 -386.707279)
			(xy 49.506378 -386.697982) (xy 49.51095 -386.666994) (xy 49.511865 -386.657821) (xy 49.507818 -386.639848)
			(xy 49.503076 -386.631942) (xy 49.48676 -386.606125) (xy 49.462988 -386.549873) (xy 49.455832 -386.520182)
			(xy 49.453695 -386.511954) (xy 49.444866 -386.497437) (xy 49.43856 -386.491734) (xy 49.401222 -386.461)
			(xy 49.391316 -386.461) (xy 49.361347 -386.460524) (xy 49.301922 -386.452702) (xy 49.244026 -386.437191)
			(xy 49.18865 -386.414255) (xy 49.136741 -386.384287) (xy 49.089189 -386.347799) (xy 49.046806 -386.305417)
			(xy 49.010318 -386.257865) (xy 48.980349 -386.205958) (xy 48.957412 -386.150582) (xy 48.941899 -386.092686)
			(xy 48.934077 -386.033261) (xy 48.933608 -386.003292) (xy 48.93413 -385.972229) (xy 48.942545 -385.910675)
			(xy 48.950372 -385.88061) (xy 48.953166 -385.870704) (xy 48.950626 -385.850384) (xy 48.908462 -385.777486)
			(xy 48.903059 -385.768886) (xy 48.886938 -385.756563) (xy 48.87722 -385.75361) (xy 48.876966 -385.75361)
			(xy 48.847852 -385.745624) (xy 48.791884 -385.72299) (xy 48.739378 -385.693195) (xy 48.691243 -385.656756)
			(xy 48.648316 -385.614306) (xy 48.611342 -385.566582) (xy 48.580963 -385.514411) (xy 48.557706 -385.458699)
			(xy 48.541974 -385.400414) (xy 48.53404 -385.340566) (xy 48.533558 -385.31038) (xy 48.534076 -385.279492)
			(xy 48.542382 -385.218276) (xy 48.558841 -385.158732) (xy 48.583154 -385.10194) (xy 48.598582 -385.075176)
			(xy 48.603965 -385.065255) (xy 48.606319 -385.042832) (xy 48.603154 -385.031996) (xy 48.577246 -384.958336)
			(xy 48.572998 -384.947975) (xy 48.557305 -384.932035) (xy 48.54702 -384.927602) (xy 48.523644 -384.918405)
			(xy 48.479746 -384.893989) (xy 48.440049 -384.863211) (xy 48.405466 -384.82678) (xy 48.376796 -384.785535)
			(xy 48.354697 -384.740426) (xy 48.33968 -384.692492) (xy 48.33209 -384.642838) (xy 48.331628 -384.617722)
			(xy 47.793148 -384.617722) (xy 47.793148 -384.61823) (xy 47.792582 -384.645204) (xy 47.783775 -384.69843)
			(xy 47.775622 -384.724148) (xy 47.771812 -384.73507) (xy 47.774352 -384.757422) (xy 47.821088 -384.833876)
			(xy 47.827377 -384.84308) (xy 47.845966 -384.855334) (xy 47.856902 -384.857498) (xy 47.857156 -384.857498)
			(xy 47.886477 -384.862186) (xy 47.943648 -384.878237) (xy 47.998262 -384.90155) (xy 48.049401 -384.931731)
			(xy 48.096206 -384.968275) (xy 48.137891 -385.010566) (xy 48.173754 -385.057894) (xy 48.203194 -385.109464)
			(xy 48.225715 -385.164409) (xy 48.24094 -385.221805) (xy 48.248611 -385.280689) (xy 48.249078 -385.31038)
			(xy 48.248551 -385.341443) (xy 48.240139 -385.402996) (xy 48.232314 -385.433062) (xy 48.22952 -385.442968)
			(xy 48.23206 -385.463288) (xy 48.274224 -385.536186) (xy 48.279614 -385.544796) (xy 48.295746 -385.557111)
			(xy 48.305466 -385.560062) (xy 48.30572 -385.560062) (xy 48.334823 -385.568083) (xy 48.39079 -385.590714)
			(xy 48.443296 -385.620505) (xy 48.49143 -385.656939) (xy 48.534357 -385.699385) (xy 48.571332 -385.747106)
			(xy 48.601713 -385.799273) (xy 48.624973 -385.854981) (xy 48.640707 -385.913263) (xy 48.648644 -385.973108)
			(xy 48.649128 -386.003292) (xy 48.649003 -386.017427) (xy 48.647221 -386.045641) (xy 48.645572 -386.05968)
			(xy 48.644787 -386.068288) (xy 48.648432 -386.085174) (xy 48.652684 -386.0927) (xy 48.668686 -386.1181)
			(xy 48.673375 -386.125105) (xy 48.686337 -386.135864) (xy 48.694086 -386.139182) (xy 48.717425 -386.148434)
			(xy 48.761269 -386.172883) (xy 48.800915 -386.203678) (xy 48.835451 -386.240111) (xy 48.864085 -386.281345)
			(xy 48.886157 -386.326433) (xy 48.901163 -386.374338) (xy 48.908755 -386.423962) (xy 48.909224 -386.449062)
			(xy 48.909224 -386.449316) (xy 48.908773 -386.473517) (xy 48.901706 -386.521401) (xy 48.887728 -386.56774)
			(xy 48.867135 -386.611543) (xy 48.854106 -386.631942) (xy 48.849381 -386.639855) (xy 48.845337 -386.657821)
			(xy 48.846232 -386.666994) (xy 48.850804 -386.697982) (xy 48.852583 -386.707244) (xy 48.861846 -386.723656)
			(xy 48.868838 -386.729986) (xy 48.890913 -386.748671) (xy 48.930651 -386.790694) (xy 48.964777 -386.837389)
			(xy 48.992748 -386.888012) (xy 49.014117 -386.941756) (xy 49.028543 -386.997764) (xy 49.035798 -387.055144)
			(xy 49.036224 -387.084062) (xy 49.035635 -387.117425) (xy 49.025991 -387.183451) (xy 49.006858 -387.247375)
			(xy 48.993298 -387.277864) (xy 48.989127 -387.288309) (xy 48.989234 -387.310767) (xy 48.99893 -387.331025)
			(xy 49.007268 -387.33857) (xy 49.029492 -387.357271) (xy 49.069557 -387.399321) (xy 49.103981 -387.446102)
			(xy 49.132209 -387.496862) (xy 49.153789 -387.550786) (xy 49.168372 -387.607007) (xy 49.175725 -387.664621)
			(xy 49.176178 -387.693662) (xy 49.175692 -387.722667) (xy 49.168381 -387.780213) (xy 49.15386 -387.836375)
			(xy 49.132361 -387.890253) (xy 49.104229 -387.940983) (xy 49.069913 -387.987754) (xy 49.029964 -388.029815)
			(xy 49.007776 -388.0485) (xy 49.000918 -388.054088) (xy 48.99152 -388.069582) (xy 48.977804 -388.143242)
			(xy 48.976605 -388.152003) (xy 48.979599 -388.169416) (xy 48.983646 -388.177278) (xy 48.983646 -388.177532)
			(xy 48.996222 -388.200718) (xy 49.014095 -388.25034) (xy 49.023196 -388.302291) (xy 49.023778 -388.328662)
			(xy 49.023709 -388.338021) (xy 49.022566 -388.356703) (xy 49.021492 -388.366) (xy 49.020476 -388.374636)
			(xy 49.024286 -388.391908) (xy 49.067974 -388.46125) (xy 49.081944 -388.471918) (xy 49.090326 -388.474712)
			(xy 49.114352 -388.483187) (xy 49.159524 -388.506738) (xy 49.20033 -388.537236) (xy 49.235709 -388.57389)
			(xy 49.264746 -388.615748) (xy 49.286685 -388.661725) (xy 49.294288 -388.68604) (xy 49.295812 -388.691882)
			(xy 49.616106 -389.245602) (xy 49.62017 -389.24992) (xy 49.636337 -389.267579) (xy 49.663654 -389.306899)
			(xy 49.68472 -389.349893) (xy 49.699052 -389.395575) (xy 49.706321 -389.442898) (xy 49.706784 -389.466836)
			(xy 49.706784 -389.467344) (xy 49.706323 -389.492134) (xy 49.698561 -389.541103) (xy 49.683235 -389.588255)
			(xy 49.660722 -389.632429) (xy 49.631577 -389.672539) (xy 49.596517 -389.707595) (xy 49.556405 -389.736737)
			(xy 49.512229 -389.759246) (xy 49.465076 -389.774567) (xy 49.416106 -389.782325) (xy 49.391316 -389.782812)
			(xy 49.365922 -389.782297) (xy 49.315789 -389.774169) (xy 49.267604 -389.75812) (xy 49.22261 -389.734564)
			(xy 49.181967 -389.704108) (xy 49.146724 -389.667539) (xy 49.11779 -389.625799) (xy 49.095911 -389.579966)
			(xy 49.088294 -389.555736) (xy 49.08677 -389.549894) (xy 48.766476 -388.996174) (xy 48.762412 -388.991856)
			(xy 48.746211 -388.974145) (xy 48.718786 -388.934756) (xy 48.697642 -388.891667) (xy 48.683268 -388.845873)
			(xy 48.675994 -388.79843) (xy 48.675544 -388.774432) (xy 48.675686 -388.76238) (xy 48.677592 -388.73835)
			(xy 48.679354 -388.726426) (xy 48.680321 -388.717667) (xy 48.676955 -388.700387) (xy 48.67275 -388.692644)
			(xy 48.639984 -388.637272) (xy 48.635284 -388.629993) (xy 48.622046 -388.618829) (xy 48.614076 -388.615428)
			(xy 48.613568 -388.615428) (xy 48.591851 -388.606992) (xy 48.551046 -388.584515) (xy 48.514126 -388.556103)
			(xy 48.48195 -388.522414) (xy 48.455262 -388.484229) (xy 48.434683 -388.442435) (xy 48.420689 -388.398)
			(xy 48.413605 -388.351955) (xy 48.413162 -388.328662) (xy 48.413733 -388.302289) (xy 48.422814 -388.250331)
			(xy 48.440701 -388.200711) (xy 48.453294 -388.177532) (xy 48.453294 -388.177278) (xy 48.457305 -388.169403)
			(xy 48.460304 -388.152001) (xy 48.459136 -388.143242) (xy 48.44542 -388.069582) (xy 48.436022 -388.054088)
			(xy 48.429164 -388.0485) (xy 48.406986 -388.029803) (xy 48.367041 -387.987739) (xy 48.332725 -387.940969)
			(xy 48.304587 -387.890241) (xy 48.283079 -387.836368) (xy 48.268543 -387.78021) (xy 48.261213 -387.722666)
			(xy 48.260762 -387.693662) (xy 48.260762 -387.693408) (xy 48.261341 -387.660086) (xy 48.271008 -387.594147)
			(xy 48.290138 -387.530308) (xy 48.303688 -387.49986) (xy 48.307936 -387.48944) (xy 48.307802 -387.466961)
			(xy 48.298072 -387.446697) (xy 48.289718 -387.439154) (xy 48.267455 -387.420499) (xy 48.227392 -387.37844)
			(xy 48.192972 -387.331651) (xy 48.164749 -387.280883) (xy 48.143176 -387.226952) (xy 48.128601 -387.170724)
			(xy 48.121256 -387.113105) (xy 48.120808 -387.084062) (xy 48.120808 -387.083808) (xy 48.121236 -387.054908)
			(xy 48.128523 -386.997569) (xy 48.142969 -386.941604) (xy 48.164345 -386.887902) (xy 48.19231 -386.837318)
			(xy 48.22642 -386.790656) (xy 48.266132 -386.748659) (xy 48.288194 -386.729986) (xy 48.29527 -386.723725)
			(xy 48.304538 -386.707278) (xy 48.306228 -386.697982) (xy 48.3108 -386.666994) (xy 48.311707 -386.657821)
			(xy 48.307665 -386.639849) (xy 48.302926 -386.631942) (xy 48.286614 -386.606122) (xy 48.262839 -386.549873)
			(xy 48.255682 -386.520182) (xy 48.253532 -386.511958) (xy 48.244711 -386.49744) (xy 48.23841 -386.491734)
			(xy 48.201072 -386.461) (xy 48.19142 -386.461) (xy 48.161451 -386.46052) (xy 48.102026 -386.452699)
			(xy 48.04413 -386.437188) (xy 47.988754 -386.414252) (xy 47.936846 -386.384285) (xy 47.889293 -386.347798)
			(xy 47.84691 -386.305416) (xy 47.810422 -386.257864) (xy 47.780453 -386.205957) (xy 47.757516 -386.150582)
			(xy 47.742003 -386.092686) (xy 47.734181 -386.033261) (xy 47.733712 -386.003292) (xy 47.734234 -385.972229)
			(xy 47.742649 -385.910675) (xy 47.750476 -385.88061) (xy 47.75327 -385.870704) (xy 47.75073 -385.850384)
			(xy 47.708566 -385.777486) (xy 47.703161 -385.768887) (xy 47.687041 -385.756563) (xy 47.677324 -385.75361)
			(xy 47.67707 -385.75361) (xy 47.665348 -385.750466) (xy 47.642223 -385.743094) (xy 47.630842 -385.738878)
			(xy 47.622664 -385.736165) (xy 47.605445 -385.735839) (xy 47.589095 -385.741247) (xy 47.582074 -385.746244)
			(xy 47.50308 -385.806696) (xy 47.492666 -385.830826) (xy 47.493936 -385.84378) (xy 47.49546 -385.87553)
			(xy 47.495076 -385.899206) (xy 47.488343 -385.946077) (xy 47.474978 -385.991503) (xy 47.465488 -386.013198)
			(xy 47.461635 -386.022538) (xy 47.460837 -386.042708) (xy 47.463964 -386.052314) (xy 47.492666 -386.129276)
			(xy 47.506382 -386.144008) (xy 47.51578 -386.148072) (xy 47.540156 -386.159749) (xy 47.585024 -386.189879)
			(xy 47.624401 -386.2269) (xy 47.657238 -386.269828) (xy 47.682663 -386.317521) (xy 47.7 -386.368711)
			(xy 47.708789 -386.422039) (xy 47.709328 -386.449062) (xy 47.709328 -386.449316) (xy 47.708876 -386.473517)
			(xy 47.70181 -386.5214) (xy 47.687831 -386.56774) (xy 47.667239 -386.611543) (xy 47.65421 -386.631942)
			(xy 47.649485 -386.639856) (xy 47.645441 -386.657821) (xy 47.646336 -386.666994) (xy 47.650908 -386.697982)
			(xy 47.652686 -386.707244) (xy 47.661949 -386.723656) (xy 47.668942 -386.729986) (xy 47.691018 -386.74867)
			(xy 47.730756 -386.790693) (xy 47.764882 -386.837389) (xy 47.792852 -386.888012) (xy 47.814221 -386.941756)
			(xy 47.828647 -386.997764) (xy 47.835902 -387.055144) (xy 47.836328 -387.084062) (xy 47.835739 -387.117425)
			(xy 47.826095 -387.183451) (xy 47.806962 -387.247375) (xy 47.793402 -387.277864) (xy 47.78923 -387.288309)
			(xy 47.789337 -387.310768) (xy 47.799034 -387.331025) (xy 47.807372 -387.33857) (xy 47.829596 -387.35727)
			(xy 47.869662 -387.39932) (xy 47.904085 -387.446101) (xy 47.932314 -387.496862) (xy 47.953893 -387.550786)
			(xy 47.968476 -387.607007) (xy 47.975829 -387.664621) (xy 47.976282 -387.693662) (xy 47.975794 -387.722667)
			(xy 47.968484 -387.780213) (xy 47.953963 -387.836375) (xy 47.932464 -387.890252) (xy 47.904332 -387.940983)
			(xy 47.870016 -387.987753) (xy 47.830068 -388.029815) (xy 47.80788 -388.0485) (xy 47.801022 -388.054088)
			(xy 47.791624 -388.069582) (xy 47.777908 -388.143242) (xy 47.776708 -388.152003) (xy 47.779702 -388.169416)
			(xy 47.78375 -388.177278) (xy 47.78375 -388.177532) (xy 47.796326 -388.200718) (xy 47.814199 -388.25034)
			(xy 47.8233 -388.302291) (xy 47.823882 -388.328662) (xy 47.823813 -388.338021) (xy 47.82267 -388.356703)
			(xy 47.821596 -388.366) (xy 47.82058 -388.374636) (xy 47.82439 -388.391908) (xy 47.868078 -388.46125)
			(xy 47.882048 -388.471918) (xy 47.89043 -388.474712) (xy 47.914456 -388.483185) (xy 47.959629 -388.506737)
			(xy 48.000434 -388.537235) (xy 48.035814 -388.573889) (xy 48.06485 -388.615747) (xy 48.086789 -388.661725)
			(xy 48.094392 -388.68604) (xy 48.095916 -388.691882) (xy 48.41621 -389.245602) (xy 48.420274 -389.24992)
			(xy 48.436442 -389.267579) (xy 48.463758 -389.306899) (xy 48.484824 -389.349893) (xy 48.499156 -389.395575)
			(xy 48.506425 -389.442898) (xy 48.506888 -389.466836) (xy 48.506888 -389.467344) (xy 48.506423 -389.492134)
			(xy 48.498661 -389.541102) (xy 48.483335 -389.588254) (xy 48.460823 -389.632428) (xy 48.431678 -389.672537)
			(xy 48.396619 -389.707594) (xy 48.356507 -389.736736) (xy 48.312332 -389.759244) (xy 48.265179 -389.774566)
			(xy 48.21621 -389.782325) (xy 48.19142 -389.782812) (xy 48.166026 -389.782294) (xy 48.115893 -389.774166)
			(xy 48.067708 -389.758118) (xy 48.022714 -389.734562) (xy 47.982071 -389.704107) (xy 47.946828 -389.667538)
			(xy 47.917894 -389.625799) (xy 47.896015 -389.579966) (xy 47.888398 -389.555736) (xy 47.886874 -389.549894)
			(xy 47.56658 -388.996174) (xy 47.562516 -388.991856) (xy 47.546316 -388.974145) (xy 47.51889 -388.934755)
			(xy 47.497746 -388.891667) (xy 47.483372 -388.845873) (xy 47.476098 -388.79843) (xy 47.475648 -388.774432)
			(xy 47.47579 -388.76238) (xy 47.477696 -388.73835) (xy 47.479458 -388.726426) (xy 47.480425 -388.717667)
			(xy 47.477058 -388.700387) (xy 47.472854 -388.692644) (xy 47.440088 -388.637272) (xy 47.435386 -388.629994)
			(xy 47.422149 -388.618829) (xy 47.41418 -388.615428) (xy 47.413672 -388.615428) (xy 47.391956 -388.60699)
			(xy 47.35115 -388.584514) (xy 47.314231 -388.556102) (xy 47.282054 -388.522413) (xy 47.255367 -388.484229)
			(xy 47.234787 -388.442434) (xy 47.220793 -388.398) (xy 47.213709 -388.351955) (xy 47.213266 -388.328662)
			(xy 47.213836 -388.302289) (xy 47.222918 -388.250331) (xy 47.240805 -388.200711) (xy 47.253398 -388.177532)
			(xy 47.253398 -388.177278) (xy 47.257409 -388.169403) (xy 47.260408 -388.152001) (xy 47.25924 -388.143242)
			(xy 47.245524 -388.069582) (xy 47.236126 -388.054088) (xy 47.229268 -388.0485) (xy 47.207091 -388.029802)
			(xy 47.167145 -387.987738) (xy 47.132829 -387.940968) (xy 47.104692 -387.890241) (xy 47.083183 -387.836367)
			(xy 47.068647 -387.78021) (xy 47.061317 -387.722666) (xy 47.060866 -387.693662) (xy 47.060866 -387.693408)
			(xy 47.061445 -387.660086) (xy 47.071112 -387.594147) (xy 47.090242 -387.530308) (xy 47.103792 -387.49986)
			(xy 47.108039 -387.489439) (xy 47.107904 -387.466961) (xy 47.098176 -387.446697) (xy 47.089822 -387.439154)
			(xy 47.06756 -387.420498) (xy 47.027496 -387.37844) (xy 46.993077 -387.331651) (xy 46.964853 -387.280883)
			(xy 46.94328 -387.226951) (xy 46.928705 -387.170724) (xy 46.92136 -387.113105) (xy 46.920912 -387.084062)
			(xy 46.920912 -387.083808) (xy 46.921338 -387.054908) (xy 46.928625 -386.997569) (xy 46.943072 -386.941604)
			(xy 46.964448 -386.887902) (xy 46.992413 -386.837318) (xy 47.026524 -386.790656) (xy 47.066236 -386.748659)
			(xy 47.088298 -386.729986) (xy 47.095374 -386.723726) (xy 47.104642 -386.707278) (xy 47.106332 -386.697982)
			(xy 47.110904 -386.666994) (xy 47.111811 -386.657821) (xy 47.107768 -386.63985) (xy 47.10303 -386.631942)
			(xy 47.089992 -386.611512) (xy 47.069395 -386.567642) (xy 47.055411 -386.52124) (xy 47.048338 -386.473294)
			(xy 47.047912 -386.449062) (xy 47.048296 -386.425386) (xy 47.055029 -386.378515) (xy 47.068394 -386.333089)
			(xy 47.077884 -386.311394) (xy 47.08174 -386.302055) (xy 47.082534 -386.281885) (xy 47.079408 -386.272278)
			(xy 47.050706 -386.195316) (xy 47.03699 -386.180584) (xy 47.027592 -386.17652) (xy 47.00323 -386.164816)
			(xy 46.958358 -386.134694) (xy 46.918978 -386.097679) (xy 46.886138 -386.054756) (xy 46.86071 -386.007066)
			(xy 46.843372 -385.955878) (xy 46.834583 -385.902552) (xy 46.834044 -385.87553) (xy 45.347002 -385.87553)
			(xy 45.317581 -385.912289) (xy 45.295566 -385.93395) (xy 45.287426 -385.942562) (xy 45.27933 -385.964797)
			(xy 45.280072 -385.976622) (xy 45.28947 -386.05714) (xy 45.291339 -386.068799) (xy 45.304046 -386.088666)
			(xy 45.313854 -386.09524) (xy 45.314108 -386.09524) (xy 45.339458 -386.110732) (xy 45.386309 -386.147261)
			(xy 45.428038 -386.189547) (xy 45.463945 -386.236877) (xy 45.493424 -386.288457) (xy 45.515981 -386.343417)
			(xy 45.531234 -386.400835) (xy 45.53893 -386.459743) (xy 45.539406 -386.489448) (xy 45.538947 -386.520107)
			(xy 45.530754 -386.580877) (xy 45.514522 -386.640008) (xy 45.49054 -386.696443) (xy 45.45924 -386.749172)
			(xy 45.42118 -386.797249) (xy 45.399452 -386.818886) (xy 45.391716 -386.827201) (xy 45.383711 -386.84842)
			(xy 45.38562 -386.871018) (xy 45.390816 -386.881116) (xy 45.404956 -386.906584) (xy 45.425024 -386.961263)
			(xy 45.435186 -387.018616) (xy 45.435774 -387.04774) (xy 45.435264 -387.073727) (xy 45.427134 -387.125062)
			(xy 45.411073 -387.174492) (xy 45.387477 -387.220802) (xy 45.356927 -387.26285) (xy 45.320176 -387.299601)
			(xy 45.278128 -387.330151) (xy 45.231818 -387.353747) (xy 45.182388 -387.369808) (xy 45.131053 -387.377938)
			(xy 45.079079 -387.377938) (xy 45.027744 -387.369808) (xy 44.978314 -387.353747) (xy 44.932004 -387.330151)
			(xy 44.889956 -387.299601) (xy 44.853205 -387.26285) (xy 44.822655 -387.220802) (xy 44.799059 -387.174492)
			(xy 44.782998 -387.125062) (xy 44.774868 -387.073727) (xy 44.774358 -387.04774) (xy 44.774358 -387.047486)
			(xy 44.774798 -387.023015) (xy 44.781994 -386.974607) (xy 44.796255 -386.92779) (xy 44.806362 -386.9055)
			(xy 44.810718 -386.895034) (xy 44.810723 -386.872388) (xy 44.801028 -386.851923) (xy 44.792646 -386.844286)
			(xy 44.770424 -386.825623) (xy 44.730416 -386.783586) (xy 44.696044 -386.736827) (xy 44.667862 -386.686097)
			(xy 44.646321 -386.63221) (xy 44.631768 -386.576032) (xy 44.624436 -386.518464) (xy 44.62399 -386.489448)
			(xy 44.624494 -386.458568) (xy 44.632811 -386.397371) (xy 44.649286 -386.337849) (xy 44.673621 -386.281086)
			(xy 44.705372 -386.228113) (xy 44.743963 -386.179894) (xy 44.765976 -386.158232) (xy 44.774132 -386.149633)
			(xy 44.782217 -386.127387) (xy 44.78147 -386.11556) (xy 44.772072 -386.035042) (xy 44.770236 -386.023374)
			(xy 44.757507 -386.003509) (xy 44.747688 -385.996942) (xy 44.747434 -385.996942) (xy 44.724055 -385.982711)
			(xy 44.680543 -385.949509) (xy 44.641308 -385.911347) (xy 44.606912 -385.868772) (xy 44.577846 -385.822394)
			(xy 44.565824 -385.797806) (xy 44.565824 -385.797552) (xy 44.561605 -385.789569) (xy 44.548653 -385.777007)
			(xy 44.532137 -385.769744) (xy 44.523152 -385.76885) (xy 44.434252 -385.763008) (xy 44.425158 -385.76274)
			(xy 44.407734 -385.767947) (xy 44.393224 -385.778908) (xy 44.388024 -385.786376) (xy 44.388024 -385.78663)
			(xy 44.372965 -385.809531) (xy 44.33727 -385.851123) (xy 44.295989 -385.887179) (xy 44.249973 -385.916955)
			(xy 44.200169 -385.939839) (xy 44.147603 -385.95536) (xy 44.093357 -385.963197) (xy 44.065952 -385.963668)
			(xy 44.0387 -385.963259) (xy 43.984752 -385.955496) (xy 43.932457 -385.940135) (xy 43.882881 -385.917489)
			(xy 43.837032 -385.888018) (xy 43.795843 -385.852323) (xy 43.760153 -385.81113) (xy 43.730688 -385.765277)
			(xy 43.708048 -385.715697) (xy 43.692694 -385.663401) (xy 43.684938 -385.609452) (xy 41.576793 -385.609452)
			(xy 41.569047 -385.663366) (xy 41.553694 -385.715666) (xy 41.531053 -385.765248) (xy 41.501585 -385.811103)
			(xy 41.465891 -385.852296) (xy 41.424696 -385.88799) (xy 41.378841 -385.917457) (xy 41.329259 -385.940096)
			(xy 41.276958 -385.955448) (xy 41.223005 -385.9632) (xy 41.195752 -385.963668) (xy 41.195498 -385.963668)
			(xy 41.168887 -385.96318) (xy 41.116187 -385.955742) (xy 41.065029 -385.941065) (xy 41.016401 -385.919432)
			(xy 40.993568 -385.905756) (xy 40.983561 -385.900251) (xy 40.960892 -385.897736) (xy 40.939367 -385.905278)
			(xy 40.93083 -385.912868) (xy 40.787066 -386.056632) (xy 40.780217 -386.064029) (xy 40.772484 -386.082628)
			(xy 40.77208 -386.0927) (xy 40.77208 -386.473446) (xy 40.772534 -386.483252) (xy 40.779894 -386.501433)
			(xy 40.793527 -386.515534) (xy 40.802306 -386.519928) (xy 40.901112 -386.56387) (xy 40.930576 -386.559044)
			(xy 40.941752 -386.548884) (xy 40.965191 -386.528337) (xy 41.016197 -386.492508) (xy 41.071198 -386.463178)
			(xy 41.12937 -386.440786) (xy 41.189842 -386.425668) (xy 41.251708 -386.41805) (xy 41.282874 -386.417566)
			(xy 41.283128 -386.417566) (xy 41.303989 -386.417788) (xy 41.345571 -386.421221) (xy 41.366186 -386.424424)
			(xy 41.375134 -386.425564) (xy 41.392841 -386.422191) (xy 41.40073 -386.41782) (xy 41.457626 -386.383784)
			(xy 41.465035 -386.378812) (xy 41.476201 -386.364909) (xy 41.47947 -386.356606) (xy 41.47947 -386.356352)
			(xy 41.488238 -386.331333) (xy 41.51172 -386.283803) (xy 41.541563 -386.239986) (xy 41.57719 -386.200727)
			(xy 41.617914 -386.166784) (xy 41.662948 -386.138813) (xy 41.711425 -386.117352) (xy 41.762407 -386.102816)
			(xy 41.814913 -386.095486) (xy 41.84142 -386.094986) (xy 41.86867 -386.095473) (xy 41.922616 -386.103232)
			(xy 41.974909 -386.118589) (xy 42.024484 -386.141231) (xy 42.070332 -386.170698) (xy 42.111521 -386.206389)
			(xy 42.147211 -386.247579) (xy 42.176676 -386.293428) (xy 42.199316 -386.343004) (xy 42.214671 -386.395297)
			(xy 42.222428 -386.449244) (xy 42.222928 -386.476494) (xy 42.222431 -386.50446) (xy 42.214253 -386.559792)
			(xy 42.198087 -386.613338) (xy 42.174277 -386.66395) (xy 42.143334 -386.710545) (xy 42.105922 -386.752124)
			(xy 42.062842 -386.787797) (xy 42.015015 -386.816799) (xy 41.963468 -386.83851) (xy 41.909303 -386.852464)
			(xy 41.881552 -386.85597) (xy 41.872408 -386.856732) (xy 41.856152 -386.86486) (xy 41.804336 -386.91947)
			(xy 41.798523 -386.92623) (xy 41.791501 -386.942603) (xy 41.79062 -386.951474) (xy 41.79062 -386.951728)
			(xy 41.788489 -386.984041) (xy 41.777059 -387.047783) (xy 41.757632 -387.109559) (xy 41.730523 -387.16837)
			(xy 41.696169 -387.223266) (xy 41.676066 -387.248654) (xy 41.670866 -387.255617) (xy 41.665031 -387.271976)
			(xy 41.664636 -387.280658) (xy 41.664636 -387.43509) (xy 41.664981 -387.443782) (xy 41.670822 -387.460154)
			(xy 41.676066 -387.467094) (xy 41.697783 -387.494491) (xy 41.734293 -387.554112) (xy 41.762292 -387.618172)
			(xy 41.781254 -387.685464) (xy 41.790819 -387.754718) (xy 41.791382 -387.789674) (xy 41.791382 -387.790182)
			(xy 41.790623 -387.829032) (xy 41.778752 -387.90582) (xy 41.76776 -387.94309) (xy 41.764204 -387.954012)
			(xy 41.767506 -387.976872) (xy 41.817798 -388.052564) (xy 41.824618 -388.061667) (xy 41.844134 -388.073294)
			(xy 41.85539 -388.074916) (xy 41.883492 -388.077966) (xy 41.938422 -388.091296) (xy 41.990784 -388.112585)
			(xy 42.039431 -388.141366) (xy 42.083301 -388.17701) (xy 42.121431 -388.218736) (xy 42.152988 -388.265631)
			(xy 42.168239 -388.297674) (xy 43.808902 -388.297674) (xy 43.812973 -388.242052) (xy 43.825099 -388.187615)
			(xy 43.845022 -388.135524) (xy 43.872318 -388.086889) (xy 43.906404 -388.042746) (xy 43.946553 -388.004037)
			(xy 43.991911 -387.971586) (xy 44.041511 -387.946085) (xy 44.094295 -387.928078) (xy 44.149138 -387.917948)
			(xy 44.204872 -387.915911) (xy 44.260309 -387.922011) (xy 44.314266 -387.936117) (xy 44.365595 -387.957929)
			(xy 44.413201 -387.986983) (xy 44.456069 -388.022658) (xy 44.493286 -388.064195) (xy 44.524059 -388.110708)
			(xy 44.547731 -388.161205) (xy 44.563799 -388.214612) (xy 44.571919 -388.269788) (xy 44.572428 -388.297674)
			(xy 44.571981 -388.322137) (xy 44.774868 -388.322137) (xy 44.774868 -388.270163) (xy 44.782998 -388.218828)
			(xy 44.799059 -388.169398) (xy 44.822655 -388.123088) (xy 44.853205 -388.08104) (xy 44.889956 -388.044289)
			(xy 44.932004 -388.013739) (xy 44.978314 -387.990143) (xy 45.027744 -387.974082) (xy 45.079079 -387.965952)
			(xy 45.131053 -387.965952) (xy 45.182388 -387.974082) (xy 45.231818 -387.990143) (xy 45.278128 -388.013739)
			(xy 45.320176 -388.044289) (xy 45.356927 -388.08104) (xy 45.387477 -388.123088) (xy 45.411073 -388.169398)
			(xy 45.427134 -388.218828) (xy 45.435264 -388.270163) (xy 45.435774 -388.29615) (xy 45.435264 -388.322137)
			(xy 45.427134 -388.373472) (xy 45.411073 -388.422902) (xy 45.387477 -388.469212) (xy 45.356927 -388.51126)
			(xy 45.320176 -388.548011) (xy 45.278128 -388.578561) (xy 45.231818 -388.602157) (xy 45.182388 -388.618218)
			(xy 45.131053 -388.626348) (xy 45.079079 -388.626348) (xy 45.027744 -388.618218) (xy 44.978314 -388.602157)
			(xy 44.932004 -388.578561) (xy 44.889956 -388.548011) (xy 44.853205 -388.51126) (xy 44.822655 -388.469212)
			(xy 44.799059 -388.422902) (xy 44.782998 -388.373472) (xy 44.774868 -388.322137) (xy 44.571981 -388.322137)
			(xy 44.571919 -388.32556) (xy 44.563799 -388.380736) (xy 44.547731 -388.434143) (xy 44.524059 -388.48464)
			(xy 44.493286 -388.531153) (xy 44.456069 -388.57269) (xy 44.413201 -388.608365) (xy 44.365595 -388.637419)
			(xy 44.314266 -388.659231) (xy 44.260309 -388.673337) (xy 44.204872 -388.679437) (xy 44.149138 -388.6774)
			(xy 44.094295 -388.66727) (xy 44.041511 -388.649263) (xy 43.991911 -388.623762) (xy 43.946553 -388.591311)
			(xy 43.906404 -388.552602) (xy 43.872318 -388.508459) (xy 43.845022 -388.459824) (xy 43.825099 -388.407733)
			(xy 43.812973 -388.353296) (xy 43.808902 -388.297674) (xy 42.168239 -388.297674) (xy 42.17728 -388.316669)
			(xy 42.193777 -388.370732) (xy 42.202116 -388.426638) (xy 42.202608 -388.4549) (xy 42.202122 -388.482151)
			(xy 42.194366 -388.536099) (xy 42.179011 -388.588394) (xy 42.156369 -388.637971) (xy 42.126903 -388.683821)
			(xy 42.091212 -388.725012) (xy 42.050021 -388.760703) (xy 42.004171 -388.790169) (xy 41.954594 -388.812811)
			(xy 41.902299 -388.828166) (xy 41.848351 -388.835922) (xy 41.793849 -388.835922) (xy 41.739901 -388.828166)
			(xy 41.687606 -388.812811) (xy 41.638029 -388.790169) (xy 41.592179 -388.760703) (xy 41.550988 -388.725012)
			(xy 41.515297 -388.683821) (xy 41.485831 -388.637971) (xy 41.463189 -388.588394) (xy 41.447834 -388.536099)
			(xy 41.440078 -388.482151) (xy 41.439592 -388.4549) (xy 41.43969 -388.443504) (xy 41.441088 -388.420756)
			(xy 41.442386 -388.409434) (xy 41.442386 -388.408926) (xy 41.443656 -388.397496) (xy 41.436544 -388.37616)
			(xy 41.373044 -388.310882) (xy 41.364647 -388.303189) (xy 41.343275 -388.295414) (xy 41.331896 -388.295896)
			(xy 41.331642 -388.295896) (xy 41.31948 -388.296984) (xy 41.295085 -388.298125) (xy 41.282874 -388.298182)
			(xy 41.251708 -388.297709) (xy 41.189843 -388.290089) (xy 41.129372 -388.274968) (xy 41.071203 -388.25257)
			(xy 41.016206 -388.223232) (xy 40.965206 -388.187394) (xy 40.941752 -388.166864) (xy 40.930576 -388.156704)
			(xy 40.901112 -388.151878) (xy 40.802306 -388.19582) (xy 40.793515 -388.200199) (xy 40.779869 -388.214296)
			(xy 40.772526 -388.232491) (xy 40.77208 -388.242302) (xy 40.77208 -388.442708) (xy 40.772504 -388.452778)
			(xy 40.780218 -388.471382) (xy 40.787066 -388.478776) (xy 41.183052 -388.874762) (xy 41.205247 -388.897554)
			(xy 41.244925 -388.947288) (xy 41.278783 -389.001151) (xy 41.306396 -389.058468) (xy 41.327417 -389.118517)
			(xy 41.34158 -389.180542) (xy 41.348708 -389.243763) (xy 41.349168 -389.275574) (xy 41.349168 -390.626092)
			(xy 44.635674 -390.626092) (xy 44.636275 -390.592792) (xy 44.645955 -390.526898) (xy 44.665094 -390.463106)
			(xy 44.693288 -390.402767) (xy 44.711112 -390.374632) (xy 44.716173 -390.366115) (xy 44.71999 -390.346693)
			(xy 44.716168 -390.327272) (xy 44.711112 -390.318752) (xy 44.693296 -390.290613) (xy 44.66512 -390.230269)
			(xy 44.645985 -390.16648) (xy 44.636294 -390.100591) (xy 44.635674 -390.067292) (xy 44.636164 -390.037324)
			(xy 44.643987 -389.977902) (xy 44.6595 -389.920009) (xy 44.682436 -389.864636) (xy 44.712403 -389.81273)
			(xy 44.74889 -389.76518) (xy 44.79127 -389.7228) (xy 44.83882 -389.686313) (xy 44.890726 -389.656346)
			(xy 44.946099 -389.63341) (xy 45.003992 -389.617897) (xy 45.063414 -389.610074) (xy 45.12335 -389.610074)
			(xy 45.182772 -389.617897) (xy 45.240665 -389.63341) (xy 45.296038 -389.656346) (xy 45.347944 -389.686313)
			(xy 45.395494 -389.7228) (xy 45.437874 -389.76518) (xy 45.474361 -389.81273) (xy 45.504328 -389.864636)
			(xy 45.527264 -389.920009) (xy 45.542777 -389.977902) (xy 45.5506 -390.037324) (xy 45.55109 -390.067292)
			(xy 45.550488 -390.100592) (xy 45.541761 -390.160002) (xy 47.085262 -390.160002) (xy 47.089222 -390.110948)
			(xy 47.100999 -390.063164) (xy 47.12029 -390.017888) (xy 47.146593 -389.976292) (xy 47.179228 -389.939455)
			(xy 47.217349 -389.90833) (xy 47.25997 -389.883723) (xy 47.305986 -389.866271) (xy 47.354205 -389.856427)
			(xy 47.40338 -389.854446) (xy 47.452235 -389.860378) (xy 47.499506 -389.87407) (xy 47.543968 -389.895168)
			(xy 47.584471 -389.923124) (xy 47.619964 -389.957216) (xy 47.649529 -389.99656) (xy 47.6724 -390.040137)
			(xy 47.687984 -390.086818) (xy 47.695879 -390.135395) (xy 47.696374 -390.160002) (xy 48.285412 -390.160002)
			(xy 48.289372 -390.110948) (xy 48.301149 -390.063164) (xy 48.32044 -390.017888) (xy 48.346743 -389.976292)
			(xy 48.379378 -389.939455) (xy 48.417499 -389.90833) (xy 48.46012 -389.883723) (xy 48.506136 -389.866271)
			(xy 48.554355 -389.856427) (xy 48.60353 -389.854446) (xy 48.652385 -389.860378) (xy 48.699656 -389.87407)
			(xy 48.744118 -389.895168) (xy 48.784621 -389.923124) (xy 48.820114 -389.957216) (xy 48.849679 -389.99656)
			(xy 48.87255 -390.040137) (xy 48.888134 -390.086818) (xy 48.896029 -390.135395) (xy 48.896524 -390.160002)
			(xy 49.485562 -390.160002) (xy 49.489522 -390.110948) (xy 49.501299 -390.063164) (xy 49.52059 -390.017888)
			(xy 49.546893 -389.976292) (xy 49.579528 -389.939455) (xy 49.617649 -389.90833) (xy 49.66027 -389.883723)
			(xy 49.706286 -389.866271) (xy 49.754505 -389.856427) (xy 49.80368 -389.854446) (xy 49.852535 -389.860378)
			(xy 49.899806 -389.87407) (xy 49.944268 -389.895168) (xy 49.984771 -389.923124) (xy 50.020264 -389.957216)
			(xy 50.049829 -389.99656) (xy 50.0727 -390.040137) (xy 50.088284 -390.086818) (xy 50.096179 -390.135395)
			(xy 50.096674 -390.160002) (xy 50.685458 -390.160002) (xy 50.689418 -390.110948) (xy 50.701195 -390.063164)
			(xy 50.720486 -390.017888) (xy 50.746789 -389.976292) (xy 50.779424 -389.939455) (xy 50.817545 -389.90833)
			(xy 50.860166 -389.883723) (xy 50.906182 -389.866271) (xy 50.954401 -389.856427) (xy 51.003576 -389.854446)
			(xy 51.052431 -389.860378) (xy 51.099702 -389.87407) (xy 51.144164 -389.895168) (xy 51.184667 -389.923124)
			(xy 51.22016 -389.957216) (xy 51.249725 -389.99656) (xy 51.272596 -390.040137) (xy 51.28818 -390.086818)
			(xy 51.296075 -390.135395) (xy 51.29657 -390.160002) (xy 51.885608 -390.160002) (xy 51.889568 -390.110948)
			(xy 51.901345 -390.063164) (xy 51.920636 -390.017888) (xy 51.946939 -389.976292) (xy 51.979574 -389.939455)
			(xy 52.017695 -389.90833) (xy 52.060316 -389.883723) (xy 52.106332 -389.866271) (xy 52.154551 -389.856427)
			(xy 52.203726 -389.854446) (xy 52.252581 -389.860378) (xy 52.299852 -389.87407) (xy 52.344314 -389.895168)
			(xy 52.384817 -389.923124) (xy 52.42031 -389.957216) (xy 52.449875 -389.99656) (xy 52.472746 -390.040137)
			(xy 52.48833 -390.086818) (xy 52.496225 -390.135395) (xy 52.49672 -390.160002) (xy 53.085504 -390.160002)
			(xy 53.089464 -390.110948) (xy 53.101241 -390.063164) (xy 53.120532 -390.017888) (xy 53.146835 -389.976292)
			(xy 53.17947 -389.939455) (xy 53.217591 -389.90833) (xy 53.260212 -389.883723) (xy 53.306228 -389.866271)
			(xy 53.354447 -389.856427) (xy 53.403622 -389.854446) (xy 53.452477 -389.860378) (xy 53.499748 -389.87407)
			(xy 53.54421 -389.895168) (xy 53.584713 -389.923124) (xy 53.620206 -389.957216) (xy 53.649771 -389.99656)
			(xy 53.672642 -390.040137) (xy 53.688226 -390.086818) (xy 53.696121 -390.135395) (xy 53.696616 -390.160002)
			(xy 54.2854 -390.160002) (xy 54.28936 -390.110948) (xy 54.301137 -390.063164) (xy 54.320428 -390.017888)
			(xy 54.346731 -389.976292) (xy 54.379366 -389.939455) (xy 54.417487 -389.90833) (xy 54.460108 -389.883723)
			(xy 54.506124 -389.866271) (xy 54.554343 -389.856427) (xy 54.603518 -389.854446) (xy 54.652373 -389.860378)
			(xy 54.699644 -389.87407) (xy 54.744106 -389.895168) (xy 54.784609 -389.923124) (xy 54.820102 -389.957216)
			(xy 54.849667 -389.99656) (xy 54.872538 -390.040137) (xy 54.888122 -390.086818) (xy 54.896017 -390.135395)
			(xy 54.896512 -390.160002) (xy 55.48555 -390.160002) (xy 55.48951 -390.110948) (xy 55.501287 -390.063164)
			(xy 55.520578 -390.017888) (xy 55.546881 -389.976292) (xy 55.579516 -389.939455) (xy 55.617637 -389.90833)
			(xy 55.660258 -389.883723) (xy 55.706274 -389.866271) (xy 55.754493 -389.856427) (xy 55.803668 -389.854446)
			(xy 55.852523 -389.860378) (xy 55.899794 -389.87407) (xy 55.944256 -389.895168) (xy 55.984759 -389.923124)
			(xy 56.020252 -389.957216) (xy 56.049817 -389.99656) (xy 56.072688 -390.040137) (xy 56.088272 -390.086818)
			(xy 56.096167 -390.135395) (xy 56.096662 -390.160002) (xy 56.685446 -390.160002) (xy 56.689406 -390.110948)
			(xy 56.701183 -390.063164) (xy 56.720474 -390.017888) (xy 56.746777 -389.976292) (xy 56.779412 -389.939455)
			(xy 56.817533 -389.90833) (xy 56.860154 -389.883723) (xy 56.90617 -389.866271) (xy 56.954389 -389.856427)
			(xy 57.003564 -389.854446) (xy 57.052419 -389.860378) (xy 57.09969 -389.87407) (xy 57.144152 -389.895168)
			(xy 57.184655 -389.923124) (xy 57.220148 -389.957216) (xy 57.249713 -389.99656) (xy 57.272584 -390.040137)
			(xy 57.288168 -390.086818) (xy 57.296063 -390.135395) (xy 57.296558 -390.160002) (xy 57.885596 -390.160002)
			(xy 57.889556 -390.110948) (xy 57.901333 -390.063164) (xy 57.920624 -390.017888) (xy 57.946927 -389.976292)
			(xy 57.979562 -389.939455) (xy 58.017683 -389.90833) (xy 58.060304 -389.883723) (xy 58.10632 -389.866271)
			(xy 58.154539 -389.856427) (xy 58.203714 -389.854446) (xy 58.252569 -389.860378) (xy 58.29984 -389.87407)
			(xy 58.344302 -389.895168) (xy 58.384805 -389.923124) (xy 58.420298 -389.957216) (xy 58.449863 -389.99656)
			(xy 58.472734 -390.040137) (xy 58.488318 -390.086818) (xy 58.496213 -390.135395) (xy 58.496708 -390.160002)
			(xy 59.085492 -390.160002) (xy 59.089452 -390.110948) (xy 59.101229 -390.063164) (xy 59.12052 -390.017888)
			(xy 59.146823 -389.976292) (xy 59.179458 -389.939455) (xy 59.217579 -389.90833) (xy 59.2602 -389.883723)
			(xy 59.306216 -389.866271) (xy 59.354435 -389.856427) (xy 59.40361 -389.854446) (xy 59.452465 -389.860378)
			(xy 59.499736 -389.87407) (xy 59.544198 -389.895168) (xy 59.584701 -389.923124) (xy 59.620194 -389.957216)
			(xy 59.649759 -389.99656) (xy 59.67263 -390.040137) (xy 59.688214 -390.086818) (xy 59.696109 -390.135395)
			(xy 59.696604 -390.160002) (xy 60.285388 -390.160002) (xy 60.289348 -390.110948) (xy 60.301125 -390.063164)
			(xy 60.320416 -390.017888) (xy 60.346719 -389.976292) (xy 60.379354 -389.939455) (xy 60.417475 -389.90833)
			(xy 60.460096 -389.883723) (xy 60.506112 -389.866271) (xy 60.554331 -389.856427) (xy 60.603506 -389.854446)
			(xy 60.652361 -389.860378) (xy 60.699632 -389.87407) (xy 60.744094 -389.895168) (xy 60.784597 -389.923124)
			(xy 60.82009 -389.957216) (xy 60.849655 -389.99656) (xy 60.872526 -390.040137) (xy 60.88811 -390.086818)
			(xy 60.896005 -390.135395) (xy 60.8965 -390.160002) (xy 61.485538 -390.160002) (xy 61.489498 -390.110948)
			(xy 61.501275 -390.063164) (xy 61.520566 -390.017888) (xy 61.546869 -389.976292) (xy 61.579504 -389.939455)
			(xy 61.617625 -389.90833) (xy 61.660246 -389.883723) (xy 61.706262 -389.866271) (xy 61.754481 -389.856427)
			(xy 61.803656 -389.854446) (xy 61.852511 -389.860378) (xy 61.899782 -389.87407) (xy 61.944244 -389.895168)
			(xy 61.984747 -389.923124) (xy 62.02024 -389.957216) (xy 62.049805 -389.99656) (xy 62.072676 -390.040137)
			(xy 62.08826 -390.086818) (xy 62.096155 -390.135395) (xy 62.09665 -390.160002) (xy 62.685434 -390.160002)
			(xy 62.689394 -390.110948) (xy 62.701171 -390.063164) (xy 62.720462 -390.017888) (xy 62.746765 -389.976292)
			(xy 62.7794 -389.939455) (xy 62.817521 -389.90833) (xy 62.860142 -389.883723) (xy 62.906158 -389.866271)
			(xy 62.954377 -389.856427) (xy 63.003552 -389.854446) (xy 63.052407 -389.860378) (xy 63.099678 -389.87407)
			(xy 63.14414 -389.895168) (xy 63.184643 -389.923124) (xy 63.220136 -389.957216) (xy 63.249701 -389.99656)
			(xy 63.272572 -390.040137) (xy 63.288156 -390.086818) (xy 63.296051 -390.135395) (xy 63.296546 -390.160002)
			(xy 63.885584 -390.160002) (xy 63.889544 -390.110948) (xy 63.901321 -390.063164) (xy 63.920612 -390.017888)
			(xy 63.946915 -389.976292) (xy 63.97955 -389.939455) (xy 64.017671 -389.90833) (xy 64.060292 -389.883723)
			(xy 64.106308 -389.866271) (xy 64.154527 -389.856427) (xy 64.203702 -389.854446) (xy 64.252557 -389.860378)
			(xy 64.299828 -389.87407) (xy 64.34429 -389.895168) (xy 64.384793 -389.923124) (xy 64.420286 -389.957216)
			(xy 64.449851 -389.99656) (xy 64.472722 -390.040137) (xy 64.488306 -390.086818) (xy 64.496201 -390.135395)
			(xy 64.496696 -390.160002) (xy 65.08548 -390.160002) (xy 65.08944 -390.110948) (xy 65.101217 -390.063164)
			(xy 65.120508 -390.017888) (xy 65.146811 -389.976292) (xy 65.179446 -389.939455) (xy 65.217567 -389.90833)
			(xy 65.260188 -389.883723) (xy 65.306204 -389.866271) (xy 65.354423 -389.856427) (xy 65.403598 -389.854446)
			(xy 65.452453 -389.860378) (xy 65.499724 -389.87407) (xy 65.544186 -389.895168) (xy 65.584689 -389.923124)
			(xy 65.620182 -389.957216) (xy 65.649747 -389.99656) (xy 65.672618 -390.040137) (xy 65.688202 -390.086818)
			(xy 65.696097 -390.135395) (xy 65.696592 -390.160002) (xy 65.696097 -390.184609) (xy 65.695873 -390.185989)
			(xy 66.41516 -390.185989) (xy 66.41516 -390.134015) (xy 66.42329 -390.08268) (xy 66.439351 -390.03325)
			(xy 66.462947 -389.98694) (xy 66.493497 -389.944892) (xy 66.530248 -389.908141) (xy 66.572296 -389.877591)
			(xy 66.618606 -389.853995) (xy 66.668036 -389.837934) (xy 66.719371 -389.829804) (xy 66.771345 -389.829804)
			(xy 66.82268 -389.837934) (xy 66.87211 -389.853995) (xy 66.91842 -389.877591) (xy 66.960468 -389.908141)
			(xy 66.997219 -389.944892) (xy 67.027769 -389.98694) (xy 67.051365 -390.03325) (xy 67.067426 -390.08268)
			(xy 67.075556 -390.134015) (xy 67.076066 -390.160002) (xy 67.075556 -390.185989) (xy 67.067426 -390.237324)
			(xy 67.051365 -390.286754) (xy 67.027769 -390.333064) (xy 66.997219 -390.375112) (xy 66.960468 -390.411863)
			(xy 66.91842 -390.442413) (xy 66.87211 -390.466009) (xy 66.82268 -390.48207) (xy 66.771345 -390.4902)
			(xy 66.719371 -390.4902) (xy 66.668036 -390.48207) (xy 66.618606 -390.466009) (xy 66.572296 -390.442413)
			(xy 66.530248 -390.411863) (xy 66.493497 -390.375112) (xy 66.462947 -390.333064) (xy 66.439351 -390.286754)
			(xy 66.42329 -390.237324) (xy 66.41516 -390.185989) (xy 65.695873 -390.185989) (xy 65.688202 -390.233186)
			(xy 65.672618 -390.279867) (xy 65.649747 -390.323444) (xy 65.620182 -390.362788) (xy 65.584689 -390.39688)
			(xy 65.544186 -390.424836) (xy 65.499724 -390.445934) (xy 65.452453 -390.459626) (xy 65.403598 -390.465558)
			(xy 65.354423 -390.463577) (xy 65.306204 -390.453733) (xy 65.260188 -390.436281) (xy 65.217567 -390.411674)
			(xy 65.179446 -390.380549) (xy 65.146811 -390.343712) (xy 65.120508 -390.302116) (xy 65.101217 -390.25684)
			(xy 65.08944 -390.209056) (xy 65.08548 -390.160002) (xy 64.496696 -390.160002) (xy 64.496201 -390.184609)
			(xy 64.488306 -390.233186) (xy 64.472722 -390.279867) (xy 64.449851 -390.323444) (xy 64.420286 -390.362788)
			(xy 64.384793 -390.39688) (xy 64.34429 -390.424836) (xy 64.299828 -390.445934) (xy 64.252557 -390.459626)
			(xy 64.203702 -390.465558) (xy 64.154527 -390.463577) (xy 64.106308 -390.453733) (xy 64.060292 -390.436281)
			(xy 64.017671 -390.411674) (xy 63.97955 -390.380549) (xy 63.946915 -390.343712) (xy 63.920612 -390.302116)
			(xy 63.901321 -390.25684) (xy 63.889544 -390.209056) (xy 63.885584 -390.160002) (xy 63.296546 -390.160002)
			(xy 63.296051 -390.184609) (xy 63.288156 -390.233186) (xy 63.272572 -390.279867) (xy 63.249701 -390.323444)
			(xy 63.220136 -390.362788) (xy 63.184643 -390.39688) (xy 63.14414 -390.424836) (xy 63.099678 -390.445934)
			(xy 63.052407 -390.459626) (xy 63.003552 -390.465558) (xy 62.954377 -390.463577) (xy 62.906158 -390.453733)
			(xy 62.860142 -390.436281) (xy 62.817521 -390.411674) (xy 62.7794 -390.380549) (xy 62.746765 -390.343712)
			(xy 62.720462 -390.302116) (xy 62.701171 -390.25684) (xy 62.689394 -390.209056) (xy 62.685434 -390.160002)
			(xy 62.09665 -390.160002) (xy 62.096155 -390.184609) (xy 62.08826 -390.233186) (xy 62.072676 -390.279867)
			(xy 62.049805 -390.323444) (xy 62.02024 -390.362788) (xy 61.984747 -390.39688) (xy 61.944244 -390.424836)
			(xy 61.899782 -390.445934) (xy 61.852511 -390.459626) (xy 61.803656 -390.465558) (xy 61.754481 -390.463577)
			(xy 61.706262 -390.453733) (xy 61.660246 -390.436281) (xy 61.617625 -390.411674) (xy 61.579504 -390.380549)
			(xy 61.546869 -390.343712) (xy 61.520566 -390.302116) (xy 61.501275 -390.25684) (xy 61.489498 -390.209056)
			(xy 61.485538 -390.160002) (xy 60.8965 -390.160002) (xy 60.896005 -390.184609) (xy 60.88811 -390.233186)
			(xy 60.872526 -390.279867) (xy 60.849655 -390.323444) (xy 60.82009 -390.362788) (xy 60.784597 -390.39688)
			(xy 60.744094 -390.424836) (xy 60.699632 -390.445934) (xy 60.652361 -390.459626) (xy 60.603506 -390.465558)
			(xy 60.554331 -390.463577) (xy 60.506112 -390.453733) (xy 60.460096 -390.436281) (xy 60.417475 -390.411674)
			(xy 60.379354 -390.380549) (xy 60.346719 -390.343712) (xy 60.320416 -390.302116) (xy 60.301125 -390.25684)
			(xy 60.289348 -390.209056) (xy 60.285388 -390.160002) (xy 59.696604 -390.160002) (xy 59.696109 -390.184609)
			(xy 59.688214 -390.233186) (xy 59.67263 -390.279867) (xy 59.649759 -390.323444) (xy 59.620194 -390.362788)
			(xy 59.584701 -390.39688) (xy 59.544198 -390.424836) (xy 59.499736 -390.445934) (xy 59.452465 -390.459626)
			(xy 59.40361 -390.465558) (xy 59.354435 -390.463577) (xy 59.306216 -390.453733) (xy 59.2602 -390.436281)
			(xy 59.217579 -390.411674) (xy 59.179458 -390.380549) (xy 59.146823 -390.343712) (xy 59.12052 -390.302116)
			(xy 59.101229 -390.25684) (xy 59.089452 -390.209056) (xy 59.085492 -390.160002) (xy 58.496708 -390.160002)
			(xy 58.496213 -390.184609) (xy 58.488318 -390.233186) (xy 58.472734 -390.279867) (xy 58.449863 -390.323444)
			(xy 58.420298 -390.362788) (xy 58.384805 -390.39688) (xy 58.344302 -390.424836) (xy 58.29984 -390.445934)
			(xy 58.252569 -390.459626) (xy 58.203714 -390.465558) (xy 58.154539 -390.463577) (xy 58.10632 -390.453733)
			(xy 58.060304 -390.436281) (xy 58.017683 -390.411674) (xy 57.979562 -390.380549) (xy 57.946927 -390.343712)
			(xy 57.920624 -390.302116) (xy 57.901333 -390.25684) (xy 57.889556 -390.209056) (xy 57.885596 -390.160002)
			(xy 57.296558 -390.160002) (xy 57.296063 -390.184609) (xy 57.288168 -390.233186) (xy 57.272584 -390.279867)
			(xy 57.249713 -390.323444) (xy 57.220148 -390.362788) (xy 57.184655 -390.39688) (xy 57.144152 -390.424836)
			(xy 57.09969 -390.445934) (xy 57.052419 -390.459626) (xy 57.003564 -390.465558) (xy 56.954389 -390.463577)
			(xy 56.90617 -390.453733) (xy 56.860154 -390.436281) (xy 56.817533 -390.411674) (xy 56.779412 -390.380549)
			(xy 56.746777 -390.343712) (xy 56.720474 -390.302116) (xy 56.701183 -390.25684) (xy 56.689406 -390.209056)
			(xy 56.685446 -390.160002) (xy 56.096662 -390.160002) (xy 56.096167 -390.184609) (xy 56.088272 -390.233186)
			(xy 56.072688 -390.279867) (xy 56.049817 -390.323444) (xy 56.020252 -390.362788) (xy 55.984759 -390.39688)
			(xy 55.944256 -390.424836) (xy 55.899794 -390.445934) (xy 55.852523 -390.459626) (xy 55.803668 -390.465558)
			(xy 55.754493 -390.463577) (xy 55.706274 -390.453733) (xy 55.660258 -390.436281) (xy 55.617637 -390.411674)
			(xy 55.579516 -390.380549) (xy 55.546881 -390.343712) (xy 55.520578 -390.302116) (xy 55.501287 -390.25684)
			(xy 55.48951 -390.209056) (xy 55.48555 -390.160002) (xy 54.896512 -390.160002) (xy 54.896017 -390.184609)
			(xy 54.888122 -390.233186) (xy 54.872538 -390.279867) (xy 54.849667 -390.323444) (xy 54.820102 -390.362788)
			(xy 54.784609 -390.39688) (xy 54.744106 -390.424836) (xy 54.699644 -390.445934) (xy 54.652373 -390.459626)
			(xy 54.603518 -390.465558) (xy 54.554343 -390.463577) (xy 54.506124 -390.453733) (xy 54.460108 -390.436281)
			(xy 54.417487 -390.411674) (xy 54.379366 -390.380549) (xy 54.346731 -390.343712) (xy 54.320428 -390.302116)
			(xy 54.301137 -390.25684) (xy 54.28936 -390.209056) (xy 54.2854 -390.160002) (xy 53.696616 -390.160002)
			(xy 53.696121 -390.184609) (xy 53.688226 -390.233186) (xy 53.672642 -390.279867) (xy 53.649771 -390.323444)
			(xy 53.620206 -390.362788) (xy 53.584713 -390.39688) (xy 53.54421 -390.424836) (xy 53.499748 -390.445934)
			(xy 53.452477 -390.459626) (xy 53.403622 -390.465558) (xy 53.354447 -390.463577) (xy 53.306228 -390.453733)
			(xy 53.260212 -390.436281) (xy 53.217591 -390.411674) (xy 53.17947 -390.380549) (xy 53.146835 -390.343712)
			(xy 53.120532 -390.302116) (xy 53.101241 -390.25684) (xy 53.089464 -390.209056) (xy 53.085504 -390.160002)
			(xy 52.49672 -390.160002) (xy 52.496225 -390.184609) (xy 52.48833 -390.233186) (xy 52.472746 -390.279867)
			(xy 52.449875 -390.323444) (xy 52.42031 -390.362788) (xy 52.384817 -390.39688) (xy 52.344314 -390.424836)
			(xy 52.299852 -390.445934) (xy 52.252581 -390.459626) (xy 52.203726 -390.465558) (xy 52.154551 -390.463577)
			(xy 52.106332 -390.453733) (xy 52.060316 -390.436281) (xy 52.017695 -390.411674) (xy 51.979574 -390.380549)
			(xy 51.946939 -390.343712) (xy 51.920636 -390.302116) (xy 51.901345 -390.25684) (xy 51.889568 -390.209056)
			(xy 51.885608 -390.160002) (xy 51.29657 -390.160002) (xy 51.296075 -390.184609) (xy 51.28818 -390.233186)
			(xy 51.272596 -390.279867) (xy 51.249725 -390.323444) (xy 51.22016 -390.362788) (xy 51.184667 -390.39688)
			(xy 51.144164 -390.424836) (xy 51.099702 -390.445934) (xy 51.052431 -390.459626) (xy 51.003576 -390.465558)
			(xy 50.954401 -390.463577) (xy 50.906182 -390.453733) (xy 50.860166 -390.436281) (xy 50.817545 -390.411674)
			(xy 50.779424 -390.380549) (xy 50.746789 -390.343712) (xy 50.720486 -390.302116) (xy 50.701195 -390.25684)
			(xy 50.689418 -390.209056) (xy 50.685458 -390.160002) (xy 50.096674 -390.160002) (xy 50.096179 -390.184609)
			(xy 50.088284 -390.233186) (xy 50.0727 -390.279867) (xy 50.049829 -390.323444) (xy 50.020264 -390.362788)
			(xy 49.984771 -390.39688) (xy 49.944268 -390.424836) (xy 49.899806 -390.445934) (xy 49.852535 -390.459626)
			(xy 49.80368 -390.465558) (xy 49.754505 -390.463577) (xy 49.706286 -390.453733) (xy 49.66027 -390.436281)
			(xy 49.617649 -390.411674) (xy 49.579528 -390.380549) (xy 49.546893 -390.343712) (xy 49.52059 -390.302116)
			(xy 49.501299 -390.25684) (xy 49.489522 -390.209056) (xy 49.485562 -390.160002) (xy 48.896524 -390.160002)
			(xy 48.896029 -390.184609) (xy 48.888134 -390.233186) (xy 48.87255 -390.279867) (xy 48.849679 -390.323444)
			(xy 48.820114 -390.362788) (xy 48.784621 -390.39688) (xy 48.744118 -390.424836) (xy 48.699656 -390.445934)
			(xy 48.652385 -390.459626) (xy 48.60353 -390.465558) (xy 48.554355 -390.463577) (xy 48.506136 -390.453733)
			(xy 48.46012 -390.436281) (xy 48.417499 -390.411674) (xy 48.379378 -390.380549) (xy 48.346743 -390.343712)
			(xy 48.32044 -390.302116) (xy 48.301149 -390.25684) (xy 48.289372 -390.209056) (xy 48.285412 -390.160002)
			(xy 47.696374 -390.160002) (xy 47.695879 -390.184609) (xy 47.687984 -390.233186) (xy 47.6724 -390.279867)
			(xy 47.649529 -390.323444) (xy 47.619964 -390.362788) (xy 47.584471 -390.39688) (xy 47.543968 -390.424836)
			(xy 47.499506 -390.445934) (xy 47.452235 -390.459626) (xy 47.40338 -390.465558) (xy 47.354205 -390.463577)
			(xy 47.305986 -390.453733) (xy 47.25997 -390.436281) (xy 47.217349 -390.411674) (xy 47.179228 -390.380549)
			(xy 47.146593 -390.343712) (xy 47.12029 -390.302116) (xy 47.100999 -390.25684) (xy 47.089222 -390.209056)
			(xy 47.085262 -390.160002) (xy 45.541761 -390.160002) (xy 45.540809 -390.166486) (xy 45.52167 -390.230278)
			(xy 45.493476 -390.290617) (xy 45.475652 -390.318752) (xy 45.470607 -390.327277) (xy 45.466789 -390.346693)
			(xy 45.470602 -390.366111) (xy 45.475652 -390.374632) (xy 45.493468 -390.40277) (xy 45.521642 -390.463115)
			(xy 45.540777 -390.526905) (xy 45.550469 -390.592793) (xy 45.55109 -390.626092) (xy 45.55109 -390.626346)
			(xy 45.550615 -390.655602) (xy 45.543157 -390.713637) (xy 45.528345 -390.770242) (xy 45.517816 -390.797542)
			(xy 45.514006 -390.80694) (xy 45.51426 -390.827514) (xy 45.551852 -390.913112) (xy 45.566838 -390.927082)
			(xy 45.57649 -390.930638) (xy 45.59985 -390.939841) (xy 45.643696 -390.964296) (xy 45.683343 -390.995098)
			(xy 45.717878 -391.031538) (xy 45.746509 -391.072779) (xy 45.768578 -391.117874) (xy 45.783578 -391.165786)
			(xy 45.791163 -391.215415) (xy 45.791628 -391.240518) (xy 45.791118 -391.266505) (xy 45.782988 -391.31784)
			(xy 45.766927 -391.36727) (xy 45.743331 -391.41358) (xy 45.712781 -391.455628) (xy 45.67603 -391.492379)
			(xy 45.633982 -391.522929) (xy 45.587672 -391.546525) (xy 45.538242 -391.562586) (xy 45.486907 -391.570716)
			(xy 45.434933 -391.570716) (xy 45.383598 -391.562586) (xy 45.334168 -391.546525) (xy 45.287858 -391.522929)
			(xy 45.24581 -391.492379) (xy 45.209059 -391.455628) (xy 45.178509 -391.41358) (xy 45.154913 -391.36727)
			(xy 45.138852 -391.31784) (xy 45.130722 -391.266505) (xy 45.130212 -391.240518) (xy 45.130314 -391.229307)
			(xy 45.13184 -391.206936) (xy 45.13326 -391.195814) (xy 45.13326 -391.19556) (xy 45.134174 -391.185491)
			(xy 45.128926 -391.165978) (xy 45.1231 -391.157714) (xy 45.071792 -391.092182) (xy 45.053758 -391.082022)
			(xy 45.043598 -391.081006) (xy 45.013419 -391.077136) (xy 44.954344 -391.062583) (xy 44.897719 -391.040329)
			(xy 44.844543 -391.010767) (xy 44.795754 -390.974417) (xy 44.752213 -390.931922) (xy 44.714689 -390.884031)
			(xy 44.683843 -390.831589) (xy 44.660219 -390.775521) (xy 44.644235 -390.716817) (xy 44.636173 -390.656513)
			(xy 44.635674 -390.626092) (xy 41.349168 -390.626092) (xy 41.349168 -391.047986) (xy 41.349611 -391.058016)
			(xy 41.35719 -391.076586) (xy 41.3639 -391.084054) (xy 41.382442 -391.102342) (xy 41.389808 -391.109182)
			(xy 41.408341 -391.116924) (xy 41.428425 -391.116924) (xy 41.446958 -391.109182) (xy 41.454324 -391.102342)
			(xy 41.46169 -391.094976) (xy 41.4655 -391.08507) (xy 41.476378 -391.058595) (xy 41.504907 -391.008976)
			(xy 41.540521 -390.964169) (xy 41.582422 -390.925179) (xy 41.629672 -390.892878) (xy 41.681213 -390.867989)
			(xy 41.735892 -390.85107) (xy 41.792482 -390.842499) (xy 41.8211 -390.841992) (xy 41.848351 -390.842478)
			(xy 41.902299 -390.850234) (xy 41.954594 -390.865589) (xy 42.004171 -390.888231) (xy 42.050021 -390.917697)
			(xy 42.091212 -390.953388) (xy 42.126903 -390.994579) (xy 42.156369 -391.040429) (xy 42.179011 -391.090006)
			(xy 42.194366 -391.142301) (xy 42.202122 -391.196249) (xy 42.202608 -391.2235) (xy 42.202083 -391.251948)
			(xy 42.193635 -391.308213) (xy 42.176928 -391.3626) (xy 42.15233 -391.413904) (xy 42.120388 -391.460987)
			(xy 42.081809 -391.502806) (xy 42.037449 -391.538433) (xy 42.013124 -391.553192) (xy 42.002964 -391.559034)
			(xy 41.989756 -391.578846) (xy 41.978072 -391.670032) (xy 41.977138 -391.681748) (xy 41.984673 -391.703983)
			(xy 41.99255 -391.712704) (xy 42.191646 -391.9118) (xy 42.729408 -391.9118) (xy 42.733422 -391.848005)
			(xy 42.7454 -391.785216) (xy 42.765153 -391.724423) (xy 42.79237 -391.666586) (xy 42.826622 -391.612616)
			(xy 42.867368 -391.563364) (xy 42.913965 -391.519608) (xy 42.96568 -391.482037) (xy 43.021695 -391.451245)
			(xy 43.081128 -391.427715) (xy 43.143042 -391.411821) (xy 43.206459 -391.403812) (xy 43.23842 -391.403332)
			(xy 43.270233 -391.40381) (xy 43.333362 -391.41176) (xy 43.395005 -391.42752) (xy 43.454203 -391.450846)
			(xy 43.510028 -391.481372) (xy 43.536108 -391.499598) (xy 43.544126 -391.504813) (xy 43.562645 -391.509527)
			(xy 43.572176 -391.508742) (xy 43.650916 -391.498582) (xy 43.667934 -391.489184) (xy 43.67403 -391.481818)
			(xy 43.694759 -391.45739) (xy 43.741383 -391.413447) (xy 43.793159 -391.37571) (xy 43.849267 -391.344779)
			(xy 43.908816 -391.321143) (xy 43.970864 -391.305177) (xy 44.034426 -391.297134) (xy 44.06646 -391.296652)
			(xy 44.098421 -391.29721) (xy 44.161841 -391.305218) (xy 44.223757 -391.32111) (xy 44.283192 -391.344638)
			(xy 44.33921 -391.375431) (xy 44.390926 -391.413001) (xy 44.437526 -391.456757) (xy 44.478273 -391.506009)
			(xy 44.512526 -391.55998) (xy 44.539745 -391.617819) (xy 44.559499 -391.678613) (xy 44.571478 -391.741403)
			(xy 44.575492 -391.8052) (xy 44.571478 -391.868997) (xy 44.559499 -391.931787) (xy 44.539745 -391.992581)
			(xy 44.512526 -392.05042) (xy 44.478273 -392.104391) (xy 44.437526 -392.153643) (xy 44.390926 -392.197399)
			(xy 44.33921 -392.234969) (xy 44.283192 -392.265762) (xy 44.223757 -392.28929) (xy 44.161841 -392.305182)
			(xy 44.098421 -392.31319) (xy 44.06646 -392.313668) (xy 44.034648 -392.313148) (xy 43.971521 -392.305208)
			(xy 43.909878 -392.289457) (xy 43.85068 -392.266141) (xy 43.794853 -392.235624) (xy 43.768772 -392.217402)
			(xy 43.76076 -392.212177) (xy 43.742236 -392.207469) (xy 43.732704 -392.208258) (xy 43.653964 -392.218418)
			(xy 43.636946 -392.227816) (xy 43.63085 -392.235182) (xy 43.610132 -392.25962) (xy 43.563506 -392.303563)
			(xy 43.520713 -392.33475) (xy 46.164246 -392.33475) (xy 46.164645 -392.311516) (xy 46.171144 -392.265506)
			(xy 46.18402 -392.220859) (xy 46.203021 -392.178454) (xy 46.227772 -392.139127) (xy 46.242478 -392.121136)
			(xy 46.24832 -392.114278) (xy 46.25467 -392.09726) (xy 46.25467 -392.01344) (xy 46.24832 -391.996422)
			(xy 46.242478 -391.989564) (xy 46.227797 -391.971553) (xy 46.203044 -391.932231) (xy 46.184038 -391.889831)
			(xy 46.171153 -391.845189) (xy 46.164643 -391.799182) (xy 46.164246 -391.77595) (xy 46.164756 -391.749963)
			(xy 46.172886 -391.698628) (xy 46.188947 -391.649198) (xy 46.212543 -391.602888) (xy 46.243093 -391.56084)
			(xy 46.279844 -391.524089) (xy 46.321892 -391.493539) (xy 46.368202 -391.469943) (xy 46.417632 -391.453882)
			(xy 46.468967 -391.445752) (xy 46.520941 -391.445752) (xy 46.572276 -391.453882) (xy 46.621706 -391.469943)
			(xy 46.668016 -391.493539) (xy 46.710064 -391.524089) (xy 46.746815 -391.56084) (xy 46.777365 -391.602888)
			(xy 46.800961 -391.649198) (xy 46.817022 -391.698628) (xy 46.825152 -391.749963) (xy 46.825662 -391.77595)
			(xy 46.825261 -391.799184) (xy 46.818763 -391.845194) (xy 46.805886 -391.889841) (xy 46.786886 -391.932246)
			(xy 46.762136 -391.971573) (xy 46.74743 -391.989564) (xy 46.741588 -391.996422) (xy 46.735238 -392.01344)
			(xy 46.735238 -392.09726) (xy 46.741588 -392.114278) (xy 46.74743 -392.121136) (xy 46.762113 -392.139146)
			(xy 46.786865 -392.178468) (xy 46.805871 -392.220869) (xy 46.818755 -392.265511) (xy 46.825265 -392.311518)
			(xy 46.825662 -392.33475) (xy 46.825152 -392.360737) (xy 46.817022 -392.412072) (xy 46.800961 -392.461502)
			(xy 46.777365 -392.507812) (xy 46.746815 -392.54986) (xy 46.710064 -392.586611) (xy 46.668016 -392.617161)
			(xy 46.621706 -392.640757) (xy 46.572276 -392.656818) (xy 46.520941 -392.664948) (xy 46.468967 -392.664948)
			(xy 46.417632 -392.656818) (xy 46.368202 -392.640757) (xy 46.321892 -392.617161) (xy 46.279844 -392.586611)
			(xy 46.243093 -392.54986) (xy 46.212543 -392.507812) (xy 46.188947 -392.461502) (xy 46.172886 -392.412072)
			(xy 46.164756 -392.360737) (xy 46.164246 -392.33475) (xy 43.520713 -392.33475) (xy 43.511728 -392.341298)
			(xy 43.455619 -392.372228) (xy 43.396067 -392.395862) (xy 43.334018 -392.411826) (xy 43.270455 -392.419867)
			(xy 43.23842 -392.420348) (xy 43.206459 -392.419788) (xy 43.143042 -392.411779) (xy 43.081128 -392.395885)
			(xy 43.021695 -392.372355) (xy 42.96568 -392.341563) (xy 42.913965 -392.303992) (xy 42.867368 -392.260236)
			(xy 42.826622 -392.210984) (xy 42.79237 -392.157014) (xy 42.765153 -392.099177) (xy 42.7454 -392.038384)
			(xy 42.733422 -391.975595) (xy 42.729408 -391.9118) (xy 42.191646 -391.9118) (xy 43.572938 -393.293092)
			(xy 47.435008 -393.293092) (xy 47.435008 -392.428984) (xy 47.435475 -392.402659) (xy 47.442728 -392.350509)
			(xy 47.45708 -392.299852) (xy 47.478259 -392.251648) (xy 47.505862 -392.206813) (xy 47.539367 -392.166198)
			(xy 47.558452 -392.14806) (xy 47.564998 -392.141447) (xy 47.573208 -392.124769) (xy 47.574454 -392.115548)
			(xy 47.58182 -392.038332) (xy 47.576994 -392.020298) (xy 47.57166 -392.012932) (xy 47.571152 -392.012424)
			(xy 47.557036 -391.992602) (xy 47.53464 -391.9494) (xy 47.519391 -391.90319) (xy 47.511676 -391.855145)
			(xy 47.511208 -391.830814) (xy 47.51173 -391.805559) (xy 47.520043 -391.755737) (xy 47.536444 -391.707963)
			(xy 47.560485 -391.66354) (xy 47.591509 -391.62368) (xy 47.628671 -391.58947) (xy 47.670957 -391.561844)
			(xy 47.717213 -391.541554) (xy 47.766178 -391.529154) (xy 47.816516 -391.524983) (xy 47.866854 -391.529154)
			(xy 47.915819 -391.541554) (xy 47.962075 -391.561844) (xy 48.004361 -391.58947) (xy 48.041523 -391.62368)
			(xy 48.072547 -391.66354) (xy 48.096588 -391.707963) (xy 48.112989 -391.755737) (xy 48.121302 -391.805559)
			(xy 48.121824 -391.830814) (xy 48.121351 -391.855187) (xy 48.113591 -391.90331) (xy 48.098272 -391.949586)
			(xy 48.075784 -391.992834) (xy 48.061626 -392.012678) (xy 48.061372 -392.012932) (xy 48.056286 -392.020583)
			(xy 48.051481 -392.038301) (xy 48.051974 -392.047476) (xy 48.05934 -392.124946) (xy 48.067722 -392.14171)
			(xy 48.07458 -392.14806) (xy 48.093685 -392.166181) (xy 48.127208 -392.206788) (xy 48.154823 -392.251623)
			(xy 48.176005 -392.299832) (xy 48.19035 -392.350498) (xy 48.197586 -392.402655) (xy 48.198024 -392.428984)
			(xy 48.198024 -393.293092) (xy 48.197456 -393.323216) (xy 48.187975 -393.382712) (xy 48.169264 -393.439981)
			(xy 48.141788 -393.493598) (xy 48.106228 -393.542232) (xy 48.085248 -393.563856) (xy 48.078644 -393.57046)
			(xy 48.071024 -393.587224) (xy 48.066198 -393.663932) (xy 48.066022 -393.673209) (xy 48.071477 -393.690924)
			(xy 48.076866 -393.698476) (xy 48.093373 -393.720464) (xy 48.119648 -393.768757) (xy 48.137579 -393.820729)
			(xy 48.146675 -393.874949) (xy 48.147224 -393.902438) (xy 48.146714 -393.928425) (xy 48.138584 -393.97976)
			(xy 48.122523 -394.02919) (xy 48.098927 -394.0755) (xy 48.068377 -394.117548) (xy 48.031626 -394.154299)
			(xy 47.989578 -394.184849) (xy 47.943268 -394.208445) (xy 47.893838 -394.224506) (xy 47.842503 -394.232636)
			(xy 47.790529 -394.232636) (xy 47.739194 -394.224506) (xy 47.689764 -394.208445) (xy 47.643454 -394.184849)
			(xy 47.601406 -394.154299) (xy 47.564655 -394.117548) (xy 47.534105 -394.0755) (xy 47.510509 -394.02919)
			(xy 47.494448 -393.97976) (xy 47.486318 -393.928425) (xy 47.485808 -393.902438) (xy 47.486359 -393.874947)
			(xy 47.495435 -393.820721) (xy 47.513361 -393.768745) (xy 47.539641 -393.720452) (xy 47.556166 -393.698476)
			(xy 47.56155 -393.69092) (xy 47.567025 -393.673208) (xy 47.566834 -393.663932) (xy 47.562008 -393.587224)
			(xy 47.554388 -393.57046) (xy 47.547784 -393.563856) (xy 47.526803 -393.542232) (xy 47.491235 -393.493603)
			(xy 47.463756 -393.439986) (xy 47.445048 -393.382716) (xy 47.435576 -393.323216) (xy 47.435008 -393.293092)
			(xy 43.572938 -393.293092) (xy 45.843444 -395.563598) (xy 45.850297 -395.570994) (xy 45.858041 -395.589592)
			(xy 45.85843 -395.599666) (xy 45.85843 -398.575784) (xy 45.859446 -398.58061) (xy 45.863641 -398.604198)
			(xy 45.868098 -398.651903) (xy 45.868336 -398.67586) (xy 45.868083 -398.699816) (xy 45.863631 -398.747521)
			(xy 45.859446 -398.77111) (xy 45.85843 -398.775936) (xy 45.85843 -399.312384) (xy 45.859446 -399.31721)
			(xy 45.863641 -399.340798) (xy 45.868098 -399.388503) (xy 45.868336 -399.41246) (xy 45.868083 -399.436416)
			(xy 45.863631 -399.484121) (xy 45.859446 -399.50771) (xy 45.85843 -399.512536) (xy 45.85843 -399.729452)
			(xy 45.858978 -399.739809) (xy 45.867238 -399.758811) (xy 45.874432 -399.766282) (xy 45.928026 -399.817082)
			(xy 45.935942 -399.823822) (xy 45.955474 -399.830884) (xy 45.965872 -399.830798) (xy 45.966126 -399.830798)
			(xy 45.996098 -399.829782) (xy 46.028061 -399.830263) (xy 46.091483 -399.838275) (xy 46.153401 -399.854172)
			(xy 46.212838 -399.877705) (xy 46.268857 -399.908501) (xy 46.320574 -399.946076) (xy 46.367175 -399.989836)
			(xy 46.407923 -400.039092) (xy 46.442176 -400.093067) (xy 46.469395 -400.150909) (xy 46.489149 -400.211706)
			(xy 46.501128 -400.2745) (xy 46.505142 -400.3383) (xy 46.501128 -400.4021) (xy 46.489149 -400.464894)
			(xy 46.469395 -400.525691) (xy 46.442176 -400.583533) (xy 46.407923 -400.637508) (xy 46.367175 -400.686764)
			(xy 46.320574 -400.730524) (xy 46.268857 -400.768099) (xy 46.212838 -400.798895) (xy 46.153401 -400.822428)
			(xy 46.091483 -400.838325) (xy 46.028061 -400.846337) (xy 45.996098 -400.846798) (xy 45.96638 -400.845782)
			(xy 45.965872 -400.845782) (xy 45.955469 -400.845649) (xy 45.935926 -400.852728) (xy 45.928026 -400.859498)
			(xy 45.874432 -400.910298) (xy 45.867207 -400.917747) (xy 45.858948 -400.936763) (xy 45.85843 -400.947128)
			(xy 45.85843 -401.430236) (xy 45.859008 -401.44182) (xy 45.869159 -401.462648) (xy 45.88737 -401.476973)
			(xy 45.898562 -401.48002) (xy 45.898816 -401.48002) (xy 45.929569 -401.486971) (xy 45.989194 -401.507473)
			(xy 46.045825 -401.53519) (xy 46.098596 -401.569697) (xy 46.146694 -401.610463) (xy 46.189384 -401.656864)
			(xy 46.226008 -401.708187) (xy 46.256006 -401.763645) (xy 46.278917 -401.822386) (xy 46.294388 -401.883509)
			(xy 46.302184 -401.946076) (xy 46.302184 -402.009127) (xy 46.294388 -402.071694) (xy 46.278916 -402.132817)
			(xy 46.256005 -402.191557) (xy 46.226007 -402.247015) (xy 46.189382 -402.298338) (xy 46.146693 -402.344738)
			(xy 46.098594 -402.385505) (xy 46.045823 -402.420011) (xy 45.989191 -402.447728) (xy 45.929567 -402.46823)
			(xy 45.898816 -402.475192) (xy 45.898562 -402.475192) (xy 45.887335 -402.478164) (xy 45.869082 -402.492483)
			(xy 45.85899 -402.513373) (xy 45.85843 -402.524976) (xy 45.85843 -410.100018) (xy 45.858004 -410.110087)
			(xy 45.850289 -410.12869) (xy 45.843444 -410.136086) (xy 44.704508 -411.275022) (xy 44.697664 -411.282421)
			(xy 44.689937 -411.301019) (xy 44.689522 -411.31109) (xy 44.689522 -413.279844) (xy 44.689954 -413.28991)
			(xy 44.697682 -413.308501) (xy 44.704508 -413.315912) (xy 44.90974 -413.521144) (xy 44.931936 -413.543936)
			(xy 44.971616 -413.593668) (xy 45.005477 -413.647532) (xy 45.033093 -413.704849) (xy 45.054115 -413.764898)
			(xy 45.068281 -413.826923) (xy 45.075411 -413.890145) (xy 45.075856 -413.921956) (xy 45.075856 -421.653208)
			(xy 45.076345 -421.663218) (xy 45.084004 -421.681714) (xy 45.098155 -421.695876) (xy 45.116647 -421.703548)
			(xy 45.126656 -421.704008)
		)
		(stroke
			(width 0)
			(type solid)
		)
		(fill yes)
		(layer "In11.Cu")
		(net "P1V8_CPU1_RT_1D")
	)
	(gr_poly
		(pts
			(xy 32.638238 -366.275366) (xy 32.648304 -366.274935) (xy 32.666896 -366.267207) (xy 32.674306 -366.26038)
			(xy 32.747712 -366.186974) (xy 32.754564 -366.179578) (xy 32.762303 -366.160979) (xy 32.762698 -366.150906)
			(xy 32.762698 -361.789726) (xy 32.762261 -361.779662) (xy 32.754528 -361.761077) (xy 32.747712 -361.753658)
			(xy 32.414972 -361.420918) (xy 32.407573 -361.414074) (xy 32.388975 -361.406347) (xy 32.378904 -361.405932)
			(xy 28.742894 -361.405932) (xy 28.732825 -361.406357) (xy 28.714225 -361.414076) (xy 28.706826 -361.420918)
			(xy 28.684982 -361.442762) (xy 28.677584 -361.44961) (xy 28.658986 -361.457344) (xy 28.648914 -361.457748)
			(xy 28.173172 -361.457748) (xy 28.163105 -361.457318) (xy 28.144513 -361.449591) (xy 28.137104 -361.442762)
			(xy 25.6286 -358.934258) (xy 25.62176 -358.926857) (xy 25.614041 -358.908259) (xy 25.613614 -358.89819)
			(xy 25.613614 -356.298246) (xy 25.613182 -356.28818) (xy 25.605455 -356.269588) (xy 25.598628 -356.262178)
			(xy 22.520402 -353.183952) (xy 22.513563 -353.176551) (xy 22.505846 -353.157953) (xy 22.505416 -353.147884)
			(xy 22.505416 -350.111822) (xy 22.505832 -350.101799) (xy 22.513498 -350.083277) (xy 22.527672 -350.069102)
			(xy 22.546193 -350.061433) (xy 22.556216 -350.061022) (xy 22.591776 -350.061022) (xy 22.601841 -350.060586)
			(xy 22.620427 -350.052854) (xy 22.627844 -350.046036) (xy 23.372318 -349.301308) (xy 23.379174 -349.293914)
			(xy 23.386925 -349.275315) (xy 23.387304 -349.26524) (xy 23.387304 -346.742004) (xy 23.387207 -346.736986)
			(xy 23.385279 -346.727137) (xy 23.383494 -346.722446) (xy 23.174706 -346.218256) (xy 23.172697 -346.213693)
			(xy 23.167195 -346.205382) (xy 23.163784 -346.201746) (xy 18.84807 -341.886032) (xy 18.830851 -341.867921)
			(xy 18.803118 -341.826359) (xy 18.784016 -341.78019) (xy 18.774278 -341.731183) (xy 18.773648 -341.7062)
			(xy 18.773648 -333.41437) (xy 18.774262 -333.389388) (xy 18.784008 -333.340383) (xy 18.803121 -333.294218)
			(xy 18.830866 -333.252665) (xy 18.84807 -333.234538) (xy 19.800824 -332.281784) (xy 19.818922 -332.264534)
			(xy 19.860471 -332.236738) (xy 19.906641 -332.217575) (xy 19.955662 -332.207782) (xy 19.980656 -332.207108)
			(xy 20.399248 -332.207108) (xy 20.400264 -332.207108) (xy 20.62734 -332.203044) (xy 20.637373 -332.202391)
			(xy 20.655804 -332.194412) (xy 20.663154 -332.18755) (xy 20.681442 -332.1685) (xy 20.688808 -332.149704)
			(xy 20.688554 -332.139544) (xy 20.688554 -332.132178) (xy 20.68904 -332.104927) (xy 20.696796 -332.050979)
			(xy 20.712151 -331.998684) (xy 20.734793 -331.949107) (xy 20.764259 -331.903257) (xy 20.79995 -331.862066)
			(xy 20.841141 -331.826375) (xy 20.886991 -331.796909) (xy 20.936568 -331.774267) (xy 20.988863 -331.758912)
			(xy 21.042811 -331.751156) (xy 21.097313 -331.751156) (xy 21.151261 -331.758912) (xy 21.203556 -331.774267)
			(xy 21.253133 -331.796909) (xy 21.298983 -331.826375) (xy 21.340174 -331.862066) (xy 21.375865 -331.903257)
			(xy 21.405331 -331.949107) (xy 21.427973 -331.998684) (xy 21.443328 -332.050979) (xy 21.451084 -332.104927)
			(xy 21.45157 -332.132178) (xy 21.451099 -332.159151) (xy 21.44349 -332.212556) (xy 21.428435 -332.264358)
			(xy 21.406234 -332.313523) (xy 21.37733 -332.359072) (xy 21.342299 -332.400095) (xy 21.301839 -332.435775)
			(xy 21.256757 -332.465401) (xy 21.207952 -332.488382) (xy 21.156396 -332.504261) (xy 21.103119 -332.512719)
			(xy 21.076158 -332.513686) (xy 21.065998 -332.513686) (xy 21.047456 -332.521814) (xy 20.965922 -332.606142)
			(xy 20.959328 -332.613686) (xy 20.952009 -332.632316) (xy 20.952376 -332.652329) (xy 20.960373 -332.670678)
			(xy 20.967192 -332.678024) (xy 21.05152 -332.759558) (xy 21.070316 -332.766924) (xy 21.080476 -332.76667)
			(xy 21.087842 -332.76667) (xy 21.115093 -332.767156) (xy 21.169041 -332.774913) (xy 21.221336 -332.790268)
			(xy 21.270913 -332.812909) (xy 21.316764 -332.842376) (xy 21.357954 -332.878068) (xy 21.393645 -332.919258)
			(xy 21.423111 -332.965109) (xy 21.445753 -333.014686) (xy 21.461108 -333.066981) (xy 21.468864 -333.120929)
			(xy 21.468864 -333.175431) (xy 21.461108 -333.229379) (xy 21.445753 -333.281674) (xy 21.423111 -333.331251)
			(xy 21.393645 -333.377102) (xy 21.357954 -333.418292) (xy 21.316764 -333.453984) (xy 21.270913 -333.483451)
			(xy 21.221336 -333.506092) (xy 21.169041 -333.521447) (xy 21.115093 -333.529204) (xy 21.087842 -333.529686)
			(xy 21.060868 -333.529216) (xy 21.007459 -333.52161) (xy 20.955654 -333.506557) (xy 20.906486 -333.484357)
			(xy 20.860934 -333.455454) (xy 20.819907 -333.420423) (xy 20.784223 -333.379963) (xy 20.754593 -333.33488)
			(xy 20.731609 -333.286074) (xy 20.715728 -333.234516) (xy 20.707266 -333.181236) (xy 20.706334 -333.154274)
			(xy 20.706334 -333.144114) (xy 20.698206 -333.125572) (xy 20.679156 -333.10703) (xy 20.671626 -333.100348)
			(xy 20.652898 -333.093004) (xy 20.642834 -333.092806) (xy 20.41017 -333.09687) (xy 20.405598 -333.097124)
			(xy 20.265136 -333.097124) (xy 20.255071 -333.097559) (xy 20.236486 -333.105293) (xy 20.229068 -333.11211)
			(xy 19.678142 -333.662782) (xy 19.671304 -333.670183) (xy 19.663593 -333.688782) (xy 19.663156 -333.69885)
			(xy 19.663156 -337.886548) (xy 67.302378 -337.886548) (xy 67.306449 -337.830926) (xy 67.318575 -337.776489)
			(xy 67.338498 -337.724398) (xy 67.365794 -337.675763) (xy 67.39988 -337.63162) (xy 67.440029 -337.592911)
			(xy 67.485387 -337.56046) (xy 67.534987 -337.534959) (xy 67.587771 -337.516952) (xy 67.642614 -337.506822)
			(xy 67.698348 -337.504785) (xy 67.753785 -337.510885) (xy 67.807742 -337.524991) (xy 67.859071 -337.546803)
			(xy 67.906677 -337.575857) (xy 67.949545 -337.611532) (xy 67.986762 -337.653069) (xy 68.017535 -337.699582)
			(xy 68.041207 -337.750079) (xy 68.057275 -337.803486) (xy 68.065395 -337.858662) (xy 68.065904 -337.886548)
			(xy 68.065395 -337.914434) (xy 68.057275 -337.96961) (xy 68.041207 -338.023017) (xy 68.017535 -338.073514)
			(xy 67.986762 -338.120027) (xy 67.949545 -338.161564) (xy 67.906677 -338.197239) (xy 67.859071 -338.226293)
			(xy 67.807742 -338.248105) (xy 67.753785 -338.262211) (xy 67.698348 -338.268311) (xy 67.642614 -338.266274)
			(xy 67.587771 -338.256144) (xy 67.534987 -338.238137) (xy 67.485387 -338.212636) (xy 67.440029 -338.180185)
			(xy 67.39988 -338.141476) (xy 67.365794 -338.097333) (xy 67.338498 -338.048698) (xy 67.318575 -337.996607)
			(xy 67.306449 -337.94217) (xy 67.302378 -337.886548) (xy 19.663156 -337.886548) (xy 19.663156 -338.781898)
			(xy 66.723258 -338.781898) (xy 66.727329 -338.726276) (xy 66.739455 -338.671839) (xy 66.759378 -338.619748)
			(xy 66.786674 -338.571113) (xy 66.82076 -338.52697) (xy 66.860909 -338.488261) (xy 66.906267 -338.45581)
			(xy 66.955867 -338.430309) (xy 67.008651 -338.412302) (xy 67.063494 -338.402172) (xy 67.119228 -338.400135)
			(xy 67.174665 -338.406235) (xy 67.228622 -338.420341) (xy 67.279951 -338.442153) (xy 67.327557 -338.471207)
			(xy 67.370425 -338.506882) (xy 67.407642 -338.548419) (xy 67.438415 -338.594932) (xy 67.462087 -338.645429)
			(xy 67.478155 -338.698836) (xy 67.486275 -338.754012) (xy 67.486784 -338.781898) (xy 67.486275 -338.809784)
			(xy 67.478155 -338.86496) (xy 67.462087 -338.918367) (xy 67.438415 -338.968864) (xy 67.407642 -339.015377)
			(xy 67.370425 -339.056914) (xy 67.327557 -339.092589) (xy 67.279951 -339.121643) (xy 67.228622 -339.143455)
			(xy 67.174665 -339.157561) (xy 67.119228 -339.163661) (xy 67.063494 -339.161624) (xy 67.008651 -339.151494)
			(xy 66.955867 -339.133487) (xy 66.906267 -339.107986) (xy 66.860909 -339.075535) (xy 66.82076 -339.036826)
			(xy 66.786674 -338.992683) (xy 66.759378 -338.944048) (xy 66.739455 -338.891957) (xy 66.727329 -338.83752)
			(xy 66.723258 -338.781898) (xy 19.663156 -338.781898) (xy 19.663156 -339.457538) (xy 68.062094 -339.457538)
			(xy 68.062604 -339.430064) (xy 68.070491 -339.375686) (xy 68.086105 -339.323004) (xy 68.109124 -339.273111)
			(xy 68.139071 -339.227041) (xy 68.156836 -339.206078) (xy 68.15709 -339.205824) (xy 68.162672 -339.198734)
			(xy 68.168922 -339.18182) (xy 68.169282 -339.172804) (xy 68.169282 -339.10524) (xy 68.16891 -339.096225)
			(xy 68.162673 -339.079307) (xy 68.15709 -339.07222) (xy 68.156582 -339.071712) (xy 68.138855 -339.05076)
			(xy 68.108972 -339.004729) (xy 68.086005 -338.954885) (xy 68.070429 -338.902261) (xy 68.062566 -338.847946)
			(xy 68.062094 -338.820506) (xy 68.06258 -338.793255) (xy 68.070336 -338.739307) (xy 68.085691 -338.687012)
			(xy 68.108333 -338.637435) (xy 68.137799 -338.591585) (xy 68.17349 -338.550394) (xy 68.214681 -338.514703)
			(xy 68.260531 -338.485237) (xy 68.310108 -338.462595) (xy 68.362403 -338.44724) (xy 68.416351 -338.439484)
			(xy 68.470853 -338.439484) (xy 68.524801 -338.44724) (xy 68.577096 -338.462595) (xy 68.626673 -338.485237)
			(xy 68.672523 -338.514703) (xy 68.713714 -338.550394) (xy 68.749405 -338.591585) (xy 68.778871 -338.637435)
			(xy 68.801513 -338.687012) (xy 68.816868 -338.739307) (xy 68.824624 -338.793255) (xy 68.82511 -338.820506)
			(xy 68.824625 -338.847981) (xy 68.816732 -338.90236) (xy 68.801112 -338.955042) (xy 68.798477 -338.960751)
			(xy 69.066891 -338.960751) (xy 69.066891 -338.906249) (xy 69.074648 -338.852301) (xy 69.090004 -338.800007)
			(xy 69.112645 -338.75043) (xy 69.142112 -338.704581) (xy 69.177804 -338.663392) (xy 69.218995 -338.627701)
			(xy 69.264846 -338.598237) (xy 69.314424 -338.575597) (xy 69.366719 -338.560244) (xy 69.420667 -338.55249)
			(xy 69.447918 -338.552028) (xy 69.448172 -338.552028) (xy 69.473375 -338.552441) (xy 69.523343 -338.559077)
			(xy 69.571997 -338.57225) (xy 69.618487 -338.591728) (xy 69.64045 -338.604098) (xy 69.650356 -338.60994)
			(xy 69.6722 -338.611972) (xy 69.766942 -338.578444) (xy 69.78269 -338.56295) (xy 69.786754 -338.552536)
			(xy 69.797438 -338.525755) (xy 69.82573 -338.475516) (xy 69.861264 -338.430108) (xy 69.903228 -338.390568)
			(xy 69.950666 -338.357795) (xy 70.002498 -338.332538) (xy 70.057541 -338.315371) (xy 70.114541 -338.306687)
			(xy 70.14337 -338.306156) (xy 70.170619 -338.306706) (xy 70.224562 -338.314458) (xy 70.276854 -338.329807)
			(xy 70.326428 -338.352442) (xy 70.372277 -338.381902) (xy 70.413467 -338.417587) (xy 70.449159 -338.45877)
			(xy 70.478626 -338.504614) (xy 70.50127 -338.554184) (xy 70.513991 -338.597494) (xy 72.654922 -338.597494)
			(xy 72.655376 -338.569919) (xy 72.66333 -338.515345) (xy 72.679057 -338.462485) (xy 72.702229 -338.412439)
			(xy 72.732364 -338.366249) (xy 72.768834 -338.324879) (xy 72.789542 -338.306664) (xy 72.79764 -338.29913)
			(xy 72.80698 -338.279102) (xy 72.807576 -338.268056) (xy 72.807576 -338.190332) (xy 72.806997 -338.179284)
			(xy 72.79764 -338.159262) (xy 72.789542 -338.151724) (xy 72.768848 -338.133494) (xy 72.732374 -338.092131)
			(xy 72.702239 -338.045945) (xy 72.67907 -337.9959) (xy 72.66335 -337.943041) (xy 72.655408 -337.888468)
			(xy 72.654922 -337.860894) (xy 72.65535 -337.83364) (xy 72.663108 -337.779686) (xy 72.678467 -337.727386)
			(xy 72.701112 -337.677803) (xy 72.730584 -337.631949) (xy 72.766281 -337.590755) (xy 72.807478 -337.555062)
			(xy 72.853335 -337.525595) (xy 72.902919 -337.502954) (xy 72.955221 -337.487601) (xy 73.009176 -337.479847)
			(xy 73.03643 -337.479386) (xy 73.036938 -337.479386) (xy 73.07072 -337.48091) (xy 73.08088 -337.481926)
			(xy 73.100184 -337.47583) (xy 73.163176 -337.422998) (xy 73.170481 -337.416288) (xy 73.179755 -337.398774)
			(xy 73.18121 -337.388962) (xy 73.18121 -337.3882) (xy 73.184175 -337.360053) (xy 73.197368 -337.305015)
			(xy 73.21855 -337.252531) (xy 73.247257 -337.203755) (xy 73.282858 -337.159757) (xy 73.32457 -337.121505)
			(xy 73.371479 -337.089837) (xy 73.422553 -337.065451) (xy 73.47667 -337.048882) (xy 73.532642 -337.040493)
			(xy 73.56094 -337.039966) (xy 73.561194 -337.039966) (xy 73.579213 -337.040192) (xy 73.615088 -337.043623)
			(xy 73.632822 -337.046824) (xy 73.642474 -337.048602) (xy 73.661524 -337.045046) (xy 73.736454 -336.99704)
			(xy 73.747884 -336.981292) (xy 73.75017 -336.971894) (xy 73.757635 -336.94487) (xy 73.779256 -336.893146)
			(xy 73.808211 -336.845141) (xy 73.843878 -336.801889) (xy 73.885489 -336.76432) (xy 73.932148 -336.733243)
			(xy 73.982851 -336.709327) (xy 74.036508 -336.693085) (xy 74.091964 -336.684868) (xy 74.119994 -336.684366)
			(xy 74.147244 -336.684883) (xy 74.201189 -336.692638) (xy 74.253482 -336.707991) (xy 74.303057 -336.73063)
			(xy 74.348906 -336.760093) (xy 74.390096 -336.795781) (xy 74.425788 -336.836968) (xy 74.455255 -336.882815)
			(xy 74.477897 -336.932388) (xy 74.493255 -336.98468) (xy 74.501014 -337.038624) (xy 74.501502 -337.065874)
			(xy 74.501018 -337.093448) (xy 74.493069 -337.14802) (xy 74.477347 -337.200879) (xy 74.454181 -337.250925)
			(xy 74.424052 -337.297115) (xy 74.387588 -337.338488) (xy 74.366882 -337.356704) (xy 74.358802 -337.364255)
			(xy 74.349451 -337.38427) (xy 74.348848 -337.395312) (xy 74.348848 -337.473036) (xy 74.349437 -337.484083)
			(xy 74.358786 -337.504105) (xy 74.366882 -337.511644) (xy 74.387566 -337.529885) (xy 74.424039 -337.571247)
			(xy 74.454175 -337.617431) (xy 74.477346 -337.667473) (xy 74.493068 -337.72033) (xy 74.501013 -337.774901)
			(xy 74.501502 -337.802474) (xy 74.501018 -337.830048) (xy 74.493824 -337.879436) (xy 75.657962 -337.879436)
			(xy 75.662033 -337.823814) (xy 75.674159 -337.769377) (xy 75.694082 -337.717286) (xy 75.721378 -337.668651)
			(xy 75.755464 -337.624508) (xy 75.795613 -337.585799) (xy 75.840971 -337.553348) (xy 75.890571 -337.527847)
			(xy 75.943355 -337.50984) (xy 75.998198 -337.49971) (xy 76.053932 -337.497673) (xy 76.109369 -337.503773)
			(xy 76.163326 -337.517879) (xy 76.214655 -337.539691) (xy 76.262261 -337.568745) (xy 76.305129 -337.60442)
			(xy 76.342346 -337.645957) (xy 76.373119 -337.69247) (xy 76.396791 -337.742967) (xy 76.412859 -337.796374)
			(xy 76.420979 -337.85155) (xy 76.421488 -337.879436) (xy 76.420979 -337.907322) (xy 76.412859 -337.962498)
			(xy 76.396791 -338.015905) (xy 76.373119 -338.066402) (xy 76.342346 -338.112915) (xy 76.305129 -338.154452)
			(xy 76.262261 -338.190127) (xy 76.214655 -338.219181) (xy 76.163326 -338.240993) (xy 76.109369 -338.255099)
			(xy 76.053932 -338.261199) (xy 75.998198 -338.259162) (xy 75.943355 -338.249032) (xy 75.890571 -338.231025)
			(xy 75.840971 -338.205524) (xy 75.795613 -338.173073) (xy 75.755464 -338.134364) (xy 75.721378 -338.090221)
			(xy 75.694082 -338.041586) (xy 75.674159 -337.989495) (xy 75.662033 -337.935058) (xy 75.657962 -337.879436)
			(xy 74.493824 -337.879436) (xy 74.493069 -337.88462) (xy 74.477347 -337.937479) (xy 74.454181 -337.987525)
			(xy 74.424052 -338.033715) (xy 74.387588 -338.075088) (xy 74.366882 -338.093304) (xy 74.358802 -338.100855)
			(xy 74.349451 -338.12087) (xy 74.348848 -338.131912) (xy 74.348848 -338.209636) (xy 74.349437 -338.220683)
			(xy 74.358786 -338.240705) (xy 74.366882 -338.248244) (xy 74.387566 -338.266485) (xy 74.424039 -338.307847)
			(xy 74.454175 -338.354031) (xy 74.477346 -338.404073) (xy 74.493068 -338.45693) (xy 74.501013 -338.511501)
			(xy 74.501502 -338.539074) (xy 74.50102 -338.566326) (xy 74.493267 -338.620277) (xy 74.477914 -338.672575)
			(xy 74.455274 -338.722155) (xy 74.425808 -338.768009) (xy 74.419936 -338.774786) (xy 75.078842 -338.774786)
			(xy 75.082913 -338.719164) (xy 75.095039 -338.664727) (xy 75.114962 -338.612636) (xy 75.142258 -338.564001)
			(xy 75.176344 -338.519858) (xy 75.216493 -338.481149) (xy 75.261851 -338.448698) (xy 75.311451 -338.423197)
			(xy 75.364235 -338.40519) (xy 75.419078 -338.39506) (xy 75.474812 -338.393023) (xy 75.530249 -338.399123)
			(xy 75.584206 -338.413229) (xy 75.635535 -338.435041) (xy 75.683141 -338.464095) (xy 75.726009 -338.49977)
			(xy 75.763226 -338.541307) (xy 75.793999 -338.58782) (xy 75.817671 -338.638317) (xy 75.833739 -338.691724)
			(xy 75.841859 -338.7469) (xy 75.842368 -338.774786) (xy 75.841859 -338.802672) (xy 75.833739 -338.857848)
			(xy 75.817671 -338.911255) (xy 75.793999 -338.961752) (xy 75.763226 -339.008265) (xy 75.726009 -339.049802)
			(xy 75.683141 -339.085477) (xy 75.635535 -339.114531) (xy 75.584206 -339.136343) (xy 75.530249 -339.150449)
			(xy 75.474812 -339.156549) (xy 75.419078 -339.154512) (xy 75.364235 -339.144382) (xy 75.311451 -339.126375)
			(xy 75.261851 -339.100874) (xy 75.216493 -339.068423) (xy 75.176344 -339.029714) (xy 75.142258 -338.985571)
			(xy 75.114962 -338.936936) (xy 75.095039 -338.884845) (xy 75.082913 -338.830408) (xy 75.078842 -338.774786)
			(xy 74.419936 -338.774786) (xy 74.390116 -338.809202) (xy 74.348925 -338.844896) (xy 74.303073 -338.874364)
			(xy 74.253494 -338.897007) (xy 74.201197 -338.912363) (xy 74.147246 -338.920119) (xy 74.119994 -338.920582)
			(xy 74.092138 -338.920078) (xy 74.037021 -338.911953) (xy 73.983669 -338.895906) (xy 73.933216 -338.872277)
			(xy 73.886731 -338.841568) (xy 73.845201 -338.80443) (xy 73.809509 -338.761652) (xy 73.780411 -338.714142)
			(xy 73.758525 -338.662908) (xy 73.750932 -338.636102) (xy 73.748646 -338.627212) (xy 73.737978 -338.611972)
			(xy 73.666096 -338.56422) (xy 73.648062 -338.560156) (xy 73.638918 -338.561426) (xy 73.625901 -338.563091)
			(xy 73.599717 -338.564874) (xy 73.586594 -338.564982) (xy 73.572445 -338.564889) (xy 73.544222 -338.562854)
			(xy 73.530206 -338.560918) (xy 73.5203 -338.559394) (xy 73.500488 -338.56422) (xy 73.426066 -338.6201)
			(xy 73.415906 -338.637626) (xy 73.414636 -338.647786) (xy 73.410562 -338.674941) (xy 73.395584 -338.727771)
			(xy 73.373189 -338.777907) (xy 73.343839 -338.824317) (xy 73.30814 -338.86604) (xy 73.266829 -338.902215)
			(xy 73.22076 -338.932096) (xy 73.170883 -338.955065) (xy 73.118229 -338.970648) (xy 73.063886 -338.978523)
			(xy 73.03643 -338.979002) (xy 73.009178 -338.978517) (xy 72.955227 -338.970764) (xy 72.902929 -338.955411)
			(xy 72.853349 -338.932772) (xy 72.807495 -338.903306) (xy 72.766302 -338.867615) (xy 72.730608 -338.826424)
			(xy 72.70114 -338.780572) (xy 72.678497 -338.730993) (xy 72.663141 -338.678696) (xy 72.655385 -338.624746)
			(xy 72.654922 -338.597494) (xy 70.513991 -338.597494) (xy 70.516628 -338.606473) (xy 70.524389 -338.660415)
			(xy 70.524878 -338.687664) (xy 70.524231 -338.719227) (xy 70.513839 -338.781493) (xy 70.493348 -338.841202)
			(xy 70.478904 -338.869274) (xy 70.474078 -338.878164) (xy 70.472046 -338.897722) (xy 70.494906 -338.976208)
			(xy 70.498149 -338.98563) (xy 70.510563 -339.00119) (xy 70.519036 -339.006434) (xy 70.544122 -339.021008)
			(xy 70.590007 -339.056505) (xy 70.629985 -339.098543) (xy 70.663133 -339.146153) (xy 70.688687 -339.198234)
			(xy 70.706055 -339.253586) (xy 70.714838 -339.31093) (xy 70.715378 -339.339936) (xy 70.714892 -339.367187)
			(xy 70.707136 -339.421135) (xy 70.691781 -339.47343) (xy 70.669139 -339.523007) (xy 70.639673 -339.568857)
			(xy 70.603982 -339.610048) (xy 70.562791 -339.645739) (xy 70.516941 -339.675205) (xy 70.467364 -339.697847)
			(xy 70.415069 -339.713202) (xy 70.361121 -339.720958) (xy 70.306619 -339.720958) (xy 70.252671 -339.713202)
			(xy 70.200376 -339.697847) (xy 70.150799 -339.675205) (xy 70.104949 -339.645739) (xy 70.063758 -339.610048)
			(xy 70.028067 -339.568857) (xy 69.998601 -339.523007) (xy 69.975959 -339.47343) (xy 69.960604 -339.421135)
			(xy 69.952848 -339.367187) (xy 69.952362 -339.339936) (xy 69.953016 -339.308373) (xy 69.963407 -339.246108)
			(xy 69.983894 -339.186399) (xy 69.998336 -339.158326) (xy 70.003162 -339.149436) (xy 70.005194 -339.129878)
			(xy 69.982334 -339.051392) (xy 69.979113 -339.04196) (xy 69.966684 -339.026404) (xy 69.958204 -339.021166)
			(xy 69.950838 -339.017102) (xy 69.940932 -339.01126) (xy 69.919088 -339.009228) (xy 69.824346 -339.042756)
			(xy 69.808598 -339.05825) (xy 69.804534 -339.068664) (xy 69.79386 -339.095449) (xy 69.765567 -339.145689)
			(xy 69.730032 -339.191097) (xy 69.688066 -339.230637) (xy 69.640626 -339.263409) (xy 69.588793 -339.288665)
			(xy 69.533749 -339.305831) (xy 69.476747 -339.314514) (xy 69.447918 -339.315044) (xy 69.420667 -339.31451)
			(xy 69.366719 -339.306756) (xy 69.314424 -339.291403) (xy 69.264846 -339.268763) (xy 69.218995 -339.239299)
			(xy 69.177804 -339.203608) (xy 69.142112 -339.162419) (xy 69.112645 -339.11657) (xy 69.090004 -339.066993)
			(xy 69.074648 -339.014699) (xy 69.066891 -338.960751) (xy 68.798477 -338.960751) (xy 68.778087 -339.004935)
			(xy 68.748135 -339.051004) (xy 68.730368 -339.071966) (xy 68.730114 -339.07222) (xy 68.724514 -339.079298)
			(xy 68.718275 -339.096221) (xy 68.717922 -339.10524) (xy 68.717922 -339.172804) (xy 68.718272 -339.181822)
			(xy 68.724524 -339.198739) (xy 68.730114 -339.205824) (xy 68.730622 -339.206332) (xy 68.74837 -339.227266)
			(xy 68.77825 -339.273303) (xy 68.801213 -339.323151) (xy 68.816784 -339.375779) (xy 68.824641 -339.430096)
			(xy 68.82511 -339.457538) (xy 68.824624 -339.484789) (xy 68.816868 -339.538737) (xy 68.801513 -339.591032)
			(xy 68.778871 -339.640609) (xy 68.749405 -339.686459) (xy 68.713714 -339.72765) (xy 68.672523 -339.763341)
			(xy 68.626673 -339.792807) (xy 68.577096 -339.815449) (xy 68.524801 -339.830804) (xy 68.470853 -339.83856)
			(xy 68.416351 -339.83856) (xy 68.362403 -339.830804) (xy 68.310108 -339.815449) (xy 68.260531 -339.792807)
			(xy 68.214681 -339.763341) (xy 68.17349 -339.72765) (xy 68.137799 -339.686459) (xy 68.108333 -339.640609)
			(xy 68.085691 -339.591032) (xy 68.070336 -339.538737) (xy 68.06258 -339.484789) (xy 68.062094 -339.457538)
			(xy 19.663156 -339.457538) (xy 19.663156 -341.42172) (xy 19.663584 -341.431787) (xy 19.67131 -341.450381)
			(xy 19.678142 -341.457788) (xy 23.865078 -345.644724) (xy 24.264112 -345.644724) (xy 24.264112 -343.17432)
			(xy 24.264728 -343.144344) (xy 24.274115 -343.08513) (xy 24.292644 -343.028113) (xy 24.319861 -342.974694)
			(xy 24.355095 -342.926188) (xy 24.375872 -342.904572) (xy 26.260552 -341.019892) (xy 26.28215 -340.999092)
			(xy 26.330652 -340.963838) (xy 26.384074 -340.936608) (xy 26.441098 -340.918073) (xy 26.50032 -340.90869)
			(xy 26.5303 -340.908132) (xy 31.99892 -340.908132) (xy 32.028898 -340.908717) (xy 32.088113 -340.918111)
			(xy 32.145131 -340.936647) (xy 32.198549 -340.96387) (xy 32.247054 -340.999111) (xy 32.268668 -341.019892)
			(xy 33.350708 -342.101932) (xy 33.371547 -342.123495) (xy 33.406796 -342.172007) (xy 33.434019 -342.225437)
			(xy 33.452544 -342.282469) (xy 33.461916 -342.341697) (xy 33.462468 -342.37168) (xy 33.462468 -347.434662)
			(xy 33.462854 -347.444278) (xy 33.469901 -347.46217) (xy 33.476184 -347.46946) (xy 33.495435 -347.490737)
			(xy 33.527954 -347.53801) (xy 33.553027 -347.589619) (xy 33.570089 -347.644402) (xy 33.578754 -347.701122)
			(xy 33.579308 -347.72981) (xy 33.579308 -347.730572) (xy 33.578859 -347.758484) (xy 33.570714 -347.813712)
			(xy 33.554608 -347.867163) (xy 33.530886 -347.917697) (xy 33.500053 -347.964235) (xy 33.481772 -347.985334)
			(xy 33.475857 -347.992498) (xy 33.469218 -348.009833) (xy 33.468818 -348.019116) (xy 33.468818 -348.096586)
			(xy 33.475422 -348.113858) (xy 33.481772 -348.12097) (xy 33.500111 -348.142065) (xy 33.531018 -348.188638)
			(xy 33.554794 -348.239224) (xy 33.57093 -348.29274) (xy 33.579079 -348.348038) (xy 33.579562 -348.375986)
			(xy 33.579076 -348.403237) (xy 33.57132 -348.457185) (xy 33.555965 -348.50948) (xy 33.533323 -348.559057)
			(xy 33.503857 -348.604907) (xy 33.468166 -348.646098) (xy 33.426975 -348.681789) (xy 33.383856 -348.7095)
			(xy 37.198721 -348.7095) (xy 37.20289 -348.653877) (xy 37.215303 -348.599498) (xy 37.235682 -348.547575)
			(xy 37.263573 -348.49927) (xy 37.298352 -348.455662) (xy 37.339242 -348.417725) (xy 37.38533 -348.386307)
			(xy 37.435587 -348.362108) (xy 37.488888 -348.345671) (xy 37.544045 -348.337363) (xy 37.571934 -348.33687)
			(xy 37.598356 -348.337315) (xy 37.650672 -348.344769) (xy 37.70141 -348.359538) (xy 37.749554 -348.381324)
			(xy 37.794139 -348.409692) (xy 37.814504 -348.426532) (xy 37.821362 -348.432374) (xy 37.83838 -348.438724)
			(xy 37.922708 -348.438724) (xy 37.939726 -348.432374) (xy 37.946584 -348.426532) (xy 37.96695 -348.409693)
			(xy 38.011536 -348.381328) (xy 38.05968 -348.359541) (xy 38.110417 -348.34477) (xy 38.162732 -348.33731)
			(xy 38.215576 -348.33731) (xy 38.267891 -348.34477) (xy 38.318628 -348.359541) (xy 38.366772 -348.381328)
			(xy 38.411358 -348.409693) (xy 38.431724 -348.426532) (xy 38.438582 -348.432374) (xy 38.4556 -348.438724)
			(xy 38.539928 -348.438724) (xy 38.556946 -348.432374) (xy 38.563804 -348.426532) (xy 38.582653 -348.410899)
			(xy 38.623697 -348.384187) (xy 38.667889 -348.363089) (xy 38.691058 -348.355158) (xy 38.691312 -348.355158)
			(xy 38.702426 -348.350745) (xy 38.719249 -348.333795) (xy 38.72357 -348.322646) (xy 38.749224 -348.244414)
			(xy 38.752273 -348.232768) (xy 38.748427 -348.209037) (xy 38.741858 -348.198948) (xy 38.741858 -348.198694)
			(xy 38.724615 -348.1741) (xy 38.697284 -348.120617) (xy 38.678681 -348.063509) (xy 38.669266 -348.004189)
			(xy 38.668706 -347.974158) (xy 38.66921 -347.946585) (xy 38.677154 -347.892014) (xy 38.692871 -347.839154)
			(xy 38.716034 -347.789108) (xy 38.74616 -347.742918) (xy 38.782622 -347.701545) (xy 38.803326 -347.683328)
			(xy 38.811393 -347.675766) (xy 38.820751 -347.65576) (xy 38.82136 -347.64472) (xy 38.82136 -347.566996)
			(xy 38.820751 -347.555951) (xy 38.811416 -347.535929) (xy 38.803326 -347.528388) (xy 38.782611 -347.510181)
			(xy 38.74614 -347.468812) (xy 38.716008 -347.422621) (xy 38.692842 -347.372573) (xy 38.677127 -347.319709)
			(xy 38.66919 -347.265133) (xy 38.668706 -347.237558) (xy 38.669192 -347.210307) (xy 38.676948 -347.156359)
			(xy 38.692303 -347.104064) (xy 38.714945 -347.054487) (xy 38.744411 -347.008637) (xy 38.780102 -346.967446)
			(xy 38.821293 -346.931755) (xy 38.867143 -346.902289) (xy 38.91672 -346.879647) (xy 38.969015 -346.864292)
			(xy 39.022963 -346.856536) (xy 39.077465 -346.856536) (xy 39.131413 -346.864292) (xy 39.183708 -346.879647)
			(xy 39.233285 -346.902289) (xy 39.279135 -346.931755) (xy 39.320326 -346.967446) (xy 39.356017 -347.008637)
			(xy 39.385483 -347.054487) (xy 39.408125 -347.104064) (xy 39.42348 -347.156359) (xy 39.431236 -347.210307)
			(xy 39.431722 -347.237558) (xy 39.43122 -347.265131) (xy 39.423274 -347.319702) (xy 39.407555 -347.372561)
			(xy 39.384392 -347.422607) (xy 39.354266 -347.468797) (xy 39.317806 -347.510171) (xy 39.297102 -347.528388)
			(xy 39.289032 -347.535948) (xy 39.279675 -347.555956) (xy 39.279068 -347.566996) (xy 39.279068 -347.64472)
			(xy 39.279659 -347.655767) (xy 39.289006 -347.67579) (xy 39.297102 -347.683328) (xy 39.31783 -347.70152)
			(xy 39.354299 -347.742893) (xy 39.384429 -347.789087) (xy 39.407592 -347.839139) (xy 39.423305 -347.892005)
			(xy 39.431239 -347.946582) (xy 39.431722 -347.974158) (xy 39.431285 -348.001084) (xy 39.423713 -348.0544)
			(xy 39.408714 -348.10612) (xy 39.386586 -348.155215) (xy 39.357769 -348.200708) (xy 39.322837 -348.241693)
			(xy 39.282486 -348.277354) (xy 39.237518 -348.306983) (xy 39.188828 -348.329988) (xy 39.163244 -348.338394)
			(xy 39.16299 -348.338394) (xy 39.151826 -348.342701) (xy 39.134852 -348.359516) (xy 39.130478 -348.370652)
			(xy 39.12866 -348.375986) (xy 41.122346 -348.375986) (xy 41.122841 -348.348075) (xy 41.130977 -348.29285)
			(xy 41.147072 -348.2394) (xy 41.170784 -348.188865) (xy 41.201606 -348.142325) (xy 41.219882 -348.121224)
			(xy 41.225766 -348.114037) (xy 41.232425 -348.096719) (xy 41.232836 -348.087442) (xy 41.232836 -348.009718)
			(xy 41.226232 -347.992446) (xy 41.219882 -347.985334) (xy 41.201596 -347.964241) (xy 41.17077 -347.917701)
			(xy 41.147057 -347.867164) (xy 41.130962 -347.813712) (xy 41.12283 -347.758484) (xy 41.122346 -347.730572)
			(xy 41.122832 -347.703321) (xy 41.130588 -347.649373) (xy 41.145943 -347.597078) (xy 41.168585 -347.547501)
			(xy 41.198051 -347.501651) (xy 41.233742 -347.46046) (xy 41.274933 -347.424769) (xy 41.320783 -347.395303)
			(xy 41.37036 -347.372661) (xy 41.422655 -347.357306) (xy 41.476603 -347.34955) (xy 41.531105 -347.34955)
			(xy 41.585053 -347.357306) (xy 41.637348 -347.372661) (xy 41.686925 -347.395303) (xy 41.732775 -347.424769)
			(xy 41.773966 -347.46046) (xy 41.809657 -347.501651) (xy 41.839123 -347.547501) (xy 41.861765 -347.597078)
			(xy 41.87712 -347.649373) (xy 41.884876 -347.703321) (xy 41.885362 -347.730572) (xy 41.884899 -347.758484)
			(xy 41.876755 -347.81371) (xy 41.860652 -347.867161) (xy 41.836933 -347.917695) (xy 41.806105 -347.964234)
			(xy 41.787826 -347.985334) (xy 41.781918 -347.992504) (xy 41.775273 -348.009834) (xy 41.774872 -348.019116)
			(xy 41.774872 -348.09684) (xy 41.781476 -348.114112) (xy 41.787826 -348.121224) (xy 41.806094 -348.142332)
			(xy 41.836922 -348.188868) (xy 41.860639 -348.239401) (xy 41.876738 -348.29285) (xy 41.884875 -348.348075)
			(xy 41.885362 -348.375986) (xy 41.884876 -348.403237) (xy 41.87712 -348.457185) (xy 41.861765 -348.50948)
			(xy 41.839123 -348.559057) (xy 41.809657 -348.604907) (xy 41.773966 -348.646098) (xy 41.732775 -348.681789)
			(xy 41.689656 -348.7095) (xy 45.504521 -348.7095) (xy 45.50869 -348.653877) (xy 45.521103 -348.599498)
			(xy 45.541482 -348.547575) (xy 45.569373 -348.49927) (xy 45.604152 -348.455662) (xy 45.645042 -348.417725)
			(xy 45.69113 -348.386307) (xy 45.741387 -348.362108) (xy 45.794688 -348.345671) (xy 45.849845 -348.337363)
			(xy 45.877734 -348.33687) (xy 45.904156 -348.337315) (xy 45.956472 -348.344769) (xy 46.00721 -348.359538)
			(xy 46.055354 -348.381324) (xy 46.099939 -348.409692) (xy 46.120304 -348.426532) (xy 46.127162 -348.432374)
			(xy 46.14418 -348.438724) (xy 46.228508 -348.438724) (xy 46.245526 -348.432374) (xy 46.252384 -348.426532)
			(xy 46.27275 -348.409693) (xy 46.317336 -348.381328) (xy 46.36548 -348.359541) (xy 46.416217 -348.34477)
			(xy 46.468532 -348.33731) (xy 46.521376 -348.33731) (xy 46.573691 -348.34477) (xy 46.624428 -348.359541)
			(xy 46.672572 -348.381328) (xy 46.717158 -348.409693) (xy 46.737524 -348.426532) (xy 46.744382 -348.432374)
			(xy 46.7614 -348.438724) (xy 46.845728 -348.438724) (xy 46.862746 -348.432374) (xy 46.869604 -348.426532)
			(xy 46.895641 -348.405213) (xy 46.953781 -348.371343) (xy 46.985174 -348.359222) (xy 46.995597 -348.354864)
			(xy 47.011554 -348.338913) (xy 47.015908 -348.328488) (xy 47.04207 -348.254828) (xy 47.045301 -348.244099)
			(xy 47.043211 -348.221822) (xy 47.038006 -348.211902) (xy 47.02535 -348.189724) (xy 47.005398 -348.14272)
			(xy 46.991893 -348.093476) (xy 46.985077 -348.042869) (xy 46.984666 -348.017338) (xy 46.985135 -347.989763)
			(xy 46.993083 -347.93519) (xy 47.008806 -347.882329) (xy 47.031976 -347.832282) (xy 47.062109 -347.786093)
			(xy 47.098578 -347.744723) (xy 47.119286 -347.726508) (xy 47.127356 -347.718948) (xy 47.136714 -347.69894)
			(xy 47.13732 -347.6879) (xy 47.13732 -347.610176) (xy 47.136735 -347.599128) (xy 47.127384 -347.579105)
			(xy 47.119286 -347.571568) (xy 47.098553 -347.55338) (xy 47.062085 -347.512006) (xy 47.031956 -347.465811)
			(xy 47.008794 -347.415759) (xy 46.993082 -347.362892) (xy 46.985148 -347.308314) (xy 46.984666 -347.280738)
			(xy 46.985152 -347.253487) (xy 46.992908 -347.199539) (xy 47.008263 -347.147244) (xy 47.030905 -347.097667)
			(xy 47.060371 -347.051817) (xy 47.096062 -347.010626) (xy 47.137253 -346.974935) (xy 47.183103 -346.945469)
			(xy 47.23268 -346.922827) (xy 47.284975 -346.907472) (xy 47.338923 -346.899716) (xy 47.393425 -346.899716)
			(xy 47.447373 -346.907472) (xy 47.499668 -346.922827) (xy 47.549245 -346.945469) (xy 47.595095 -346.974935)
			(xy 47.636286 -347.010626) (xy 47.671977 -347.051817) (xy 47.701443 -347.097667) (xy 47.724085 -347.147244)
			(xy 47.73944 -347.199539) (xy 47.747196 -347.253487) (xy 47.747682 -347.280738) (xy 47.74718 -347.308311)
			(xy 47.739236 -347.362883) (xy 47.723518 -347.415742) (xy 47.700355 -347.465789) (xy 47.670229 -347.511979)
			(xy 47.633767 -347.553351) (xy 47.613062 -347.571568) (xy 47.604995 -347.57913) (xy 47.595638 -347.599136)
			(xy 47.595028 -347.610176) (xy 47.595028 -347.6879) (xy 47.595643 -347.698944) (xy 47.604974 -347.718966)
			(xy 47.613062 -347.726508) (xy 47.633773 -347.74472) (xy 47.670245 -347.786088) (xy 47.700378 -347.832277)
			(xy 47.723544 -347.882325) (xy 47.73926 -347.935188) (xy 47.747198 -347.989763) (xy 47.747682 -348.017338)
			(xy 47.747249 -348.043602) (xy 47.740051 -348.095633) (xy 47.725782 -348.146185) (xy 47.704713 -348.194302)
			(xy 47.677241 -348.239072) (xy 47.643886 -348.27965) (xy 47.60528 -348.315268) (xy 47.562152 -348.345253)
			(xy 47.515318 -348.369037) (xy 47.496219 -348.375986) (xy 49.478946 -348.375986) (xy 49.479441 -348.348075)
			(xy 49.487577 -348.29285) (xy 49.503672 -348.2394) (xy 49.527384 -348.188865) (xy 49.558206 -348.142325)
			(xy 49.576482 -348.121224) (xy 49.582366 -348.114037) (xy 49.589025 -348.096719) (xy 49.589436 -348.087442)
			(xy 49.589436 -348.009718) (xy 49.582832 -347.992446) (xy 49.576482 -347.985334) (xy 49.558196 -347.964241)
			(xy 49.52737 -347.917701) (xy 49.503657 -347.867164) (xy 49.487562 -347.813712) (xy 49.47943 -347.758484)
			(xy 49.478946 -347.730572) (xy 49.479432 -347.703321) (xy 49.487188 -347.649373) (xy 49.502543 -347.597078)
			(xy 49.525185 -347.547501) (xy 49.554651 -347.501651) (xy 49.590342 -347.46046) (xy 49.631533 -347.424769)
			(xy 49.677383 -347.395303) (xy 49.72696 -347.372661) (xy 49.779255 -347.357306) (xy 49.833203 -347.34955)
			(xy 49.887705 -347.34955) (xy 49.941653 -347.357306) (xy 49.993948 -347.372661) (xy 50.043525 -347.395303)
			(xy 50.089375 -347.424769) (xy 50.130566 -347.46046) (xy 50.166257 -347.501651) (xy 50.195723 -347.547501)
			(xy 50.218365 -347.597078) (xy 50.23372 -347.649373) (xy 50.241476 -347.703321) (xy 50.241962 -347.730572)
			(xy 50.241499 -347.758484) (xy 50.233355 -347.81371) (xy 50.217252 -347.867161) (xy 50.193533 -347.917695)
			(xy 50.162705 -347.964234) (xy 50.144426 -347.985334) (xy 50.138518 -347.992504) (xy 50.131873 -348.009834)
			(xy 50.131472 -348.019116) (xy 50.131472 -348.09684) (xy 50.138076 -348.114112) (xy 50.144426 -348.121224)
			(xy 50.162694 -348.142332) (xy 50.193522 -348.188868) (xy 50.217239 -348.239401) (xy 50.233338 -348.29285)
			(xy 50.241475 -348.348075) (xy 50.241962 -348.375986) (xy 50.241476 -348.403237) (xy 50.23372 -348.457185)
			(xy 50.218365 -348.50948) (xy 50.195723 -348.559057) (xy 50.166257 -348.604907) (xy 50.130566 -348.646098)
			(xy 50.089375 -348.681789) (xy 50.046256 -348.7095) (xy 53.861121 -348.7095) (xy 53.86529 -348.653877)
			(xy 53.877703 -348.599498) (xy 53.898082 -348.547575) (xy 53.925973 -348.49927) (xy 53.960752 -348.455662)
			(xy 54.001642 -348.417725) (xy 54.04773 -348.386307) (xy 54.097987 -348.362108) (xy 54.151288 -348.345671)
			(xy 54.206445 -348.337363) (xy 54.234334 -348.33687) (xy 54.260756 -348.337315) (xy 54.313072 -348.344769)
			(xy 54.36381 -348.359538) (xy 54.411954 -348.381324) (xy 54.456539 -348.409692) (xy 54.476904 -348.426532)
			(xy 54.483762 -348.432374) (xy 54.50078 -348.438724) (xy 54.585108 -348.438724) (xy 54.602126 -348.432374)
			(xy 54.608984 -348.426532) (xy 54.62935 -348.409693) (xy 54.673936 -348.381328) (xy 54.72208 -348.359541)
			(xy 54.772817 -348.34477) (xy 54.825132 -348.33731) (xy 54.877976 -348.33731) (xy 54.930291 -348.34477)
			(xy 54.981028 -348.359541) (xy 55.029172 -348.381328) (xy 55.073758 -348.409693) (xy 55.094124 -348.426532)
			(xy 55.100982 -348.432374) (xy 55.118 -348.438724) (xy 55.202328 -348.438724) (xy 55.219346 -348.432374)
			(xy 55.226204 -348.426532) (xy 55.245009 -348.410904) (xy 55.285974 -348.384209) (xy 55.33008 -348.363102)
			(xy 55.353204 -348.355158) (xy 55.36438 -348.351602) (xy 55.381398 -348.335092) (xy 55.412386 -348.248224)
			(xy 55.415708 -348.236964) (xy 55.412936 -348.213678) (xy 55.407052 -348.20352) (xy 55.392675 -348.180322)
			(xy 55.369981 -348.130687) (xy 55.354589 -348.078326) (xy 55.346812 -348.024306) (xy 55.346346 -347.997018)
			(xy 55.346808 -347.969443) (xy 55.354759 -347.914869) (xy 55.370484 -347.862009) (xy 55.393654 -347.811962)
			(xy 55.423788 -347.765773) (xy 55.460258 -347.724403) (xy 55.480966 -347.706188) (xy 55.489058 -347.698648)
			(xy 55.4984 -347.678625) (xy 55.499 -347.66758) (xy 55.499 -347.589856) (xy 55.4984 -347.578811)
			(xy 55.489057 -347.558789) (xy 55.480966 -347.551248) (xy 55.460268 -347.533023) (xy 55.423798 -347.491656)
			(xy 55.393665 -347.445469) (xy 55.370498 -347.395424) (xy 55.354778 -347.342564) (xy 55.346834 -347.287992)
			(xy 55.346346 -347.260418) (xy 55.346832 -347.233167) (xy 55.354588 -347.179219) (xy 55.369943 -347.126924)
			(xy 55.392585 -347.077347) (xy 55.422051 -347.031497) (xy 55.457742 -346.990306) (xy 55.498933 -346.954615)
			(xy 55.544783 -346.925149) (xy 55.59436 -346.902507) (xy 55.646655 -346.887152) (xy 55.700603 -346.879396)
			(xy 55.755105 -346.879396) (xy 55.809053 -346.887152) (xy 55.861348 -346.902507) (xy 55.910925 -346.925149)
			(xy 55.956775 -346.954615) (xy 55.997966 -346.990306) (xy 56.033657 -347.031497) (xy 56.063123 -347.077347)
			(xy 56.085765 -347.126924) (xy 56.10112 -347.179219) (xy 56.108876 -347.233167) (xy 56.109362 -347.260418)
			(xy 56.108853 -347.287991) (xy 56.100911 -347.342563) (xy 56.085196 -347.395422) (xy 56.062034 -347.445469)
			(xy 56.031908 -347.491659) (xy 55.995447 -347.533032) (xy 55.974742 -347.551248) (xy 55.966636 -347.558775)
			(xy 55.957301 -347.578808) (xy 55.956708 -347.589856) (xy 55.956708 -347.66758) (xy 55.957285 -347.678628)
			(xy 55.966644 -347.698649) (xy 55.974742 -347.706188) (xy 55.995459 -347.724393) (xy 56.031927 -347.765764)
			(xy 56.062057 -347.811955) (xy 56.085222 -347.862005) (xy 56.100937 -347.914868) (xy 56.108877 -347.969443)
			(xy 56.109362 -347.997018) (xy 56.108932 -348.023945) (xy 56.101364 -348.077263) (xy 56.086367 -348.128986)
			(xy 56.06424 -348.178083) (xy 56.035422 -348.223577) (xy 56.000489 -348.264562) (xy 55.960135 -348.300223)
			(xy 55.915163 -348.329849) (xy 55.86647 -348.352851) (xy 55.840884 -348.361254) (xy 55.84063 -348.361254)
			(xy 55.829745 -348.365308) (xy 55.818532 -348.375986) (xy 57.810146 -348.375986) (xy 57.810641 -348.348075)
			(xy 57.818777 -348.29285) (xy 57.834872 -348.2394) (xy 57.858584 -348.188865) (xy 57.889406 -348.142325)
			(xy 57.907682 -348.121224) (xy 57.913566 -348.114037) (xy 57.920225 -348.096719) (xy 57.920636 -348.087442)
			(xy 57.920636 -348.009718) (xy 57.914032 -347.992446) (xy 57.907682 -347.985334) (xy 57.889396 -347.964241)
			(xy 57.85857 -347.917701) (xy 57.834857 -347.867164) (xy 57.818762 -347.813712) (xy 57.81063 -347.758484)
			(xy 57.810146 -347.730572) (xy 57.810632 -347.703321) (xy 57.818388 -347.649373) (xy 57.833743 -347.597078)
			(xy 57.856385 -347.547501) (xy 57.885851 -347.501651) (xy 57.921542 -347.46046) (xy 57.962733 -347.424769)
			(xy 58.008583 -347.395303) (xy 58.05816 -347.372661) (xy 58.110455 -347.357306) (xy 58.164403 -347.34955)
			(xy 58.218905 -347.34955) (xy 58.272853 -347.357306) (xy 58.325148 -347.372661) (xy 58.374725 -347.395303)
			(xy 58.420575 -347.424769) (xy 58.461766 -347.46046) (xy 58.497457 -347.501651) (xy 58.526923 -347.547501)
			(xy 58.549565 -347.597078) (xy 58.56492 -347.649373) (xy 58.572676 -347.703321) (xy 58.573162 -347.730572)
			(xy 58.572699 -347.758484) (xy 58.564555 -347.81371) (xy 58.548452 -347.867161) (xy 58.524733 -347.917695)
			(xy 58.493905 -347.964234) (xy 58.475626 -347.985334) (xy 58.469718 -347.992504) (xy 58.463073 -348.009834)
			(xy 58.462672 -348.019116) (xy 58.462672 -348.09684) (xy 58.469276 -348.114112) (xy 58.475626 -348.121224)
			(xy 58.493894 -348.142332) (xy 58.524722 -348.188868) (xy 58.548439 -348.239401) (xy 58.564538 -348.29285)
			(xy 58.572675 -348.348075) (xy 58.573162 -348.375986) (xy 58.572676 -348.403237) (xy 58.56492 -348.457185)
			(xy 58.549565 -348.50948) (xy 58.526923 -348.559057) (xy 58.497457 -348.604907) (xy 58.461766 -348.646098)
			(xy 58.420575 -348.681789) (xy 58.377456 -348.7095) (xy 62.192321 -348.7095) (xy 62.19649 -348.653877)
			(xy 62.208903 -348.599498) (xy 62.229282 -348.547575) (xy 62.257173 -348.49927) (xy 62.291952 -348.455662)
			(xy 62.332842 -348.417725) (xy 62.37893 -348.386307) (xy 62.429187 -348.362108) (xy 62.482488 -348.345671)
			(xy 62.537645 -348.337363) (xy 62.565534 -348.33687) (xy 62.591956 -348.337315) (xy 62.644272 -348.344769)
			(xy 62.69501 -348.359538) (xy 62.743154 -348.381324) (xy 62.787739 -348.409692) (xy 62.808104 -348.426532)
			(xy 62.814962 -348.432374) (xy 62.83198 -348.438724) (xy 62.916308 -348.438724) (xy 62.933326 -348.432374)
			(xy 62.940184 -348.426532) (xy 62.96055 -348.409693) (xy 63.005136 -348.381328) (xy 63.05328 -348.359541)
			(xy 63.104017 -348.34477) (xy 63.156332 -348.33731) (xy 63.209176 -348.33731) (xy 63.261491 -348.34477)
			(xy 63.312228 -348.359541) (xy 63.360372 -348.381328) (xy 63.404958 -348.409693) (xy 63.425324 -348.426532)
			(xy 63.432182 -348.432374) (xy 63.4492 -348.438724) (xy 63.533528 -348.438724) (xy 63.550546 -348.432374)
			(xy 63.557404 -348.426532) (xy 63.575177 -348.411793) (xy 63.613713 -348.386357) (xy 63.655099 -348.365882)
			(xy 63.676784 -348.357952) (xy 63.677038 -348.357952) (xy 63.687058 -348.353786) (xy 63.702581 -348.338649)
			(xy 63.70701 -348.328742) (xy 63.739268 -348.246192) (xy 63.737998 -348.224094) (xy 63.732664 -348.214188)
			(xy 63.718927 -348.187081) (xy 63.699447 -348.129523) (xy 63.689577 -348.069565) (xy 63.688976 -348.039182)
			(xy 63.688976 -348.038928) (xy 63.689463 -348.011285) (xy 63.697623 -347.956605) (xy 63.713768 -347.903729)
			(xy 63.737544 -347.853818) (xy 63.76843 -347.807964) (xy 63.805748 -347.767174) (xy 63.826898 -347.749368)
			(xy 63.835343 -347.741789) (xy 63.845095 -347.721331) (xy 63.845694 -347.709998) (xy 63.845694 -347.631258)
			(xy 63.84506 -347.619938) (xy 63.835297 -347.599505) (xy 63.826898 -347.591888) (xy 63.805763 -347.574066)
			(xy 63.76845 -347.533276) (xy 63.737567 -347.487424) (xy 63.713792 -347.437516) (xy 63.697645 -347.384645)
			(xy 63.689479 -347.329969) (xy 63.688976 -347.302328) (xy 63.689497 -347.274443) (xy 63.697809 -347.219296)
			(xy 63.714247 -347.166004) (xy 63.738445 -347.115758) (xy 63.769861 -347.069679) (xy 63.807794 -347.028797)
			(xy 63.851396 -346.994025) (xy 63.899694 -346.96614) (xy 63.951609 -346.945765) (xy 64.00598 -346.933355)
			(xy 64.061594 -346.929188) (xy 64.117208 -346.933355) (xy 64.171579 -346.945765) (xy 64.223494 -346.96614)
			(xy 64.271792 -346.994025) (xy 64.315394 -347.028797) (xy 64.353327 -347.069679) (xy 64.384743 -347.115758)
			(xy 64.408941 -347.166004) (xy 64.425379 -347.219296) (xy 64.433691 -347.274443) (xy 64.434212 -347.302328)
			(xy 64.433699 -347.32997) (xy 64.425545 -347.384649) (xy 64.409406 -347.437524) (xy 64.385634 -347.487436)
			(xy 64.354753 -347.533291) (xy 64.317438 -347.574082) (xy 64.29629 -347.591888) (xy 64.287863 -347.599484)
			(xy 64.278102 -347.619929) (xy 64.277494 -347.631258) (xy 64.277494 -347.709998) (xy 64.278157 -347.721314)
			(xy 64.2879 -347.741747) (xy 64.29629 -347.749368) (xy 64.31747 -347.767139) (xy 64.354776 -347.807942)
			(xy 64.385651 -347.853805) (xy 64.409418 -347.903723) (xy 64.425556 -347.956602) (xy 64.433713 -348.011284)
			(xy 64.434212 -348.038928) (xy 64.433698 -348.067675) (xy 64.424872 -348.124486) (xy 64.407417 -348.179265)
			(xy 64.381749 -348.23071) (xy 64.348478 -348.277598) (xy 64.308395 -348.318815) (xy 64.262453 -348.35338)
			(xy 64.211743 -348.380472) (xy 64.184784 -348.390464) (xy 64.18453 -348.390464) (xy 64.174519 -348.394649)
			(xy 64.15899 -348.409771) (xy 64.154558 -348.419674) (xy 64.1223 -348.502224) (xy 64.12357 -348.524322)
			(xy 64.128904 -348.534228) (xy 64.142644 -348.561333) (xy 64.162124 -348.618892) (xy 64.171992 -348.678851)
			(xy 64.172592 -348.709234) (xy 64.172592 -348.709488) (xy 64.172155 -348.736107) (xy 64.164579 -348.788802)
			(xy 64.149581 -348.839884) (xy 64.127466 -348.88831) (xy 64.098683 -348.933096) (xy 64.06382 -348.97333)
			(xy 64.023585 -349.008192) (xy 63.978798 -349.036973) (xy 63.93037 -349.059086) (xy 63.879289 -349.074082)
			(xy 63.826593 -349.081656) (xy 63.799974 -349.082106) (xy 63.773552 -349.081662) (xy 63.721236 -349.074208)
			(xy 63.670497 -349.05944) (xy 63.622353 -349.037653) (xy 63.577769 -349.009285) (xy 63.557404 -348.992444)
			(xy 63.550546 -348.986602) (xy 63.533528 -348.980252) (xy 63.4492 -348.980252) (xy 63.432182 -348.986602)
			(xy 63.425324 -348.992444) (xy 63.404958 -349.009283) (xy 63.360372 -349.037648) (xy 63.312228 -349.059435)
			(xy 63.261491 -349.074206) (xy 63.209176 -349.081666) (xy 63.156332 -349.081666) (xy 63.104017 -349.074206)
			(xy 63.05328 -349.059435) (xy 63.005136 -349.037648) (xy 62.96055 -349.009283) (xy 62.940184 -348.992444)
			(xy 62.933326 -348.986602) (xy 62.916308 -348.980252) (xy 62.83198 -348.980252) (xy 62.814962 -348.986602)
			(xy 62.808104 -348.992444) (xy 62.78773 -349.009272) (xy 62.743143 -349.03763) (xy 62.695001 -349.059412)
			(xy 62.644266 -349.074182) (xy 62.591954 -349.081644) (xy 62.565534 -349.082106) (xy 62.537645 -349.081637)
			(xy 62.482488 -349.073329) (xy 62.429187 -349.056892) (xy 62.37893 -349.032693) (xy 62.332842 -349.001275)
			(xy 62.291952 -348.963338) (xy 62.257173 -348.91973) (xy 62.229282 -348.871425) (xy 62.208903 -348.819502)
			(xy 62.19649 -348.765123) (xy 62.192321 -348.7095) (xy 58.377456 -348.7095) (xy 58.374725 -348.711255)
			(xy 58.325148 -348.733897) (xy 58.272853 -348.749252) (xy 58.218905 -348.757008) (xy 58.164403 -348.757008)
			(xy 58.110455 -348.749252) (xy 58.05816 -348.733897) (xy 58.008583 -348.711255) (xy 57.962733 -348.681789)
			(xy 57.921542 -348.646098) (xy 57.885851 -348.604907) (xy 57.856385 -348.559057) (xy 57.833743 -348.50948)
			(xy 57.818388 -348.457185) (xy 57.810632 -348.403237) (xy 57.810146 -348.375986) (xy 55.818532 -348.375986)
			(xy 55.812942 -348.38131) (xy 55.808372 -348.391988) (xy 55.776114 -348.478856) (xy 55.7784 -348.50197)
			(xy 55.78475 -348.51213) (xy 55.798167 -348.534423) (xy 55.81936 -348.581941) (xy 55.833718 -348.63195)
			(xy 55.840962 -348.683473) (xy 55.841392 -348.709488) (xy 55.840955 -348.736107) (xy 55.833379 -348.788802)
			(xy 55.818381 -348.839884) (xy 55.796266 -348.88831) (xy 55.767483 -348.933096) (xy 55.73262 -348.97333)
			(xy 55.692385 -349.008192) (xy 55.647598 -349.036973) (xy 55.59917 -349.059086) (xy 55.548089 -349.074082)
			(xy 55.495393 -349.081656) (xy 55.468774 -349.082106) (xy 55.442352 -349.081662) (xy 55.390036 -349.074208)
			(xy 55.339297 -349.05944) (xy 55.291153 -349.037653) (xy 55.246569 -349.009285) (xy 55.226204 -348.992444)
			(xy 55.219346 -348.986602) (xy 55.202328 -348.980252) (xy 55.118 -348.980252) (xy 55.100982 -348.986602)
			(xy 55.094124 -348.992444) (xy 55.073758 -349.009283) (xy 55.029172 -349.037648) (xy 54.981028 -349.059435)
			(xy 54.930291 -349.074206) (xy 54.877976 -349.081666) (xy 54.825132 -349.081666) (xy 54.772817 -349.074206)
			(xy 54.72208 -349.059435) (xy 54.673936 -349.037648) (xy 54.62935 -349.009283) (xy 54.608984 -348.992444)
			(xy 54.602126 -348.986602) (xy 54.585108 -348.980252) (xy 54.50078 -348.980252) (xy 54.483762 -348.986602)
			(xy 54.476904 -348.992444) (xy 54.45653 -349.009272) (xy 54.411943 -349.03763) (xy 54.363801 -349.059412)
			(xy 54.313066 -349.074182) (xy 54.260754 -349.081644) (xy 54.234334 -349.082106) (xy 54.206445 -349.081637)
			(xy 54.151288 -349.073329) (xy 54.097987 -349.056892) (xy 54.04773 -349.032693) (xy 54.001642 -349.001275)
			(xy 53.960752 -348.963338) (xy 53.925973 -348.91973) (xy 53.898082 -348.871425) (xy 53.877703 -348.819502)
			(xy 53.86529 -348.765123) (xy 53.861121 -348.7095) (xy 50.046256 -348.7095) (xy 50.043525 -348.711255)
			(xy 49.993948 -348.733897) (xy 49.941653 -348.749252) (xy 49.887705 -348.757008) (xy 49.833203 -348.757008)
			(xy 49.779255 -348.749252) (xy 49.72696 -348.733897) (xy 49.677383 -348.711255) (xy 49.631533 -348.681789)
			(xy 49.590342 -348.646098) (xy 49.554651 -348.604907) (xy 49.525185 -348.559057) (xy 49.502543 -348.50948)
			(xy 49.487188 -348.457185) (xy 49.479432 -348.403237) (xy 49.478946 -348.375986) (xy 47.496219 -348.375986)
			(xy 47.490634 -348.378018) (xy 47.479712 -348.381574) (xy 47.46371 -348.397322) (xy 47.432214 -348.48165)
			(xy 47.42878 -348.492215) (xy 47.430365 -348.51435) (xy 47.435262 -348.524322) (xy 47.435516 -348.524322)
			(xy 47.435516 -348.52483) (xy 47.44719 -348.545996) (xy 47.465591 -348.590694) (xy 47.478056 -348.637397)
			(xy 47.484374 -348.68532) (xy 47.484792 -348.709488) (xy 47.484355 -348.736107) (xy 47.476779 -348.788802)
			(xy 47.461781 -348.839884) (xy 47.439666 -348.88831) (xy 47.410883 -348.933096) (xy 47.37602 -348.97333)
			(xy 47.335785 -349.008192) (xy 47.290998 -349.036973) (xy 47.24257 -349.059086) (xy 47.191489 -349.074082)
			(xy 47.138793 -349.081656) (xy 47.112174 -349.082106) (xy 47.085752 -349.081662) (xy 47.033436 -349.074208)
			(xy 46.982697 -349.05944) (xy 46.934553 -349.037653) (xy 46.889969 -349.009285) (xy 46.869604 -348.992444)
			(xy 46.862746 -348.986602) (xy 46.845728 -348.980252) (xy 46.7614 -348.980252) (xy 46.744382 -348.986602)
			(xy 46.737524 -348.992444) (xy 46.717158 -349.009283) (xy 46.672572 -349.037648) (xy 46.624428 -349.059435)
			(xy 46.573691 -349.074206) (xy 46.521376 -349.081666) (xy 46.468532 -349.081666) (xy 46.416217 -349.074206)
			(xy 46.36548 -349.059435) (xy 46.317336 -349.037648) (xy 46.27275 -349.009283) (xy 46.252384 -348.992444)
			(xy 46.245526 -348.986602) (xy 46.228508 -348.980252) (xy 46.14418 -348.980252) (xy 46.127162 -348.986602)
			(xy 46.120304 -348.992444) (xy 46.09993 -349.009272) (xy 46.055343 -349.03763) (xy 46.007201 -349.059412)
			(xy 45.956466 -349.074182) (xy 45.904154 -349.081644) (xy 45.877734 -349.082106) (xy 45.849845 -349.081637)
			(xy 45.794688 -349.073329) (xy 45.741387 -349.056892) (xy 45.69113 -349.032693) (xy 45.645042 -349.001275)
			(xy 45.604152 -348.963338) (xy 45.569373 -348.91973) (xy 45.541482 -348.871425) (xy 45.521103 -348.819502)
			(xy 45.50869 -348.765123) (xy 45.504521 -348.7095) (xy 41.689656 -348.7095) (xy 41.686925 -348.711255)
			(xy 41.637348 -348.733897) (xy 41.585053 -348.749252) (xy 41.531105 -348.757008) (xy 41.476603 -348.757008)
			(xy 41.422655 -348.749252) (xy 41.37036 -348.733897) (xy 41.320783 -348.711255) (xy 41.274933 -348.681789)
			(xy 41.233742 -348.646098) (xy 41.198051 -348.604907) (xy 41.168585 -348.559057) (xy 41.145943 -348.50948)
			(xy 41.130588 -348.457185) (xy 41.122832 -348.403237) (xy 41.122346 -348.375986) (xy 39.12866 -348.375986)
			(xy 39.103808 -348.448884) (xy 39.100616 -348.460369) (xy 39.103913 -348.483944) (xy 39.110158 -348.494096)
			(xy 39.110666 -348.494604) (xy 39.126771 -348.518304) (xy 39.152276 -348.569614) (xy 39.169637 -348.62422)
			(xy 39.178445 -348.680839) (xy 39.178992 -348.709488) (xy 39.178555 -348.736107) (xy 39.170979 -348.788802)
			(xy 39.155981 -348.839884) (xy 39.133866 -348.88831) (xy 39.105083 -348.933096) (xy 39.07022 -348.97333)
			(xy 39.029985 -349.008192) (xy 38.985198 -349.036973) (xy 38.93677 -349.059086) (xy 38.885689 -349.074082)
			(xy 38.832993 -349.081656) (xy 38.806374 -349.082106) (xy 38.779952 -349.081662) (xy 38.727636 -349.074208)
			(xy 38.676897 -349.05944) (xy 38.628753 -349.037653) (xy 38.584169 -349.009285) (xy 38.563804 -348.992444)
			(xy 38.556946 -348.986602) (xy 38.539928 -348.980252) (xy 38.4556 -348.980252) (xy 38.438582 -348.986602)
			(xy 38.431724 -348.992444) (xy 38.411358 -349.009283) (xy 38.366772 -349.037648) (xy 38.318628 -349.059435)
			(xy 38.267891 -349.074206) (xy 38.215576 -349.081666) (xy 38.162732 -349.081666) (xy 38.110417 -349.074206)
			(xy 38.05968 -349.059435) (xy 38.011536 -349.037648) (xy 37.96695 -349.009283) (xy 37.946584 -348.992444)
			(xy 37.939726 -348.986602) (xy 37.922708 -348.980252) (xy 37.83838 -348.980252) (xy 37.821362 -348.986602)
			(xy 37.814504 -348.992444) (xy 37.79413 -349.009272) (xy 37.749543 -349.03763) (xy 37.701401 -349.059412)
			(xy 37.650666 -349.074182) (xy 37.598354 -349.081644) (xy 37.571934 -349.082106) (xy 37.544045 -349.081637)
			(xy 37.488888 -349.073329) (xy 37.435587 -349.056892) (xy 37.38533 -349.032693) (xy 37.339242 -349.001275)
			(xy 37.298352 -348.963338) (xy 37.263573 -348.91973) (xy 37.235682 -348.871425) (xy 37.215303 -348.819502)
			(xy 37.20289 -348.765123) (xy 37.198721 -348.7095) (xy 33.383856 -348.7095) (xy 33.381125 -348.711255)
			(xy 33.331548 -348.733897) (xy 33.279253 -348.749252) (xy 33.225305 -348.757008) (xy 33.170803 -348.757008)
			(xy 33.116855 -348.749252) (xy 33.06456 -348.733897) (xy 33.014983 -348.711255) (xy 32.969133 -348.681789)
			(xy 32.927942 -348.646098) (xy 32.892251 -348.604907) (xy 32.862785 -348.559057) (xy 32.840143 -348.50948)
			(xy 32.824788 -348.457185) (xy 32.817032 -348.403237) (xy 32.816546 -348.375986) (xy 32.817109 -348.345862)
			(xy 32.826592 -348.286366) (xy 32.845305 -348.229098) (xy 32.872782 -348.175481) (xy 32.908342 -348.126847)
			(xy 32.929322 -348.105222) (xy 32.936148 -348.097811) (xy 32.943875 -348.07922) (xy 32.944308 -348.069154)
			(xy 32.944308 -348.037404) (xy 32.94389 -348.027242) (xy 32.936021 -348.008505) (xy 32.929068 -348.001082)
			(xy 32.928306 -348.00032) (xy 32.811212 -347.883226) (xy 32.790405 -347.861634) (xy 32.755151 -347.813131)
			(xy 32.727922 -347.759708) (xy 32.709389 -347.702682) (xy 32.700008 -347.643459) (xy 32.699452 -347.613478)
			(xy 32.699452 -342.55075) (xy 32.699013 -342.540682) (xy 32.691303 -342.522083) (xy 32.684466 -342.514682)
			(xy 31.855918 -341.686134) (xy 31.848502 -341.679314) (xy 31.829915 -341.671582) (xy 31.81985 -341.671148)
			(xy 26.70937 -341.671148) (xy 26.699297 -341.671545) (xy 26.680699 -341.679284) (xy 26.673302 -341.686134)
			(xy 25.042114 -343.317322) (xy 25.035274 -343.324722) (xy 25.027554 -343.343321) (xy 25.027128 -343.35339)
			(xy 25.027128 -345.558618) (xy 25.027226 -345.563637) (xy 25.029141 -345.573489) (xy 25.030938 -345.578176)
			(xy 25.269952 -346.155518) (xy 25.279083 -346.178686) (xy 25.291965 -346.22679) (xy 25.298483 -346.276161)
			(xy 25.298908 -346.30106) (xy 25.298908 -347.730572) (xy 25.298459 -347.758484) (xy 25.290314 -347.813712)
			(xy 25.274208 -347.867163) (xy 25.250486 -347.917697) (xy 25.219653 -347.964235) (xy 25.201372 -347.985334)
			(xy 25.195457 -347.992498) (xy 25.188818 -348.009833) (xy 25.188418 -348.019116) (xy 25.188418 -348.096586)
			(xy 25.195022 -348.113858) (xy 25.201372 -348.12097) (xy 25.219711 -348.142065) (xy 25.250618 -348.188638)
			(xy 25.274394 -348.239224) (xy 25.29053 -348.29274) (xy 25.298679 -348.348038) (xy 25.299162 -348.375986)
			(xy 25.298676 -348.403237) (xy 25.29092 -348.457185) (xy 25.275565 -348.50948) (xy 25.252923 -348.559057)
			(xy 25.223457 -348.604907) (xy 25.187766 -348.646098) (xy 25.146575 -348.681789) (xy 25.103456 -348.7095)
			(xy 28.918321 -348.7095) (xy 28.92249 -348.653877) (xy 28.934903 -348.599498) (xy 28.955282 -348.547575)
			(xy 28.983173 -348.49927) (xy 29.017952 -348.455662) (xy 29.058842 -348.417725) (xy 29.10493 -348.386307)
			(xy 29.155187 -348.362108) (xy 29.208488 -348.345671) (xy 29.263645 -348.337363) (xy 29.291534 -348.33687)
			(xy 29.317956 -348.337315) (xy 29.370272 -348.344769) (xy 29.42101 -348.359538) (xy 29.469154 -348.381324)
			(xy 29.513739 -348.409692) (xy 29.534104 -348.426532) (xy 29.540962 -348.432374) (xy 29.55798 -348.438724)
			(xy 29.642308 -348.438724) (xy 29.659326 -348.432374) (xy 29.666184 -348.426532) (xy 29.68655 -348.409693)
			(xy 29.731136 -348.381328) (xy 29.77928 -348.359541) (xy 29.830017 -348.34477) (xy 29.882332 -348.33731)
			(xy 29.935176 -348.33731) (xy 29.987491 -348.34477) (xy 30.038228 -348.359541) (xy 30.086372 -348.381328)
			(xy 30.130958 -348.409693) (xy 30.151324 -348.426532) (xy 30.158182 -348.432374) (xy 30.1752 -348.438724)
			(xy 30.259528 -348.438724) (xy 30.276546 -348.432374) (xy 30.283404 -348.426532) (xy 30.304989 -348.408734)
			(xy 30.35245 -348.379119) (xy 30.403805 -348.356931) (xy 30.430724 -348.349316) (xy 30.44317 -348.346014)
			(xy 30.461204 -348.32925) (xy 30.49778 -348.22638) (xy 30.494224 -348.201488) (xy 30.486858 -348.191328)
			(xy 30.469611 -348.166737) (xy 30.442275 -348.113255) (xy 30.423672 -348.056145) (xy 30.414262 -347.996824)
			(xy 30.413706 -347.966792) (xy 30.413706 -347.966538) (xy 30.414196 -347.938964) (xy 30.422143 -347.884392)
			(xy 30.437863 -347.831533) (xy 30.461029 -347.781487) (xy 30.491157 -347.735297) (xy 30.527621 -347.693924)
			(xy 30.548326 -347.675708) (xy 30.556402 -347.668154) (xy 30.565755 -347.648142) (xy 30.56636 -347.6371)
			(xy 30.56636 -347.559376) (xy 30.565762 -347.54833) (xy 30.556419 -347.528308) (xy 30.548326 -347.520768)
			(xy 30.527601 -347.502571) (xy 30.491131 -347.4612) (xy 30.461 -347.415008) (xy 30.437836 -347.364957)
			(xy 30.422123 -347.312091) (xy 30.414188 -347.257514) (xy 30.413706 -347.229938) (xy 30.414192 -347.202687)
			(xy 30.421948 -347.148739) (xy 30.437303 -347.096444) (xy 30.459945 -347.046867) (xy 30.489411 -347.001017)
			(xy 30.525102 -346.959826) (xy 30.566293 -346.924135) (xy 30.612143 -346.894669) (xy 30.66172 -346.872027)
			(xy 30.714015 -346.856672) (xy 30.767963 -346.848916) (xy 30.822465 -346.848916) (xy 30.876413 -346.856672)
			(xy 30.928708 -346.872027) (xy 30.978285 -346.894669) (xy 31.024135 -346.924135) (xy 31.065326 -346.959826)
			(xy 31.101017 -347.001017) (xy 31.130483 -347.046867) (xy 31.153125 -347.096444) (xy 31.16848 -347.148739)
			(xy 31.176236 -347.202687) (xy 31.176722 -347.229938) (xy 31.176206 -347.257511) (xy 31.168263 -347.312081)
			(xy 31.152547 -347.36494) (xy 31.129386 -347.414986) (xy 31.099263 -347.461176) (xy 31.062805 -347.50255)
			(xy 31.042102 -347.520768) (xy 31.034041 -347.528336) (xy 31.024679 -347.548338) (xy 31.024068 -347.559376)
			(xy 31.024068 -347.6371) (xy 31.02467 -347.648146) (xy 31.034009 -347.668168) (xy 31.042102 -347.675708)
			(xy 31.062821 -347.693911) (xy 31.09929 -347.735282) (xy 31.129421 -347.781473) (xy 31.152586 -347.831523)
			(xy 31.168301 -347.884387) (xy 31.176238 -347.938963) (xy 31.176722 -347.966538) (xy 31.176251 -347.994643)
			(xy 31.167999 -348.050245) (xy 31.151678 -348.104034) (xy 31.127642 -348.154846) (xy 31.096411 -348.201583)
			(xy 31.058662 -348.243231) (xy 31.01521 -348.27889) (xy 30.966997 -348.307789) (xy 30.915065 -348.329301)
			(xy 30.887924 -348.336616) (xy 30.876191 -348.340398) (xy 30.857883 -348.356849) (xy 30.852872 -348.368112)
			(xy 30.81909 -348.458536) (xy 30.822646 -348.483428) (xy 30.830012 -348.493842) (xy 30.84618 -348.517552)
			(xy 30.871785 -348.568909) (xy 30.889211 -348.623585) (xy 30.898046 -348.680287) (xy 30.898592 -348.70898)
			(xy 30.898592 -348.709488) (xy 30.898155 -348.736107) (xy 30.890579 -348.788802) (xy 30.875581 -348.839884)
			(xy 30.853466 -348.88831) (xy 30.824683 -348.933096) (xy 30.78982 -348.97333) (xy 30.749585 -349.008192)
			(xy 30.704798 -349.036973) (xy 30.65637 -349.059086) (xy 30.605289 -349.074082) (xy 30.552593 -349.081656)
			(xy 30.525974 -349.082106) (xy 30.499552 -349.081662) (xy 30.447236 -349.074208) (xy 30.396497 -349.05944)
			(xy 30.348353 -349.037653) (xy 30.303769 -349.009285) (xy 30.283404 -348.992444) (xy 30.276546 -348.986602)
			(xy 30.259528 -348.980252) (xy 30.1752 -348.980252) (xy 30.158182 -348.986602) (xy 30.151324 -348.992444)
			(xy 30.130958 -349.009283) (xy 30.086372 -349.037648) (xy 30.038228 -349.059435) (xy 29.987491 -349.074206)
			(xy 29.935176 -349.081666) (xy 29.882332 -349.081666) (xy 29.830017 -349.074206) (xy 29.77928 -349.059435)
			(xy 29.731136 -349.037648) (xy 29.68655 -349.009283) (xy 29.666184 -348.992444) (xy 29.659326 -348.986602)
			(xy 29.642308 -348.980252) (xy 29.55798 -348.980252) (xy 29.540962 -348.986602) (xy 29.534104 -348.992444)
			(xy 29.51373 -349.009272) (xy 29.469143 -349.03763) (xy 29.421001 -349.059412) (xy 29.370266 -349.074182)
			(xy 29.317954 -349.081644) (xy 29.291534 -349.082106) (xy 29.263645 -349.081637) (xy 29.208488 -349.073329)
			(xy 29.155187 -349.056892) (xy 29.10493 -349.032693) (xy 29.058842 -349.001275) (xy 29.017952 -348.963338)
			(xy 28.983173 -348.91973) (xy 28.955282 -348.871425) (xy 28.934903 -348.819502) (xy 28.92249 -348.765123)
			(xy 28.918321 -348.7095) (xy 25.103456 -348.7095) (xy 25.100725 -348.711255) (xy 25.051148 -348.733897)
			(xy 24.998853 -348.749252) (xy 24.944905 -348.757008) (xy 24.890403 -348.757008) (xy 24.836455 -348.749252)
			(xy 24.78416 -348.733897) (xy 24.734583 -348.711255) (xy 24.688733 -348.681789) (xy 24.647542 -348.646098)
			(xy 24.611851 -348.604907) (xy 24.582385 -348.559057) (xy 24.559743 -348.50948) (xy 24.544388 -348.457185)
			(xy 24.536632 -348.403237) (xy 24.536146 -348.375986) (xy 24.536629 -348.34804) (xy 24.544797 -348.292748)
			(xy 24.560942 -348.239238) (xy 24.584719 -348.188655) (xy 24.615618 -348.142081) (xy 24.633936 -348.12097)
			(xy 24.63985 -348.113805) (xy 24.64649 -348.09647) (xy 24.64689 -348.087188) (xy 24.64689 -348.009718)
			(xy 24.640286 -347.992446) (xy 24.633936 -347.985334) (xy 24.615643 -347.964247) (xy 24.584819 -347.917705)
			(xy 24.561108 -347.867166) (xy 24.545015 -347.813713) (xy 24.536884 -347.758484) (xy 24.5364 -347.730572)
			(xy 24.5364 -346.387674) (xy 24.536303 -346.382655) (xy 24.534387 -346.372803) (xy 24.53259 -346.368116)
			(xy 24.293322 -345.790774) (xy 24.284074 -345.767549) (xy 24.271078 -345.719277) (xy 24.264515 -345.669719)
			(xy 24.264112 -345.644724) (xy 23.865078 -345.644724) (xy 23.889716 -345.669362) (xy 23.906985 -345.687447)
			(xy 23.93474 -345.729034) (xy 23.944834 -345.751912) (xy 24.257762 -346.507308) (xy 24.266802 -346.530611)
			(xy 24.276661 -346.579604) (xy 24.27732 -346.60459) (xy 24.27732 -349.607632) (xy 25.493978 -349.607632)
			(xy 25.498049 -349.55201) (xy 25.510175 -349.497573) (xy 25.530098 -349.445482) (xy 25.557394 -349.396847)
			(xy 25.59148 -349.352704) (xy 25.631629 -349.313995) (xy 25.676987 -349.281544) (xy 25.726587 -349.256043)
			(xy 25.779371 -349.238036) (xy 25.834214 -349.227906) (xy 25.889948 -349.225869) (xy 25.945385 -349.231969)
			(xy 25.999342 -349.246075) (xy 26.050671 -349.267887) (xy 26.098277 -349.296941) (xy 26.141145 -349.332616)
			(xy 26.178362 -349.374153) (xy 26.209135 -349.420666) (xy 26.232807 -349.471163) (xy 26.248875 -349.52457)
			(xy 26.256995 -349.579746) (xy 26.257504 -349.607632) (xy 26.256995 -349.635518) (xy 26.248875 -349.690694)
			(xy 26.232807 -349.744101) (xy 26.209135 -349.794598) (xy 26.178362 -349.841111) (xy 26.141145 -349.882648)
			(xy 26.098277 -349.918323) (xy 26.050671 -349.947377) (xy 25.999342 -349.969189) (xy 25.945385 -349.983295)
			(xy 25.889948 -349.989395) (xy 25.834214 -349.987358) (xy 25.779371 -349.977228) (xy 25.726587 -349.959221)
			(xy 25.676987 -349.93372) (xy 25.631629 -349.901269) (xy 25.59148 -349.86256) (xy 25.557394 -349.818417)
			(xy 25.530098 -349.769782) (xy 25.510175 -349.717691) (xy 25.498049 -349.663254) (xy 25.493978 -349.607632)
			(xy 24.27732 -349.607632) (xy 24.27732 -349.787464) (xy 24.276682 -349.812459) (xy 24.266879 -349.861481)
			(xy 24.247701 -349.907648) (xy 24.219886 -349.949187) (xy 24.202644 -349.967296) (xy 23.666958 -350.502982)
			(xy 24.914858 -350.502982) (xy 24.918929 -350.44736) (xy 24.931055 -350.392923) (xy 24.950978 -350.340832)
			(xy 24.978274 -350.292197) (xy 25.01236 -350.248054) (xy 25.052509 -350.209345) (xy 25.097867 -350.176894)
			(xy 25.147467 -350.151393) (xy 25.200251 -350.133386) (xy 25.255094 -350.123256) (xy 25.310828 -350.121219)
			(xy 25.366265 -350.127319) (xy 25.420222 -350.141425) (xy 25.471551 -350.163237) (xy 25.519157 -350.192291)
			(xy 25.562025 -350.227966) (xy 25.599242 -350.269503) (xy 25.630015 -350.316016) (xy 25.653687 -350.366513)
			(xy 25.669755 -350.41992) (xy 25.677875 -350.475096) (xy 25.678384 -350.502982) (xy 25.677875 -350.530868)
			(xy 25.669755 -350.586044) (xy 25.653687 -350.639451) (xy 25.630015 -350.689948) (xy 25.599242 -350.736461)
			(xy 25.562025 -350.777998) (xy 25.519157 -350.813673) (xy 25.471551 -350.842727) (xy 25.420222 -350.864539)
			(xy 25.366265 -350.878645) (xy 25.310828 -350.884745) (xy 25.255094 -350.882708) (xy 25.200251 -350.872578)
			(xy 25.147467 -350.854571) (xy 25.097867 -350.82907) (xy 25.052509 -350.796619) (xy 25.01236 -350.75791)
			(xy 24.978274 -350.713767) (xy 24.950978 -350.665132) (xy 24.931055 -350.613041) (xy 24.918929 -350.558604)
			(xy 24.914858 -350.502982) (xy 23.666958 -350.502982) (xy 23.574502 -350.595438) (xy 23.567661 -350.602839)
			(xy 23.55994 -350.621437) (xy 23.559516 -350.631506) (xy 23.559516 -351.178622) (xy 26.253694 -351.178622)
			(xy 26.254195 -351.151148) (xy 26.262083 -351.096769) (xy 26.2777 -351.044087) (xy 26.300722 -350.994194)
			(xy 26.33067 -350.948124) (xy 26.348436 -350.927162) (xy 26.34869 -350.926908) (xy 26.354278 -350.919823)
			(xy 26.360524 -350.902905) (xy 26.360882 -350.893888) (xy 26.360882 -350.826324) (xy 26.360517 -350.817308)
			(xy 26.354275 -350.800391) (xy 26.34869 -350.793304) (xy 26.348182 -350.792796) (xy 26.330448 -350.77185)
			(xy 26.300566 -350.725817) (xy 26.2776 -350.675972) (xy 26.262026 -350.623347) (xy 26.254165 -350.569031)
			(xy 26.253694 -350.54159) (xy 26.25418 -350.514339) (xy 26.261936 -350.460391) (xy 26.277291 -350.408096)
			(xy 26.299933 -350.358519) (xy 26.329399 -350.312669) (xy 26.36509 -350.271478) (xy 26.406281 -350.235787)
			(xy 26.452131 -350.206321) (xy 26.501708 -350.183679) (xy 26.554003 -350.168324) (xy 26.607951 -350.160568)
			(xy 26.662453 -350.160568) (xy 26.716401 -350.168324) (xy 26.768696 -350.183679) (xy 26.818273 -350.206321)
			(xy 26.864123 -350.235787) (xy 26.905314 -350.271478) (xy 26.941005 -350.312669) (xy 26.970471 -350.358519)
			(xy 26.993113 -350.408096) (xy 27.008468 -350.460391) (xy 27.016224 -350.514339) (xy 27.01671 -350.54159)
			(xy 27.016215 -350.569064) (xy 27.008325 -350.623443) (xy 26.992707 -350.676126) (xy 26.990065 -350.681852)
			(xy 27.258475 -350.681852) (xy 27.258475 -350.627348) (xy 27.266232 -350.573398) (xy 27.281589 -350.521102)
			(xy 27.304231 -350.471523) (xy 27.333699 -350.425671) (xy 27.369393 -350.38448) (xy 27.410586 -350.348788)
			(xy 27.456439 -350.319322) (xy 27.506018 -350.296682) (xy 27.558316 -350.281329) (xy 27.612266 -350.273574)
			(xy 27.639518 -350.273112) (xy 27.639772 -350.273112) (xy 27.664975 -350.273528) (xy 27.714942 -350.280163)
			(xy 27.763597 -350.293335) (xy 27.810087 -350.312813) (xy 27.83205 -350.325182) (xy 27.841956 -350.331024)
			(xy 27.8638 -350.333056) (xy 27.958542 -350.299528) (xy 27.97429 -350.284034) (xy 27.978354 -350.27362)
			(xy 27.989083 -350.246857) (xy 28.017365 -350.196615) (xy 28.052889 -350.151205) (xy 28.094846 -350.111661)
			(xy 28.142279 -350.078885) (xy 28.194106 -350.053625) (xy 28.249145 -350.036457) (xy 28.306142 -350.027771)
			(xy 28.33497 -350.02724) (xy 28.362224 -350.027683) (xy 28.416178 -350.035437) (xy 28.46848 -350.050792)
			(xy 28.518063 -350.073435) (xy 28.563918 -350.102904) (xy 28.605113 -350.1386) (xy 28.640807 -350.179796)
			(xy 28.670274 -350.225653) (xy 28.692914 -350.275237) (xy 28.705636 -350.318578) (xy 30.846522 -350.318578)
			(xy 30.847034 -350.291005) (xy 30.854976 -350.236434) (xy 30.870691 -350.183575) (xy 30.893852 -350.133528)
			(xy 30.923977 -350.087337) (xy 30.960438 -350.045965) (xy 30.981142 -350.027748) (xy 30.989203 -350.02018)
			(xy 30.998563 -350.000178) (xy 30.999176 -349.98914) (xy 30.999176 -349.911416) (xy 30.998607 -349.900367)
			(xy 30.989243 -349.880345) (xy 30.981142 -349.872808) (xy 30.96044 -349.854587) (xy 30.923967 -349.813221)
			(xy 30.893833 -349.767034) (xy 30.870665 -349.716988) (xy 30.854947 -349.664126) (xy 30.847007 -349.609552)
			(xy 30.846522 -349.581978) (xy 30.846934 -349.554723) (xy 30.854695 -349.500769) (xy 30.870056 -349.448468)
			(xy 30.892703 -349.398886) (xy 30.922176 -349.353031) (xy 30.957875 -349.311838) (xy 30.999073 -349.276145)
			(xy 31.044932 -349.246678) (xy 31.094517 -349.224037) (xy 31.14682 -349.208684) (xy 31.200775 -349.200931)
			(xy 31.22803 -349.20047) (xy 31.228538 -349.20047) (xy 31.26232 -349.201994) (xy 31.27248 -349.20301)
			(xy 31.291784 -349.196914) (xy 31.354776 -349.144082) (xy 31.362049 -349.137342) (xy 31.371341 -349.11985)
			(xy 31.37281 -349.110046) (xy 31.37281 -349.109284) (xy 31.375762 -349.081135) (xy 31.388956 -349.026097)
			(xy 31.410141 -348.973613) (xy 31.438849 -348.924837) (xy 31.474452 -348.88084) (xy 31.516166 -348.842588)
			(xy 31.563076 -348.810921) (xy 31.614151 -348.786535) (xy 31.668269 -348.769966) (xy 31.724241 -348.761577)
			(xy 31.75254 -348.76105) (xy 31.752794 -348.76105) (xy 31.770813 -348.761277) (xy 31.806688 -348.764707)
			(xy 31.824422 -348.767908) (xy 31.834074 -348.769686) (xy 31.853124 -348.76613) (xy 31.928054 -348.718124)
			(xy 31.939484 -348.702376) (xy 31.94177 -348.692978) (xy 31.949225 -348.665951) (xy 31.970848 -348.614227)
			(xy 31.999805 -348.566223) (xy 32.035473 -348.522971) (xy 32.077085 -348.485403) (xy 32.123745 -348.454326)
			(xy 32.174449 -348.43041) (xy 32.228107 -348.414169) (xy 32.283563 -348.405952) (xy 32.311594 -348.40545)
			(xy 32.338843 -348.405983) (xy 32.392787 -348.413738) (xy 32.445078 -348.42909) (xy 32.494653 -348.451727)
			(xy 32.540501 -348.481189) (xy 32.58169 -348.516876) (xy 32.617382 -348.55806) (xy 32.64685 -348.603905)
			(xy 32.669493 -348.653477) (xy 32.684852 -348.705766) (xy 32.692613 -348.759709) (xy 32.693102 -348.786958)
			(xy 32.692607 -348.814531) (xy 32.68466 -348.869103) (xy 32.668941 -348.921962) (xy 32.645776 -348.972008)
			(xy 32.615649 -349.018199) (xy 32.579187 -349.059571) (xy 32.558482 -349.077788) (xy 32.550409 -349.085345)
			(xy 32.541054 -349.105355) (xy 32.540448 -349.116396) (xy 32.540448 -349.19412) (xy 32.541045 -349.205166)
			(xy 32.550388 -349.225188) (xy 32.558482 -349.232728) (xy 32.579206 -349.250925) (xy 32.615676 -349.292296)
			(xy 32.645807 -349.338489) (xy 32.668971 -349.38854) (xy 32.684684 -349.441405) (xy 32.692619 -349.495982)
			(xy 32.693102 -349.523558) (xy 32.692607 -349.551131) (xy 32.68466 -349.605703) (xy 32.684086 -349.607632)
			(xy 33.774378 -349.607632) (xy 33.778449 -349.55201) (xy 33.790575 -349.497573) (xy 33.810498 -349.445482)
			(xy 33.837794 -349.396847) (xy 33.87188 -349.352704) (xy 33.912029 -349.313995) (xy 33.957387 -349.281544)
			(xy 34.006987 -349.256043) (xy 34.059771 -349.238036) (xy 34.114614 -349.227906) (xy 34.170348 -349.225869)
			(xy 34.225785 -349.231969) (xy 34.279742 -349.246075) (xy 34.331071 -349.267887) (xy 34.378677 -349.296941)
			(xy 34.421545 -349.332616) (xy 34.458762 -349.374153) (xy 34.489535 -349.420666) (xy 34.513207 -349.471163)
			(xy 34.529275 -349.52457) (xy 34.537395 -349.579746) (xy 34.537904 -349.607632) (xy 34.537395 -349.635518)
			(xy 34.529275 -349.690694) (xy 34.513207 -349.744101) (xy 34.489535 -349.794598) (xy 34.458762 -349.841111)
			(xy 34.421545 -349.882648) (xy 34.378677 -349.918323) (xy 34.331071 -349.947377) (xy 34.279742 -349.969189)
			(xy 34.225785 -349.983295) (xy 34.170348 -349.989395) (xy 34.114614 -349.987358) (xy 34.059771 -349.977228)
			(xy 34.006987 -349.959221) (xy 33.957387 -349.93372) (xy 33.912029 -349.901269) (xy 33.87188 -349.86256)
			(xy 33.837794 -349.818417) (xy 33.810498 -349.769782) (xy 33.790575 -349.717691) (xy 33.778449 -349.663254)
			(xy 33.774378 -349.607632) (xy 32.684086 -349.607632) (xy 32.668941 -349.658562) (xy 32.645776 -349.708608)
			(xy 32.615649 -349.754799) (xy 32.579187 -349.796171) (xy 32.558482 -349.814388) (xy 32.550409 -349.821945)
			(xy 32.541054 -349.841955) (xy 32.540448 -349.852996) (xy 32.540448 -349.93072) (xy 32.541045 -349.941766)
			(xy 32.550388 -349.961788) (xy 32.558482 -349.969328) (xy 32.579206 -349.987525) (xy 32.615676 -350.028896)
			(xy 32.645807 -350.075089) (xy 32.668971 -350.12514) (xy 32.684684 -350.178005) (xy 32.692619 -350.232582)
			(xy 32.693102 -350.260158) (xy 32.692606 -350.28741) (xy 32.684854 -350.34136) (xy 32.669503 -350.393658)
			(xy 32.646865 -350.443238) (xy 32.617401 -350.489092) (xy 32.605367 -350.502982) (xy 33.195258 -350.502982)
			(xy 33.199329 -350.44736) (xy 33.211455 -350.392923) (xy 33.231378 -350.340832) (xy 33.258674 -350.292197)
			(xy 33.29276 -350.248054) (xy 33.332909 -350.209345) (xy 33.378267 -350.176894) (xy 33.427867 -350.151393)
			(xy 33.480651 -350.133386) (xy 33.535494 -350.123256) (xy 33.591228 -350.121219) (xy 33.646665 -350.127319)
			(xy 33.700622 -350.141425) (xy 33.751951 -350.163237) (xy 33.799557 -350.192291) (xy 33.842425 -350.227966)
			(xy 33.879642 -350.269503) (xy 33.910415 -350.316016) (xy 33.934087 -350.366513) (xy 33.950155 -350.41992)
			(xy 33.958275 -350.475096) (xy 33.958784 -350.502982) (xy 33.958275 -350.530868) (xy 33.950155 -350.586044)
			(xy 33.934087 -350.639451) (xy 33.910415 -350.689948) (xy 33.879642 -350.736461) (xy 33.842425 -350.777998)
			(xy 33.799557 -350.813673) (xy 33.751951 -350.842727) (xy 33.700622 -350.864539) (xy 33.646665 -350.878645)
			(xy 33.591228 -350.884745) (xy 33.535494 -350.882708) (xy 33.480651 -350.872578) (xy 33.427867 -350.854571)
			(xy 33.378267 -350.82907) (xy 33.332909 -350.796619) (xy 33.29276 -350.75791) (xy 33.258674 -350.713767)
			(xy 33.231378 -350.665132) (xy 33.211455 -350.613041) (xy 33.199329 -350.558604) (xy 33.195258 -350.502982)
			(xy 32.605367 -350.502982) (xy 32.581711 -350.530285) (xy 32.540521 -350.565979) (xy 32.49467 -350.595448)
			(xy 32.445092 -350.618091) (xy 32.392795 -350.633447) (xy 32.338846 -350.641203) (xy 32.311594 -350.641666)
			(xy 32.283737 -350.641174) (xy 32.228619 -350.633048) (xy 32.175267 -350.617) (xy 32.124813 -350.59337)
			(xy 32.078327 -350.56266) (xy 32.036798 -350.52552) (xy 32.001106 -350.482741) (xy 31.972009 -350.435229)
			(xy 31.950124 -350.383993) (xy 31.942532 -350.357186) (xy 31.940246 -350.348296) (xy 31.929578 -350.333056)
			(xy 31.857696 -350.285304) (xy 31.839662 -350.28124) (xy 31.830518 -350.28251) (xy 31.817501 -350.284175)
			(xy 31.791317 -350.285958) (xy 31.778194 -350.286066) (xy 31.764045 -350.285973) (xy 31.735822 -350.283938)
			(xy 31.721806 -350.282002) (xy 31.7119 -350.280478) (xy 31.692088 -350.285304) (xy 31.617666 -350.341184)
			(xy 31.607506 -350.35871) (xy 31.606236 -350.36887) (xy 31.60215 -350.396023) (xy 31.587174 -350.448852)
			(xy 31.564781 -350.498989) (xy 31.535432 -350.545399) (xy 31.499735 -350.587122) (xy 31.458425 -350.623298)
			(xy 31.412357 -350.653179) (xy 31.362481 -350.676149) (xy 31.309828 -350.691732) (xy 31.255485 -350.699607)
			(xy 31.22803 -350.700086) (xy 31.200777 -350.699617) (xy 31.146825 -350.691863) (xy 31.094526 -350.67651)
			(xy 31.044944 -350.653869) (xy 30.99909 -350.624402) (xy 30.957897 -350.588709) (xy 30.922202 -350.547516)
			(xy 30.892735 -350.501663) (xy 30.870093 -350.452082) (xy 30.854738 -350.399783) (xy 30.846984 -350.345831)
			(xy 30.846522 -350.318578) (xy 28.705636 -350.318578) (xy 28.708266 -350.327539) (xy 28.716018 -350.381494)
			(xy 28.716478 -350.408748) (xy 28.715825 -350.440311) (xy 28.705435 -350.502577) (xy 28.684947 -350.562286)
			(xy 28.670504 -350.590358) (xy 28.665678 -350.599248) (xy 28.663646 -350.618806) (xy 28.686506 -350.697292)
			(xy 28.689755 -350.706712) (xy 28.702165 -350.722273) (xy 28.710636 -350.727518) (xy 28.735715 -350.742104)
			(xy 28.7816 -350.777599) (xy 28.821578 -350.819635) (xy 28.854727 -350.867242) (xy 28.880282 -350.919322)
			(xy 28.897652 -350.974672) (xy 28.906437 -351.032014) (xy 28.906978 -351.06102) (xy 28.906492 -351.088271)
			(xy 28.898736 -351.142219) (xy 28.888047 -351.178622) (xy 34.534094 -351.178622) (xy 34.534595 -351.151148)
			(xy 34.542483 -351.096769) (xy 34.5581 -351.044087) (xy 34.581122 -350.994194) (xy 34.61107 -350.948124)
			(xy 34.628836 -350.927162) (xy 34.62909 -350.926908) (xy 34.634678 -350.919823) (xy 34.640924 -350.902905)
			(xy 34.641282 -350.893888) (xy 34.641282 -350.826324) (xy 34.640917 -350.817308) (xy 34.634675 -350.800391)
			(xy 34.62909 -350.793304) (xy 34.628582 -350.792796) (xy 34.610848 -350.77185) (xy 34.580966 -350.725817)
			(xy 34.558 -350.675972) (xy 34.542426 -350.623347) (xy 34.534565 -350.569031) (xy 34.534094 -350.54159)
			(xy 34.53458 -350.514339) (xy 34.542336 -350.460391) (xy 34.557691 -350.408096) (xy 34.580333 -350.358519)
			(xy 34.609799 -350.312669) (xy 34.64549 -350.271478) (xy 34.686681 -350.235787) (xy 34.732531 -350.206321)
			(xy 34.782108 -350.183679) (xy 34.834403 -350.168324) (xy 34.888351 -350.160568) (xy 34.942853 -350.160568)
			(xy 34.996801 -350.168324) (xy 35.049096 -350.183679) (xy 35.098673 -350.206321) (xy 35.144523 -350.235787)
			(xy 35.185714 -350.271478) (xy 35.221405 -350.312669) (xy 35.250871 -350.358519) (xy 35.273513 -350.408096)
			(xy 35.288868 -350.460391) (xy 35.296624 -350.514339) (xy 35.29711 -350.54159) (xy 35.296615 -350.569064)
			(xy 35.288725 -350.623443) (xy 35.273107 -350.676126) (xy 35.270465 -350.681852) (xy 35.538875 -350.681852)
			(xy 35.538875 -350.627348) (xy 35.546632 -350.573398) (xy 35.561989 -350.521102) (xy 35.584631 -350.471523)
			(xy 35.614099 -350.425671) (xy 35.649793 -350.38448) (xy 35.690986 -350.348788) (xy 35.736839 -350.319322)
			(xy 35.786418 -350.296682) (xy 35.838716 -350.281329) (xy 35.892666 -350.273574) (xy 35.919918 -350.273112)
			(xy 35.920172 -350.273112) (xy 35.945375 -350.273528) (xy 35.995342 -350.280163) (xy 36.043997 -350.293335)
			(xy 36.090487 -350.312813) (xy 36.11245 -350.325182) (xy 36.122356 -350.331024) (xy 36.1442 -350.333056)
			(xy 36.238942 -350.299528) (xy 36.25469 -350.284034) (xy 36.258754 -350.27362) (xy 36.269483 -350.246857)
			(xy 36.297765 -350.196615) (xy 36.333289 -350.151205) (xy 36.375246 -350.111661) (xy 36.422679 -350.078885)
			(xy 36.474506 -350.053625) (xy 36.529545 -350.036457) (xy 36.586542 -350.027771) (xy 36.61537 -350.02724)
			(xy 36.642624 -350.027683) (xy 36.696578 -350.035437) (xy 36.74888 -350.050792) (xy 36.798463 -350.073435)
			(xy 36.844318 -350.102904) (xy 36.885513 -350.1386) (xy 36.921207 -350.179796) (xy 36.950674 -350.225653)
			(xy 36.973314 -350.275237) (xy 36.986036 -350.318578) (xy 39.126922 -350.318578) (xy 39.127434 -350.291005)
			(xy 39.135376 -350.236434) (xy 39.151091 -350.183575) (xy 39.174252 -350.133528) (xy 39.204377 -350.087337)
			(xy 39.240838 -350.045965) (xy 39.261542 -350.027748) (xy 39.269603 -350.02018) (xy 39.278963 -350.000178)
			(xy 39.279576 -349.98914) (xy 39.279576 -349.911416) (xy 39.279007 -349.900367) (xy 39.269643 -349.880345)
			(xy 39.261542 -349.872808) (xy 39.24084 -349.854587) (xy 39.204367 -349.813221) (xy 39.174233 -349.767034)
			(xy 39.151065 -349.716988) (xy 39.135347 -349.664126) (xy 39.127407 -349.609552) (xy 39.126922 -349.581978)
			(xy 39.127334 -349.554723) (xy 39.135095 -349.500769) (xy 39.150456 -349.448468) (xy 39.173103 -349.398886)
			(xy 39.202576 -349.353031) (xy 39.238275 -349.311838) (xy 39.279473 -349.276145) (xy 39.325332 -349.246678)
			(xy 39.374917 -349.224037) (xy 39.42722 -349.208684) (xy 39.481175 -349.200931) (xy 39.50843 -349.20047)
			(xy 39.508938 -349.20047) (xy 39.54272 -349.201994) (xy 39.55288 -349.20301) (xy 39.572184 -349.196914)
			(xy 39.635176 -349.144082) (xy 39.642449 -349.137342) (xy 39.651741 -349.11985) (xy 39.65321 -349.110046)
			(xy 39.65321 -349.109284) (xy 39.656162 -349.081135) (xy 39.669356 -349.026097) (xy 39.690541 -348.973613)
			(xy 39.719249 -348.924837) (xy 39.754852 -348.88084) (xy 39.796566 -348.842588) (xy 39.843476 -348.810921)
			(xy 39.894551 -348.786535) (xy 39.948669 -348.769966) (xy 40.004641 -348.761577) (xy 40.03294 -348.76105)
			(xy 40.033194 -348.76105) (xy 40.051213 -348.761277) (xy 40.087088 -348.764707) (xy 40.104822 -348.767908)
			(xy 40.114474 -348.769686) (xy 40.133524 -348.76613) (xy 40.208454 -348.718124) (xy 40.219884 -348.702376)
			(xy 40.22217 -348.692978) (xy 40.229625 -348.665951) (xy 40.251248 -348.614227) (xy 40.280205 -348.566223)
			(xy 40.315873 -348.522971) (xy 40.357485 -348.485403) (xy 40.404145 -348.454326) (xy 40.454849 -348.43041)
			(xy 40.508507 -348.414169) (xy 40.563963 -348.405952) (xy 40.591994 -348.40545) (xy 40.619243 -348.405983)
			(xy 40.673187 -348.413738) (xy 40.725478 -348.42909) (xy 40.775053 -348.451727) (xy 40.820901 -348.481189)
			(xy 40.86209 -348.516876) (xy 40.897782 -348.55806) (xy 40.92725 -348.603905) (xy 40.949893 -348.653477)
			(xy 40.965252 -348.705766) (xy 40.973013 -348.759709) (xy 40.973502 -348.786958) (xy 40.973007 -348.814531)
			(xy 40.96506 -348.869103) (xy 40.949341 -348.921962) (xy 40.926176 -348.972008) (xy 40.896049 -349.018199)
			(xy 40.859587 -349.059571) (xy 40.838882 -349.077788) (xy 40.830809 -349.085345) (xy 40.821454 -349.105355)
			(xy 40.820848 -349.116396) (xy 40.820848 -349.19412) (xy 40.821445 -349.205166) (xy 40.830788 -349.225188)
			(xy 40.838882 -349.232728) (xy 40.859606 -349.250925) (xy 40.896076 -349.292296) (xy 40.926207 -349.338489)
			(xy 40.949371 -349.38854) (xy 40.965084 -349.441405) (xy 40.973019 -349.495982) (xy 40.973502 -349.523558)
			(xy 40.973007 -349.551131) (xy 40.96506 -349.605703) (xy 40.964486 -349.607632) (xy 42.080178 -349.607632)
			(xy 42.084249 -349.55201) (xy 42.096375 -349.497573) (xy 42.116298 -349.445482) (xy 42.143594 -349.396847)
			(xy 42.17768 -349.352704) (xy 42.217829 -349.313995) (xy 42.263187 -349.281544) (xy 42.312787 -349.256043)
			(xy 42.365571 -349.238036) (xy 42.420414 -349.227906) (xy 42.476148 -349.225869) (xy 42.531585 -349.231969)
			(xy 42.585542 -349.246075) (xy 42.636871 -349.267887) (xy 42.684477 -349.296941) (xy 42.727345 -349.332616)
			(xy 42.764562 -349.374153) (xy 42.795335 -349.420666) (xy 42.819007 -349.471163) (xy 42.835075 -349.52457)
			(xy 42.843195 -349.579746) (xy 42.843704 -349.607632) (xy 42.843195 -349.635518) (xy 42.835075 -349.690694)
			(xy 42.819007 -349.744101) (xy 42.795335 -349.794598) (xy 42.764562 -349.841111) (xy 42.727345 -349.882648)
			(xy 42.684477 -349.918323) (xy 42.636871 -349.947377) (xy 42.585542 -349.969189) (xy 42.531585 -349.983295)
			(xy 42.476148 -349.989395) (xy 42.420414 -349.987358) (xy 42.365571 -349.977228) (xy 42.312787 -349.959221)
			(xy 42.263187 -349.93372) (xy 42.217829 -349.901269) (xy 42.17768 -349.86256) (xy 42.143594 -349.818417)
			(xy 42.116298 -349.769782) (xy 42.096375 -349.717691) (xy 42.084249 -349.663254) (xy 42.080178 -349.607632)
			(xy 40.964486 -349.607632) (xy 40.949341 -349.658562) (xy 40.926176 -349.708608) (xy 40.896049 -349.754799)
			(xy 40.859587 -349.796171) (xy 40.838882 -349.814388) (xy 40.830809 -349.821945) (xy 40.821454 -349.841955)
			(xy 40.820848 -349.852996) (xy 40.820848 -349.93072) (xy 40.821445 -349.941766) (xy 40.830788 -349.961788)
			(xy 40.838882 -349.969328) (xy 40.859606 -349.987525) (xy 40.896076 -350.028896) (xy 40.926207 -350.075089)
			(xy 40.949371 -350.12514) (xy 40.965084 -350.178005) (xy 40.973019 -350.232582) (xy 40.973502 -350.260158)
			(xy 40.973006 -350.28741) (xy 40.965254 -350.34136) (xy 40.949903 -350.393658) (xy 40.927265 -350.443238)
			(xy 40.897801 -350.489092) (xy 40.885767 -350.502982) (xy 41.501058 -350.502982) (xy 41.505129 -350.44736)
			(xy 41.517255 -350.392923) (xy 41.537178 -350.340832) (xy 41.564474 -350.292197) (xy 41.59856 -350.248054)
			(xy 41.638709 -350.209345) (xy 41.684067 -350.176894) (xy 41.733667 -350.151393) (xy 41.786451 -350.133386)
			(xy 41.841294 -350.123256) (xy 41.897028 -350.121219) (xy 41.952465 -350.127319) (xy 42.006422 -350.141425)
			(xy 42.057751 -350.163237) (xy 42.105357 -350.192291) (xy 42.148225 -350.227966) (xy 42.185442 -350.269503)
			(xy 42.216215 -350.316016) (xy 42.239887 -350.366513) (xy 42.255955 -350.41992) (xy 42.264075 -350.475096)
			(xy 42.264584 -350.502982) (xy 42.264075 -350.530868) (xy 42.255955 -350.586044) (xy 42.239887 -350.639451)
			(xy 42.216215 -350.689948) (xy 42.185442 -350.736461) (xy 42.148225 -350.777998) (xy 42.105357 -350.813673)
			(xy 42.057751 -350.842727) (xy 42.006422 -350.864539) (xy 41.952465 -350.878645) (xy 41.897028 -350.884745)
			(xy 41.841294 -350.882708) (xy 41.786451 -350.872578) (xy 41.733667 -350.854571) (xy 41.684067 -350.82907)
			(xy 41.638709 -350.796619) (xy 41.59856 -350.75791) (xy 41.564474 -350.713767) (xy 41.537178 -350.665132)
			(xy 41.517255 -350.613041) (xy 41.505129 -350.558604) (xy 41.501058 -350.502982) (xy 40.885767 -350.502982)
			(xy 40.862111 -350.530285) (xy 40.820921 -350.565979) (xy 40.77507 -350.595448) (xy 40.725492 -350.618091)
			(xy 40.673195 -350.633447) (xy 40.619246 -350.641203) (xy 40.591994 -350.641666) (xy 40.564137 -350.641174)
			(xy 40.509019 -350.633048) (xy 40.455667 -350.617) (xy 40.405213 -350.59337) (xy 40.358727 -350.56266)
			(xy 40.317198 -350.52552) (xy 40.281506 -350.482741) (xy 40.252409 -350.435229) (xy 40.230524 -350.383993)
			(xy 40.222932 -350.357186) (xy 40.220646 -350.348296) (xy 40.209978 -350.333056) (xy 40.138096 -350.285304)
			(xy 40.120062 -350.28124) (xy 40.110918 -350.28251) (xy 40.097901 -350.284175) (xy 40.071717 -350.285958)
			(xy 40.058594 -350.286066) (xy 40.044445 -350.285973) (xy 40.016222 -350.283938) (xy 40.002206 -350.282002)
			(xy 39.9923 -350.280478) (xy 39.972488 -350.285304) (xy 39.898066 -350.341184) (xy 39.887906 -350.35871)
			(xy 39.886636 -350.36887) (xy 39.88255 -350.396023) (xy 39.867574 -350.448852) (xy 39.845181 -350.498989)
			(xy 39.815832 -350.545399) (xy 39.780135 -350.587122) (xy 39.738825 -350.623298) (xy 39.692757 -350.653179)
			(xy 39.642881 -350.676149) (xy 39.590228 -350.691732) (xy 39.535885 -350.699607) (xy 39.50843 -350.700086)
			(xy 39.481177 -350.699617) (xy 39.427225 -350.691863) (xy 39.374926 -350.67651) (xy 39.325344 -350.653869)
			(xy 39.27949 -350.624402) (xy 39.238297 -350.588709) (xy 39.202602 -350.547516) (xy 39.173135 -350.501663)
			(xy 39.150493 -350.452082) (xy 39.135138 -350.399783) (xy 39.127384 -350.345831) (xy 39.126922 -350.318578)
			(xy 36.986036 -350.318578) (xy 36.988666 -350.327539) (xy 36.996418 -350.381494) (xy 36.996878 -350.408748)
			(xy 36.996225 -350.440311) (xy 36.985835 -350.502577) (xy 36.965347 -350.562286) (xy 36.950904 -350.590358)
			(xy 36.946078 -350.599248) (xy 36.944046 -350.618806) (xy 36.966906 -350.697292) (xy 36.970155 -350.706712)
			(xy 36.982565 -350.722273) (xy 36.991036 -350.727518) (xy 37.016115 -350.742104) (xy 37.062 -350.777599)
			(xy 37.101978 -350.819635) (xy 37.135127 -350.867242) (xy 37.160682 -350.919322) (xy 37.178052 -350.974672)
			(xy 37.186837 -351.032014) (xy 37.187378 -351.06102) (xy 37.186892 -351.088271) (xy 37.179136 -351.142219)
			(xy 37.168447 -351.178622) (xy 42.839894 -351.178622) (xy 42.840395 -351.151148) (xy 42.848283 -351.096769)
			(xy 42.8639 -351.044087) (xy 42.886922 -350.994194) (xy 42.91687 -350.948124) (xy 42.934636 -350.927162)
			(xy 42.93489 -350.926908) (xy 42.940478 -350.919823) (xy 42.946724 -350.902905) (xy 42.947082 -350.893888)
			(xy 42.947082 -350.826324) (xy 42.946717 -350.817308) (xy 42.940475 -350.800391) (xy 42.93489 -350.793304)
			(xy 42.934382 -350.792796) (xy 42.916648 -350.77185) (xy 42.886766 -350.725817) (xy 42.8638 -350.675972)
			(xy 42.848226 -350.623347) (xy 42.840365 -350.569031) (xy 42.839894 -350.54159) (xy 42.84038 -350.514339)
			(xy 42.848136 -350.460391) (xy 42.863491 -350.408096) (xy 42.886133 -350.358519) (xy 42.915599 -350.312669)
			(xy 42.95129 -350.271478) (xy 42.992481 -350.235787) (xy 43.038331 -350.206321) (xy 43.087908 -350.183679)
			(xy 43.140203 -350.168324) (xy 43.194151 -350.160568) (xy 43.248653 -350.160568) (xy 43.302601 -350.168324)
			(xy 43.354896 -350.183679) (xy 43.404473 -350.206321) (xy 43.450323 -350.235787) (xy 43.491514 -350.271478)
			(xy 43.527205 -350.312669) (xy 43.556671 -350.358519) (xy 43.579313 -350.408096) (xy 43.594668 -350.460391)
			(xy 43.602424 -350.514339) (xy 43.60291 -350.54159) (xy 43.602415 -350.569064) (xy 43.594525 -350.623443)
			(xy 43.578907 -350.676126) (xy 43.576265 -350.681852) (xy 43.844675 -350.681852) (xy 43.844675 -350.627348)
			(xy 43.852432 -350.573398) (xy 43.867789 -350.521102) (xy 43.890431 -350.471523) (xy 43.919899 -350.425671)
			(xy 43.955593 -350.38448) (xy 43.996786 -350.348788) (xy 44.042639 -350.319322) (xy 44.092218 -350.296682)
			(xy 44.144516 -350.281329) (xy 44.198466 -350.273574) (xy 44.225718 -350.273112) (xy 44.225972 -350.273112)
			(xy 44.251175 -350.273528) (xy 44.301142 -350.280163) (xy 44.349797 -350.293335) (xy 44.396287 -350.312813)
			(xy 44.41825 -350.325182) (xy 44.428156 -350.331024) (xy 44.45 -350.333056) (xy 44.544742 -350.299528)
			(xy 44.56049 -350.284034) (xy 44.564554 -350.27362) (xy 44.575283 -350.246857) (xy 44.603565 -350.196615)
			(xy 44.639089 -350.151205) (xy 44.681046 -350.111661) (xy 44.728479 -350.078885) (xy 44.780306 -350.053625)
			(xy 44.835345 -350.036457) (xy 44.892342 -350.027771) (xy 44.92117 -350.02724) (xy 44.948424 -350.027683)
			(xy 45.002378 -350.035437) (xy 45.05468 -350.050792) (xy 45.104263 -350.073435) (xy 45.150118 -350.102904)
			(xy 45.191313 -350.1386) (xy 45.227007 -350.179796) (xy 45.256474 -350.225653) (xy 45.279114 -350.275237)
			(xy 45.291836 -350.318578) (xy 47.432722 -350.318578) (xy 47.433234 -350.291005) (xy 47.441176 -350.236434)
			(xy 47.456891 -350.183575) (xy 47.480052 -350.133528) (xy 47.510177 -350.087337) (xy 47.546638 -350.045965)
			(xy 47.567342 -350.027748) (xy 47.575403 -350.02018) (xy 47.584763 -350.000178) (xy 47.585376 -349.98914)
			(xy 47.585376 -349.911416) (xy 47.584807 -349.900367) (xy 47.575443 -349.880345) (xy 47.567342 -349.872808)
			(xy 47.54664 -349.854587) (xy 47.510167 -349.813221) (xy 47.480033 -349.767034) (xy 47.456865 -349.716988)
			(xy 47.441147 -349.664126) (xy 47.433207 -349.609552) (xy 47.432722 -349.581978) (xy 47.433134 -349.554723)
			(xy 47.440895 -349.500769) (xy 47.456256 -349.448468) (xy 47.478903 -349.398886) (xy 47.508376 -349.353031)
			(xy 47.544075 -349.311838) (xy 47.585273 -349.276145) (xy 47.631132 -349.246678) (xy 47.680717 -349.224037)
			(xy 47.73302 -349.208684) (xy 47.786975 -349.200931) (xy 47.81423 -349.20047) (xy 47.814738 -349.20047)
			(xy 47.84852 -349.201994) (xy 47.85868 -349.20301) (xy 47.877984 -349.196914) (xy 47.940976 -349.144082)
			(xy 47.948249 -349.137342) (xy 47.957541 -349.11985) (xy 47.95901 -349.110046) (xy 47.95901 -349.109284)
			(xy 47.961962 -349.081135) (xy 47.975156 -349.026097) (xy 47.996341 -348.973613) (xy 48.025049 -348.924837)
			(xy 48.060652 -348.88084) (xy 48.102366 -348.842588) (xy 48.149276 -348.810921) (xy 48.200351 -348.786535)
			(xy 48.254469 -348.769966) (xy 48.310441 -348.761577) (xy 48.33874 -348.76105) (xy 48.338994 -348.76105)
			(xy 48.357013 -348.761277) (xy 48.392888 -348.764707) (xy 48.410622 -348.767908) (xy 48.420274 -348.769686)
			(xy 48.439324 -348.76613) (xy 48.514254 -348.718124) (xy 48.525684 -348.702376) (xy 48.52797 -348.692978)
			(xy 48.535425 -348.665951) (xy 48.557048 -348.614227) (xy 48.586005 -348.566223) (xy 48.621673 -348.522971)
			(xy 48.663285 -348.485403) (xy 48.709945 -348.454326) (xy 48.760649 -348.43041) (xy 48.814307 -348.414169)
			(xy 48.869763 -348.405952) (xy 48.897794 -348.40545) (xy 48.925043 -348.405983) (xy 48.978987 -348.413738)
			(xy 49.031278 -348.42909) (xy 49.080853 -348.451727) (xy 49.126701 -348.481189) (xy 49.16789 -348.516876)
			(xy 49.203582 -348.55806) (xy 49.23305 -348.603905) (xy 49.255693 -348.653477) (xy 49.271052 -348.705766)
			(xy 49.278813 -348.759709) (xy 49.279302 -348.786958) (xy 49.278807 -348.814531) (xy 49.27086 -348.869103)
			(xy 49.255141 -348.921962) (xy 49.231976 -348.972008) (xy 49.201849 -349.018199) (xy 49.165387 -349.059571)
			(xy 49.144682 -349.077788) (xy 49.136609 -349.085345) (xy 49.127254 -349.105355) (xy 49.126648 -349.116396)
			(xy 49.126648 -349.19412) (xy 49.127245 -349.205166) (xy 49.136588 -349.225188) (xy 49.144682 -349.232728)
			(xy 49.165406 -349.250925) (xy 49.201876 -349.292296) (xy 49.232007 -349.338489) (xy 49.255171 -349.38854)
			(xy 49.270884 -349.441405) (xy 49.278819 -349.495982) (xy 49.279302 -349.523558) (xy 49.278807 -349.551131)
			(xy 49.27086 -349.605703) (xy 49.270286 -349.607632) (xy 50.436778 -349.607632) (xy 50.440849 -349.55201)
			(xy 50.452975 -349.497573) (xy 50.472898 -349.445482) (xy 50.500194 -349.396847) (xy 50.53428 -349.352704)
			(xy 50.574429 -349.313995) (xy 50.619787 -349.281544) (xy 50.669387 -349.256043) (xy 50.722171 -349.238036)
			(xy 50.777014 -349.227906) (xy 50.832748 -349.225869) (xy 50.888185 -349.231969) (xy 50.942142 -349.246075)
			(xy 50.993471 -349.267887) (xy 51.041077 -349.296941) (xy 51.083945 -349.332616) (xy 51.121162 -349.374153)
			(xy 51.151935 -349.420666) (xy 51.175607 -349.471163) (xy 51.191675 -349.52457) (xy 51.199795 -349.579746)
			(xy 51.200304 -349.607632) (xy 51.199795 -349.635518) (xy 51.191675 -349.690694) (xy 51.175607 -349.744101)
			(xy 51.151935 -349.794598) (xy 51.121162 -349.841111) (xy 51.083945 -349.882648) (xy 51.041077 -349.918323)
			(xy 50.993471 -349.947377) (xy 50.942142 -349.969189) (xy 50.888185 -349.983295) (xy 50.832748 -349.989395)
			(xy 50.777014 -349.987358) (xy 50.722171 -349.977228) (xy 50.669387 -349.959221) (xy 50.619787 -349.93372)
			(xy 50.574429 -349.901269) (xy 50.53428 -349.86256) (xy 50.500194 -349.818417) (xy 50.472898 -349.769782)
			(xy 50.452975 -349.717691) (xy 50.440849 -349.663254) (xy 50.436778 -349.607632) (xy 49.270286 -349.607632)
			(xy 49.255141 -349.658562) (xy 49.231976 -349.708608) (xy 49.201849 -349.754799) (xy 49.165387 -349.796171)
			(xy 49.144682 -349.814388) (xy 49.136609 -349.821945) (xy 49.127254 -349.841955) (xy 49.126648 -349.852996)
			(xy 49.126648 -349.93072) (xy 49.127245 -349.941766) (xy 49.136588 -349.961788) (xy 49.144682 -349.969328)
			(xy 49.165406 -349.987525) (xy 49.201876 -350.028896) (xy 49.232007 -350.075089) (xy 49.255171 -350.12514)
			(xy 49.270884 -350.178005) (xy 49.278819 -350.232582) (xy 49.279302 -350.260158) (xy 49.278806 -350.28741)
			(xy 49.271054 -350.34136) (xy 49.255703 -350.393658) (xy 49.233065 -350.443238) (xy 49.203601 -350.489092)
			(xy 49.191567 -350.502982) (xy 49.857658 -350.502982) (xy 49.861729 -350.44736) (xy 49.873855 -350.392923)
			(xy 49.893778 -350.340832) (xy 49.921074 -350.292197) (xy 49.95516 -350.248054) (xy 49.995309 -350.209345)
			(xy 50.040667 -350.176894) (xy 50.090267 -350.151393) (xy 50.143051 -350.133386) (xy 50.197894 -350.123256)
			(xy 50.253628 -350.121219) (xy 50.309065 -350.127319) (xy 50.363022 -350.141425) (xy 50.414351 -350.163237)
			(xy 50.461957 -350.192291) (xy 50.504825 -350.227966) (xy 50.542042 -350.269503) (xy 50.572815 -350.316016)
			(xy 50.596487 -350.366513) (xy 50.612555 -350.41992) (xy 50.620675 -350.475096) (xy 50.621184 -350.502982)
			(xy 50.620675 -350.530868) (xy 50.612555 -350.586044) (xy 50.596487 -350.639451) (xy 50.572815 -350.689948)
			(xy 50.542042 -350.736461) (xy 50.504825 -350.777998) (xy 50.461957 -350.813673) (xy 50.414351 -350.842727)
			(xy 50.363022 -350.864539) (xy 50.309065 -350.878645) (xy 50.253628 -350.884745) (xy 50.197894 -350.882708)
			(xy 50.143051 -350.872578) (xy 50.090267 -350.854571) (xy 50.040667 -350.82907) (xy 49.995309 -350.796619)
			(xy 49.95516 -350.75791) (xy 49.921074 -350.713767) (xy 49.893778 -350.665132) (xy 49.873855 -350.613041)
			(xy 49.861729 -350.558604) (xy 49.857658 -350.502982) (xy 49.191567 -350.502982) (xy 49.167911 -350.530285)
			(xy 49.126721 -350.565979) (xy 49.08087 -350.595448) (xy 49.031292 -350.618091) (xy 48.978995 -350.633447)
			(xy 48.925046 -350.641203) (xy 48.897794 -350.641666) (xy 48.869937 -350.641174) (xy 48.814819 -350.633048)
			(xy 48.761467 -350.617) (xy 48.711013 -350.59337) (xy 48.664527 -350.56266) (xy 48.622998 -350.52552)
			(xy 48.587306 -350.482741) (xy 48.558209 -350.435229) (xy 48.536324 -350.383993) (xy 48.528732 -350.357186)
			(xy 48.526446 -350.348296) (xy 48.515778 -350.333056) (xy 48.443896 -350.285304) (xy 48.425862 -350.28124)
			(xy 48.416718 -350.28251) (xy 48.403701 -350.284175) (xy 48.377517 -350.285958) (xy 48.364394 -350.286066)
			(xy 48.350245 -350.285973) (xy 48.322022 -350.283938) (xy 48.308006 -350.282002) (xy 48.2981 -350.280478)
			(xy 48.278288 -350.285304) (xy 48.203866 -350.341184) (xy 48.193706 -350.35871) (xy 48.192436 -350.36887)
			(xy 48.18835 -350.396023) (xy 48.173374 -350.448852) (xy 48.150981 -350.498989) (xy 48.121632 -350.545399)
			(xy 48.085935 -350.587122) (xy 48.044625 -350.623298) (xy 47.998557 -350.653179) (xy 47.948681 -350.676149)
			(xy 47.896028 -350.691732) (xy 47.841685 -350.699607) (xy 47.81423 -350.700086) (xy 47.786977 -350.699617)
			(xy 47.733025 -350.691863) (xy 47.680726 -350.67651) (xy 47.631144 -350.653869) (xy 47.58529 -350.624402)
			(xy 47.544097 -350.588709) (xy 47.508402 -350.547516) (xy 47.478935 -350.501663) (xy 47.456293 -350.452082)
			(xy 47.440938 -350.399783) (xy 47.433184 -350.345831) (xy 47.432722 -350.318578) (xy 45.291836 -350.318578)
			(xy 45.294466 -350.327539) (xy 45.302218 -350.381494) (xy 45.302678 -350.408748) (xy 45.302025 -350.440311)
			(xy 45.291635 -350.502577) (xy 45.271147 -350.562286) (xy 45.256704 -350.590358) (xy 45.251878 -350.599248)
			(xy 45.249846 -350.618806) (xy 45.272706 -350.697292) (xy 45.275955 -350.706712) (xy 45.288365 -350.722273)
			(xy 45.296836 -350.727518) (xy 45.321915 -350.742104) (xy 45.3678 -350.777599) (xy 45.407778 -350.819635)
			(xy 45.440927 -350.867242) (xy 45.466482 -350.919322) (xy 45.483852 -350.974672) (xy 45.492637 -351.032014)
			(xy 45.493178 -351.06102) (xy 45.492692 -351.088271) (xy 45.484936 -351.142219) (xy 45.474247 -351.178622)
			(xy 51.196494 -351.178622) (xy 51.196995 -351.151148) (xy 51.204883 -351.096769) (xy 51.2205 -351.044087)
			(xy 51.243522 -350.994194) (xy 51.27347 -350.948124) (xy 51.291236 -350.927162) (xy 51.29149 -350.926908)
			(xy 51.297078 -350.919823) (xy 51.303324 -350.902905) (xy 51.303682 -350.893888) (xy 51.303682 -350.826324)
			(xy 51.303317 -350.817308) (xy 51.297075 -350.800391) (xy 51.29149 -350.793304) (xy 51.290982 -350.792796)
			(xy 51.273248 -350.77185) (xy 51.243366 -350.725817) (xy 51.2204 -350.675972) (xy 51.204826 -350.623347)
			(xy 51.196965 -350.569031) (xy 51.196494 -350.54159) (xy 51.19698 -350.514339) (xy 51.204736 -350.460391)
			(xy 51.220091 -350.408096) (xy 51.242733 -350.358519) (xy 51.272199 -350.312669) (xy 51.30789 -350.271478)
			(xy 51.349081 -350.235787) (xy 51.394931 -350.206321) (xy 51.444508 -350.183679) (xy 51.496803 -350.168324)
			(xy 51.550751 -350.160568) (xy 51.605253 -350.160568) (xy 51.659201 -350.168324) (xy 51.711496 -350.183679)
			(xy 51.761073 -350.206321) (xy 51.806923 -350.235787) (xy 51.848114 -350.271478) (xy 51.883805 -350.312669)
			(xy 51.913271 -350.358519) (xy 51.935913 -350.408096) (xy 51.951268 -350.460391) (xy 51.959024 -350.514339)
			(xy 51.95951 -350.54159) (xy 51.959015 -350.569064) (xy 51.951125 -350.623443) (xy 51.935507 -350.676126)
			(xy 51.932865 -350.681852) (xy 52.201275 -350.681852) (xy 52.201275 -350.627348) (xy 52.209032 -350.573398)
			(xy 52.224389 -350.521102) (xy 52.247031 -350.471523) (xy 52.276499 -350.425671) (xy 52.312193 -350.38448)
			(xy 52.353386 -350.348788) (xy 52.399239 -350.319322) (xy 52.448818 -350.296682) (xy 52.501116 -350.281329)
			(xy 52.555066 -350.273574) (xy 52.582318 -350.273112) (xy 52.582572 -350.273112) (xy 52.607775 -350.273528)
			(xy 52.657742 -350.280163) (xy 52.706397 -350.293335) (xy 52.752887 -350.312813) (xy 52.77485 -350.325182)
			(xy 52.784756 -350.331024) (xy 52.8066 -350.333056) (xy 52.901342 -350.299528) (xy 52.91709 -350.284034)
			(xy 52.921154 -350.27362) (xy 52.931883 -350.246857) (xy 52.960165 -350.196615) (xy 52.995689 -350.151205)
			(xy 53.037646 -350.111661) (xy 53.085079 -350.078885) (xy 53.136906 -350.053625) (xy 53.191945 -350.036457)
			(xy 53.248942 -350.027771) (xy 53.27777 -350.02724) (xy 53.305024 -350.027683) (xy 53.358978 -350.035437)
			(xy 53.41128 -350.050792) (xy 53.460863 -350.073435) (xy 53.506718 -350.102904) (xy 53.547913 -350.1386)
			(xy 53.583607 -350.179796) (xy 53.613074 -350.225653) (xy 53.635714 -350.275237) (xy 53.648436 -350.318578)
			(xy 55.789322 -350.318578) (xy 55.789834 -350.291005) (xy 55.797776 -350.236434) (xy 55.813491 -350.183575)
			(xy 55.836652 -350.133528) (xy 55.866777 -350.087337) (xy 55.903238 -350.045965) (xy 55.923942 -350.027748)
			(xy 55.932003 -350.02018) (xy 55.941363 -350.000178) (xy 55.941976 -349.98914) (xy 55.941976 -349.911416)
			(xy 55.941407 -349.900367) (xy 55.932043 -349.880345) (xy 55.923942 -349.872808) (xy 55.90324 -349.854587)
			(xy 55.866767 -349.813221) (xy 55.836633 -349.767034) (xy 55.813465 -349.716988) (xy 55.797747 -349.664126)
			(xy 55.789807 -349.609552) (xy 55.789322 -349.581978) (xy 55.789734 -349.554723) (xy 55.797495 -349.500769)
			(xy 55.812856 -349.448468) (xy 55.835503 -349.398886) (xy 55.864976 -349.353031) (xy 55.900675 -349.311838)
			(xy 55.941873 -349.276145) (xy 55.987732 -349.246678) (xy 56.037317 -349.224037) (xy 56.08962 -349.208684)
			(xy 56.143575 -349.200931) (xy 56.17083 -349.20047) (xy 56.171338 -349.20047) (xy 56.20512 -349.201994)
			(xy 56.21528 -349.20301) (xy 56.234584 -349.196914) (xy 56.297576 -349.144082) (xy 56.304849 -349.137342)
			(xy 56.314141 -349.11985) (xy 56.31561 -349.110046) (xy 56.31561 -349.109284) (xy 56.318562 -349.081135)
			(xy 56.331756 -349.026097) (xy 56.352941 -348.973613) (xy 56.381649 -348.924837) (xy 56.417252 -348.88084)
			(xy 56.458966 -348.842588) (xy 56.505876 -348.810921) (xy 56.556951 -348.786535) (xy 56.611069 -348.769966)
			(xy 56.667041 -348.761577) (xy 56.69534 -348.76105) (xy 56.695594 -348.76105) (xy 56.713613 -348.761277)
			(xy 56.749488 -348.764707) (xy 56.767222 -348.767908) (xy 56.776874 -348.769686) (xy 56.795924 -348.76613)
			(xy 56.870854 -348.718124) (xy 56.882284 -348.702376) (xy 56.88457 -348.692978) (xy 56.892025 -348.665951)
			(xy 56.913648 -348.614227) (xy 56.942605 -348.566223) (xy 56.978273 -348.522971) (xy 57.019885 -348.485403)
			(xy 57.066545 -348.454326) (xy 57.117249 -348.43041) (xy 57.170907 -348.414169) (xy 57.226363 -348.405952)
			(xy 57.254394 -348.40545) (xy 57.281643 -348.405983) (xy 57.335587 -348.413738) (xy 57.387878 -348.42909)
			(xy 57.437453 -348.451727) (xy 57.483301 -348.481189) (xy 57.52449 -348.516876) (xy 57.560182 -348.55806)
			(xy 57.58965 -348.603905) (xy 57.612293 -348.653477) (xy 57.627652 -348.705766) (xy 57.635413 -348.759709)
			(xy 57.635902 -348.786958) (xy 57.635407 -348.814531) (xy 57.62746 -348.869103) (xy 57.611741 -348.921962)
			(xy 57.588576 -348.972008) (xy 57.558449 -349.018199) (xy 57.521987 -349.059571) (xy 57.501282 -349.077788)
			(xy 57.493209 -349.085345) (xy 57.483854 -349.105355) (xy 57.483248 -349.116396) (xy 57.483248 -349.19412)
			(xy 57.483845 -349.205166) (xy 57.493188 -349.225188) (xy 57.501282 -349.232728) (xy 57.522006 -349.250925)
			(xy 57.558476 -349.292296) (xy 57.588607 -349.338489) (xy 57.611771 -349.38854) (xy 57.627484 -349.441405)
			(xy 57.635419 -349.495982) (xy 57.635902 -349.523558) (xy 57.635407 -349.551131) (xy 57.62746 -349.605703)
			(xy 57.626886 -349.607632) (xy 58.767978 -349.607632) (xy 58.772049 -349.55201) (xy 58.784175 -349.497573)
			(xy 58.804098 -349.445482) (xy 58.831394 -349.396847) (xy 58.86548 -349.352704) (xy 58.905629 -349.313995)
			(xy 58.950987 -349.281544) (xy 59.000587 -349.256043) (xy 59.053371 -349.238036) (xy 59.108214 -349.227906)
			(xy 59.163948 -349.225869) (xy 59.219385 -349.231969) (xy 59.273342 -349.246075) (xy 59.324671 -349.267887)
			(xy 59.372277 -349.296941) (xy 59.415145 -349.332616) (xy 59.452362 -349.374153) (xy 59.483135 -349.420666)
			(xy 59.506807 -349.471163) (xy 59.522875 -349.52457) (xy 59.530995 -349.579746) (xy 59.531504 -349.607632)
			(xy 59.530995 -349.635518) (xy 59.522875 -349.690694) (xy 59.506807 -349.744101) (xy 59.483135 -349.794598)
			(xy 59.452362 -349.841111) (xy 59.415145 -349.882648) (xy 59.372277 -349.918323) (xy 59.324671 -349.947377)
			(xy 59.273342 -349.969189) (xy 59.219385 -349.983295) (xy 59.163948 -349.989395) (xy 59.108214 -349.987358)
			(xy 59.053371 -349.977228) (xy 59.000587 -349.959221) (xy 58.950987 -349.93372) (xy 58.905629 -349.901269)
			(xy 58.86548 -349.86256) (xy 58.831394 -349.818417) (xy 58.804098 -349.769782) (xy 58.784175 -349.717691)
			(xy 58.772049 -349.663254) (xy 58.767978 -349.607632) (xy 57.626886 -349.607632) (xy 57.611741 -349.658562)
			(xy 57.588576 -349.708608) (xy 57.558449 -349.754799) (xy 57.521987 -349.796171) (xy 57.501282 -349.814388)
			(xy 57.493209 -349.821945) (xy 57.483854 -349.841955) (xy 57.483248 -349.852996) (xy 57.483248 -349.93072)
			(xy 57.483845 -349.941766) (xy 57.493188 -349.961788) (xy 57.501282 -349.969328) (xy 57.522006 -349.987525)
			(xy 57.558476 -350.028896) (xy 57.588607 -350.075089) (xy 57.611771 -350.12514) (xy 57.627484 -350.178005)
			(xy 57.635419 -350.232582) (xy 57.635902 -350.260158) (xy 57.635406 -350.28741) (xy 57.627654 -350.34136)
			(xy 57.612303 -350.393658) (xy 57.589665 -350.443238) (xy 57.560201 -350.489092) (xy 57.548167 -350.502982)
			(xy 58.188858 -350.502982) (xy 58.192929 -350.44736) (xy 58.205055 -350.392923) (xy 58.224978 -350.340832)
			(xy 58.252274 -350.292197) (xy 58.28636 -350.248054) (xy 58.326509 -350.209345) (xy 58.371867 -350.176894)
			(xy 58.421467 -350.151393) (xy 58.474251 -350.133386) (xy 58.529094 -350.123256) (xy 58.584828 -350.121219)
			(xy 58.640265 -350.127319) (xy 58.694222 -350.141425) (xy 58.745551 -350.163237) (xy 58.793157 -350.192291)
			(xy 58.836025 -350.227966) (xy 58.873242 -350.269503) (xy 58.904015 -350.316016) (xy 58.927687 -350.366513)
			(xy 58.943755 -350.41992) (xy 58.951875 -350.475096) (xy 58.952384 -350.502982) (xy 58.951875 -350.530868)
			(xy 58.943755 -350.586044) (xy 58.927687 -350.639451) (xy 58.904015 -350.689948) (xy 58.873242 -350.736461)
			(xy 58.836025 -350.777998) (xy 58.793157 -350.813673) (xy 58.745551 -350.842727) (xy 58.694222 -350.864539)
			(xy 58.640265 -350.878645) (xy 58.584828 -350.884745) (xy 58.529094 -350.882708) (xy 58.474251 -350.872578)
			(xy 58.421467 -350.854571) (xy 58.371867 -350.82907) (xy 58.326509 -350.796619) (xy 58.28636 -350.75791)
			(xy 58.252274 -350.713767) (xy 58.224978 -350.665132) (xy 58.205055 -350.613041) (xy 58.192929 -350.558604)
			(xy 58.188858 -350.502982) (xy 57.548167 -350.502982) (xy 57.524511 -350.530285) (xy 57.483321 -350.565979)
			(xy 57.43747 -350.595448) (xy 57.387892 -350.618091) (xy 57.335595 -350.633447) (xy 57.281646 -350.641203)
			(xy 57.254394 -350.641666) (xy 57.226537 -350.641174) (xy 57.171419 -350.633048) (xy 57.118067 -350.617)
			(xy 57.067613 -350.59337) (xy 57.021127 -350.56266) (xy 56.979598 -350.52552) (xy 56.943906 -350.482741)
			(xy 56.914809 -350.435229) (xy 56.892924 -350.383993) (xy 56.885332 -350.357186) (xy 56.883046 -350.348296)
			(xy 56.872378 -350.333056) (xy 56.800496 -350.285304) (xy 56.782462 -350.28124) (xy 56.773318 -350.28251)
			(xy 56.760301 -350.284175) (xy 56.734117 -350.285958) (xy 56.720994 -350.286066) (xy 56.706845 -350.285973)
			(xy 56.678622 -350.283938) (xy 56.664606 -350.282002) (xy 56.6547 -350.280478) (xy 56.634888 -350.285304)
			(xy 56.560466 -350.341184) (xy 56.550306 -350.35871) (xy 56.549036 -350.36887) (xy 56.54495 -350.396023)
			(xy 56.529974 -350.448852) (xy 56.507581 -350.498989) (xy 56.478232 -350.545399) (xy 56.442535 -350.587122)
			(xy 56.401225 -350.623298) (xy 56.355157 -350.653179) (xy 56.305281 -350.676149) (xy 56.252628 -350.691732)
			(xy 56.198285 -350.699607) (xy 56.17083 -350.700086) (xy 56.143577 -350.699617) (xy 56.089625 -350.691863)
			(xy 56.037326 -350.67651) (xy 55.987744 -350.653869) (xy 55.94189 -350.624402) (xy 55.900697 -350.588709)
			(xy 55.865002 -350.547516) (xy 55.835535 -350.501663) (xy 55.812893 -350.452082) (xy 55.797538 -350.399783)
			(xy 55.789784 -350.345831) (xy 55.789322 -350.318578) (xy 53.648436 -350.318578) (xy 53.651066 -350.327539)
			(xy 53.658818 -350.381494) (xy 53.659278 -350.408748) (xy 53.658625 -350.440311) (xy 53.648235 -350.502577)
			(xy 53.627747 -350.562286) (xy 53.613304 -350.590358) (xy 53.608478 -350.599248) (xy 53.606446 -350.618806)
			(xy 53.629306 -350.697292) (xy 53.632555 -350.706712) (xy 53.644965 -350.722273) (xy 53.653436 -350.727518)
			(xy 53.678515 -350.742104) (xy 53.7244 -350.777599) (xy 53.764378 -350.819635) (xy 53.797527 -350.867242)
			(xy 53.823082 -350.919322) (xy 53.840452 -350.974672) (xy 53.849237 -351.032014) (xy 53.849778 -351.06102)
			(xy 53.849292 -351.088271) (xy 53.841536 -351.142219) (xy 53.830847 -351.178622) (xy 59.527694 -351.178622)
			(xy 59.528195 -351.151148) (xy 59.536083 -351.096769) (xy 59.5517 -351.044087) (xy 59.574722 -350.994194)
			(xy 59.60467 -350.948124) (xy 59.622436 -350.927162) (xy 59.62269 -350.926908) (xy 59.628278 -350.919823)
			(xy 59.634524 -350.902905) (xy 59.634882 -350.893888) (xy 59.634882 -350.826324) (xy 59.634517 -350.817308)
			(xy 59.628275 -350.800391) (xy 59.62269 -350.793304) (xy 59.622182 -350.792796) (xy 59.604448 -350.77185)
			(xy 59.574566 -350.725817) (xy 59.5516 -350.675972) (xy 59.536026 -350.623347) (xy 59.528165 -350.569031)
			(xy 59.527694 -350.54159) (xy 59.52818 -350.514339) (xy 59.535936 -350.460391) (xy 59.551291 -350.408096)
			(xy 59.573933 -350.358519) (xy 59.603399 -350.312669) (xy 59.63909 -350.271478) (xy 59.680281 -350.235787)
			(xy 59.726131 -350.206321) (xy 59.775708 -350.183679) (xy 59.828003 -350.168324) (xy 59.881951 -350.160568)
			(xy 59.936453 -350.160568) (xy 59.990401 -350.168324) (xy 60.042696 -350.183679) (xy 60.092273 -350.206321)
			(xy 60.138123 -350.235787) (xy 60.179314 -350.271478) (xy 60.215005 -350.312669) (xy 60.244471 -350.358519)
			(xy 60.267113 -350.408096) (xy 60.282468 -350.460391) (xy 60.290224 -350.514339) (xy 60.29071 -350.54159)
			(xy 60.290215 -350.569064) (xy 60.282325 -350.623443) (xy 60.266707 -350.676126) (xy 60.264065 -350.681852)
			(xy 60.532475 -350.681852) (xy 60.532475 -350.627348) (xy 60.540232 -350.573398) (xy 60.555589 -350.521102)
			(xy 60.578231 -350.471523) (xy 60.607699 -350.425671) (xy 60.643393 -350.38448) (xy 60.684586 -350.348788)
			(xy 60.730439 -350.319322) (xy 60.780018 -350.296682) (xy 60.832316 -350.281329) (xy 60.886266 -350.273574)
			(xy 60.913518 -350.273112) (xy 60.913772 -350.273112) (xy 60.938975 -350.273528) (xy 60.988942 -350.280163)
			(xy 61.037597 -350.293335) (xy 61.084087 -350.312813) (xy 61.10605 -350.325182) (xy 61.115956 -350.331024)
			(xy 61.1378 -350.333056) (xy 61.232542 -350.299528) (xy 61.24829 -350.284034) (xy 61.252354 -350.27362)
			(xy 61.263083 -350.246857) (xy 61.291365 -350.196615) (xy 61.326889 -350.151205) (xy 61.368846 -350.111661)
			(xy 61.416279 -350.078885) (xy 61.468106 -350.053625) (xy 61.523145 -350.036457) (xy 61.580142 -350.027771)
			(xy 61.60897 -350.02724) (xy 61.636224 -350.027683) (xy 61.690178 -350.035437) (xy 61.74248 -350.050792)
			(xy 61.792063 -350.073435) (xy 61.837918 -350.102904) (xy 61.879113 -350.1386) (xy 61.914807 -350.179796)
			(xy 61.944274 -350.225653) (xy 61.966914 -350.275237) (xy 61.979636 -350.318578) (xy 64.120522 -350.318578)
			(xy 64.121034 -350.291005) (xy 64.128976 -350.236434) (xy 64.144691 -350.183575) (xy 64.167852 -350.133528)
			(xy 64.197977 -350.087337) (xy 64.234438 -350.045965) (xy 64.255142 -350.027748) (xy 64.263203 -350.02018)
			(xy 64.272563 -350.000178) (xy 64.273176 -349.98914) (xy 64.273176 -349.911416) (xy 64.272607 -349.900367)
			(xy 64.263243 -349.880345) (xy 64.255142 -349.872808) (xy 64.23444 -349.854587) (xy 64.197967 -349.813221)
			(xy 64.167833 -349.767034) (xy 64.144665 -349.716988) (xy 64.128947 -349.664126) (xy 64.121007 -349.609552)
			(xy 64.120522 -349.581978) (xy 64.120934 -349.554723) (xy 64.128695 -349.500769) (xy 64.144056 -349.448468)
			(xy 64.166703 -349.398886) (xy 64.196176 -349.353031) (xy 64.231875 -349.311838) (xy 64.273073 -349.276145)
			(xy 64.318932 -349.246678) (xy 64.368517 -349.224037) (xy 64.42082 -349.208684) (xy 64.474775 -349.200931)
			(xy 64.50203 -349.20047) (xy 64.502538 -349.20047) (xy 64.53632 -349.201994) (xy 64.54648 -349.20301)
			(xy 64.565784 -349.196914) (xy 64.628776 -349.144082) (xy 64.636049 -349.137342) (xy 64.645341 -349.11985)
			(xy 64.64681 -349.110046) (xy 64.64681 -349.109284) (xy 64.649762 -349.081135) (xy 64.662956 -349.026097)
			(xy 64.684141 -348.973613) (xy 64.712849 -348.924837) (xy 64.748452 -348.88084) (xy 64.790166 -348.842588)
			(xy 64.837076 -348.810921) (xy 64.888151 -348.786535) (xy 64.942269 -348.769966) (xy 64.998241 -348.761577)
			(xy 65.02654 -348.76105) (xy 65.026794 -348.76105) (xy 65.044813 -348.761277) (xy 65.080688 -348.764707)
			(xy 65.098422 -348.767908) (xy 65.108074 -348.769686) (xy 65.127124 -348.76613) (xy 65.202054 -348.718124)
			(xy 65.213484 -348.702376) (xy 65.21577 -348.692978) (xy 65.223225 -348.665951) (xy 65.244848 -348.614227)
			(xy 65.273805 -348.566223) (xy 65.309473 -348.522971) (xy 65.351085 -348.485403) (xy 65.397745 -348.454326)
			(xy 65.448449 -348.43041) (xy 65.502107 -348.414169) (xy 65.557563 -348.405952) (xy 65.585594 -348.40545)
			(xy 65.612843 -348.405983) (xy 65.666787 -348.413738) (xy 65.719078 -348.42909) (xy 65.768653 -348.451727)
			(xy 65.814501 -348.481189) (xy 65.85569 -348.516876) (xy 65.891382 -348.55806) (xy 65.92085 -348.603905)
			(xy 65.943493 -348.653477) (xy 65.958852 -348.705766) (xy 65.966613 -348.759709) (xy 65.967102 -348.786958)
			(xy 65.966607 -348.814531) (xy 65.95866 -348.869103) (xy 65.942941 -348.921962) (xy 65.919776 -348.972008)
			(xy 65.889649 -349.018199) (xy 65.853187 -349.059571) (xy 65.832482 -349.077788) (xy 65.824409 -349.085345)
			(xy 65.815054 -349.105355) (xy 65.814448 -349.116396) (xy 65.814448 -349.19412) (xy 65.815045 -349.205166)
			(xy 65.824388 -349.225188) (xy 65.832482 -349.232728) (xy 65.853206 -349.250925) (xy 65.889676 -349.292296)
			(xy 65.919807 -349.338489) (xy 65.942971 -349.38854) (xy 65.958684 -349.441405) (xy 65.966619 -349.495982)
			(xy 65.967102 -349.523558) (xy 65.966607 -349.551131) (xy 65.95866 -349.605703) (xy 65.942941 -349.658562)
			(xy 65.919776 -349.708608) (xy 65.889649 -349.754799) (xy 65.853187 -349.796171) (xy 65.832482 -349.814388)
			(xy 65.824409 -349.821945) (xy 65.815054 -349.841955) (xy 65.814448 -349.852996) (xy 65.814448 -349.93072)
			(xy 65.815045 -349.941766) (xy 65.824388 -349.961788) (xy 65.832482 -349.969328) (xy 65.853206 -349.987525)
			(xy 65.889676 -350.028896) (xy 65.919807 -350.075089) (xy 65.942971 -350.12514) (xy 65.958684 -350.178005)
			(xy 65.966619 -350.232582) (xy 65.967102 -350.260158) (xy 65.966606 -350.28741) (xy 65.958854 -350.34136)
			(xy 65.943503 -350.393658) (xy 65.920865 -350.443238) (xy 65.891401 -350.489092) (xy 65.855711 -350.530285)
			(xy 65.814521 -350.565979) (xy 65.76867 -350.595448) (xy 65.719092 -350.618091) (xy 65.666795 -350.633447)
			(xy 65.612846 -350.641203) (xy 65.585594 -350.641666) (xy 65.557737 -350.641174) (xy 65.502619 -350.633048)
			(xy 65.449267 -350.617) (xy 65.398813 -350.59337) (xy 65.352327 -350.56266) (xy 65.310798 -350.52552)
			(xy 65.275106 -350.482741) (xy 65.246009 -350.435229) (xy 65.224124 -350.383993) (xy 65.216532 -350.357186)
			(xy 65.214246 -350.348296) (xy 65.203578 -350.333056) (xy 65.131696 -350.285304) (xy 65.113662 -350.28124)
			(xy 65.104518 -350.28251) (xy 65.091501 -350.284175) (xy 65.065317 -350.285958) (xy 65.052194 -350.286066)
			(xy 65.038045 -350.285973) (xy 65.009822 -350.283938) (xy 64.995806 -350.282002) (xy 64.9859 -350.280478)
			(xy 64.966088 -350.285304) (xy 64.891666 -350.341184) (xy 64.881506 -350.35871) (xy 64.880236 -350.36887)
			(xy 64.87615 -350.396023) (xy 64.861174 -350.448852) (xy 64.838781 -350.498989) (xy 64.809432 -350.545399)
			(xy 64.773735 -350.587122) (xy 64.732425 -350.623298) (xy 64.686357 -350.653179) (xy 64.636481 -350.676149)
			(xy 64.583828 -350.691732) (xy 64.529485 -350.699607) (xy 64.50203 -350.700086) (xy 64.474777 -350.699617)
			(xy 64.420825 -350.691863) (xy 64.368526 -350.67651) (xy 64.318944 -350.653869) (xy 64.27309 -350.624402)
			(xy 64.231897 -350.588709) (xy 64.196202 -350.547516) (xy 64.166735 -350.501663) (xy 64.144093 -350.452082)
			(xy 64.128738 -350.399783) (xy 64.120984 -350.345831) (xy 64.120522 -350.318578) (xy 61.979636 -350.318578)
			(xy 61.982266 -350.327539) (xy 61.990018 -350.381494) (xy 61.990478 -350.408748) (xy 61.989825 -350.440311)
			(xy 61.979435 -350.502577) (xy 61.958947 -350.562286) (xy 61.944504 -350.590358) (xy 61.939678 -350.599248)
			(xy 61.937646 -350.618806) (xy 61.960506 -350.697292) (xy 61.963755 -350.706712) (xy 61.976165 -350.722273)
			(xy 61.984636 -350.727518) (xy 62.009715 -350.742104) (xy 62.0556 -350.777599) (xy 62.095578 -350.819635)
			(xy 62.128727 -350.867242) (xy 62.154282 -350.919322) (xy 62.171652 -350.974672) (xy 62.180437 -351.032014)
			(xy 62.180978 -351.06102) (xy 62.180492 -351.088271) (xy 62.172736 -351.142219) (xy 62.157381 -351.194514)
			(xy 62.134739 -351.244091) (xy 62.105273 -351.289941) (xy 62.069582 -351.331132) (xy 62.028391 -351.366823)
			(xy 61.982541 -351.396289) (xy 61.932964 -351.418931) (xy 61.880669 -351.434286) (xy 61.826721 -351.442042)
			(xy 61.772219 -351.442042) (xy 61.718271 -351.434286) (xy 61.665976 -351.418931) (xy 61.616399 -351.396289)
			(xy 61.570549 -351.366823) (xy 61.529358 -351.331132) (xy 61.493667 -351.289941) (xy 61.464201 -351.244091)
			(xy 61.441559 -351.194514) (xy 61.426204 -351.142219) (xy 61.418448 -351.088271) (xy 61.417962 -351.06102)
			(xy 61.41861 -351.029457) (xy 61.429003 -350.967191) (xy 61.449493 -350.907483) (xy 61.463936 -350.87941)
			(xy 61.468762 -350.87052) (xy 61.470794 -350.850962) (xy 61.447934 -350.772476) (xy 61.444719 -350.763041)
			(xy 61.432286 -350.747487) (xy 61.423804 -350.74225) (xy 61.416438 -350.738186) (xy 61.406532 -350.732344)
			(xy 61.384688 -350.730312) (xy 61.289946 -350.76384) (xy 61.274198 -350.779334) (xy 61.270134 -350.789748)
			(xy 61.259452 -350.81653) (xy 61.23116 -350.86677) (xy 61.195627 -350.912178) (xy 61.153663 -350.951719)
			(xy 61.106224 -350.984492) (xy 61.054392 -351.009749) (xy 60.999348 -351.026915) (xy 60.942347 -351.035598)
			(xy 60.913518 -351.036128) (xy 60.886266 -351.035626) (xy 60.832316 -351.027871) (xy 60.780018 -351.012518)
			(xy 60.730439 -350.989878) (xy 60.684586 -350.960412) (xy 60.643393 -350.92472) (xy 60.607699 -350.883529)
			(xy 60.578231 -350.837677) (xy 60.555589 -350.788098) (xy 60.540232 -350.735802) (xy 60.532475 -350.681852)
			(xy 60.264065 -350.681852) (xy 60.243684 -350.726018) (xy 60.213734 -350.772088) (xy 60.195968 -350.79305)
			(xy 60.195714 -350.793304) (xy 60.190121 -350.800386) (xy 60.183878 -350.817306) (xy 60.183522 -350.826324)
			(xy 60.183522 -350.893888) (xy 60.18388 -350.902905) (xy 60.190126 -350.919822) (xy 60.195714 -350.926908)
			(xy 60.196222 -350.927416) (xy 60.213962 -350.948356) (xy 60.243843 -350.994391) (xy 60.266808 -351.044238)
			(xy 60.282381 -351.096864) (xy 60.29024 -351.151181) (xy 60.29071 -351.178622) (xy 60.290224 -351.205873)
			(xy 60.282468 -351.259821) (xy 60.267113 -351.312116) (xy 60.244471 -351.361693) (xy 60.215005 -351.407543)
			(xy 60.179314 -351.448734) (xy 60.138123 -351.484425) (xy 60.092273 -351.513891) (xy 60.042696 -351.536533)
			(xy 59.990401 -351.551888) (xy 59.936453 -351.559644) (xy 59.881951 -351.559644) (xy 59.828003 -351.551888)
			(xy 59.775708 -351.536533) (xy 59.726131 -351.513891) (xy 59.680281 -351.484425) (xy 59.63909 -351.448734)
			(xy 59.603399 -351.407543) (xy 59.573933 -351.361693) (xy 59.551291 -351.312116) (xy 59.535936 -351.259821)
			(xy 59.52818 -351.205873) (xy 59.527694 -351.178622) (xy 53.830847 -351.178622) (xy 53.826181 -351.194514)
			(xy 53.803539 -351.244091) (xy 53.774073 -351.289941) (xy 53.738382 -351.331132) (xy 53.697191 -351.366823)
			(xy 53.651341 -351.396289) (xy 53.601764 -351.418931) (xy 53.549469 -351.434286) (xy 53.495521 -351.442042)
			(xy 53.441019 -351.442042) (xy 53.387071 -351.434286) (xy 53.334776 -351.418931) (xy 53.285199 -351.396289)
			(xy 53.239349 -351.366823) (xy 53.198158 -351.331132) (xy 53.162467 -351.289941) (xy 53.133001 -351.244091)
			(xy 53.110359 -351.194514) (xy 53.095004 -351.142219) (xy 53.087248 -351.088271) (xy 53.086762 -351.06102)
			(xy 53.08741 -351.029457) (xy 53.097803 -350.967191) (xy 53.118293 -350.907483) (xy 53.132736 -350.87941)
			(xy 53.137562 -350.87052) (xy 53.139594 -350.850962) (xy 53.116734 -350.772476) (xy 53.113519 -350.763041)
			(xy 53.101086 -350.747487) (xy 53.092604 -350.74225) (xy 53.085238 -350.738186) (xy 53.075332 -350.732344)
			(xy 53.053488 -350.730312) (xy 52.958746 -350.76384) (xy 52.942998 -350.779334) (xy 52.938934 -350.789748)
			(xy 52.928252 -350.81653) (xy 52.89996 -350.86677) (xy 52.864427 -350.912178) (xy 52.822463 -350.951719)
			(xy 52.775024 -350.984492) (xy 52.723192 -351.009749) (xy 52.668148 -351.026915) (xy 52.611147 -351.035598)
			(xy 52.582318 -351.036128) (xy 52.555066 -351.035626) (xy 52.501116 -351.027871) (xy 52.448818 -351.012518)
			(xy 52.399239 -350.989878) (xy 52.353386 -350.960412) (xy 52.312193 -350.92472) (xy 52.276499 -350.883529)
			(xy 52.247031 -350.837677) (xy 52.224389 -350.788098) (xy 52.209032 -350.735802) (xy 52.201275 -350.681852)
			(xy 51.932865 -350.681852) (xy 51.912484 -350.726018) (xy 51.882534 -350.772088) (xy 51.864768 -350.79305)
			(xy 51.864514 -350.793304) (xy 51.858921 -350.800386) (xy 51.852678 -350.817306) (xy 51.852322 -350.826324)
			(xy 51.852322 -350.893888) (xy 51.85268 -350.902905) (xy 51.858926 -350.919822) (xy 51.864514 -350.926908)
			(xy 51.865022 -350.927416) (xy 51.882762 -350.948356) (xy 51.912643 -350.994391) (xy 51.935608 -351.044238)
			(xy 51.951181 -351.096864) (xy 51.95904 -351.151181) (xy 51.95951 -351.178622) (xy 51.959024 -351.205873)
			(xy 51.951268 -351.259821) (xy 51.935913 -351.312116) (xy 51.913271 -351.361693) (xy 51.883805 -351.407543)
			(xy 51.848114 -351.448734) (xy 51.806923 -351.484425) (xy 51.761073 -351.513891) (xy 51.711496 -351.536533)
			(xy 51.659201 -351.551888) (xy 51.605253 -351.559644) (xy 51.550751 -351.559644) (xy 51.496803 -351.551888)
			(xy 51.444508 -351.536533) (xy 51.394931 -351.513891) (xy 51.349081 -351.484425) (xy 51.30789 -351.448734)
			(xy 51.272199 -351.407543) (xy 51.242733 -351.361693) (xy 51.220091 -351.312116) (xy 51.204736 -351.259821)
			(xy 51.19698 -351.205873) (xy 51.196494 -351.178622) (xy 45.474247 -351.178622) (xy 45.469581 -351.194514)
			(xy 45.446939 -351.244091) (xy 45.417473 -351.289941) (xy 45.381782 -351.331132) (xy 45.340591 -351.366823)
			(xy 45.294741 -351.396289) (xy 45.245164 -351.418931) (xy 45.192869 -351.434286) (xy 45.138921 -351.442042)
			(xy 45.084419 -351.442042) (xy 45.030471 -351.434286) (xy 44.978176 -351.418931) (xy 44.928599 -351.396289)
			(xy 44.882749 -351.366823) (xy 44.841558 -351.331132) (xy 44.805867 -351.289941) (xy 44.776401 -351.244091)
			(xy 44.753759 -351.194514) (xy 44.738404 -351.142219) (xy 44.730648 -351.088271) (xy 44.730162 -351.06102)
			(xy 44.73081 -351.029457) (xy 44.741203 -350.967191) (xy 44.761693 -350.907483) (xy 44.776136 -350.87941)
			(xy 44.780962 -350.87052) (xy 44.782994 -350.850962) (xy 44.760134 -350.772476) (xy 44.756919 -350.763041)
			(xy 44.744486 -350.747487) (xy 44.736004 -350.74225) (xy 44.728638 -350.738186) (xy 44.718732 -350.732344)
			(xy 44.696888 -350.730312) (xy 44.602146 -350.76384) (xy 44.586398 -350.779334) (xy 44.582334 -350.789748)
			(xy 44.571652 -350.81653) (xy 44.54336 -350.86677) (xy 44.507827 -350.912178) (xy 44.465863 -350.951719)
			(xy 44.418424 -350.984492) (xy 44.366592 -351.009749) (xy 44.311548 -351.026915) (xy 44.254547 -351.035598)
			(xy 44.225718 -351.036128) (xy 44.198466 -351.035626) (xy 44.144516 -351.027871) (xy 44.092218 -351.012518)
			(xy 44.042639 -350.989878) (xy 43.996786 -350.960412) (xy 43.955593 -350.92472) (xy 43.919899 -350.883529)
			(xy 43.890431 -350.837677) (xy 43.867789 -350.788098) (xy 43.852432 -350.735802) (xy 43.844675 -350.681852)
			(xy 43.576265 -350.681852) (xy 43.555884 -350.726018) (xy 43.525934 -350.772088) (xy 43.508168 -350.79305)
			(xy 43.507914 -350.793304) (xy 43.502321 -350.800386) (xy 43.496078 -350.817306) (xy 43.495722 -350.826324)
			(xy 43.495722 -350.893888) (xy 43.49608 -350.902905) (xy 43.502326 -350.919822) (xy 43.507914 -350.926908)
			(xy 43.508422 -350.927416) (xy 43.526162 -350.948356) (xy 43.556043 -350.994391) (xy 43.579008 -351.044238)
			(xy 43.594581 -351.096864) (xy 43.60244 -351.151181) (xy 43.60291 -351.178622) (xy 43.602424 -351.205873)
			(xy 43.594668 -351.259821) (xy 43.579313 -351.312116) (xy 43.556671 -351.361693) (xy 43.527205 -351.407543)
			(xy 43.491514 -351.448734) (xy 43.450323 -351.484425) (xy 43.404473 -351.513891) (xy 43.354896 -351.536533)
			(xy 43.302601 -351.551888) (xy 43.248653 -351.559644) (xy 43.194151 -351.559644) (xy 43.140203 -351.551888)
			(xy 43.087908 -351.536533) (xy 43.038331 -351.513891) (xy 42.992481 -351.484425) (xy 42.95129 -351.448734)
			(xy 42.915599 -351.407543) (xy 42.886133 -351.361693) (xy 42.863491 -351.312116) (xy 42.848136 -351.259821)
			(xy 42.84038 -351.205873) (xy 42.839894 -351.178622) (xy 37.168447 -351.178622) (xy 37.163781 -351.194514)
			(xy 37.141139 -351.244091) (xy 37.111673 -351.289941) (xy 37.075982 -351.331132) (xy 37.034791 -351.366823)
			(xy 36.988941 -351.396289) (xy 36.939364 -351.418931) (xy 36.887069 -351.434286) (xy 36.833121 -351.442042)
			(xy 36.778619 -351.442042) (xy 36.724671 -351.434286) (xy 36.672376 -351.418931) (xy 36.622799 -351.396289)
			(xy 36.576949 -351.366823) (xy 36.535758 -351.331132) (xy 36.500067 -351.289941) (xy 36.470601 -351.244091)
			(xy 36.447959 -351.194514) (xy 36.432604 -351.142219) (xy 36.424848 -351.088271) (xy 36.424362 -351.06102)
			(xy 36.42501 -351.029457) (xy 36.435403 -350.967191) (xy 36.455893 -350.907483) (xy 36.470336 -350.87941)
			(xy 36.475162 -350.87052) (xy 36.477194 -350.850962) (xy 36.454334 -350.772476) (xy 36.451119 -350.763041)
			(xy 36.438686 -350.747487) (xy 36.430204 -350.74225) (xy 36.422838 -350.738186) (xy 36.412932 -350.732344)
			(xy 36.391088 -350.730312) (xy 36.296346 -350.76384) (xy 36.280598 -350.779334) (xy 36.276534 -350.789748)
			(xy 36.265852 -350.81653) (xy 36.23756 -350.86677) (xy 36.202027 -350.912178) (xy 36.160063 -350.951719)
			(xy 36.112624 -350.984492) (xy 36.060792 -351.009749) (xy 36.005748 -351.026915) (xy 35.948747 -351.035598)
			(xy 35.919918 -351.036128) (xy 35.892666 -351.035626) (xy 35.838716 -351.027871) (xy 35.786418 -351.012518)
			(xy 35.736839 -350.989878) (xy 35.690986 -350.960412) (xy 35.649793 -350.92472) (xy 35.614099 -350.883529)
			(xy 35.584631 -350.837677) (xy 35.561989 -350.788098) (xy 35.546632 -350.735802) (xy 35.538875 -350.681852)
			(xy 35.270465 -350.681852) (xy 35.250084 -350.726018) (xy 35.220134 -350.772088) (xy 35.202368 -350.79305)
			(xy 35.202114 -350.793304) (xy 35.196521 -350.800386) (xy 35.190278 -350.817306) (xy 35.189922 -350.826324)
			(xy 35.189922 -350.893888) (xy 35.19028 -350.902905) (xy 35.196526 -350.919822) (xy 35.202114 -350.926908)
			(xy 35.202622 -350.927416) (xy 35.220362 -350.948356) (xy 35.250243 -350.994391) (xy 35.273208 -351.044238)
			(xy 35.288781 -351.096864) (xy 35.29664 -351.151181) (xy 35.29711 -351.178622) (xy 35.296624 -351.205873)
			(xy 35.288868 -351.259821) (xy 35.273513 -351.312116) (xy 35.250871 -351.361693) (xy 35.221405 -351.407543)
			(xy 35.185714 -351.448734) (xy 35.144523 -351.484425) (xy 35.098673 -351.513891) (xy 35.049096 -351.536533)
			(xy 34.996801 -351.551888) (xy 34.942853 -351.559644) (xy 34.888351 -351.559644) (xy 34.834403 -351.551888)
			(xy 34.782108 -351.536533) (xy 34.732531 -351.513891) (xy 34.686681 -351.484425) (xy 34.64549 -351.448734)
			(xy 34.609799 -351.407543) (xy 34.580333 -351.361693) (xy 34.557691 -351.312116) (xy 34.542336 -351.259821)
			(xy 34.53458 -351.205873) (xy 34.534094 -351.178622) (xy 28.888047 -351.178622) (xy 28.883381 -351.194514)
			(xy 28.860739 -351.244091) (xy 28.831273 -351.289941) (xy 28.795582 -351.331132) (xy 28.754391 -351.366823)
			(xy 28.708541 -351.396289) (xy 28.658964 -351.418931) (xy 28.606669 -351.434286) (xy 28.552721 -351.442042)
			(xy 28.498219 -351.442042) (xy 28.444271 -351.434286) (xy 28.391976 -351.418931) (xy 28.342399 -351.396289)
			(xy 28.296549 -351.366823) (xy 28.255358 -351.331132) (xy 28.219667 -351.289941) (xy 28.190201 -351.244091)
			(xy 28.167559 -351.194514) (xy 28.152204 -351.142219) (xy 28.144448 -351.088271) (xy 28.143962 -351.06102)
			(xy 28.14461 -351.029457) (xy 28.155003 -350.967191) (xy 28.175493 -350.907483) (xy 28.189936 -350.87941)
			(xy 28.194762 -350.87052) (xy 28.196794 -350.850962) (xy 28.173934 -350.772476) (xy 28.170719 -350.763041)
			(xy 28.158286 -350.747487) (xy 28.149804 -350.74225) (xy 28.142438 -350.738186) (xy 28.132532 -350.732344)
			(xy 28.110688 -350.730312) (xy 28.015946 -350.76384) (xy 28.000198 -350.779334) (xy 27.996134 -350.789748)
			(xy 27.985452 -350.81653) (xy 27.95716 -350.86677) (xy 27.921627 -350.912178) (xy 27.879663 -350.951719)
			(xy 27.832224 -350.984492) (xy 27.780392 -351.009749) (xy 27.725348 -351.026915) (xy 27.668347 -351.035598)
			(xy 27.639518 -351.036128) (xy 27.612266 -351.035626) (xy 27.558316 -351.027871) (xy 27.506018 -351.012518)
			(xy 27.456439 -350.989878) (xy 27.410586 -350.960412) (xy 27.369393 -350.92472) (xy 27.333699 -350.883529)
			(xy 27.304231 -350.837677) (xy 27.281589 -350.788098) (xy 27.266232 -350.735802) (xy 27.258475 -350.681852)
			(xy 26.990065 -350.681852) (xy 26.969684 -350.726018) (xy 26.939734 -350.772088) (xy 26.921968 -350.79305)
			(xy 26.921714 -350.793304) (xy 26.916121 -350.800386) (xy 26.909878 -350.817306) (xy 26.909522 -350.826324)
			(xy 26.909522 -350.893888) (xy 26.90988 -350.902905) (xy 26.916126 -350.919822) (xy 26.921714 -350.926908)
			(xy 26.922222 -350.927416) (xy 26.939962 -350.948356) (xy 26.969843 -350.994391) (xy 26.992808 -351.044238)
			(xy 27.008381 -351.096864) (xy 27.01624 -351.151181) (xy 27.01671 -351.178622) (xy 27.016224 -351.205873)
			(xy 27.008468 -351.259821) (xy 26.993113 -351.312116) (xy 26.970471 -351.361693) (xy 26.941005 -351.407543)
			(xy 26.905314 -351.448734) (xy 26.864123 -351.484425) (xy 26.818273 -351.513891) (xy 26.768696 -351.536533)
			(xy 26.716401 -351.551888) (xy 26.662453 -351.559644) (xy 26.607951 -351.559644) (xy 26.554003 -351.551888)
			(xy 26.501708 -351.536533) (xy 26.452131 -351.513891) (xy 26.406281 -351.484425) (xy 26.36509 -351.448734)
			(xy 26.329399 -351.407543) (xy 26.299933 -351.361693) (xy 26.277291 -351.312116) (xy 26.261936 -351.259821)
			(xy 26.25418 -351.205873) (xy 26.253694 -351.178622) (xy 23.559516 -351.178622) (xy 23.559516 -351.516442)
			(xy 23.559947 -351.526508) (xy 23.567674 -351.5451) (xy 23.574502 -351.55251) (xy 23.682452 -351.66046)
			(xy 24.043585 -352.021648) (xy 24.394666 -352.021648) (xy 24.398737 -351.966026) (xy 24.410863 -351.911589)
			(xy 24.430786 -351.859498) (xy 24.458082 -351.810863) (xy 24.492168 -351.76672) (xy 24.532317 -351.728011)
			(xy 24.577675 -351.69556) (xy 24.627275 -351.670059) (xy 24.680059 -351.652052) (xy 24.734902 -351.641922)
			(xy 24.790636 -351.639885) (xy 24.846073 -351.645985) (xy 24.90003 -351.660091) (xy 24.951359 -351.681903)
			(xy 24.998965 -351.710957) (xy 25.041833 -351.746632) (xy 25.07905 -351.788169) (xy 25.109823 -351.834682)
			(xy 25.133495 -351.885179) (xy 25.149563 -351.938586) (xy 25.157683 -351.993762) (xy 25.158192 -352.021648)
			(xy 25.157683 -352.049534) (xy 25.149563 -352.10471) (xy 25.133495 -352.158117) (xy 25.109823 -352.208614)
			(xy 25.07905 -352.255127) (xy 25.041833 -352.296664) (xy 24.998965 -352.332339) (xy 24.951359 -352.361393)
			(xy 24.90003 -352.383205) (xy 24.846073 -352.397311) (xy 24.790636 -352.403411) (xy 24.734902 -352.401374)
			(xy 24.680059 -352.391244) (xy 24.627275 -352.373237) (xy 24.577675 -352.347736) (xy 24.532317 -352.315285)
			(xy 24.492168 -352.276576) (xy 24.458082 -352.232433) (xy 24.430786 -352.183798) (xy 24.410863 -352.131707)
			(xy 24.398737 -352.07727) (xy 24.394666 -352.021648) (xy 24.043585 -352.021648) (xy 25.344882 -353.323144)
			(xy 25.352282 -353.329983) (xy 25.370881 -353.337697) (xy 25.38095 -353.33813) (xy 30.089856 -353.33813)
			(xy 30.099921 -353.338564) (xy 30.118508 -353.346296) (xy 30.125924 -353.353116) (xy 30.347158 -353.57435)
			(xy 30.35457 -353.581034) (xy 30.373003 -353.588631) (xy 30.392941 -353.588631) (xy 30.411374 -353.581034)
			(xy 30.418786 -353.57435) (xy 31.425896 -352.56724) (xy 31.443992 -352.549985) (xy 31.485538 -352.522178)
			(xy 31.531709 -352.503006) (xy 31.580732 -352.493205) (xy 31.605728 -352.492564) (xy 67.879976 -352.492564)
			(xy 67.890039 -352.492126) (xy 67.90862 -352.484388) (xy 67.916044 -352.477578) (xy 75.973686 -344.42019)
			(xy 75.980532 -344.412791) (xy 75.988265 -344.394193) (xy 75.988672 -344.384122) (xy 75.988672 -339.093302)
			(xy 75.989283 -339.068319) (xy 75.999025 -339.019311) (xy 76.018135 -338.973143) (xy 76.045879 -338.931587)
			(xy 76.063094 -338.91347) (xy 76.343002 -338.633562) (xy 76.358664 -338.618526) (xy 76.394129 -338.593485)
			(xy 76.433329 -338.574826) (xy 76.475126 -338.563088) (xy 76.496672 -338.56041) (xy 76.505319 -338.559086)
			(xy 76.521023 -338.551409) (xy 76.527406 -338.545424) (xy 76.549084 -338.524312) (xy 76.597869 -338.488519)
			(xy 76.651683 -338.460856) (xy 76.709183 -338.442015) (xy 76.768932 -338.432466) (xy 76.799186 -338.431886)
			(xy 76.82644 -338.432348) (xy 76.880392 -338.440104) (xy 76.932692 -338.455458) (xy 76.982275 -338.4781)
			(xy 77.02813 -338.507568) (xy 77.069325 -338.543261) (xy 77.10502 -338.584454) (xy 77.13449 -338.630308)
			(xy 77.157135 -338.679889) (xy 77.172492 -338.732188) (xy 77.18025 -338.78614) (xy 77.180694 -338.813394)
			(xy 77.180223 -338.840835) (xy 77.172361 -338.89515) (xy 77.156786 -338.947775) (xy 77.154078 -338.953651)
			(xy 77.422479 -338.953651) (xy 77.422479 -338.899149) (xy 77.430236 -338.845201) (xy 77.445591 -338.792906)
			(xy 77.468232 -338.743329) (xy 77.497699 -338.697479) (xy 77.53339 -338.656289) (xy 77.57458 -338.620597)
			(xy 77.620431 -338.591131) (xy 77.670008 -338.56849) (xy 77.722303 -338.553135) (xy 77.776251 -338.545379)
			(xy 77.803502 -338.544916) (xy 77.803756 -338.544916) (xy 77.828959 -338.545338) (xy 77.878926 -338.551972)
			(xy 77.92758 -338.565142) (xy 77.974071 -338.584618) (xy 77.996034 -338.596986) (xy 78.00594 -338.602828)
			(xy 78.027784 -338.60486) (xy 78.122526 -338.571332) (xy 78.138274 -338.555838) (xy 78.142338 -338.545424)
			(xy 78.153082 -338.518668) (xy 78.181362 -338.468427) (xy 78.216884 -338.423016) (xy 78.258839 -338.383472)
			(xy 78.30627 -338.350695) (xy 78.358094 -338.325434) (xy 78.413132 -338.308264) (xy 78.470127 -338.299576)
			(xy 78.498954 -338.299044) (xy 78.526202 -338.299621) (xy 78.580144 -338.30737) (xy 78.632434 -338.322717)
			(xy 78.682008 -338.345349) (xy 78.727856 -338.374806) (xy 78.769045 -338.410488) (xy 78.804738 -338.451669)
			(xy 78.834206 -338.49751) (xy 78.85685 -338.547078) (xy 78.869571 -338.590382) (xy 81.010506 -338.590382)
			(xy 81.011026 -338.562809) (xy 81.018967 -338.508239) (xy 81.034681 -338.45538) (xy 81.057841 -338.405334)
			(xy 81.087964 -338.359143) (xy 81.124423 -338.317769) (xy 81.145126 -338.299552) (xy 81.153227 -338.292021)
			(xy 81.162566 -338.271991) (xy 81.16316 -338.260944) (xy 81.16316 -338.18322) (xy 81.162593 -338.17217)
			(xy 81.153228 -338.152149) (xy 81.145126 -338.144612) (xy 81.124423 -338.126392) (xy 81.087951 -338.085026)
			(xy 81.057817 -338.038838) (xy 81.03465 -337.988792) (xy 81.018932 -337.93593) (xy 81.010991 -337.881356)
			(xy 81.010506 -337.853782) (xy 81.010961 -337.82653) (xy 81.01872 -337.77258) (xy 81.034079 -337.720284)
			(xy 81.056723 -337.670706) (xy 81.086192 -337.624855) (xy 81.121887 -337.583664) (xy 81.16308 -337.547973)
			(xy 81.208934 -337.518507) (xy 81.258514 -337.495867) (xy 81.310811 -337.480514) (xy 81.364762 -337.472759)
			(xy 81.392014 -337.472274) (xy 81.392522 -337.472274) (xy 81.426304 -337.473798) (xy 81.436464 -337.474814)
			(xy 81.455768 -337.468718) (xy 81.51876 -337.415886) (xy 81.526045 -337.409158) (xy 81.535327 -337.391657)
			(xy 81.536794 -337.38185) (xy 81.536794 -337.381088) (xy 81.539765 -337.352942) (xy 81.552958 -337.297905)
			(xy 81.574141 -337.245422) (xy 81.602848 -337.196647) (xy 81.638448 -337.15265) (xy 81.68016 -337.114398)
			(xy 81.727067 -337.08273) (xy 81.77814 -337.058344) (xy 81.832256 -337.041773) (xy 81.888226 -337.033382)
			(xy 81.916524 -337.032854) (xy 81.916778 -337.032854) (xy 81.934798 -337.033069) (xy 81.970672 -337.036507)
			(xy 81.988406 -337.039712) (xy 81.998058 -337.04149) (xy 82.017108 -337.037934) (xy 82.092038 -336.989928)
			(xy 82.103468 -336.97418) (xy 82.105754 -336.964782) (xy 82.113135 -336.937733) (xy 82.134764 -336.886004)
			(xy 82.163729 -336.837996) (xy 82.199406 -336.794743) (xy 82.241027 -336.757175) (xy 82.287697 -336.726101)
			(xy 82.338412 -336.70219) (xy 82.392079 -336.685957) (xy 82.447544 -336.67775) (xy 82.475578 -336.677254)
			(xy 82.502827 -336.677799) (xy 82.556771 -336.685551) (xy 82.609062 -336.700902) (xy 82.658636 -336.723537)
			(xy 82.704485 -336.752998) (xy 82.745674 -336.788683) (xy 82.781366 -336.829867) (xy 82.810834 -336.875711)
			(xy 82.833477 -336.925282) (xy 82.848836 -336.977571) (xy 82.856597 -337.031513) (xy 82.857086 -337.058762)
			(xy 82.856599 -337.086336) (xy 82.848652 -337.140908) (xy 82.832931 -337.193768) (xy 82.809765 -337.243814)
			(xy 82.779636 -337.290004) (xy 82.743172 -337.331376) (xy 82.722466 -337.349592) (xy 82.714389 -337.357145)
			(xy 82.705037 -337.377158) (xy 82.704432 -337.3882) (xy 82.704432 -337.465924) (xy 82.705033 -337.47697)
			(xy 82.714374 -337.496991) (xy 82.722466 -337.504532) (xy 82.743189 -337.52273) (xy 82.77966 -337.564101)
			(xy 82.809791 -337.610293) (xy 82.832955 -337.660344) (xy 82.848669 -337.713209) (xy 82.856604 -337.767786)
			(xy 82.857086 -337.795362) (xy 82.856599 -337.822936) (xy 82.85048 -337.864958) (xy 84.015578 -337.864958)
			(xy 84.019649 -337.809336) (xy 84.031775 -337.754899) (xy 84.051698 -337.702808) (xy 84.078994 -337.654173)
			(xy 84.11308 -337.61003) (xy 84.153229 -337.571321) (xy 84.198587 -337.53887) (xy 84.248187 -337.513369)
			(xy 84.300971 -337.495362) (xy 84.355814 -337.485232) (xy 84.411548 -337.483195) (xy 84.466985 -337.489295)
			(xy 84.520942 -337.503401) (xy 84.572271 -337.525213) (xy 84.619877 -337.554267) (xy 84.662745 -337.589942)
			(xy 84.699962 -337.631479) (xy 84.730735 -337.677992) (xy 84.754407 -337.728489) (xy 84.770475 -337.781896)
			(xy 84.778595 -337.837072) (xy 84.779104 -337.864958) (xy 84.778595 -337.892844) (xy 84.770475 -337.94802)
			(xy 84.754407 -338.001427) (xy 84.730735 -338.051924) (xy 84.699962 -338.098437) (xy 84.662745 -338.139974)
			(xy 84.619877 -338.175649) (xy 84.572271 -338.204703) (xy 84.520942 -338.226515) (xy 84.466985 -338.240621)
			(xy 84.411548 -338.246721) (xy 84.355814 -338.244684) (xy 84.300971 -338.234554) (xy 84.248187 -338.216547)
			(xy 84.198587 -338.191046) (xy 84.153229 -338.158595) (xy 84.11308 -338.119886) (xy 84.078994 -338.075743)
			(xy 84.051698 -338.027108) (xy 84.031775 -337.975017) (xy 84.019649 -337.92058) (xy 84.015578 -337.864958)
			(xy 82.85048 -337.864958) (xy 82.848652 -337.877508) (xy 82.832931 -337.930368) (xy 82.809765 -337.980414)
			(xy 82.779636 -338.026604) (xy 82.743172 -338.067976) (xy 82.722466 -338.086192) (xy 82.714389 -338.093745)
			(xy 82.705037 -338.113758) (xy 82.704432 -338.1248) (xy 82.704432 -338.202524) (xy 82.705033 -338.21357)
			(xy 82.714374 -338.233591) (xy 82.722466 -338.241132) (xy 82.743189 -338.25933) (xy 82.77966 -338.300701)
			(xy 82.809791 -338.346893) (xy 82.832955 -338.396944) (xy 82.848669 -338.449809) (xy 82.856604 -338.504386)
			(xy 82.857086 -338.531962) (xy 82.856609 -338.559215) (xy 82.848857 -338.613167) (xy 82.833505 -338.665465)
			(xy 82.810865 -338.715047) (xy 82.78178 -338.760308) (xy 83.436458 -338.760308) (xy 83.440529 -338.704686)
			(xy 83.452655 -338.650249) (xy 83.472578 -338.598158) (xy 83.499874 -338.549523) (xy 83.53396 -338.50538)
			(xy 83.574109 -338.466671) (xy 83.619467 -338.43422) (xy 83.669067 -338.408719) (xy 83.721851 -338.390712)
			(xy 83.776694 -338.380582) (xy 83.832428 -338.378545) (xy 83.887865 -338.384645) (xy 83.941822 -338.398751)
			(xy 83.993151 -338.420563) (xy 84.040757 -338.449617) (xy 84.083625 -338.485292) (xy 84.120842 -338.526829)
			(xy 84.151615 -338.573342) (xy 84.175287 -338.623839) (xy 84.191355 -338.677246) (xy 84.199475 -338.732422)
			(xy 84.199984 -338.760308) (xy 84.199475 -338.788194) (xy 84.191355 -338.84337) (xy 84.175287 -338.896777)
			(xy 84.151615 -338.947274) (xy 84.120842 -338.993787) (xy 84.083625 -339.035324) (xy 84.040757 -339.070999)
			(xy 83.993151 -339.100053) (xy 83.941822 -339.121865) (xy 83.887865 -339.135971) (xy 83.832428 -339.142071)
			(xy 83.776694 -339.140034) (xy 83.721851 -339.129904) (xy 83.669067 -339.111897) (xy 83.619467 -339.086396)
			(xy 83.574109 -339.053945) (xy 83.53396 -339.015236) (xy 83.499874 -338.971093) (xy 83.472578 -338.922458)
			(xy 83.452655 -338.870367) (xy 83.440529 -338.81593) (xy 83.436458 -338.760308) (xy 82.78178 -338.760308)
			(xy 82.781399 -338.760901) (xy 82.745706 -338.802095) (xy 82.704514 -338.837789) (xy 82.658661 -338.867257)
			(xy 82.60908 -338.889899) (xy 82.556782 -338.905254) (xy 82.502831 -338.913008) (xy 82.475578 -338.91347)
			(xy 82.447721 -338.912989) (xy 82.392603 -338.904862) (xy 82.33925 -338.888812) (xy 82.288796 -338.86518)
			(xy 82.242311 -338.834468) (xy 82.200782 -338.797327) (xy 82.16509 -338.754547) (xy 82.135993 -338.707034)
			(xy 82.114108 -338.655797) (xy 82.106516 -338.62899) (xy 82.10423 -338.6201) (xy 82.093562 -338.60486)
			(xy 82.02168 -338.557108) (xy 82.003646 -338.553044) (xy 81.994502 -338.554314) (xy 81.981485 -338.555981)
			(xy 81.955301 -338.557762) (xy 81.942178 -338.55787) (xy 81.928029 -338.557779) (xy 81.899806 -338.555743)
			(xy 81.88579 -338.553806) (xy 81.875884 -338.552282) (xy 81.856072 -338.557108) (xy 81.78165 -338.612988)
			(xy 81.77149 -338.630514) (xy 81.77022 -338.640674) (xy 81.766152 -338.667831) (xy 81.751175 -338.720661)
			(xy 81.72878 -338.770799) (xy 81.69943 -338.817209) (xy 81.66373 -338.858933) (xy 81.622418 -338.895108)
			(xy 81.576348 -338.924989) (xy 81.52647 -338.947957) (xy 81.473815 -338.963539) (xy 81.41947 -338.971412)
			(xy 81.392014 -338.97189) (xy 81.364761 -338.971432) (xy 81.310809 -338.963676) (xy 81.25851 -338.948321)
			(xy 81.208928 -338.925679) (xy 81.163074 -338.896211) (xy 81.121881 -338.860516) (xy 81.086187 -338.819323)
			(xy 81.056719 -338.773468) (xy 81.034078 -338.723887) (xy 81.018723 -338.671587) (xy 81.010968 -338.617635)
			(xy 81.010506 -338.590382) (xy 78.869571 -338.590382) (xy 78.87221 -338.599364) (xy 78.879972 -338.653304)
			(xy 78.880462 -338.680552) (xy 78.879812 -338.712115) (xy 78.869421 -338.774381) (xy 78.848932 -338.83409)
			(xy 78.834488 -338.862162) (xy 78.829662 -338.871052) (xy 78.82763 -338.89061) (xy 78.85049 -338.969096)
			(xy 78.853744 -338.978514) (xy 78.86615 -338.994076) (xy 78.87462 -338.999322) (xy 78.89972 -339.013872)
			(xy 78.945601 -339.049377) (xy 78.985575 -339.091421) (xy 79.01872 -339.139034) (xy 79.044271 -339.191118)
			(xy 79.061638 -339.246472) (xy 79.070422 -339.303817) (xy 79.070962 -339.332824) (xy 79.070476 -339.360075)
			(xy 79.06272 -339.414023) (xy 79.047365 -339.466318) (xy 79.024723 -339.515895) (xy 78.995257 -339.561745)
			(xy 78.959566 -339.602936) (xy 78.918375 -339.638627) (xy 78.872525 -339.668093) (xy 78.822948 -339.690735)
			(xy 78.770653 -339.70609) (xy 78.716705 -339.713846) (xy 78.662203 -339.713846) (xy 78.608255 -339.70609)
			(xy 78.55596 -339.690735) (xy 78.506383 -339.668093) (xy 78.460533 -339.638627) (xy 78.419342 -339.602936)
			(xy 78.383651 -339.561745) (xy 78.354185 -339.515895) (xy 78.331543 -339.466318) (xy 78.316188 -339.414023)
			(xy 78.308432 -339.360075) (xy 78.307946 -339.332824) (xy 78.308586 -339.30126) (xy 78.31898 -339.238994)
			(xy 78.339474 -339.179286) (xy 78.35392 -339.151214) (xy 78.358746 -339.142324) (xy 78.360778 -339.122766)
			(xy 78.337918 -339.04428) (xy 78.334671 -339.03486) (xy 78.322259 -339.0193) (xy 78.313788 -339.014054)
			(xy 78.306422 -339.00999) (xy 78.296516 -339.004148) (xy 78.274672 -339.002116) (xy 78.17993 -339.035644)
			(xy 78.164182 -339.051138) (xy 78.160118 -339.061552) (xy 78.149451 -339.088341) (xy 78.121157 -339.138581)
			(xy 78.085622 -339.183989) (xy 78.043656 -339.22353) (xy 77.996215 -339.256302) (xy 77.94438 -339.281558)
			(xy 77.889334 -339.298722) (xy 77.832332 -339.307403) (xy 77.803502 -339.307932) (xy 77.776251 -339.307421)
			(xy 77.722303 -339.299665) (xy 77.670008 -339.28431) (xy 77.620431 -339.261669) (xy 77.57458 -339.232203)
			(xy 77.53339 -339.196511) (xy 77.497699 -339.155321) (xy 77.468232 -339.109471) (xy 77.445591 -339.059894)
			(xy 77.430236 -339.007599) (xy 77.422479 -338.953651) (xy 77.154078 -338.953651) (xy 77.133819 -338.997619)
			(xy 77.103936 -339.043651) (xy 77.086206 -339.0646) (xy 77.085698 -339.065108) (xy 77.080114 -339.072195)
			(xy 77.073875 -339.089112) (xy 77.073506 -339.098128) (xy 77.073506 -339.165692) (xy 77.073864 -339.174709)
			(xy 77.08011 -339.191626) (xy 77.085698 -339.198712) (xy 77.085952 -339.198966) (xy 77.103718 -339.219928)
			(xy 77.133667 -339.265998) (xy 77.156689 -339.315891) (xy 77.172306 -339.368573) (xy 77.180194 -339.422952)
			(xy 77.180694 -339.450426) (xy 77.180236 -339.477271) (xy 77.172708 -339.53043) (xy 77.157806 -339.582009)
			(xy 77.135822 -339.630992) (xy 77.107192 -339.67641) (xy 77.072479 -339.717368) (xy 77.032369 -339.753058)
			(xy 76.987653 -339.782774) (xy 76.939215 -339.805931) (xy 76.91374 -339.814408) (xy 76.897738 -339.819488)
			(xy 76.87818 -339.846158) (xy 76.87818 -344.668602) (xy 76.877569 -344.693586) (xy 76.867828 -344.742595)
			(xy 76.848721 -344.788764) (xy 76.820979 -344.830324) (xy 76.803758 -344.848434) (xy 68.344288 -353.307904)
			(xy 68.32619 -353.325155) (xy 68.284642 -353.352955) (xy 68.238472 -353.372121) (xy 68.189451 -353.381916)
			(xy 68.164456 -353.38258) (xy 31.93542 -353.38258) (xy 31.925356 -353.383017) (xy 31.906771 -353.39075)
			(xy 31.899352 -353.397566) (xy 31.07055 -354.226114) (xy 31.06387 -354.233525) (xy 31.05628 -354.251954)
			(xy 31.056288 -354.271885) (xy 31.063892 -354.290309) (xy 31.07055 -354.297742) (xy 31.286958 -354.51415)
			(xy 31.29437 -354.520834) (xy 31.312803 -354.528431) (xy 31.332741 -354.528431) (xy 31.351174 -354.520834)
			(xy 31.358586 -354.51415) (xy 31.885636 -353.9871) (xy 31.903732 -353.969843) (xy 31.945277 -353.94203)
			(xy 31.991447 -353.922851) (xy 32.040471 -353.91304) (xy 32.065468 -353.912424) (xy 69.101716 -353.912424)
			(xy 69.111785 -353.911999) (xy 69.130388 -353.904283) (xy 69.137784 -353.897438) (xy 81.61401 -341.421466)
			(xy 81.63212 -341.404243) (xy 81.67368 -341.376501) (xy 81.719849 -341.357389) (xy 81.768858 -341.34764)
			(xy 81.793842 -341.347044) (xy 83.427316 -341.347044) (xy 83.437384 -341.346616) (xy 83.455979 -341.338892)
			(xy 83.463384 -341.332058) (xy 84.331302 -340.46414) (xy 84.338139 -340.456738) (xy 84.345851 -340.43814)
			(xy 84.346288 -340.428072) (xy 84.346288 -339.078824) (xy 84.346897 -339.05384) (xy 84.356635 -339.00483)
			(xy 84.375744 -338.95866) (xy 84.403488 -338.917102) (xy 84.42071 -338.898992) (xy 84.700618 -338.619084)
			(xy 84.71628 -338.604047) (xy 84.751745 -338.579007) (xy 84.790945 -338.560348) (xy 84.832742 -338.548612)
			(xy 84.854288 -338.545932) (xy 84.862942 -338.544622) (xy 84.878668 -338.536965) (xy 84.885022 -338.530946)
			(xy 84.9067 -338.509834) (xy 84.955485 -338.47404) (xy 85.009299 -338.446378) (xy 85.066799 -338.427539)
			(xy 85.126548 -338.417992) (xy 85.156802 -338.417408) (xy 85.184054 -338.417871) (xy 85.238004 -338.425629)
			(xy 85.290301 -338.440985) (xy 85.33988 -338.463628) (xy 85.385731 -338.493096) (xy 85.426923 -338.52879)
			(xy 85.462615 -338.569983) (xy 85.492081 -338.615836) (xy 85.514721 -338.665416) (xy 85.530075 -338.717713)
			(xy 85.53783 -338.771664) (xy 85.53831 -338.798916) (xy 85.537837 -338.826356) (xy 85.529973 -338.88067)
			(xy 85.514396 -338.933293) (xy 85.511697 -338.93915) (xy 85.780101 -338.93915) (xy 85.780101 -338.88465)
			(xy 85.787858 -338.830704) (xy 85.803213 -338.778411) (xy 85.825854 -338.728835) (xy 85.85532 -338.682987)
			(xy 85.891011 -338.641799) (xy 85.932201 -338.606109) (xy 85.978051 -338.576645) (xy 86.027628 -338.554007)
			(xy 86.079921 -338.538654) (xy 86.133868 -338.5309) (xy 86.161118 -338.530438) (xy 86.161372 -338.530438)
			(xy 86.186575 -338.53085) (xy 86.236543 -338.537486) (xy 86.285197 -338.550659) (xy 86.331688 -338.570138)
			(xy 86.35365 -338.582508) (xy 86.363556 -338.58835) (xy 86.3854 -338.590382) (xy 86.480142 -338.556854)
			(xy 86.49589 -338.54136) (xy 86.499954 -338.530946) (xy 86.510643 -338.504167) (xy 86.538934 -338.453928)
			(xy 86.574467 -338.40852) (xy 86.61643 -338.368979) (xy 86.663868 -338.336206) (xy 86.715699 -338.310948)
			(xy 86.770741 -338.293782) (xy 86.827741 -338.285097) (xy 86.85657 -338.284566) (xy 86.883821 -338.285083)
			(xy 86.937769 -338.292835) (xy 86.990064 -338.308186) (xy 87.039642 -338.330823) (xy 87.085494 -338.360286)
			(xy 87.126686 -338.395974) (xy 87.162381 -338.437161) (xy 87.19185 -338.483009) (xy 87.214494 -338.532584)
			(xy 87.227218 -338.575904) (xy 89.368122 -338.575904) (xy 89.368583 -338.548329) (xy 89.376535 -338.493756)
			(xy 89.392261 -338.440895) (xy 89.415432 -338.390849) (xy 89.445565 -338.34466) (xy 89.482034 -338.303289)
			(xy 89.502742 -338.285074) (xy 89.510836 -338.277536) (xy 89.520178 -338.257511) (xy 89.520776 -338.246466)
			(xy 89.520776 -338.168742) (xy 89.520192 -338.157694) (xy 89.510839 -338.137673) (xy 89.502742 -338.130134)
			(xy 89.482052 -338.111899) (xy 89.445579 -338.070536) (xy 89.415443 -338.024352) (xy 89.392273 -337.974308)
			(xy 89.376552 -337.921449) (xy 89.368609 -337.866878) (xy 89.368122 -337.839304) (xy 89.368559 -337.81205)
			(xy 89.376316 -337.758096) (xy 89.391673 -337.705796) (xy 89.414318 -337.656214) (xy 89.443788 -337.61036)
			(xy 89.479485 -337.569166) (xy 89.52068 -337.533472) (xy 89.566537 -337.504005) (xy 89.616121 -337.481364)
			(xy 89.668422 -337.466011) (xy 89.722376 -337.458257) (xy 89.74963 -337.457796) (xy 89.750138 -337.457796)
			(xy 89.78392 -337.45932) (xy 89.79408 -337.460336) (xy 89.813384 -337.45424) (xy 89.876376 -337.401408)
			(xy 89.883678 -337.394695) (xy 89.892954 -337.377183) (xy 89.89441 -337.367372) (xy 89.89441 -337.36661)
			(xy 89.8973 -337.338454) (xy 89.910505 -337.283414) (xy 89.931698 -337.230931) (xy 89.960416 -337.182155)
			(xy 89.996025 -337.138159) (xy 90.037746 -337.099908) (xy 90.084661 -337.068243) (xy 90.135741 -337.043859)
			(xy 90.189863 -337.027291) (xy 90.24584 -337.018903) (xy 90.27414 -337.018376) (xy 90.274394 -337.018376)
			(xy 90.292413 -337.018602) (xy 90.328288 -337.022033) (xy 90.346022 -337.025234) (xy 90.355674 -337.027012)
			(xy 90.374724 -337.023456) (xy 90.449654 -336.97545) (xy 90.461084 -336.959702) (xy 90.46337 -336.950304)
			(xy 90.470776 -336.923263) (xy 90.492409 -336.87154) (xy 90.521374 -336.823538) (xy 90.55705 -336.780288)
			(xy 90.598668 -336.742722) (xy 90.645333 -336.711648) (xy 90.696041 -336.687734) (xy 90.749702 -336.671494)
			(xy 90.805162 -336.663278) (xy 90.833194 -336.662776) (xy 90.860444 -336.663283) (xy 90.914391 -336.671039)
			(xy 90.958918 -336.684112) (xy 91.388946 -336.684112) (xy 91.389457 -336.656202) (xy 91.397589 -336.600977)
			(xy 91.41368 -336.547527) (xy 91.437389 -336.496992) (xy 91.468208 -336.450451) (xy 91.486482 -336.42935)
			(xy 91.492398 -336.422186) (xy 91.499038 -336.404851) (xy 91.499436 -336.395568) (xy 91.499436 -336.317844)
			(xy 91.492832 -336.300572) (xy 91.486482 -336.29346) (xy 91.468208 -336.272357) (xy 91.437381 -336.225819)
			(xy 91.413665 -336.175286) (xy 91.397567 -336.121835) (xy 91.389432 -336.066609) (xy 91.388946 -336.038698)
			(xy 91.389432 -336.011447) (xy 91.397188 -335.957499) (xy 91.412543 -335.905204) (xy 91.435185 -335.855627)
			(xy 91.464651 -335.809777) (xy 91.500342 -335.768586) (xy 91.541533 -335.732895) (xy 91.587383 -335.703429)
			(xy 91.63696 -335.680787) (xy 91.689255 -335.665432) (xy 91.743203 -335.657676) (xy 91.797705 -335.657676)
			(xy 91.851653 -335.665432) (xy 91.903948 -335.680787) (xy 91.953525 -335.703429) (xy 91.999375 -335.732895)
			(xy 92.040566 -335.768586) (xy 92.076257 -335.809777) (xy 92.105723 -335.855627) (xy 92.128365 -335.905204)
			(xy 92.14372 -335.957499) (xy 92.151476 -336.011447) (xy 92.151962 -336.038698) (xy 92.151455 -336.066608)
			(xy 92.143322 -336.121833) (xy 92.127229 -336.175283) (xy 92.10352 -336.225818) (xy 92.0727 -336.272359)
			(xy 92.054426 -336.29346) (xy 92.048507 -336.300622) (xy 92.041868 -336.317959) (xy 92.041472 -336.327242)
			(xy 92.041472 -336.404966) (xy 92.048076 -336.422238) (xy 92.054426 -336.42935) (xy 92.072706 -336.450448)
			(xy 92.103532 -336.496987) (xy 92.127247 -336.547522) (xy 92.143343 -336.600974) (xy 92.151477 -336.656201)
			(xy 92.151962 -336.684112) (xy 92.151476 -336.711363) (xy 92.14372 -336.765311) (xy 92.128365 -336.817606)
			(xy 92.105723 -336.867183) (xy 92.076257 -336.913033) (xy 92.040566 -336.954224) (xy 91.999375 -336.989915)
			(xy 91.956296 -337.0176) (xy 95.771147 -337.0176) (xy 95.775316 -336.961981) (xy 95.787728 -336.907605)
			(xy 95.808105 -336.855686) (xy 95.835994 -336.807385) (xy 95.870771 -336.76378) (xy 95.911658 -336.725845)
			(xy 95.957743 -336.694429) (xy 96.007996 -336.670233) (xy 96.061294 -336.653797) (xy 96.116447 -336.645488)
			(xy 96.144334 -336.644996) (xy 96.170756 -336.645435) (xy 96.223073 -336.65289) (xy 96.273811 -336.667659)
			(xy 96.321955 -336.689447) (xy 96.366539 -336.717817) (xy 96.386904 -336.734658) (xy 96.393762 -336.7405)
			(xy 96.41078 -336.74685) (xy 96.495108 -336.74685) (xy 96.512126 -336.7405) (xy 96.518984 -336.734658)
			(xy 96.53935 -336.717819) (xy 96.583936 -336.689454) (xy 96.63208 -336.667667) (xy 96.682817 -336.652896)
			(xy 96.735132 -336.645436) (xy 96.787976 -336.645436) (xy 96.840291 -336.652896) (xy 96.891028 -336.667667)
			(xy 96.939172 -336.689454) (xy 96.983758 -336.717819) (xy 97.004124 -336.734658) (xy 97.010982 -336.7405)
			(xy 97.028 -336.74685) (xy 97.112328 -336.74685) (xy 97.129346 -336.7405) (xy 97.136204 -336.734658)
			(xy 97.157001 -336.717486) (xy 97.202585 -336.688665) (xy 97.251853 -336.666726) (xy 97.277682 -336.658966)
			(xy 97.277936 -336.658966) (xy 97.288984 -336.655196) (xy 97.306315 -336.639591) (xy 97.31121 -336.628994)
			(xy 97.341182 -336.554064) (xy 97.344904 -336.542981) (xy 97.343072 -336.519703) (xy 97.337626 -336.50936)
			(xy 97.325246 -336.487715) (xy 97.305774 -336.441811) (xy 97.292598 -336.393719) (xy 97.285952 -336.3443)
			(xy 97.285556 -336.319368) (xy 97.286078 -336.291727) (xy 97.294232 -336.237048) (xy 97.31037 -336.184174)
			(xy 97.33414 -336.134262) (xy 97.365019 -336.088407) (xy 97.402331 -336.047615) (xy 97.423478 -336.029808)
			(xy 97.431902 -336.022209) (xy 97.441666 -336.001766) (xy 97.442274 -335.990438) (xy 97.442274 -335.911698)
			(xy 97.441624 -335.90038) (xy 97.431873 -335.879946) (xy 97.423478 -335.872328) (xy 97.402359 -335.854489)
			(xy 97.365045 -335.813702) (xy 97.334161 -335.767854) (xy 97.310383 -335.717949) (xy 97.294232 -335.665081)
			(xy 97.286062 -335.610408) (xy 97.285556 -335.582768) (xy 97.286077 -335.554883) (xy 97.294389 -335.499736)
			(xy 97.310827 -335.446444) (xy 97.335025 -335.396198) (xy 97.366441 -335.350119) (xy 97.404374 -335.309237)
			(xy 97.447976 -335.274465) (xy 97.496274 -335.24658) (xy 97.548189 -335.226205) (xy 97.60256 -335.213795)
			(xy 97.658174 -335.209628) (xy 97.713788 -335.213795) (xy 97.768159 -335.226205) (xy 97.820074 -335.24658)
			(xy 97.868372 -335.274465) (xy 97.911974 -335.309237) (xy 97.949907 -335.350119) (xy 97.981323 -335.396198)
			(xy 98.005521 -335.446444) (xy 98.021959 -335.499736) (xy 98.030271 -335.554883) (xy 98.030792 -335.582768)
			(xy 98.030314 -335.610411) (xy 98.022154 -335.665092) (xy 98.006008 -335.717969) (xy 97.98223 -335.767881)
			(xy 97.951342 -335.813734) (xy 97.914021 -335.854523) (xy 97.89287 -335.872328) (xy 97.884438 -335.87992)
			(xy 97.874676 -335.900368) (xy 97.874074 -335.911698) (xy 97.874074 -335.990438) (xy 97.874688 -336.001761)
			(xy 97.884463 -336.022195) (xy 97.89287 -336.029808) (xy 97.914017 -336.047616) (xy 97.951326 -336.088411)
			(xy 97.982205 -336.134266) (xy 98.005978 -336.184177) (xy 98.022124 -336.23705) (xy 98.030288 -336.291726)
			(xy 98.030792 -336.319368) (xy 98.030319 -336.346211) (xy 98.022619 -336.399341) (xy 98.007372 -336.450816)
			(xy 97.984896 -336.499569) (xy 97.955655 -336.544593) (xy 97.920256 -336.584953) (xy 97.879429 -336.619815)
			(xy 97.834023 -336.648456) (xy 97.784975 -336.670284) (xy 97.759266 -336.678016) (xy 97.759012 -336.678016)
			(xy 97.747956 -336.68177) (xy 97.730626 -336.697384) (xy 97.725738 -336.707988) (xy 97.695766 -336.782918)
			(xy 97.691997 -336.793989) (xy 97.693862 -336.817279) (xy 97.699322 -336.827622) (xy 97.711699 -336.849268)
			(xy 97.731171 -336.895173) (xy 97.744348 -336.943264) (xy 97.750995 -336.992682) (xy 97.751392 -337.017614)
			(xy 97.750979 -337.044233) (xy 97.7434 -337.09693) (xy 97.728399 -337.148011) (xy 97.70628 -337.196438)
			(xy 97.677495 -337.241224) (xy 97.642629 -337.281457) (xy 97.602392 -337.316319) (xy 97.557603 -337.345099)
			(xy 97.509174 -337.367213) (xy 97.458091 -337.382208) (xy 97.405393 -337.389782) (xy 97.378774 -337.390232)
			(xy 97.352352 -337.389782) (xy 97.300037 -337.382329) (xy 97.249298 -337.367562) (xy 97.201154 -337.345776)
			(xy 97.156569 -337.31741) (xy 97.136204 -337.30057) (xy 97.129346 -337.294728) (xy 97.112328 -337.288378)
			(xy 97.028 -337.288378) (xy 97.010982 -337.294728) (xy 97.004124 -337.30057) (xy 96.983758 -337.317409)
			(xy 96.939172 -337.345774) (xy 96.891028 -337.367561) (xy 96.840291 -337.382332) (xy 96.787976 -337.389792)
			(xy 96.735132 -337.389792) (xy 96.682817 -337.382332) (xy 96.63208 -337.367561) (xy 96.583936 -337.345774)
			(xy 96.53935 -337.317409) (xy 96.518984 -337.30057) (xy 96.512126 -337.294728) (xy 96.495108 -337.288378)
			(xy 96.41078 -337.288378) (xy 96.393762 -337.294728) (xy 96.386904 -337.30057) (xy 96.366533 -337.317402)
			(xy 96.321945 -337.345759) (xy 96.273802 -337.36754) (xy 96.223066 -337.382309) (xy 96.170755 -337.38977)
			(xy 96.144334 -337.390232) (xy 96.116447 -337.389712) (xy 96.061294 -337.381403) (xy 96.007996 -337.364967)
			(xy 95.957743 -337.340771) (xy 95.911658 -337.309355) (xy 95.870771 -337.27142) (xy 95.835994 -337.227815)
			(xy 95.808105 -337.179514) (xy 95.787728 -337.127595) (xy 95.775316 -337.073219) (xy 95.771147 -337.0176)
			(xy 91.956296 -337.0176) (xy 91.953525 -337.019381) (xy 91.903948 -337.042023) (xy 91.851653 -337.057378)
			(xy 91.797705 -337.065134) (xy 91.743203 -337.065134) (xy 91.689255 -337.057378) (xy 91.63696 -337.042023)
			(xy 91.587383 -337.019381) (xy 91.541533 -336.989915) (xy 91.500342 -336.954224) (xy 91.464651 -336.913033)
			(xy 91.435185 -336.867183) (xy 91.412543 -336.817606) (xy 91.397188 -336.765311) (xy 91.389432 -336.711363)
			(xy 91.388946 -336.684112) (xy 90.958918 -336.684112) (xy 90.966684 -336.686392) (xy 91.01626 -336.709031)
			(xy 91.06211 -336.738496) (xy 91.1033 -336.774185) (xy 91.138991 -336.815373) (xy 91.168458 -336.861221)
			(xy 91.1911 -336.910795) (xy 91.206457 -336.963088) (xy 91.214215 -337.017034) (xy 91.214702 -337.044284)
			(xy 91.214225 -337.071858) (xy 91.206274 -337.12643) (xy 91.190552 -337.17929) (xy 91.167384 -337.229336)
			(xy 91.137253 -337.275526) (xy 91.100788 -337.316898) (xy 91.080082 -337.335114) (xy 91.071997 -337.342661)
			(xy 91.062649 -337.362679) (xy 91.062048 -337.373722) (xy 91.062048 -337.451446) (xy 91.062631 -337.462494)
			(xy 91.071984 -337.482516) (xy 91.080082 -337.490054) (xy 91.100771 -337.50829) (xy 91.137243 -337.549653)
			(xy 91.167379 -337.595837) (xy 91.190549 -337.645881) (xy 91.20627 -337.698739) (xy 91.214214 -337.753311)
			(xy 91.214702 -337.780884) (xy 91.214225 -337.808458) (xy 91.206274 -337.86303) (xy 91.190591 -337.915758)
			(xy 92.346778 -337.915758) (xy 92.350849 -337.860136) (xy 92.362975 -337.805699) (xy 92.382898 -337.753608)
			(xy 92.410194 -337.704973) (xy 92.44428 -337.66083) (xy 92.484429 -337.622121) (xy 92.529787 -337.58967)
			(xy 92.579387 -337.564169) (xy 92.632171 -337.546162) (xy 92.687014 -337.536032) (xy 92.742748 -337.533995)
			(xy 92.798185 -337.540095) (xy 92.852142 -337.554201) (xy 92.903471 -337.576013) (xy 92.951077 -337.605067)
			(xy 92.993945 -337.640742) (xy 93.031162 -337.682279) (xy 93.061935 -337.728792) (xy 93.085607 -337.779289)
			(xy 93.101675 -337.832696) (xy 93.109795 -337.887872) (xy 93.110304 -337.915758) (xy 93.109795 -337.943644)
			(xy 93.101675 -337.99882) (xy 93.085607 -338.052227) (xy 93.061935 -338.102724) (xy 93.031162 -338.149237)
			(xy 92.993945 -338.190774) (xy 92.951077 -338.226449) (xy 92.903471 -338.255503) (xy 92.852142 -338.277315)
			(xy 92.798185 -338.291421) (xy 92.742748 -338.297521) (xy 92.687014 -338.295484) (xy 92.632171 -338.285354)
			(xy 92.579387 -338.267347) (xy 92.529787 -338.241846) (xy 92.484429 -338.209395) (xy 92.44428 -338.170686)
			(xy 92.410194 -338.126543) (xy 92.382898 -338.077908) (xy 92.362975 -338.025817) (xy 92.350849 -337.97138)
			(xy 92.346778 -337.915758) (xy 91.190591 -337.915758) (xy 91.190552 -337.91589) (xy 91.167384 -337.965936)
			(xy 91.137253 -338.012126) (xy 91.100788 -338.053498) (xy 91.080082 -338.071714) (xy 91.071997 -338.079261)
			(xy 91.062649 -338.099279) (xy 91.062048 -338.110322) (xy 91.062048 -338.188046) (xy 91.062631 -338.199094)
			(xy 91.071984 -338.219116) (xy 91.080082 -338.226654) (xy 91.100771 -338.24489) (xy 91.137243 -338.286253)
			(xy 91.167379 -338.332437) (xy 91.190549 -338.382481) (xy 91.20627 -338.435339) (xy 91.214214 -338.489911)
			(xy 91.214702 -338.517484) (xy 91.21423 -338.544737) (xy 91.206475 -338.598688) (xy 91.191121 -338.650986)
			(xy 91.168479 -338.700566) (xy 91.139013 -338.74642) (xy 91.10332 -338.787613) (xy 91.076206 -338.811108)
			(xy 91.767658 -338.811108) (xy 91.771729 -338.755486) (xy 91.783855 -338.701049) (xy 91.803778 -338.648958)
			(xy 91.831074 -338.600323) (xy 91.86516 -338.55618) (xy 91.905309 -338.517471) (xy 91.950667 -338.48502)
			(xy 92.000267 -338.459519) (xy 92.053051 -338.441512) (xy 92.107894 -338.431382) (xy 92.163628 -338.429345)
			(xy 92.219065 -338.435445) (xy 92.273022 -338.449551) (xy 92.324351 -338.471363) (xy 92.371957 -338.500417)
			(xy 92.414825 -338.536092) (xy 92.452042 -338.577629) (xy 92.482815 -338.624142) (xy 92.506487 -338.674639)
			(xy 92.522555 -338.728046) (xy 92.530675 -338.783222) (xy 92.531184 -338.811108) (xy 92.530675 -338.838994)
			(xy 92.522555 -338.89417) (xy 92.506487 -338.947577) (xy 92.482815 -338.998074) (xy 92.452042 -339.044587)
			(xy 92.414825 -339.086124) (xy 92.371957 -339.121799) (xy 92.324351 -339.150853) (xy 92.273022 -339.172665)
			(xy 92.219065 -339.186771) (xy 92.163628 -339.192871) (xy 92.107894 -339.190834) (xy 92.053051 -339.180704)
			(xy 92.000267 -339.162697) (xy 91.950667 -339.137196) (xy 91.905309 -339.104745) (xy 91.86516 -339.066036)
			(xy 91.831074 -339.021893) (xy 91.803778 -338.973258) (xy 91.783855 -338.921167) (xy 91.771729 -338.86673)
			(xy 91.767658 -338.811108) (xy 91.076206 -338.811108) (xy 91.062128 -338.823307) (xy 91.016275 -338.852775)
			(xy 90.966695 -338.875417) (xy 90.914397 -338.890773) (xy 90.860447 -338.898529) (xy 90.833194 -338.898992)
			(xy 90.805338 -338.89848) (xy 90.750222 -338.890356) (xy 90.696871 -338.874309) (xy 90.646418 -338.850681)
			(xy 90.599933 -338.819973) (xy 90.558404 -338.782836) (xy 90.522711 -338.740059) (xy 90.493612 -338.69255)
			(xy 90.471725 -338.641318) (xy 90.464132 -338.614512) (xy 90.461846 -338.605622) (xy 90.451178 -338.590382)
			(xy 90.379296 -338.54263) (xy 90.361262 -338.538566) (xy 90.352118 -338.539836) (xy 90.339101 -338.541502)
			(xy 90.312917 -338.543284) (xy 90.299794 -338.543392) (xy 90.285645 -338.543299) (xy 90.257422 -338.541264)
			(xy 90.243406 -338.539328) (xy 90.2335 -338.537804) (xy 90.213688 -338.54263) (xy 90.139266 -338.59851)
			(xy 90.129106 -338.616036) (xy 90.127836 -338.626196) (xy 90.12377 -338.653353) (xy 90.108791 -338.706182)
			(xy 90.086395 -338.756319) (xy 90.057043 -338.802728) (xy 90.021343 -338.844451) (xy 89.980032 -338.880626)
			(xy 89.933961 -338.910507) (xy 89.884084 -338.933475) (xy 89.83143 -338.949058) (xy 89.777086 -338.956933)
			(xy 89.74963 -338.957412) (xy 89.722378 -338.956917) (xy 89.668428 -338.949164) (xy 89.616131 -338.933812)
			(xy 89.566552 -338.911173) (xy 89.520699 -338.881709) (xy 89.479506 -338.846018) (xy 89.443812 -338.804829)
			(xy 89.414343 -338.758978) (xy 89.3917 -338.7094) (xy 89.376343 -338.657105) (xy 89.368586 -338.603156)
			(xy 89.368122 -338.575904) (xy 87.227218 -338.575904) (xy 87.229853 -338.584877) (xy 87.237613 -338.638823)
			(xy 87.238078 -338.666074) (xy 87.237435 -338.697638) (xy 87.227041 -338.759903) (xy 87.206549 -338.819612)
			(xy 87.192104 -338.847684) (xy 87.187278 -338.856574) (xy 87.185246 -338.876132) (xy 87.208106 -338.954618)
			(xy 87.211345 -338.964042) (xy 87.223762 -338.979601) (xy 87.232236 -338.984844) (xy 87.257326 -338.999411)
			(xy 87.303211 -339.034909) (xy 87.343189 -339.076948) (xy 87.376337 -339.124559) (xy 87.40189 -339.176642)
			(xy 87.419257 -339.231994) (xy 87.428039 -339.289339) (xy 87.428578 -339.318346) (xy 87.428092 -339.345597)
			(xy 87.420336 -339.399545) (xy 87.404981 -339.45184) (xy 87.389038 -339.486748) (xy 93.106494 -339.486748)
			(xy 93.106951 -339.459272) (xy 93.11485 -339.404892) (xy 93.130477 -339.352209) (xy 93.153508 -339.302317)
			(xy 93.183466 -339.256249) (xy 93.201236 -339.235288) (xy 93.20149 -339.235034) (xy 93.207067 -339.227941)
			(xy 93.21332 -339.211029) (xy 93.213682 -339.202014) (xy 93.213682 -339.13445) (xy 93.213305 -339.125435)
			(xy 93.207072 -339.108518) (xy 93.20149 -339.10143) (xy 93.200982 -339.100922) (xy 93.18326 -339.079967)
			(xy 93.153376 -339.033936) (xy 93.130408 -338.984093) (xy 93.114831 -338.93147) (xy 93.106967 -338.877156)
			(xy 93.106494 -338.849716) (xy 93.10698 -338.822465) (xy 93.114736 -338.768517) (xy 93.130091 -338.716222)
			(xy 93.152733 -338.666645) (xy 93.182199 -338.620795) (xy 93.21789 -338.579604) (xy 93.259081 -338.543913)
			(xy 93.304931 -338.514447) (xy 93.354508 -338.491805) (xy 93.406803 -338.47645) (xy 93.460751 -338.468694)
			(xy 93.515253 -338.468694) (xy 93.569201 -338.47645) (xy 93.621496 -338.491805) (xy 93.671073 -338.514447)
			(xy 93.716923 -338.543913) (xy 93.758114 -338.579604) (xy 93.793805 -338.620795) (xy 93.823271 -338.666645)
			(xy 93.845913 -338.716222) (xy 93.861268 -338.768517) (xy 93.869024 -338.822465) (xy 93.86951 -338.849716)
			(xy 93.869031 -338.877191) (xy 93.861137 -338.931571) (xy 93.845515 -338.984253) (xy 93.842886 -338.98995)
			(xy 94.111301 -338.98995) (xy 94.111301 -338.93545) (xy 94.119058 -338.881504) (xy 94.134413 -338.829211)
			(xy 94.157054 -338.779635) (xy 94.18652 -338.733787) (xy 94.222211 -338.692599) (xy 94.263401 -338.656909)
			(xy 94.309251 -338.627445) (xy 94.358828 -338.604807) (xy 94.411121 -338.589454) (xy 94.465068 -338.5817)
			(xy 94.492318 -338.581238) (xy 94.492572 -338.581238) (xy 94.517775 -338.58165) (xy 94.567743 -338.588286)
			(xy 94.616397 -338.601459) (xy 94.662888 -338.620938) (xy 94.68485 -338.633308) (xy 94.694756 -338.63915)
			(xy 94.7166 -338.641182) (xy 94.811342 -338.607654) (xy 94.82709 -338.59216) (xy 94.831154 -338.581746)
			(xy 94.841843 -338.554967) (xy 94.870134 -338.504728) (xy 94.905667 -338.45932) (xy 94.94763 -338.419779)
			(xy 94.995068 -338.387006) (xy 95.046899 -338.361748) (xy 95.101941 -338.344582) (xy 95.158941 -338.335897)
			(xy 95.18777 -338.335366) (xy 95.215021 -338.335883) (xy 95.268969 -338.343635) (xy 95.321264 -338.358986)
			(xy 95.370842 -338.381623) (xy 95.416694 -338.411086) (xy 95.457886 -338.446774) (xy 95.493581 -338.487961)
			(xy 95.52305 -338.533809) (xy 95.545694 -338.583384) (xy 95.558418 -338.626704) (xy 97.699322 -338.626704)
			(xy 97.699783 -338.599129) (xy 97.707735 -338.544556) (xy 97.723461 -338.491695) (xy 97.746632 -338.441649)
			(xy 97.776765 -338.39546) (xy 97.813234 -338.354089) (xy 97.833942 -338.335874) (xy 97.842036 -338.328336)
			(xy 97.851378 -338.308311) (xy 97.851976 -338.297266) (xy 97.851976 -338.219542) (xy 97.851392 -338.208494)
			(xy 97.842039 -338.188473) (xy 97.833942 -338.180934) (xy 97.813252 -338.162699) (xy 97.776779 -338.121336)
			(xy 97.746643 -338.075152) (xy 97.723473 -338.025108) (xy 97.707752 -337.972249) (xy 97.699809 -337.917678)
			(xy 97.699322 -337.890104) (xy 97.699759 -337.86285) (xy 97.707516 -337.808896) (xy 97.722873 -337.756596)
			(xy 97.745518 -337.707014) (xy 97.774988 -337.66116) (xy 97.810685 -337.619966) (xy 97.85188 -337.584272)
			(xy 97.897737 -337.554805) (xy 97.947321 -337.532164) (xy 97.999622 -337.516811) (xy 98.053576 -337.509057)
			(xy 98.08083 -337.508596) (xy 98.081338 -337.508596) (xy 98.11512 -337.51012) (xy 98.12528 -337.511136)
			(xy 98.144584 -337.50504) (xy 98.207576 -337.452208) (xy 98.214878 -337.445495) (xy 98.224154 -337.427983)
			(xy 98.22561 -337.418172) (xy 98.22561 -337.41741) (xy 98.228502 -337.389241) (xy 98.241716 -337.334178)
			(xy 98.262927 -337.281674) (xy 98.291666 -337.232882) (xy 98.327304 -337.188876) (xy 98.369056 -337.150622)
			(xy 98.416005 -337.118961) (xy 98.467119 -337.09459) (xy 98.521274 -337.078043) (xy 98.57728 -337.069685)
			(xy 98.605594 -337.069176) (xy 98.632844 -337.069683) (xy 98.686791 -337.077439) (xy 98.739084 -337.092792)
			(xy 98.78866 -337.115431) (xy 98.83451 -337.144896) (xy 98.8757 -337.180585) (xy 98.911391 -337.221773)
			(xy 98.940858 -337.267621) (xy 98.9635 -337.317195) (xy 98.978857 -337.369488) (xy 98.986615 -337.423434)
			(xy 98.987102 -337.450684) (xy 98.986613 -337.478546) (xy 98.978512 -337.533679) (xy 98.962482 -337.587049)
			(xy 98.938862 -337.63752) (xy 98.908154 -337.68402) (xy 98.871012 -337.725562) (xy 98.849942 -337.7438)
			(xy 98.840798 -337.75142) (xy 98.8314 -337.772502) (xy 98.834448 -337.864704) (xy 98.835391 -337.876182)
			(xy 98.846094 -337.896547) (xy 98.855022 -337.90382) (xy 98.855276 -337.904074) (xy 98.875807 -337.919521)
			(xy 98.91294 -337.95503) (xy 98.944972 -337.995202) (xy 98.971323 -338.039309) (xy 98.991515 -338.086554)
			(xy 99.005184 -338.136081) (xy 99.012082 -338.186995) (xy 99.012502 -338.212684) (xy 99.011987 -338.242127)
			(xy 99.002939 -338.300314) (xy 98.985057 -338.356419) (xy 98.958764 -338.409109) (xy 98.924687 -338.457133)
			(xy 98.904552 -338.478622) (xy 98.904298 -338.478876) (xy 98.896575 -338.487741) (xy 98.889414 -338.510104)
			(xy 98.890582 -338.521802) (xy 98.904806 -338.614004) (xy 98.918522 -338.633308) (xy 98.928936 -338.638896)
			(xy 98.954506 -338.6533) (xy 99.001281 -338.688741) (xy 99.042078 -338.730927) (xy 99.075934 -338.778862)
			(xy 99.102052 -338.831415) (xy 99.119814 -338.887348) (xy 99.128803 -338.945341) (xy 99.129342 -338.974684)
			(xy 99.128834 -339.003602) (xy 99.120106 -339.060774) (xy 99.102848 -339.115974) (xy 99.077454 -339.167936)
			(xy 99.044508 -339.21547) (xy 99.004763 -339.257485) (xy 98.982276 -339.275674) (xy 98.973486 -339.283298)
			(xy 98.963294 -339.304186) (xy 98.962718 -339.315806) (xy 98.962718 -339.395562) (xy 98.963229 -339.407198)
			(xy 98.973437 -339.428107) (xy 98.982276 -339.435694) (xy 99.004752 -339.453894) (xy 99.044488 -339.495912)
			(xy 99.077429 -339.543444) (xy 99.102819 -339.595404) (xy 99.120077 -339.6506) (xy 99.128807 -339.707768)
			(xy 99.129342 -339.736684) (xy 99.128807 -339.763933) (xy 99.121054 -339.817877) (xy 99.105702 -339.870169)
			(xy 99.083065 -339.919744) (xy 99.053604 -339.965593) (xy 99.017918 -340.006782) (xy 98.976733 -340.042474)
			(xy 98.930888 -340.071941) (xy 98.881316 -340.094585) (xy 98.829026 -340.109943) (xy 98.775083 -340.117703)
			(xy 98.747834 -340.118192) (xy 98.718894 -340.117667) (xy 98.661681 -340.108901) (xy 98.606448 -340.091596)
			(xy 98.554462 -340.066148) (xy 98.506915 -340.033142) (xy 98.464898 -339.993334) (xy 98.429374 -339.947637)
			(xy 98.401158 -339.897099) (xy 98.380898 -339.842881) (xy 98.374454 -339.814662) (xy 98.374454 -339.814408)
			(xy 98.37202 -339.80506) (xy 98.361327 -339.788995) (xy 98.353626 -339.783166) (xy 98.287332 -339.7377)
			(xy 98.26879 -339.733382) (xy 98.259138 -339.734906) (xy 98.25863 -339.734906) (xy 98.243871 -339.737128)
			(xy 98.214119 -339.739547) (xy 98.199194 -339.739732) (xy 98.171944 -339.739228) (xy 98.117998 -339.731471)
			(xy 98.065705 -339.716116) (xy 98.016129 -339.693476) (xy 97.97028 -339.664012) (xy 97.929091 -339.628322)
			(xy 97.893399 -339.587134) (xy 97.863932 -339.541287) (xy 97.84129 -339.491712) (xy 97.825933 -339.43942)
			(xy 97.818173 -339.385474) (xy 97.817686 -339.358224) (xy 97.818159 -339.330984) (xy 97.825925 -339.277061)
			(xy 97.841289 -339.224793) (xy 97.863937 -339.175245) (xy 97.893407 -339.129424) (xy 97.910904 -339.108542)
			(xy 97.917723 -339.099699) (xy 97.923796 -339.07824) (xy 97.922588 -339.06714) (xy 97.908364 -338.978748)
			(xy 97.895918 -338.96046) (xy 97.886012 -338.954618) (xy 97.862006 -338.939797) (xy 97.818266 -338.904163)
			(xy 97.780254 -338.862474) (xy 97.748798 -338.81564) (xy 97.724585 -338.764683) (xy 97.708143 -338.710714)
			(xy 97.699831 -338.654913) (xy 97.699322 -338.626704) (xy 95.558418 -338.626704) (xy 95.561053 -338.635677)
			(xy 95.568813 -338.689623) (xy 95.569278 -338.716874) (xy 95.568635 -338.748438) (xy 95.558241 -338.810703)
			(xy 95.537749 -338.870412) (xy 95.523304 -338.898484) (xy 95.518478 -338.907374) (xy 95.516446 -338.926932)
			(xy 95.539306 -339.005418) (xy 95.542545 -339.014842) (xy 95.554962 -339.030401) (xy 95.563436 -339.035644)
			(xy 95.588526 -339.050211) (xy 95.634411 -339.085709) (xy 95.674389 -339.127748) (xy 95.707537 -339.175359)
			(xy 95.73309 -339.227442) (xy 95.750457 -339.282794) (xy 95.759239 -339.340139) (xy 95.759778 -339.369146)
			(xy 95.759292 -339.396397) (xy 95.751536 -339.450345) (xy 95.736181 -339.50264) (xy 95.713539 -339.552217)
			(xy 95.684073 -339.598067) (xy 95.648382 -339.639258) (xy 95.607191 -339.674949) (xy 95.561341 -339.704415)
			(xy 95.511764 -339.727057) (xy 95.459469 -339.742412) (xy 95.405521 -339.750168) (xy 95.351019 -339.750168)
			(xy 95.297071 -339.742412) (xy 95.244776 -339.727057) (xy 95.195199 -339.704415) (xy 95.149349 -339.674949)
			(xy 95.108158 -339.639258) (xy 95.072467 -339.598067) (xy 95.043001 -339.552217) (xy 95.020359 -339.50264)
			(xy 95.005004 -339.450345) (xy 94.997248 -339.396397) (xy 94.996762 -339.369146) (xy 94.99742 -339.337583)
			(xy 95.007809 -339.275318) (xy 95.028295 -339.215609) (xy 95.042736 -339.187536) (xy 95.047562 -339.178646)
			(xy 95.049594 -339.159088) (xy 95.026734 -339.080602) (xy 95.023509 -339.071172) (xy 95.011083 -339.055615)
			(xy 95.002604 -339.050376) (xy 94.995238 -339.046312) (xy 94.985332 -339.04047) (xy 94.963488 -339.038438)
			(xy 94.868746 -339.071966) (xy 94.852998 -339.08746) (xy 94.848934 -339.097874) (xy 94.838212 -339.12464)
			(xy 94.80993 -339.174882) (xy 94.774404 -339.220293) (xy 94.732447 -339.259837) (xy 94.685013 -339.292613)
			(xy 94.633185 -339.317872) (xy 94.578144 -339.33504) (xy 94.521146 -339.343724) (xy 94.492318 -339.344254)
			(xy 94.465068 -339.3437) (xy 94.411121 -339.335946) (xy 94.358828 -339.320593) (xy 94.309251 -339.297955)
			(xy 94.263401 -339.268491) (xy 94.222211 -339.232801) (xy 94.18652 -339.191613) (xy 94.157054 -339.145765)
			(xy 94.134413 -339.096189) (xy 94.119058 -339.043896) (xy 94.111301 -338.98995) (xy 93.842886 -338.98995)
			(xy 93.822489 -339.034146) (xy 93.792536 -339.080214) (xy 93.774768 -339.101176) (xy 93.774514 -339.10143)
			(xy 93.768952 -339.108534) (xy 93.76269 -339.125437) (xy 93.762322 -339.13445) (xy 93.762322 -339.202014)
			(xy 93.762667 -339.211032) (xy 93.768922 -339.227949) (xy 93.774514 -339.235034) (xy 93.775022 -339.235542)
			(xy 93.792775 -339.256473) (xy 93.822654 -339.30251) (xy 93.845616 -339.352359) (xy 93.861186 -339.404988)
			(xy 93.869042 -339.459306) (xy 93.86951 -339.486748) (xy 93.869024 -339.513999) (xy 93.861268 -339.567947)
			(xy 93.845913 -339.620242) (xy 93.823271 -339.669819) (xy 93.793805 -339.715669) (xy 93.758114 -339.75686)
			(xy 93.716923 -339.792551) (xy 93.671073 -339.822017) (xy 93.621496 -339.844659) (xy 93.569201 -339.860014)
			(xy 93.515253 -339.86777) (xy 93.460751 -339.86777) (xy 93.406803 -339.860014) (xy 93.354508 -339.844659)
			(xy 93.304931 -339.822017) (xy 93.259081 -339.792551) (xy 93.21789 -339.75686) (xy 93.182199 -339.715669)
			(xy 93.152733 -339.669819) (xy 93.130091 -339.620242) (xy 93.114736 -339.567947) (xy 93.10698 -339.513999)
			(xy 93.106494 -339.486748) (xy 87.389038 -339.486748) (xy 87.382339 -339.501417) (xy 87.352873 -339.547267)
			(xy 87.317182 -339.588458) (xy 87.275991 -339.624149) (xy 87.230141 -339.653615) (xy 87.180564 -339.676257)
			(xy 87.128269 -339.691612) (xy 87.074321 -339.699368) (xy 87.019819 -339.699368) (xy 86.965871 -339.691612)
			(xy 86.913576 -339.676257) (xy 86.863999 -339.653615) (xy 86.818149 -339.624149) (xy 86.776958 -339.588458)
			(xy 86.741267 -339.547267) (xy 86.711801 -339.501417) (xy 86.689159 -339.45184) (xy 86.673804 -339.399545)
			(xy 86.666048 -339.345597) (xy 86.665562 -339.318346) (xy 86.66622 -339.286783) (xy 86.676609 -339.224518)
			(xy 86.697095 -339.164809) (xy 86.711536 -339.136736) (xy 86.716362 -339.127846) (xy 86.718394 -339.108288)
			(xy 86.695534 -339.029802) (xy 86.692309 -339.020372) (xy 86.679883 -339.004815) (xy 86.671404 -338.999576)
			(xy 86.664038 -338.995512) (xy 86.654132 -338.98967) (xy 86.632288 -338.987638) (xy 86.537546 -339.021166)
			(xy 86.521798 -339.03666) (xy 86.517734 -339.047074) (xy 86.507012 -339.07384) (xy 86.47873 -339.124082)
			(xy 86.443204 -339.169493) (xy 86.401247 -339.209037) (xy 86.353813 -339.241813) (xy 86.301985 -339.267072)
			(xy 86.246944 -339.28424) (xy 86.189946 -339.292924) (xy 86.161118 -339.293454) (xy 86.133868 -339.2929)
			(xy 86.079921 -339.285146) (xy 86.027628 -339.269793) (xy 85.978051 -339.247155) (xy 85.932201 -339.217691)
			(xy 85.891011 -339.182001) (xy 85.85532 -339.140813) (xy 85.825854 -339.094965) (xy 85.803213 -339.045389)
			(xy 85.787858 -338.993096) (xy 85.780101 -338.93915) (xy 85.511697 -338.93915) (xy 85.491428 -338.983136)
			(xy 85.461545 -339.029167) (xy 85.443822 -339.050122) (xy 85.443314 -339.05063) (xy 85.437732 -339.057718)
			(xy 85.431498 -339.074635) (xy 85.431122 -339.08365) (xy 85.431122 -339.151214) (xy 85.431484 -339.160229)
			(xy 85.437737 -339.177141) (xy 85.443314 -339.184234) (xy 85.443568 -339.184488) (xy 85.461338 -339.205449)
			(xy 85.491295 -339.251517) (xy 85.514326 -339.301409) (xy 85.529953 -339.354092) (xy 85.537852 -339.408472)
			(xy 85.53831 -339.435948) (xy 85.53785 -339.462792) (xy 85.53032 -339.51595) (xy 85.515416 -339.567528)
			(xy 85.493432 -339.616508) (xy 85.464801 -339.661925) (xy 85.430088 -339.702882) (xy 85.389979 -339.73857)
			(xy 85.345264 -339.768286) (xy 85.296827 -339.791444) (xy 85.271356 -339.79993) (xy 85.255354 -339.80501)
			(xy 85.235796 -339.83168) (xy 85.235796 -340.712552) (xy 85.23519 -340.737538) (xy 85.225458 -340.786552)
			(xy 85.206357 -340.832729) (xy 85.178622 -340.874297) (xy 85.161374 -340.892384) (xy 84.459572 -341.594186)
			(xy 99.664774 -341.594186) (xy 99.665262 -341.566275) (xy 99.673398 -341.511049) (xy 99.689495 -341.457599)
			(xy 99.713209 -341.407064) (xy 99.744033 -341.360524) (xy 99.76231 -341.339424) (xy 99.768198 -341.33224)
			(xy 99.774854 -341.31492) (xy 99.775264 -341.305642) (xy 99.775264 -341.227918) (xy 99.76866 -341.210646)
			(xy 99.76231 -341.203534) (xy 99.744028 -341.182437) (xy 99.713201 -341.135898) (xy 99.689486 -341.085363)
			(xy 99.673391 -341.031911) (xy 99.665258 -340.976684) (xy 99.664774 -340.948772) (xy 99.66526 -340.921521)
			(xy 99.673016 -340.867573) (xy 99.688371 -340.815278) (xy 99.711013 -340.765701) (xy 99.740479 -340.719851)
			(xy 99.77617 -340.67866) (xy 99.817361 -340.642969) (xy 99.863211 -340.613503) (xy 99.912788 -340.590861)
			(xy 99.965083 -340.575506) (xy 100.019031 -340.56775) (xy 100.073533 -340.56775) (xy 100.127481 -340.575506)
			(xy 100.179776 -340.590861) (xy 100.229353 -340.613503) (xy 100.275203 -340.642969) (xy 100.316394 -340.67866)
			(xy 100.352085 -340.719851) (xy 100.381551 -340.765701) (xy 100.404193 -340.815278) (xy 100.419548 -340.867573)
			(xy 100.427304 -340.921521) (xy 100.42779 -340.948772) (xy 100.42732 -340.976683) (xy 100.419177 -341.031909)
			(xy 100.403075 -341.08536) (xy 100.379358 -341.135894) (xy 100.348531 -341.182434) (xy 100.330254 -341.203534)
			(xy 100.324337 -341.210697) (xy 100.317699 -341.228033) (xy 100.3173 -341.237316) (xy 100.3173 -341.31504)
			(xy 100.323904 -341.332312) (xy 100.330254 -341.339424) (xy 100.348526 -341.360528) (xy 100.379353 -341.407066)
			(xy 100.403068 -341.4576) (xy 100.419166 -341.51105) (xy 100.427303 -341.566275) (xy 100.42779 -341.594186)
			(xy 100.427304 -341.621437) (xy 100.419548 -341.675385) (xy 100.404193 -341.72768) (xy 100.381551 -341.777257)
			(xy 100.352085 -341.823107) (xy 100.316394 -341.864298) (xy 100.275203 -341.899989) (xy 100.232084 -341.9277)
			(xy 104.047047 -341.9277) (xy 104.051215 -341.872088) (xy 104.063623 -341.817718) (xy 104.083996 -341.765805)
			(xy 104.111879 -341.717508) (xy 104.146648 -341.673905) (xy 104.187526 -341.635971) (xy 104.233602 -341.604553)
			(xy 104.283845 -341.580353) (xy 104.337134 -341.56391) (xy 104.392278 -341.555594) (xy 104.420162 -341.55507)
			(xy 104.446585 -341.555499) (xy 104.498901 -341.562957) (xy 104.54964 -341.577729) (xy 104.597784 -341.599519)
			(xy 104.642367 -341.62789) (xy 104.662732 -341.644732) (xy 104.66959 -341.650574) (xy 104.686608 -341.656924)
			(xy 104.770936 -341.656924) (xy 104.787954 -341.650574) (xy 104.794812 -341.644732) (xy 104.815178 -341.627893)
			(xy 104.859764 -341.599528) (xy 104.907908 -341.577741) (xy 104.958645 -341.56297) (xy 105.01096 -341.55551)
			(xy 105.063804 -341.55551) (xy 105.116119 -341.56297) (xy 105.166856 -341.577741) (xy 105.215 -341.599528)
			(xy 105.259586 -341.627893) (xy 105.279952 -341.644732) (xy 105.28681 -341.650574) (xy 105.303828 -341.656924)
			(xy 105.388156 -341.656924) (xy 105.405174 -341.650574) (xy 105.412032 -341.644732) (xy 105.432821 -341.627549)
			(xy 105.478409 -341.598732) (xy 105.527679 -341.576798) (xy 105.55351 -341.56904) (xy 105.553764 -341.56904)
			(xy 105.564805 -341.565251) (xy 105.58214 -341.549661) (xy 105.587038 -341.539068) (xy 105.61701 -341.464138)
			(xy 105.620746 -341.453059) (xy 105.618904 -341.429777) (xy 105.613454 -341.419434) (xy 105.601097 -341.397777)
			(xy 105.581621 -341.351876) (xy 105.568438 -341.303789) (xy 105.561785 -341.254373) (xy 105.561384 -341.229442)
			(xy 105.561878 -341.201799) (xy 105.570036 -341.14712) (xy 105.586179 -341.094244) (xy 105.609954 -341.044332)
			(xy 105.640839 -340.998478) (xy 105.678156 -340.957688) (xy 105.699306 -340.939882) (xy 105.707746 -340.932298)
			(xy 105.717501 -340.911844) (xy 105.718102 -340.900512) (xy 105.718102 -340.821772) (xy 105.717457 -340.810454)
			(xy 105.707701 -340.790021) (xy 105.699306 -340.782402) (xy 105.67818 -340.76457) (xy 105.640866 -340.723783)
			(xy 105.609982 -340.677933) (xy 105.586205 -340.628027) (xy 105.570056 -340.575157) (xy 105.561888 -340.520482)
			(xy 105.561384 -340.492842) (xy 105.561905 -340.464957) (xy 105.570217 -340.40981) (xy 105.586655 -340.356518)
			(xy 105.610853 -340.306272) (xy 105.642269 -340.260193) (xy 105.680202 -340.219311) (xy 105.723804 -340.184539)
			(xy 105.772102 -340.156654) (xy 105.824017 -340.136279) (xy 105.878388 -340.123869) (xy 105.934002 -340.119702)
			(xy 105.989616 -340.123869) (xy 106.043987 -340.136279) (xy 106.095902 -340.156654) (xy 106.1442 -340.184539)
			(xy 106.187802 -340.219311) (xy 106.225735 -340.260193) (xy 106.257151 -340.306272) (xy 106.281349 -340.356518)
			(xy 106.297787 -340.40981) (xy 106.306099 -340.464957) (xy 106.30662 -340.492842) (xy 106.306114 -340.520484)
			(xy 106.297958 -340.575163) (xy 106.281817 -340.628039) (xy 106.258045 -340.677951) (xy 106.227162 -340.723805)
			(xy 106.189847 -340.764596) (xy 106.168698 -340.782402) (xy 106.160266 -340.789993) (xy 106.150507 -340.810442)
			(xy 106.149902 -340.821772) (xy 106.149902 -340.900512) (xy 106.150554 -340.91183) (xy 106.160305 -340.932263)
			(xy 106.168698 -340.939882) (xy 106.189817 -340.957721) (xy 106.227132 -340.998508) (xy 106.258017 -341.044356)
			(xy 106.281795 -341.09426) (xy 106.297945 -341.147129) (xy 106.306114 -341.201802) (xy 106.30662 -341.229442)
			(xy 106.306104 -341.256283) (xy 106.298407 -341.30941) (xy 106.283166 -341.360883) (xy 106.260695 -341.409636)
			(xy 106.23146 -341.454658) (xy 106.196065 -341.495019) (xy 106.155245 -341.529882) (xy 106.109843 -341.558525)
			(xy 106.060801 -341.580356) (xy 106.035094 -341.58809) (xy 106.03484 -341.58809) (xy 106.023794 -341.591867)
			(xy 106.00646 -341.607465) (xy 106.001566 -341.618062) (xy 105.971594 -341.692992) (xy 105.967839 -341.704066)
			(xy 105.969694 -341.727353) (xy 105.97515 -341.737696) (xy 105.98752 -341.759346) (xy 106.006992 -341.805249)
			(xy 106.020171 -341.853339) (xy 106.026821 -341.902757) (xy 106.02722 -341.927688) (xy 106.026755 -341.954305)
			(xy 106.01918 -342.006999) (xy 106.004184 -342.058078) (xy 105.98207 -342.106502) (xy 105.95329 -342.151287)
			(xy 105.91843 -342.19152) (xy 105.878198 -342.226382) (xy 105.833415 -342.255163) (xy 105.784991 -342.277279)
			(xy 105.733912 -342.292277) (xy 105.681219 -342.299854) (xy 105.654602 -342.300306) (xy 105.62818 -342.299846)
			(xy 105.575865 -342.292396) (xy 105.525127 -342.277632) (xy 105.476982 -342.255848) (xy 105.432397 -342.227483)
			(xy 105.412032 -342.210644) (xy 105.405174 -342.204802) (xy 105.388156 -342.198452) (xy 105.303828 -342.198452)
			(xy 105.28681 -342.204802) (xy 105.279952 -342.210644) (xy 105.259586 -342.227483) (xy 105.215 -342.255848)
			(xy 105.166856 -342.277635) (xy 105.116119 -342.292406) (xy 105.063804 -342.299866) (xy 105.01096 -342.299866)
			(xy 104.958645 -342.292406) (xy 104.907908 -342.277635) (xy 104.859764 -342.255848) (xy 104.815178 -342.227483)
			(xy 104.794812 -342.210644) (xy 104.787954 -342.204802) (xy 104.770936 -342.198452) (xy 104.686608 -342.198452)
			(xy 104.66959 -342.204802) (xy 104.662732 -342.210644) (xy 104.642348 -342.227458) (xy 104.597764 -342.255819)
			(xy 104.549624 -342.277604) (xy 104.498891 -342.292377) (xy 104.446582 -342.299842) (xy 104.420162 -342.300306)
			(xy 104.392278 -342.299806) (xy 104.337134 -342.29149) (xy 104.283845 -342.275047) (xy 104.233602 -342.250847)
			(xy 104.187526 -342.219429) (xy 104.146648 -342.181495) (xy 104.111879 -342.137892) (xy 104.083996 -342.089595)
			(xy 104.063623 -342.037682) (xy 104.051215 -341.983312) (xy 104.047047 -341.9277) (xy 100.232084 -341.9277)
			(xy 100.229353 -341.929455) (xy 100.179776 -341.952097) (xy 100.127481 -341.967452) (xy 100.073533 -341.975208)
			(xy 100.019031 -341.975208) (xy 99.965083 -341.967452) (xy 99.912788 -341.952097) (xy 99.863211 -341.929455)
			(xy 99.817361 -341.899989) (xy 99.77617 -341.864298) (xy 99.740479 -341.823107) (xy 99.711013 -341.777257)
			(xy 99.688371 -341.72768) (xy 99.673016 -341.675385) (xy 99.66526 -341.621437) (xy 99.664774 -341.594186)
			(xy 84.459572 -341.594186) (xy 83.891628 -342.16213) (xy 83.873517 -342.179349) (xy 83.831955 -342.207081)
			(xy 83.785785 -342.226182) (xy 83.736778 -342.235919) (xy 83.711796 -342.236552) (xy 82.078322 -342.236552)
			(xy 82.068259 -342.236991) (xy 82.04968 -342.244731) (xy 82.042254 -342.251538) (xy 81.46796 -342.825832)
			(xy 100.622606 -342.825832) (xy 100.626677 -342.77021) (xy 100.638803 -342.715773) (xy 100.658726 -342.663682)
			(xy 100.686022 -342.615047) (xy 100.720108 -342.570904) (xy 100.760257 -342.532195) (xy 100.805615 -342.499744)
			(xy 100.855215 -342.474243) (xy 100.907999 -342.456236) (xy 100.962842 -342.446106) (xy 101.018576 -342.444069)
			(xy 101.074013 -342.450169) (xy 101.12797 -342.464275) (xy 101.179299 -342.486087) (xy 101.226905 -342.515141)
			(xy 101.269773 -342.550816) (xy 101.30699 -342.592353) (xy 101.337763 -342.638866) (xy 101.361435 -342.689363)
			(xy 101.377503 -342.74277) (xy 101.385623 -342.797946) (xy 101.386132 -342.825832) (xy 101.385623 -342.853718)
			(xy 101.377503 -342.908894) (xy 101.361435 -342.962301) (xy 101.337763 -343.012798) (xy 101.30699 -343.059311)
			(xy 101.269773 -343.100848) (xy 101.226905 -343.136523) (xy 101.179299 -343.165577) (xy 101.12797 -343.187389)
			(xy 101.074013 -343.201495) (xy 101.018576 -343.207595) (xy 100.962842 -343.205558) (xy 100.907999 -343.195428)
			(xy 100.855215 -343.177421) (xy 100.805615 -343.15192) (xy 100.760257 -343.119469) (xy 100.720108 -343.08076)
			(xy 100.686022 -343.036617) (xy 100.658726 -342.987982) (xy 100.638803 -342.935891) (xy 100.626677 -342.881454)
			(xy 100.622606 -342.825832) (xy 81.46796 -342.825832) (xy 80.57261 -343.721182) (xy 100.043486 -343.721182)
			(xy 100.047557 -343.66556) (xy 100.059683 -343.611123) (xy 100.079606 -343.559032) (xy 100.106902 -343.510397)
			(xy 100.140988 -343.466254) (xy 100.181137 -343.427545) (xy 100.226495 -343.395094) (xy 100.276095 -343.369593)
			(xy 100.328879 -343.351586) (xy 100.383722 -343.341456) (xy 100.439456 -343.339419) (xy 100.494893 -343.345519)
			(xy 100.54885 -343.359625) (xy 100.600179 -343.381437) (xy 100.647785 -343.410491) (xy 100.690653 -343.446166)
			(xy 100.72787 -343.487703) (xy 100.758643 -343.534216) (xy 100.782315 -343.584713) (xy 100.798383 -343.63812)
			(xy 100.806503 -343.693296) (xy 100.807012 -343.721182) (xy 100.806503 -343.749068) (xy 100.798383 -343.804244)
			(xy 100.782315 -343.857651) (xy 100.758643 -343.908148) (xy 100.72787 -343.954661) (xy 100.690653 -343.996198)
			(xy 100.647785 -344.031873) (xy 100.600179 -344.060927) (xy 100.54885 -344.082739) (xy 100.494893 -344.096845)
			(xy 100.439456 -344.102945) (xy 100.383722 -344.100908) (xy 100.328879 -344.090778) (xy 100.276095 -344.072771)
			(xy 100.226495 -344.04727) (xy 100.181137 -344.014819) (xy 100.140988 -343.97611) (xy 100.106902 -343.931967)
			(xy 100.079606 -343.883332) (xy 100.059683 -343.831241) (xy 100.047557 -343.776804) (xy 100.043486 -343.721182)
			(xy 80.57261 -343.721182) (xy 79.89697 -344.396822) (xy 101.382322 -344.396822) (xy 101.382816 -344.369348)
			(xy 101.390705 -344.314968) (xy 101.406323 -344.262286) (xy 101.429346 -344.212393) (xy 101.459297 -344.166324)
			(xy 101.477064 -344.145362) (xy 101.477318 -344.145108) (xy 101.482909 -344.138025) (xy 101.489153 -344.121105)
			(xy 101.48951 -344.112088) (xy 101.48951 -344.044524) (xy 101.489139 -344.035509) (xy 101.482901 -344.018592)
			(xy 101.477318 -344.011504) (xy 101.47681 -344.010996) (xy 101.45908 -343.990047) (xy 101.429197 -343.944015)
			(xy 101.40623 -343.894171) (xy 101.390654 -343.841546) (xy 101.382793 -343.787231) (xy 101.382322 -343.75979)
			(xy 101.382808 -343.732539) (xy 101.390564 -343.678591) (xy 101.405919 -343.626296) (xy 101.428561 -343.576719)
			(xy 101.458027 -343.530869) (xy 101.493718 -343.489678) (xy 101.534909 -343.453987) (xy 101.580759 -343.424521)
			(xy 101.630336 -343.401879) (xy 101.682631 -343.386524) (xy 101.736579 -343.378768) (xy 101.791081 -343.378768)
			(xy 101.845029 -343.386524) (xy 101.897324 -343.401879) (xy 101.946901 -343.424521) (xy 101.992751 -343.453987)
			(xy 102.033942 -343.489678) (xy 102.069633 -343.530869) (xy 102.099099 -343.576719) (xy 102.121741 -343.626296)
			(xy 102.137096 -343.678591) (xy 102.144852 -343.732539) (xy 102.145338 -343.75979) (xy 102.144836 -343.787264)
			(xy 102.136947 -343.841643) (xy 102.12133 -343.894324) (xy 102.118686 -343.900054) (xy 102.387075 -343.900054)
			(xy 102.387075 -343.845546) (xy 102.394833 -343.791594) (xy 102.410191 -343.739296) (xy 102.432835 -343.689715)
			(xy 102.462306 -343.643862) (xy 102.498003 -343.60267) (xy 102.539199 -343.566979) (xy 102.585055 -343.537513)
			(xy 102.634639 -343.514875) (xy 102.686939 -343.499523) (xy 102.740892 -343.491772) (xy 102.768146 -343.491312)
			(xy 102.7684 -343.491312) (xy 102.793604 -343.491715) (xy 102.843571 -343.498354) (xy 102.892226 -343.51153)
			(xy 102.938716 -343.531011) (xy 102.960678 -343.543382) (xy 102.970584 -343.549224) (xy 102.992428 -343.551256)
			(xy 103.08717 -343.517728) (xy 103.102918 -343.502234) (xy 103.106982 -343.49182) (xy 103.117687 -343.465047)
			(xy 103.145972 -343.414804) (xy 103.1815 -343.369393) (xy 103.22346 -343.32985) (xy 103.270896 -343.297075)
			(xy 103.322727 -343.271817) (xy 103.377769 -343.254651) (xy 103.434769 -343.245969) (xy 103.463598 -343.24544)
			(xy 103.490853 -343.245857) (xy 103.544808 -343.253615) (xy 103.59711 -343.268973) (xy 103.646693 -343.291619)
			(xy 103.692548 -343.321092) (xy 103.733742 -343.35679) (xy 103.769436 -343.397988) (xy 103.798903 -343.443847)
			(xy 103.801787 -343.450164) (xy 105.961942 -343.450164) (xy 105.962437 -343.42259) (xy 105.970382 -343.368018)
			(xy 105.9861 -343.315158) (xy 106.009264 -343.265112) (xy 106.039392 -343.218922) (xy 106.075856 -343.17755)
			(xy 106.096562 -343.159334) (xy 106.104632 -343.151775) (xy 106.113987 -343.131766) (xy 106.114596 -343.120726)
			(xy 106.114596 -343.043002) (xy 106.114028 -343.031953) (xy 106.104663 -343.011932) (xy 106.096562 -343.004394)
			(xy 106.075837 -342.986198) (xy 106.03937 -342.944825) (xy 106.00924 -342.898632) (xy 105.986077 -342.848581)
			(xy 105.970363 -342.795716) (xy 105.962426 -342.741139) (xy 105.961942 -342.713564) (xy 105.962322 -342.686308)
			(xy 105.970085 -342.632351) (xy 105.985448 -342.580049) (xy 106.008098 -342.530465) (xy 106.037575 -342.48461)
			(xy 106.073277 -342.443416) (xy 106.114479 -342.407723) (xy 106.160341 -342.378257) (xy 106.20993 -342.355618)
			(xy 106.262236 -342.340266) (xy 106.316194 -342.332515) (xy 106.34345 -342.332056) (xy 106.375072 -342.33266)
			(xy 106.437445 -342.343115) (xy 106.497234 -342.363729) (xy 106.525314 -342.378284) (xy 106.53395 -342.382856)
			(xy 106.553254 -342.385142) (xy 106.639868 -342.362028) (xy 106.655362 -342.350344) (xy 106.660442 -342.341962)
			(xy 106.676797 -342.316317) (xy 106.716359 -342.270121) (xy 106.739182 -342.250014) (xy 106.747248 -342.24245)
			(xy 106.756608 -342.222446) (xy 106.757216 -342.211406) (xy 106.757216 -342.133682) (xy 106.756629 -342.122634)
			(xy 106.74728 -342.102611) (xy 106.739182 -342.095074) (xy 106.718451 -342.076884) (xy 106.681983 -342.03551)
			(xy 106.651854 -341.989316) (xy 106.628692 -341.939264) (xy 106.61298 -341.886398) (xy 106.605045 -341.83182)
			(xy 106.604562 -341.804244) (xy 106.605048 -341.776993) (xy 106.612804 -341.723045) (xy 106.628159 -341.67075)
			(xy 106.650801 -341.621173) (xy 106.680267 -341.575323) (xy 106.715958 -341.534132) (xy 106.757149 -341.498441)
			(xy 106.802999 -341.468975) (xy 106.852576 -341.446333) (xy 106.904871 -341.430978) (xy 106.958819 -341.423222)
			(xy 107.013321 -341.423222) (xy 107.067269 -341.430978) (xy 107.119564 -341.446333) (xy 107.169141 -341.468975)
			(xy 107.214991 -341.498441) (xy 107.256182 -341.534132) (xy 107.291873 -341.575323) (xy 107.321339 -341.621173)
			(xy 107.343981 -341.67075) (xy 107.359336 -341.723045) (xy 107.367092 -341.776993) (xy 107.367578 -341.804244)
			(xy 107.367081 -341.831818) (xy 107.359136 -341.886389) (xy 107.343418 -341.939249) (xy 107.320254 -341.989295)
			(xy 107.290126 -342.035486) (xy 107.253663 -342.076858) (xy 107.232958 -342.095074) (xy 107.224887 -342.102633)
			(xy 107.215532 -342.122642) (xy 107.214924 -342.133682) (xy 107.214924 -342.211406) (xy 107.215537 -342.22245)
			(xy 107.22487 -342.242472) (xy 107.232958 -342.250014) (xy 107.253671 -342.268224) (xy 107.290143 -342.309592)
			(xy 107.320276 -342.355781) (xy 107.343442 -342.40583) (xy 107.359157 -342.458693) (xy 107.367094 -342.513269)
			(xy 107.367578 -342.540844) (xy 107.367008 -342.570786) (xy 107.357634 -342.629932) (xy 107.339138 -342.686889)
			(xy 107.311974 -342.740259) (xy 107.27681 -342.788732) (xy 107.256072 -342.810338) (xy 107.248971 -342.818108)
			(xy 107.241235 -342.837659) (xy 107.241086 -342.848184) (xy 107.244134 -342.922606) (xy 107.245046 -342.933142)
			(xy 107.254233 -342.952166) (xy 107.261914 -342.959436) (xy 107.282469 -342.977667) (xy 107.318675 -343.018991)
			(xy 107.34858 -343.065079) (xy 107.371568 -343.114979) (xy 107.387162 -343.167661) (xy 107.39504 -343.222034)
			(xy 107.395518 -343.249504) (xy 107.395049 -343.277078) (xy 107.387096 -343.331651) (xy 107.371371 -343.38451)
			(xy 107.348202 -343.434556) (xy 107.31807 -343.480746) (xy 107.281604 -343.522118) (xy 107.260898 -343.540334)
			(xy 107.252807 -343.547875) (xy 107.243462 -343.567897) (xy 107.242864 -343.578942) (xy 107.242864 -343.656666)
			(xy 107.243431 -343.667716) (xy 107.252795 -343.687738) (xy 107.260898 -343.695274) (xy 107.281599 -343.713496)
			(xy 107.318071 -343.754862) (xy 107.348204 -343.80105) (xy 107.371371 -343.851096) (xy 107.38709 -343.903957)
			(xy 107.395032 -343.95853) (xy 107.395518 -343.986104) (xy 107.395032 -344.013355) (xy 107.387276 -344.067303)
			(xy 107.371921 -344.119598) (xy 107.349279 -344.169175) (xy 107.319813 -344.215025) (xy 107.284122 -344.256216)
			(xy 107.242931 -344.291907) (xy 107.197081 -344.321373) (xy 107.147504 -344.344015) (xy 107.095209 -344.35937)
			(xy 107.041261 -344.367126) (xy 106.986759 -344.367126) (xy 106.932811 -344.35937) (xy 106.880516 -344.344015)
			(xy 106.830939 -344.321373) (xy 106.785089 -344.291907) (xy 106.743898 -344.256216) (xy 106.708207 -344.215025)
			(xy 106.678741 -344.169175) (xy 106.656099 -344.119598) (xy 106.640744 -344.067303) (xy 106.632988 -344.013355)
			(xy 106.632502 -343.986104) (xy 106.632502 -343.985342) (xy 106.632746 -343.966675) (xy 106.636431 -343.929523)
			(xy 106.639868 -343.911174) (xy 106.642662 -343.897204) (xy 106.63301 -343.870534) (xy 106.540046 -343.796366)
			(xy 106.512106 -343.79281) (xy 106.498898 -343.798652) (xy 106.474378 -343.809107) (xy 106.423142 -343.823814)
			(xy 106.370356 -343.831233) (xy 106.343704 -343.831672) (xy 106.34345 -343.831672) (xy 106.316197 -343.831198)
			(xy 106.262244 -343.823447) (xy 106.209944 -343.808095) (xy 106.160362 -343.785456) (xy 106.114507 -343.75599)
			(xy 106.073313 -343.720297) (xy 106.037618 -343.679104) (xy 106.008151 -343.63325) (xy 105.985509 -343.583669)
			(xy 105.970156 -343.531369) (xy 105.962403 -343.477417) (xy 105.961942 -343.450164) (xy 103.801787 -343.450164)
			(xy 103.821543 -343.493433) (xy 103.836895 -343.545737) (xy 103.844646 -343.599693) (xy 103.845106 -343.626948)
			(xy 103.844449 -343.658511) (xy 103.834061 -343.720776) (xy 103.813574 -343.780485) (xy 103.799132 -343.808558)
			(xy 103.794306 -343.817448) (xy 103.792274 -343.837006) (xy 103.815134 -343.915492) (xy 103.818373 -343.924916)
			(xy 103.83079 -343.940476) (xy 103.839264 -343.945718) (xy 103.864349 -343.960293) (xy 103.910233 -343.995791)
			(xy 103.95021 -344.037829) (xy 103.983358 -344.085439) (xy 104.008911 -344.13752) (xy 104.026281 -344.192871)
			(xy 104.035065 -344.250214) (xy 104.035606 -344.27922) (xy 104.03512 -344.306471) (xy 104.027364 -344.360419)
			(xy 104.012009 -344.412714) (xy 103.989367 -344.462291) (xy 103.959901 -344.508141) (xy 103.92421 -344.549332)
			(xy 103.883019 -344.585023) (xy 103.837169 -344.614489) (xy 103.787592 -344.637131) (xy 103.735297 -344.652486)
			(xy 103.681349 -344.660242) (xy 103.626847 -344.660242) (xy 103.572899 -344.652486) (xy 103.520604 -344.637131)
			(xy 103.471027 -344.614489) (xy 103.425177 -344.585023) (xy 103.383986 -344.549332) (xy 103.348295 -344.508141)
			(xy 103.318829 -344.462291) (xy 103.296187 -344.412714) (xy 103.280832 -344.360419) (xy 103.273076 -344.306471)
			(xy 103.27259 -344.27922) (xy 103.273235 -344.247657) (xy 103.283628 -344.185391) (xy 103.30412 -344.125682)
			(xy 103.318564 -344.09761) (xy 103.32339 -344.08872) (xy 103.325422 -344.069162) (xy 103.302562 -343.990676)
			(xy 103.299337 -343.981246) (xy 103.28691 -343.96569) (xy 103.278432 -343.96045) (xy 103.271066 -343.956386)
			(xy 103.26116 -343.950544) (xy 103.239316 -343.948512) (xy 103.144574 -343.98204) (xy 103.128826 -343.997534)
			(xy 103.124762 -344.007948) (xy 103.114056 -344.03472) (xy 103.085767 -344.084959) (xy 103.050238 -344.130367)
			(xy 103.008277 -344.169908) (xy 102.960841 -344.202682) (xy 102.909013 -344.227941) (xy 102.853972 -344.245109)
			(xy 102.796974 -344.253796) (xy 102.768146 -344.254328) (xy 102.740892 -344.253828) (xy 102.686939 -344.246077)
			(xy 102.634639 -344.230725) (xy 102.585055 -344.208087) (xy 102.539199 -344.178621) (xy 102.498003 -344.14293)
			(xy 102.462306 -344.101738) (xy 102.432835 -344.055885) (xy 102.410191 -344.006304) (xy 102.394833 -343.954006)
			(xy 102.387075 -343.900054) (xy 102.118686 -343.900054) (xy 102.098309 -343.944217) (xy 102.068361 -343.990287)
			(xy 102.050596 -344.01125) (xy 102.050342 -344.011504) (xy 102.044741 -344.01858) (xy 102.038504 -344.035505)
			(xy 102.03815 -344.044524) (xy 102.03815 -344.112088) (xy 102.038502 -344.121106) (xy 102.044752 -344.138023)
			(xy 102.050342 -344.145108) (xy 102.05085 -344.145616) (xy 102.068579 -344.166566) (xy 102.098464 -344.212597)
			(xy 102.121432 -344.262441) (xy 102.137007 -344.315066) (xy 102.144868 -344.369381) (xy 102.145338 -344.396822)
			(xy 102.144852 -344.424073) (xy 102.137096 -344.478021) (xy 102.121741 -344.530316) (xy 102.099099 -344.579893)
			(xy 102.069633 -344.625743) (xy 102.033942 -344.666934) (xy 101.992751 -344.702625) (xy 101.946901 -344.732091)
			(xy 101.897324 -344.754733) (xy 101.845029 -344.770088) (xy 101.791081 -344.777844) (xy 101.736579 -344.777844)
			(xy 101.682631 -344.770088) (xy 101.630336 -344.754733) (xy 101.580759 -344.732091) (xy 101.534909 -344.702625)
			(xy 101.493718 -344.666934) (xy 101.458027 -344.625743) (xy 101.428561 -344.579893) (xy 101.405919 -344.530316)
			(xy 101.390564 -344.478021) (xy 101.382808 -344.424073) (xy 101.382322 -344.396822) (xy 79.89697 -344.396822)
			(xy 79.05623 -345.237562) (xy 88.93302 -345.237562) (xy 88.933443 -345.210309) (xy 88.941205 -345.156357)
			(xy 88.956566 -345.104059) (xy 88.979214 -345.05448) (xy 89.008687 -345.008629) (xy 89.044385 -344.967438)
			(xy 89.085582 -344.931747) (xy 89.131438 -344.902282) (xy 89.181021 -344.879643) (xy 89.233322 -344.864291)
			(xy 89.287274 -344.856538) (xy 89.314528 -344.856054) (xy 89.339987 -344.856488) (xy 89.390452 -344.863253)
			(xy 89.439569 -344.876671) (xy 89.486464 -344.896505) (xy 89.530304 -344.922402) (xy 89.570308 -344.953902)
			(xy 89.58834 -344.971878) (xy 89.595447 -344.978501) (xy 89.613201 -344.986344) (xy 89.622884 -344.987118)
			(xy 89.702894 -344.989912) (xy 89.721436 -344.983308) (xy 89.728802 -344.976704) (xy 89.749893 -344.958526)
			(xy 89.796364 -344.927857) (xy 89.8468 -344.904269) (xy 89.900128 -344.888262) (xy 89.955217 -344.880177)
			(xy 89.983056 -344.879676) (xy 90.010426 -344.880149) (xy 90.064606 -344.887963) (xy 90.117109 -344.903449)
			(xy 90.166857 -344.92629) (xy 90.212823 -344.956014) (xy 90.233754 -344.973656) (xy 90.234008 -344.97391)
			(xy 90.241087 -344.979507) (xy 90.25801 -344.985747) (xy 90.267028 -344.986102) (xy 90.334084 -344.986102)
			(xy 90.3431 -344.985737) (xy 90.360017 -344.979495) (xy 90.367104 -344.97391) (xy 90.367104 -344.973656)
			(xy 90.367358 -344.973656) (xy 90.388289 -344.956016) (xy 90.434263 -344.926306) (xy 90.484011 -344.90347)
			(xy 90.536511 -344.887979) (xy 90.590687 -344.88015) (xy 90.618056 -344.879676) (xy 90.646973 -344.880197)
			(xy 90.704145 -344.888922) (xy 90.759345 -344.906177) (xy 90.811308 -344.931568) (xy 90.858841 -344.964513)
			(xy 90.900857 -345.004256) (xy 90.919046 -345.026742) (xy 90.926636 -345.035567) (xy 90.94755 -345.045739)
			(xy 90.959178 -345.0463) (xy 91.038934 -345.0463) (xy 91.050566 -345.045766) (xy 91.071476 -345.035573)
			(xy 91.079066 -345.026742) (xy 91.097287 -345.004284) (xy 91.139299 -344.964545) (xy 91.186827 -344.931602)
			(xy 91.238783 -344.906209) (xy 91.293976 -344.888947) (xy 91.351142 -344.880213) (xy 91.380056 -344.879676)
			(xy 91.407426 -344.880149) (xy 91.461606 -344.887963) (xy 91.514109 -344.903449) (xy 91.563857 -344.92629)
			(xy 91.609823 -344.956014) (xy 91.630754 -344.973656) (xy 91.631008 -344.97391) (xy 91.638087 -344.979507)
			(xy 91.65501 -344.985747) (xy 91.664028 -344.986102) (xy 91.731084 -344.986102) (xy 91.7401 -344.985737)
			(xy 91.757017 -344.979495) (xy 91.764104 -344.97391) (xy 91.764104 -344.973656) (xy 91.764358 -344.973656)
			(xy 91.785291 -344.956015) (xy 91.831259 -344.926291) (xy 91.881005 -344.903445) (xy 91.933507 -344.887949)
			(xy 91.987685 -344.88012) (xy 92.042427 -344.88012) (xy 92.096605 -344.887949) (xy 92.149107 -344.903445)
			(xy 92.198853 -344.926291) (xy 92.244821 -344.956015) (xy 92.265754 -344.973656) (xy 92.266008 -344.97391)
			(xy 92.273087 -344.979507) (xy 92.29001 -344.985747) (xy 92.299028 -344.986102) (xy 92.366084 -344.986102)
			(xy 92.3751 -344.985737) (xy 92.392017 -344.979495) (xy 92.399104 -344.97391) (xy 92.399104 -344.973656)
			(xy 92.399358 -344.973656) (xy 92.420289 -344.956016) (xy 92.466263 -344.926306) (xy 92.516011 -344.90347)
			(xy 92.568511 -344.887979) (xy 92.622687 -344.88015) (xy 92.650056 -344.879676) (xy 92.677307 -344.880196)
			(xy 92.731255 -344.887947) (xy 92.783551 -344.903296) (xy 92.83313 -344.925933) (xy 92.878982 -344.955395)
			(xy 92.920175 -344.991082) (xy 92.955869 -345.03227) (xy 92.985339 -345.078117) (xy 93.007983 -345.127693)
			(xy 93.02334 -345.179986) (xy 93.0311 -345.233933) (xy 93.031564 -345.261184) (xy 93.031019 -345.289629)
			(xy 93.022568 -345.345888) (xy 93.00585 -345.400266) (xy 92.981238 -345.451556) (xy 92.949277 -345.49862)
			(xy 92.910677 -345.540411) (xy 92.888816 -345.558618) (xy 92.880986 -345.565633) (xy 92.871273 -345.584249)
			(xy 92.87002 -345.594686) (xy 92.86494 -345.669362) (xy 92.864763 -345.679888) (xy 92.871843 -345.699691)
			(xy 92.878656 -345.707716) (xy 92.898109 -345.72907) (xy 92.930987 -345.776563) (xy 92.956328 -345.828471)
			(xy 92.973551 -345.883606) (xy 92.982263 -345.940709) (xy 92.982796 -345.96959) (xy 92.98234 -345.996725)
			(xy 92.974645 -346.050445) (xy 92.959409 -346.102532) (xy 92.936941 -346.151931) (xy 92.907694 -346.197645)
			(xy 92.89034 -346.21851) (xy 92.890086 -346.218764) (xy 92.884144 -346.226452) (xy 92.877994 -346.244864)
			(xy 92.878148 -346.254578) (xy 92.881958 -346.324936) (xy 92.882979 -346.334743) (xy 92.891491 -346.352511)
			(xy 92.898468 -346.35948) (xy 92.917459 -346.377615) (xy 92.950775 -346.418205) (xy 92.978215 -346.462976)
			(xy 92.999261 -346.511085) (xy 93.013517 -346.561624) (xy 93.020713 -346.61364) (xy 93.02115 -346.639896)
			(xy 93.020619 -346.667145) (xy 93.012864 -346.721089) (xy 92.997511 -346.77338) (xy 92.974874 -346.822955)
			(xy 92.945412 -346.868803) (xy 92.909725 -346.909992) (xy 92.86854 -346.945684) (xy 92.822695 -346.975152)
			(xy 92.773124 -346.997795) (xy 92.720834 -347.013154) (xy 92.666891 -347.020915) (xy 92.639642 -347.021404)
			(xy 92.612273 -347.020912) (xy 92.558095 -347.013101) (xy 92.505592 -346.997617) (xy 92.455845 -346.974781)
			(xy 92.409877 -346.945063) (xy 92.388944 -346.927424) (xy 92.38869 -346.92717) (xy 92.381613 -346.92157)
			(xy 92.364689 -346.915332) (xy 92.35567 -346.914978) (xy 92.288614 -346.914978) (xy 92.279598 -346.915347)
			(xy 92.262682 -346.921587) (xy 92.255594 -346.92717) (xy 92.255594 -346.927424) (xy 92.25534 -346.927424)
			(xy 92.234407 -346.945062) (xy 92.188434 -346.974773) (xy 92.138687 -346.997609) (xy 92.086186 -347.0131)
			(xy 92.032011 -347.020929) (xy 92.004642 -347.021404) (xy 91.978327 -347.020974) (xy 91.926197 -347.013731)
			(xy 91.875553 -346.999405) (xy 91.827355 -346.978265) (xy 91.782512 -346.950713) (xy 91.741874 -346.917268)
			(xy 91.723718 -346.898214) (xy 91.71619 -346.89082) (xy 91.696915 -346.882291) (xy 91.68638 -346.881704)
			(xy 91.611704 -346.881704) (xy 91.601153 -346.882221) (xy 91.581858 -346.890765) (xy 91.574366 -346.898214)
			(xy 91.556223 -346.917282) (xy 91.51559 -346.950737) (xy 91.470747 -346.978294) (xy 91.422544 -346.999431)
			(xy 91.371894 -347.013745) (xy 91.319759 -347.020967) (xy 91.293442 -347.021404) (xy 91.266073 -347.020912)
			(xy 91.211895 -347.013101) (xy 91.159392 -346.997617) (xy 91.109645 -346.974781) (xy 91.063677 -346.945063)
			(xy 91.042744 -346.927424) (xy 91.04249 -346.92717) (xy 91.035413 -346.92157) (xy 91.018489 -346.915332)
			(xy 91.00947 -346.914978) (xy 90.942414 -346.914978) (xy 90.933398 -346.915347) (xy 90.916482 -346.921587)
			(xy 90.909394 -346.92717) (xy 90.909394 -346.927424) (xy 90.90914 -346.927424) (xy 90.888207 -346.945065)
			(xy 90.842239 -346.974789) (xy 90.792493 -346.997635) (xy 90.739991 -347.013131) (xy 90.685813 -347.02096)
			(xy 90.631071 -347.02096) (xy 90.576893 -347.013131) (xy 90.524391 -346.997635) (xy 90.474645 -346.974789)
			(xy 90.428677 -346.945065) (xy 90.407744 -346.927424) (xy 90.40749 -346.92717) (xy 90.400413 -346.92157)
			(xy 90.383489 -346.915332) (xy 90.37447 -346.914978) (xy 90.307414 -346.914978) (xy 90.298398 -346.915347)
			(xy 90.281482 -346.921587) (xy 90.274394 -346.92717) (xy 90.274394 -346.927424) (xy 90.27414 -346.927424)
			(xy 90.253207 -346.945065) (xy 90.207239 -346.974789) (xy 90.157493 -346.997635) (xy 90.104991 -347.013131)
			(xy 90.050813 -347.02096) (xy 89.996071 -347.02096) (xy 89.941893 -347.013131) (xy 89.889391 -346.997635)
			(xy 89.839645 -346.974789) (xy 89.793677 -346.945065) (xy 89.772744 -346.927424) (xy 89.77249 -346.92717)
			(xy 89.765413 -346.92157) (xy 89.748489 -346.915332) (xy 89.73947 -346.914978) (xy 89.672414 -346.914978)
			(xy 89.663398 -346.915347) (xy 89.646482 -346.921587) (xy 89.639394 -346.92717) (xy 89.639394 -346.927424)
			(xy 89.63914 -346.927424) (xy 89.618207 -346.945062) (xy 89.572234 -346.974773) (xy 89.522487 -346.997609)
			(xy 89.469986 -347.0131) (xy 89.415811 -347.020929) (xy 89.388442 -347.021404) (xy 89.36119 -347.020906)
			(xy 89.30724 -347.013154) (xy 89.254943 -346.997803) (xy 89.205362 -346.975165) (xy 89.159509 -346.945701)
			(xy 89.118316 -346.910011) (xy 89.082621 -346.868822) (xy 89.053153 -346.822971) (xy 89.03051 -346.773393)
			(xy 89.015154 -346.721097) (xy 89.007397 -346.667148) (xy 89.006934 -346.639896) (xy 89.007433 -346.612763)
			(xy 89.015116 -346.559044) (xy 89.030342 -346.506957) (xy 89.0528 -346.457557) (xy 89.082039 -346.411842)
			(xy 89.09939 -346.390976) (xy 89.099644 -346.390722) (xy 89.105596 -346.383041) (xy 89.111739 -346.364624)
			(xy 89.111582 -346.354908) (xy 89.107772 -346.28455) (xy 89.1067 -346.274752) (xy 89.098224 -346.256981)
			(xy 89.091262 -346.250006) (xy 89.07227 -346.231872) (xy 89.038953 -346.191283) (xy 89.011512 -346.146511)
			(xy 88.990466 -346.098402) (xy 88.976211 -346.047862) (xy 88.969016 -345.995846) (xy 88.96858 -345.96959)
			(xy 88.968982 -345.943757) (xy 88.975961 -345.892564) (xy 88.989789 -345.842783) (xy 89.010214 -345.795326)
			(xy 89.036861 -345.751062) (xy 89.069241 -345.710801) (xy 89.087706 -345.69273) (xy 89.08796 -345.692476)
			(xy 89.095447 -345.684537) (xy 89.103483 -345.664272) (xy 89.103454 -345.65336) (xy 89.099644 -345.576144)
			(xy 89.098606 -345.565329) (xy 89.088744 -345.545991) (xy 89.080594 -345.538806) (xy 89.080086 -345.538552)
			(xy 89.057625 -345.520335) (xy 89.017889 -345.47832) (xy 88.984947 -345.430791) (xy 88.959555 -345.378835)
			(xy 88.942294 -345.323642) (xy 88.933559 -345.266476) (xy 88.93302 -345.237562) (xy 79.05623 -345.237562)
			(xy 75.394312 -348.89948) (xy 81.802478 -348.89948) (xy 81.802982 -348.871033) (xy 81.81144 -348.814772)
			(xy 81.828164 -348.760392) (xy 81.852784 -348.709102) (xy 81.884753 -348.66204) (xy 81.923361 -348.620251)
			(xy 81.945226 -348.602046) (xy 81.953061 -348.595036) (xy 81.962773 -348.576416) (xy 81.964022 -348.565978)
			(xy 81.969102 -348.491302) (xy 81.969289 -348.480776) (xy 81.962201 -348.460973) (xy 81.955386 -348.452948)
			(xy 81.93597 -348.431562) (xy 81.903085 -348.384078) (xy 81.877737 -348.332179) (xy 81.860505 -348.27705)
			(xy 81.851784 -348.219953) (xy 81.851246 -348.191074) (xy 81.851732 -348.163823) (xy 81.859488 -348.109875)
			(xy 81.874843 -348.05758) (xy 81.897485 -348.008003) (xy 81.926951 -347.962153) (xy 81.962642 -347.920962)
			(xy 82.003833 -347.885271) (xy 82.049683 -347.855805) (xy 82.09926 -347.833163) (xy 82.151555 -347.817808)
			(xy 82.205503 -347.810052) (xy 82.260005 -347.810052) (xy 82.313953 -347.817808) (xy 82.366248 -347.833163)
			(xy 82.415825 -347.855805) (xy 82.461675 -347.885271) (xy 82.502866 -347.920962) (xy 82.538557 -347.962153)
			(xy 82.568023 -348.008003) (xy 82.590665 -348.05758) (xy 82.60602 -348.109875) (xy 82.613776 -348.163823)
			(xy 82.614262 -348.191074) (xy 82.613711 -348.219519) (xy 82.605261 -348.275777) (xy 82.588544 -348.330155)
			(xy 82.563933 -348.381446) (xy 82.531973 -348.428509) (xy 82.493375 -348.470301) (xy 82.471514 -348.488508)
			(xy 82.463647 -348.495487) (xy 82.453955 -348.51413) (xy 82.452718 -348.524576) (xy 82.447638 -348.599252)
			(xy 82.447467 -348.609778) (xy 82.454543 -348.62958) (xy 82.461354 -348.637606) (xy 82.480802 -348.658964)
			(xy 82.513681 -348.706456) (xy 82.539022 -348.758363) (xy 82.556247 -348.813497) (xy 82.563515 -348.861126)
			(xy 84.464144 -348.861126) (xy 84.464693 -348.832681) (xy 84.473143 -348.776422) (xy 84.48986 -348.722044)
			(xy 84.514471 -348.670754) (xy 84.546432 -348.62369) (xy 84.585031 -348.581899) (xy 84.606892 -348.563692)
			(xy 84.61476 -348.556714) (xy 84.624452 -348.53807) (xy 84.625688 -348.527624) (xy 84.630768 -348.452948)
			(xy 84.630938 -348.442422) (xy 84.623863 -348.42262) (xy 84.617052 -348.414594) (xy 84.597605 -348.393235)
			(xy 84.564726 -348.345743) (xy 84.539384 -348.293837) (xy 84.522159 -348.238702) (xy 84.513446 -348.181601)
			(xy 84.512912 -348.15272) (xy 84.513398 -348.125469) (xy 84.521154 -348.071521) (xy 84.536509 -348.019226)
			(xy 84.559151 -347.969649) (xy 84.588617 -347.923799) (xy 84.624308 -347.882608) (xy 84.665499 -347.846917)
			(xy 84.711349 -347.817451) (xy 84.760926 -347.794809) (xy 84.813221 -347.779454) (xy 84.867169 -347.771698)
			(xy 84.921671 -347.771698) (xy 84.975619 -347.779454) (xy 85.027914 -347.794809) (xy 85.077491 -347.817451)
			(xy 85.123341 -347.846917) (xy 85.164532 -347.882608) (xy 85.200223 -347.923799) (xy 85.229689 -347.969649)
			(xy 85.252331 -348.019226) (xy 85.267686 -348.071521) (xy 85.275442 -348.125469) (xy 85.275928 -348.15272)
			(xy 85.275422 -348.181167) (xy 85.266964 -348.237428) (xy 85.25024 -348.291807) (xy 85.22562 -348.343098)
			(xy 85.193652 -348.39016) (xy 85.155045 -348.431949) (xy 85.13318 -348.450154) (xy 85.125346 -348.457165)
			(xy 85.115633 -348.475784) (xy 85.114384 -348.486222) (xy 85.109304 -348.560898) (xy 85.109116 -348.571424)
			(xy 85.116205 -348.591227) (xy 85.12302 -348.599252) (xy 85.142437 -348.620638) (xy 85.175321 -348.668121)
			(xy 85.200669 -348.720021) (xy 85.217901 -348.77515) (xy 85.226622 -348.832247) (xy 85.22716 -348.861126)
			(xy 85.226675 -348.88826) (xy 85.218989 -348.94198) (xy 85.20376 -348.994066) (xy 85.181298 -349.043466)
			(xy 85.152056 -349.089181) (xy 85.134704 -349.110046) (xy 85.13445 -349.1103) (xy 85.128487 -349.117974)
			(xy 85.122351 -349.136397) (xy 85.122512 -349.146114) (xy 85.126322 -349.216472) (xy 85.127385 -349.226271)
			(xy 85.135868 -349.244041) (xy 85.142832 -349.251016) (xy 85.161804 -349.26917) (xy 85.19512 -349.309756)
			(xy 85.222561 -349.354524) (xy 85.24361 -349.40263) (xy 85.257871 -349.453165) (xy 85.265073 -349.505178)
			(xy 85.265514 -349.531432) (xy 85.265084 -349.557607) (xy 85.257906 -349.609464) (xy 85.243704 -349.659852)
			(xy 85.222744 -349.707825) (xy 85.195421 -349.75248) (xy 85.162246 -349.792978) (xy 85.14334 -349.811086)
			(xy 85.135996 -349.818627) (xy 85.127606 -349.83791) (xy 85.127084 -349.848424) (xy 85.127084 -349.922846)
			(xy 85.127591 -349.933366) (xy 85.135975 -349.952657) (xy 85.14334 -349.960184) (xy 85.162244 -349.978296)
			(xy 85.195432 -350.018785) (xy 85.222764 -350.063437) (xy 85.243724 -350.11141) (xy 85.25792 -350.161801)
			(xy 85.265082 -350.213662) (xy 85.265514 -350.239838) (xy 85.265028 -350.267089) (xy 85.257272 -350.321037)
			(xy 85.241917 -350.373332) (xy 85.219275 -350.422909) (xy 85.189809 -350.468759) (xy 85.154118 -350.50995)
			(xy 85.112927 -350.545641) (xy 85.067077 -350.575107) (xy 85.0175 -350.597749) (xy 84.965205 -350.613104)
			(xy 84.911257 -350.62086) (xy 84.856755 -350.62086) (xy 84.802807 -350.613104) (xy 84.750512 -350.597749)
			(xy 84.700935 -350.575107) (xy 84.655085 -350.545641) (xy 84.613894 -350.50995) (xy 84.578203 -350.468759)
			(xy 84.548737 -350.422909) (xy 84.526095 -350.373332) (xy 84.51074 -350.321037) (xy 84.502984 -350.267089)
			(xy 84.502498 -350.239838) (xy 84.502904 -350.213662) (xy 84.510086 -350.161804) (xy 84.524293 -350.111415)
			(xy 84.545257 -350.063443) (xy 84.572585 -350.018788) (xy 84.605763 -349.978291) (xy 84.624672 -349.960184)
			(xy 84.632031 -349.952655) (xy 84.640412 -349.933363) (xy 84.640928 -349.922846) (xy 84.640928 -349.848424)
			(xy 84.640462 -349.837899) (xy 84.632052 -349.818606) (xy 84.624672 -349.811086) (xy 84.605736 -349.793006)
			(xy 84.572555 -349.752508) (xy 84.545229 -349.707849) (xy 84.524274 -349.65987) (xy 84.510085 -349.609474)
			(xy 84.502927 -349.55761) (xy 84.502498 -349.531432) (xy 84.502968 -349.504298) (xy 84.51066 -349.450578)
			(xy 84.525892 -349.398491) (xy 84.548357 -349.349092) (xy 84.577601 -349.303377) (xy 84.594954 -349.282512)
			(xy 84.595208 -349.282258) (xy 84.60114 -349.274563) (xy 84.607296 -349.256157) (xy 84.607146 -349.246444)
			(xy 84.603336 -349.176086) (xy 84.602306 -349.166281) (xy 84.593801 -349.148512) (xy 84.586826 -349.141542)
			(xy 84.567845 -349.123397) (xy 84.534528 -349.08281) (xy 84.507087 -349.03804) (xy 84.486039 -348.989933)
			(xy 84.471781 -348.939396) (xy 84.464582 -348.887381) (xy 84.464144 -348.861126) (xy 82.563515 -348.861126)
			(xy 82.56496 -348.870599) (xy 82.565494 -348.89948) (xy 82.565032 -348.926614) (xy 82.557339 -348.980335)
			(xy 82.542105 -349.032421) (xy 82.519638 -349.081821) (xy 82.490392 -349.127535) (xy 82.473038 -349.1484)
			(xy 82.472784 -349.148654) (xy 82.466846 -349.156345) (xy 82.460694 -349.174754) (xy 82.460846 -349.184468)
			(xy 82.464656 -349.254826) (xy 82.465682 -349.264632) (xy 82.47419 -349.282401) (xy 82.481166 -349.28937)
			(xy 82.500152 -349.307511) (xy 82.533468 -349.348099) (xy 82.560909 -349.392869) (xy 82.581956 -349.440977)
			(xy 82.596213 -349.491515) (xy 82.60341 -349.543531) (xy 82.603848 -349.569786) (xy 82.603378 -349.597599)
			(xy 82.595301 -349.652636) (xy 82.579317 -349.705916) (xy 82.555764 -349.756309) (xy 82.525142 -349.802748)
			(xy 82.4881 -349.844246) (xy 82.445423 -349.879925) (xy 82.421984 -349.894906) (xy 82.410554 -349.901764)
			(xy 82.397854 -349.924624) (xy 82.3976 -350.0247) (xy 82.397893 -350.033379) (xy 82.403646 -350.049756)
			(xy 82.414528 -350.063278) (xy 82.42173 -350.068134) (xy 82.421984 -350.068134) (xy 82.445372 -350.083138)
			(xy 82.487977 -350.118807) (xy 82.524956 -350.16028) (xy 82.555528 -350.206678) (xy 82.579045 -350.257021)
			(xy 82.59501 -350.310243) (xy 82.603085 -350.365218) (xy 82.603594 -350.393) (xy 82.603108 -350.420251)
			(xy 82.595352 -350.474199) (xy 82.579997 -350.526494) (xy 82.557355 -350.576071) (xy 82.527889 -350.621921)
			(xy 82.492198 -350.663112) (xy 82.451007 -350.698803) (xy 82.405157 -350.728269) (xy 82.35558 -350.750911)
			(xy 82.303285 -350.766266) (xy 82.249337 -350.774022) (xy 82.194835 -350.774022) (xy 82.140887 -350.766266)
			(xy 82.088592 -350.750911) (xy 82.039015 -350.728269) (xy 81.993165 -350.698803) (xy 81.951974 -350.663112)
			(xy 81.916283 -350.621921) (xy 81.886817 -350.576071) (xy 81.864175 -350.526494) (xy 81.84882 -350.474199)
			(xy 81.841064 -350.420251) (xy 81.840578 -350.393) (xy 81.841025 -350.365186) (xy 81.849104 -350.310148)
			(xy 81.865092 -350.256867) (xy 81.888648 -350.206473) (xy 81.919274 -350.160034) (xy 81.95632 -350.118537)
			(xy 81.999001 -350.082859) (xy 82.022442 -350.06788) (xy 82.033872 -350.061022) (xy 82.046572 -350.038162)
			(xy 82.046826 -349.938086) (xy 82.046531 -349.929407) (xy 82.040776 -349.913032) (xy 82.029896 -349.899509)
			(xy 82.022696 -349.894652) (xy 82.022442 -349.894652) (xy 81.999053 -349.879648) (xy 81.956447 -349.84398)
			(xy 81.919467 -349.802508) (xy 81.888895 -349.756109) (xy 81.865378 -349.705766) (xy 81.849414 -349.652544)
			(xy 81.84134 -349.597568) (xy 81.840832 -349.569786) (xy 81.841326 -349.542653) (xy 81.84901 -349.488933)
			(xy 81.864237 -349.436847) (xy 81.886697 -349.387447) (xy 81.915937 -349.341731) (xy 81.933288 -349.320866)
			(xy 81.933542 -349.320612) (xy 81.939499 -349.312934) (xy 81.945639 -349.294515) (xy 81.94548 -349.284798)
			(xy 81.94167 -349.21444) (xy 81.940604 -349.204641) (xy 81.932123 -349.186871) (xy 81.92516 -349.179896)
			(xy 81.906163 -349.161767) (xy 81.872846 -349.121177) (xy 81.845406 -349.076404) (xy 81.824361 -349.028294)
			(xy 81.810107 -348.977753) (xy 81.802913 -348.925736) (xy 81.802478 -348.89948) (xy 75.394312 -348.89948)
			(xy 72.655938 -351.637854) (xy 74.429874 -351.637854) (xy 74.430361 -351.609407) (xy 74.438823 -351.553145)
			(xy 74.455551 -351.498765) (xy 74.480174 -351.447474) (xy 74.512146 -351.400413) (xy 74.550756 -351.358624)
			(xy 74.572622 -351.34042) (xy 74.580467 -351.333419) (xy 74.590174 -351.314793) (xy 74.591418 -351.304352)
			(xy 74.596498 -351.229676) (xy 74.596645 -351.219152) (xy 74.589585 -351.199351) (xy 74.582782 -351.191322)
			(xy 74.563353 -351.169947) (xy 74.53047 -351.12246) (xy 74.505125 -351.070558) (xy 74.487896 -351.015427)
			(xy 74.479178 -350.958328) (xy 74.478642 -350.929448) (xy 74.479128 -350.902197) (xy 74.486884 -350.848249)
			(xy 74.502239 -350.795954) (xy 74.524881 -350.746377) (xy 74.554347 -350.700527) (xy 74.590038 -350.659336)
			(xy 74.631229 -350.623645) (xy 74.677079 -350.594179) (xy 74.726656 -350.571537) (xy 74.778951 -350.556182)
			(xy 74.832899 -350.548426) (xy 74.887401 -350.548426) (xy 74.941349 -350.556182) (xy 74.993644 -350.571537)
			(xy 75.043221 -350.594179) (xy 75.089071 -350.623645) (xy 75.130262 -350.659336) (xy 75.165953 -350.700527)
			(xy 75.195419 -350.746377) (xy 75.218061 -350.795954) (xy 75.233416 -350.848249) (xy 75.241172 -350.902197)
			(xy 75.241658 -350.929448) (xy 75.24116 -350.957895) (xy 75.232699 -351.014156) (xy 75.215973 -351.068535)
			(xy 75.191351 -351.119825) (xy 75.159382 -351.166887) (xy 75.120775 -351.208677) (xy 75.09891 -351.226882)
			(xy 75.091053 -351.233871) (xy 75.081355 -351.252507) (xy 75.080114 -351.26295) (xy 75.075034 -351.337626)
			(xy 75.074878 -351.348151) (xy 75.081943 -351.367953) (xy 75.08875 -351.37598) (xy 75.108185 -351.39735)
			(xy 75.141066 -351.444838) (xy 75.16641 -351.496742) (xy 75.183637 -351.551874) (xy 75.190908 -351.5995)
			(xy 77.09154 -351.5995) (xy 77.092072 -351.571055) (xy 77.100526 -351.514795) (xy 77.117246 -351.460417)
			(xy 77.141861 -351.409126) (xy 77.173824 -351.362063) (xy 77.212426 -351.320272) (xy 77.234288 -351.302066)
			(xy 77.242125 -351.295058) (xy 77.251835 -351.276436) (xy 77.253084 -351.265998) (xy 77.258164 -351.191322)
			(xy 77.25835 -351.180796) (xy 77.251264 -351.160992) (xy 77.244448 -351.152968) (xy 77.224988 -351.13162)
			(xy 77.192111 -351.084126) (xy 77.166771 -351.032216) (xy 77.14955 -350.977079) (xy 77.14084 -350.919976)
			(xy 77.140308 -350.891094) (xy 77.140794 -350.863843) (xy 77.14855 -350.809895) (xy 77.163905 -350.7576)
			(xy 77.186547 -350.708023) (xy 77.216013 -350.662173) (xy 77.251704 -350.620982) (xy 77.292895 -350.585291)
			(xy 77.338745 -350.555825) (xy 77.388322 -350.533183) (xy 77.440617 -350.517828) (xy 77.494565 -350.510072)
			(xy 77.549067 -350.510072) (xy 77.603015 -350.517828) (xy 77.65531 -350.533183) (xy 77.704887 -350.555825)
			(xy 77.750737 -350.585291) (xy 77.791928 -350.620982) (xy 77.827619 -350.662173) (xy 77.857085 -350.708023)
			(xy 77.879727 -350.7576) (xy 77.895082 -350.809895) (xy 77.902838 -350.863843) (xy 77.903324 -350.891094)
			(xy 77.902801 -350.91954) (xy 77.894347 -350.9758) (xy 77.877626 -351.03018) (xy 77.85301 -351.08147)
			(xy 77.821044 -351.128533) (xy 77.78244 -351.170323) (xy 77.760576 -351.188528) (xy 77.752752 -351.195549)
			(xy 77.743033 -351.21416) (xy 77.74178 -351.224596) (xy 77.7367 -351.299272) (xy 77.736527 -351.309797)
			(xy 77.743605 -351.3296) (xy 77.750416 -351.337626) (xy 77.769867 -351.358982) (xy 77.802747 -351.406473)
			(xy 77.828089 -351.458381) (xy 77.845312 -351.513516) (xy 77.854023 -351.570619) (xy 77.854556 -351.5995)
			(xy 77.854057 -351.626633) (xy 77.846374 -351.680352) (xy 77.831149 -351.732439) (xy 77.80869 -351.781839)
			(xy 77.779451 -351.827555) (xy 77.7621 -351.84842) (xy 77.761846 -351.848674) (xy 77.755895 -351.856356)
			(xy 77.749752 -351.874772) (xy 77.749908 -351.884488) (xy 77.753718 -351.954846) (xy 77.754795 -351.964643)
			(xy 77.763268 -351.982414) (xy 77.770228 -351.98939) (xy 77.789235 -352.007508) (xy 77.822548 -352.048103)
			(xy 77.849984 -352.092878) (xy 77.871028 -352.14099) (xy 77.88528 -352.191532) (xy 77.892474 -352.24355)
			(xy 77.89291 -352.269806) (xy 77.892464 -352.295981) (xy 77.88529 -352.347837) (xy 77.871091 -352.398225)
			(xy 77.850134 -352.446197) (xy 77.822813 -352.490853) (xy 77.789641 -352.531352) (xy 77.770736 -352.54946)
			(xy 77.763403 -352.55701) (xy 77.755007 -352.576286) (xy 77.75448 -352.586798) (xy 77.75448 -352.66122)
			(xy 77.754974 -352.671742) (xy 77.763364 -352.691035) (xy 77.770736 -352.698558) (xy 77.789627 -352.716683)
			(xy 77.822816 -352.757169) (xy 77.850149 -352.801818) (xy 77.871113 -352.849789) (xy 77.885311 -352.900178)
			(xy 77.892477 -352.952036) (xy 77.89291 -352.978212) (xy 77.892424 -353.005463) (xy 77.884668 -353.059411)
			(xy 77.869313 -353.111706) (xy 77.846671 -353.161283) (xy 77.817205 -353.207133) (xy 77.781514 -353.248324)
			(xy 77.740323 -353.284015) (xy 77.694473 -353.313481) (xy 77.644896 -353.336123) (xy 77.592601 -353.351478)
			(xy 77.538653 -353.359234) (xy 77.484151 -353.359234) (xy 77.430203 -353.351478) (xy 77.377908 -353.336123)
			(xy 77.328331 -353.313481) (xy 77.282481 -353.284015) (xy 77.24129 -353.248324) (xy 77.205599 -353.207133)
			(xy 77.176133 -353.161283) (xy 77.153491 -353.111706) (xy 77.138136 -353.059411) (xy 77.13038 -353.005463)
			(xy 77.129894 -352.978212) (xy 77.130351 -352.952037) (xy 77.137522 -352.900182) (xy 77.151719 -352.849794)
			(xy 77.172674 -352.801822) (xy 77.199993 -352.757166) (xy 77.233163 -352.716666) (xy 77.252068 -352.698558)
			(xy 77.259393 -352.691002) (xy 77.267794 -352.67173) (xy 77.268324 -352.66122) (xy 77.268324 -352.586798)
			(xy 77.267873 -352.576271) (xy 77.259452 -352.556979) (xy 77.252068 -352.54946) (xy 77.233187 -352.531325)
			(xy 77.199997 -352.490841) (xy 77.172662 -352.446194) (xy 77.151697 -352.398226) (xy 77.137497 -352.347838)
			(xy 77.130328 -352.295981) (xy 77.129894 -352.269806) (xy 77.130385 -352.242672) (xy 77.138068 -352.188952)
			(xy 77.153294 -352.136865) (xy 77.175756 -352.087465) (xy 77.204998 -352.041751) (xy 77.22235 -352.020886)
			(xy 77.222604 -352.020632) (xy 77.228547 -352.012944) (xy 77.234697 -351.994533) (xy 77.234542 -351.984818)
			(xy 77.230732 -351.91446) (xy 77.229667 -351.904661) (xy 77.221186 -351.88689) (xy 77.214222 -351.879916)
			(xy 77.195227 -351.861784) (xy 77.161912 -351.821194) (xy 77.134473 -351.776422) (xy 77.113427 -351.728312)
			(xy 77.099172 -351.677772) (xy 77.091977 -351.625756) (xy 77.09154 -351.5995) (xy 75.190908 -351.5995)
			(xy 75.192354 -351.608974) (xy 75.19289 -351.637854) (xy 75.192414 -351.664988) (xy 75.184724 -351.718708)
			(xy 75.169494 -351.770794) (xy 75.14703 -351.820194) (xy 75.117787 -351.865909) (xy 75.100434 -351.886774)
			(xy 75.10018 -351.887028) (xy 75.094208 -351.894696) (xy 75.088076 -351.913123) (xy 75.088242 -351.922842)
			(xy 75.092052 -351.9932) (xy 75.093093 -352.003003) (xy 75.101591 -352.020773) (xy 75.108562 -352.027744)
			(xy 75.127534 -352.045898) (xy 75.160852 -352.086483) (xy 75.188295 -352.131251) (xy 75.209345 -352.179356)
			(xy 75.223604 -352.229892) (xy 75.230805 -352.281905) (xy 75.231244 -352.30816) (xy 75.230756 -352.335972)
			(xy 75.222682 -352.391008) (xy 75.206701 -352.444288) (xy 75.183151 -352.494681) (xy 75.152532 -352.54112)
			(xy 75.115492 -352.582619) (xy 75.072818 -352.618299) (xy 75.04938 -352.63328) (xy 75.03795 -352.640138)
			(xy 75.02525 -352.662998) (xy 75.024996 -352.763074) (xy 75.025309 -352.771752) (xy 75.031054 -352.788127)
			(xy 75.041928 -352.801651) (xy 75.049126 -352.806508) (xy 75.04938 -352.806508) (xy 75.072801 -352.821464)
			(xy 75.115406 -352.857141) (xy 75.152383 -352.898621) (xy 75.182951 -352.945028) (xy 75.206463 -352.995379)
			(xy 75.22242 -353.048608) (xy 75.230486 -353.103589) (xy 75.23099 -353.131374) (xy 75.230504 -353.158625)
			(xy 75.222748 -353.212573) (xy 75.207393 -353.264868) (xy 75.184751 -353.314445) (xy 75.155285 -353.360295)
			(xy 75.119594 -353.401486) (xy 75.078403 -353.437177) (xy 75.032553 -353.466643) (xy 74.982976 -353.489285)
			(xy 74.930681 -353.50464) (xy 74.876733 -353.512396) (xy 74.822231 -353.512396) (xy 74.768283 -353.50464)
			(xy 74.715988 -353.489285) (xy 74.666411 -353.466643) (xy 74.620561 -353.437177) (xy 74.57937 -353.401486)
			(xy 74.543679 -353.360295) (xy 74.514213 -353.314445) (xy 74.491571 -353.264868) (xy 74.476216 -353.212573)
			(xy 74.46846 -353.158625) (xy 74.467974 -353.131374) (xy 74.46848 -353.103562) (xy 74.476549 -353.048527)
			(xy 74.492526 -352.995247) (xy 74.516073 -352.944853) (xy 74.54669 -352.898414) (xy 74.583728 -352.856915)
			(xy 74.6264 -352.821235) (xy 74.649838 -352.806254) (xy 74.661268 -352.799396) (xy 74.673968 -352.776536)
			(xy 74.674222 -352.67646) (xy 74.673877 -352.667785) (xy 74.668146 -352.651412) (xy 74.657284 -352.637886)
			(xy 74.650092 -352.633026) (xy 74.649838 -352.633026) (xy 74.626436 -352.618041) (xy 74.583831 -352.58237)
			(xy 74.546852 -352.540894) (xy 74.516281 -352.494492) (xy 74.492766 -352.444146) (xy 74.476805 -352.390921)
			(xy 74.468734 -352.335943) (xy 74.468228 -352.30816) (xy 74.468708 -352.281026) (xy 74.476396 -352.227306)
			(xy 74.491626 -352.17522) (xy 74.514089 -352.12582) (xy 74.543331 -352.080105) (xy 74.560684 -352.05924)
			(xy 74.560938 -352.058986) (xy 74.566906 -352.051316) (xy 74.57304 -352.03289) (xy 74.572876 -352.023172)
			(xy 74.569066 -351.952814) (xy 74.568013 -351.943013) (xy 74.559523 -351.925243) (xy 74.552556 -351.91827)
			(xy 74.533594 -351.900106) (xy 74.500274 -351.859523) (xy 74.47283 -351.814758) (xy 74.451778 -351.766655)
			(xy 74.437517 -351.71612) (xy 74.430314 -351.664108) (xy 74.429874 -351.637854) (xy 72.655938 -351.637854)
			(xy 69.921628 -354.372164) (xy 86.93785 -354.372164) (xy 86.938309 -354.346244) (xy 86.945343 -354.294883)
			(xy 86.959263 -354.244946) (xy 86.979813 -354.197352) (xy 87.006615 -354.152978) (xy 87.039176 -354.112639)
			(xy 87.057738 -354.094542) (xy 87.064596 -354.087938) (xy 87.072724 -354.07092) (xy 87.079074 -353.98329)
			(xy 87.073486 -353.965256) (xy 87.067644 -353.957636) (xy 87.052104 -353.937355) (xy 87.026046 -353.893404)
			(xy 87.006084 -353.84637) (xy 86.992574 -353.797094) (xy 86.985757 -353.746455) (xy 86.985348 -353.720908)
			(xy 86.985807 -353.693537) (xy 86.993625 -353.639358) (xy 87.009115 -353.586854) (xy 87.031958 -353.537107)
			(xy 87.061685 -353.491141) (xy 87.079328 -353.47021) (xy 87.079582 -353.469956) (xy 87.085149 -353.462856)
			(xy 87.091408 -353.44595) (xy 87.091774 -353.436936) (xy 87.091774 -353.36988) (xy 87.091432 -353.360861)
			(xy 87.085175 -353.343944) (xy 87.079582 -353.33686) (xy 87.079328 -353.33686) (xy 87.079328 -353.336606)
			(xy 87.061695 -353.315667) (xy 87.03197 -353.2697) (xy 87.009124 -353.219955) (xy 86.993627 -353.167454)
			(xy 86.985798 -353.113276) (xy 86.985797 -353.058536) (xy 86.993625 -353.004358) (xy 87.00912 -352.951856)
			(xy 87.031964 -352.90211) (xy 87.061688 -352.856143) (xy 87.079328 -352.83521) (xy 87.079582 -352.834956)
			(xy 87.085149 -352.827856) (xy 87.091408 -352.81095) (xy 87.091774 -352.801936) (xy 87.091774 -352.73488)
			(xy 87.091432 -352.725861) (xy 87.085175 -352.708944) (xy 87.079582 -352.70186) (xy 87.079328 -352.70186)
			(xy 87.079328 -352.701606) (xy 87.061695 -352.680667) (xy 87.03197 -352.6347) (xy 87.009124 -352.584955)
			(xy 86.993627 -352.532454) (xy 86.985798 -352.478276) (xy 86.985797 -352.423536) (xy 86.993625 -352.369358)
			(xy 87.00912 -352.316856) (xy 87.031964 -352.26711) (xy 87.061688 -352.221143) (xy 87.079328 -352.20021)
			(xy 87.079582 -352.199956) (xy 87.085149 -352.192856) (xy 87.091408 -352.17595) (xy 87.091774 -352.166936)
			(xy 87.091774 -352.09988) (xy 87.091432 -352.090861) (xy 87.085175 -352.073944) (xy 87.079582 -352.06686)
			(xy 87.079328 -352.06686) (xy 87.079328 -352.066606) (xy 87.061695 -352.045667) (xy 87.03197 -351.9997)
			(xy 87.009124 -351.949955) (xy 86.993627 -351.897454) (xy 86.985798 -351.843276) (xy 86.985797 -351.788536)
			(xy 86.993625 -351.734358) (xy 87.00912 -351.681856) (xy 87.031964 -351.63211) (xy 87.061688 -351.586143)
			(xy 87.079328 -351.56521) (xy 87.079582 -351.564956) (xy 87.085149 -351.557856) (xy 87.091408 -351.54095)
			(xy 87.091774 -351.531936) (xy 87.091774 -351.46488) (xy 87.091432 -351.455861) (xy 87.085175 -351.438944)
			(xy 87.079582 -351.43186) (xy 87.079328 -351.43186) (xy 87.079328 -351.431606) (xy 87.061695 -351.410667)
			(xy 87.03197 -351.3647) (xy 87.009124 -351.314955) (xy 86.993627 -351.262454) (xy 86.985798 -351.208276)
			(xy 86.985797 -351.153536) (xy 86.993625 -351.099358) (xy 87.00912 -351.046856) (xy 87.031964 -350.99711)
			(xy 87.061688 -350.951143) (xy 87.079328 -350.93021) (xy 87.079582 -350.929956) (xy 87.085149 -350.922856)
			(xy 87.091408 -350.90595) (xy 87.091774 -350.896936) (xy 87.091774 -350.82988) (xy 87.091432 -350.820861)
			(xy 87.085175 -350.803944) (xy 87.079582 -350.79686) (xy 87.079328 -350.79686) (xy 87.079328 -350.796606)
			(xy 87.061683 -350.775679) (xy 87.031971 -350.729705) (xy 87.009136 -350.679956) (xy 86.993646 -350.627455)
			(xy 86.98582 -350.573278) (xy 86.985348 -350.545908) (xy 86.985885 -350.518659) (xy 86.993639 -350.464715)
			(xy 87.008991 -350.412424) (xy 87.031628 -350.36285) (xy 87.06109 -350.317002) (xy 87.096776 -350.275812)
			(xy 87.13796 -350.240121) (xy 87.183804 -350.210653) (xy 87.233375 -350.188009) (xy 87.285664 -350.17265)
			(xy 87.339607 -350.164889) (xy 87.366856 -350.1644) (xy 87.394225 -350.164892) (xy 87.448403 -350.172703)
			(xy 87.500906 -350.188187) (xy 87.550653 -350.211022) (xy 87.596621 -350.240741) (xy 87.617554 -350.25838)
			(xy 87.617808 -350.258634) (xy 87.624885 -350.264234) (xy 87.641809 -350.270471) (xy 87.650828 -350.270826)
			(xy 87.717884 -350.270826) (xy 87.726899 -350.270456) (xy 87.743816 -350.264217) (xy 87.750904 -350.258634)
			(xy 87.750904 -350.25838) (xy 87.751158 -350.25838) (xy 87.772091 -350.240739) (xy 87.818059 -350.211015)
			(xy 87.867805 -350.188169) (xy 87.920307 -350.172673) (xy 87.974485 -350.164844) (xy 88.029227 -350.164844)
			(xy 88.083405 -350.172673) (xy 88.135907 -350.188169) (xy 88.185653 -350.211015) (xy 88.231621 -350.240739)
			(xy 88.252554 -350.25838) (xy 88.252808 -350.258634) (xy 88.259885 -350.264234) (xy 88.276809 -350.270471)
			(xy 88.285828 -350.270826) (xy 88.352884 -350.270826) (xy 88.361899 -350.270456) (xy 88.378816 -350.264217)
			(xy 88.385904 -350.258634) (xy 88.385904 -350.25838) (xy 88.386158 -350.25838) (xy 88.407091 -350.240739)
			(xy 88.453059 -350.211015) (xy 88.502805 -350.188169) (xy 88.555307 -350.172673) (xy 88.609485 -350.164844)
			(xy 88.664227 -350.164844) (xy 88.718405 -350.172673) (xy 88.770907 -350.188169) (xy 88.820653 -350.211015)
			(xy 88.866621 -350.240739) (xy 88.887554 -350.25838) (xy 88.887808 -350.258634) (xy 88.894885 -350.264234)
			(xy 88.911809 -350.270471) (xy 88.920828 -350.270826) (xy 88.987884 -350.270826) (xy 88.996899 -350.270456)
			(xy 89.013816 -350.264217) (xy 89.020904 -350.258634) (xy 89.020904 -350.25838) (xy 89.021158 -350.25838)
			(xy 89.042091 -350.240739) (xy 89.088059 -350.211015) (xy 89.137805 -350.188169) (xy 89.190307 -350.172673)
			(xy 89.244485 -350.164844) (xy 89.299227 -350.164844) (xy 89.353405 -350.172673) (xy 89.405907 -350.188169)
			(xy 89.455653 -350.211015) (xy 89.501621 -350.240739) (xy 89.522554 -350.25838) (xy 89.522808 -350.258634)
			(xy 89.529885 -350.264234) (xy 89.546809 -350.270471) (xy 89.555828 -350.270826) (xy 89.622884 -350.270826)
			(xy 89.631899 -350.270456) (xy 89.648816 -350.264217) (xy 89.655904 -350.258634) (xy 89.655904 -350.25838)
			(xy 89.656158 -350.25838) (xy 89.677091 -350.240739) (xy 89.723059 -350.211015) (xy 89.772805 -350.188169)
			(xy 89.825307 -350.172673) (xy 89.879485 -350.164844) (xy 89.934227 -350.164844) (xy 89.988405 -350.172673)
			(xy 90.040907 -350.188169) (xy 90.090653 -350.211015) (xy 90.136621 -350.240739) (xy 90.157554 -350.25838)
			(xy 90.157808 -350.258634) (xy 90.164885 -350.264234) (xy 90.181809 -350.270471) (xy 90.190828 -350.270826)
			(xy 90.257884 -350.270826) (xy 90.266899 -350.270456) (xy 90.283816 -350.264217) (xy 90.290904 -350.258634)
			(xy 90.290904 -350.25838) (xy 90.291158 -350.25838) (xy 90.312091 -350.240739) (xy 90.358059 -350.211015)
			(xy 90.407805 -350.188169) (xy 90.460307 -350.172673) (xy 90.514485 -350.164844) (xy 90.569227 -350.164844)
			(xy 90.623405 -350.172673) (xy 90.675907 -350.188169) (xy 90.725653 -350.211015) (xy 90.771621 -350.240739)
			(xy 90.792554 -350.25838) (xy 90.792808 -350.258634) (xy 90.799885 -350.264234) (xy 90.816809 -350.270471)
			(xy 90.825828 -350.270826) (xy 90.892884 -350.270826) (xy 90.901899 -350.270456) (xy 90.918816 -350.264217)
			(xy 90.925904 -350.258634) (xy 90.925904 -350.25838) (xy 90.926158 -350.25838) (xy 90.947091 -350.240739)
			(xy 90.993059 -350.211015) (xy 91.042805 -350.188169) (xy 91.095307 -350.172673) (xy 91.149485 -350.164844)
			(xy 91.204227 -350.164844) (xy 91.258405 -350.172673) (xy 91.310907 -350.188169) (xy 91.360653 -350.211015)
			(xy 91.406621 -350.240739) (xy 91.427554 -350.25838) (xy 91.427808 -350.258634) (xy 91.434885 -350.264234)
			(xy 91.451809 -350.270471) (xy 91.460828 -350.270826) (xy 91.527884 -350.270826) (xy 91.536899 -350.270456)
			(xy 91.553816 -350.264217) (xy 91.560904 -350.258634) (xy 91.560904 -350.25838) (xy 91.561158 -350.25838)
			(xy 91.582091 -350.240739) (xy 91.628059 -350.211015) (xy 91.677805 -350.188169) (xy 91.730307 -350.172673)
			(xy 91.784485 -350.164844) (xy 91.839227 -350.164844) (xy 91.893405 -350.172673) (xy 91.945907 -350.188169)
			(xy 91.995653 -350.211015) (xy 92.041621 -350.240739) (xy 92.062554 -350.25838) (xy 92.062808 -350.258634)
			(xy 92.069885 -350.264234) (xy 92.086809 -350.270471) (xy 92.095828 -350.270826) (xy 92.162884 -350.270826)
			(xy 92.171899 -350.270456) (xy 92.188816 -350.264217) (xy 92.195904 -350.258634) (xy 92.195904 -350.25838)
			(xy 92.196158 -350.25838) (xy 92.217091 -350.240739) (xy 92.263059 -350.211015) (xy 92.312805 -350.188169)
			(xy 92.365307 -350.172673) (xy 92.419485 -350.164844) (xy 92.474227 -350.164844) (xy 92.528405 -350.172673)
			(xy 92.580907 -350.188169) (xy 92.630653 -350.211015) (xy 92.676621 -350.240739) (xy 92.697554 -350.25838)
			(xy 92.697808 -350.258634) (xy 92.704885 -350.264234) (xy 92.721809 -350.270471) (xy 92.730828 -350.270826)
			(xy 92.797884 -350.270826) (xy 92.806899 -350.270456) (xy 92.823816 -350.264217) (xy 92.830904 -350.258634)
			(xy 92.830904 -350.25838) (xy 92.831158 -350.25838) (xy 92.852091 -350.240739) (xy 92.898059 -350.211015)
			(xy 92.947805 -350.188169) (xy 93.000307 -350.172673) (xy 93.054485 -350.164844) (xy 93.109227 -350.164844)
			(xy 93.163405 -350.172673) (xy 93.215907 -350.188169) (xy 93.265653 -350.211015) (xy 93.311621 -350.240739)
			(xy 93.332554 -350.25838) (xy 93.332808 -350.258634) (xy 93.339885 -350.264234) (xy 93.356809 -350.270471)
			(xy 93.365828 -350.270826) (xy 93.432884 -350.270826) (xy 93.441899 -350.270456) (xy 93.458816 -350.264217)
			(xy 93.465904 -350.258634) (xy 93.465904 -350.25838) (xy 93.466158 -350.25838) (xy 93.487093 -350.240744)
			(xy 93.533065 -350.211032) (xy 93.582812 -350.188196) (xy 93.635312 -350.172704) (xy 93.689487 -350.164875)
			(xy 93.716856 -350.1644) (xy 93.744108 -350.164896) (xy 93.798058 -350.172647) (xy 93.850356 -350.187998)
			(xy 93.899937 -350.210636) (xy 93.94579 -350.2401) (xy 93.986984 -350.275791) (xy 94.022678 -350.316981)
			(xy 94.052146 -350.362832) (xy 94.074789 -350.41241) (xy 94.090145 -350.464706) (xy 94.097901 -350.518656)
			(xy 94.098364 -350.545908) (xy 94.097911 -350.573279) (xy 94.090092 -350.627459) (xy 94.0746 -350.679962)
			(xy 94.051755 -350.729709) (xy 94.022027 -350.775675) (xy 94.004384 -350.796606) (xy 94.00413 -350.79686)
			(xy 93.998546 -350.803948) (xy 93.9923 -350.820864) (xy 93.991938 -350.82988) (xy 93.991938 -350.896936)
			(xy 93.99227 -350.905956) (xy 93.998534 -350.922873) (xy 94.00413 -350.929956) (xy 94.004384 -350.929956)
			(xy 94.004384 -350.93021) (xy 94.022032 -350.951137) (xy 94.051756 -350.997106) (xy 94.0746 -351.046853)
			(xy 94.090095 -351.099356) (xy 94.097923 -351.153535) (xy 94.097922 -351.208277) (xy 94.090093 -351.262456)
			(xy 94.074596 -351.314958) (xy 94.05175 -351.364705) (xy 94.022025 -351.410673) (xy 94.004384 -351.431606)
			(xy 94.00413 -351.43186) (xy 93.998546 -351.438948) (xy 93.9923 -351.455864) (xy 93.991938 -351.46488)
			(xy 93.991938 -351.531936) (xy 93.99227 -351.540956) (xy 93.998534 -351.557873) (xy 94.00413 -351.564956)
			(xy 94.004384 -351.564956) (xy 94.004384 -351.56521) (xy 94.022039 -351.58613) (xy 94.051749 -351.632106)
			(xy 94.074582 -351.681856) (xy 94.090069 -351.73436) (xy 94.097893 -351.788538) (xy 94.098364 -351.815908)
			(xy 94.097824 -351.844763) (xy 94.089138 -351.901815) (xy 94.07195 -351.956905) (xy 94.046654 -352.008775)
			(xy 94.013827 -352.056238) (xy 93.97422 -352.098211) (xy 93.951806 -352.11639) (xy 93.94467 -352.122532)
			(xy 93.935035 -352.138691) (xy 93.93301 -352.147886) (xy 93.92031 -352.22561) (xy 93.92412 -352.244152)
			(xy 93.9292 -352.252026) (xy 93.943856 -352.275367) (xy 93.966997 -352.325387) (xy 93.982711 -352.378213)
			(xy 93.990672 -352.432749) (xy 93.991176 -352.460306) (xy 93.990727 -352.486168) (xy 93.983745 -352.537418)
			(xy 93.969896 -352.587253) (xy 93.949435 -352.634758) (xy 93.922738 -352.679059) (xy 93.890296 -352.719343)
			(xy 93.871796 -352.73742) (xy 93.871542 -352.737674) (xy 93.864419 -352.745175) (xy 93.856286 -352.764172)
			(xy 93.855794 -352.774504) (xy 93.855794 -352.858832) (xy 93.864176 -352.878136) (xy 93.871796 -352.885248)
			(xy 93.890305 -352.903358) (xy 93.922813 -352.943663) (xy 93.949569 -352.987995) (xy 93.970082 -353.03554)
			(xy 93.983975 -353.085422) (xy 93.990991 -353.136726) (xy 93.99143 -353.162616) (xy 93.99099 -353.189987)
			(xy 93.983169 -353.244168) (xy 93.967674 -353.296672) (xy 93.944826 -353.346419) (xy 93.915095 -353.392384)
			(xy 93.89745 -353.413314) (xy 93.897196 -353.413568) (xy 93.891616 -353.420659) (xy 93.885366 -353.437572)
			(xy 93.885004 -353.446588) (xy 93.885004 -353.513644) (xy 93.885387 -353.522658) (xy 93.891617 -353.539575)
			(xy 93.897196 -353.546664) (xy 93.89745 -353.546664) (xy 93.89745 -353.546918) (xy 93.915056 -353.567877)
			(xy 93.944775 -353.613841) (xy 93.967618 -353.663582) (xy 93.983116 -353.716077) (xy 93.990952 -353.770249)
			(xy 93.99143 -353.797616) (xy 93.990974 -353.823944) (xy 93.983748 -353.876102) (xy 93.969409 -353.926768)
			(xy 93.948229 -353.974977) (xy 93.920612 -354.01981) (xy 93.887085 -354.060413) (xy 93.867986 -354.07854)
			(xy 93.861184 -354.085297) (xy 93.852836 -354.102543) (xy 93.85173 -354.112068) (xy 93.846904 -354.181664)
			(xy 93.846559 -354.191229) (xy 93.852162 -354.209511) (xy 93.857826 -354.217224) (xy 93.85808 -354.217478)
			(xy 93.874192 -354.237978) (xy 93.901292 -354.282522) (xy 93.922072 -354.330342) (xy 93.936146 -354.380546)
			(xy 93.943251 -354.4322) (xy 93.943678 -354.45827) (xy 93.943217 -354.485523) (xy 93.935463 -354.539476)
			(xy 93.920109 -354.591776) (xy 93.897468 -354.641358) (xy 93.868 -354.687213) (xy 93.832306 -354.728406)
			(xy 93.791113 -354.7641) (xy 93.745258 -354.793568) (xy 93.695676 -354.816209) (xy 93.643376 -354.831563)
			(xy 93.589423 -354.839317) (xy 93.56217 -354.839778) (xy 93.533989 -354.839267) (xy 93.478242 -354.830966)
			(xy 93.42432 -354.814563) (xy 93.373394 -354.790415) (xy 93.326569 -354.759046) (xy 93.305376 -354.740464)
			(xy 93.298518 -354.734114) (xy 93.280738 -354.727256) (xy 93.193108 -354.727256) (xy 93.175328 -354.734114)
			(xy 93.16847 -354.740464) (xy 93.147286 -354.759166) (xy 93.100394 -354.790697) (xy 93.049364 -354.814968)
			(xy 92.995313 -354.831449) (xy 92.939422 -354.839777) (xy 92.911168 -354.840286) (xy 92.883666 -354.839821)
			(xy 92.829232 -354.831924) (xy 92.776495 -354.816297) (xy 92.726546 -354.793264) (xy 92.68042 -354.763302)
			(xy 92.63907 -354.727031) (xy 92.620846 -354.706428) (xy 92.613662 -354.698707) (xy 92.594769 -354.68939)
			(xy 92.58427 -354.688394) (xy 92.510102 -354.6856) (xy 92.499539 -354.685655) (xy 92.479859 -354.69327)
			(xy 92.472002 -354.700332) (xy 92.450393 -354.720963) (xy 92.401994 -354.755981) (xy 92.348726 -354.783024)
			(xy 92.291893 -354.80143) (xy 92.232886 -354.810748) (xy 92.203016 -354.81133) (xy 92.202762 -354.81133)
			(xy 92.1747 -354.810835) (xy 92.119184 -354.802595) (xy 92.065474 -354.786314) (xy 92.014727 -354.762341)
			(xy 91.968039 -354.731195) (xy 91.926415 -354.693547) (xy 91.890754 -354.650209) (xy 91.875864 -354.626418)
			(xy 91.868918 -354.616097) (xy 91.847599 -354.603323) (xy 91.835224 -354.602034) (xy 91.73845 -354.5967)
			(xy 91.71559 -354.607368) (xy 91.70797 -354.617528) (xy 91.689791 -354.640507) (xy 91.647619 -354.681181)
			(xy 91.599726 -354.71493) (xy 91.547235 -354.740961) (xy 91.491383 -354.758662) (xy 91.433481 -354.767617)
			(xy 91.404186 -354.76815) (xy 91.374745 -354.767578) (xy 91.316562 -354.758542) (xy 91.260458 -354.740672)
			(xy 91.207767 -354.714393) (xy 91.15974 -354.680328) (xy 91.138248 -354.6602) (xy 91.130882 -354.653088)
			(xy 91.113102 -354.645976) (xy 91.021916 -354.645976) (xy 91.004136 -354.653088) (xy 90.99677 -354.6602)
			(xy 90.975265 -354.680314) (xy 90.927241 -354.714383) (xy 90.874554 -354.74067) (xy 90.818454 -354.758551)
			(xy 90.760272 -354.767602) (xy 90.730832 -354.76815) (xy 90.702652 -354.767668) (xy 90.64691 -354.759354)
			(xy 90.592996 -354.742931) (xy 90.542085 -354.718756) (xy 90.495283 -354.687356) (xy 90.453608 -354.649413)
			(xy 90.417969 -354.605753) (xy 90.389138 -354.557326) (xy 90.367745 -354.505184) (xy 90.354253 -354.450464)
			(xy 90.351102 -354.422456) (xy 90.351102 -354.422202) (xy 90.349826 -354.41288) (xy 90.341413 -354.396066)
			(xy 90.327498 -354.383421) (xy 90.309957 -354.376651) (xy 90.300556 -354.376228) (xy 89.917778 -354.376228)
			(xy 89.908391 -354.376727) (xy 89.890879 -354.383496) (xy 89.876981 -354.396119) (xy 89.868562 -354.4129)
			(xy 89.867232 -354.422202) (xy 89.867232 -354.422456) (xy 89.864083 -354.450461) (xy 89.850594 -354.505176)
			(xy 89.829201 -354.557311) (xy 89.800369 -354.605731) (xy 89.764727 -354.649382) (xy 89.72305 -354.687313)
			(xy 89.676246 -354.718699) (xy 89.625333 -354.742856) (xy 89.571419 -354.75926) (xy 89.515679 -354.767551)
			(xy 89.459325 -354.767551) (xy 89.403585 -354.75926) (xy 89.349671 -354.742856) (xy 89.298758 -354.718699)
			(xy 89.251954 -354.687313) (xy 89.210277 -354.649382) (xy 89.174635 -354.605731) (xy 89.145803 -354.557311)
			(xy 89.12441 -354.505176) (xy 89.110921 -354.450461) (xy 89.107772 -354.422456) (xy 89.107772 -354.422202)
			(xy 89.10643 -354.412894) (xy 89.098031 -354.39609) (xy 89.084138 -354.383446) (xy 89.066619 -354.376662)
			(xy 89.057226 -354.376228) (xy 89.03462 -354.376228) (xy 89.024597 -354.376637) (xy 89.006075 -354.384305)
			(xy 88.991901 -354.398482) (xy 88.984235 -354.417005) (xy 88.98382 -354.427028) (xy 88.98382 -354.429568)
			(xy 88.983315 -354.45682) (xy 88.975563 -354.510768) (xy 88.960211 -354.563065) (xy 88.937573 -354.612644)
			(xy 88.90811 -354.658497) (xy 88.87242 -354.699689) (xy 88.831232 -354.735383) (xy 88.785383 -354.764852)
			(xy 88.735806 -354.787496) (xy 88.683511 -354.802853) (xy 88.629563 -354.810612) (xy 88.602312 -354.811076)
			(xy 88.572261 -354.810494) (xy 88.512904 -354.80106) (xy 88.455759 -354.78244) (xy 88.402239 -354.755094)
			(xy 88.353666 -354.719697) (xy 88.332056 -354.698808) (xy 88.325198 -354.692555) (xy 88.30827 -354.684991)
			(xy 88.299036 -354.684076) (xy 88.231472 -354.680012) (xy 88.222307 -354.67998) (xy 88.204866 -354.685568)
			(xy 88.197436 -354.690934) (xy 88.197182 -354.690934) (xy 88.176892 -354.706404) (xy 88.13298 -354.732385)
			(xy 88.086 -354.752287) (xy 88.036787 -354.765755) (xy 87.986219 -354.772551) (xy 87.960708 -354.772976)
			(xy 87.931827 -354.772419) (xy 87.874725 -354.763719) (xy 87.819589 -354.746503) (xy 87.767682 -354.721164)
			(xy 87.720192 -354.688283) (xy 87.698834 -354.668836) (xy 87.691976 -354.662486) (xy 87.674958 -354.655374)
			(xy 87.597742 -354.653088) (xy 87.588657 -354.653208) (xy 87.57147 -354.659051) (xy 87.564214 -354.664518)
			(xy 87.563706 -354.665026) (xy 87.543037 -354.68167) (xy 87.497971 -354.709691) (xy 87.449461 -354.731205)
			(xy 87.39844 -354.745799) (xy 87.345891 -354.753192) (xy 87.319358 -354.753672) (xy 87.292104 -354.753261)
			(xy 87.238152 -354.745498) (xy 87.185853 -354.730136) (xy 87.136274 -354.707487) (xy 87.090422 -354.678013)
			(xy 87.049231 -354.642314) (xy 87.01354 -354.601116) (xy 86.984076 -354.555258) (xy 86.961437 -354.505673)
			(xy 86.946085 -354.453372) (xy 86.938333 -354.399418) (xy 86.93785 -354.372164) (xy 69.921628 -354.372164)
			(xy 69.566028 -354.727764) (xy 69.547933 -354.745021) (xy 69.506387 -354.772831) (xy 69.460216 -354.792007)
			(xy 69.411193 -354.801812) (xy 69.386196 -354.80244) (xy 32.349948 -354.80244) (xy 32.339883 -354.802874)
			(xy 32.321296 -354.810606) (xy 32.31388 -354.817426) (xy 31.994094 -355.137212) (xy 31.98727 -355.14454)
			(xy 31.979512 -355.162984) (xy 31.979427 -355.182993) (xy 31.98703 -355.201502) (xy 31.99384 -355.20884)
			(xy 32.386524 -355.601524) (xy 32.394187 -355.608558) (xy 32.413464 -355.616318) (xy 32.423862 -355.61651)
			(xy 32.507936 -355.614478) (xy 32.526986 -355.605588) (xy 32.533844 -355.597968) (xy 32.552019 -355.578581)
			(xy 32.592808 -355.544518) (xy 32.637928 -355.516443) (xy 32.686505 -355.494898) (xy 32.737602 -355.480298)
			(xy 32.790229 -355.472927) (xy 32.8168 -355.472492) (xy 32.844051 -355.472978) (xy 32.897999 -355.480734)
			(xy 32.950294 -355.496089) (xy 32.999871 -355.518731) (xy 33.045721 -355.548197) (xy 33.086912 -355.583888)
			(xy 33.122603 -355.625079) (xy 33.152069 -355.670929) (xy 33.174711 -355.720506) (xy 33.184076 -355.7524)
			(xy 34.669982 -355.7524) (xy 34.674053 -355.696778) (xy 34.686179 -355.642341) (xy 34.706102 -355.59025)
			(xy 34.733398 -355.541615) (xy 34.767484 -355.497472) (xy 34.807633 -355.458763) (xy 34.852991 -355.426312)
			(xy 34.902591 -355.400811) (xy 34.955375 -355.382804) (xy 35.010218 -355.372674) (xy 35.065952 -355.370637)
			(xy 35.121389 -355.376737) (xy 35.175346 -355.390843) (xy 35.226675 -355.412655) (xy 35.274281 -355.441709)
			(xy 35.317149 -355.477384) (xy 35.354366 -355.518921) (xy 35.385139 -355.565434) (xy 35.408811 -355.615931)
			(xy 35.424879 -355.669338) (xy 35.432999 -355.724514) (xy 35.433508 -355.7524) (xy 35.432999 -355.780286)
			(xy 35.424879 -355.835462) (xy 35.408811 -355.888869) (xy 35.385139 -355.939366) (xy 35.354366 -355.985879)
			(xy 35.317149 -356.027416) (xy 35.274281 -356.063091) (xy 35.226675 -356.092145) (xy 35.175346 -356.113957)
			(xy 35.121389 -356.128063) (xy 35.065952 -356.134163) (xy 35.010218 -356.132126) (xy 34.955375 -356.121996)
			(xy 34.902591 -356.103989) (xy 34.852991 -356.078488) (xy 34.807633 -356.046037) (xy 34.767484 -356.007328)
			(xy 34.733398 -355.963185) (xy 34.706102 -355.91455) (xy 34.686179 -355.862459) (xy 34.674053 -355.808022)
			(xy 34.669982 -355.7524) (xy 33.184076 -355.7524) (xy 33.190066 -355.772801) (xy 33.197822 -355.826749)
			(xy 33.198308 -355.854) (xy 33.19785 -355.88057) (xy 33.190481 -355.933196) (xy 33.175885 -355.984292)
			(xy 33.154345 -356.03287) (xy 33.126276 -356.077991) (xy 33.092222 -356.118785) (xy 33.072832 -356.136956)
			(xy 33.065212 -356.143814) (xy 33.056322 -356.162864) (xy 33.05429 -356.246938) (xy 33.054522 -356.257332)
			(xy 33.062252 -356.276611) (xy 33.069276 -356.284276) (xy 33.191196 -356.406196) (xy 33.198594 -356.413044)
			(xy 33.217192 -356.42078) (xy 33.227264 -356.421182) (xy 37.780722 -356.421182) (xy 37.790791 -356.421609)
			(xy 37.809391 -356.429327) (xy 37.81679 -356.436168) (xy 39.280592 -357.89997) (xy 39.287428 -357.907372)
			(xy 39.295138 -357.92597) (xy 39.295578 -357.936038) (xy 39.295578 -358.549194) (xy 40.988234 -358.549194)
			(xy 40.988686 -358.523273) (xy 40.995718 -358.471911) (xy 41.009638 -358.421973) (xy 41.030189 -358.374379)
			(xy 41.056993 -358.330005) (xy 41.089557 -358.289667) (xy 41.108122 -358.271572) (xy 41.11498 -358.264968)
			(xy 41.123108 -358.24795) (xy 41.129712 -358.16032) (xy 41.124124 -358.142286) (xy 41.118028 -358.134666)
			(xy 41.102545 -358.114386) (xy 41.076567 -358.070471) (xy 41.056669 -358.023487) (xy 41.043203 -357.974273)
			(xy 41.03641 -357.923704) (xy 41.035986 -357.898192) (xy 41.036451 -357.870822) (xy 41.044269 -357.816643)
			(xy 41.059759 -357.76414) (xy 41.082601 -357.714393) (xy 41.112325 -357.668426) (xy 41.129966 -357.647494)
			(xy 41.13022 -357.64724) (xy 41.135798 -357.640148) (xy 41.142049 -357.623235) (xy 41.142412 -357.61422)
			(xy 41.142412 -357.547164) (xy 41.14207 -357.538146) (xy 41.135812 -357.521229) (xy 41.13022 -357.514144)
			(xy 41.129966 -357.514144) (xy 41.129966 -357.51389) (xy 41.112303 -357.492977) (xy 41.082596 -357.446998)
			(xy 41.059765 -357.397246) (xy 41.04428 -357.344741) (xy 41.036457 -357.290562) (xy 41.035986 -357.263192)
			(xy 41.036472 -357.235941) (xy 41.044228 -357.181993) (xy 41.059583 -357.129698) (xy 41.082225 -357.080121)
			(xy 41.111691 -357.034271) (xy 41.147382 -356.99308) (xy 41.188573 -356.957389) (xy 41.234423 -356.927923)
			(xy 41.284 -356.905281) (xy 41.336295 -356.889926) (xy 41.390243 -356.88217) (xy 41.444745 -356.88217)
			(xy 41.498693 -356.889926) (xy 41.550988 -356.905281) (xy 41.600565 -356.927923) (xy 41.646415 -356.957389)
			(xy 41.687606 -356.99308) (xy 41.723297 -357.034271) (xy 41.752763 -357.080121) (xy 41.775405 -357.129698)
			(xy 41.79076 -357.181993) (xy 41.798516 -357.235941) (xy 41.799002 -357.263192) (xy 41.798531 -357.290562)
			(xy 41.790714 -357.344741) (xy 41.775226 -357.397244) (xy 41.752386 -357.446991) (xy 41.722663 -357.492958)
			(xy 41.705022 -357.51389) (xy 41.704768 -357.514144) (xy 41.699195 -357.52124) (xy 41.692941 -357.53815)
			(xy 41.692576 -357.547164) (xy 41.692576 -357.61422) (xy 41.692928 -357.623237) (xy 41.69918 -357.640154)
			(xy 41.704768 -357.64724) (xy 41.705022 -357.64724) (xy 41.705022 -357.647494) (xy 41.722675 -357.668415)
			(xy 41.752384 -357.714391) (xy 41.775217 -357.764141) (xy 41.790705 -357.816644) (xy 41.79853 -357.870822)
			(xy 41.799002 -357.898192) (xy 41.798529 -357.924112) (xy 41.7915 -357.975473) (xy 41.777584 -358.02541)
			(xy 41.757036 -358.073004) (xy 41.730236 -358.117379) (xy 41.697676 -358.157718) (xy 41.679114 -358.175814)
			(xy 41.672256 -358.182418) (xy 41.664128 -358.199436) (xy 41.657524 -358.287066) (xy 41.663112 -358.3051)
			(xy 41.669208 -358.31272) (xy 41.684676 -358.333012) (xy 41.710657 -358.376923) (xy 41.73056 -358.423903)
			(xy 41.744029 -358.473115) (xy 41.749099 -358.51084) (xy 43.554396 -358.51084) (xy 43.554825 -358.484919)
			(xy 43.561863 -358.433556) (xy 43.575788 -358.383618) (xy 43.596343 -358.336024) (xy 43.623151 -358.29165)
			(xy 43.655718 -358.251313) (xy 43.674284 -358.233218) (xy 43.681142 -358.226614) (xy 43.68927 -358.209596)
			(xy 43.695874 -358.121966) (xy 43.690286 -358.103932) (xy 43.68419 -358.096312) (xy 43.668737 -358.07601)
			(xy 43.642753 -358.032102) (xy 43.622847 -357.985124) (xy 43.609375 -357.935914) (xy 43.602575 -357.885348)
			(xy 43.602148 -357.859838) (xy 43.602625 -357.832468) (xy 43.610438 -357.778289) (xy 43.625924 -357.725785)
			(xy 43.648764 -357.676038) (xy 43.678487 -357.630072) (xy 43.696128 -357.60914) (xy 43.696382 -357.608886)
			(xy 43.701978 -357.601806) (xy 43.708219 -357.584884) (xy 43.708574 -357.575866) (xy 43.708574 -357.50881)
			(xy 43.708218 -357.499793) (xy 43.70197 -357.482876) (xy 43.696382 -357.47579) (xy 43.696128 -357.47579)
			(xy 43.696128 -357.475536) (xy 43.678497 -357.454598) (xy 43.648783 -357.408627) (xy 43.625945 -357.358881)
			(xy 43.610452 -357.306382) (xy 43.602623 -357.252207) (xy 43.602148 -357.224838) (xy 43.602634 -357.197587)
			(xy 43.61039 -357.143639) (xy 43.625745 -357.091344) (xy 43.648387 -357.041767) (xy 43.677853 -356.995917)
			(xy 43.713544 -356.954726) (xy 43.754735 -356.919035) (xy 43.800585 -356.889569) (xy 43.850162 -356.866927)
			(xy 43.902457 -356.851572) (xy 43.956405 -356.843816) (xy 44.010907 -356.843816) (xy 44.064855 -356.851572)
			(xy 44.11715 -356.866927) (xy 44.166727 -356.889569) (xy 44.212577 -356.919035) (xy 44.253768 -356.954726)
			(xy 44.289459 -356.995917) (xy 44.318925 -357.041767) (xy 44.341567 -357.091344) (xy 44.356922 -357.143639)
			(xy 44.364678 -357.197587) (xy 44.365164 -357.224838) (xy 44.36467 -357.252207) (xy 44.356861 -357.306386)
			(xy 44.341378 -357.358889) (xy 44.318543 -357.408636) (xy 44.288823 -357.454604) (xy 44.271184 -357.475536)
			(xy 44.27093 -357.47579) (xy 44.265333 -357.482869) (xy 44.259095 -357.499792) (xy 44.258738 -357.50881)
			(xy 44.258738 -357.575866) (xy 44.259103 -357.584882) (xy 44.265344 -357.6018) (xy 44.27093 -357.608886)
			(xy 44.271184 -357.608886) (xy 44.271184 -357.60914) (xy 44.288806 -357.630086) (xy 44.318521 -357.676055)
			(xy 44.34136 -357.725799) (xy 44.356855 -357.778296) (xy 44.364688 -357.83247) (xy 44.365164 -357.859838)
			(xy 44.364733 -357.885759) (xy 44.357697 -357.937123) (xy 44.343774 -357.987061) (xy 44.323218 -358.034655)
			(xy 44.29641 -358.079029) (xy 44.272612 -358.108504) (xy 47.49927 -358.108504) (xy 47.499749 -358.082584)
			(xy 47.506778 -358.031224) (xy 47.520694 -357.981287) (xy 47.54124 -357.933694) (xy 47.568039 -357.889318)
			(xy 47.600597 -357.848979) (xy 47.619158 -357.830882) (xy 47.626016 -357.824278) (xy 47.634144 -357.80726)
			(xy 47.640748 -357.71963) (xy 47.63516 -357.701596) (xy 47.629064 -357.693976) (xy 47.613591 -357.673689)
			(xy 47.587611 -357.629776) (xy 47.567709 -357.582795) (xy 47.554241 -357.533581) (xy 47.547447 -357.483013)
			(xy 47.547022 -357.457502) (xy 47.547484 -357.430132) (xy 47.555302 -357.375952) (xy 47.570792 -357.323449)
			(xy 47.593634 -357.273702) (xy 47.62336 -357.227735) (xy 47.641002 -357.206804) (xy 47.641256 -357.20655)
			(xy 47.646834 -357.199458) (xy 47.653085 -357.182545) (xy 47.653448 -357.17353) (xy 47.653448 -357.106474)
			(xy 47.653115 -357.097454) (xy 47.646852 -357.080537) (xy 47.641256 -357.073454) (xy 47.641002 -357.073454)
			(xy 47.641002 -357.0732) (xy 47.62335 -357.052279) (xy 47.59364 -357.006303) (xy 47.570806 -356.956553)
			(xy 47.555318 -356.90405) (xy 47.547494 -356.849872) (xy 47.547022 -356.822502) (xy 47.547457 -356.795248)
			(xy 47.555215 -356.741294) (xy 47.570572 -356.688994) (xy 47.593217 -356.639412) (xy 47.622687 -356.593557)
			(xy 47.658384 -356.552364) (xy 47.69958 -356.51667) (xy 47.745437 -356.487203) (xy 47.79502 -356.464562)
			(xy 47.847322 -356.449209) (xy 47.901276 -356.441455) (xy 47.92853 -356.440994) (xy 47.957165 -356.441498)
			(xy 48.01379 -356.450062) (xy 48.0685 -356.466994) (xy 48.120064 -356.491913) (xy 48.167324 -356.52426)
			(xy 48.209219 -356.563306) (xy 48.244806 -356.608177) (xy 48.259492 -356.632764) (xy 48.264243 -356.640338)
			(xy 48.277941 -356.651811) (xy 48.294752 -356.657867) (xy 48.303688 -356.658164) (xy 48.391572 -356.658164)
			(xy 48.4005 -356.657828) (xy 48.417292 -356.651761) (xy 48.430994 -356.640315) (xy 48.435768 -356.632764)
			(xy 48.450459 -356.608179) (xy 48.486042 -356.563306) (xy 48.527934 -356.524256) (xy 48.575194 -356.491909)
			(xy 48.626758 -356.466992) (xy 48.681469 -356.450064) (xy 48.738095 -356.441506) (xy 48.76673 -356.440994)
			(xy 48.794101 -356.441444) (xy 48.848281 -356.449266) (xy 48.900784 -356.464759) (xy 48.95053 -356.487604)
			(xy 48.996497 -356.517332) (xy 49.017428 -356.534974) (xy 49.017682 -356.535228) (xy 49.024767 -356.540816)
			(xy 49.041685 -356.547061) (xy 49.050702 -356.54742) (xy 49.117758 -356.54742) (xy 49.126772 -356.547039)
			(xy 49.143689 -356.540808) (xy 49.150778 -356.535228) (xy 49.150778 -356.534974) (xy 49.151032 -356.534974)
			(xy 49.171965 -356.517333) (xy 49.217933 -356.487609) (xy 49.267679 -356.464763) (xy 49.320181 -356.449267)
			(xy 49.374359 -356.441438) (xy 49.429101 -356.441438) (xy 49.483279 -356.449267) (xy 49.535781 -356.464763)
			(xy 49.585527 -356.487609) (xy 49.631495 -356.517333) (xy 49.652428 -356.534974) (xy 49.652682 -356.535228)
			(xy 49.659767 -356.540816) (xy 49.676685 -356.547061) (xy 49.685702 -356.54742) (xy 49.752758 -356.54742)
			(xy 49.761772 -356.547039) (xy 49.778689 -356.540808) (xy 49.785778 -356.535228) (xy 49.785778 -356.534974)
			(xy 49.786032 -356.534974) (xy 49.806965 -356.517333) (xy 49.852933 -356.487609) (xy 49.902679 -356.464763)
			(xy 49.955181 -356.449267) (xy 50.009359 -356.441438) (xy 50.064101 -356.441438) (xy 50.118279 -356.449267)
			(xy 50.170781 -356.464763) (xy 50.220527 -356.487609) (xy 50.266495 -356.517333) (xy 50.287428 -356.534974)
			(xy 50.287682 -356.535228) (xy 50.294767 -356.540816) (xy 50.311685 -356.547061) (xy 50.320702 -356.54742)
			(xy 50.387758 -356.54742) (xy 50.396772 -356.547039) (xy 50.413689 -356.540808) (xy 50.420778 -356.535228)
			(xy 50.420778 -356.534974) (xy 50.421032 -356.534974) (xy 50.441976 -356.517349) (xy 50.487946 -356.487636)
			(xy 50.53769 -356.464798) (xy 50.590188 -356.449303) (xy 50.644362 -356.441471) (xy 50.67173 -356.440994)
			(xy 50.698982 -356.44145) (xy 50.752931 -356.449211) (xy 50.805226 -356.46457) (xy 50.854804 -356.487214)
			(xy 50.900654 -356.516684) (xy 50.941844 -356.552379) (xy 50.977535 -356.593571) (xy 51.007001 -356.639424)
			(xy 51.029642 -356.689004) (xy 51.044996 -356.7413) (xy 51.052752 -356.79525) (xy 51.053238 -356.822502)
			(xy 51.052788 -356.849873) (xy 51.044969 -356.904053) (xy 51.029477 -356.956557) (xy 51.006631 -357.006304)
			(xy 50.976902 -357.052269) (xy 50.959258 -357.0732) (xy 50.959004 -357.073454) (xy 50.953431 -357.08055)
			(xy 50.947176 -357.097459) (xy 50.946812 -357.106474) (xy 50.946812 -357.17353) (xy 50.947152 -357.182549)
			(xy 50.953411 -357.199466) (xy 50.959004 -357.20655) (xy 50.959258 -357.20655) (xy 50.959258 -357.206804)
			(xy 50.976906 -357.227729) (xy 51.006618 -357.273703) (xy 51.029453 -357.323452) (xy 51.044942 -357.375955)
			(xy 51.052766 -357.430132) (xy 51.053238 -357.457502) (xy 51.052761 -357.483422) (xy 51.045731 -357.534782)
			(xy 51.031815 -357.584719) (xy 51.011268 -357.632312) (xy 50.984469 -357.676687) (xy 50.951911 -357.717027)
			(xy 50.93335 -357.735124) (xy 50.926492 -357.741728) (xy 50.918364 -357.758746) (xy 50.91176 -357.846376)
			(xy 50.917348 -357.86441) (xy 50.923444 -357.87203) (xy 50.938921 -357.892314) (xy 50.964901 -357.936228)
			(xy 50.984801 -357.98321) (xy 50.998268 -358.032424) (xy 51.005062 -358.082993) (xy 51.005486 -358.108504)
			(xy 51.005048 -358.135758) (xy 50.99729 -358.189711) (xy 50.981933 -358.242011) (xy 50.959288 -358.291592)
			(xy 50.929818 -358.337446) (xy 50.894121 -358.37864) (xy 50.852926 -358.414333) (xy 50.807069 -358.4438)
			(xy 50.757486 -358.466442) (xy 50.705185 -358.481796) (xy 50.651232 -358.48955) (xy 50.623978 -358.490012)
			(xy 50.596607 -358.489556) (xy 50.542428 -358.481735) (xy 50.489925 -358.466244) (xy 50.440178 -358.4434)
			(xy 50.394212 -358.413674) (xy 50.37328 -358.396032) (xy 50.373026 -358.395778) (xy 50.365938 -358.390194)
			(xy 50.349022 -358.383946) (xy 50.340006 -358.383586) (xy 50.27295 -358.383586) (xy 50.263936 -358.38397)
			(xy 50.247019 -358.390199) (xy 50.23993 -358.395778) (xy 50.23993 -358.396032) (xy 50.239676 -358.396032)
			(xy 50.218743 -358.413673) (xy 50.172775 -358.443397) (xy 50.123029 -358.466243) (xy 50.070527 -358.481739)
			(xy 50.016349 -358.489568) (xy 49.961607 -358.489568) (xy 49.907429 -358.481739) (xy 49.854927 -358.466243)
			(xy 49.805181 -358.443397) (xy 49.759213 -358.413673) (xy 49.73828 -358.396032) (xy 49.738026 -358.395778)
			(xy 49.730938 -358.390194) (xy 49.714022 -358.383946) (xy 49.705006 -358.383586) (xy 49.63795 -358.383586)
			(xy 49.628936 -358.38397) (xy 49.612019 -358.390199) (xy 49.60493 -358.395778) (xy 49.60493 -358.396032)
			(xy 49.604676 -358.396032) (xy 49.583743 -358.413673) (xy 49.537775 -358.443397) (xy 49.488029 -358.466243)
			(xy 49.435527 -358.481739) (xy 49.381349 -358.489568) (xy 49.326607 -358.489568) (xy 49.272429 -358.481739)
			(xy 49.219927 -358.466243) (xy 49.170181 -358.443397) (xy 49.124213 -358.413673) (xy 49.10328 -358.396032)
			(xy 49.103026 -358.395778) (xy 49.095938 -358.390194) (xy 49.079022 -358.383946) (xy 49.070006 -358.383586)
			(xy 49.00295 -358.383586) (xy 48.993936 -358.38397) (xy 48.977019 -358.390199) (xy 48.96993 -358.395778)
			(xy 48.96993 -358.396032) (xy 48.969676 -358.396032) (xy 48.94873 -358.413654) (xy 48.902761 -358.443367)
			(xy 48.853017 -358.466206) (xy 48.800519 -358.481701) (xy 48.746346 -358.489535) (xy 48.718978 -358.490012)
			(xy 48.690344 -358.489499) (xy 48.633719 -358.480936) (xy 48.57901 -358.464005) (xy 48.527446 -358.439088)
			(xy 48.480185 -358.406743) (xy 48.43829 -358.367697) (xy 48.402702 -358.322829) (xy 48.388016 -358.298242)
			(xy 48.383258 -358.290673) (xy 48.369563 -358.279199) (xy 48.352755 -358.273141) (xy 48.34382 -358.272842)
			(xy 48.255936 -358.272842) (xy 48.247008 -358.273181) (xy 48.230216 -358.279246) (xy 48.216514 -358.290691)
			(xy 48.21174 -358.298242) (xy 48.197046 -358.322824) (xy 48.161463 -358.367698) (xy 48.119571 -358.406747)
			(xy 48.072312 -358.439094) (xy 48.020748 -358.464012) (xy 47.966039 -358.480941) (xy 47.909413 -358.4895)
			(xy 47.880778 -358.490012) (xy 47.853526 -358.489543) (xy 47.799578 -358.481783) (xy 47.747283 -358.466426)
			(xy 47.697706 -358.443782) (xy 47.651856 -358.414314) (xy 47.610666 -358.378621) (xy 47.574975 -358.337429)
			(xy 47.545509 -358.291578) (xy 47.522868 -358.242) (xy 47.507513 -358.189704) (xy 47.499756 -358.135756)
			(xy 47.49927 -358.108504) (xy 44.272612 -358.108504) (xy 44.263842 -358.119366) (xy 44.245276 -358.13746)
			(xy 44.238418 -358.144064) (xy 44.23029 -358.161082) (xy 44.223686 -358.248712) (xy 44.229274 -358.266746)
			(xy 44.23537 -358.274366) (xy 44.250822 -358.294669) (xy 44.276804 -358.338578) (xy 44.296709 -358.385555)
			(xy 44.310182 -358.434765) (xy 44.316984 -358.48533) (xy 44.317412 -358.51084) (xy 44.316847 -358.539303)
			(xy 44.308379 -358.595597) (xy 44.291638 -358.650006) (xy 44.266995 -358.701322) (xy 44.234998 -358.748406)
			(xy 44.216066 -358.769666) (xy 44.208954 -358.77754) (xy 44.202096 -358.797352) (xy 44.209716 -358.893618)
			(xy 44.219622 -358.91216) (xy 44.228258 -358.918764) (xy 44.250665 -358.936951) (xy 44.290263 -358.978928)
			(xy 44.323086 -359.026392) (xy 44.348384 -359.078259) (xy 44.36558 -359.133345) (xy 44.374282 -359.190392)
			(xy 44.374816 -359.219246) (xy 44.37433 -359.246497) (xy 44.366574 -359.300445) (xy 44.351219 -359.35274)
			(xy 44.328577 -359.402317) (xy 44.299111 -359.448167) (xy 44.26342 -359.489358) (xy 44.222229 -359.525049)
			(xy 44.176379 -359.554515) (xy 44.126802 -359.577157) (xy 44.074507 -359.592512) (xy 44.020559 -359.600268)
			(xy 43.966057 -359.600268) (xy 43.912109 -359.592512) (xy 43.859814 -359.577157) (xy 43.810237 -359.554515)
			(xy 43.764387 -359.525049) (xy 43.723196 -359.489358) (xy 43.687505 -359.448167) (xy 43.658039 -359.402317)
			(xy 43.635397 -359.35274) (xy 43.620042 -359.300445) (xy 43.612286 -359.246497) (xy 43.6118 -359.219246)
			(xy 43.612354 -359.190782) (xy 43.620824 -359.134488) (xy 43.637567 -359.080079) (xy 43.662213 -359.028763)
			(xy 43.694212 -358.98168) (xy 43.713146 -358.96042) (xy 43.720258 -358.952546) (xy 43.727116 -358.932734)
			(xy 43.719496 -358.836468) (xy 43.70959 -358.817926) (xy 43.700954 -358.811322) (xy 43.678543 -358.79314)
			(xy 43.638944 -358.751162) (xy 43.606122 -358.703697) (xy 43.580824 -358.65183) (xy 43.563629 -358.596743)
			(xy 43.554929 -358.539694) (xy 43.554396 -358.51084) (xy 41.749099 -358.51084) (xy 41.750825 -358.523683)
			(xy 41.75125 -358.549194) (xy 41.750733 -358.577659) (xy 41.742256 -358.633955) (xy 41.725505 -358.688366)
			(xy 41.700851 -358.739682) (xy 41.668842 -358.786762) (xy 41.649904 -358.80802) (xy 41.642792 -358.815894)
			(xy 41.635934 -358.835706) (xy 41.643554 -358.931972) (xy 41.65346 -358.950514) (xy 41.662096 -358.957118)
			(xy 41.684516 -358.97529) (xy 41.724116 -359.017269) (xy 41.756939 -359.064735) (xy 41.782236 -359.116605)
			(xy 41.799428 -359.171694) (xy 41.808123 -359.228745) (xy 41.808654 -359.2576) (xy 41.808168 -359.284851)
			(xy 41.800412 -359.338799) (xy 41.785057 -359.391094) (xy 41.762415 -359.440671) (xy 41.732949 -359.486521)
			(xy 41.697258 -359.527712) (xy 41.656067 -359.563403) (xy 41.610217 -359.592869) (xy 41.56064 -359.615511)
			(xy 41.508345 -359.630866) (xy 41.454397 -359.638622) (xy 41.399895 -359.638622) (xy 41.345947 -359.630866)
			(xy 41.293652 -359.615511) (xy 41.244075 -359.592869) (xy 41.198225 -359.563403) (xy 41.157034 -359.527712)
			(xy 41.121343 -359.486521) (xy 41.091877 -359.440671) (xy 41.069235 -359.391094) (xy 41.05388 -359.338799)
			(xy 41.046124 -359.284851) (xy 41.045638 -359.2576) (xy 41.046154 -359.229135) (xy 41.054632 -359.172839)
			(xy 41.071384 -359.118428) (xy 41.096038 -359.067113) (xy 41.128046 -359.020032) (xy 41.146984 -358.998774)
			(xy 41.154096 -358.9909) (xy 41.160954 -358.971088) (xy 41.153334 -358.874822) (xy 41.143428 -358.85628)
			(xy 41.134792 -358.849676) (xy 41.112367 -358.831511) (xy 41.072767 -358.78953) (xy 41.039945 -358.742062)
			(xy 41.01465 -358.690191) (xy 40.997459 -358.635101) (xy 40.988764 -358.578049) (xy 40.988234 -358.549194)
			(xy 39.295578 -358.549194) (xy 39.295578 -360.651298) (xy 39.295155 -360.661368) (xy 39.287438 -360.679971)
			(xy 39.280592 -360.687366) (xy 39.071296 -360.896662) (xy 39.068248 -360.901742) (xy 39.058493 -360.917307)
			(xy 39.035824 -360.946212) (xy 39.023036 -360.9594) (xy 38.468046 -361.514136) (xy 38.464638 -361.517425)
			(xy 38.456843 -361.522802) (xy 38.452552 -361.524804) (xy 38.444424 -361.52836) (xy 38.440139 -361.530374)
			(xy 38.432342 -361.535745) (xy 38.42893 -361.539028) (xy 38.418262 -361.549696) (xy 38.412394 -361.555979)
			(xy 38.404885 -361.571431) (xy 38.402927 -361.588499) (xy 38.404546 -361.59694) (xy 38.423596 -361.68076)
			(xy 38.425793 -361.689016) (xy 38.434843 -361.703493) (xy 38.448176 -361.714157) (xy 38.456108 -361.717336)
			(xy 38.48358 -361.727671) (xy 38.535227 -361.755557) (xy 38.581998 -361.791017) (xy 38.622794 -361.833216)
			(xy 38.656654 -361.881159) (xy 38.68278 -361.933718) (xy 38.700557 -361.989655) (xy 38.709567 -362.047653)
			(xy 38.710108 -362.077) (xy 38.709622 -362.104251) (xy 38.701866 -362.158199) (xy 38.686511 -362.210494)
			(xy 38.663869 -362.260071) (xy 38.634403 -362.305921) (xy 38.598712 -362.347112) (xy 38.557521 -362.382803)
			(xy 38.511671 -362.412269) (xy 38.462094 -362.434911) (xy 38.409799 -362.450266) (xy 38.355851 -362.458022)
			(xy 38.3286 -362.458508) (xy 38.297012 -362.457874) (xy 38.234707 -362.447409) (xy 38.204648 -362.43768)
			(xy 38.192964 -362.433616) (xy 38.168834 -362.437172) (xy 38.091364 -362.492544) (xy 38.08186 -362.500163)
			(xy 38.070723 -362.521785) (xy 38.070028 -362.533946) (xy 38.070028 -362.85424) (xy 46.115224 -362.85424)
			(xy 46.115708 -362.82687) (xy 46.12352 -362.772692) (xy 46.139005 -362.720189) (xy 46.161843 -362.670441)
			(xy 46.191564 -362.624474) (xy 46.209204 -362.603542) (xy 46.209458 -362.603288) (xy 46.215063 -362.596214)
			(xy 46.221297 -362.579287) (xy 46.22165 -362.570268) (xy 46.22165 -362.503212) (xy 46.221298 -362.494194)
			(xy 46.215048 -362.477277) (xy 46.209458 -362.470192) (xy 46.209204 -362.470192) (xy 46.209204 -362.469938)
			(xy 46.191603 -362.448973) (xy 46.161879 -362.40301) (xy 46.139032 -362.353269) (xy 46.123534 -362.300772)
			(xy 46.115702 -362.246599) (xy 46.115698 -362.191862) (xy 46.123521 -362.137687) (xy 46.139011 -362.085187)
			(xy 46.16185 -362.035443) (xy 46.191567 -361.989475) (xy 46.209204 -361.968542) (xy 46.209458 -361.968288)
			(xy 46.215063 -361.961214) (xy 46.221297 -361.944287) (xy 46.22165 -361.935268) (xy 46.22165 -361.868212)
			(xy 46.221298 -361.859194) (xy 46.215048 -361.842277) (xy 46.209458 -361.835192) (xy 46.209204 -361.835192)
			(xy 46.209204 -361.834938) (xy 46.191603 -361.813973) (xy 46.161879 -361.76801) (xy 46.139032 -361.718269)
			(xy 46.123534 -361.665772) (xy 46.115702 -361.611599) (xy 46.115698 -361.556862) (xy 46.123521 -361.502687)
			(xy 46.139011 -361.450187) (xy 46.16185 -361.400443) (xy 46.191567 -361.354475) (xy 46.209204 -361.333542)
			(xy 46.209458 -361.333288) (xy 46.215063 -361.326214) (xy 46.221297 -361.309287) (xy 46.22165 -361.300268)
			(xy 46.22165 -361.233212) (xy 46.221298 -361.224194) (xy 46.215048 -361.207277) (xy 46.209458 -361.200192)
			(xy 46.209204 -361.200192) (xy 46.209204 -361.199938) (xy 46.191603 -361.178973) (xy 46.161879 -361.13301)
			(xy 46.139032 -361.083269) (xy 46.123534 -361.030772) (xy 46.115702 -360.976599) (xy 46.115698 -360.921862)
			(xy 46.123521 -360.867687) (xy 46.139011 -360.815187) (xy 46.16185 -360.765443) (xy 46.191567 -360.719475)
			(xy 46.209204 -360.698542) (xy 46.209458 -360.698288) (xy 46.215063 -360.691214) (xy 46.221297 -360.674287)
			(xy 46.22165 -360.665268) (xy 46.22165 -360.598212) (xy 46.221298 -360.589194) (xy 46.215048 -360.572277)
			(xy 46.209458 -360.565192) (xy 46.209204 -360.565192) (xy 46.209204 -360.564938) (xy 46.191603 -360.543973)
			(xy 46.161879 -360.49801) (xy 46.139032 -360.448269) (xy 46.123534 -360.395772) (xy 46.115702 -360.341599)
			(xy 46.115698 -360.286862) (xy 46.123521 -360.232687) (xy 46.139011 -360.180187) (xy 46.16185 -360.130443)
			(xy 46.191567 -360.084475) (xy 46.209204 -360.063542) (xy 46.209458 -360.063288) (xy 46.215063 -360.056214)
			(xy 46.221297 -360.039287) (xy 46.22165 -360.030268) (xy 46.22165 -359.963212) (xy 46.221298 -359.954194)
			(xy 46.215048 -359.937277) (xy 46.209458 -359.930192) (xy 46.209204 -359.930192) (xy 46.209204 -359.929938)
			(xy 46.19157 -359.909002) (xy 46.161857 -359.86303) (xy 46.13902 -359.813284) (xy 46.123528 -359.760784)
			(xy 46.115699 -359.706609) (xy 46.115224 -359.67924) (xy 46.115693 -359.651987) (xy 46.123445 -359.598034)
			(xy 46.138798 -359.545735) (xy 46.161438 -359.496152) (xy 46.190905 -359.450298) (xy 46.226598 -359.409104)
			(xy 46.267791 -359.373409) (xy 46.313645 -359.343942) (xy 46.363227 -359.3213) (xy 46.415526 -359.305947)
			(xy 46.469479 -359.298193) (xy 46.496732 -359.297732) (xy 46.524103 -359.298172) (xy 46.578284 -359.305995)
			(xy 46.630788 -359.321489) (xy 46.680534 -359.344337) (xy 46.726499 -359.374068) (xy 46.74743 -359.391712)
			(xy 46.747684 -359.391966) (xy 46.754765 -359.39756) (xy 46.771686 -359.4038) (xy 46.780704 -359.404158)
			(xy 46.84776 -359.404158) (xy 46.856776 -359.403791) (xy 46.873694 -359.397551) (xy 46.88078 -359.391966)
			(xy 46.88078 -359.391712) (xy 46.881034 -359.391712) (xy 46.901967 -359.374071) (xy 46.947935 -359.344347)
			(xy 46.997681 -359.321501) (xy 47.050183 -359.306005) (xy 47.104361 -359.298176) (xy 47.159103 -359.298176)
			(xy 47.213281 -359.306005) (xy 47.265783 -359.321501) (xy 47.315529 -359.344347) (xy 47.361497 -359.374071)
			(xy 47.38243 -359.391712) (xy 47.382684 -359.391966) (xy 47.389765 -359.39756) (xy 47.406686 -359.4038)
			(xy 47.415704 -359.404158) (xy 47.48276 -359.404158) (xy 47.491776 -359.403791) (xy 47.508694 -359.397551)
			(xy 47.51578 -359.391966) (xy 47.51578 -359.391712) (xy 47.516034 -359.391712) (xy 47.536982 -359.374092)
			(xy 47.58295 -359.344377) (xy 47.632694 -359.321537) (xy 47.685191 -359.306042) (xy 47.739364 -359.298209)
			(xy 47.766732 -359.297732) (xy 47.793558 -359.298162) (xy 47.846678 -359.305703) (xy 47.898219 -359.320605)
			(xy 47.947167 -359.342574) (xy 47.992559 -359.371178) (xy 48.033501 -359.405853) (xy 48.069187 -359.445917)
			(xy 48.098914 -359.490581) (xy 48.122097 -359.538966) (xy 48.13828 -359.590119) (xy 48.14316 -359.616502)
			(xy 48.144938 -359.627424) (xy 48.156876 -359.645458) (xy 48.240442 -359.697274) (xy 48.262032 -359.700068)
			(xy 48.272446 -359.69702) (xy 48.299366 -359.689407) (xy 48.354711 -359.681252) (xy 48.382682 -359.680764)
			(xy 48.410053 -359.681225) (xy 48.464233 -359.689042) (xy 48.516736 -359.704531) (xy 48.566483 -359.727374)
			(xy 48.612449 -359.757101) (xy 48.63338 -359.774744) (xy 48.633634 -359.774998) (xy 48.640735 -359.780563)
			(xy 48.657641 -359.786823) (xy 48.666654 -359.78719) (xy 48.73371 -359.78719) (xy 48.742728 -359.78684)
			(xy 48.759645 -359.780588) (xy 48.76673 -359.774998) (xy 48.76673 -359.774744) (xy 48.766984 -359.774744)
			(xy 48.787917 -359.757103) (xy 48.833885 -359.727379) (xy 48.883631 -359.704533) (xy 48.936133 -359.689037)
			(xy 48.990311 -359.681208) (xy 49.045053 -359.681208) (xy 49.099231 -359.689037) (xy 49.151733 -359.704533)
			(xy 49.201479 -359.727379) (xy 49.247447 -359.757103) (xy 49.26838 -359.774744) (xy 49.268634 -359.774998)
			(xy 49.275735 -359.780563) (xy 49.292641 -359.786823) (xy 49.301654 -359.78719) (xy 49.36871 -359.78719)
			(xy 49.377728 -359.78684) (xy 49.394645 -359.780588) (xy 49.40173 -359.774998) (xy 49.40173 -359.774744)
			(xy 49.401984 -359.774744) (xy 49.422917 -359.757103) (xy 49.468885 -359.727379) (xy 49.518631 -359.704533)
			(xy 49.571133 -359.689037) (xy 49.625311 -359.681208) (xy 49.680053 -359.681208) (xy 49.734231 -359.689037)
			(xy 49.786733 -359.704533) (xy 49.836479 -359.727379) (xy 49.882447 -359.757103) (xy 49.90338 -359.774744)
			(xy 49.903634 -359.774998) (xy 49.910735 -359.780563) (xy 49.927641 -359.786823) (xy 49.936654 -359.78719)
			(xy 50.00371 -359.78719) (xy 50.012728 -359.78684) (xy 50.029645 -359.780588) (xy 50.03673 -359.774998)
			(xy 50.03673 -359.774744) (xy 50.036984 -359.774744) (xy 50.057917 -359.757106) (xy 50.103889 -359.727392)
			(xy 50.153636 -359.704555) (xy 50.206137 -359.689064) (xy 50.260313 -359.681237) (xy 50.287682 -359.680764)
			(xy 50.288444 -359.680764) (xy 50.318219 -359.681365) (xy 50.377036 -359.690673) (xy 50.405538 -359.699306)
			(xy 50.415444 -359.702608) (xy 50.436526 -359.700576) (xy 50.519584 -359.655364) (xy 50.532284 -359.639108)
			(xy 50.535078 -359.628948) (xy 50.542719 -359.602235) (xy 50.564657 -359.551191) (xy 50.59377 -359.50387)
			(xy 50.629442 -359.461274) (xy 50.670916 -359.424306) (xy 50.717316 -359.393746) (xy 50.76766 -359.370244)
			(xy 50.82088 -359.354295) (xy 50.875852 -359.346237) (xy 50.903632 -359.345738) (xy 50.932527 -359.346241)
			(xy 50.989656 -359.354951) (xy 51.044816 -359.372184) (xy 51.096745 -359.397542) (xy 51.120802 -359.413556)
			(xy 51.128422 -359.41889) (xy 51.146964 -359.423462) (xy 51.233578 -359.411778) (xy 51.249834 -359.402888)
			(xy 51.256184 -359.395522) (xy 51.274429 -359.374664) (xy 51.315856 -359.33786) (xy 51.362173 -359.30744)
			(xy 51.412405 -359.284044) (xy 51.465495 -359.268163) (xy 51.520323 -359.260134) (xy 51.54803 -359.259632)
			(xy 51.573982 -359.26006) (xy 51.625404 -359.267112) (xy 51.675397 -359.281066) (xy 51.723038 -359.301667)
			(xy 51.767447 -359.328534) (xy 51.807806 -359.36117) (xy 51.825906 -359.379774) (xy 51.825906 -359.380028)
			(xy 51.832847 -359.386731) (xy 51.85034 -359.394831) (xy 51.859942 -359.395776) (xy 51.939698 -359.400348)
			(xy 51.957986 -359.394252) (xy 51.965606 -359.387902) (xy 51.986326 -359.370947) (xy 52.031651 -359.34245)
			(xy 52.080513 -359.320564) (xy 52.131953 -359.305717) (xy 52.184963 -359.298202) (xy 52.211732 -359.297732)
			(xy 52.239103 -359.298172) (xy 52.293284 -359.305995) (xy 52.345788 -359.321489) (xy 52.395534 -359.344337)
			(xy 52.441499 -359.374068) (xy 52.46243 -359.391712) (xy 52.462684 -359.391966) (xy 52.469765 -359.39756)
			(xy 52.486686 -359.4038) (xy 52.495704 -359.404158) (xy 52.56276 -359.404158) (xy 52.571776 -359.403791)
			(xy 52.588694 -359.397551) (xy 52.59578 -359.391966) (xy 52.59578 -359.391712) (xy 52.596034 -359.391712)
			(xy 52.616982 -359.374092) (xy 52.66295 -359.344377) (xy 52.712694 -359.321537) (xy 52.765191 -359.306042)
			(xy 52.819364 -359.298209) (xy 52.846732 -359.297732) (xy 52.873988 -359.298125) (xy 52.927943 -359.305888)
			(xy 52.980245 -359.32125) (xy 53.029828 -359.343899) (xy 53.075683 -359.373374) (xy 53.116876 -359.409075)
			(xy 53.152569 -359.450275) (xy 53.182036 -359.496136) (xy 53.204675 -359.545723) (xy 53.220028 -359.598027)
			(xy 53.22778 -359.651984) (xy 53.22824 -359.67924) (xy 53.22824 -359.679748) (xy 53.227695 -359.707631)
			(xy 53.219541 -359.762798) (xy 53.203442 -359.81619) (xy 53.179741 -359.866669) (xy 53.148944 -359.91316)
			(xy 53.130704 -359.934256) (xy 53.124354 -359.941114) (xy 53.117496 -359.958894) (xy 53.11775 -360.045762)
			(xy 53.124354 -360.063034) (xy 53.130704 -360.070146) (xy 53.149106 -360.091278) (xy 53.180168 -360.137913)
			(xy 53.204071 -360.188592) (xy 53.2203 -360.242224) (xy 53.228505 -360.297653) (xy 53.229002 -360.32567)
			(xy 53.228517 -360.352922) (xy 53.220764 -360.406873) (xy 53.205411 -360.459171) (xy 53.182772 -360.508751)
			(xy 53.153306 -360.554605) (xy 53.117615 -360.595798) (xy 53.076424 -360.631492) (xy 53.030572 -360.66096)
			(xy 52.980993 -360.683603) (xy 52.928696 -360.698959) (xy 52.874746 -360.706715) (xy 52.847494 -360.707178)
			(xy 52.819383 -360.706684) (xy 52.763768 -360.698437) (xy 52.709964 -360.682124) (xy 52.659135 -360.658096)
			(xy 52.612379 -360.626873) (xy 52.591208 -360.608372) (xy 52.58435 -360.602276) (xy 52.567586 -360.595418)
			(xy 52.481734 -360.593894) (xy 52.464716 -360.599736) (xy 52.457604 -360.605832) (xy 52.4369 -360.622757)
			(xy 52.391624 -360.651213) (xy 52.342812 -360.673053) (xy 52.291423 -360.687848) (xy 52.23847 -360.695308)
			(xy 52.211732 -360.695748) (xy 52.185781 -360.695285) (xy 52.13436 -360.688242) (xy 52.084367 -360.674294)
			(xy 52.036727 -360.6537) (xy 51.992316 -360.626839) (xy 51.951956 -360.594207) (xy 51.933856 -360.575606)
			(xy 51.933856 -360.575352) (xy 51.926931 -360.568631) (xy 51.909426 -360.560541) (xy 51.89982 -360.559604)
			(xy 51.820064 -360.555032) (xy 51.801776 -360.561128) (xy 51.794156 -360.567478) (xy 51.773411 -360.584402)
			(xy 51.728093 -360.612904) (xy 51.679237 -360.634796) (xy 51.627803 -360.64965) (xy 51.574798 -360.657174)
			(xy 51.54803 -360.657648) (xy 51.519137 -360.6571) (xy 51.46201 -360.6484) (xy 51.40685 -360.631181)
			(xy 51.35492 -360.605836) (xy 51.33086 -360.58983) (xy 51.32324 -360.584496) (xy 51.304698 -360.579924)
			(xy 51.218084 -360.591608) (xy 51.201828 -360.600498) (xy 51.195478 -360.607864) (xy 51.17592 -360.629454)
			(xy 51.168882 -360.637388) (xy 51.161396 -360.657203) (xy 51.161442 -360.667808) (xy 51.166014 -360.753406)
			(xy 51.175666 -360.772456) (xy 51.183794 -360.77906) (xy 51.205176 -360.797302) (xy 51.242916 -360.838946)
			(xy 51.274139 -360.885676) (xy 51.298169 -360.936481) (xy 51.314486 -360.990261) (xy 51.322737 -361.045853)
			(xy 51.32324 -361.073954) (xy 51.322702 -361.101204) (xy 51.314952 -361.155151) (xy 51.299604 -361.207445)
			(xy 51.276969 -361.257023) (xy 51.247509 -361.302875) (xy 51.211823 -361.344067) (xy 51.170638 -361.379762)
			(xy 51.124792 -361.409231) (xy 51.075219 -361.431876) (xy 51.022927 -361.447236) (xy 50.968982 -361.454996)
			(xy 50.941732 -361.455462) (xy 50.941478 -361.455462) (xy 50.913612 -361.454993) (xy 50.858474 -361.446874)
			(xy 50.805111 -361.430798) (xy 50.77968 -361.419394) (xy 50.779426 -361.419394) (xy 50.769836 -361.415439)
			(xy 50.749119 -361.414792) (xy 50.739294 -361.418124) (xy 50.660554 -361.449112) (xy 50.646076 -361.46359)
			(xy 50.642012 -361.473496) (xy 50.630964 -361.499689) (xy 50.602339 -361.548798) (xy 50.56674 -361.593113)
			(xy 50.524956 -361.631652) (xy 50.477913 -361.663561) (xy 50.426655 -361.688132) (xy 50.372317 -361.70482)
			(xy 50.316104 -361.713257) (xy 50.287682 -361.71378) (xy 50.260311 -361.713329) (xy 50.206131 -361.705509)
			(xy 50.153628 -361.690016) (xy 50.103881 -361.667171) (xy 50.057915 -361.637443) (xy 50.036984 -361.6198)
			(xy 50.03673 -361.619546) (xy 50.029644 -361.613959) (xy 50.012727 -361.607714) (xy 50.00371 -361.607354)
			(xy 49.936654 -361.607354) (xy 49.927638 -361.607725) (xy 49.910721 -361.613962) (xy 49.903634 -361.619546)
			(xy 49.903634 -361.6198) (xy 49.90338 -361.6198) (xy 49.882447 -361.637441) (xy 49.836479 -361.667165)
			(xy 49.786733 -361.690011) (xy 49.734231 -361.705507) (xy 49.680053 -361.713336) (xy 49.625311 -361.713336)
			(xy 49.571133 -361.705507) (xy 49.518631 -361.690011) (xy 49.468885 -361.667165) (xy 49.422917 -361.637441)
			(xy 49.401984 -361.6198) (xy 49.40173 -361.619546) (xy 49.394644 -361.613959) (xy 49.377727 -361.607714)
			(xy 49.36871 -361.607354) (xy 49.301654 -361.607354) (xy 49.292638 -361.607725) (xy 49.275721 -361.613962)
			(xy 49.268634 -361.619546) (xy 49.268634 -361.6198) (xy 49.26838 -361.6198) (xy 49.247447 -361.637441)
			(xy 49.201479 -361.667165) (xy 49.151733 -361.690011) (xy 49.099231 -361.705507) (xy 49.045053 -361.713336)
			(xy 48.990311 -361.713336) (xy 48.936133 -361.705507) (xy 48.883631 -361.690011) (xy 48.833885 -361.667165)
			(xy 48.787917 -361.637441) (xy 48.766984 -361.6198) (xy 48.76673 -361.619546) (xy 48.759644 -361.613959)
			(xy 48.742727 -361.607714) (xy 48.73371 -361.607354) (xy 48.666654 -361.607354) (xy 48.657638 -361.607725)
			(xy 48.640721 -361.613962) (xy 48.633634 -361.619546) (xy 48.633634 -361.6198) (xy 48.63338 -361.6198)
			(xy 48.612429 -361.637415) (xy 48.566461 -361.667131) (xy 48.516718 -361.689971) (xy 48.464222 -361.705468)
			(xy 48.41005 -361.713302) (xy 48.382682 -361.71378) (xy 48.382174 -361.71378) (xy 48.358643 -361.713421)
			(xy 48.311942 -361.707594) (xy 48.266312 -361.696071) (xy 48.244252 -361.687872) (xy 48.243998 -361.687872)
			(xy 48.234838 -361.684775) (xy 48.215519 -361.684897) (xy 48.206406 -361.688126) (xy 48.14189 -361.714542)
			(xy 48.133064 -361.718588) (xy 48.119088 -361.732038) (xy 48.114712 -361.740704) (xy 48.102724 -361.766129)
			(xy 48.072367 -361.813437) (xy 48.05426 -361.834938) (xy 48.054006 -361.835192) (xy 48.048417 -361.842277)
			(xy 48.042172 -361.859195) (xy 48.041814 -361.868212) (xy 48.041814 -361.935268) (xy 48.042184 -361.944284)
			(xy 48.048422 -361.961201) (xy 48.054006 -361.968288) (xy 48.05426 -361.968288) (xy 48.05426 -361.968542)
			(xy 48.071879 -361.98949) (xy 48.101595 -362.035458) (xy 48.124436 -362.085201) (xy 48.139931 -362.137699)
			(xy 48.147764 -362.191872) (xy 48.14824 -362.21924) (xy 48.147759 -362.246491) (xy 48.139998 -362.300437)
			(xy 48.12464 -362.35273) (xy 48.101996 -362.402305) (xy 48.072529 -362.448154) (xy 48.036837 -362.489343)
			(xy 47.995647 -362.525034) (xy 47.949798 -362.5545) (xy 47.900222 -362.577143) (xy 47.847929 -362.5925)
			(xy 47.793983 -362.60026) (xy 47.766732 -362.600748) (xy 47.737254 -362.600203) (xy 47.679001 -362.591137)
			(xy 47.622836 -362.573217) (xy 47.570096 -362.546868) (xy 47.522039 -362.512719) (xy 47.50054 -362.492544)
			(xy 47.493193 -362.486026) (xy 47.475042 -362.478573) (xy 47.465234 -362.478066) (xy 47.411894 -362.478066)
			(xy 47.405036 -362.485432) (xy 47.398486 -362.492754) (xy 47.391052 -362.510924) (xy 47.390558 -362.520738)
			(xy 47.390558 -362.552742) (xy 47.391043 -362.562556) (xy 47.39849 -362.58072) (xy 47.405036 -362.588048)
			(xy 47.42523 -362.609529) (xy 47.459372 -362.657593) (xy 47.485715 -362.710337) (xy 47.503632 -362.766506)
			(xy 47.512694 -362.824762) (xy 47.51324 -362.85424) (xy 47.512759 -362.881491) (xy 47.504998 -362.935437)
			(xy 47.48964 -362.98773) (xy 47.466996 -363.037305) (xy 47.437529 -363.083154) (xy 47.401837 -363.124343)
			(xy 47.360647 -363.160034) (xy 47.314798 -363.1895) (xy 47.265222 -363.212143) (xy 47.212929 -363.2275)
			(xy 47.158983 -363.23526) (xy 47.131732 -363.235748) (xy 47.104362 -363.235276) (xy 47.050183 -363.227461)
			(xy 46.997679 -363.211974) (xy 46.947932 -363.189134) (xy 46.901965 -363.159409) (xy 46.881034 -363.141768)
			(xy 46.88078 -363.141514) (xy 46.873702 -363.135914) (xy 46.856779 -363.129675) (xy 46.84776 -363.129322)
			(xy 46.780704 -363.129322) (xy 46.771687 -363.129676) (xy 46.754769 -363.135925) (xy 46.747684 -363.141514)
			(xy 46.747684 -363.141768) (xy 46.74743 -363.141768) (xy 46.726493 -363.159402) (xy 46.680522 -363.189115)
			(xy 46.630776 -363.211953) (xy 46.578276 -363.227445) (xy 46.524101 -363.235274) (xy 46.496732 -363.235748)
			(xy 46.469483 -363.235192) (xy 46.41554 -363.227441) (xy 46.363249 -363.212092) (xy 46.313675 -363.189457)
			(xy 46.267826 -363.159998) (xy 46.226637 -363.124314) (xy 46.190945 -363.083131) (xy 46.161477 -363.037288)
			(xy 46.138833 -362.987718) (xy 46.123474 -362.93543) (xy 46.115713 -362.881489) (xy 46.115224 -362.85424)
			(xy 38.070028 -362.85424) (xy 38.070028 -365.496602) (xy 38.070454 -365.506646) (xy 38.078163 -365.525196)
			(xy 38.0924 -365.539368) (xy 38.101524 -365.543592) (xy 38.115748 -365.549688) (xy 38.14572 -365.543592)
			(xy 39.230046 -364.459266) (xy 39.241883 -364.447912) (xy 39.268791 -364.429162) (xy 39.298589 -364.415463)
			(xy 39.314374 -364.411006) (xy 39.323607 -364.408129) (xy 39.339147 -364.396641) (xy 39.3446 -364.388654)
			(xy 39.359619 -364.365475) (xy 39.395284 -364.323304) (xy 39.436663 -364.286722) (xy 39.482889 -364.256495)
			(xy 39.532993 -364.233257) (xy 39.585926 -364.217494) (xy 39.640581 -364.209536) (xy 39.668196 -364.209076)
			(xy 39.69545 -364.209539) (xy 39.749404 -364.217295) (xy 39.801704 -364.232652) (xy 39.851287 -364.255295)
			(xy 39.897143 -364.284764) (xy 39.938338 -364.320459) (xy 39.974033 -364.361654) (xy 40.003503 -364.407509)
			(xy 40.026147 -364.457092) (xy 40.041504 -364.509392) (xy 40.049261 -364.563346) (xy 40.049261 -364.617854)
			(xy 40.041504 -364.671808) (xy 40.026147 -364.724108) (xy 40.003503 -364.773691) (xy 39.974033 -364.819546)
			(xy 39.938338 -364.860741) (xy 39.897143 -364.896436) (xy 39.851287 -364.925905) (xy 39.801704 -364.948548)
			(xy 39.749404 -364.963905) (xy 39.69545 -364.971661) (xy 39.668196 -364.972092) (xy 39.639944 -364.971581)
			(xy 39.584057 -364.963245) (xy 39.530011 -364.946758) (xy 39.478989 -364.922479) (xy 39.432105 -364.89094)
			(xy 39.410894 -364.87227) (xy 39.395908 -364.858554) (xy 39.355268 -364.859316) (xy 38.64991 -365.564674)
			(xy 38.643239 -365.572076) (xy 38.635661 -365.590484) (xy 38.635676 -365.610391) (xy 38.638988 -365.619792)
			(xy 38.64483 -365.63427) (xy 38.670484 -365.651288) (xy 39.786306 -365.651288) (xy 39.8145 -365.627412)
			(xy 39.817548 -365.609124) (xy 39.82281 -365.58163) (xy 39.840656 -365.528574) (xy 39.866413 -365.478876)
			(xy 39.899473 -365.433705) (xy 39.918894 -365.413544) (xy 39.979092 -365.353346) (xy 39.999719 -365.333486)
			(xy 40.046056 -365.299853) (xy 40.09709 -365.273893) (xy 40.151559 -365.256247) (xy 40.179752 -365.251238)
			(xy 40.188134 -365.248952) (xy 40.217802 -365.23957) (xy 40.279198 -365.229484) (xy 40.310308 -365.228886)
			(xy 40.310816 -365.228886) (xy 40.338129 -365.229348) (xy 40.392196 -365.237131) (xy 40.4446 -365.252549)
			(xy 40.494267 -365.275288) (xy 40.540181 -365.304881) (xy 40.581403 -365.340723) (xy 40.617088 -365.382081)
			(xy 40.646507 -365.428107) (xy 40.669056 -365.477861) (xy 40.684275 -365.530323) (xy 40.688514 -365.557308)
			(xy 40.690206 -365.566603) (xy 40.699472 -365.583052) (xy 40.706548 -365.589312) (xy 40.75938 -365.633)
			(xy 40.766925 -365.638772) (xy 40.784933 -365.64478) (xy 40.794432 -365.644684) (xy 40.813736 -365.644176)
			(xy 40.831044 -365.644394) (xy 40.865514 -365.647575) (xy 40.88257 -365.650526) (xy 40.887142 -365.651288)
			(xy 61.794644 -365.651288) (xy 61.804677 -365.650851) (xy 61.823253 -365.643278) (xy 61.830712 -365.636556)
			(xy 61.915802 -365.551212) (xy 61.923226 -365.544433) (xy 61.941823 -365.536838) (xy 61.95187 -365.53648)
			(xy 73.47585 -365.53648) (xy 73.485916 -365.536047) (xy 73.504505 -365.528318) (xy 73.511918 -365.521494)
			(xy 81.954878 -357.078534) (xy 81.962279 -357.071696) (xy 81.980878 -357.063985) (xy 81.990946 -357.063548)
			(xy 92.38488 -357.063548) (xy 92.390747 -357.063394) (xy 92.402165 -357.060692) (xy 92.407486 -357.058214)
			(xy 95.216218 -355.662992) (xy 95.221806 -355.65969) (xy 114.800888 -342.577166) (xy 114.835499 -342.553443)
			(xy 114.900369 -342.500209) (xy 114.959707 -342.440871) (xy 115.012941 -342.376001) (xy 115.059559 -342.306225)
			(xy 115.09911 -342.232213) (xy 115.115594 -342.193626) (xy 115.884706 -340.336378) (xy 115.886502 -340.331691)
			(xy 115.888416 -340.321839) (xy 115.888516 -340.31682) (xy 115.888516 -338.67852) (xy 115.887754 -338.669376)
			(xy 115.538504 -336.727292) (xy 115.536486 -336.718354) (xy 115.527084 -336.702643) (xy 115.51276 -336.691237)
			(xy 115.495342 -336.685592) (xy 115.48618 -336.685636) (xy 115.469162 -336.68589) (xy 115.441913 -336.685401)
			(xy 115.38797 -336.67764) (xy 115.335681 -336.662282) (xy 115.28611 -336.639638) (xy 115.240266 -336.61017)
			(xy 115.199082 -336.574479) (xy 115.163396 -336.533289) (xy 115.133935 -336.487441) (xy 115.111299 -336.437866)
			(xy 115.095948 -336.385575) (xy 115.088195 -336.331631) (xy 115.087654 -336.304382) (xy 115.088103 -336.277684)
			(xy 115.095558 -336.224812) (xy 115.110319 -336.173498) (xy 115.132098 -336.124746) (xy 115.160468 -336.079512)
			(xy 115.194873 -336.038679) (xy 115.234641 -336.003048) (xy 115.278992 -335.973316) (xy 115.327059 -335.950065)
			(xy 115.352322 -335.941416) (xy 115.360888 -335.938201) (xy 115.375159 -335.926772) (xy 115.384527 -335.911071)
			(xy 115.387808 -335.893085) (xy 115.386612 -335.884012) (xy 114.516408 -331.043788) (xy 114.514793 -331.036236)
			(xy 114.507683 -331.022533) (xy 114.502438 -331.016864) (xy 111.359188 -327.873614) (xy 111.351789 -327.866768)
			(xy 111.333191 -327.859036) (xy 111.32312 -327.858628) (xy 111.246666 -327.858628) (xy 111.229648 -327.864978)
			(xy 111.22279 -327.871074) (xy 111.201919 -327.888477) (xy 111.156175 -327.917809) (xy 111.106726 -327.940342)
			(xy 111.054577 -327.955619) (xy 111.000786 -327.96333) (xy 110.973616 -327.963784) (xy 110.973362 -327.963784)
			(xy 110.946192 -327.963307) (xy 110.892402 -327.955599) (xy 110.840251 -327.94033) (xy 110.790797 -327.91781)
			(xy 110.745043 -327.888495) (xy 110.724188 -327.871074) (xy 110.717066 -327.865392) (xy 110.700016 -327.859011)
			(xy 110.690914 -327.858628) (xy 107.000802 -327.858628) (xy 106.990643 -327.859069) (xy 106.971904 -327.866921)
			(xy 106.96448 -327.873868) (xy 106.906568 -327.93305) (xy 106.898948 -327.9521) (xy 106.899202 -327.96226)
			(xy 106.899202 -327.969626) (xy 106.898714 -327.996876) (xy 106.890955 -328.05082) (xy 106.875597 -328.103112)
			(xy 106.852955 -328.152685) (xy 106.823488 -328.198532) (xy 106.787796 -328.239719) (xy 106.746606 -328.275407)
			(xy 106.700757 -328.30487) (xy 106.651182 -328.327509) (xy 106.598889 -328.342862) (xy 106.544944 -328.350617)
			(xy 106.517694 -328.351134) (xy 106.490324 -328.350662) (xy 106.436148 -328.342836) (xy 106.383646 -328.327346)
			(xy 106.333898 -328.30451) (xy 106.287925 -328.274798) (xy 106.266996 -328.257154) (xy 106.266742 -328.257154)
			(xy 106.266742 -328.2569) (xy 106.259657 -328.251309) (xy 106.24274 -328.245053) (xy 106.233722 -328.244708)
			(xy 106.166666 -328.244708) (xy 106.157652 -328.245073) (xy 106.140744 -328.25133) (xy 106.133646 -328.2569)
			(xy 106.133392 -328.257154) (xy 106.112459 -328.274795) (xy 106.066491 -328.304519) (xy 106.016745 -328.327365)
			(xy 105.964243 -328.342861) (xy 105.910065 -328.35069) (xy 105.855323 -328.35069) (xy 105.801145 -328.342861)
			(xy 105.748643 -328.327365) (xy 105.698897 -328.304519) (xy 105.652929 -328.274795) (xy 105.631996 -328.257154)
			(xy 105.631742 -328.257154) (xy 105.631742 -328.2569) (xy 105.624657 -328.251309) (xy 105.60774 -328.245053)
			(xy 105.598722 -328.244708) (xy 105.531666 -328.244708) (xy 105.522652 -328.245073) (xy 105.505744 -328.25133)
			(xy 105.498646 -328.2569) (xy 105.498392 -328.257154) (xy 105.477461 -328.274797) (xy 105.431496 -328.304526)
			(xy 105.381749 -328.327371) (xy 105.329245 -328.342862) (xy 105.275065 -328.350681) (xy 105.247694 -328.351134)
			(xy 105.220442 -328.350648) (xy 105.166494 -328.342891) (xy 105.114198 -328.327535) (xy 105.06462 -328.304894)
			(xy 105.018769 -328.275428) (xy 104.977577 -328.239737) (xy 104.941884 -328.198547) (xy 104.912415 -328.152697)
			(xy 104.889772 -328.10312) (xy 104.874413 -328.050826) (xy 104.866654 -327.996878) (xy 104.866186 -327.969626)
			(xy 104.866186 -327.96226) (xy 104.86644 -327.9521) (xy 104.85882 -327.93305) (xy 104.800908 -327.873868)
			(xy 104.793481 -327.866923) (xy 104.774745 -327.859068) (xy 104.764586 -327.858628) (xy 102.960932 -327.858628)
			(xy 102.950488 -327.859197) (xy 102.931356 -327.8676) (xy 102.923848 -327.874884) (xy 102.873048 -327.929494)
			(xy 102.866333 -327.937416) (xy 102.859365 -327.956958) (xy 102.859586 -327.96734) (xy 102.859586 -327.967594)
			(xy 102.860602 -327.995026) (xy 102.860114 -328.022276) (xy 102.852355 -328.07622) (xy 102.836997 -328.128512)
			(xy 102.814355 -328.178085) (xy 102.784888 -328.223932) (xy 102.749196 -328.265119) (xy 102.708006 -328.300807)
			(xy 102.662157 -328.33027) (xy 102.612582 -328.352909) (xy 102.560289 -328.368262) (xy 102.506344 -328.376017)
			(xy 102.479094 -328.376534) (xy 102.451724 -328.376062) (xy 102.397548 -328.368236) (xy 102.345046 -328.352746)
			(xy 102.295298 -328.32991) (xy 102.249325 -328.300198) (xy 102.228396 -328.282554) (xy 102.228142 -328.282554)
			(xy 102.228142 -328.2823) (xy 102.221057 -328.276709) (xy 102.20414 -328.270453) (xy 102.195122 -328.270108)
			(xy 102.128066 -328.270108) (xy 102.119052 -328.270473) (xy 102.102144 -328.27673) (xy 102.095046 -328.2823)
			(xy 102.094792 -328.282554) (xy 102.073859 -328.300195) (xy 102.027891 -328.329919) (xy 101.978145 -328.352765)
			(xy 101.925643 -328.368261) (xy 101.871465 -328.37609) (xy 101.816723 -328.37609) (xy 101.762545 -328.368261)
			(xy 101.710043 -328.352765) (xy 101.660297 -328.329919) (xy 101.614329 -328.300195) (xy 101.593396 -328.282554)
			(xy 101.593142 -328.282554) (xy 101.593142 -328.2823) (xy 101.586057 -328.276709) (xy 101.56914 -328.270453)
			(xy 101.560122 -328.270108) (xy 101.493066 -328.270108) (xy 101.484052 -328.270473) (xy 101.467144 -328.27673)
			(xy 101.460046 -328.2823) (xy 101.459792 -328.282554) (xy 101.438861 -328.300197) (xy 101.392896 -328.329926)
			(xy 101.343149 -328.352771) (xy 101.290645 -328.368262) (xy 101.236465 -328.376081) (xy 101.209094 -328.376534)
			(xy 101.181842 -328.376048) (xy 101.127894 -328.368291) (xy 101.075598 -328.352935) (xy 101.02602 -328.330294)
			(xy 100.980169 -328.300828) (xy 100.938977 -328.265137) (xy 100.903284 -328.223947) (xy 100.873815 -328.178097)
			(xy 100.851172 -328.12852) (xy 100.835813 -328.076226) (xy 100.828054 -328.022278) (xy 100.827586 -327.995026)
			(xy 100.828602 -327.967594) (xy 100.828602 -327.96734) (xy 100.828775 -327.956966) (xy 100.821814 -327.937441)
			(xy 100.81514 -327.929494) (xy 100.76434 -327.874884) (xy 100.756871 -327.867542) (xy 100.737716 -327.859132)
			(xy 100.727256 -327.858628) (xy 81.345024 -327.858628) (xy 81.334961 -327.859066) (xy 81.316379 -327.866803)
			(xy 81.308956 -327.873614) (xy 78.61427 -330.5683) (xy 78.60687 -330.575142) (xy 78.588272 -330.582865)
			(xy 78.578202 -330.583286) (xy 70.538848 -330.583286) (xy 70.528782 -330.583718) (xy 70.51019 -330.591444)
			(xy 70.50278 -330.598272) (xy 64.44615 -336.654902) (xy 66.344546 -336.654902) (xy 66.345051 -336.626992)
			(xy 66.353184 -336.571767) (xy 66.369277 -336.518317) (xy 66.392987 -336.467782) (xy 66.423807 -336.421241)
			(xy 66.442082 -336.40014) (xy 66.448002 -336.392979) (xy 66.45464 -336.375642) (xy 66.455036 -336.366358)
			(xy 66.455036 -336.288634) (xy 66.448432 -336.271362) (xy 66.442082 -336.26425) (xy 66.423803 -336.243151)
			(xy 66.392977 -336.196612) (xy 66.369262 -336.146077) (xy 66.353165 -336.092626) (xy 66.345031 -336.037399)
			(xy 66.344546 -336.009488) (xy 66.345032 -335.982237) (xy 66.352788 -335.928289) (xy 66.368143 -335.875994)
			(xy 66.390785 -335.826417) (xy 66.420251 -335.780567) (xy 66.455942 -335.739376) (xy 66.497133 -335.703685)
			(xy 66.542983 -335.674219) (xy 66.59256 -335.651577) (xy 66.644855 -335.636222) (xy 66.698803 -335.628466)
			(xy 66.753305 -335.628466) (xy 66.807253 -335.636222) (xy 66.859548 -335.651577) (xy 66.909125 -335.674219)
			(xy 66.954975 -335.703685) (xy 66.996166 -335.739376) (xy 67.031857 -335.780567) (xy 67.061323 -335.826417)
			(xy 67.083965 -335.875994) (xy 67.09932 -335.928289) (xy 67.107076 -335.982237) (xy 67.107562 -336.009488)
			(xy 67.107049 -336.037398) (xy 67.098918 -336.092622) (xy 67.082826 -336.146072) (xy 67.059118 -336.196607)
			(xy 67.0283 -336.243149) (xy 67.010026 -336.26425) (xy 67.004111 -336.271415) (xy 66.99747 -336.288749)
			(xy 66.997072 -336.298032) (xy 66.997072 -336.375756) (xy 67.003676 -336.393028) (xy 67.010026 -336.40014)
			(xy 67.028301 -336.421242) (xy 67.059128 -336.46778) (xy 67.082844 -336.518314) (xy 67.098941 -336.571765)
			(xy 67.107076 -336.626991) (xy 67.107562 -336.654902) (xy 67.107076 -336.682153) (xy 67.09932 -336.736101)
			(xy 67.083965 -336.788396) (xy 67.061323 -336.837973) (xy 67.031857 -336.883823) (xy 66.996166 -336.925014)
			(xy 66.954975 -336.960705) (xy 66.911881 -336.9884) (xy 70.726737 -336.9884) (xy 70.730906 -336.93278)
			(xy 70.743318 -336.878402) (xy 70.763696 -336.826482) (xy 70.791586 -336.778179) (xy 70.826364 -336.734573)
			(xy 70.867252 -336.696638) (xy 70.913338 -336.66522) (xy 70.963593 -336.641023) (xy 71.016892 -336.624587)
			(xy 71.072046 -336.616279) (xy 71.099934 -336.615786) (xy 71.126356 -336.616227) (xy 71.178672 -336.623682)
			(xy 71.229411 -336.638451) (xy 71.277555 -336.660238) (xy 71.322139 -336.688607) (xy 71.342504 -336.705448)
			(xy 71.349362 -336.71129) (xy 71.36638 -336.71764) (xy 71.450708 -336.71764) (xy 71.467726 -336.71129)
			(xy 71.474584 -336.705448) (xy 71.49495 -336.688609) (xy 71.539536 -336.660244) (xy 71.58768 -336.638457)
			(xy 71.638417 -336.623686) (xy 71.690732 -336.616226) (xy 71.743576 -336.616226) (xy 71.795891 -336.623686)
			(xy 71.846628 -336.638457) (xy 71.894772 -336.660244) (xy 71.939358 -336.688609) (xy 71.959724 -336.705448)
			(xy 71.966582 -336.71129) (xy 71.9836 -336.71764) (xy 72.067928 -336.71764) (xy 72.084946 -336.71129)
			(xy 72.091804 -336.705448) (xy 72.114863 -336.686472) (xy 72.165817 -336.655339) (xy 72.221092 -336.632749)
			(xy 72.250046 -336.625438) (xy 72.262238 -336.622644) (xy 72.281288 -336.606134) (xy 72.320658 -336.503772)
			(xy 72.31761 -336.47888) (xy 72.310244 -336.468466) (xy 72.294537 -336.444928) (xy 72.269667 -336.3941)
			(xy 72.252765 -336.340098) (xy 72.244219 -336.284161) (xy 72.243696 -336.255868) (xy 72.244204 -336.228226)
			(xy 72.252358 -336.173546) (xy 72.268498 -336.120671) (xy 72.292271 -336.070759) (xy 72.323153 -336.024905)
			(xy 72.360469 -335.984114) (xy 72.381618 -335.966308) (xy 72.390048 -335.958715) (xy 72.399807 -335.938267)
			(xy 72.400414 -335.926938) (xy 72.400414 -335.848198) (xy 72.399784 -335.836877) (xy 72.390021 -335.816442)
			(xy 72.381618 -335.808828) (xy 72.360486 -335.791003) (xy 72.323176 -335.750211) (xy 72.292295 -335.70436)
			(xy 72.26852 -335.654452) (xy 72.252371 -335.601583) (xy 72.244202 -335.546908) (xy 72.243696 -335.519268)
			(xy 72.244217 -335.491383) (xy 72.252529 -335.436236) (xy 72.268967 -335.382944) (xy 72.293165 -335.332698)
			(xy 72.324581 -335.286619) (xy 72.362514 -335.245737) (xy 72.406116 -335.210965) (xy 72.454414 -335.18308)
			(xy 72.506329 -335.162705) (xy 72.5607 -335.150295) (xy 72.616314 -335.146128) (xy 72.671928 -335.150295)
			(xy 72.726299 -335.162705) (xy 72.778214 -335.18308) (xy 72.826512 -335.210965) (xy 72.870114 -335.245737)
			(xy 72.908047 -335.286619) (xy 72.939463 -335.332698) (xy 72.963661 -335.382944) (xy 72.980099 -335.436236)
			(xy 72.988411 -335.491383) (xy 72.988932 -335.519268) (xy 72.98844 -335.546911) (xy 72.98028 -335.60159)
			(xy 72.964136 -335.654466) (xy 72.940361 -335.704377) (xy 72.909477 -335.750231) (xy 72.872159 -335.791022)
			(xy 72.85101 -335.808828) (xy 72.842568 -335.81641) (xy 72.832814 -335.836866) (xy 72.832214 -335.848198)
			(xy 72.832214 -335.926938) (xy 72.832848 -335.938258) (xy 72.842611 -335.958691) (xy 72.85101 -335.966308)
			(xy 72.872144 -335.98413) (xy 72.909457 -336.024921) (xy 72.94034 -336.070772) (xy 72.964115 -336.12068)
			(xy 72.980263 -336.173551) (xy 72.988428 -336.228227) (xy 72.988932 -336.255868) (xy 72.988393 -336.283672)
			(xy 72.980133 -336.338664) (xy 72.963792 -336.391817) (xy 72.939733 -336.441952) (xy 72.90849 -336.487954)
			(xy 72.870758 -336.528802) (xy 72.827373 -336.563589) (xy 72.779301 -336.591541) (xy 72.727608 -336.612039)
			(xy 72.700642 -336.618834) (xy 72.68845 -336.621628) (xy 72.6694 -336.638138) (xy 72.665688 -336.64779)
			(xy 74.70013 -336.64779) (xy 74.700632 -336.61988) (xy 74.708766 -336.564655) (xy 74.724861 -336.511205)
			(xy 74.748571 -336.46067) (xy 74.779391 -336.414129) (xy 74.797666 -336.393028) (xy 74.803559 -336.385848)
			(xy 74.810211 -336.368525) (xy 74.81062 -336.359246) (xy 74.81062 -336.281522) (xy 74.804016 -336.26425)
			(xy 74.797666 -336.257138) (xy 74.779379 -336.236046) (xy 74.748554 -336.189505) (xy 74.724841 -336.138968)
			(xy 74.708747 -336.085516) (xy 74.700614 -336.030288) (xy 74.70013 -336.002376) (xy 74.700616 -335.975125)
			(xy 74.708372 -335.921177) (xy 74.723727 -335.868882) (xy 74.746369 -335.819305) (xy 74.775835 -335.773455)
			(xy 74.811526 -335.732264) (xy 74.852717 -335.696573) (xy 74.898567 -335.667107) (xy 74.948144 -335.644465)
			(xy 75.000439 -335.62911) (xy 75.054387 -335.621354) (xy 75.108889 -335.621354) (xy 75.162837 -335.62911)
			(xy 75.215132 -335.644465) (xy 75.264709 -335.667107) (xy 75.310559 -335.696573) (xy 75.35175 -335.732264)
			(xy 75.387441 -335.773455) (xy 75.416907 -335.819305) (xy 75.439549 -335.868882) (xy 75.454904 -335.921177)
			(xy 75.46266 -335.975125) (xy 75.463146 -336.002376) (xy 75.46263 -336.030286) (xy 75.4545 -336.08551)
			(xy 75.438409 -336.13896) (xy 75.414702 -336.189496) (xy 75.383884 -336.236037) (xy 75.36561 -336.257138)
			(xy 75.359698 -336.264305) (xy 75.353056 -336.281638) (xy 75.352656 -336.29092) (xy 75.352656 -336.368644)
			(xy 75.35926 -336.385916) (xy 75.36561 -336.393028) (xy 75.383877 -336.414137) (xy 75.414706 -336.460673)
			(xy 75.438423 -336.511205) (xy 75.454522 -336.564654) (xy 75.462659 -336.619879) (xy 75.463146 -336.64779)
			(xy 75.46266 -336.675041) (xy 75.454904 -336.728989) (xy 75.439549 -336.781284) (xy 75.416907 -336.830861)
			(xy 75.387441 -336.876711) (xy 75.35175 -336.917902) (xy 75.310559 -336.953593) (xy 75.267446 -336.9813)
			(xy 79.082325 -336.9813) (xy 79.086494 -336.92568) (xy 79.098906 -336.871302) (xy 79.119284 -336.819381)
			(xy 79.147173 -336.771078) (xy 79.18195 -336.727471) (xy 79.222838 -336.689534) (xy 79.268923 -336.658115)
			(xy 79.319177 -336.633917) (xy 79.372476 -336.617478) (xy 79.42763 -336.609168) (xy 79.455518 -336.608674)
			(xy 79.48194 -336.609127) (xy 79.534255 -336.616579) (xy 79.584994 -336.631346) (xy 79.633138 -336.65313)
			(xy 79.677723 -336.681496) (xy 79.698088 -336.698336) (xy 79.704946 -336.704178) (xy 79.721964 -336.710528)
			(xy 79.806292 -336.710528) (xy 79.82331 -336.704178) (xy 79.830168 -336.698336) (xy 79.850534 -336.681497)
			(xy 79.89512 -336.653132) (xy 79.943264 -336.631345) (xy 79.994001 -336.616574) (xy 80.046316 -336.609114)
			(xy 80.09916 -336.609114) (xy 80.151475 -336.616574) (xy 80.202212 -336.631345) (xy 80.250356 -336.653132)
			(xy 80.294942 -336.681497) (xy 80.315308 -336.698336) (xy 80.322166 -336.704178) (xy 80.339184 -336.710528)
			(xy 80.423512 -336.710528) (xy 80.44053 -336.704178) (xy 80.447388 -336.698336) (xy 80.471196 -336.678767)
			(xy 80.523961 -336.646931) (xy 80.581236 -336.624189) (xy 80.611218 -336.617056) (xy 80.62341 -336.614516)
			(xy 80.642968 -336.598006) (xy 80.683354 -336.495136) (xy 80.680306 -336.470244) (xy 80.67294 -336.459576)
			(xy 80.657025 -336.435937) (xy 80.631775 -336.384853) (xy 80.614606 -336.330517) (xy 80.60592 -336.2742)
			(xy 80.605376 -336.245708) (xy 80.605919 -336.218067) (xy 80.614067 -336.16339) (xy 80.630201 -336.110515)
			(xy 80.653967 -336.060603) (xy 80.684843 -336.014748) (xy 80.722152 -335.973956) (xy 80.743298 -335.956148)
			(xy 80.751752 -335.948578) (xy 80.761499 -335.928113) (xy 80.762094 -335.916778) (xy 80.762094 -335.838038)
			(xy 80.761415 -335.826724) (xy 80.751684 -335.80629) (xy 80.743298 -335.798668) (xy 80.722154 -335.780857)
			(xy 80.684841 -335.740064) (xy 80.65396 -335.694211) (xy 80.630186 -335.6443) (xy 80.614041 -335.591427)
			(xy 80.605878 -335.53675) (xy 80.605376 -335.509108) (xy 80.605897 -335.481223) (xy 80.614209 -335.426076)
			(xy 80.630647 -335.372784) (xy 80.654845 -335.322538) (xy 80.686261 -335.276459) (xy 80.724194 -335.235577)
			(xy 80.767796 -335.200805) (xy 80.816094 -335.17292) (xy 80.868009 -335.152545) (xy 80.92238 -335.140135)
			(xy 80.977994 -335.135968) (xy 81.033608 -335.140135) (xy 81.087979 -335.152545) (xy 81.139894 -335.17292)
			(xy 81.188192 -335.200805) (xy 81.231794 -335.235577) (xy 81.269727 -335.276459) (xy 81.301143 -335.322538)
			(xy 81.325341 -335.372784) (xy 81.341779 -335.426076) (xy 81.350091 -335.481223) (xy 81.350612 -335.509108)
			(xy 81.350085 -335.536749) (xy 81.341934 -335.591428) (xy 81.325797 -335.644303) (xy 81.302029 -335.694215)
			(xy 81.27115 -335.74007) (xy 81.233837 -335.780861) (xy 81.21269 -335.798668) (xy 81.204272 -335.806272)
			(xy 81.194506 -335.826711) (xy 81.193894 -335.838038) (xy 81.193894 -335.916778) (xy 81.194568 -335.928093)
			(xy 81.204304 -335.948526) (xy 81.21269 -335.956148) (xy 81.23386 -335.973929) (xy 81.271167 -336.014731)
			(xy 81.302043 -336.060591) (xy 81.325812 -336.110507) (xy 81.341952 -336.163384) (xy 81.350111 -336.218065)
			(xy 81.350612 -336.245708) (xy 81.350052 -336.273832) (xy 81.34161 -336.329444) (xy 81.324904 -336.383154)
			(xy 81.300313 -336.433743) (xy 81.268398 -336.48006) (xy 81.229882 -336.521053) (xy 81.185641 -336.55579)
			(xy 81.136681 -336.583482) (xy 81.084115 -336.603499) (xy 81.056734 -336.609944) (xy 81.044542 -336.612484)
			(xy 81.024984 -336.628994) (xy 81.023289 -336.633312) (xy 83.057746 -336.633312) (xy 83.058257 -336.605402)
			(xy 83.066389 -336.550177) (xy 83.08248 -336.496727) (xy 83.106189 -336.446192) (xy 83.137008 -336.399651)
			(xy 83.155282 -336.37855) (xy 83.161198 -336.371386) (xy 83.167838 -336.354051) (xy 83.168236 -336.344768)
			(xy 83.168236 -336.267044) (xy 83.161632 -336.249772) (xy 83.155282 -336.24266) (xy 83.137008 -336.221557)
			(xy 83.106181 -336.175019) (xy 83.082465 -336.124486) (xy 83.066367 -336.071035) (xy 83.058232 -336.015809)
			(xy 83.057746 -335.987898) (xy 83.058232 -335.960647) (xy 83.065988 -335.906699) (xy 83.081343 -335.854404)
			(xy 83.103985 -335.804827) (xy 83.133451 -335.758977) (xy 83.169142 -335.717786) (xy 83.210333 -335.682095)
			(xy 83.256183 -335.652629) (xy 83.30576 -335.629987) (xy 83.358055 -335.614632) (xy 83.412003 -335.606876)
			(xy 83.466505 -335.606876) (xy 83.520453 -335.614632) (xy 83.572748 -335.629987) (xy 83.622325 -335.652629)
			(xy 83.668175 -335.682095) (xy 83.709366 -335.717786) (xy 83.745057 -335.758977) (xy 83.774523 -335.804827)
			(xy 83.797165 -335.854404) (xy 83.81252 -335.906699) (xy 83.820276 -335.960647) (xy 83.820762 -335.987898)
			(xy 83.820255 -336.015808) (xy 83.812122 -336.071033) (xy 83.796029 -336.124483) (xy 83.77232 -336.175018)
			(xy 83.7415 -336.221559) (xy 83.723226 -336.24266) (xy 83.717307 -336.249822) (xy 83.710668 -336.267159)
			(xy 83.710272 -336.276442) (xy 83.710272 -336.354166) (xy 83.716876 -336.371438) (xy 83.723226 -336.37855)
			(xy 83.741506 -336.399648) (xy 83.772332 -336.446187) (xy 83.796047 -336.496722) (xy 83.812143 -336.550174)
			(xy 83.820277 -336.605401) (xy 83.820762 -336.633312) (xy 83.820276 -336.660563) (xy 83.81252 -336.714511)
			(xy 83.797165 -336.766806) (xy 83.774523 -336.816383) (xy 83.745057 -336.862233) (xy 83.709366 -336.903424)
			(xy 83.668175 -336.939115) (xy 83.625096 -336.9668) (xy 87.439947 -336.9668) (xy 87.444116 -336.911181)
			(xy 87.456528 -336.856805) (xy 87.476905 -336.804886) (xy 87.504794 -336.756585) (xy 87.539571 -336.71298)
			(xy 87.580458 -336.675045) (xy 87.626543 -336.643629) (xy 87.676796 -336.619433) (xy 87.730094 -336.602997)
			(xy 87.785247 -336.594688) (xy 87.813134 -336.594196) (xy 87.839556 -336.594635) (xy 87.891873 -336.60209)
			(xy 87.942611 -336.616859) (xy 87.990755 -336.638647) (xy 88.035339 -336.667017) (xy 88.055704 -336.683858)
			(xy 88.062562 -336.6897) (xy 88.07958 -336.69605) (xy 88.163908 -336.69605) (xy 88.180926 -336.6897)
			(xy 88.187784 -336.683858) (xy 88.20815 -336.667019) (xy 88.252736 -336.638654) (xy 88.30088 -336.616867)
			(xy 88.351617 -336.602096) (xy 88.403932 -336.594636) (xy 88.456776 -336.594636) (xy 88.509091 -336.602096)
			(xy 88.559828 -336.616867) (xy 88.607972 -336.638654) (xy 88.652558 -336.667019) (xy 88.672924 -336.683858)
			(xy 88.679782 -336.6897) (xy 88.6968 -336.69605) (xy 88.781128 -336.69605) (xy 88.798146 -336.6897)
			(xy 88.805004 -336.683858) (xy 88.825835 -336.666667) (xy 88.871508 -336.637844) (xy 88.920863 -336.615915)
			(xy 88.946736 -336.608166) (xy 88.95842 -336.604864) (xy 88.9762 -336.588608) (xy 89.009474 -336.501232)
			(xy 89.01313 -336.489877) (xy 89.010739 -336.46617) (xy 89.004902 -336.455766) (xy 88.99112 -336.43326)
			(xy 88.969376 -336.385174) (xy 88.954635 -336.334501) (xy 88.947192 -336.282255) (xy 88.946736 -336.255868)
			(xy 88.947229 -336.228225) (xy 88.955384 -336.173544) (xy 88.971527 -336.120668) (xy 88.995301 -336.070755)
			(xy 89.026187 -336.024902) (xy 89.063507 -335.984113) (xy 89.084658 -335.966308) (xy 89.093079 -335.958705)
			(xy 89.102846 -335.938266) (xy 89.103454 -335.926938) (xy 89.103454 -335.848198) (xy 89.102811 -335.836879)
			(xy 89.093055 -335.816445) (xy 89.084658 -335.808828) (xy 89.063534 -335.790994) (xy 89.026222 -335.750205)
			(xy 88.995339 -335.704356) (xy 88.971562 -335.65445) (xy 88.955412 -335.601581) (xy 88.947242 -335.546908)
			(xy 88.946736 -335.519268) (xy 88.947257 -335.491383) (xy 88.955569 -335.436236) (xy 88.972007 -335.382944)
			(xy 88.996205 -335.332698) (xy 89.027621 -335.286619) (xy 89.065554 -335.245737) (xy 89.109156 -335.210965)
			(xy 89.157454 -335.18308) (xy 89.209369 -335.162705) (xy 89.26374 -335.150295) (xy 89.319354 -335.146128)
			(xy 89.374968 -335.150295) (xy 89.429339 -335.162705) (xy 89.481254 -335.18308) (xy 89.529552 -335.210965)
			(xy 89.573154 -335.245737) (xy 89.611087 -335.286619) (xy 89.642503 -335.332698) (xy 89.666701 -335.382944)
			(xy 89.683139 -335.436236) (xy 89.691451 -335.491383) (xy 89.691972 -335.519268) (xy 89.691502 -335.546912)
			(xy 89.683341 -335.601593) (xy 89.667194 -335.65447) (xy 89.643415 -335.704382) (xy 89.612525 -335.750235)
			(xy 89.575202 -335.791023) (xy 89.55405 -335.808828) (xy 89.545615 -335.816417) (xy 89.535855 -335.836867)
			(xy 89.535254 -335.848198) (xy 89.535254 -335.926938) (xy 89.535874 -335.93826) (xy 89.545645 -335.958694)
			(xy 89.55405 -335.966308) (xy 89.575192 -335.984121) (xy 89.612503 -336.024914) (xy 89.643384 -336.070768)
			(xy 89.667157 -336.120678) (xy 89.683303 -336.17355) (xy 89.691468 -336.228227) (xy 89.691972 -336.255868)
			(xy 89.69155 -336.282722) (xy 89.683817 -336.335871) (xy 89.668536 -336.38736) (xy 89.646023 -336.436122)
			(xy 89.616744 -336.481149) (xy 89.581306 -336.521506) (xy 89.540442 -336.55636) (xy 89.494998 -336.584987)
			(xy 89.445917 -336.606796) (xy 89.420192 -336.614516) (xy 89.408508 -336.617818) (xy 89.390728 -336.634074)
			(xy 89.357454 -336.72145) (xy 89.353819 -336.732809) (xy 89.356199 -336.75651) (xy 89.362026 -336.766916)
			(xy 89.375793 -336.789431) (xy 89.397542 -336.837513) (xy 89.412288 -336.888183) (xy 89.419734 -336.940428)
			(xy 89.420192 -336.966814) (xy 89.419779 -336.993433) (xy 89.4122 -337.04613) (xy 89.397199 -337.097211)
			(xy 89.37508 -337.145638) (xy 89.346295 -337.190424) (xy 89.311429 -337.230657) (xy 89.271192 -337.265519)
			(xy 89.226403 -337.294299) (xy 89.177974 -337.316413) (xy 89.126891 -337.331408) (xy 89.074193 -337.338982)
			(xy 89.047574 -337.339432) (xy 89.021152 -337.338982) (xy 88.968837 -337.331529) (xy 88.918098 -337.316762)
			(xy 88.869954 -337.294976) (xy 88.825369 -337.26661) (xy 88.805004 -337.24977) (xy 88.798146 -337.243928)
			(xy 88.781128 -337.237578) (xy 88.6968 -337.237578) (xy 88.679782 -337.243928) (xy 88.672924 -337.24977)
			(xy 88.652558 -337.266609) (xy 88.607972 -337.294974) (xy 88.559828 -337.316761) (xy 88.509091 -337.331532)
			(xy 88.456776 -337.338992) (xy 88.403932 -337.338992) (xy 88.351617 -337.331532) (xy 88.30088 -337.316761)
			(xy 88.252736 -337.294974) (xy 88.20815 -337.266609) (xy 88.187784 -337.24977) (xy 88.180926 -337.243928)
			(xy 88.163908 -337.237578) (xy 88.07958 -337.237578) (xy 88.062562 -337.243928) (xy 88.055704 -337.24977)
			(xy 88.035333 -337.266602) (xy 87.990745 -337.294959) (xy 87.942602 -337.31674) (xy 87.891866 -337.331509)
			(xy 87.839555 -337.33897) (xy 87.813134 -337.339432) (xy 87.785247 -337.338912) (xy 87.730094 -337.330603)
			(xy 87.676796 -337.314167) (xy 87.626543 -337.289971) (xy 87.580458 -337.258555) (xy 87.539571 -337.22062)
			(xy 87.504794 -337.177015) (xy 87.476905 -337.128714) (xy 87.456528 -337.076795) (xy 87.444116 -337.022419)
			(xy 87.439947 -336.9668) (xy 83.625096 -336.9668) (xy 83.622325 -336.968581) (xy 83.572748 -336.991223)
			(xy 83.520453 -337.006578) (xy 83.466505 -337.014334) (xy 83.412003 -337.014334) (xy 83.358055 -337.006578)
			(xy 83.30576 -336.991223) (xy 83.256183 -336.968581) (xy 83.210333 -336.939115) (xy 83.169142 -336.903424)
			(xy 83.133451 -336.862233) (xy 83.103985 -336.816383) (xy 83.081343 -336.766806) (xy 83.065988 -336.714511)
			(xy 83.058232 -336.660563) (xy 83.057746 -336.633312) (xy 81.023289 -336.633312) (xy 80.984598 -336.731864)
			(xy 80.987646 -336.756756) (xy 80.995012 -336.767424) (xy 81.010922 -336.791067) (xy 81.036174 -336.842149)
			(xy 81.053345 -336.896483) (xy 81.062032 -336.9528) (xy 81.062576 -336.981292) (xy 81.062158 -337.007912)
			(xy 81.054582 -337.060609) (xy 81.039583 -337.111691) (xy 81.017466 -337.160119) (xy 80.988681 -337.204906)
			(xy 80.953816 -337.24514) (xy 80.913578 -337.280002) (xy 80.868789 -337.308782) (xy 80.820359 -337.330895)
			(xy 80.769275 -337.345889) (xy 80.716578 -337.353461) (xy 80.689958 -337.35391) (xy 80.663535 -337.353474)
			(xy 80.611219 -337.346019) (xy 80.56048 -337.331248) (xy 80.512336 -337.30946) (xy 80.467753 -337.28109)
			(xy 80.447388 -337.264248) (xy 80.44053 -337.258406) (xy 80.423512 -337.252056) (xy 80.339184 -337.252056)
			(xy 80.322166 -337.258406) (xy 80.315308 -337.264248) (xy 80.294942 -337.281087) (xy 80.250356 -337.309452)
			(xy 80.202212 -337.331239) (xy 80.151475 -337.34601) (xy 80.09916 -337.35347) (xy 80.046316 -337.35347)
			(xy 79.994001 -337.34601) (xy 79.943264 -337.331239) (xy 79.89512 -337.309452) (xy 79.850534 -337.281087)
			(xy 79.830168 -337.264248) (xy 79.82331 -337.258406) (xy 79.806292 -337.252056) (xy 79.721964 -337.252056)
			(xy 79.704946 -337.258406) (xy 79.698088 -337.264248) (xy 79.67772 -337.281084) (xy 79.633132 -337.309441)
			(xy 79.584988 -337.331221) (xy 79.534252 -337.34599) (xy 79.481939 -337.35345) (xy 79.455518 -337.35391)
			(xy 79.42763 -337.353432) (xy 79.372476 -337.345122) (xy 79.319177 -337.328683) (xy 79.268923 -337.304485)
			(xy 79.222838 -337.273066) (xy 79.18195 -337.235129) (xy 79.147173 -337.191522) (xy 79.119284 -337.143219)
			(xy 79.098906 -337.091298) (xy 79.086494 -337.03692) (xy 79.082325 -336.9813) (xy 75.267446 -336.9813)
			(xy 75.264709 -336.983059) (xy 75.215132 -337.005701) (xy 75.162837 -337.021056) (xy 75.108889 -337.028812)
			(xy 75.054387 -337.028812) (xy 75.000439 -337.021056) (xy 74.948144 -337.005701) (xy 74.898567 -336.983059)
			(xy 74.852717 -336.953593) (xy 74.811526 -336.917902) (xy 74.775835 -336.876711) (xy 74.746369 -336.830861)
			(xy 74.723727 -336.781284) (xy 74.708372 -336.728989) (xy 74.700616 -336.675041) (xy 74.70013 -336.64779)
			(xy 72.665688 -336.64779) (xy 72.63003 -336.7405) (xy 72.633078 -336.765392) (xy 72.640444 -336.775806)
			(xy 72.65615 -336.799345) (xy 72.681017 -336.850173) (xy 72.697919 -336.904175) (xy 72.706468 -336.960111)
			(xy 72.706992 -336.988404) (xy 72.706569 -337.015023) (xy 72.698992 -337.067719) (xy 72.683992 -337.118801)
			(xy 72.661875 -337.167227) (xy 72.633091 -337.212013) (xy 72.598225 -337.252247) (xy 72.557989 -337.287109)
			(xy 72.513201 -337.315889) (xy 72.464773 -337.338002) (xy 72.41369 -337.352998) (xy 72.360993 -337.360572)
			(xy 72.334374 -337.361022) (xy 72.307952 -337.360574) (xy 72.255636 -337.353121) (xy 72.204898 -337.338353)
			(xy 72.156754 -337.316568) (xy 72.112169 -337.2882) (xy 72.091804 -337.27136) (xy 72.084946 -337.265518)
			(xy 72.067928 -337.259168) (xy 71.9836 -337.259168) (xy 71.966582 -337.265518) (xy 71.959724 -337.27136)
			(xy 71.939358 -337.288199) (xy 71.894772 -337.316564) (xy 71.846628 -337.338351) (xy 71.795891 -337.353122)
			(xy 71.743576 -337.360582) (xy 71.690732 -337.360582) (xy 71.638417 -337.353122) (xy 71.58768 -337.338351)
			(xy 71.539536 -337.316564) (xy 71.49495 -337.288199) (xy 71.474584 -337.27136) (xy 71.467726 -337.265518)
			(xy 71.450708 -337.259168) (xy 71.36638 -337.259168) (xy 71.349362 -337.265518) (xy 71.342504 -337.27136)
			(xy 71.322132 -337.28819) (xy 71.277545 -337.316548) (xy 71.229401 -337.338329) (xy 71.178666 -337.353099)
			(xy 71.126355 -337.36056) (xy 71.099934 -337.361022) (xy 71.072046 -337.360521) (xy 71.016892 -337.352213)
			(xy 70.963593 -337.335777) (xy 70.913338 -337.31158) (xy 70.867252 -337.280162) (xy 70.826364 -337.242227)
			(xy 70.791586 -337.198621) (xy 70.763696 -337.150318) (xy 70.743318 -337.098398) (xy 70.730906 -337.04402)
			(xy 70.726737 -336.9884) (xy 66.911881 -336.9884) (xy 66.909125 -336.990171) (xy 66.859548 -337.012813)
			(xy 66.807253 -337.028168) (xy 66.753305 -337.035924) (xy 66.698803 -337.035924) (xy 66.644855 -337.028168)
			(xy 66.59256 -337.012813) (xy 66.542983 -336.990171) (xy 66.497133 -336.960705) (xy 66.455942 -336.925014)
			(xy 66.420251 -336.883823) (xy 66.390785 -336.837973) (xy 66.368143 -336.788396) (xy 66.352788 -336.736101)
			(xy 66.345032 -336.682153) (xy 66.344546 -336.654902) (xy 64.44615 -336.654902) (xy 63.452756 -337.648296)
			(xy 63.445355 -337.655136) (xy 63.426757 -337.662855) (xy 63.416688 -337.663282) (xy 25.622504 -337.663282)
			(xy 25.612434 -337.662859) (xy 25.59383 -337.655144) (xy 25.586436 -337.648296) (xy 24.744172 -336.806032)
			(xy 24.737329 -336.798633) (xy 24.729608 -336.780034) (xy 24.729186 -336.769964) (xy 24.729186 -330.223876)
			(xy 24.728758 -330.213808) (xy 24.721036 -330.195211) (xy 24.7142 -330.187808) (xy 24.502364 -329.975972)
			(xy 24.494967 -329.969123) (xy 24.476368 -329.961391) (xy 24.466296 -329.960986) (xy 17.035272 -329.960986)
			(xy 17.025204 -329.961414) (xy 17.006605 -329.969134) (xy 16.999204 -329.975972) (xy 16.096742 -330.878434)
			(xy 16.089897 -330.885832) (xy 16.082168 -330.904431) (xy 16.081756 -330.914502) (xy 16.081756 -333.780638)
			(xy 16.979898 -333.780638) (xy 16.983969 -333.725016) (xy 16.996095 -333.670579) (xy 17.016018 -333.618488)
			(xy 17.043314 -333.569853) (xy 17.0774 -333.52571) (xy 17.117549 -333.487001) (xy 17.162907 -333.45455)
			(xy 17.212507 -333.429049) (xy 17.265291 -333.411042) (xy 17.320134 -333.400912) (xy 17.375868 -333.398875)
			(xy 17.431305 -333.404975) (xy 17.485262 -333.419081) (xy 17.536591 -333.440893) (xy 17.584197 -333.469947)
			(xy 17.627065 -333.505622) (xy 17.664282 -333.547159) (xy 17.695055 -333.593672) (xy 17.718727 -333.644169)
			(xy 17.734795 -333.697576) (xy 17.742915 -333.752752) (xy 17.743424 -333.780638) (xy 17.742915 -333.808524)
			(xy 17.734795 -333.8637) (xy 17.718727 -333.917107) (xy 17.695055 -333.967604) (xy 17.664282 -334.014117)
			(xy 17.627065 -334.055654) (xy 17.584197 -334.091329) (xy 17.536591 -334.120383) (xy 17.485262 -334.142195)
			(xy 17.431305 -334.156301) (xy 17.375868 -334.162401) (xy 17.320134 -334.160364) (xy 17.265291 -334.150234)
			(xy 17.212507 -334.132227) (xy 17.162907 -334.106726) (xy 17.117549 -334.074275) (xy 17.0774 -334.035566)
			(xy 17.043314 -333.991423) (xy 17.016018 -333.942788) (xy 16.996095 -333.890697) (xy 16.983969 -333.83626)
			(xy 16.979898 -333.780638) (xy 16.081756 -333.780638) (xy 16.081756 -343.04605) (xy 16.08219 -343.056115)
			(xy 16.089923 -343.074701) (xy 16.096742 -343.082118) (xy 17.361916 -344.347292) (xy 17.368773 -344.354686)
			(xy 17.376523 -344.373285) (xy 17.376902 -344.38336) (xy 17.376902 -351.74936) (xy 17.377336 -351.759425)
			(xy 17.385066 -351.778014) (xy 17.391888 -351.785428) (xy 19.072098 -353.465638) (xy 21.394926 -353.465638)
			(xy 21.398997 -353.410016) (xy 21.411123 -353.355579) (xy 21.431046 -353.303488) (xy 21.458342 -353.254853)
			(xy 21.492428 -353.21071) (xy 21.532577 -353.172001) (xy 21.577935 -353.13955) (xy 21.627535 -353.114049)
			(xy 21.680319 -353.096042) (xy 21.735162 -353.085912) (xy 21.790896 -353.083875) (xy 21.846333 -353.089975)
			(xy 21.90029 -353.104081) (xy 21.951619 -353.125893) (xy 21.999225 -353.154947) (xy 22.042093 -353.190622)
			(xy 22.07931 -353.232159) (xy 22.110083 -353.278672) (xy 22.133755 -353.329169) (xy 22.149823 -353.382576)
			(xy 22.157943 -353.437752) (xy 22.158452 -353.465638) (xy 22.157943 -353.493524) (xy 22.149823 -353.5487)
			(xy 22.133755 -353.602107) (xy 22.110083 -353.652604) (xy 22.07931 -353.699117) (xy 22.042093 -353.740654)
			(xy 21.999225 -353.776329) (xy 21.951619 -353.805383) (xy 21.90029 -353.827195) (xy 21.846333 -353.841301)
			(xy 21.790896 -353.847401) (xy 21.735162 -353.845364) (xy 21.680319 -353.835234) (xy 21.627535 -353.817227)
			(xy 21.577935 -353.791726) (xy 21.532577 -353.759275) (xy 21.492428 -353.720566) (xy 21.458342 -353.676423)
			(xy 21.431046 -353.627788) (xy 21.411123 -353.575697) (xy 21.398997 -353.52126) (xy 21.394926 -353.465638)
			(xy 19.072098 -353.465638) (xy 20.573746 -354.967286) (xy 20.581146 -354.974127) (xy 20.599745 -354.981847)
			(xy 20.609814 -354.982272) (xy 22.691598 -354.982272) (xy 22.701669 -354.982694) (xy 22.720277 -354.990405)
			(xy 22.727666 -354.997258) (xy 24.465534 -356.735126) (xy 24.472383 -356.742523) (xy 24.480119 -356.761122)
			(xy 24.48052 -356.771194) (xy 24.48052 -361.036616) (xy 24.473916 -361.04322) (xy 24.473916 -361.488228)
			(xy 24.474345 -361.498296) (xy 24.482068 -361.516891) (xy 24.488902 -361.524296) (xy 25.447498 -362.482892)
			(xy 25.456071 -362.490515) (xy 25.477705 -362.498052) (xy 25.489154 -362.49737) (xy 25.579324 -362.487464)
			(xy 25.598882 -362.475272) (xy 25.604978 -362.465366) (xy 25.620073 -362.442459) (xy 25.655789 -362.400818)
			(xy 25.697094 -362.364715) (xy 25.743139 -362.334892) (xy 25.792978 -362.311964) (xy 25.845583 -362.296402)
			(xy 25.899875 -362.288525) (xy 25.927304 -362.288074) (xy 25.954556 -362.28856) (xy 26.008504 -362.296317)
			(xy 26.060799 -362.311672) (xy 26.110377 -362.334313) (xy 26.156228 -362.363779) (xy 26.197419 -362.399471)
			(xy 26.233112 -362.440661) (xy 26.26258 -362.486511) (xy 26.285223 -362.536088) (xy 26.30058 -362.588383)
			(xy 26.308339 -362.64233) (xy 26.308812 -362.669582) (xy 26.308321 -362.697026) (xy 26.300423 -362.751343)
			(xy 26.293064 -362.777786) (xy 26.289762 -362.78947) (xy 26.293826 -362.812838) (xy 26.34996 -362.887768)
			(xy 26.357562 -362.896875) (xy 26.378753 -362.907473) (xy 26.3906 -362.908088) (xy 26.887932 -362.908088)
			(xy 26.898 -362.908516) (xy 26.916597 -362.916238) (xy 26.924 -362.923074) (xy 27.360118 -363.359192)
			(xy 27.366974 -363.366586) (xy 27.374725 -363.385185) (xy 27.375104 -363.39526) (xy 27.375104 -366.098836)
			(xy 27.375534 -366.108903) (xy 27.383258 -366.127498) (xy 27.39009 -366.134904) (xy 27.515566 -366.26038)
			(xy 27.522967 -366.267218) (xy 27.541566 -366.274932) (xy 27.551634 -366.275366)
		)
		(stroke
			(width 0)
			(type solid)
		)
		(fill yes)
		(layer "In11.Cu")
		(net "GND")
	)
	(gr_poly
		(pts
			(xy 284.066488 -440.515248) (xy 284.076558 -440.514826) (xy 284.095161 -440.507108) (xy 284.102556 -440.500262)
			(xy 285.106872 -439.495946) (xy 285.113713 -439.488546) (xy 285.121432 -439.469947) (xy 285.121858 -439.459878)
			(xy 285.121858 -434.247036) (xy 285.122294 -434.236972) (xy 285.130032 -434.21839) (xy 285.136844 -434.210968)
			(xy 289.360864 -429.986948) (xy 289.368264 -429.980106) (xy 289.386862 -429.972388) (xy 289.396932 -429.971962)
			(xy 298.71543 -429.971962) (xy 298.725496 -429.972392) (xy 298.744087 -429.980121) (xy 298.751498 -429.986948)
			(xy 299.865796 -431.101246) (xy 300.779686 -431.101246) (xy 300.783757 -431.045624) (xy 300.795883 -430.991187)
			(xy 300.815806 -430.939096) (xy 300.843102 -430.890461) (xy 300.877188 -430.846318) (xy 300.917337 -430.807609)
			(xy 300.962695 -430.775158) (xy 301.012295 -430.749657) (xy 301.065079 -430.73165) (xy 301.119922 -430.72152)
			(xy 301.175656 -430.719483) (xy 301.231093 -430.725583) (xy 301.28505 -430.739689) (xy 301.336379 -430.761501)
			(xy 301.383985 -430.790555) (xy 301.426853 -430.82623) (xy 301.46407 -430.867767) (xy 301.494843 -430.91428)
			(xy 301.518515 -430.964777) (xy 301.534583 -431.018184) (xy 301.542703 -431.07336) (xy 301.543212 -431.101246)
			(xy 301.542703 -431.129132) (xy 301.534583 -431.184308) (xy 301.518515 -431.237715) (xy 301.494843 -431.288212)
			(xy 301.46407 -431.334725) (xy 301.426853 -431.376262) (xy 301.383985 -431.411937) (xy 301.336379 -431.440991)
			(xy 301.28505 -431.462803) (xy 301.231093 -431.476909) (xy 301.175656 -431.483009) (xy 301.119922 -431.480972)
			(xy 301.065079 -431.470842) (xy 301.012295 -431.452835) (xy 300.962695 -431.427334) (xy 300.917337 -431.394883)
			(xy 300.877188 -431.356174) (xy 300.843102 -431.312031) (xy 300.815806 -431.263396) (xy 300.795883 -431.211305)
			(xy 300.783757 -431.156868) (xy 300.779686 -431.101246) (xy 299.865796 -431.101246) (xy 300.823376 -432.058826)
			(xy 300.830221 -432.066225) (xy 300.83795 -432.084823) (xy 300.838362 -432.094894) (xy 300.838362 -432.678797)
			(xy 302.415442 -432.678797) (xy 302.415442 -432.614875) (xy 302.423453 -432.551457) (xy 302.43935 -432.489543)
			(xy 302.462882 -432.43011) (xy 302.493676 -432.374095) (xy 302.531249 -432.32238) (xy 302.575006 -432.275783)
			(xy 302.624259 -432.235038) (xy 302.67823 -432.200787) (xy 302.736069 -432.17357) (xy 302.796862 -432.153817)
			(xy 302.859652 -432.141839) (xy 302.923448 -432.137826) (xy 302.987244 -432.141839) (xy 303.050034 -432.153817)
			(xy 303.110827 -432.17357) (xy 303.168666 -432.200787) (xy 303.222637 -432.235038) (xy 303.27189 -432.275783)
			(xy 303.315647 -432.32238) (xy 303.35322 -432.374095) (xy 303.384014 -432.43011) (xy 303.407546 -432.489543)
			(xy 303.423443 -432.551457) (xy 303.431454 -432.614875) (xy 303.43179 -432.636237) (xy 303.684535 -432.636237)
			(xy 303.68975 -432.573375) (xy 303.702699 -432.511641) (xy 303.723186 -432.451982) (xy 303.750895 -432.395316)
			(xy 303.7854 -432.342512) (xy 303.826171 -432.294382) (xy 303.872583 -432.251665) (xy 303.923922 -432.215017)
			(xy 303.979401 -432.185) (xy 304.038166 -432.162076) (xy 304.099315 -432.146597) (xy 304.161909 -432.138801)
			(xy 304.193448 -432.138328) (xy 304.235104 -432.140106) (xy 304.249462 -432.140721) (xy 304.277604 -432.134979)
			(xy 304.303037 -432.121633) (xy 304.323752 -432.101738) (xy 304.338114 -432.076865) (xy 304.344989 -432.048978)
			(xy 304.343834 -432.020279) (xy 304.339752 -432.006502) (xy 304.330484 -431.976944) (xy 304.320526 -431.915807)
			(xy 304.31994 -431.884836) (xy 304.320426 -431.857585) (xy 304.328182 -431.803637) (xy 304.343537 -431.751342)
			(xy 304.366179 -431.701765) (xy 304.395645 -431.655915) (xy 304.431336 -431.614724) (xy 304.472527 -431.579033)
			(xy 304.518377 -431.549567) (xy 304.567954 -431.526925) (xy 304.620249 -431.51157) (xy 304.674197 -431.503814)
			(xy 304.728699 -431.503814) (xy 304.782647 -431.51157) (xy 304.834942 -431.526925) (xy 304.884519 -431.549567)
			(xy 304.930369 -431.579033) (xy 304.97156 -431.614724) (xy 305.007251 -431.655915) (xy 305.036717 -431.701765)
			(xy 305.059359 -431.751342) (xy 305.074714 -431.803637) (xy 305.08247 -431.857585) (xy 305.082956 -431.884836)
			(xy 305.08246 -431.913464) (xy 305.073885 -431.970075) (xy 305.056949 -432.024769) (xy 305.03203 -432.076318)
			(xy 304.99969 -432.123566) (xy 304.960653 -432.165452) (xy 304.915797 -432.201035) (xy 304.866127 -432.229517)
			(xy 304.81276 -432.250259) (xy 304.756892 -432.262793) (xy 304.728372 -432.265328) (xy 304.714067 -432.266889)
			(xy 304.687081 -432.276826) (xy 304.663937 -432.293896) (xy 304.646472 -432.316743) (xy 304.636072 -432.343554)
			(xy 304.633562 -432.372203) (xy 304.639141 -432.400414) (xy 304.645314 -432.41341) (xy 304.658848 -432.440547)
			(xy 304.680059 -432.497361) (xy 304.694356 -432.556296) (xy 304.701536 -432.616514) (xy 304.701841 -432.638563)
			(xy 306.311421 -432.638563) (xy 306.316632 -432.575699) (xy 306.329579 -432.513963) (xy 306.350063 -432.454302)
			(xy 306.377769 -432.397634) (xy 306.412272 -432.344827) (xy 306.453041 -432.296694) (xy 306.499452 -432.253973)
			(xy 306.55079 -432.217321) (xy 306.606267 -432.1873) (xy 306.665032 -432.164372) (xy 306.726181 -432.148889)
			(xy 306.788776 -432.141089) (xy 306.820316 -432.140614) (xy 306.8447 -432.141122) (xy 306.858749 -432.141367)
			(xy 306.886121 -432.135072) (xy 306.910737 -432.121547) (xy 306.930729 -432.101819) (xy 306.94458 -432.077386)
			(xy 306.951239 -432.0501) (xy 306.9502 -432.022032) (xy 306.9463 -432.008534) (xy 306.937674 -431.979965)
			(xy 306.928358 -431.921023) (xy 306.927758 -431.891186) (xy 306.928244 -431.863935) (xy 306.936 -431.809987)
			(xy 306.951355 -431.757692) (xy 306.973997 -431.708115) (xy 307.003463 -431.662265) (xy 307.039154 -431.621074)
			(xy 307.080345 -431.585383) (xy 307.126195 -431.555917) (xy 307.175772 -431.533275) (xy 307.228067 -431.51792)
			(xy 307.282015 -431.510164) (xy 307.336517 -431.510164) (xy 307.390465 -431.51792) (xy 307.44276 -431.533275)
			(xy 307.492337 -431.555917) (xy 307.538187 -431.585383) (xy 307.579378 -431.621074) (xy 307.615069 -431.662265)
			(xy 307.644535 -431.708115) (xy 307.667177 -431.757692) (xy 307.682532 -431.809987) (xy 307.690288 -431.863935)
			(xy 307.690774 -431.891186) (xy 307.690297 -431.919032) (xy 307.682228 -431.974137) (xy 307.66623 -432.027481)
			(xy 307.642644 -432.077932) (xy 307.611971 -432.124416) (xy 307.574864 -432.165945) (xy 307.532111 -432.201635)
			(xy 307.484622 -432.230728) (xy 307.433406 -432.252604) (xy 307.379554 -432.266799) (xy 307.351938 -432.270408)
			(xy 307.338031 -432.27234) (xy 307.31205 -432.282967) (xy 307.289946 -432.300271) (xy 307.273395 -432.322943)
			(xy 307.263647 -432.349267) (xy 307.261442 -432.377251) (xy 307.266945 -432.404777) (xy 307.272944 -432.417474)
			(xy 307.286278 -432.444436) (xy 307.307191 -432.500836) (xy 307.321293 -432.559313) (xy 307.328387 -432.619046)
			(xy 307.328671 -432.638563) (xy 307.581421 -432.638563) (xy 307.586632 -432.575699) (xy 307.599579 -432.513963)
			(xy 307.620063 -432.454302) (xy 307.647769 -432.397634) (xy 307.682272 -432.344827) (xy 307.723041 -432.296694)
			(xy 307.769452 -432.253973) (xy 307.82079 -432.217321) (xy 307.876267 -432.1873) (xy 307.935032 -432.164372)
			(xy 307.996181 -432.148889) (xy 308.058776 -432.141089) (xy 308.090316 -432.140614) (xy 308.131972 -432.142392)
			(xy 308.146328 -432.143086) (xy 308.174475 -432.137327) (xy 308.19991 -432.123965) (xy 308.220625 -432.104057)
			(xy 308.234985 -432.079173) (xy 308.241859 -432.051277) (xy 308.240702 -432.02257) (xy 308.23662 -432.008788)
			(xy 308.227351 -431.97923) (xy 308.217393 -431.918093) (xy 308.216808 -431.887122) (xy 308.217294 -431.859871)
			(xy 308.22505 -431.805923) (xy 308.240405 -431.753628) (xy 308.263047 -431.704051) (xy 308.292513 -431.658201)
			(xy 308.328204 -431.61701) (xy 308.369395 -431.581319) (xy 308.415245 -431.551853) (xy 308.464822 -431.529211)
			(xy 308.517117 -431.513856) (xy 308.571065 -431.5061) (xy 308.625567 -431.5061) (xy 308.679515 -431.513856)
			(xy 308.73181 -431.529211) (xy 308.781387 -431.551853) (xy 308.827237 -431.581319) (xy 308.868428 -431.61701)
			(xy 308.904119 -431.658201) (xy 308.933585 -431.704051) (xy 308.956227 -431.753628) (xy 308.971582 -431.805923)
			(xy 308.979338 -431.859871) (xy 308.979824 -431.887122) (xy 308.979345 -431.915751) (xy 308.970771 -431.972364)
			(xy 308.953834 -432.02706) (xy 308.928915 -432.078612) (xy 308.896573 -432.125861) (xy 308.857534 -432.167747)
			(xy 308.812675 -432.20333) (xy 308.763002 -432.231811) (xy 308.709632 -432.25255) (xy 308.653762 -432.265081)
			(xy 308.62524 -432.267614) (xy 308.610936 -432.269172) (xy 308.583954 -432.279115) (xy 308.560814 -432.296187)
			(xy 308.543352 -432.319034) (xy 308.532952 -432.345843) (xy 308.530439 -432.374489) (xy 308.536012 -432.4027)
			(xy 308.542182 -432.415696) (xy 308.555709 -432.442837) (xy 308.576922 -432.499649) (xy 308.591221 -432.558583)
			(xy 308.598403 -432.6188) (xy 308.598824 -432.649122) (xy 308.598309 -432.680662) (xy 308.590504 -432.743256)
			(xy 308.575016 -432.804404) (xy 308.552084 -432.863167) (xy 308.522059 -432.918643) (xy 308.485403 -432.969978)
			(xy 308.442679 -433.016385) (xy 308.394543 -433.057151) (xy 308.341733 -433.09165) (xy 308.285063 -433.119352)
			(xy 308.2254 -433.139831) (xy 308.163663 -433.152774) (xy 308.100799 -433.15798) (xy 308.037774 -433.155371)
			(xy 307.975556 -433.144986) (xy 307.915099 -433.126985) (xy 307.857334 -433.101644) (xy 307.803147 -433.069353)
			(xy 307.75337 -433.030607) (xy 307.708768 -432.986001) (xy 307.670026 -432.936222) (xy 307.637738 -432.882032)
			(xy 307.612402 -432.824265) (xy 307.594405 -432.763807) (xy 307.584025 -432.701588) (xy 307.581421 -432.638563)
			(xy 307.328671 -432.638563) (xy 307.328824 -432.649122) (xy 307.328309 -432.680662) (xy 307.320504 -432.743256)
			(xy 307.305016 -432.804404) (xy 307.282084 -432.863167) (xy 307.252059 -432.918643) (xy 307.215403 -432.969978)
			(xy 307.172679 -433.016385) (xy 307.124543 -433.057151) (xy 307.071733 -433.09165) (xy 307.015063 -433.119352)
			(xy 306.9554 -433.139831) (xy 306.893663 -433.152774) (xy 306.830799 -433.15798) (xy 306.767774 -433.155371)
			(xy 306.705556 -433.144986) (xy 306.645099 -433.126985) (xy 306.587334 -433.101644) (xy 306.533147 -433.069353)
			(xy 306.48337 -433.030607) (xy 306.438768 -432.986001) (xy 306.400026 -432.936222) (xy 306.367738 -432.882032)
			(xy 306.342402 -432.824265) (xy 306.324405 -432.763807) (xy 306.314025 -432.701588) (xy 306.311421 -432.638563)
			(xy 304.701841 -432.638563) (xy 304.701956 -432.646836) (xy 304.701394 -432.678375) (xy 304.693587 -432.740968)
			(xy 304.678098 -432.802115) (xy 304.655165 -432.860876) (xy 304.625139 -432.916349) (xy 304.588482 -432.967682)
			(xy 304.545757 -433.014087) (xy 304.49762 -433.05485) (xy 304.444811 -433.089347) (xy 304.38814 -433.117046)
			(xy 304.328478 -433.137523) (xy 304.266742 -433.150463) (xy 304.203879 -433.155667) (xy 304.140855 -433.153055)
			(xy 304.078638 -433.142668) (xy 304.018184 -433.124664) (xy 303.960421 -433.099322) (xy 303.906236 -433.067029)
			(xy 303.856462 -433.028281) (xy 303.811863 -432.983675) (xy 303.773124 -432.933894) (xy 303.74084 -432.879704)
			(xy 303.715507 -432.821937) (xy 303.697513 -432.76148) (xy 303.687136 -432.699261) (xy 303.684535 -432.636237)
			(xy 303.43179 -432.636237) (xy 303.431956 -432.646836) (xy 303.431454 -432.678797) (xy 303.423443 -432.742215)
			(xy 303.407546 -432.804129) (xy 303.384014 -432.863562) (xy 303.35322 -432.919577) (xy 303.315647 -432.971292)
			(xy 303.27189 -433.017889) (xy 303.222637 -433.058634) (xy 303.168666 -433.092885) (xy 303.110827 -433.120102)
			(xy 303.050034 -433.139855) (xy 302.987244 -433.151833) (xy 302.923448 -433.155847) (xy 302.859652 -433.151833)
			(xy 302.796862 -433.139855) (xy 302.736069 -433.120102) (xy 302.67823 -433.092885) (xy 302.624259 -433.058634)
			(xy 302.575006 -433.017889) (xy 302.531249 -432.971292) (xy 302.493676 -432.919577) (xy 302.462882 -432.863562)
			(xy 302.43935 -432.804129) (xy 302.423453 -432.742215) (xy 302.415442 -432.678797) (xy 300.838362 -432.678797)
			(xy 300.838362 -433.614322) (xy 305.54752 -433.614322) (xy 305.551591 -433.5587) (xy 305.563717 -433.504263)
			(xy 305.58364 -433.452172) (xy 305.610936 -433.403537) (xy 305.645022 -433.359394) (xy 305.685171 -433.320685)
			(xy 305.730529 -433.288234) (xy 305.780129 -433.262733) (xy 305.832913 -433.244726) (xy 305.887756 -433.234596)
			(xy 305.94349 -433.232559) (xy 305.998927 -433.238659) (xy 306.052884 -433.252765) (xy 306.104213 -433.274577)
			(xy 306.112778 -433.279804) (xy 308.704232 -433.279804) (xy 308.708303 -433.224182) (xy 308.720429 -433.169745)
			(xy 308.740352 -433.117654) (xy 308.767648 -433.069019) (xy 308.801734 -433.024876) (xy 308.841883 -432.986167)
			(xy 308.887241 -432.953716) (xy 308.936841 -432.928215) (xy 308.989625 -432.910208) (xy 309.044468 -432.900078)
			(xy 309.100202 -432.898041) (xy 309.155639 -432.904141) (xy 309.209596 -432.918247) (xy 309.260925 -432.940059)
			(xy 309.308531 -432.969113) (xy 309.351399 -433.004788) (xy 309.388616 -433.046325) (xy 309.419389 -433.092838)
			(xy 309.443061 -433.143335) (xy 309.459129 -433.196742) (xy 309.467249 -433.251918) (xy 309.467758 -433.279804)
			(xy 309.467249 -433.30769) (xy 309.459129 -433.362866) (xy 309.443061 -433.416273) (xy 309.419389 -433.46677)
			(xy 309.388616 -433.513283) (xy 309.351399 -433.55482) (xy 309.308531 -433.590495) (xy 309.260925 -433.619549)
			(xy 309.209596 -433.641361) (xy 309.155639 -433.655467) (xy 309.100202 -433.661567) (xy 309.044468 -433.65953)
			(xy 308.989625 -433.6494) (xy 308.936841 -433.631393) (xy 308.887241 -433.605892) (xy 308.841883 -433.573441)
			(xy 308.801734 -433.534732) (xy 308.767648 -433.490589) (xy 308.740352 -433.441954) (xy 308.720429 -433.389863)
			(xy 308.708303 -433.335426) (xy 308.704232 -433.279804) (xy 306.112778 -433.279804) (xy 306.151819 -433.303631)
			(xy 306.194687 -433.339306) (xy 306.231904 -433.380843) (xy 306.262677 -433.427356) (xy 306.286349 -433.477853)
			(xy 306.302417 -433.53126) (xy 306.310537 -433.586436) (xy 306.311046 -433.614322) (xy 306.310537 -433.642208)
			(xy 306.302417 -433.697384) (xy 306.286349 -433.750791) (xy 306.262677 -433.801288) (xy 306.231904 -433.847801)
			(xy 306.194687 -433.889338) (xy 306.151819 -433.925013) (xy 306.104213 -433.954067) (xy 306.052884 -433.975879)
			(xy 305.998927 -433.989985) (xy 305.94349 -433.996085) (xy 305.887756 -433.994048) (xy 305.832913 -433.983918)
			(xy 305.780129 -433.965911) (xy 305.730529 -433.94041) (xy 305.685171 -433.907959) (xy 305.645022 -433.86925)
			(xy 305.610936 -433.825107) (xy 305.58364 -433.776472) (xy 305.563717 -433.724381) (xy 305.551591 -433.669944)
			(xy 305.54752 -433.614322) (xy 300.838362 -433.614322) (xy 300.838362 -434.914294) (xy 303.5968 -434.914294)
			(xy 303.600871 -434.858672) (xy 303.612997 -434.804235) (xy 303.63292 -434.752144) (xy 303.660216 -434.703509)
			(xy 303.694302 -434.659366) (xy 303.734451 -434.620657) (xy 303.779809 -434.588206) (xy 303.829409 -434.562705)
			(xy 303.882193 -434.544698) (xy 303.937036 -434.534568) (xy 303.99277 -434.532531) (xy 304.048207 -434.538631)
			(xy 304.102164 -434.552737) (xy 304.153493 -434.574549) (xy 304.201099 -434.603603) (xy 304.243967 -434.639278)
			(xy 304.281184 -434.680815) (xy 304.311957 -434.727328) (xy 304.335629 -434.777825) (xy 304.351697 -434.831232)
			(xy 304.359817 -434.886408) (xy 304.360326 -434.914294) (xy 304.359817 -434.94218) (xy 304.351697 -434.997356)
			(xy 304.335629 -435.050763) (xy 304.311957 -435.10126) (xy 304.281184 -435.147773) (xy 304.243967 -435.18931)
			(xy 304.201099 -435.224985) (xy 304.153493 -435.254039) (xy 304.102164 -435.275851) (xy 304.048207 -435.289957)
			(xy 303.99277 -435.296057) (xy 303.937036 -435.29402) (xy 303.882193 -435.28389) (xy 303.829409 -435.265883)
			(xy 303.779809 -435.240382) (xy 303.734451 -435.207931) (xy 303.694302 -435.169222) (xy 303.660216 -435.125079)
			(xy 303.63292 -435.076444) (xy 303.612997 -435.024353) (xy 303.600871 -434.969916) (xy 303.5968 -434.914294)
			(xy 300.838362 -434.914294) (xy 300.838362 -436.120794) (xy 306.391562 -436.120794) (xy 306.395633 -436.065172)
			(xy 306.407759 -436.010735) (xy 306.427682 -435.958644) (xy 306.454978 -435.910009) (xy 306.489064 -435.865866)
			(xy 306.529213 -435.827157) (xy 306.574571 -435.794706) (xy 306.624171 -435.769205) (xy 306.676955 -435.751198)
			(xy 306.731798 -435.741068) (xy 306.787532 -435.739031) (xy 306.842969 -435.745131) (xy 306.896926 -435.759237)
			(xy 306.948255 -435.781049) (xy 306.995861 -435.810103) (xy 307.038729 -435.845778) (xy 307.075946 -435.887315)
			(xy 307.106719 -435.933828) (xy 307.130391 -435.984325) (xy 307.146459 -436.037732) (xy 307.154579 -436.092908)
			(xy 307.155088 -436.120794) (xy 307.154579 -436.14868) (xy 307.146459 -436.203856) (xy 307.130391 -436.257263)
			(xy 307.106719 -436.30776) (xy 307.075946 -436.354273) (xy 307.038729 -436.39581) (xy 306.995861 -436.431485)
			(xy 306.948255 -436.460539) (xy 306.896926 -436.482351) (xy 306.842969 -436.496457) (xy 306.787532 -436.502557)
			(xy 306.731798 -436.50052) (xy 306.676955 -436.49039) (xy 306.624171 -436.472383) (xy 306.574571 -436.446882)
			(xy 306.529213 -436.414431) (xy 306.489064 -436.375722) (xy 306.454978 -436.331579) (xy 306.427682 -436.282944)
			(xy 306.407759 -436.230853) (xy 306.395633 -436.176416) (xy 306.391562 -436.120794) (xy 300.838362 -436.120794)
			(xy 300.838362 -437.170322) (xy 304.238658 -437.170322) (xy 304.242729 -437.1147) (xy 304.254855 -437.060263)
			(xy 304.274778 -437.008172) (xy 304.302074 -436.959537) (xy 304.33616 -436.915394) (xy 304.376309 -436.876685)
			(xy 304.421667 -436.844234) (xy 304.471267 -436.818733) (xy 304.524051 -436.800726) (xy 304.578894 -436.790596)
			(xy 304.634628 -436.788559) (xy 304.690065 -436.794659) (xy 304.744022 -436.808765) (xy 304.795351 -436.830577)
			(xy 304.842957 -436.859631) (xy 304.885825 -436.895306) (xy 304.923042 -436.936843) (xy 304.953815 -436.983356)
			(xy 304.977487 -437.033853) (xy 304.993555 -437.08726) (xy 305.001675 -437.142436) (xy 305.002184 -437.170322)
			(xy 305.001675 -437.198208) (xy 304.993555 -437.253384) (xy 304.977487 -437.306791) (xy 304.953815 -437.357288)
			(xy 304.923042 -437.403801) (xy 304.885825 -437.445338) (xy 304.842957 -437.481013) (xy 304.795351 -437.510067)
			(xy 304.744022 -437.531879) (xy 304.690065 -437.545985) (xy 304.634628 -437.552085) (xy 304.578894 -437.550048)
			(xy 304.524051 -437.539918) (xy 304.471267 -437.521911) (xy 304.421667 -437.49641) (xy 304.376309 -437.463959)
			(xy 304.33616 -437.42525) (xy 304.302074 -437.381107) (xy 304.274778 -437.332472) (xy 304.254855 -437.280381)
			(xy 304.242729 -437.225944) (xy 304.238658 -437.170322) (xy 300.838362 -437.170322) (xy 300.838362 -438.470294)
			(xy 303.608738 -438.470294) (xy 303.612809 -438.414672) (xy 303.624935 -438.360235) (xy 303.644858 -438.308144)
			(xy 303.672154 -438.259509) (xy 303.70624 -438.215366) (xy 303.746389 -438.176657) (xy 303.791747 -438.144206)
			(xy 303.841347 -438.118705) (xy 303.894131 -438.100698) (xy 303.948974 -438.090568) (xy 304.004708 -438.088531)
			(xy 304.060145 -438.094631) (xy 304.114102 -438.108737) (xy 304.165431 -438.130549) (xy 304.213037 -438.159603)
			(xy 304.255905 -438.195278) (xy 304.293122 -438.236815) (xy 304.323895 -438.283328) (xy 304.347567 -438.333825)
			(xy 304.363635 -438.387232) (xy 304.371755 -438.442408) (xy 304.372264 -438.470294) (xy 304.371755 -438.49818)
			(xy 304.363635 -438.553356) (xy 304.347567 -438.606763) (xy 304.323895 -438.65726) (xy 304.293122 -438.703773)
			(xy 304.255905 -438.74531) (xy 304.213037 -438.780985) (xy 304.165431 -438.810039) (xy 304.114102 -438.831851)
			(xy 304.060145 -438.845957) (xy 304.004708 -438.852057) (xy 303.948974 -438.85002) (xy 303.894131 -438.83989)
			(xy 303.841347 -438.821883) (xy 303.791747 -438.796382) (xy 303.746389 -438.763931) (xy 303.70624 -438.725222)
			(xy 303.672154 -438.681079) (xy 303.644858 -438.632444) (xy 303.624935 -438.580353) (xy 303.612809 -438.525916)
			(xy 303.608738 -438.470294) (xy 300.838362 -438.470294) (xy 300.838362 -438.753504) (xy 300.838787 -438.763573)
			(xy 300.84651 -438.78217) (xy 300.853348 -438.789572) (xy 301.74057 -439.676794) (xy 306.391562 -439.676794)
			(xy 306.395633 -439.621172) (xy 306.407759 -439.566735) (xy 306.427682 -439.514644) (xy 306.454978 -439.466009)
			(xy 306.489064 -439.421866) (xy 306.529213 -439.383157) (xy 306.574571 -439.350706) (xy 306.624171 -439.325205)
			(xy 306.676955 -439.307198) (xy 306.731798 -439.297068) (xy 306.787532 -439.295031) (xy 306.842969 -439.301131)
			(xy 306.896926 -439.315237) (xy 306.948255 -439.337049) (xy 306.995861 -439.366103) (xy 307.038729 -439.401778)
			(xy 307.075946 -439.443315) (xy 307.106719 -439.489828) (xy 307.130391 -439.540325) (xy 307.146459 -439.593732)
			(xy 307.154579 -439.648908) (xy 307.155088 -439.676794) (xy 307.154579 -439.70468) (xy 307.146459 -439.759856)
			(xy 307.130391 -439.813263) (xy 307.106719 -439.86376) (xy 307.075946 -439.910273) (xy 307.038729 -439.95181)
			(xy 306.995861 -439.987485) (xy 306.948255 -440.016539) (xy 306.896926 -440.038351) (xy 306.842969 -440.052457)
			(xy 306.787532 -440.058557) (xy 306.731798 -440.05652) (xy 306.676955 -440.04639) (xy 306.624171 -440.028383)
			(xy 306.574571 -440.002882) (xy 306.529213 -439.970431) (xy 306.489064 -439.931722) (xy 306.454978 -439.887579)
			(xy 306.427682 -439.838944) (xy 306.407759 -439.786853) (xy 306.395633 -439.732416) (xy 306.391562 -439.676794)
			(xy 301.74057 -439.676794) (xy 302.531272 -440.467496) (xy 302.538674 -440.474331) (xy 302.557273 -440.48204)
			(xy 302.56734 -440.482482) (xy 309.225442 -440.482482) (xy 309.235508 -440.482051) (xy 309.2541 -440.474324)
			(xy 309.26151 -440.467496) (xy 309.594504 -440.134502) (xy 309.601866 -440.126377) (xy 309.609488 -440.105841)
			(xy 309.609236 -440.094878) (xy 309.60314 -440.007248) (xy 309.592726 -439.988198) (xy 309.583836 -439.981594)
			(xy 309.560665 -439.963437) (xy 309.519665 -439.9212) (xy 309.485635 -439.873169) (xy 309.45938 -439.820484)
			(xy 309.441524 -439.764393) (xy 309.432489 -439.706226) (xy 309.431944 -439.676794) (xy 309.432409 -439.64986)
			(xy 309.439994 -439.596528) (xy 309.455013 -439.544795) (xy 309.477166 -439.495693) (xy 309.506012 -439.450198)
			(xy 309.52313 -439.429398) (xy 309.529988 -439.42127) (xy 309.536084 -439.401712) (xy 309.52567 -439.306716)
			(xy 309.51551 -439.288936) (xy 309.506874 -439.282332) (xy 309.480425 -439.261669) (xy 309.432667 -439.214509)
			(xy 309.391525 -439.161479) (xy 309.357714 -439.103498) (xy 309.331822 -439.041575) (xy 309.314297 -438.976785)
			(xy 309.305446 -438.910253) (xy 309.304944 -438.876694) (xy 309.305417 -438.845191) (xy 309.313201 -438.782668)
			(xy 309.328649 -438.721585) (xy 309.351524 -438.662879) (xy 309.381477 -438.607447) (xy 309.418047 -438.556141)
			(xy 309.460675 -438.509745) (xy 309.508708 -438.468971) (xy 309.561411 -438.434442) (xy 309.617975 -438.406688)
			(xy 309.677534 -438.386135) (xy 309.739176 -438.373096) (xy 309.770526 -438.369964) (xy 309.779704 -438.368833)
			(xy 309.796387 -438.360893) (xy 309.803038 -438.35447) (xy 309.823866 -438.332626) (xy 309.830255 -438.325307)
			(xy 309.837454 -438.30728) (xy 309.837836 -438.297574) (xy 309.837836 -438.185814) (xy 309.837402 -438.176117)
			(xy 309.830217 -438.158103) (xy 309.823866 -438.150762) (xy 309.803038 -438.128918) (xy 309.79636 -438.12253)
			(xy 309.779694 -438.114578) (xy 309.770526 -438.113424) (xy 309.739174 -438.110296) (xy 309.677529 -438.097265)
			(xy 309.617966 -438.076718) (xy 309.561398 -438.048968) (xy 309.508693 -438.01444) (xy 309.460658 -437.973665)
			(xy 309.418029 -437.927267) (xy 309.381461 -437.875957) (xy 309.351512 -437.820522) (xy 309.328644 -437.761811)
			(xy 309.313205 -437.700724) (xy 309.305432 -437.638198) (xy 309.304944 -437.606694) (xy 309.306722 -437.565038)
			(xy 309.307738 -437.552084) (xy 309.297578 -437.528716) (xy 309.210456 -437.46039) (xy 309.18531 -437.456072)
			(xy 309.173118 -437.46039) (xy 309.143564 -437.469676) (xy 309.082425 -437.479633) (xy 309.051452 -437.480202)
			(xy 309.024203 -437.479713) (xy 308.970262 -437.471951) (xy 308.917974 -437.456592) (xy 308.868403 -437.433948)
			(xy 308.822559 -437.404481) (xy 308.781376 -437.36879) (xy 308.74569 -437.327602) (xy 308.716229 -437.281755)
			(xy 308.693591 -437.232181) (xy 308.678239 -437.179891) (xy 308.670484 -437.125949) (xy 308.670484 -437.071451)
			(xy 308.678239 -437.017509) (xy 308.693591 -436.965219) (xy 308.716229 -436.915645) (xy 308.74569 -436.869798)
			(xy 308.781376 -436.82861) (xy 308.822559 -436.792919) (xy 308.868403 -436.763452) (xy 308.917974 -436.740808)
			(xy 308.970262 -436.725449) (xy 309.024203 -436.717687) (xy 309.051452 -436.717186) (xy 309.080083 -436.717696)
			(xy 309.136703 -436.726249) (xy 309.191408 -436.74317) (xy 309.242969 -436.768078) (xy 309.290227 -436.800415)
			(xy 309.33212 -436.839453) (xy 309.367706 -436.884314) (xy 309.396187 -436.933991) (xy 309.416921 -436.987368)
			(xy 309.429443 -437.043244) (xy 309.431944 -437.07177) (xy 309.43296 -437.084724) (xy 309.446676 -437.106314)
			(xy 309.542942 -437.160416) (xy 309.568596 -437.160924) (xy 309.580026 -437.154828) (xy 309.609837 -437.140059)
			(xy 309.672431 -437.117518) (xy 309.737426 -437.103315) (xy 309.770526 -437.099964) (xy 309.779704 -437.098833)
			(xy 309.796387 -437.090893) (xy 309.803038 -437.08447) (xy 309.823866 -437.062626) (xy 309.830255 -437.055307)
			(xy 309.837454 -437.03728) (xy 309.837836 -437.027574) (xy 309.837836 -436.572406) (xy 309.83742 -436.562797)
			(xy 309.830372 -436.544917) (xy 309.82412 -436.537608) (xy 309.803546 -436.515764) (xy 309.797108 -436.509441)
			(xy 309.78097 -436.501391) (xy 309.77205 -436.500016) (xy 309.744366 -436.496503) (xy 309.690367 -436.482426)
			(xy 309.638995 -436.460634) (xy 309.591344 -436.431592) (xy 309.548431 -436.39592) (xy 309.511172 -436.354378)
			(xy 309.480361 -436.307851) (xy 309.456655 -436.257334) (xy 309.440559 -436.203902) (xy 309.432418 -436.148696)
			(xy 309.431944 -436.120794) (xy 309.432409 -436.09386) (xy 309.439994 -436.040528) (xy 309.455013 -435.988795)
			(xy 309.477166 -435.939693) (xy 309.506012 -435.894198) (xy 309.52313 -435.873398) (xy 309.529988 -435.86527)
			(xy 309.536084 -435.845712) (xy 309.52567 -435.750716) (xy 309.51551 -435.732936) (xy 309.506874 -435.726332)
			(xy 309.480425 -435.705669) (xy 309.432667 -435.658509) (xy 309.391525 -435.605479) (xy 309.357714 -435.547498)
			(xy 309.331822 -435.485575) (xy 309.314297 -435.420785) (xy 309.305446 -435.354253) (xy 309.304944 -435.320694)
			(xy 309.305417 -435.289191) (xy 309.313201 -435.226668) (xy 309.328649 -435.165585) (xy 309.351524 -435.106879)
			(xy 309.381477 -435.051447) (xy 309.418047 -435.000141) (xy 309.460675 -434.953745) (xy 309.508708 -434.912971)
			(xy 309.561411 -434.878442) (xy 309.617975 -434.850688) (xy 309.677534 -434.830135) (xy 309.739176 -434.817096)
			(xy 309.770526 -434.813964) (xy 309.779704 -434.812833) (xy 309.796387 -434.804893) (xy 309.803038 -434.79847)
			(xy 309.823866 -434.776626) (xy 309.830255 -434.769307) (xy 309.837454 -434.75128) (xy 309.837836 -434.741574)
			(xy 309.837836 -434.629814) (xy 309.837402 -434.620117) (xy 309.830217 -434.602103) (xy 309.823866 -434.594762)
			(xy 309.803038 -434.572918) (xy 309.79636 -434.56653) (xy 309.779694 -434.558578) (xy 309.770526 -434.557424)
			(xy 309.739176 -434.55429) (xy 309.677536 -434.541252) (xy 309.617978 -434.520698) (xy 309.561415 -434.492945)
			(xy 309.508714 -434.458417) (xy 309.460682 -434.417643) (xy 309.418055 -434.371247) (xy 309.381486 -434.319942)
			(xy 309.351535 -434.264511) (xy 309.32866 -434.205806) (xy 309.313213 -434.144724) (xy 309.30543 -434.082202)
			(xy 309.30543 -434.019197) (xy 309.313213 -433.956675) (xy 309.328661 -433.895593) (xy 309.351535 -433.836888)
			(xy 309.381486 -433.781458) (xy 309.418056 -433.730152) (xy 309.460683 -433.683757) (xy 309.508715 -433.642983)
			(xy 309.561416 -433.608455) (xy 309.617979 -433.580701) (xy 309.677537 -433.560148) (xy 309.739177 -433.547109)
			(xy 309.770526 -433.543964) (xy 309.779704 -433.542833) (xy 309.796387 -433.534893) (xy 309.803038 -433.52847)
			(xy 309.823866 -433.506626) (xy 309.830255 -433.499307) (xy 309.837454 -433.48128) (xy 309.837836 -433.471574)
			(xy 309.837836 -428.876206) (xy 309.837412 -428.866137) (xy 309.829692 -428.847537) (xy 309.82285 -428.840138)
			(xy 308.609746 -427.627034) (xy 308.601069 -427.619225) (xy 308.57896 -427.611814) (xy 308.567328 -427.61281)
			(xy 308.475634 -427.624748) (xy 308.45633 -427.637448) (xy 308.450234 -427.647862) (xy 308.435474 -427.672231)
			(xy 308.399861 -427.716697) (xy 308.358031 -427.755373) (xy 308.310915 -427.787399) (xy 308.259561 -427.812063)
			(xy 308.20511 -427.828816) (xy 308.148773 -427.837286) (xy 308.120288 -427.837854) (xy 308.093036 -427.837367)
			(xy 308.039087 -427.82961) (xy 307.986791 -427.814254) (xy 307.937213 -427.791613) (xy 307.89136 -427.762147)
			(xy 307.850168 -427.726456) (xy 307.814473 -427.685267) (xy 307.785003 -427.639417) (xy 307.762358 -427.589841)
			(xy 307.746997 -427.537546) (xy 307.739235 -427.483598) (xy 307.73878 -427.456346) (xy 307.739305 -427.427857)
			(xy 307.747772 -427.371512) (xy 307.764524 -427.317053) (xy 307.78919 -427.265691) (xy 307.821219 -427.218568)
			(xy 307.8599 -427.176733) (xy 307.904373 -427.141115) (xy 307.928772 -427.1264) (xy 307.939186 -427.120304)
			(xy 307.951886 -427.101) (xy 307.963824 -427.009306) (xy 307.964753 -426.997686) (xy 307.957333 -426.975613)
			(xy 307.9496 -426.966888) (xy 306.83962 -425.856908) (xy 306.830619 -425.848866) (xy 306.807685 -425.841444)
			(xy 306.795678 -425.842684) (xy 306.702206 -425.85767) (xy 306.682648 -425.87164) (xy 306.67706 -425.882816)
			(xy 306.661629 -425.912156) (xy 306.624292 -425.966935) (xy 306.602638 -425.992036) (xy 306.596288 -425.998894)
			(xy 306.589684 -426.016166) (xy 306.589684 -426.103034) (xy 306.596288 -426.120306) (xy 306.602638 -426.127164)
			(xy 306.621542 -426.148931) (xy 306.654845 -426.195995) (xy 306.68262 -426.246519) (xy 306.704511 -426.299857)
			(xy 306.720238 -426.355325) (xy 306.72532 -426.383704) (xy 306.727264 -426.392785) (xy 306.73665 -426.408793)
			(xy 306.743608 -426.414946) (xy 306.767738 -426.43425) (xy 306.775205 -426.439707) (xy 306.792779 -426.445427)
			(xy 306.802028 -426.445426) (xy 306.820316 -426.444918) (xy 306.847567 -426.445382) (xy 306.901515 -426.453141)
			(xy 306.95381 -426.468499) (xy 307.003386 -426.491143) (xy 307.049235 -426.520612) (xy 307.090424 -426.556306)
			(xy 307.126113 -426.597498) (xy 307.155577 -426.643351) (xy 307.178216 -426.69293) (xy 307.193568 -426.745226)
			(xy 307.201321 -426.799175) (xy 307.201824 -426.826426) (xy 307.201375 -426.853231) (xy 307.19388 -426.906316)
			(xy 307.179028 -426.957828) (xy 307.157111 -427.006753) (xy 307.12856 -427.052129) (xy 307.093938 -427.093061)
			(xy 307.053927 -427.128743) (xy 307.009315 -427.158473) (xy 306.96098 -427.181664) (xy 306.909875 -427.197861)
			(xy 306.857005 -427.206744) (xy 306.830222 -427.207934) (xy 306.820316 -427.207934) (xy 306.803044 -427.2153)
			(xy 306.739544 -427.277276) (xy 306.73167 -427.294548) (xy 306.731162 -427.3042) (xy 306.728871 -427.338678)
			(xy 306.716132 -427.406593) (xy 306.694313 -427.472158) (xy 306.663817 -427.534163) (xy 306.625205 -427.591468)
			(xy 306.602638 -427.617636) (xy 306.596288 -427.624494) (xy 306.589684 -427.641766) (xy 306.589684 -427.728634)
			(xy 306.596288 -427.745906) (xy 306.602638 -427.752764) (xy 306.622885 -427.776126) (xy 306.658168 -427.826891)
			(xy 306.687042 -427.881557) (xy 306.709081 -427.939318) (xy 306.723961 -427.999323) (xy 306.731462 -428.060689)
			(xy 306.731924 -428.0916) (xy 306.731422 -428.123561) (xy 306.723411 -428.186979) (xy 306.707514 -428.248893)
			(xy 306.683982 -428.308326) (xy 306.653188 -428.364341) (xy 306.615615 -428.416056) (xy 306.571858 -428.462653)
			(xy 306.522605 -428.503398) (xy 306.468634 -428.537649) (xy 306.410795 -428.564866) (xy 306.350002 -428.584619)
			(xy 306.287212 -428.596597) (xy 306.223416 -428.600611) (xy 306.15962 -428.596597) (xy 306.09683 -428.584619)
			(xy 306.036037 -428.564866) (xy 305.978198 -428.537649) (xy 305.924227 -428.503398) (xy 305.874974 -428.462653)
			(xy 305.831217 -428.416056) (xy 305.793644 -428.364341) (xy 305.76285 -428.308326) (xy 305.739318 -428.248893)
			(xy 305.723421 -428.186979) (xy 305.71541 -428.123561) (xy 305.714908 -428.0916) (xy 305.715364 -428.060688)
			(xy 305.722859 -427.999321) (xy 305.737736 -427.939314) (xy 305.759778 -427.881554) (xy 305.788659 -427.826891)
			(xy 305.823953 -427.776132) (xy 305.844194 -427.752764) (xy 305.850544 -427.745906) (xy 305.857148 -427.728634)
			(xy 305.857148 -427.641766) (xy 305.850544 -427.624494) (xy 305.844194 -427.617636) (xy 305.823947 -427.594275)
			(xy 305.788665 -427.54351) (xy 305.759794 -427.488844) (xy 305.737761 -427.431082) (xy 305.722889 -427.371077)
			(xy 305.715398 -427.309711) (xy 305.715398 -427.247889) (xy 305.722889 -427.186523) (xy 305.737761 -427.126518)
			(xy 305.759794 -427.068756) (xy 305.788665 -427.01409) (xy 305.823947 -426.963325) (xy 305.844194 -426.939964)
			(xy 305.850544 -426.933106) (xy 305.857148 -426.915834) (xy 305.857148 -426.828966) (xy 305.850544 -426.811694)
			(xy 305.844194 -426.804836) (xy 305.823947 -426.781475) (xy 305.788665 -426.73071) (xy 305.759794 -426.676044)
			(xy 305.737761 -426.618282) (xy 305.722889 -426.558277) (xy 305.715398 -426.496911) (xy 305.715398 -426.435089)
			(xy 305.722889 -426.373723) (xy 305.737761 -426.313718) (xy 305.759794 -426.255956) (xy 305.788665 -426.20129)
			(xy 305.823947 -426.150525) (xy 305.844194 -426.127164) (xy 305.850544 -426.120306) (xy 305.857148 -426.103034)
			(xy 305.857148 -426.016166) (xy 305.850544 -425.998894) (xy 305.844194 -425.992036) (xy 305.82395 -425.968673)
			(xy 305.788671 -425.917906) (xy 305.759801 -425.86324) (xy 305.737765 -425.805479) (xy 305.722888 -425.745475)
			(xy 305.715387 -425.684111) (xy 305.714908 -425.6532) (xy 305.715373 -425.622051) (xy 305.722975 -425.560218)
			(xy 305.738077 -425.499778) (xy 305.760453 -425.441636) (xy 305.789767 -425.386665) (xy 305.825579 -425.335689)
			(xy 305.867353 -425.289472) (xy 305.914463 -425.248707) (xy 305.966202 -425.214006) (xy 305.9938 -425.199556)
			(xy 306.004976 -425.193968) (xy 306.018946 -425.17441) (xy 306.033932 -425.080938) (xy 306.035201 -425.068928)
			(xy 306.027773 -425.045986) (xy 306.019708 -425.036996) (xy 304.992024 -424.009312) (xy 304.984622 -424.002476)
			(xy 304.966024 -423.994768) (xy 304.955956 -423.994326) (xy 301.844964 -423.994326) (xy 301.834896 -423.993897)
			(xy 301.816299 -423.986176) (xy 301.808896 -423.97934) (xy 293.167562 -415.338006) (xy 293.160162 -415.331165)
			(xy 293.141564 -415.323443) (xy 293.131494 -415.32302) (xy 288.28238 -415.32302) (xy 288.256726 -415.340546)
			(xy 288.251138 -415.355278) (xy 288.239032 -415.385039) (xy 288.208379 -415.441506) (xy 288.170857 -415.493663)
			(xy 288.127066 -415.540678) (xy 288.077701 -415.581804) (xy 288.023549 -415.616384) (xy 287.965473 -415.643867)
			(xy 287.904398 -415.663818) (xy 287.841297 -415.675916) (xy 287.777174 -415.679971) (xy 287.713051 -415.675916)
			(xy 287.64995 -415.663818) (xy 287.588875 -415.643867) (xy 287.530799 -415.616384) (xy 287.476647 -415.581804)
			(xy 287.427282 -415.540678) (xy 287.383491 -415.493663) (xy 287.345969 -415.441506) (xy 287.315316 -415.385039)
			(xy 287.30321 -415.355278) (xy 287.297622 -415.340546) (xy 287.271968 -415.32302) (xy 286.161988 -415.32302)
			(xy 286.134048 -415.346134) (xy 286.130492 -415.364168) (xy 286.123986 -415.395438) (xy 286.104195 -415.456167)
			(xy 286.076954 -415.513938) (xy 286.042692 -415.567843) (xy 286.001949 -415.617032) (xy 285.955365 -415.660731)
			(xy 285.903675 -415.698251) (xy 285.847693 -415.729002) (xy 285.788301 -415.752499) (xy 285.726433 -415.768372)
			(xy 285.663064 -415.776372) (xy 285.599192 -415.776372) (xy 285.535823 -415.768372) (xy 285.473955 -415.752499)
			(xy 285.414563 -415.729002) (xy 285.358581 -415.698251) (xy 285.306891 -415.660731) (xy 285.260307 -415.617032)
			(xy 285.219564 -415.567843) (xy 285.185302 -415.513938) (xy 285.158061 -415.456167) (xy 285.13827 -415.395438)
			(xy 285.131764 -415.364168) (xy 285.128208 -415.346134) (xy 285.100268 -415.32302) (xy 279.115266 -415.32302)
			(xy 279.086564 -415.348674) (xy 279.084278 -415.367978) (xy 279.080129 -415.39994) (xy 279.064787 -415.462541)
			(xy 279.041657 -415.522701) (xy 279.01111 -415.579456) (xy 278.973635 -415.631895) (xy 278.929835 -415.679178)
			(xy 278.88041 -415.720547) (xy 278.826153 -415.755339) (xy 278.767935 -415.782995) (xy 278.706689 -415.803073)
			(xy 278.643396 -415.815249) (xy 278.579072 -415.81933) (xy 278.514748 -415.815249) (xy 278.451455 -415.803073)
			(xy 278.390209 -415.782995) (xy 278.331991 -415.755339) (xy 278.277734 -415.720547) (xy 278.228309 -415.679178)
			(xy 278.184509 -415.631895) (xy 278.147034 -415.579456) (xy 278.116487 -415.522701) (xy 278.093357 -415.462541)
			(xy 278.078015 -415.39994) (xy 278.073866 -415.367978) (xy 278.07158 -415.348674) (xy 278.042878 -415.32302)
			(xy 277.211282 -415.32302) (xy 277.201214 -415.323447) (xy 277.182616 -415.331168) (xy 277.175214 -415.338006)
			(xy 275.498835 -417.014385) (xy 284.219894 -417.014385) (xy 284.219894 -416.961087) (xy 284.227837 -416.908383)
			(xy 284.243547 -416.857453) (xy 284.266673 -416.809432) (xy 284.296697 -416.765395) (xy 284.332949 -416.726324)
			(xy 284.37462 -416.693093) (xy 284.420778 -416.666444) (xy 284.470392 -416.646972) (xy 284.522354 -416.635112)
			(xy 284.575504 -416.631129) (xy 284.628654 -416.635112) (xy 284.680616 -416.646972) (xy 284.73023 -416.666444)
			(xy 284.776388 -416.693093) (xy 284.818059 -416.726324) (xy 284.854311 -416.765395) (xy 284.884335 -416.809432)
			(xy 284.907461 -416.857453) (xy 284.923171 -416.908383) (xy 284.931114 -416.961087) (xy 284.931612 -416.987736)
			(xy 284.931114 -417.014385) (xy 284.928434 -417.032165) (xy 285.518088 -417.032165) (xy 285.518088 -416.978867)
			(xy 285.526031 -416.926163) (xy 285.541741 -416.875233) (xy 285.564867 -416.827212) (xy 285.594891 -416.783175)
			(xy 285.631143 -416.744104) (xy 285.672814 -416.710873) (xy 285.718972 -416.684224) (xy 285.768586 -416.664752)
			(xy 285.820548 -416.652892) (xy 285.873698 -416.648909) (xy 285.926848 -416.652892) (xy 285.97881 -416.664752)
			(xy 286.028424 -416.684224) (xy 286.074582 -416.710873) (xy 286.116253 -416.744104) (xy 286.152505 -416.783175)
			(xy 286.182529 -416.827212) (xy 286.205655 -416.875233) (xy 286.221365 -416.926163) (xy 286.229308 -416.978867)
			(xy 286.229806 -417.005516) (xy 286.229313 -417.031911) (xy 286.860478 -417.031911) (xy 286.860478 -416.978613)
			(xy 286.868421 -416.925909) (xy 286.884131 -416.874979) (xy 286.907257 -416.826958) (xy 286.937281 -416.782921)
			(xy 286.973533 -416.74385) (xy 287.015204 -416.710619) (xy 287.061362 -416.68397) (xy 287.110976 -416.664498)
			(xy 287.162938 -416.652638) (xy 287.216088 -416.648655) (xy 287.269238 -416.652638) (xy 287.3212 -416.664498)
			(xy 287.370814 -416.68397) (xy 287.416972 -416.710619) (xy 287.458643 -416.74385) (xy 287.494895 -416.782921)
			(xy 287.524919 -416.826958) (xy 287.548045 -416.874979) (xy 287.563755 -416.925909) (xy 287.571698 -416.978613)
			(xy 287.572196 -417.005262) (xy 287.571698 -417.031911) (xy 287.563755 -417.084615) (xy 287.548045 -417.135545)
			(xy 287.524919 -417.183566) (xy 287.494895 -417.227603) (xy 287.458643 -417.266674) (xy 287.416972 -417.299905)
			(xy 287.370814 -417.326554) (xy 287.3212 -417.346026) (xy 287.269238 -417.357886) (xy 287.216088 -417.36187)
			(xy 287.162938 -417.357886) (xy 287.110976 -417.346026) (xy 287.061362 -417.326554) (xy 287.015204 -417.299905)
			(xy 286.973533 -417.266674) (xy 286.937281 -417.227603) (xy 286.907257 -417.183566) (xy 286.884131 -417.135545)
			(xy 286.868421 -417.084615) (xy 286.860478 -417.031911) (xy 286.229313 -417.031911) (xy 286.229308 -417.032165)
			(xy 286.221365 -417.084869) (xy 286.205655 -417.135799) (xy 286.182529 -417.18382) (xy 286.152505 -417.227857)
			(xy 286.116253 -417.266928) (xy 286.074582 -417.300159) (xy 286.028424 -417.326808) (xy 285.97881 -417.34628)
			(xy 285.926848 -417.35814) (xy 285.873698 -417.362124) (xy 285.820548 -417.35814) (xy 285.768586 -417.34628)
			(xy 285.718972 -417.326808) (xy 285.672814 -417.300159) (xy 285.631143 -417.266928) (xy 285.594891 -417.227857)
			(xy 285.564867 -417.18382) (xy 285.541741 -417.135799) (xy 285.526031 -417.084869) (xy 285.518088 -417.032165)
			(xy 284.928434 -417.032165) (xy 284.923171 -417.067089) (xy 284.907461 -417.118019) (xy 284.884335 -417.16604)
			(xy 284.854311 -417.210077) (xy 284.818059 -417.249148) (xy 284.776388 -417.282379) (xy 284.73023 -417.309028)
			(xy 284.680616 -417.3285) (xy 284.628654 -417.34036) (xy 284.575504 -417.344344) (xy 284.522354 -417.34036)
			(xy 284.470392 -417.3285) (xy 284.420778 -417.309028) (xy 284.37462 -417.282379) (xy 284.332949 -417.249148)
			(xy 284.296697 -417.210077) (xy 284.266673 -417.16604) (xy 284.243547 -417.118019) (xy 284.227837 -417.067089)
			(xy 284.219894 -417.014385) (xy 275.498835 -417.014385) (xy 275.421344 -417.091876) (xy 275.417534 -417.102798)
			(xy 275.402132 -417.144905) (xy 275.364127 -417.226115) (xy 275.318255 -417.303156) (xy 275.264967 -417.375267)
			(xy 275.204789 -417.441736) (xy 275.16169 -417.48075) (xy 276.514814 -417.48075) (xy 276.5153 -417.453499)
			(xy 276.523056 -417.399551) (xy 276.538411 -417.347256) (xy 276.561053 -417.297679) (xy 276.590519 -417.251829)
			(xy 276.62621 -417.210638) (xy 276.667401 -417.174947) (xy 276.713251 -417.145481) (xy 276.762828 -417.122839)
			(xy 276.815123 -417.107484) (xy 276.869071 -417.099728) (xy 276.923573 -417.099728) (xy 276.977521 -417.107484)
			(xy 277.029816 -417.122839) (xy 277.079393 -417.145481) (xy 277.125243 -417.174947) (xy 277.166434 -417.210638)
			(xy 277.202125 -417.251829) (xy 277.231591 -417.297679) (xy 277.254233 -417.347256) (xy 277.269588 -417.399551)
			(xy 277.275529 -417.440872) (xy 278.121108 -417.440872) (xy 278.125179 -417.38525) (xy 278.137305 -417.330813)
			(xy 278.157228 -417.278722) (xy 278.184524 -417.230087) (xy 278.21861 -417.185944) (xy 278.258759 -417.147235)
			(xy 278.304117 -417.114784) (xy 278.353717 -417.089283) (xy 278.406501 -417.071276) (xy 278.461344 -417.061146)
			(xy 278.517078 -417.059109) (xy 278.572515 -417.065209) (xy 278.626472 -417.079315) (xy 278.677801 -417.101127)
			(xy 278.725407 -417.130181) (xy 278.768275 -417.165856) (xy 278.805492 -417.207393) (xy 278.836265 -417.253906)
			(xy 278.859937 -417.304403) (xy 278.876005 -417.35781) (xy 278.884125 -417.412986) (xy 278.884634 -417.440872)
			(xy 278.884125 -417.468758) (xy 278.876005 -417.523934) (xy 278.859937 -417.577341) (xy 278.836265 -417.627838)
			(xy 278.805492 -417.674351) (xy 278.768275 -417.715888) (xy 278.725407 -417.751563) (xy 278.677801 -417.780617)
			(xy 278.626472 -417.802429) (xy 278.572515 -417.816535) (xy 278.517078 -417.822635) (xy 278.461344 -417.820598)
			(xy 278.406501 -417.810468) (xy 278.353717 -417.792461) (xy 278.304117 -417.76696) (xy 278.258759 -417.734509)
			(xy 278.21861 -417.6958) (xy 278.184524 -417.651657) (xy 278.157228 -417.603022) (xy 278.137305 -417.550931)
			(xy 278.125179 -417.496494) (xy 278.121108 -417.440872) (xy 277.275529 -417.440872) (xy 277.277344 -417.453499)
			(xy 277.27783 -417.48075) (xy 277.277467 -417.504687) (xy 277.271498 -417.552187) (xy 277.259622 -417.598564)
			(xy 277.25116 -417.620958) (xy 277.247604 -417.630102) (xy 277.247604 -417.649914) (xy 277.282402 -417.73348)
			(xy 277.296118 -417.74745) (xy 277.305262 -417.751514) (xy 277.335191 -417.765056) (xy 277.391623 -417.798684)
			(xy 277.443254 -417.8393) (xy 277.489224 -417.886227) (xy 277.528767 -417.938684) (xy 277.561224 -417.995797)
			(xy 277.586055 -418.056614) (xy 277.602847 -418.120123) (xy 277.611319 -418.185266) (xy 277.61184 -418.218112)
			(xy 277.611256 -418.253067) (xy 277.609983 -418.262287) (xy 284.17519 -418.262287) (xy 284.17519 -418.208989)
			(xy 284.183133 -418.156285) (xy 284.198843 -418.105355) (xy 284.221969 -418.057334) (xy 284.251993 -418.013297)
			(xy 284.288245 -417.974226) (xy 284.329916 -417.940995) (xy 284.376074 -417.914346) (xy 284.425688 -417.894874)
			(xy 284.47765 -417.883014) (xy 284.5308 -417.879031) (xy 284.58395 -417.883014) (xy 284.635912 -417.894874)
			(xy 284.685526 -417.914346) (xy 284.731684 -417.940995) (xy 284.773355 -417.974226) (xy 284.809607 -418.013297)
			(xy 284.839631 -418.057334) (xy 284.862757 -418.105355) (xy 284.878467 -418.156285) (xy 284.88641 -418.208989)
			(xy 284.886908 -418.235638) (xy 284.88641 -418.262287) (xy 284.878467 -418.314991) (xy 284.867145 -418.351695)
			(xy 286.838126 -418.351695) (xy 286.838126 -418.298397) (xy 286.846069 -418.245693) (xy 286.861779 -418.194763)
			(xy 286.884905 -418.146742) (xy 286.914929 -418.102705) (xy 286.951181 -418.063634) (xy 286.992852 -418.030403)
			(xy 287.03901 -418.003754) (xy 287.088624 -417.984282) (xy 287.140586 -417.972422) (xy 287.193736 -417.968439)
			(xy 287.246886 -417.972422) (xy 287.298848 -417.984282) (xy 287.348462 -418.003754) (xy 287.39462 -418.030403)
			(xy 287.436291 -418.063634) (xy 287.472543 -418.102705) (xy 287.502567 -418.146742) (xy 287.525693 -418.194763)
			(xy 287.541403 -418.245693) (xy 287.549346 -418.298397) (xy 287.549844 -418.325046) (xy 287.549346 -418.351695)
			(xy 287.541403 -418.404399) (xy 287.525693 -418.455329) (xy 287.502567 -418.50335) (xy 287.472543 -418.547387)
			(xy 287.448871 -418.5729) (xy 288.426739 -418.5729) (xy 288.430752 -418.509113) (xy 288.442728 -418.446332)
			(xy 288.462478 -418.385546) (xy 288.48969 -418.327715) (xy 288.523935 -418.273751) (xy 288.564673 -418.224504)
			(xy 288.611263 -418.180751) (xy 288.662968 -418.143181) (xy 288.718974 -418.112389) (xy 288.778398 -418.088858)
			(xy 288.840303 -418.07296) (xy 288.903711 -418.064946) (xy 288.935668 -418.064442) (xy 288.971156 -418.065025)
			(xy 289.041441 -418.074903) (xy 289.109666 -418.094471) (xy 289.174503 -418.123348) (xy 289.204908 -418.141658)
			(xy 289.214814 -418.147754) (xy 289.237674 -418.150294) (xy 289.334702 -418.116004) (xy 289.350958 -418.099748)
			(xy 289.354768 -418.088572) (xy 289.364983 -418.060326) (xy 289.391124 -418.006245) (xy 289.423451 -417.955619)
			(xy 289.442144 -417.932108) (xy 289.447441 -417.925109) (xy 289.453415 -417.908618) (xy 289.453828 -417.89985)
			(xy 289.453828 -417.745926) (xy 289.453449 -417.737151) (xy 289.447475 -417.720648) (xy 289.442144 -417.713668)
			(xy 289.420423 -417.686275) (xy 289.383925 -417.626648) (xy 289.355933 -417.562586) (xy 289.336975 -417.495296)
			(xy 289.327406 -417.426043) (xy 289.326828 -417.391088) (xy 289.327379 -417.358939) (xy 289.335497 -417.295155)
			(xy 289.351589 -417.232903) (xy 289.375399 -417.173176) (xy 289.406547 -417.116925) (xy 289.444535 -417.065049)
			(xy 289.488759 -417.018375) (xy 289.538513 -416.977647) (xy 289.593004 -416.943514) (xy 289.621976 -416.92957)
			(xy 289.632136 -416.924744) (xy 289.646614 -416.90798) (xy 289.673284 -416.811206) (xy 289.669474 -416.789362)
			(xy 289.663124 -416.779964) (xy 289.647364 -416.756017) (xy 289.622391 -416.704417) (xy 289.605422 -416.64966)
			(xy 289.596839 -416.592981) (xy 289.596322 -416.564318) (xy 289.596808 -416.537067) (xy 289.604564 -416.483119)
			(xy 289.619919 -416.430824) (xy 289.642561 -416.381247) (xy 289.672027 -416.335397) (xy 289.707718 -416.294206)
			(xy 289.748909 -416.258515) (xy 289.794759 -416.229049) (xy 289.844336 -416.206407) (xy 289.896631 -416.191052)
			(xy 289.950579 -416.183296) (xy 290.005081 -416.183296) (xy 290.059029 -416.191052) (xy 290.111324 -416.206407)
			(xy 290.160901 -416.229049) (xy 290.206751 -416.258515) (xy 290.247942 -416.294206) (xy 290.283633 -416.335397)
			(xy 290.313099 -416.381247) (xy 290.335741 -416.430824) (xy 290.351096 -416.483119) (xy 290.358852 -416.537067)
			(xy 290.359338 -416.564318) (xy 290.358948 -416.589999) (xy 290.35207 -416.640897) (xy 290.338429 -416.690413)
			(xy 290.318271 -416.737653) (xy 290.291959 -416.781762) (xy 290.259969 -416.821944) (xy 290.22288 -416.857473)
			(xy 290.202366 -416.872928) (xy 290.192968 -416.879532) (xy 290.1823 -416.898836) (xy 290.174934 -416.998912)
			(xy 290.182808 -417.01974) (xy 290.190936 -417.027614) (xy 290.214675 -417.051622) (xy 290.256268 -417.104805)
			(xy 290.290456 -417.163025) (xy 290.316639 -417.225258) (xy 290.334354 -417.290408) (xy 290.343292 -417.35733)
			(xy 290.343844 -417.391088) (xy 290.343246 -417.426043) (xy 290.333687 -417.495295) (xy 290.314733 -417.562585)
			(xy 290.286742 -417.626646) (xy 290.250241 -417.686269) (xy 290.228528 -417.713668) (xy 290.223238 -417.720671)
			(xy 290.21726 -417.73716) (xy 290.216844 -417.745926) (xy 290.216844 -417.89985) (xy 290.21724 -417.908624)
			(xy 290.223203 -417.925126) (xy 290.228528 -417.932108) (xy 290.250249 -417.959501) (xy 290.286744 -418.019129)
			(xy 290.314735 -418.083191) (xy 290.333694 -418.150481) (xy 290.343264 -418.219733) (xy 290.343844 -418.254688)
			(xy 290.343491 -418.282344) (xy 290.337504 -418.33733) (xy 290.331906 -418.364416) (xy 290.32962 -418.37483)
			(xy 290.33343 -418.39515) (xy 290.387024 -418.47389) (xy 290.404296 -418.484812) (xy 290.414964 -418.48659)
			(xy 290.440587 -418.491137) (xy 290.490351 -418.506359) (xy 290.537587 -418.528197) (xy 290.58142 -418.556249)
			(xy 290.621038 -418.589993) (xy 290.655706 -418.628804) (xy 290.684782 -418.671964) (xy 290.69665 -418.695124)
			(xy 290.702492 -418.706808) (xy 290.723574 -418.721794) (xy 290.834826 -418.733986) (xy 290.858702 -418.724334)
			(xy 290.867084 -418.71392) (xy 290.885312 -418.692133) (xy 290.927107 -418.653663) (xy 290.974143 -418.621814)
			(xy 291.02538 -418.597289) (xy 291.079686 -418.58063) (xy 291.135862 -418.572205) (xy 291.164264 -418.57168)
			(xy 291.191515 -418.572189) (xy 291.245464 -418.579941) (xy 291.29776 -418.595291) (xy 291.34734 -418.617929)
			(xy 291.393192 -418.647392) (xy 291.434385 -418.683081) (xy 291.470079 -418.724269) (xy 291.499548 -418.770118)
			(xy 291.522192 -418.819695) (xy 291.537549 -418.871989) (xy 291.545308 -418.925937) (xy 291.545772 -418.953188)
			(xy 291.545332 -418.979234) (xy 291.538257 -419.030842) (xy 291.524235 -419.08101) (xy 291.503528 -419.128808)
			(xy 291.4904 -419.151308) (xy 291.48588 -419.159562) (xy 291.482488 -419.178057) (xy 291.483796 -419.187376)
			(xy 291.489892 -419.217856) (xy 291.492072 -419.227216) (xy 291.502406 -419.243406) (xy 291.509958 -419.249352)
			(xy 291.533966 -419.267305) (xy 291.578009 -419.307977) (xy 291.616963 -419.353546) (xy 291.650287 -419.403381)
			(xy 291.677518 -419.45679) (xy 291.698279 -419.51303) (xy 291.71228 -419.571323) (xy 291.719327 -419.630857)
			(xy 291.719762 -419.660832) (xy 291.719185 -419.695787) (xy 291.70962 -419.76504) (xy 291.690661 -419.832331)
			(xy 291.662665 -419.896391) (xy 291.626161 -419.956013) (xy 291.604446 -419.983412) (xy 291.599164 -419.990404)
			(xy 291.593326 -420.006912) (xy 291.593016 -420.01567) (xy 291.593016 -420.169594) (xy 291.59338 -420.178341)
			(xy 291.599216 -420.194832) (xy 291.604446 -420.201852) (xy 291.626144 -420.229263) (xy 291.662642 -420.288886)
			(xy 291.690637 -420.352943) (xy 291.709602 -420.42023) (xy 291.719179 -420.489478) (xy 291.719623 -420.516122)
			(xy 292.906778 -420.516122) (xy 292.909385 -420.45309) (xy 292.919769 -420.390864) (xy 292.93777 -420.330401)
			(xy 292.963112 -420.272628) (xy 292.995405 -420.218434) (xy 293.034154 -420.168651) (xy 293.078763 -420.124043)
			(xy 293.128548 -420.085296) (xy 293.182743 -420.053004) (xy 293.240516 -420.027664) (xy 293.30098 -420.009665)
			(xy 293.363205 -419.999284) (xy 293.426238 -419.996679) (xy 293.489108 -420.00189) (xy 293.550851 -420.014839)
			(xy 293.610518 -420.035326) (xy 293.667193 -420.063035) (xy 293.720004 -420.097543) (xy 293.768142 -420.138317)
			(xy 293.810867 -420.184734) (xy 293.847522 -420.236078) (xy 293.877544 -420.291562) (xy 293.900473 -420.350334)
			(xy 293.915955 -420.411491) (xy 293.923754 -420.474093) (xy 293.924228 -420.505636) (xy 293.923867 -420.532374)
			(xy 293.918244 -420.585554) (xy 293.907063 -420.637848) (xy 293.899082 -420.66337) (xy 293.89451 -420.677594)
			(xy 293.901622 -420.705788) (xy 293.990268 -420.789354) (xy 294.01897 -420.794942) (xy 294.03294 -420.789354)
			(xy 294.062691 -420.77817) (xy 294.124277 -420.762455) (xy 294.187342 -420.754537) (xy 294.219122 -420.754048)
			(xy 294.251872 -420.75454) (xy 294.316829 -420.762969) (xy 294.380164 -420.77967) (xy 294.440831 -420.804368)
			(xy 294.497822 -420.836653) (xy 294.550195 -420.875991) (xy 294.597082 -420.921729) (xy 294.637705 -420.973111)
			(xy 294.654986 -421.000936) (xy 294.662606 -421.013128) (xy 294.687498 -421.026336) (xy 294.80637 -421.018716)
			(xy 294.829484 -421.00246) (xy 294.835326 -420.989252) (xy 294.84685 -420.96417) (xy 294.876088 -420.917353)
			(xy 294.91177 -420.87524) (xy 294.953151 -420.838712) (xy 294.999366 -420.808531) (xy 295.04945 -420.785329)
			(xy 295.102355 -420.76959) (xy 295.156977 -420.761643) (xy 295.184576 -420.76116) (xy 295.21082 -420.761574)
			(xy 295.262812 -420.768759) (xy 295.313327 -420.78301) (xy 295.361409 -420.804057) (xy 295.406148 -420.831502)
			(xy 295.446699 -420.864827) (xy 295.482293 -420.9034) (xy 295.512258 -420.946493) (xy 295.536027 -420.993289)
			(xy 295.545002 -421.017954) (xy 295.549574 -421.030908) (xy 295.570656 -421.048942) (xy 295.685464 -421.069008)
			(xy 295.711118 -421.059356) (xy 295.720008 -421.048688) (xy 295.740753 -421.023936) (xy 295.787479 -420.979355)
			(xy 295.839476 -420.94105) (xy 295.895905 -420.90964) (xy 295.955859 -420.885629) (xy 296.01837 -420.869405)
			(xy 296.082433 -420.861229) (xy 296.114724 -420.860728) (xy 296.146686 -420.861159) (xy 296.210107 -420.869174)
			(xy 296.272022 -420.885074) (xy 296.331457 -420.908608) (xy 296.387474 -420.939406) (xy 296.439189 -420.976982)
			(xy 296.485787 -421.020742) (xy 296.526533 -421.069998) (xy 296.560785 -421.123972) (xy 296.588002 -421.181813)
			(xy 296.607755 -421.242609) (xy 296.619733 -421.305401) (xy 296.623747 -421.3692) (xy 296.619733 -421.432999)
			(xy 296.607755 -421.495791) (xy 296.588002 -421.556587) (xy 296.560785 -421.614428) (xy 296.526533 -421.668402)
			(xy 296.485787 -421.717658) (xy 296.439189 -421.761418) (xy 296.387474 -421.798994) (xy 296.331457 -421.829792)
			(xy 296.272022 -421.853326) (xy 296.210107 -421.869226) (xy 296.146686 -421.877241) (xy 296.114724 -421.877744)
			(xy 296.083133 -421.877219) (xy 296.02044 -421.869372) (xy 295.959203 -421.853819) (xy 295.900363 -421.830801)
			(xy 295.844827 -421.800673) (xy 295.793451 -421.763897) (xy 295.747025 -421.721041) (xy 295.706265 -421.672765)
			(xy 295.671799 -421.619811) (xy 295.644158 -421.562997) (xy 295.623766 -421.503196) (xy 295.616884 -421.47236)
			(xy 295.61409 -421.458644) (xy 295.595548 -421.438324) (xy 295.484296 -421.403526) (xy 295.457372 -421.409622)
			(xy 295.447212 -421.419274) (xy 295.425831 -421.438856) (xy 295.378245 -421.471975) (xy 295.326192 -421.497506)
			(xy 295.270873 -421.51486) (xy 295.213564 -421.523637) (xy 295.184576 -421.524176) (xy 295.15563 -421.523645)
			(xy 295.098404 -421.514888) (xy 295.043155 -421.497594) (xy 294.991149 -421.472159) (xy 294.943579 -421.439166)
			(xy 294.901533 -421.39937) (xy 294.883332 -421.376856) (xy 294.874442 -421.365426) (xy 294.848026 -421.355266)
			(xy 294.730932 -421.37711) (xy 294.710104 -421.395906) (xy 294.705786 -421.409622) (xy 294.695953 -421.440588)
			(xy 294.669394 -421.499885) (xy 294.635497 -421.555315) (xy 294.594815 -421.605975) (xy 294.548011 -421.65104)
			(xy 294.495847 -421.689776) (xy 294.439174 -421.721551) (xy 294.378915 -421.745847) (xy 294.316052 -421.762269)
			(xy 294.251608 -421.770548) (xy 294.219122 -421.771064) (xy 294.188389 -421.770642) (xy 294.12737 -421.763235)
			(xy 294.067689 -421.748526) (xy 294.010216 -421.72673) (xy 293.95579 -421.698166) (xy 293.905205 -421.663248)
			(xy 293.859197 -421.622488) (xy 293.818438 -421.576478) (xy 293.783523 -421.525891) (xy 293.75496 -421.471463)
			(xy 293.733167 -421.41399) (xy 293.718461 -421.354308) (xy 293.711057 -421.293289) (xy 293.710614 -421.262556)
			(xy 293.710971 -421.235818) (xy 293.716596 -421.182638) (xy 293.727778 -421.130343) (xy 293.73576 -421.104822)
			(xy 293.740332 -421.090598) (xy 293.73322 -421.062404) (xy 293.644574 -420.978838) (xy 293.615872 -420.97325)
			(xy 293.601902 -420.978838) (xy 293.572147 -420.99001) (xy 293.510563 -421.005729) (xy 293.447499 -421.013652)
			(xy 293.41572 -421.014144) (xy 293.384177 -421.013653) (xy 293.321575 -421.005852) (xy 293.260419 -420.990368)
			(xy 293.201648 -420.967437) (xy 293.146165 -420.937413) (xy 293.094821 -420.900757) (xy 293.048406 -420.858031)
			(xy 293.007633 -420.809892) (xy 292.973127 -420.757079) (xy 292.945419 -420.700403) (xy 292.924935 -420.640735)
			(xy 292.911988 -420.578992) (xy 292.906778 -420.516122) (xy 291.719623 -420.516122) (xy 291.719762 -420.524432)
			(xy 291.719274 -420.555431) (xy 291.711728 -420.616969) (xy 291.696753 -420.677131) (xy 291.67457 -420.735025)
			(xy 291.64551 -420.789791) (xy 291.610004 -420.840615) (xy 291.568579 -420.886743) (xy 291.545518 -420.907464)
			(xy 291.53866 -420.91356) (xy 291.530024 -420.929562) (xy 291.518086 -421.013382) (xy 291.521896 -421.030908)
			(xy 291.526722 -421.038782) (xy 291.54092 -421.061871) (xy 291.563326 -421.111226) (xy 291.578519 -421.163256)
			(xy 291.586191 -421.216913) (xy 291.586666 -421.244014) (xy 291.58618 -421.271265) (xy 291.578424 -421.325213)
			(xy 291.563069 -421.377508) (xy 291.540427 -421.427085) (xy 291.510961 -421.472935) (xy 291.47527 -421.514126)
			(xy 291.434079 -421.549817) (xy 291.388229 -421.579283) (xy 291.338652 -421.601925) (xy 291.286357 -421.61728)
			(xy 291.232409 -421.625036) (xy 291.177907 -421.625036) (xy 291.123959 -421.61728) (xy 291.071664 -421.601925)
			(xy 291.022087 -421.579283) (xy 290.976237 -421.549817) (xy 290.935046 -421.514126) (xy 290.899355 -421.472935)
			(xy 290.869889 -421.427085) (xy 290.847247 -421.377508) (xy 290.831892 -421.325213) (xy 290.824136 -421.271265)
			(xy 290.82365 -421.244014) (xy 290.824142 -421.216112) (xy 290.832292 -421.160906) (xy 290.848404 -421.107478)
			(xy 290.872135 -421.056971) (xy 290.88715 -421.033448) (xy 290.89223 -421.025574) (xy 290.896294 -421.008048)
			(xy 290.885626 -420.923974) (xy 290.877244 -420.907972) (xy 290.870386 -420.901876) (xy 290.848169 -420.881142)
			(xy 290.80825 -420.835322) (xy 290.774076 -420.785071) (xy 290.746132 -420.731107) (xy 290.724817 -420.674198)
			(xy 290.710435 -420.615154) (xy 290.70319 -420.554817) (xy 290.702746 -420.524432) (xy 290.703301 -420.489476)
			(xy 290.712871 -420.420222) (xy 290.731835 -420.352931) (xy 290.759836 -420.288871) (xy 290.796345 -420.22925)
			(xy 290.818062 -420.201852) (xy 290.823318 -420.194843) (xy 290.829172 -420.178348) (xy 290.829492 -420.169594)
			(xy 290.829492 -420.01567) (xy 290.829143 -420.006922) (xy 290.823296 -419.990431) (xy 290.818062 -419.983412)
			(xy 290.796349 -419.956013) (xy 290.759853 -419.896387) (xy 290.73186 -419.832326) (xy 290.7129 -419.765037)
			(xy 290.703327 -419.695787) (xy 290.702746 -419.660832) (xy 290.703326 -419.626471) (xy 290.712571 -419.558375)
			(xy 290.730897 -419.492143) (xy 290.75797 -419.428979) (xy 290.793298 -419.370034) (xy 290.836239 -419.316381)
			(xy 290.860734 -419.292278) (xy 290.867408 -419.285397) (xy 290.875498 -419.268032) (xy 290.876482 -419.258496)
			(xy 290.87826 -419.227508) (xy 290.878413 -419.218147) (xy 290.87282 -419.200298) (xy 290.867338 -419.19271)
			(xy 290.854249 -419.176023) (xy 290.831466 -419.14025) (xy 290.821872 -419.121336) (xy 290.81603 -419.109652)
			(xy 290.794948 -419.094666) (xy 290.683696 -419.082474) (xy 290.65982 -419.092126) (xy 290.651438 -419.10254)
			(xy 290.633188 -419.124308) (xy 290.591399 -419.162781) (xy 290.544368 -419.194633) (xy 290.493135 -419.219162)
			(xy 290.438832 -419.235825) (xy 290.382659 -419.244254) (xy 290.354258 -419.24478) (xy 290.327016 -419.244362)
			(xy 290.273087 -419.236606) (xy 290.220809 -419.221257) (xy 290.171247 -419.198627) (xy 290.125408 -419.169177)
			(xy 290.084224 -419.133506) (xy 290.048533 -419.09234) (xy 290.019061 -419.046515) (xy 289.996408 -418.996963)
			(xy 289.981034 -418.944693) (xy 289.973251 -418.890768) (xy 289.97275 -418.863526) (xy 289.97275 -418.852858)
			(xy 289.964622 -418.834062) (xy 289.89528 -418.768784) (xy 289.875976 -418.761672) (xy 289.865308 -418.762434)
			(xy 289.835336 -418.763196) (xy 289.799848 -418.76262) (xy 289.729562 -418.752741) (xy 289.661336 -418.733172)
			(xy 289.596501 -418.704292) (xy 289.566096 -418.68598) (xy 289.55619 -418.679884) (xy 289.53333 -418.677344)
			(xy 289.436302 -418.711634) (xy 289.420046 -418.72789) (xy 289.416236 -418.739066) (xy 289.405481 -418.768663)
			(xy 289.377729 -418.82519) (xy 289.343207 -418.877857) (xy 289.302445 -418.925856) (xy 289.256066 -418.968454)
			(xy 289.204781 -419.004996) (xy 289.149375 -419.034925) (xy 289.090697 -419.05778) (xy 289.029645 -419.073213)
			(xy 288.967154 -419.080987) (xy 288.935668 -419.081458) (xy 288.903711 -419.080854) (xy 288.840303 -419.07284)
			(xy 288.778398 -419.056942) (xy 288.718974 -419.033411) (xy 288.662968 -419.002619) (xy 288.611263 -418.965049)
			(xy 288.564673 -418.921296) (xy 288.523935 -418.872049) (xy 288.48969 -418.818085) (xy 288.462478 -418.760254)
			(xy 288.442728 -418.699468) (xy 288.430752 -418.636687) (xy 288.426739 -418.5729) (xy 287.448871 -418.5729)
			(xy 287.436291 -418.586458) (xy 287.39462 -418.619689) (xy 287.348462 -418.646338) (xy 287.298848 -418.66581)
			(xy 287.246886 -418.67767) (xy 287.193736 -418.681654) (xy 287.140586 -418.67767) (xy 287.088624 -418.66581)
			(xy 287.03901 -418.646338) (xy 286.992852 -418.619689) (xy 286.951181 -418.586458) (xy 286.914929 -418.547387)
			(xy 286.884905 -418.50335) (xy 286.861779 -418.455329) (xy 286.846069 -418.404399) (xy 286.838126 -418.351695)
			(xy 284.867145 -418.351695) (xy 284.862757 -418.365921) (xy 284.839631 -418.413942) (xy 284.809607 -418.457979)
			(xy 284.773355 -418.49705) (xy 284.731684 -418.530281) (xy 284.685526 -418.55693) (xy 284.635912 -418.576402)
			(xy 284.58395 -418.588262) (xy 284.5308 -418.592246) (xy 284.47765 -418.588262) (xy 284.425688 -418.576402)
			(xy 284.376074 -418.55693) (xy 284.329916 -418.530281) (xy 284.288245 -418.49705) (xy 284.251993 -418.457979)
			(xy 284.221969 -418.413942) (xy 284.198843 -418.365921) (xy 284.183133 -418.314991) (xy 284.17519 -418.262287)
			(xy 277.609983 -418.262287) (xy 277.601694 -418.32232) (xy 277.582737 -418.389611) (xy 277.554742 -418.453671)
			(xy 277.518238 -418.513294) (xy 277.496524 -418.540692) (xy 277.491224 -418.547689) (xy 277.485252 -418.564182)
			(xy 277.48484 -418.57295) (xy 277.48484 -418.726874) (xy 277.485225 -418.735649) (xy 277.491195 -418.752151)
			(xy 277.496524 -418.759132) (xy 277.518255 -418.786517) (xy 277.554749 -418.846147) (xy 277.582738 -418.910211)
			(xy 277.601694 -418.977503) (xy 277.611262 -419.046756) (xy 277.61184 -419.081712) (xy 277.611379 -419.114031)
			(xy 277.603186 -419.178148) (xy 277.586933 -419.240709) (xy 277.562883 -419.300707) (xy 277.531422 -419.357172)
			(xy 277.49306 -419.409195) (xy 277.448414 -419.455937) (xy 277.423626 -419.476682) (xy 277.415498 -419.483286)
			(xy 277.405846 -419.501066) (xy 277.397464 -419.594538) (xy 277.400739 -419.604909) (xy 282.318454 -419.604909)
			(xy 282.318454 -419.540987) (xy 282.326465 -419.477569) (xy 282.342362 -419.415655) (xy 282.365894 -419.356222)
			(xy 282.396688 -419.300207) (xy 282.434261 -419.248492) (xy 282.478018 -419.201895) (xy 282.527271 -419.16115)
			(xy 282.581242 -419.126899) (xy 282.639081 -419.099682) (xy 282.699874 -419.079929) (xy 282.762664 -419.067951)
			(xy 282.82646 -419.063938) (xy 282.890256 -419.067951) (xy 282.953046 -419.079929) (xy 283.013839 -419.099682)
			(xy 283.071678 -419.126899) (xy 283.125649 -419.16115) (xy 283.174902 -419.201895) (xy 283.218659 -419.248492)
			(xy 283.256232 -419.300207) (xy 283.287026 -419.356222) (xy 283.310558 -419.415655) (xy 283.326455 -419.477569)
			(xy 283.334466 -419.540987) (xy 283.334968 -419.572948) (xy 283.334466 -419.604909) (xy 283.329522 -419.644047)
			(xy 284.27552 -419.644047) (xy 284.27552 -419.590749) (xy 284.283463 -419.538045) (xy 284.299173 -419.487115)
			(xy 284.322299 -419.439094) (xy 284.352323 -419.395057) (xy 284.388575 -419.355986) (xy 284.430246 -419.322755)
			(xy 284.476404 -419.296106) (xy 284.526018 -419.276634) (xy 284.57798 -419.264774) (xy 284.63113 -419.260791)
			(xy 284.68428 -419.264774) (xy 284.736242 -419.276634) (xy 284.785856 -419.296106) (xy 284.832014 -419.322755)
			(xy 284.873685 -419.355986) (xy 284.909937 -419.395057) (xy 284.939961 -419.439094) (xy 284.963087 -419.487115)
			(xy 284.978797 -419.538045) (xy 284.98674 -419.590749) (xy 284.987238 -419.617398) (xy 284.98674 -419.644047)
			(xy 284.980921 -419.682655) (xy 285.590224 -419.682655) (xy 285.590224 -419.629357) (xy 285.598167 -419.576653)
			(xy 285.613877 -419.525723) (xy 285.637003 -419.477702) (xy 285.667027 -419.433665) (xy 285.703279 -419.394594)
			(xy 285.74495 -419.361363) (xy 285.791108 -419.334714) (xy 285.840722 -419.315242) (xy 285.892684 -419.303382)
			(xy 285.945834 -419.299399) (xy 285.998984 -419.303382) (xy 286.050946 -419.315242) (xy 286.10056 -419.334714)
			(xy 286.146718 -419.361363) (xy 286.188389 -419.394594) (xy 286.224641 -419.433665) (xy 286.254665 -419.477702)
			(xy 286.277791 -419.525723) (xy 286.293501 -419.576653) (xy 286.301444 -419.629357) (xy 286.301942 -419.656006)
			(xy 286.301444 -419.682655) (xy 286.72662 -419.682655) (xy 286.72662 -419.629357) (xy 286.734563 -419.576653)
			(xy 286.750273 -419.525723) (xy 286.773399 -419.477702) (xy 286.803423 -419.433665) (xy 286.839675 -419.394594)
			(xy 286.881346 -419.361363) (xy 286.927504 -419.334714) (xy 286.977118 -419.315242) (xy 287.02908 -419.303382)
			(xy 287.08223 -419.299399) (xy 287.13538 -419.303382) (xy 287.187342 -419.315242) (xy 287.236956 -419.334714)
			(xy 287.283114 -419.361363) (xy 287.324785 -419.394594) (xy 287.361037 -419.433665) (xy 287.391061 -419.477702)
			(xy 287.414187 -419.525723) (xy 287.429897 -419.576653) (xy 287.43784 -419.629357) (xy 287.438338 -419.656006)
			(xy 287.43784 -419.682655) (xy 287.429897 -419.735359) (xy 287.414187 -419.786289) (xy 287.391061 -419.83431)
			(xy 287.361037 -419.878347) (xy 287.324785 -419.917418) (xy 287.283114 -419.950649) (xy 287.236956 -419.977298)
			(xy 287.187342 -419.99677) (xy 287.13538 -420.00863) (xy 287.08223 -420.012614) (xy 287.02908 -420.00863)
			(xy 286.977118 -419.99677) (xy 286.927504 -419.977298) (xy 286.881346 -419.950649) (xy 286.839675 -419.917418)
			(xy 286.803423 -419.878347) (xy 286.773399 -419.83431) (xy 286.750273 -419.786289) (xy 286.734563 -419.735359)
			(xy 286.72662 -419.682655) (xy 286.301444 -419.682655) (xy 286.293501 -419.735359) (xy 286.277791 -419.786289)
			(xy 286.254665 -419.83431) (xy 286.224641 -419.878347) (xy 286.188389 -419.917418) (xy 286.146718 -419.950649)
			(xy 286.10056 -419.977298) (xy 286.050946 -419.99677) (xy 285.998984 -420.00863) (xy 285.945834 -420.012614)
			(xy 285.892684 -420.00863) (xy 285.840722 -419.99677) (xy 285.791108 -419.977298) (xy 285.74495 -419.950649)
			(xy 285.703279 -419.917418) (xy 285.667027 -419.878347) (xy 285.637003 -419.83431) (xy 285.613877 -419.786289)
			(xy 285.598167 -419.735359) (xy 285.590224 -419.682655) (xy 284.980921 -419.682655) (xy 284.978797 -419.696751)
			(xy 284.963087 -419.747681) (xy 284.939961 -419.795702) (xy 284.909937 -419.839739) (xy 284.873685 -419.87881)
			(xy 284.832014 -419.912041) (xy 284.785856 -419.93869) (xy 284.736242 -419.958162) (xy 284.68428 -419.970022)
			(xy 284.63113 -419.974006) (xy 284.57798 -419.970022) (xy 284.526018 -419.958162) (xy 284.476404 -419.93869)
			(xy 284.430246 -419.912041) (xy 284.388575 -419.87881) (xy 284.352323 -419.839739) (xy 284.322299 -419.795702)
			(xy 284.299173 -419.747681) (xy 284.283463 -419.696751) (xy 284.27552 -419.644047) (xy 283.329522 -419.644047)
			(xy 283.326455 -419.668327) (xy 283.310558 -419.730241) (xy 283.287026 -419.789674) (xy 283.256232 -419.845689)
			(xy 283.218659 -419.897404) (xy 283.174902 -419.944001) (xy 283.125649 -419.984746) (xy 283.071678 -420.018997)
			(xy 283.013839 -420.046214) (xy 282.953046 -420.065967) (xy 282.890256 -420.077945) (xy 282.82646 -420.081959)
			(xy 282.762664 -420.077945) (xy 282.699874 -420.065967) (xy 282.639081 -420.046214) (xy 282.581242 -420.018997)
			(xy 282.527271 -419.984746) (xy 282.478018 -419.944001) (xy 282.434261 -419.897404) (xy 282.396688 -419.845689)
			(xy 282.365894 -419.789674) (xy 282.342362 -419.730241) (xy 282.326465 -419.668327) (xy 282.318454 -419.604909)
			(xy 277.400739 -419.604909) (xy 277.40356 -419.613842) (xy 277.410418 -419.621716) (xy 277.427649 -419.642546)
			(xy 277.456653 -419.688164) (xy 277.478928 -419.73742) (xy 277.494027 -419.789326) (xy 277.501647 -419.842845)
			(xy 277.502112 -419.869874) (xy 277.501626 -419.897125) (xy 277.49387 -419.951073) (xy 277.478515 -420.003368)
			(xy 277.455873 -420.052945) (xy 277.426407 -420.098795) (xy 277.390716 -420.139986) (xy 277.349525 -420.175677)
			(xy 277.303675 -420.205143) (xy 277.254098 -420.227785) (xy 277.201803 -420.24314) (xy 277.147855 -420.250896)
			(xy 277.093353 -420.250896) (xy 277.039405 -420.24314) (xy 276.98711 -420.227785) (xy 276.937533 -420.205143)
			(xy 276.891683 -420.175677) (xy 276.850492 -420.139986) (xy 276.814801 -420.098795) (xy 276.785335 -420.052945)
			(xy 276.762693 -420.003368) (xy 276.747338 -419.951073) (xy 276.739582 -419.897125) (xy 276.739096 -419.869874)
			(xy 276.739489 -419.844522) (xy 276.746168 -419.794261) (xy 276.759458 -419.74533) (xy 276.779124 -419.698596)
			(xy 276.804817 -419.654885) (xy 276.820122 -419.63467) (xy 276.826726 -419.626288) (xy 276.83206 -419.606984)
			(xy 276.81936 -419.51402) (xy 276.8092 -419.496748) (xy 276.800818 -419.490398) (xy 276.773871 -419.469784)
			(xy 276.725181 -419.422536) (xy 276.68321 -419.36923) (xy 276.648704 -419.310814) (xy 276.622276 -419.248327)
			(xy 276.604396 -419.18288) (xy 276.595381 -419.115635) (xy 276.594824 -419.081712) (xy 276.595407 -419.046757)
			(xy 276.604968 -418.977503) (xy 276.623924 -418.910212) (xy 276.651919 -418.846152) (xy 276.688425 -418.78653)
			(xy 276.71014 -418.759132) (xy 276.715427 -418.752126) (xy 276.721407 -418.73564) (xy 276.721824 -418.726874)
			(xy 276.721824 -418.57295) (xy 276.721435 -418.564176) (xy 276.715468 -418.547673) (xy 276.71014 -418.540692)
			(xy 276.688429 -418.513291) (xy 276.65193 -418.453666) (xy 276.623936 -418.389607) (xy 276.604975 -418.322318)
			(xy 276.595404 -418.253067) (xy 276.594824 -418.218112) (xy 276.595315 -418.186829) (xy 276.602994 -418.124736)
			(xy 276.618236 -418.064055) (xy 276.640811 -418.005704) (xy 276.670378 -417.950565) (xy 276.688042 -417.924742)
			(xy 276.69363 -417.916614) (xy 276.698202 -417.89731) (xy 276.684232 -417.807902) (xy 276.674072 -417.791138)
			(xy 276.666198 -417.785042) (xy 276.643129 -417.766858) (xy 276.602259 -417.724671) (xy 276.568339 -417.676719)
			(xy 276.542169 -417.624134) (xy 276.524369 -417.56816) (xy 276.515358 -417.510118) (xy 276.514814 -417.48075)
			(xy 275.16169 -417.48075) (xy 275.138315 -417.501909) (xy 275.066201 -417.555192) (xy 274.989157 -417.601058)
			(xy 274.907943 -417.639057) (xy 274.865846 -417.654486) (xy 274.854924 -417.658296) (xy 274.365212 -418.148008)
			(xy 274.358103 -418.155802) (xy 274.350374 -418.175405) (xy 274.351186 -418.196462) (xy 274.355306 -418.206174)
			(xy 274.404074 -418.307266) (xy 274.432268 -418.32276) (xy 274.448524 -418.320982) (xy 274.477883 -418.317786)
			(xy 274.536848 -418.314352) (xy 274.56638 -418.314124) (xy 274.612141 -418.314622) (xy 274.703303 -418.322747)
			(xy 274.793383 -418.338935) (xy 274.881669 -418.363057) (xy 274.967465 -418.394924) (xy 275.050093 -418.434283)
			(xy 275.128899 -418.480824) (xy 275.203261 -418.534178) (xy 275.272592 -418.593925) (xy 275.336344 -418.659592)
			(xy 275.394013 -418.73066) (xy 275.445143 -418.806568) (xy 275.489332 -418.886717) (xy 275.526229 -418.970473)
			(xy 275.555543 -419.057174) (xy 275.577042 -419.146136) (xy 275.590557 -419.236656) (xy 275.595981 -419.328018)
			(xy 275.593271 -419.4195) (xy 275.582449 -419.510381) (xy 275.563599 -419.599942) (xy 275.536871 -419.687475)
			(xy 275.502476 -419.772289) (xy 275.460686 -419.853714) (xy 275.411831 -419.931107) (xy 275.356297 -420.003855)
			(xy 275.294522 -420.071386) (xy 275.226995 -420.133164) (xy 275.154249 -420.188702) (xy 275.076859 -420.237561)
			(xy 274.995436 -420.279355) (xy 274.910624 -420.313754) (xy 274.823092 -420.340486) (xy 274.733532 -420.35934)
			(xy 274.642652 -420.370167) (xy 274.55117 -420.372882) (xy 274.459807 -420.367462) (xy 274.369287 -420.353952)
			(xy 274.280324 -420.332457) (xy 274.193622 -420.303147) (xy 274.109864 -420.266255) (xy 274.029713 -420.222071)
			(xy 273.953802 -420.170944) (xy 273.88273 -420.113278) (xy 273.81706 -420.04953) (xy 273.75731 -419.980202)
			(xy 273.703952 -419.905843) (xy 273.657407 -419.827039) (xy 273.618044 -419.744413) (xy 273.586173 -419.658619)
			(xy 273.562046 -419.570334) (xy 273.545854 -419.480254) (xy 273.537724 -419.389093) (xy 273.537172 -419.343332)
			(xy 273.537701 -419.296187) (xy 273.546321 -419.202292) (xy 273.563493 -419.109579) (xy 273.589073 -419.018826)
			(xy 273.622845 -418.930792) (xy 273.664527 -418.846216) (xy 273.71377 -418.765806) (xy 273.770161 -418.690237)
			(xy 273.833226 -418.620142) (xy 273.902438 -418.556109) (xy 273.939508 -418.526976) (xy 273.952462 -418.51707)
			(xy 273.96186 -418.485828) (xy 273.925792 -418.379402) (xy 273.921887 -418.369582) (xy 273.907634 -418.35401)
			(xy 273.888338 -418.345449) (xy 273.877786 -418.344858) (xy 272.91919 -418.344858) (xy 272.90786 -418.345461)
			(xy 272.887413 -418.355223) (xy 272.87982 -418.363654) (xy 272.82267 -418.433758) (xy 272.817336 -418.45611)
			(xy 272.819622 -418.467286) (xy 272.824725 -418.493083) (xy 272.8302 -418.545386) (xy 272.830544 -418.57168)
			(xy 272.830042 -418.603641) (xy 272.822031 -418.667059) (xy 272.806134 -418.728973) (xy 272.782602 -418.788406)
			(xy 272.751808 -418.844421) (xy 272.714235 -418.896136) (xy 272.670478 -418.942733) (xy 272.621225 -418.983478)
			(xy 272.567254 -419.017729) (xy 272.509415 -419.044946) (xy 272.448622 -419.064699) (xy 272.385832 -419.076677)
			(xy 272.322036 -419.080691) (xy 272.25824 -419.076677) (xy 272.19545 -419.064699) (xy 272.134657 -419.044946)
			(xy 272.076818 -419.017729) (xy 272.022847 -418.983478) (xy 271.973594 -418.942733) (xy 271.929837 -418.896136)
			(xy 271.892264 -418.844421) (xy 271.86147 -418.788406) (xy 271.837938 -418.728973) (xy 271.822041 -418.667059)
			(xy 271.81403 -418.603641) (xy 271.813528 -418.57168) (xy 271.813888 -418.545387) (xy 271.819363 -418.493085)
			(xy 271.82445 -418.467286) (xy 271.826736 -418.45611) (xy 271.821402 -418.433758) (xy 271.764252 -418.363654)
			(xy 271.756634 -418.355258) (xy 271.7362 -418.345509) (xy 271.724882 -418.344858) (xy 269.788132 -418.344858)
			(xy 269.778069 -418.345295) (xy 269.759488 -418.353033) (xy 269.752064 -418.359844) (xy 268.038072 -420.073836)
			(xy 269.810736 -420.073836) (xy 269.814807 -420.018214) (xy 269.826933 -419.963777) (xy 269.846856 -419.911686)
			(xy 269.874152 -419.863051) (xy 269.908238 -419.818908) (xy 269.948387 -419.780199) (xy 269.993745 -419.747748)
			(xy 270.043345 -419.722247) (xy 270.096129 -419.70424) (xy 270.150972 -419.69411) (xy 270.206706 -419.692073)
			(xy 270.262143 -419.698173) (xy 270.3161 -419.712279) (xy 270.367429 -419.734091) (xy 270.415035 -419.763145)
			(xy 270.457903 -419.79882) (xy 270.49512 -419.840357) (xy 270.525893 -419.88687) (xy 270.549565 -419.937367)
			(xy 270.565633 -419.990774) (xy 270.573753 -420.04595) (xy 270.574262 -420.073836) (xy 270.573753 -420.101722)
			(xy 270.567951 -420.141146) (xy 270.913858 -420.141146) (xy 270.917929 -420.085524) (xy 270.930055 -420.031087)
			(xy 270.949978 -419.978996) (xy 270.977274 -419.930361) (xy 271.01136 -419.886218) (xy 271.051509 -419.847509)
			(xy 271.096867 -419.815058) (xy 271.146467 -419.789557) (xy 271.199251 -419.77155) (xy 271.254094 -419.76142)
			(xy 271.309828 -419.759383) (xy 271.365265 -419.765483) (xy 271.419222 -419.779589) (xy 271.470551 -419.801401)
			(xy 271.518157 -419.830455) (xy 271.561025 -419.86613) (xy 271.598242 -419.907667) (xy 271.629015 -419.95418)
			(xy 271.652687 -420.004677) (xy 271.668755 -420.058084) (xy 271.676875 -420.11326) (xy 271.677384 -420.141146)
			(xy 271.676875 -420.169032) (xy 271.668755 -420.224208) (xy 271.652687 -420.277615) (xy 271.629015 -420.328112)
			(xy 271.598242 -420.374625) (xy 271.561025 -420.416162) (xy 271.518157 -420.451837) (xy 271.470551 -420.480891)
			(xy 271.419222 -420.502703) (xy 271.365265 -420.516809) (xy 271.309828 -420.522909) (xy 271.254094 -420.520872)
			(xy 271.199251 -420.510742) (xy 271.146467 -420.492735) (xy 271.096867 -420.467234) (xy 271.051509 -420.434783)
			(xy 271.01136 -420.396074) (xy 270.977274 -420.351931) (xy 270.949978 -420.303296) (xy 270.930055 -420.251205)
			(xy 270.917929 -420.196768) (xy 270.913858 -420.141146) (xy 270.567951 -420.141146) (xy 270.565633 -420.156898)
			(xy 270.549565 -420.210305) (xy 270.525893 -420.260802) (xy 270.49512 -420.307315) (xy 270.457903 -420.348852)
			(xy 270.415035 -420.384527) (xy 270.367429 -420.413581) (xy 270.3161 -420.435393) (xy 270.262143 -420.449499)
			(xy 270.206706 -420.455599) (xy 270.150972 -420.453562) (xy 270.096129 -420.443432) (xy 270.043345 -420.425425)
			(xy 269.993745 -420.399924) (xy 269.948387 -420.367473) (xy 269.908238 -420.328764) (xy 269.874152 -420.284621)
			(xy 269.846856 -420.235986) (xy 269.826933 -420.183895) (xy 269.814807 -420.129458) (xy 269.810736 -420.073836)
			(xy 268.038072 -420.073836) (xy 267.081508 -421.0304) (xy 267.073545 -421.039152) (xy 267.065983 -421.061541)
			(xy 267.06703 -421.073326) (xy 267.080238 -421.165782) (xy 267.0937 -421.18534) (xy 267.104368 -421.191182)
			(xy 267.129555 -421.205714) (xy 267.175603 -421.241219) (xy 267.215728 -421.283302) (xy 267.249001 -421.330988)
			(xy 267.274651 -421.383172) (xy 267.292084 -421.438643) (xy 267.300895 -421.496119) (xy 267.301472 -421.525192)
			(xy 267.301009 -421.552444) (xy 267.293253 -421.606394) (xy 267.277897 -421.658691) (xy 267.255255 -421.70827)
			(xy 267.225786 -421.754121) (xy 267.190092 -421.795312) (xy 267.148899 -421.831003) (xy 267.103045 -421.860468)
			(xy 267.053465 -421.883107) (xy 267.052699 -421.883332) (xy 273.536668 -421.883332) (xy 273.540697 -421.792326)
			(xy 273.552754 -421.702032) (xy 273.572744 -421.613157) (xy 273.60051 -421.526397) (xy 273.635836 -421.44243)
			(xy 273.678444 -421.361914) (xy 273.728002 -421.285478) (xy 273.784121 -421.213722) (xy 273.846362 -421.147206)
			(xy 273.914239 -421.086451) (xy 273.987219 -421.031933) (xy 274.064732 -420.984079) (xy 274.146171 -420.943262)
			(xy 274.230899 -420.909803) (xy 274.318253 -420.883962) (xy 274.407548 -420.865944) (xy 274.498086 -420.855887)
			(xy 274.589159 -420.853872) (xy 274.680054 -420.859914) (xy 274.770059 -420.873965) (xy 274.85847 -420.895916)
			(xy 274.944595 -420.925595) (xy 275.02776 -420.962769) (xy 275.107314 -421.007148) (xy 275.182634 -421.058385)
			(xy 275.253132 -421.116078) (xy 275.318254 -421.179775) (xy 275.377492 -421.248979) (xy 275.430382 -421.323148)
			(xy 275.462358 -421.3776) (xy 284.122086 -421.3776) (xy 284.126101 -421.313801) (xy 284.138079 -421.251009)
			(xy 284.157834 -421.190213) (xy 284.185053 -421.132372) (xy 284.219306 -421.0784) (xy 284.260055 -421.029146)
			(xy 284.306656 -420.985388) (xy 284.358373 -420.947815) (xy 284.414392 -420.917022) (xy 284.473829 -420.893492)
			(xy 284.535746 -420.877598) (xy 284.599168 -420.869589) (xy 284.63113 -420.86911) (xy 284.664273 -420.869633)
			(xy 284.729997 -420.878254) (xy 284.794043 -420.895345) (xy 284.855324 -420.920616) (xy 284.912799 -420.953639)
			(xy 284.965494 -420.993853) (xy 285.012515 -421.040576) (xy 285.033212 -421.066468) (xy 285.040812 -421.075282)
			(xy 285.061719 -421.085459) (xy 285.073344 -421.086026) (xy 285.153862 -421.086026) (xy 285.165501 -421.085534)
			(xy 285.186411 -421.075315) (xy 285.193994 -421.066468) (xy 285.214698 -421.040582) (xy 285.261718 -420.993861)
			(xy 285.314412 -420.953648) (xy 285.371887 -420.920626) (xy 285.433166 -420.895356) (xy 285.497211 -420.878266)
			(xy 285.562933 -420.869647) (xy 285.596076 -420.86911) (xy 285.626808 -420.86956) (xy 285.687825 -420.876966)
			(xy 285.747504 -420.891674) (xy 285.804975 -420.913468) (xy 285.8594 -420.942031) (xy 285.909985 -420.976946)
			(xy 285.955992 -421.017704) (xy 285.996751 -421.063711) (xy 286.031666 -421.114295) (xy 286.06023 -421.16872)
			(xy 286.082024 -421.22619) (xy 286.096732 -421.285869) (xy 286.104139 -421.346886) (xy 286.104584 -421.377618)
			(xy 286.104096 -421.409339) (xy 286.104066 -421.409579) (xy 287.123118 -421.409579) (xy 287.123118 -421.345657)
			(xy 287.131129 -421.282239) (xy 287.147026 -421.220325) (xy 287.170558 -421.160892) (xy 287.201352 -421.104877)
			(xy 287.238925 -421.053162) (xy 287.282682 -421.006565) (xy 287.331935 -420.96582) (xy 287.385906 -420.931569)
			(xy 287.443745 -420.904352) (xy 287.504538 -420.884599) (xy 287.567328 -420.872621) (xy 287.631124 -420.868608)
			(xy 287.69492 -420.872621) (xy 287.75771 -420.884599) (xy 287.818503 -420.904352) (xy 287.876342 -420.931569)
			(xy 287.930313 -420.96582) (xy 287.979566 -421.006565) (xy 288.023323 -421.053162) (xy 288.060896 -421.104877)
			(xy 288.09169 -421.160892) (xy 288.115222 -421.220325) (xy 288.131119 -421.282239) (xy 288.13913 -421.345657)
			(xy 288.139632 -421.377618) (xy 288.13913 -421.409579) (xy 288.131119 -421.472997) (xy 288.115222 -421.534911)
			(xy 288.09169 -421.594344) (xy 288.060896 -421.650359) (xy 288.023323 -421.702074) (xy 287.979566 -421.748671)
			(xy 287.930313 -421.789416) (xy 287.876342 -421.823667) (xy 287.818503 -421.850884) (xy 287.75771 -421.870637)
			(xy 287.69492 -421.882615) (xy 287.631124 -421.886629) (xy 287.567328 -421.882615) (xy 287.504538 -421.870637)
			(xy 287.443745 -421.850884) (xy 287.385906 -421.823667) (xy 287.331935 -421.789416) (xy 287.282682 -421.748671)
			(xy 287.238925 -421.702074) (xy 287.201352 -421.650359) (xy 287.170558 -421.594344) (xy 287.147026 -421.534911)
			(xy 287.131129 -421.472997) (xy 287.123118 -421.409579) (xy 286.104066 -421.409579) (xy 286.096199 -421.472288)
			(xy 286.080529 -421.533764) (xy 286.057329 -421.592812) (xy 286.026962 -421.648514) (xy 286.008826 -421.674544)
			(xy 286.00146 -421.684958) (xy 285.998158 -421.70985) (xy 286.036512 -421.812974) (xy 286.055308 -421.829484)
			(xy 286.067754 -421.832532) (xy 286.095594 -421.839604) (xy 286.149589 -421.859204) (xy 286.20103 -421.884766)
			(xy 286.249261 -421.915966) (xy 286.271716 -421.933878) (xy 286.278705 -421.939164) (xy 286.295216 -421.944999)
			(xy 286.303974 -421.945308) (xy 286.457898 -421.945308) (xy 286.466644 -421.944941) (xy 286.483136 -421.939106)
			(xy 286.490156 -421.933878) (xy 286.517568 -421.912182) (xy 286.577191 -421.875682) (xy 286.641248 -421.847687)
			(xy 286.708534 -421.828722) (xy 286.777782 -421.819145) (xy 286.812736 -421.818562) (xy 286.843467 -421.819022)
			(xy 286.904479 -421.826434) (xy 286.964154 -421.841145) (xy 287.02162 -421.862942) (xy 287.076041 -421.891506)
			(xy 287.126622 -421.926422) (xy 287.172626 -421.967178) (xy 287.213382 -422.013183) (xy 287.248297 -422.063764)
			(xy 287.27686 -422.118185) (xy 287.298656 -422.175652) (xy 287.313367 -422.235327) (xy 287.320779 -422.296339)
			(xy 287.321244 -422.32707) (xy 287.320699 -422.359021) (xy 287.312685 -422.422419) (xy 287.296792 -422.484314)
			(xy 287.273271 -422.54373) (xy 287.259729 -422.56837) (xy 292.02507 -422.56837) (xy 292.025572 -422.536409)
			(xy 292.033583 -422.472991) (xy 292.04948 -422.411077) (xy 292.073012 -422.351644) (xy 292.103806 -422.295629)
			(xy 292.141379 -422.243914) (xy 292.185136 -422.197317) (xy 292.234389 -422.156572) (xy 292.28836 -422.122321)
			(xy 292.346199 -422.095104) (xy 292.406992 -422.075351) (xy 292.469782 -422.063373) (xy 292.533578 -422.05936)
			(xy 292.597374 -422.063373) (xy 292.660164 -422.075351) (xy 292.720957 -422.095104) (xy 292.778796 -422.122321)
			(xy 292.832767 -422.156572) (xy 292.88202 -422.197317) (xy 292.925777 -422.243914) (xy 292.96335 -422.295629)
			(xy 292.994144 -422.351644) (xy 293.017676 -422.411077) (xy 293.033573 -422.472991) (xy 293.041584 -422.536409)
			(xy 293.042086 -422.56837) (xy 293.041583 -422.600623) (xy 293.033438 -422.664611) (xy 293.017262 -422.727055)
			(xy 292.993316 -422.78695) (xy 292.961984 -422.843334) (xy 292.94328 -422.869614) (xy 292.938081 -422.877292)
			(xy 292.933139 -422.895151) (xy 292.933628 -422.904412) (xy 292.936422 -422.934892) (xy 292.937638 -422.944026)
			(xy 292.945721 -422.960568) (xy 292.95217 -422.96715) (xy 292.973545 -422.987763) (xy 293.011812 -423.033174)
			(xy 293.023197 -423.050419) (xy 294.052746 -423.050419) (xy 294.052746 -422.986497) (xy 294.060757 -422.923079)
			(xy 294.076654 -422.861165) (xy 294.100186 -422.801732) (xy 294.13098 -422.745717) (xy 294.168553 -422.694002)
			(xy 294.21231 -422.647405) (xy 294.261563 -422.60666) (xy 294.315534 -422.572409) (xy 294.373373 -422.545192)
			(xy 294.434166 -422.525439) (xy 294.496956 -422.513461) (xy 294.560752 -422.509448) (xy 294.624548 -422.513461)
			(xy 294.687338 -422.525439) (xy 294.748131 -422.545192) (xy 294.80597 -422.572409) (xy 294.859941 -422.60666)
			(xy 294.909194 -422.647405) (xy 294.952951 -422.694002) (xy 294.990524 -422.745717) (xy 295.021318 -422.801732)
			(xy 295.04485 -422.861165) (xy 295.060747 -422.923079) (xy 295.068758 -422.986497) (xy 295.06926 -423.018458)
			(xy 295.068758 -423.050419) (xy 295.060747 -423.113837) (xy 295.04485 -423.175751) (xy 295.021318 -423.235184)
			(xy 295.004062 -423.266573) (xy 296.442886 -423.266573) (xy 296.442886 -423.202651) (xy 296.450897 -423.139233)
			(xy 296.466794 -423.077319) (xy 296.490326 -423.017886) (xy 296.52112 -422.961871) (xy 296.558693 -422.910156)
			(xy 296.60245 -422.863559) (xy 296.651703 -422.822814) (xy 296.705674 -422.788563) (xy 296.763513 -422.761346)
			(xy 296.824306 -422.741593) (xy 296.887096 -422.729615) (xy 296.950892 -422.725602) (xy 297.014688 -422.729615)
			(xy 297.077478 -422.741593) (xy 297.138271 -422.761346) (xy 297.19611 -422.788563) (xy 297.250081 -422.822814)
			(xy 297.299334 -422.863559) (xy 297.343091 -422.910156) (xy 297.380664 -422.961871) (xy 297.411458 -423.017886)
			(xy 297.43499 -423.077319) (xy 297.450887 -423.139233) (xy 297.458898 -423.202651) (xy 297.4594 -423.234612)
			(xy 297.458898 -423.266573) (xy 297.45809 -423.272966) (xy 299.13148 -423.272966) (xy 299.135551 -423.217344)
			(xy 299.147677 -423.162907) (xy 299.1676 -423.110816) (xy 299.194896 -423.062181) (xy 299.228982 -423.018038)
			(xy 299.269131 -422.979329) (xy 299.314489 -422.946878) (xy 299.364089 -422.921377) (xy 299.416873 -422.90337)
			(xy 299.471716 -422.89324) (xy 299.52745 -422.891203) (xy 299.582887 -422.897303) (xy 299.636844 -422.911409)
			(xy 299.688173 -422.933221) (xy 299.735779 -422.962275) (xy 299.778647 -422.99795) (xy 299.815864 -423.039487)
			(xy 299.846637 -423.086) (xy 299.870309 -423.136497) (xy 299.886377 -423.189904) (xy 299.894497 -423.24508)
			(xy 299.895006 -423.272966) (xy 299.894497 -423.300852) (xy 299.886377 -423.356028) (xy 299.870309 -423.409435)
			(xy 299.846637 -423.459932) (xy 299.815864 -423.506445) (xy 299.778647 -423.547982) (xy 299.735779 -423.583657)
			(xy 299.688173 -423.612711) (xy 299.636844 -423.634523) (xy 299.582887 -423.648629) (xy 299.52745 -423.654729)
			(xy 299.471716 -423.652692) (xy 299.416873 -423.642562) (xy 299.364089 -423.624555) (xy 299.314489 -423.599054)
			(xy 299.269131 -423.566603) (xy 299.228982 -423.527894) (xy 299.194896 -423.483751) (xy 299.1676 -423.435116)
			(xy 299.147677 -423.383025) (xy 299.135551 -423.328588) (xy 299.13148 -423.272966) (xy 297.45809 -423.272966)
			(xy 297.450887 -423.329991) (xy 297.43499 -423.391905) (xy 297.411458 -423.451338) (xy 297.380664 -423.507353)
			(xy 297.343091 -423.559068) (xy 297.299334 -423.605665) (xy 297.250081 -423.64641) (xy 297.19611 -423.680661)
			(xy 297.189686 -423.683684) (xy 298.183298 -423.683684) (xy 298.187369 -423.628062) (xy 298.199495 -423.573625)
			(xy 298.219418 -423.521534) (xy 298.246714 -423.472899) (xy 298.2808 -423.428756) (xy 298.320949 -423.390047)
			(xy 298.366307 -423.357596) (xy 298.415907 -423.332095) (xy 298.468691 -423.314088) (xy 298.523534 -423.303958)
			(xy 298.579268 -423.301921) (xy 298.634705 -423.308021) (xy 298.688662 -423.322127) (xy 298.739991 -423.343939)
			(xy 298.787597 -423.372993) (xy 298.830465 -423.408668) (xy 298.867682 -423.450205) (xy 298.898455 -423.496718)
			(xy 298.922127 -423.547215) (xy 298.938195 -423.600622) (xy 298.946315 -423.655798) (xy 298.946824 -423.683684)
			(xy 298.946315 -423.71157) (xy 298.938195 -423.766746) (xy 298.922127 -423.820153) (xy 298.898455 -423.87065)
			(xy 298.867682 -423.917163) (xy 298.830465 -423.9587) (xy 298.787597 -423.994375) (xy 298.739991 -424.023429)
			(xy 298.688662 -424.045241) (xy 298.634705 -424.059347) (xy 298.579268 -424.065447) (xy 298.523534 -424.06341)
			(xy 298.468691 -424.05328) (xy 298.415907 -424.035273) (xy 298.366307 -424.009772) (xy 298.320949 -423.977321)
			(xy 298.2808 -423.938612) (xy 298.246714 -423.894469) (xy 298.219418 -423.845834) (xy 298.199495 -423.793743)
			(xy 298.187369 -423.739306) (xy 298.183298 -423.683684) (xy 297.189686 -423.683684) (xy 297.138271 -423.707878)
			(xy 297.077478 -423.727631) (xy 297.014688 -423.739609) (xy 296.950892 -423.743623) (xy 296.887096 -423.739609)
			(xy 296.824306 -423.727631) (xy 296.763513 -423.707878) (xy 296.705674 -423.680661) (xy 296.651703 -423.64641)
			(xy 296.60245 -423.605665) (xy 296.558693 -423.559068) (xy 296.52112 -423.507353) (xy 296.490326 -423.451338)
			(xy 296.466794 -423.391905) (xy 296.450897 -423.329991) (xy 296.442886 -423.266573) (xy 295.004062 -423.266573)
			(xy 294.990524 -423.291199) (xy 294.952951 -423.342914) (xy 294.909194 -423.389511) (xy 294.859941 -423.430256)
			(xy 294.80597 -423.464507) (xy 294.748131 -423.491724) (xy 294.687338 -423.511477) (xy 294.624548 -423.523455)
			(xy 294.560752 -423.527469) (xy 294.496956 -423.523455) (xy 294.434166 -423.511477) (xy 294.373373 -423.491724)
			(xy 294.315534 -423.464507) (xy 294.261563 -423.430256) (xy 294.21231 -423.389511) (xy 294.168553 -423.342914)
			(xy 294.13098 -423.291199) (xy 294.100186 -423.235184) (xy 294.076654 -423.175751) (xy 294.060757 -423.113837)
			(xy 294.052746 -423.050419) (xy 293.023197 -423.050419) (xy 293.044531 -423.082732) (xy 293.071257 -423.135762)
			(xy 293.091627 -423.191544) (xy 293.105363 -423.249318) (xy 293.112278 -423.308298) (xy 293.112698 -423.33799)
			(xy 293.112245 -423.369865) (xy 293.104305 -423.433117) (xy 293.088511 -423.494878) (xy 293.06511 -423.554176)
			(xy 293.034472 -423.610079) (xy 293.016178 -423.636186) (xy 293.0112 -423.643612) (xy 293.006251 -423.660779)
			(xy 293.006526 -423.669714) (xy 293.008812 -423.699686) (xy 293.009773 -423.70855) (xy 293.017069 -423.724809)
			(xy 293.023036 -423.731436) (xy 293.04544 -423.755234) (xy 293.084598 -423.807566) (xy 293.116729 -423.864484)
			(xy 293.141303 -423.92505) (xy 293.157916 -423.988264) (xy 293.166293 -424.053086) (xy 293.1668 -424.085766)
			(xy 293.166333 -424.115864) (xy 293.159236 -424.175641) (xy 293.145124 -424.23416) (xy 293.124196 -424.290602)
			(xy 293.096745 -424.344175) (xy 293.063156 -424.394129) (xy 293.043864 -424.417236) (xy 293.038455 -424.424055)
			(xy 293.032234 -424.440299) (xy 293.031672 -424.448986) (xy 293.03091 -424.47845) (xy 293.031051 -424.487116)
			(xy 293.036364 -424.503601) (xy 293.041324 -424.510708) (xy 293.061001 -424.537412) (xy 293.094018 -424.594944)
			(xy 293.119277 -424.656279) (xy 293.136348 -424.720378) (xy 293.144942 -424.786151) (xy 293.145464 -424.819318)
			(xy 293.144962 -424.851279) (xy 293.136951 -424.914697) (xy 293.129941 -424.942) (xy 294.056054 -424.942)
			(xy 294.056526 -424.911455) (xy 294.063834 -424.850804) (xy 294.078358 -424.791465) (xy 294.099887 -424.734295)
			(xy 294.128113 -424.680116) (xy 294.162627 -424.62971) (xy 294.202932 -424.583803) (xy 294.248448 -424.543057)
			(xy 294.273224 -424.525186) (xy 294.282368 -424.518836) (xy 294.29329 -424.500294) (xy 294.304466 -424.402758)
			(xy 294.297862 -424.382184) (xy 294.290496 -424.374056) (xy 294.272149 -424.352935) (xy 294.24122 -424.306317)
			(xy 294.217434 -424.25568) (xy 294.201304 -424.20211) (xy 294.193174 -424.146759) (xy 294.192706 -424.118786)
			(xy 294.193192 -424.091535) (xy 294.200948 -424.037587) (xy 294.216303 -423.985292) (xy 294.238945 -423.935715)
			(xy 294.268411 -423.889865) (xy 294.304102 -423.848674) (xy 294.345293 -423.812983) (xy 294.391143 -423.783517)
			(xy 294.44072 -423.760875) (xy 294.493015 -423.74552) (xy 294.546963 -423.737764) (xy 294.601465 -423.737764)
			(xy 294.655413 -423.74552) (xy 294.707708 -423.760875) (xy 294.757285 -423.783517) (xy 294.803135 -423.812983)
			(xy 294.844326 -423.848674) (xy 294.880017 -423.889865) (xy 294.909483 -423.935715) (xy 294.932125 -423.985292)
			(xy 294.94748 -424.037587) (xy 294.955236 -424.091535) (xy 294.955722 -424.118786) (xy 294.9552 -424.147656)
			(xy 294.946521 -424.204739) (xy 294.929551 -424.2592) (xy 299.562837 -424.2592) (xy 299.566851 -424.195411)
			(xy 299.578827 -424.132628) (xy 299.598578 -424.071841) (xy 299.625791 -424.014008) (xy 299.660038 -423.960043)
			(xy 299.700779 -423.910795) (xy 299.747371 -423.867041) (xy 299.799079 -423.829472) (xy 299.855088 -423.79868)
			(xy 299.914514 -423.77515) (xy 299.976421 -423.759254) (xy 300.039832 -423.751242) (xy 300.07179 -423.75074)
			(xy 300.106744 -423.751341) (xy 300.175996 -423.7609) (xy 300.243287 -423.779853) (xy 300.307347 -423.807844)
			(xy 300.366971 -423.844344) (xy 300.39437 -423.866056) (xy 300.40152 -423.871454) (xy 300.418434 -423.877318)
			(xy 300.42739 -423.877486) (xy 300.457616 -423.876978) (xy 300.466608 -423.876468) (xy 300.48339 -423.869956)
			(xy 300.490382 -423.864278) (xy 300.513699 -423.844189) (xy 300.564316 -423.809171) (xy 300.618789 -423.78052)
			(xy 300.676323 -423.758655) (xy 300.736076 -423.743897) (xy 300.797174 -423.73646) (xy 300.827948 -423.736008)
			(xy 300.859908 -423.736481) (xy 300.923324 -423.744498) (xy 300.985234 -423.760399) (xy 301.044664 -423.783934)
			(xy 301.100676 -423.814731) (xy 301.152386 -423.852305) (xy 301.19898 -423.896064) (xy 301.239722 -423.945317)
			(xy 301.273971 -423.999288) (xy 301.301185 -424.057126) (xy 301.320936 -424.117918) (xy 301.332913 -424.180706)
			(xy 301.336927 -424.2445) (xy 301.332913 -424.308294) (xy 301.320936 -424.371082) (xy 301.301185 -424.431874)
			(xy 301.273971 -424.489712) (xy 301.239722 -424.543683) (xy 301.19898 -424.592936) (xy 301.152386 -424.636695)
			(xy 301.100676 -424.674269) (xy 301.044664 -424.705066) (xy 300.985234 -424.728601) (xy 300.923324 -424.744502)
			(xy 300.859908 -424.752519) (xy 300.827948 -424.753024) (xy 300.792992 -424.752467) (xy 300.723738 -424.742898)
			(xy 300.656447 -424.723935) (xy 300.592387 -424.695935) (xy 300.532766 -424.659425) (xy 300.505368 -424.637708)
			(xy 300.498239 -424.632279) (xy 300.481309 -424.626435) (xy 300.472348 -424.626278) (xy 300.442122 -424.626786)
			(xy 300.433133 -424.627322) (xy 300.416352 -424.633817) (xy 300.409356 -424.639486) (xy 300.386058 -424.659599)
			(xy 300.335438 -424.694615) (xy 300.280961 -424.723263) (xy 300.223423 -424.745124) (xy 300.163666 -424.759878)
			(xy 300.102565 -424.767308) (xy 300.07179 -424.767756) (xy 300.039832 -424.767158) (xy 299.976421 -424.759146)
			(xy 299.914514 -424.74325) (xy 299.855088 -424.71972) (xy 299.799079 -424.688928) (xy 299.747371 -424.651359)
			(xy 299.700779 -424.607605) (xy 299.660038 -424.558357) (xy 299.625791 -424.504392) (xy 299.598578 -424.446559)
			(xy 299.578827 -424.385772) (xy 299.566851 -424.322989) (xy 299.562837 -424.2592) (xy 294.929551 -424.2592)
			(xy 294.929344 -424.259865) (xy 294.90406 -424.311774) (xy 294.871247 -424.359284) (xy 294.851836 -424.38066)
			(xy 294.844216 -424.388534) (xy 294.837104 -424.409108) (xy 294.845994 -424.506644) (xy 294.856662 -424.525694)
			(xy 294.865552 -424.532044) (xy 294.892677 -424.552662) (xy 294.941712 -424.599968) (xy 294.983993 -424.653396)
			(xy 295.018763 -424.711991) (xy 295.045401 -424.774702) (xy 295.063429 -424.840408) (xy 295.072524 -424.907933)
			(xy 295.07307 -424.942) (xy 295.072568 -424.973961) (xy 295.064557 -425.037379) (xy 295.04866 -425.099293)
			(xy 295.025128 -425.158726) (xy 294.994334 -425.214741) (xy 294.956761 -425.266456) (xy 294.913004 -425.313053)
			(xy 294.863751 -425.353798) (xy 294.80978 -425.388049) (xy 294.751941 -425.415266) (xy 294.691148 -425.435019)
			(xy 294.628358 -425.446997) (xy 294.564562 -425.451011) (xy 294.500766 -425.446997) (xy 294.437976 -425.435019)
			(xy 294.377183 -425.415266) (xy 294.319344 -425.388049) (xy 294.265373 -425.353798) (xy 294.21612 -425.313053)
			(xy 294.172363 -425.266456) (xy 294.13479 -425.214741) (xy 294.103996 -425.158726) (xy 294.080464 -425.099293)
			(xy 294.064567 -425.037379) (xy 294.056556 -424.973961) (xy 294.056054 -424.942) (xy 293.129941 -424.942)
			(xy 293.121054 -424.976611) (xy 293.097522 -425.036044) (xy 293.066728 -425.092059) (xy 293.029155 -425.143774)
			(xy 292.985398 -425.190371) (xy 292.936145 -425.231116) (xy 292.882174 -425.265367) (xy 292.824335 -425.292584)
			(xy 292.763542 -425.312337) (xy 292.700752 -425.324315) (xy 292.636956 -425.328329) (xy 292.57316 -425.324315)
			(xy 292.51037 -425.312337) (xy 292.449577 -425.292584) (xy 292.391738 -425.265367) (xy 292.337767 -425.231116)
			(xy 292.288514 -425.190371) (xy 292.244757 -425.143774) (xy 292.207184 -425.092059) (xy 292.17639 -425.036044)
			(xy 292.152858 -424.976611) (xy 292.136961 -424.914697) (xy 292.12895 -424.851279) (xy 292.128448 -424.819318)
			(xy 292.128918 -424.78922) (xy 292.136017 -424.729444) (xy 292.150129 -424.670925) (xy 292.171056 -424.614484)
			(xy 292.198506 -424.56091) (xy 292.232094 -424.510956) (xy 292.251384 -424.487848) (xy 292.256753 -424.481001)
			(xy 292.263 -424.464778) (xy 292.263576 -424.456098) (xy 292.264338 -424.426634) (xy 292.264214 -424.417967)
			(xy 292.258891 -424.401481) (xy 292.253924 -424.394376) (xy 292.234232 -424.367682) (xy 292.201219 -424.310147)
			(xy 292.175964 -424.248809) (xy 292.158896 -424.184708) (xy 292.150304 -424.118933) (xy 292.149784 -424.085766)
			(xy 292.150269 -424.053892) (xy 292.158202 -423.990642) (xy 292.17399 -423.928881) (xy 292.197383 -423.869582)
			(xy 292.228014 -423.813678) (xy 292.246304 -423.78757) (xy 292.251299 -423.780154) (xy 292.256238 -423.762979)
			(xy 292.255956 -423.754042) (xy 292.25367 -423.72407) (xy 292.252688 -423.715209) (xy 292.245407 -423.698949)
			(xy 292.239446 -423.69232) (xy 292.217035 -423.668528) (xy 292.177875 -423.616196) (xy 292.145744 -423.559277)
			(xy 292.12117 -423.49871) (xy 292.10456 -423.435494) (xy 292.096186 -423.370671) (xy 292.095682 -423.33799)
			(xy 292.096169 -423.305737) (xy 292.104319 -423.241748) (xy 292.120498 -423.179304) (xy 292.144448 -423.119409)
			(xy 292.175783 -423.063025) (xy 292.194488 -423.036746) (xy 292.199657 -423.029049) (xy 292.204618 -423.011206)
			(xy 292.20414 -423.001948) (xy 292.201346 -422.971468) (xy 292.20011 -422.962338) (xy 292.192043 -422.945793)
			(xy 292.185598 -422.93921) (xy 292.164246 -422.918574) (xy 292.125979 -422.873167) (xy 292.093258 -422.823613)
			(xy 292.066529 -422.770586) (xy 292.046156 -422.714809) (xy 292.032415 -422.657038) (xy 292.025493 -422.598061)
			(xy 292.02507 -422.56837) (xy 287.259729 -422.56837) (xy 287.242492 -422.599732) (xy 287.20494 -422.651436)
			(xy 287.161206 -422.69803) (xy 287.111981 -422.738777) (xy 287.085278 -422.75633) (xy 287.075118 -422.762934)
			(xy 287.062672 -422.783508) (xy 287.055052 -422.888918) (xy 287.064196 -422.91127) (xy 287.07334 -422.919144)
			(xy 287.093771 -422.937331) (xy 287.129702 -422.978573) (xy 287.159373 -423.024524) (xy 287.182176 -423.074243)
			(xy 287.197643 -423.126709) (xy 287.205457 -423.180847) (xy 287.205928 -423.208196) (xy 287.205442 -423.235447)
			(xy 287.197686 -423.289395) (xy 287.182331 -423.34169) (xy 287.159689 -423.391267) (xy 287.130223 -423.437117)
			(xy 287.094532 -423.478308) (xy 287.053341 -423.513999) (xy 287.007491 -423.543465) (xy 286.957914 -423.566107)
			(xy 286.905619 -423.581462) (xy 286.851671 -423.589218) (xy 286.797169 -423.589218) (xy 286.743221 -423.581462)
			(xy 286.690926 -423.566107) (xy 286.641349 -423.543465) (xy 286.595499 -423.513999) (xy 286.554308 -423.478308)
			(xy 286.518617 -423.437117) (xy 286.489151 -423.391267) (xy 286.466509 -423.34169) (xy 286.451154 -423.289395)
			(xy 286.443398 -423.235447) (xy 286.442912 -423.208196) (xy 286.443366 -423.181688) (xy 286.450714 -423.129183)
			(xy 286.465253 -423.078199) (xy 286.486706 -423.029716) (xy 286.514658 -422.984667) (xy 286.548572 -422.943917)
			(xy 286.56788 -422.925748) (xy 286.57677 -422.91762) (xy 286.585406 -422.895268) (xy 286.574992 -422.789858)
			(xy 286.562038 -422.769792) (xy 286.551624 -422.763442) (xy 286.53557 -422.75366) (xy 286.504805 -422.732045)
			(xy 286.490156 -422.720262) (xy 286.483144 -422.715011) (xy 286.466651 -422.709154) (xy 286.457898 -422.708832)
			(xy 286.303974 -422.708832) (xy 286.295225 -422.709178) (xy 286.278734 -422.715026) (xy 286.271716 -422.720262)
			(xy 286.260052 -422.729709) (xy 286.235779 -422.747374) (xy 286.223202 -422.755568) (xy 286.213296 -422.761664)
			(xy 286.201358 -422.781222) (xy 286.190182 -422.883076) (xy 286.197802 -422.904666) (xy 286.20593 -422.912794)
			(xy 286.226652 -422.934415) (xy 286.261827 -422.982878) (xy 286.288995 -423.036244) (xy 286.307487 -423.0932)
			(xy 286.316849 -423.152347) (xy 286.317436 -423.182288) (xy 286.31695 -423.209539) (xy 286.309194 -423.263487)
			(xy 286.293839 -423.315782) (xy 286.271197 -423.365359) (xy 286.241731 -423.411209) (xy 286.20604 -423.4524)
			(xy 286.164849 -423.488091) (xy 286.118999 -423.517557) (xy 286.069422 -423.540199) (xy 286.017127 -423.555554)
			(xy 285.963179 -423.56331) (xy 285.908677 -423.56331) (xy 285.854729 -423.555554) (xy 285.802434 -423.540199)
			(xy 285.752857 -423.517557) (xy 285.707007 -423.488091) (xy 285.665816 -423.4524) (xy 285.630125 -423.411209)
			(xy 285.600659 -423.365359) (xy 285.578017 -423.315782) (xy 285.562662 -423.263487) (xy 285.554906 -423.209539)
			(xy 285.55442 -423.182288) (xy 285.554873 -423.156367) (xy 285.561905 -423.105005) (xy 285.575825 -423.055067)
			(xy 285.596376 -423.007473) (xy 285.62318 -422.963099) (xy 285.655744 -422.922761) (xy 285.674308 -422.904666)
			(xy 285.68269 -422.896538) (xy 285.691072 -422.875202) (xy 285.683198 -422.773094) (xy 285.671514 -422.753282)
			(xy 285.662116 -422.746678) (xy 285.636886 -422.728895) (xy 285.590512 -422.688153) (xy 285.549415 -422.642094)
			(xy 285.5142 -422.591396) (xy 285.485385 -422.536806) (xy 285.463395 -422.479127) (xy 285.448554 -422.419209)
			(xy 285.44108 -422.357934) (xy 285.440628 -422.32707) (xy 285.441107 -422.295349) (xy 285.449006 -422.2324)
			(xy 285.464678 -422.170923) (xy 285.487879 -422.111875) (xy 285.518249 -422.056173) (xy 285.536386 -422.030144)
			(xy 285.543752 -422.01973) (xy 285.547054 -421.994838) (xy 285.5087 -421.891714) (xy 285.489904 -421.875204)
			(xy 285.477458 -421.872156) (xy 285.444121 -421.86354) (xy 285.379958 -421.83856) (xy 285.31975 -421.805154)
			(xy 285.264598 -421.763933) (xy 285.215509 -421.71565) (xy 285.193994 -421.688768) (xy 285.186385 -421.679963)
			(xy 285.165486 -421.669779) (xy 285.153862 -421.66921) (xy 285.073344 -421.66921) (xy 285.061709 -421.669728)
			(xy 285.0408 -421.679931) (xy 285.033212 -421.688768) (xy 285.012487 -421.714637) (xy 284.965473 -421.761362)
			(xy 284.912783 -421.801578) (xy 284.855312 -421.834602) (xy 284.794035 -421.859875) (xy 284.729993 -421.876967)
			(xy 284.664272 -421.885588) (xy 284.63113 -421.886126) (xy 284.599168 -421.885611) (xy 284.535746 -421.877602)
			(xy 284.473829 -421.861708) (xy 284.414392 -421.838178) (xy 284.358373 -421.807385) (xy 284.306656 -421.769812)
			(xy 284.260055 -421.726054) (xy 284.219306 -421.6768) (xy 284.185053 -421.622828) (xy 284.157834 -421.564987)
			(xy 284.138079 -421.504191) (xy 284.126101 -421.441399) (xy 284.122086 -421.3776) (xy 275.462358 -421.3776)
			(xy 275.476511 -421.4017) (xy 275.515516 -421.484023) (xy 275.547093 -421.56947) (xy 275.570994 -421.657374)
			(xy 275.587033 -421.747046) (xy 275.595084 -421.837784) (xy 275.595588 -421.883332) (xy 275.595084 -421.92888)
			(xy 275.587033 -422.019618) (xy 275.570994 -422.10929) (xy 275.547093 -422.197194) (xy 275.515516 -422.282641)
			(xy 275.476511 -422.364964) (xy 275.430382 -422.443516) (xy 275.377492 -422.517685) (xy 275.318254 -422.586889)
			(xy 275.253132 -422.650586) (xy 275.182634 -422.708279) (xy 275.107314 -422.759516) (xy 275.02776 -422.803895)
			(xy 274.944595 -422.841069) (xy 274.85847 -422.870748) (xy 274.770059 -422.892699) (xy 274.680054 -422.90675)
			(xy 274.589159 -422.912792) (xy 274.498086 -422.910777) (xy 274.407548 -422.90072) (xy 274.318253 -422.882702)
			(xy 274.230899 -422.856861) (xy 274.146171 -422.823402) (xy 274.064732 -422.782585) (xy 273.987219 -422.734731)
			(xy 273.914239 -422.680213) (xy 273.846362 -422.619458) (xy 273.784121 -422.552942) (xy 273.728002 -422.481186)
			(xy 273.678444 -422.40475) (xy 273.635836 -422.324234) (xy 273.60051 -422.240267) (xy 273.572744 -422.153507)
			(xy 273.552754 -422.064632) (xy 273.540697 -421.974338) (xy 273.536668 -421.883332) (xy 267.052699 -421.883332)
			(xy 267.001167 -421.898459) (xy 266.947216 -421.906211) (xy 266.919964 -421.9067) (xy 266.890891 -421.906151)
			(xy 266.833418 -421.897324) (xy 266.77795 -421.879881) (xy 266.725771 -421.854224) (xy 266.678087 -421.820947)
			(xy 266.636004 -421.780822) (xy 266.600496 -421.734777) (xy 266.585954 -421.709596) (xy 266.580112 -421.698928)
			(xy 266.560554 -421.685466) (xy 266.468098 -421.672258) (xy 266.456321 -421.671279) (xy 266.433958 -421.678832)
			(xy 266.425172 -421.686736) (xy 265.999214 -422.112694) (xy 265.994896 -422.147238) (xy 266.00404 -422.162224)
			(xy 266.021328 -422.192055) (xy 266.048586 -422.255386) (xy 266.067044 -422.321817) (xy 266.068489 -422.332404)
			(xy 269.930116 -422.332404) (xy 269.934187 -422.276782) (xy 269.946313 -422.222345) (xy 269.966236 -422.170254)
			(xy 269.993532 -422.121619) (xy 270.027618 -422.077476) (xy 270.067767 -422.038767) (xy 270.113125 -422.006316)
			(xy 270.162725 -421.980815) (xy 270.215509 -421.962808) (xy 270.270352 -421.952678) (xy 270.326086 -421.950641)
			(xy 270.381523 -421.956741) (xy 270.43548 -421.970847) (xy 270.486809 -421.992659) (xy 270.534415 -422.021713)
			(xy 270.577283 -422.057388) (xy 270.6145 -422.098925) (xy 270.645273 -422.145438) (xy 270.668945 -422.195935)
			(xy 270.685013 -422.249342) (xy 270.693133 -422.304518) (xy 270.693642 -422.332404) (xy 270.693401 -422.345612)
			(xy 270.946116 -422.345612) (xy 270.950187 -422.28999) (xy 270.962313 -422.235553) (xy 270.982236 -422.183462)
			(xy 271.009532 -422.134827) (xy 271.043618 -422.090684) (xy 271.083767 -422.051975) (xy 271.129125 -422.019524)
			(xy 271.178725 -421.994023) (xy 271.231509 -421.976016) (xy 271.286352 -421.965886) (xy 271.342086 -421.963849)
			(xy 271.397523 -421.969949) (xy 271.45148 -421.984055) (xy 271.502809 -422.005867) (xy 271.550415 -422.034921)
			(xy 271.593283 -422.070596) (xy 271.6305 -422.112133) (xy 271.661273 -422.158646) (xy 271.684945 -422.209143)
			(xy 271.701013 -422.26255) (xy 271.709133 -422.317726) (xy 271.709642 -422.345612) (xy 271.709133 -422.373498)
			(xy 271.701013 -422.428674) (xy 271.684945 -422.482081) (xy 271.661273 -422.532578) (xy 271.6305 -422.579091)
			(xy 271.593283 -422.620628) (xy 271.550415 -422.656303) (xy 271.502809 -422.685357) (xy 271.45148 -422.707169)
			(xy 271.397523 -422.721275) (xy 271.342086 -422.727375) (xy 271.286352 -422.725338) (xy 271.231509 -422.715208)
			(xy 271.178725 -422.697201) (xy 271.129125 -422.6717) (xy 271.083767 -422.639249) (xy 271.043618 -422.60054)
			(xy 271.009532 -422.556397) (xy 270.982236 -422.507762) (xy 270.962313 -422.455671) (xy 270.950187 -422.401234)
			(xy 270.946116 -422.345612) (xy 270.693401 -422.345612) (xy 270.693133 -422.36029) (xy 270.685013 -422.415466)
			(xy 270.668945 -422.468873) (xy 270.645273 -422.51937) (xy 270.6145 -422.565883) (xy 270.577283 -422.60742)
			(xy 270.534415 -422.643095) (xy 270.486809 -422.672149) (xy 270.43548 -422.693961) (xy 270.381523 -422.708067)
			(xy 270.326086 -422.714167) (xy 270.270352 -422.71213) (xy 270.215509 -422.702) (xy 270.162725 -422.683993)
			(xy 270.113125 -422.658492) (xy 270.067767 -422.626041) (xy 270.027618 -422.587332) (xy 269.993532 -422.543189)
			(xy 269.966236 -422.494554) (xy 269.946313 -422.442463) (xy 269.934187 -422.388026) (xy 269.930116 -422.332404)
			(xy 266.068489 -422.332404) (xy 266.076365 -422.390132) (xy 266.076938 -422.424606) (xy 266.076459 -422.456629)
			(xy 266.068426 -422.520168) (xy 266.052475 -422.582195) (xy 266.02886 -422.641728) (xy 265.997953 -422.697822)
			(xy 265.960246 -422.74959) (xy 265.916334 -422.796212) (xy 265.866915 -422.836948) (xy 265.812769 -422.871154)
			(xy 265.754756 -422.898288) (xy 265.693794 -422.917921) (xy 265.630849 -422.92974) (xy 265.59891 -422.932098)
			(xy 265.589543 -422.933016) (xy 265.572433 -422.940829) (xy 265.565636 -422.947338) (xy 265.544554 -422.968928)
			(xy 265.537967 -422.976308) (xy 265.530507 -422.994607) (xy 265.530076 -423.004488) (xy 265.530076 -424.974469)
			(xy 274.98776 -424.974469) (xy 274.98776 -424.910547) (xy 274.995771 -424.847129) (xy 275.011668 -424.785215)
			(xy 275.0352 -424.725782) (xy 275.065994 -424.669767) (xy 275.103567 -424.618052) (xy 275.147324 -424.571455)
			(xy 275.196577 -424.53071) (xy 275.250548 -424.496459) (xy 275.308387 -424.469242) (xy 275.36918 -424.449489)
			(xy 275.43197 -424.437511) (xy 275.495766 -424.433498) (xy 275.559562 -424.437511) (xy 275.57977 -424.441366)
			(xy 283.081982 -424.441366) (xy 283.086053 -424.385744) (xy 283.098179 -424.331307) (xy 283.118102 -424.279216)
			(xy 283.145398 -424.230581) (xy 283.179484 -424.186438) (xy 283.219633 -424.147729) (xy 283.264991 -424.115278)
			(xy 283.314591 -424.089777) (xy 283.367375 -424.07177) (xy 283.422218 -424.06164) (xy 283.477952 -424.059603)
			(xy 283.533389 -424.065703) (xy 283.587346 -424.079809) (xy 283.638675 -424.101621) (xy 283.686281 -424.130675)
			(xy 283.729149 -424.16635) (xy 283.766366 -424.207887) (xy 283.797139 -424.2544) (xy 283.820811 -424.304897)
			(xy 283.836879 -424.358304) (xy 283.844999 -424.41348) (xy 283.845508 -424.441366) (xy 283.844999 -424.469252)
			(xy 283.836879 -424.524428) (xy 283.820811 -424.577835) (xy 283.797139 -424.628332) (xy 283.766366 -424.674845)
			(xy 283.747069 -424.696382) (xy 287.199578 -424.696382) (xy 287.200081 -424.668641) (xy 287.208094 -424.61374)
			(xy 287.223976 -424.560579) (xy 287.247394 -424.510281) (xy 287.277852 -424.463907) (xy 287.314708 -424.422435)
			(xy 287.357184 -424.38674) (xy 287.404383 -424.357577) (xy 287.45531 -424.33556) (xy 287.50889 -424.321155)
			(xy 287.536382 -424.317414) (xy 287.54832 -424.316144) (xy 287.568132 -424.30319) (xy 287.621218 -424.212766)
			(xy 287.622996 -424.189144) (xy 287.618424 -424.177968) (xy 287.606309 -424.147153) (xy 287.589246 -424.083176)
			(xy 287.580621 -424.017526) (xy 287.58007 -423.98442) (xy 287.580546 -423.952877) (xy 287.588347 -423.890276)
			(xy 287.603832 -423.82912) (xy 287.626762 -423.770349) (xy 287.656786 -423.714866) (xy 287.693442 -423.663523)
			(xy 287.736168 -423.617108) (xy 287.784306 -423.576335) (xy 287.837119 -423.541829) (xy 287.893794 -423.514121)
			(xy 287.953461 -423.493636) (xy 288.015204 -423.480689) (xy 288.078074 -423.475478) (xy 288.141106 -423.478085)
			(xy 288.203331 -423.488468) (xy 288.263794 -423.506468) (xy 288.321566 -423.531809) (xy 288.37576 -423.564101)
			(xy 288.425544 -423.602849) (xy 288.470152 -423.647458) (xy 288.5089 -423.697241) (xy 288.541192 -423.751435)
			(xy 288.566533 -423.809208) (xy 288.584533 -423.869671) (xy 288.594916 -423.931896) (xy 288.597522 -423.994928)
			(xy 288.592311 -424.057798) (xy 288.579364 -424.119541) (xy 288.558878 -424.179208) (xy 288.53117 -424.235883)
			(xy 288.496664 -424.288695) (xy 288.455891 -424.336834) (xy 288.409476 -424.379559) (xy 288.358132 -424.416215)
			(xy 288.302649 -424.446239) (xy 288.243878 -424.469169) (xy 288.182722 -424.484653) (xy 288.120121 -424.492454)
			(xy 288.088578 -424.492928) (xy 288.059114 -424.492166) (xy 288.046922 -424.491404) (xy 288.025332 -424.500548)
			(xy 287.990844 -424.540934) (xy 289.2077 -424.540934) (xy 289.211771 -424.485312) (xy 289.223897 -424.430875)
			(xy 289.24382 -424.378784) (xy 289.271116 -424.330149) (xy 289.305202 -424.286006) (xy 289.345351 -424.247297)
			(xy 289.390709 -424.214846) (xy 289.440309 -424.189345) (xy 289.493093 -424.171338) (xy 289.547936 -424.161208)
			(xy 289.60367 -424.159171) (xy 289.659107 -424.165271) (xy 289.713064 -424.179377) (xy 289.764393 -424.201189)
			(xy 289.811999 -424.230243) (xy 289.854867 -424.265918) (xy 289.892084 -424.307455) (xy 289.922857 -424.353968)
			(xy 289.946529 -424.404465) (xy 289.962597 -424.457872) (xy 289.963495 -424.463972) (xy 290.22116 -424.463972)
			(xy 290.225231 -424.40835) (xy 290.237357 -424.353913) (xy 290.25728 -424.301822) (xy 290.284576 -424.253187)
			(xy 290.318662 -424.209044) (xy 290.358811 -424.170335) (xy 290.404169 -424.137884) (xy 290.453769 -424.112383)
			(xy 290.506553 -424.094376) (xy 290.561396 -424.084246) (xy 290.61713 -424.082209) (xy 290.672567 -424.088309)
			(xy 290.726524 -424.102415) (xy 290.777853 -424.124227) (xy 290.825459 -424.153281) (xy 290.868327 -424.188956)
			(xy 290.905544 -424.230493) (xy 290.936317 -424.277006) (xy 290.959989 -424.327503) (xy 290.976057 -424.38091)
			(xy 290.984177 -424.436086) (xy 290.984686 -424.463972) (xy 290.984177 -424.491858) (xy 290.976057 -424.547034)
			(xy 290.959989 -424.600441) (xy 290.936317 -424.650938) (xy 290.905544 -424.697451) (xy 290.868327 -424.738988)
			(xy 290.825459 -424.774663) (xy 290.777853 -424.803717) (xy 290.726524 -424.825529) (xy 290.672567 -424.839635)
			(xy 290.61713 -424.845735) (xy 290.561396 -424.843698) (xy 290.506553 -424.833568) (xy 290.453769 -424.815561)
			(xy 290.404169 -424.79006) (xy 290.358811 -424.757609) (xy 290.318662 -424.7189) (xy 290.284576 -424.674757)
			(xy 290.25728 -424.626122) (xy 290.237357 -424.574031) (xy 290.225231 -424.519594) (xy 290.22116 -424.463972)
			(xy 289.963495 -424.463972) (xy 289.970717 -424.513048) (xy 289.971226 -424.540934) (xy 289.970717 -424.56882)
			(xy 289.962597 -424.623996) (xy 289.946529 -424.677403) (xy 289.922857 -424.7279) (xy 289.892084 -424.774413)
			(xy 289.854867 -424.81595) (xy 289.811999 -424.851625) (xy 289.764393 -424.880679) (xy 289.713064 -424.902491)
			(xy 289.659107 -424.916597) (xy 289.60367 -424.922697) (xy 289.547936 -424.92066) (xy 289.493093 -424.91053)
			(xy 289.440309 -424.892523) (xy 289.390709 -424.867022) (xy 289.345351 -424.834571) (xy 289.305202 -424.795862)
			(xy 289.271116 -424.751719) (xy 289.24382 -424.703084) (xy 289.223897 -424.650993) (xy 289.211771 -424.596556)
			(xy 289.2077 -424.540934) (xy 287.990844 -424.540934) (xy 287.957006 -424.580558) (xy 287.951164 -424.603418)
			(xy 287.953958 -424.615102) (xy 287.958029 -424.635174) (xy 287.962353 -424.675903) (xy 287.962594 -424.696382)
			(xy 287.96212 -424.723555) (xy 287.954404 -424.77735) (xy 287.939141 -424.829508) (xy 287.916637 -424.878975)
			(xy 287.902396 -424.902122) (xy 287.895792 -424.912536) (xy 287.893252 -424.936412) (xy 287.932368 -425.03598)
			(xy 287.950402 -425.051982) (xy 287.96234 -425.055284) (xy 287.995149 -425.064367) (xy 288.058174 -425.090106)
			(xy 288.117194 -425.124034) (xy 288.171152 -425.165545) (xy 288.219079 -425.213893) (xy 288.260117 -425.268212)
			(xy 288.2773 -425.2976) (xy 288.282634 -425.306998) (xy 288.29889 -425.319444) (xy 288.390584 -425.342812)
			(xy 288.410904 -425.33951) (xy 288.419794 -425.333922) (xy 288.450289 -425.315481) (xy 288.51536 -425.286423)
			(xy 288.58385 -425.266732) (xy 288.654418 -425.256793) (xy 288.69005 -425.256198) (xy 288.722015 -425.256664)
			(xy 288.785441 -425.264671) (xy 288.847363 -425.280564) (xy 288.906805 -425.304094) (xy 288.962829 -425.334888)
			(xy 289.014551 -425.372462) (xy 289.061156 -425.416222) (xy 289.101908 -425.465479) (xy 289.136165 -425.519455)
			(xy 289.163387 -425.5773) (xy 289.183143 -425.6381) (xy 289.195123 -425.700897) (xy 289.199138 -425.7647)
			(xy 289.195123 -425.828503) (xy 289.186514 -425.873629) (xy 289.396418 -425.873629) (xy 289.396418 -425.809707)
			(xy 289.404429 -425.746289) (xy 289.420326 -425.684375) (xy 289.443858 -425.624942) (xy 289.474652 -425.568927)
			(xy 289.512225 -425.517212) (xy 289.555982 -425.470615) (xy 289.605235 -425.42987) (xy 289.659206 -425.395619)
			(xy 289.717045 -425.368402) (xy 289.777838 -425.348649) (xy 289.840628 -425.336671) (xy 289.904424 -425.332658)
			(xy 289.96822 -425.336671) (xy 290.03101 -425.348649) (xy 290.091803 -425.368402) (xy 290.149642 -425.395619)
			(xy 290.203613 -425.42987) (xy 290.252866 -425.470615) (xy 290.296623 -425.517212) (xy 290.334196 -425.568927)
			(xy 290.36499 -425.624942) (xy 290.379782 -425.662301) (xy 301.962814 -425.662301) (xy 301.962814 -425.598379)
			(xy 301.970825 -425.534961) (xy 301.986722 -425.473047) (xy 302.010254 -425.413614) (xy 302.041048 -425.357599)
			(xy 302.078621 -425.305884) (xy 302.122378 -425.259287) (xy 302.171631 -425.218542) (xy 302.225602 -425.184291)
			(xy 302.283441 -425.157074) (xy 302.344234 -425.137321) (xy 302.407024 -425.125343) (xy 302.47082 -425.12133)
			(xy 302.534616 -425.125343) (xy 302.597406 -425.137321) (xy 302.658199 -425.157074) (xy 302.716038 -425.184291)
			(xy 302.770009 -425.218542) (xy 302.819262 -425.259287) (xy 302.863019 -425.305884) (xy 302.900592 -425.357599)
			(xy 302.931386 -425.413614) (xy 302.954918 -425.473047) (xy 302.970815 -425.534961) (xy 302.978826 -425.598379)
			(xy 302.97906 -425.613279) (xy 304.11394 -425.613279) (xy 304.11394 -425.549357) (xy 304.121951 -425.485939)
			(xy 304.137848 -425.424025) (xy 304.16138 -425.364592) (xy 304.192174 -425.308577) (xy 304.229747 -425.256862)
			(xy 304.273504 -425.210265) (xy 304.322757 -425.16952) (xy 304.376728 -425.135269) (xy 304.434567 -425.108052)
			(xy 304.49536 -425.088299) (xy 304.55815 -425.076321) (xy 304.621946 -425.072308) (xy 304.685742 -425.076321)
			(xy 304.748532 -425.088299) (xy 304.809325 -425.108052) (xy 304.867164 -425.135269) (xy 304.921135 -425.16952)
			(xy 304.970388 -425.210265) (xy 305.014145 -425.256862) (xy 305.051718 -425.308577) (xy 305.082512 -425.364592)
			(xy 305.106044 -425.424025) (xy 305.121941 -425.485939) (xy 305.129952 -425.549357) (xy 305.130454 -425.581318)
			(xy 305.129952 -425.613279) (xy 305.121941 -425.676697) (xy 305.106044 -425.738611) (xy 305.082512 -425.798044)
			(xy 305.051718 -425.854059) (xy 305.014145 -425.905774) (xy 304.970388 -425.952371) (xy 304.921135 -425.993116)
			(xy 304.867164 -426.027367) (xy 304.809325 -426.054584) (xy 304.748532 -426.074337) (xy 304.685742 -426.086315)
			(xy 304.621946 -426.090329) (xy 304.55815 -426.086315) (xy 304.49536 -426.074337) (xy 304.434567 -426.054584)
			(xy 304.376728 -426.027367) (xy 304.322757 -425.993116) (xy 304.273504 -425.952371) (xy 304.229747 -425.905774)
			(xy 304.192174 -425.854059) (xy 304.16138 -425.798044) (xy 304.137848 -425.738611) (xy 304.121951 -425.676697)
			(xy 304.11394 -425.613279) (xy 302.97906 -425.613279) (xy 302.979328 -425.63034) (xy 302.978826 -425.662301)
			(xy 302.970815 -425.725719) (xy 302.954918 -425.787633) (xy 302.931386 -425.847066) (xy 302.900592 -425.903081)
			(xy 302.863019 -425.954796) (xy 302.819262 -426.001393) (xy 302.770009 -426.042138) (xy 302.716038 -426.076389)
			(xy 302.658199 -426.103606) (xy 302.597406 -426.123359) (xy 302.534616 -426.135337) (xy 302.47082 -426.139351)
			(xy 302.407024 -426.135337) (xy 302.344234 -426.123359) (xy 302.283441 -426.103606) (xy 302.225602 -426.076389)
			(xy 302.171631 -426.042138) (xy 302.122378 -426.001393) (xy 302.078621 -425.954796) (xy 302.041048 -425.903081)
			(xy 302.010254 -425.847066) (xy 301.986722 -425.787633) (xy 301.970825 -425.725719) (xy 301.962814 -425.662301)
			(xy 290.379782 -425.662301) (xy 290.388522 -425.684375) (xy 290.404419 -425.746289) (xy 290.41243 -425.809707)
			(xy 290.412932 -425.841668) (xy 290.41243 -425.873629) (xy 290.404419 -425.937047) (xy 290.388522 -425.998961)
			(xy 290.36499 -426.058394) (xy 290.334196 -426.114409) (xy 290.296623 -426.166124) (xy 290.252866 -426.212721)
			(xy 290.203613 -426.253466) (xy 290.149642 -426.287717) (xy 290.091803 -426.314934) (xy 290.03101 -426.334687)
			(xy 289.96822 -426.346665) (xy 289.904424 -426.350679) (xy 289.840628 -426.346665) (xy 289.777838 -426.334687)
			(xy 289.717045 -426.314934) (xy 289.659206 -426.287717) (xy 289.605235 -426.253466) (xy 289.555982 -426.212721)
			(xy 289.512225 -426.166124) (xy 289.474652 -426.114409) (xy 289.443858 -426.058394) (xy 289.420326 -425.998961)
			(xy 289.404429 -425.937047) (xy 289.396418 -425.873629) (xy 289.186514 -425.873629) (xy 289.183143 -425.8913)
			(xy 289.163387 -425.9521) (xy 289.136165 -426.009945) (xy 289.101908 -426.063921) (xy 289.061156 -426.113178)
			(xy 289.014551 -426.156938) (xy 288.962829 -426.194512) (xy 288.906805 -426.225306) (xy 288.847363 -426.248836)
			(xy 288.785441 -426.264729) (xy 288.722015 -426.272736) (xy 288.69005 -426.273214) (xy 288.656426 -426.272697)
			(xy 288.589766 -426.263827) (xy 288.524856 -426.246249) (xy 288.46283 -426.220269) (xy 288.404768 -426.186341)
			(xy 288.351685 -426.145056) (xy 288.304507 -426.097135) (xy 288.264056 -426.043414) (xy 288.247074 -426.014388)
			(xy 288.24174 -426.00499) (xy 288.225484 -425.992544) (xy 288.13379 -425.969176) (xy 288.11347 -425.972478)
			(xy 288.10458 -425.978066) (xy 288.074067 -425.996475) (xy 288.009003 -426.025541) (xy 287.940518 -426.045241)
			(xy 287.869955 -426.05519) (xy 287.834324 -426.05579) (xy 287.803592 -426.05534) (xy 287.742575 -426.047934)
			(xy 287.682896 -426.033226) (xy 287.625425 -426.011432) (xy 287.571 -425.982869) (xy 287.520415 -425.947954)
			(xy 287.474408 -425.907196) (xy 287.433649 -425.861189) (xy 287.398734 -425.810605) (xy 287.37017 -425.75618)
			(xy 287.348376 -425.69871) (xy 287.333668 -425.639031) (xy 287.326261 -425.578014) (xy 287.325816 -425.547282)
			(xy 287.326288 -425.516005) (xy 287.333927 -425.453921) (xy 287.349124 -425.393242) (xy 287.371651 -425.334886)
			(xy 287.401165 -425.279734) (xy 287.437223 -425.228619) (xy 287.457896 -425.205144) (xy 287.466278 -425.196)
			(xy 287.472628 -425.172886) (xy 287.450784 -425.067984) (xy 287.435798 -425.049442) (xy 287.424622 -425.044362)
			(xy 287.399812 -425.032739) (xy 287.353577 -425.003342) (xy 287.312022 -424.967635) (xy 287.276 -424.926352)
			(xy 287.246252 -424.880343) (xy 287.223389 -424.830552) (xy 287.207882 -424.778003) (xy 287.200049 -424.723777)
			(xy 287.199578 -424.696382) (xy 283.747069 -424.696382) (xy 283.729149 -424.716382) (xy 283.686281 -424.752057)
			(xy 283.638675 -424.781111) (xy 283.587346 -424.802923) (xy 283.533389 -424.817029) (xy 283.477952 -424.823129)
			(xy 283.422218 -424.821092) (xy 283.367375 -424.810962) (xy 283.314591 -424.792955) (xy 283.264991 -424.767454)
			(xy 283.219633 -424.735003) (xy 283.179484 -424.696294) (xy 283.145398 -424.652151) (xy 283.118102 -424.603516)
			(xy 283.098179 -424.551425) (xy 283.086053 -424.496988) (xy 283.081982 -424.441366) (xy 275.57977 -424.441366)
			(xy 275.622352 -424.449489) (xy 275.683145 -424.469242) (xy 275.740984 -424.496459) (xy 275.794955 -424.53071)
			(xy 275.844208 -424.571455) (xy 275.887965 -424.618052) (xy 275.925538 -424.669767) (xy 275.956332 -424.725782)
			(xy 275.979864 -424.785215) (xy 275.995761 -424.847129) (xy 276.003772 -424.910547) (xy 276.004274 -424.942508)
			(xy 276.003772 -424.974469) (xy 275.995761 -425.037887) (xy 275.979864 -425.099801) (xy 275.956332 -425.159234)
			(xy 275.925538 -425.215249) (xy 275.887965 -425.266964) (xy 275.844208 -425.313561) (xy 275.794955 -425.354306)
			(xy 275.740984 -425.388557) (xy 275.683145 -425.415774) (xy 275.622352 -425.435527) (xy 275.559562 -425.447505)
			(xy 275.495766 -425.451519) (xy 275.43197 -425.447505) (xy 275.36918 -425.435527) (xy 275.308387 -425.415774)
			(xy 275.250548 -425.388557) (xy 275.196577 -425.354306) (xy 275.147324 -425.313561) (xy 275.103567 -425.266964)
			(xy 275.065994 -425.215249) (xy 275.0352 -425.159234) (xy 275.011668 -425.099801) (xy 274.995771 -425.037887)
			(xy 274.98776 -424.974469) (xy 265.530076 -424.974469) (xy 265.530076 -425.910205) (xy 273.093682 -425.910205)
			(xy 273.093682 -425.846283) (xy 273.101693 -425.782865) (xy 273.11759 -425.720951) (xy 273.141122 -425.661518)
			(xy 273.171916 -425.605503) (xy 273.209489 -425.553788) (xy 273.253246 -425.507191) (xy 273.302499 -425.466446)
			(xy 273.35647 -425.432195) (xy 273.414309 -425.404978) (xy 273.475102 -425.385225) (xy 273.537892 -425.373247)
			(xy 273.601688 -425.369234) (xy 273.665484 -425.373247) (xy 273.728274 -425.385225) (xy 273.789067 -425.404978)
			(xy 273.846906 -425.432195) (xy 273.900877 -425.466446) (xy 273.95013 -425.507191) (xy 273.993887 -425.553788)
			(xy 274.03146 -425.605503) (xy 274.062254 -425.661518) (xy 274.085786 -425.720951) (xy 274.101683 -425.782865)
			(xy 274.109694 -425.846283) (xy 274.110196 -425.878244) (xy 274.109694 -425.910205) (xy 274.101683 -425.973623)
			(xy 274.085786 -426.035537) (xy 274.062254 -426.09497) (xy 274.03146 -426.150985) (xy 273.993887 -426.2027)
			(xy 273.960865 -426.237865) (xy 284.634934 -426.237865) (xy 284.634934 -426.173943) (xy 284.642945 -426.110525)
			(xy 284.658842 -426.048611) (xy 284.682374 -425.989178) (xy 284.713168 -425.933163) (xy 284.750741 -425.881448)
			(xy 284.794498 -425.834851) (xy 284.843751 -425.794106) (xy 284.897722 -425.759855) (xy 284.955561 -425.732638)
			(xy 285.016354 -425.712885) (xy 285.079144 -425.700907) (xy 285.14294 -425.696894) (xy 285.206736 -425.700907)
			(xy 285.269526 -425.712885) (xy 285.330319 -425.732638) (xy 285.388158 -425.759855) (xy 285.442129 -425.794106)
			(xy 285.491382 -425.834851) (xy 285.535139 -425.881448) (xy 285.572712 -425.933163) (xy 285.603506 -425.989178)
			(xy 285.627038 -426.048611) (xy 285.642935 -426.110525) (xy 285.650946 -426.173943) (xy 285.651448 -426.205904)
			(xy 285.650946 -426.237865) (xy 285.642935 -426.301283) (xy 285.627038 -426.363197) (xy 285.603506 -426.42263)
			(xy 285.572712 -426.478645) (xy 285.535139 -426.53036) (xy 285.491382 -426.576957) (xy 285.442129 -426.617702)
			(xy 285.388158 -426.651953) (xy 285.330319 -426.67917) (xy 285.269526 -426.698923) (xy 285.206736 -426.710901)
			(xy 285.14294 -426.714915) (xy 285.079144 -426.710901) (xy 285.016354 -426.698923) (xy 284.955561 -426.67917)
			(xy 284.897722 -426.651953) (xy 284.843751 -426.617702) (xy 284.794498 -426.576957) (xy 284.750741 -426.53036)
			(xy 284.713168 -426.478645) (xy 284.682374 -426.42263) (xy 284.658842 -426.363197) (xy 284.642945 -426.301283)
			(xy 284.634934 -426.237865) (xy 273.960865 -426.237865) (xy 273.95013 -426.249297) (xy 273.900877 -426.290042)
			(xy 273.846906 -426.324293) (xy 273.789067 -426.35151) (xy 273.728274 -426.371263) (xy 273.665484 -426.383241)
			(xy 273.601688 -426.387255) (xy 273.537892 -426.383241) (xy 273.475102 -426.371263) (xy 273.414309 -426.35151)
			(xy 273.35647 -426.324293) (xy 273.302499 -426.290042) (xy 273.253246 -426.249297) (xy 273.209489 -426.2027)
			(xy 273.171916 -426.150985) (xy 273.141122 -426.09497) (xy 273.11759 -426.035537) (xy 273.101693 -425.973623)
			(xy 273.093682 -425.910205) (xy 265.530076 -425.910205) (xy 265.530076 -427.261528) (xy 280.287982 -427.261528)
			(xy 280.292053 -427.205906) (xy 280.304179 -427.151469) (xy 280.324102 -427.099378) (xy 280.351398 -427.050743)
			(xy 280.385484 -427.0066) (xy 280.425633 -426.967891) (xy 280.470991 -426.93544) (xy 280.520591 -426.909939)
			(xy 280.573375 -426.891932) (xy 280.628218 -426.881802) (xy 280.683952 -426.879765) (xy 280.739389 -426.885865)
			(xy 280.793346 -426.899971) (xy 280.844675 -426.921783) (xy 280.892281 -426.950837) (xy 280.935149 -426.986512)
			(xy 280.972366 -427.028049) (xy 281.003139 -427.074562) (xy 281.026811 -427.125059) (xy 281.042879 -427.178466)
			(xy 281.050999 -427.233642) (xy 281.051151 -427.24197) (xy 284.174944 -427.24197) (xy 284.179015 -427.186348)
			(xy 284.191141 -427.131911) (xy 284.211064 -427.07982) (xy 284.23836 -427.031185) (xy 284.272446 -426.987042)
			(xy 284.312595 -426.948333) (xy 284.357953 -426.915882) (xy 284.407553 -426.890381) (xy 284.460337 -426.872374)
			(xy 284.51518 -426.862244) (xy 284.570914 -426.860207) (xy 284.626351 -426.866307) (xy 284.680308 -426.880413)
			(xy 284.731637 -426.902225) (xy 284.779243 -426.931279) (xy 284.822111 -426.966954) (xy 284.859328 -427.008491)
			(xy 284.890101 -427.055004) (xy 284.913773 -427.105501) (xy 284.929841 -427.158908) (xy 284.937961 -427.214084)
			(xy 284.93847 -427.24197) (xy 284.937961 -427.269856) (xy 284.929841 -427.325032) (xy 284.913773 -427.378439)
			(xy 284.890101 -427.428936) (xy 284.859328 -427.475449) (xy 284.822111 -427.516986) (xy 284.779243 -427.552661)
			(xy 284.731637 -427.581715) (xy 284.680308 -427.603527) (xy 284.626351 -427.617633) (xy 284.570914 -427.623733)
			(xy 284.51518 -427.621696) (xy 284.460337 -427.611566) (xy 284.407553 -427.593559) (xy 284.357953 -427.568058)
			(xy 284.312595 -427.535607) (xy 284.272446 -427.496898) (xy 284.23836 -427.452755) (xy 284.211064 -427.40412)
			(xy 284.191141 -427.352029) (xy 284.179015 -427.297592) (xy 284.174944 -427.24197) (xy 281.051151 -427.24197)
			(xy 281.051508 -427.261528) (xy 281.050999 -427.289414) (xy 281.042879 -427.34459) (xy 281.026811 -427.397997)
			(xy 281.003139 -427.448494) (xy 280.972366 -427.495007) (xy 280.935149 -427.536544) (xy 280.892281 -427.572219)
			(xy 280.844675 -427.601273) (xy 280.793346 -427.623085) (xy 280.739389 -427.637191) (xy 280.683952 -427.643291)
			(xy 280.628218 -427.641254) (xy 280.573375 -427.631124) (xy 280.520591 -427.613117) (xy 280.470991 -427.587616)
			(xy 280.425633 -427.555165) (xy 280.385484 -427.516456) (xy 280.351398 -427.472313) (xy 280.324102 -427.423678)
			(xy 280.304179 -427.371587) (xy 280.292053 -427.31715) (xy 280.287982 -427.261528) (xy 265.530076 -427.261528)
			(xy 265.530076 -427.763643) (xy 285.011108 -427.763643) (xy 285.011108 -427.699721) (xy 285.019119 -427.636303)
			(xy 285.035016 -427.574389) (xy 285.058548 -427.514956) (xy 285.089342 -427.458941) (xy 285.126915 -427.407226)
			(xy 285.170672 -427.360629) (xy 285.219925 -427.319884) (xy 285.273896 -427.285633) (xy 285.331735 -427.258416)
			(xy 285.392528 -427.238663) (xy 285.455318 -427.226685) (xy 285.519114 -427.222672) (xy 285.58291 -427.226685)
			(xy 285.6457 -427.238663) (xy 285.706493 -427.258416) (xy 285.764332 -427.285633) (xy 285.818303 -427.319884)
			(xy 285.860393 -427.354703) (xy 292.153588 -427.354703) (xy 292.153588 -427.290781) (xy 292.161599 -427.227363)
			(xy 292.177496 -427.165449) (xy 292.201028 -427.106016) (xy 292.231822 -427.050001) (xy 292.269395 -426.998286)
			(xy 292.313152 -426.951689) (xy 292.362405 -426.910944) (xy 292.416376 -426.876693) (xy 292.474215 -426.849476)
			(xy 292.535008 -426.829723) (xy 292.597798 -426.817745) (xy 292.661594 -426.813732) (xy 292.72539 -426.817745)
			(xy 292.78818 -426.829723) (xy 292.848973 -426.849476) (xy 292.906812 -426.876693) (xy 292.960783 -426.910944)
			(xy 293.010036 -426.951689) (xy 293.053793 -426.998286) (xy 293.091366 -427.050001) (xy 293.12216 -427.106016)
			(xy 293.145692 -427.165449) (xy 293.161589 -427.227363) (xy 293.1696 -427.290781) (xy 293.170102 -427.322742)
			(xy 293.1696 -427.354703) (xy 293.169562 -427.355) (xy 294.004492 -427.355) (xy 294.004926 -427.325334)
			(xy 294.011821 -427.266404) (xy 294.025529 -427.208677) (xy 294.045863 -427.152939) (xy 294.072547 -427.099946)
			(xy 294.105219 -427.05042) (xy 294.143434 -427.005034) (xy 294.164766 -426.984414) (xy 294.172386 -426.977302)
			(xy 294.180768 -426.957998) (xy 294.180768 -426.863002) (xy 294.172386 -426.843698) (xy 294.164766 -426.836586)
			(xy 294.143428 -426.815972) (xy 294.105218 -426.770581) (xy 294.072549 -426.721053) (xy 294.045864 -426.66806)
			(xy 294.025527 -426.612322) (xy 294.011813 -426.554596) (xy 294.00491 -426.495666) (xy 294.004492 -426.466)
			(xy 294.004994 -426.434039) (xy 294.013005 -426.370621) (xy 294.028902 -426.308707) (xy 294.052434 -426.249274)
			(xy 294.083228 -426.193259) (xy 294.120801 -426.141544) (xy 294.164558 -426.094947) (xy 294.213811 -426.054202)
			(xy 294.267782 -426.019951) (xy 294.325621 -425.992734) (xy 294.386414 -425.972981) (xy 294.449204 -425.961003)
			(xy 294.513 -425.95699) (xy 294.576796 -425.961003) (xy 294.639586 -425.972981) (xy 294.700379 -425.992734)
			(xy 294.758218 -426.019951) (xy 294.812189 -426.054202) (xy 294.861442 -426.094947) (xy 294.905199 -426.141544)
			(xy 294.942772 -426.193259) (xy 294.973566 -426.249274) (xy 294.997098 -426.308707) (xy 295.012995 -426.370621)
			(xy 295.021006 -426.434039) (xy 295.021508 -426.466) (xy 295.021074 -426.495666) (xy 295.014179 -426.554596)
			(xy 295.000471 -426.612323) (xy 294.980137 -426.668061) (xy 294.953453 -426.721054) (xy 294.920781 -426.77058)
			(xy 294.882566 -426.815966) (xy 294.87411 -426.82414) (xy 302.54143 -426.82414) (xy 302.545501 -426.768518)
			(xy 302.557627 -426.714081) (xy 302.57755 -426.66199) (xy 302.604846 -426.613355) (xy 302.638932 -426.569212)
			(xy 302.679081 -426.530503) (xy 302.724439 -426.498052) (xy 302.774039 -426.472551) (xy 302.826823 -426.454544)
			(xy 302.881666 -426.444414) (xy 302.9374 -426.442377) (xy 302.992837 -426.448477) (xy 303.046794 -426.462583)
			(xy 303.098123 -426.484395) (xy 303.145729 -426.513449) (xy 303.188597 -426.549124) (xy 303.225814 -426.590661)
			(xy 303.256587 -426.637174) (xy 303.280259 -426.687671) (xy 303.296327 -426.741078) (xy 303.304447 -426.796254)
			(xy 303.304956 -426.82414) (xy 303.304447 -426.852026) (xy 303.296327 -426.907202) (xy 303.282802 -426.952156)
			(xy 303.718976 -426.952156) (xy 303.719478 -426.920195) (xy 303.727489 -426.856777) (xy 303.743386 -426.794863)
			(xy 303.766918 -426.73543) (xy 303.797712 -426.679415) (xy 303.835285 -426.6277) (xy 303.879042 -426.581103)
			(xy 303.928295 -426.540358) (xy 303.982266 -426.506107) (xy 304.040105 -426.47889) (xy 304.100898 -426.459137)
			(xy 304.163688 -426.447159) (xy 304.227484 -426.443146) (xy 304.29128 -426.447159) (xy 304.35407 -426.459137)
			(xy 304.414863 -426.47889) (xy 304.472702 -426.506107) (xy 304.526673 -426.540358) (xy 304.575926 -426.581103)
			(xy 304.619683 -426.6277) (xy 304.657256 -426.679415) (xy 304.68805 -426.73543) (xy 304.711582 -426.794863)
			(xy 304.727479 -426.856777) (xy 304.73549 -426.920195) (xy 304.735992 -426.952156) (xy 304.735992 -426.955712)
			(xy 304.736351 -426.966522) (xy 304.745063 -426.986302) (xy 304.761148 -427.000738) (xy 304.771298 -427.00448)
			(xy 304.801619 -427.014753) (xy 304.859597 -427.041904) (xy 304.913707 -427.07612) (xy 304.963094 -427.116858)
			(xy 305.006975 -427.163474) (xy 305.044656 -427.215231) (xy 305.075541 -427.271309) (xy 305.099142 -427.330821)
			(xy 305.115084 -427.392825) (xy 305.123115 -427.45634) (xy 305.123596 -427.48835) (xy 305.123094 -427.520311)
			(xy 305.115083 -427.583729) (xy 305.099186 -427.645643) (xy 305.075654 -427.705076) (xy 305.04486 -427.761091)
			(xy 305.007287 -427.812806) (xy 304.96353 -427.859403) (xy 304.914277 -427.900148) (xy 304.860306 -427.934399)
			(xy 304.802467 -427.961616) (xy 304.741674 -427.981369) (xy 304.678884 -427.993347) (xy 304.615088 -427.997361)
			(xy 304.551292 -427.993347) (xy 304.488502 -427.981369) (xy 304.427709 -427.961616) (xy 304.36987 -427.934399)
			(xy 304.315899 -427.900148) (xy 304.266646 -427.859403) (xy 304.222889 -427.812806) (xy 304.185316 -427.761091)
			(xy 304.154522 -427.705076) (xy 304.13099 -427.645643) (xy 304.115093 -427.583729) (xy 304.107082 -427.520311)
			(xy 304.10658 -427.48835) (xy 304.10658 -427.484794) (xy 304.106235 -427.473981) (xy 304.09752 -427.454199)
			(xy 304.081428 -427.439764) (xy 304.071274 -427.436026) (xy 304.040949 -427.425765) (xy 303.982972 -427.398611)
			(xy 303.928863 -427.364393) (xy 303.879477 -427.323653) (xy 303.835597 -427.277035) (xy 303.797916 -427.225277)
			(xy 303.767031 -427.169199) (xy 303.743431 -427.109686) (xy 303.727489 -427.047682) (xy 303.719457 -426.984167)
			(xy 303.718976 -426.952156) (xy 303.282802 -426.952156) (xy 303.280259 -426.960609) (xy 303.256587 -427.011106)
			(xy 303.225814 -427.057619) (xy 303.188597 -427.099156) (xy 303.145729 -427.134831) (xy 303.098123 -427.163885)
			(xy 303.046794 -427.185697) (xy 302.992837 -427.199803) (xy 302.9374 -427.205903) (xy 302.881666 -427.203866)
			(xy 302.826823 -427.193736) (xy 302.774039 -427.175729) (xy 302.724439 -427.150228) (xy 302.679081 -427.117777)
			(xy 302.638932 -427.079068) (xy 302.604846 -427.034925) (xy 302.57755 -426.98629) (xy 302.557627 -426.934199)
			(xy 302.545501 -426.879762) (xy 302.54143 -426.82414) (xy 294.87411 -426.82414) (xy 294.861234 -426.836586)
			(xy 294.853614 -426.843698) (xy 294.845232 -426.863002) (xy 294.845232 -426.957998) (xy 294.853614 -426.977302)
			(xy 294.861234 -426.984414) (xy 294.882572 -427.005028) (xy 294.920782 -427.050419) (xy 294.953451 -427.099947)
			(xy 294.980136 -427.15294) (xy 295.000473 -427.208678) (xy 295.014187 -427.266404) (xy 295.02109 -427.325334)
			(xy 295.021508 -427.355) (xy 295.021006 -427.386961) (xy 295.01937 -427.399915) (xy 301.564796 -427.399915)
			(xy 301.564796 -427.335993) (xy 301.572807 -427.272575) (xy 301.588704 -427.210661) (xy 301.612236 -427.151228)
			(xy 301.64303 -427.095213) (xy 301.680603 -427.043498) (xy 301.72436 -426.996901) (xy 301.773613 -426.956156)
			(xy 301.827584 -426.921905) (xy 301.885423 -426.894688) (xy 301.946216 -426.874935) (xy 302.009006 -426.862957)
			(xy 302.072802 -426.858944) (xy 302.136598 -426.862957) (xy 302.199388 -426.874935) (xy 302.260181 -426.894688)
			(xy 302.31802 -426.921905) (xy 302.371991 -426.956156) (xy 302.421244 -426.996901) (xy 302.465001 -427.043498)
			(xy 302.502574 -427.095213) (xy 302.533368 -427.151228) (xy 302.5569 -427.210661) (xy 302.572797 -427.272575)
			(xy 302.580808 -427.335993) (xy 302.58131 -427.367954) (xy 302.580808 -427.399915) (xy 302.572797 -427.463333)
			(xy 302.5569 -427.525247) (xy 302.533368 -427.58468) (xy 302.502574 -427.640695) (xy 302.465001 -427.69241)
			(xy 302.421244 -427.739007) (xy 302.371991 -427.779752) (xy 302.31802 -427.814003) (xy 302.260181 -427.84122)
			(xy 302.199388 -427.860973) (xy 302.136598 -427.872951) (xy 302.072802 -427.876965) (xy 302.009006 -427.872951)
			(xy 301.946216 -427.860973) (xy 301.885423 -427.84122) (xy 301.827584 -427.814003) (xy 301.773613 -427.779752)
			(xy 301.72436 -427.739007) (xy 301.680603 -427.69241) (xy 301.64303 -427.640695) (xy 301.612236 -427.58468)
			(xy 301.588704 -427.525247) (xy 301.572807 -427.463333) (xy 301.564796 -427.399915) (xy 295.01937 -427.399915)
			(xy 295.012995 -427.450379) (xy 294.997098 -427.512293) (xy 294.973566 -427.571726) (xy 294.942772 -427.627741)
			(xy 294.905199 -427.679456) (xy 294.861442 -427.726053) (xy 294.812189 -427.766798) (xy 294.758218 -427.801049)
			(xy 294.700379 -427.828266) (xy 294.639586 -427.848019) (xy 294.576796 -427.859997) (xy 294.513 -427.864011)
			(xy 294.449204 -427.859997) (xy 294.386414 -427.848019) (xy 294.325621 -427.828266) (xy 294.267782 -427.801049)
			(xy 294.213811 -427.766798) (xy 294.164558 -427.726053) (xy 294.120801 -427.679456) (xy 294.083228 -427.627741)
			(xy 294.052434 -427.571726) (xy 294.028902 -427.512293) (xy 294.013005 -427.450379) (xy 294.004994 -427.386961)
			(xy 294.004492 -427.355) (xy 293.169562 -427.355) (xy 293.161589 -427.418121) (xy 293.145692 -427.480035)
			(xy 293.12216 -427.539468) (xy 293.091366 -427.595483) (xy 293.053793 -427.647198) (xy 293.010036 -427.693795)
			(xy 292.960783 -427.73454) (xy 292.906812 -427.768791) (xy 292.848973 -427.796008) (xy 292.78818 -427.815761)
			(xy 292.72539 -427.827739) (xy 292.661594 -427.831753) (xy 292.597798 -427.827739) (xy 292.535008 -427.815761)
			(xy 292.474215 -427.796008) (xy 292.416376 -427.768791) (xy 292.362405 -427.73454) (xy 292.313152 -427.693795)
			(xy 292.269395 -427.647198) (xy 292.231822 -427.595483) (xy 292.201028 -427.539468) (xy 292.177496 -427.480035)
			(xy 292.161599 -427.418121) (xy 292.153588 -427.354703) (xy 285.860393 -427.354703) (xy 285.867556 -427.360629)
			(xy 285.911313 -427.407226) (xy 285.948886 -427.458941) (xy 285.97968 -427.514956) (xy 286.003212 -427.574389)
			(xy 286.019109 -427.636303) (xy 286.02712 -427.699721) (xy 286.027622 -427.731682) (xy 286.02712 -427.763643)
			(xy 286.019109 -427.827061) (xy 286.003212 -427.888975) (xy 285.97968 -427.948408) (xy 285.948886 -428.004423)
			(xy 285.915075 -428.05096) (xy 288.54095 -428.05096) (xy 288.545021 -427.995338) (xy 288.557147 -427.940901)
			(xy 288.57707 -427.88881) (xy 288.604366 -427.840175) (xy 288.638452 -427.796032) (xy 288.678601 -427.757323)
			(xy 288.723959 -427.724872) (xy 288.773559 -427.699371) (xy 288.826343 -427.681364) (xy 288.881186 -427.671234)
			(xy 288.93692 -427.669197) (xy 288.992357 -427.675297) (xy 289.046314 -427.689403) (xy 289.097643 -427.711215)
			(xy 289.145249 -427.740269) (xy 289.188117 -427.775944) (xy 289.225334 -427.817481) (xy 289.256107 -427.863994)
			(xy 289.279779 -427.914491) (xy 289.295847 -427.967898) (xy 289.303967 -428.023074) (xy 289.304476 -428.05096)
			(xy 289.303967 -428.078846) (xy 289.295847 -428.134022) (xy 289.279779 -428.187429) (xy 289.256107 -428.237926)
			(xy 289.225334 -428.284439) (xy 289.188117 -428.325976) (xy 289.145249 -428.361651) (xy 289.097643 -428.390705)
			(xy 289.046314 -428.412517) (xy 288.992357 -428.426623) (xy 288.93692 -428.432723) (xy 288.881186 -428.430686)
			(xy 288.826343 -428.420556) (xy 288.773559 -428.402549) (xy 288.723959 -428.377048) (xy 288.678601 -428.344597)
			(xy 288.638452 -428.305888) (xy 288.604366 -428.261745) (xy 288.57707 -428.21311) (xy 288.557147 -428.161019)
			(xy 288.545021 -428.106582) (xy 288.54095 -428.05096) (xy 285.915075 -428.05096) (xy 285.911313 -428.056138)
			(xy 285.867556 -428.102735) (xy 285.818303 -428.14348) (xy 285.764332 -428.177731) (xy 285.706493 -428.204948)
			(xy 285.6457 -428.224701) (xy 285.58291 -428.236679) (xy 285.519114 -428.240693) (xy 285.455318 -428.236679)
			(xy 285.392528 -428.224701) (xy 285.331735 -428.204948) (xy 285.273896 -428.177731) (xy 285.219925 -428.14348)
			(xy 285.170672 -428.102735) (xy 285.126915 -428.056138) (xy 285.089342 -428.004423) (xy 285.058548 -427.948408)
			(xy 285.035016 -427.888975) (xy 285.019119 -427.827061) (xy 285.011108 -427.763643) (xy 265.530076 -427.763643)
			(xy 265.530076 -428.984156) (xy 275.625306 -428.984156) (xy 275.625808 -428.952195) (xy 275.633819 -428.888777)
			(xy 275.649716 -428.826863) (xy 275.673248 -428.76743) (xy 275.704042 -428.711415) (xy 275.741615 -428.6597)
			(xy 275.785372 -428.613103) (xy 275.834625 -428.572358) (xy 275.888596 -428.538107) (xy 275.946435 -428.51089)
			(xy 276.007228 -428.491137) (xy 276.070018 -428.479159) (xy 276.133814 -428.475146) (xy 276.19761 -428.479159)
			(xy 276.2604 -428.491137) (xy 276.321193 -428.51089) (xy 276.379032 -428.538107) (xy 276.433003 -428.572358)
			(xy 276.482256 -428.613103) (xy 276.526013 -428.6597) (xy 276.563586 -428.711415) (xy 276.59438 -428.76743)
			(xy 276.617912 -428.826863) (xy 276.633809 -428.888777) (xy 276.639225 -428.931654) (xy 286.368155 -428.931654)
			(xy 286.368155 -428.877146) (xy 286.375913 -428.823191) (xy 286.391271 -428.770891) (xy 286.413916 -428.721308)
			(xy 286.443388 -428.675453) (xy 286.479085 -428.63426) (xy 286.520282 -428.598566) (xy 286.56614 -428.569099)
			(xy 286.615724 -428.546459) (xy 286.668027 -428.531106) (xy 286.721981 -428.523353) (xy 286.749236 -428.522892)
			(xy 286.776818 -428.523349) (xy 286.806787 -428.527718) (xy 296.59148 -428.527718) (xy 296.595551 -428.472096)
			(xy 296.607677 -428.417659) (xy 296.6276 -428.365568) (xy 296.654896 -428.316933) (xy 296.688982 -428.27279)
			(xy 296.729131 -428.234081) (xy 296.774489 -428.20163) (xy 296.824089 -428.176129) (xy 296.876873 -428.158122)
			(xy 296.931716 -428.147992) (xy 296.98745 -428.145955) (xy 297.042887 -428.152055) (xy 297.096844 -428.166161)
			(xy 297.148173 -428.187973) (xy 297.195779 -428.217027) (xy 297.238647 -428.252702) (xy 297.275864 -428.294239)
			(xy 297.306637 -428.340752) (xy 297.330309 -428.391249) (xy 297.339348 -428.421292) (xy 299.06671 -428.421292)
			(xy 299.070781 -428.36567) (xy 299.082907 -428.311233) (xy 299.10283 -428.259142) (xy 299.130126 -428.210507)
			(xy 299.164212 -428.166364) (xy 299.204361 -428.127655) (xy 299.249719 -428.095204) (xy 299.299319 -428.069703)
			(xy 299.352103 -428.051696) (xy 299.406946 -428.041566) (xy 299.46268 -428.039529) (xy 299.518117 -428.045629)
			(xy 299.572074 -428.059735) (xy 299.623403 -428.081547) (xy 299.671009 -428.110601) (xy 299.713877 -428.146276)
			(xy 299.751094 -428.187813) (xy 299.781867 -428.234326) (xy 299.805539 -428.284823) (xy 299.821607 -428.33823)
			(xy 299.829727 -428.393406) (xy 299.830236 -428.421292) (xy 299.829727 -428.449178) (xy 299.821607 -428.504354)
			(xy 299.805539 -428.557761) (xy 299.781867 -428.608258) (xy 299.751094 -428.654771) (xy 299.713877 -428.696308)
			(xy 299.671009 -428.731983) (xy 299.623403 -428.761037) (xy 299.572074 -428.782849) (xy 299.518117 -428.796955)
			(xy 299.46268 -428.803055) (xy 299.406946 -428.801018) (xy 299.352103 -428.790888) (xy 299.299319 -428.772881)
			(xy 299.249719 -428.74738) (xy 299.204361 -428.714929) (xy 299.164212 -428.67622) (xy 299.130126 -428.632077)
			(xy 299.10283 -428.583442) (xy 299.082907 -428.531351) (xy 299.070781 -428.476914) (xy 299.06671 -428.421292)
			(xy 297.339348 -428.421292) (xy 297.346377 -428.444656) (xy 297.354497 -428.499832) (xy 297.355006 -428.527718)
			(xy 297.354497 -428.555604) (xy 297.346377 -428.61078) (xy 297.330309 -428.664187) (xy 297.306637 -428.714684)
			(xy 297.275864 -428.761197) (xy 297.238647 -428.802734) (xy 297.217203 -428.82058) (xy 303.904902 -428.82058)
			(xy 303.908973 -428.764958) (xy 303.921099 -428.710521) (xy 303.941022 -428.65843) (xy 303.968318 -428.609795)
			(xy 304.002404 -428.565652) (xy 304.042553 -428.526943) (xy 304.087911 -428.494492) (xy 304.137511 -428.468991)
			(xy 304.190295 -428.450984) (xy 304.245138 -428.440854) (xy 304.300872 -428.438817) (xy 304.356309 -428.444917)
			(xy 304.410266 -428.459023) (xy 304.461595 -428.480835) (xy 304.509201 -428.509889) (xy 304.552069 -428.545564)
			(xy 304.589286 -428.587101) (xy 304.620059 -428.633614) (xy 304.643731 -428.684111) (xy 304.659799 -428.737518)
			(xy 304.667919 -428.792694) (xy 304.668428 -428.82058) (xy 304.667919 -428.848466) (xy 304.659799 -428.903642)
			(xy 304.643731 -428.957049) (xy 304.620059 -429.007546) (xy 304.589286 -429.054059) (xy 304.552069 -429.095596)
			(xy 304.509201 -429.131271) (xy 304.461595 -429.160325) (xy 304.410266 -429.182137) (xy 304.356309 -429.196243)
			(xy 304.300872 -429.202343) (xy 304.245138 -429.200306) (xy 304.190295 -429.190176) (xy 304.137511 -429.172169)
			(xy 304.087911 -429.146668) (xy 304.042553 -429.114217) (xy 304.002404 -429.075508) (xy 303.968318 -429.031365)
			(xy 303.941022 -428.98273) (xy 303.921099 -428.930639) (xy 303.908973 -428.876202) (xy 303.904902 -428.82058)
			(xy 297.217203 -428.82058) (xy 297.195779 -428.838409) (xy 297.148173 -428.867463) (xy 297.096844 -428.889275)
			(xy 297.042887 -428.903381) (xy 296.98745 -428.909481) (xy 296.931716 -428.907444) (xy 296.876873 -428.897314)
			(xy 296.824089 -428.879307) (xy 296.774489 -428.853806) (xy 296.729131 -428.821355) (xy 296.688982 -428.782646)
			(xy 296.654896 -428.738503) (xy 296.6276 -428.689868) (xy 296.607677 -428.637777) (xy 296.595551 -428.58334)
			(xy 296.59148 -428.527718) (xy 286.806787 -428.527718) (xy 286.831406 -428.531307) (xy 286.884281 -428.547037)
			(xy 286.934342 -428.570212) (xy 286.980547 -428.60035) (xy 287.021934 -428.636823) (xy 287.057642 -428.678872)
			(xy 287.086928 -428.725621) (xy 287.109181 -428.776099) (xy 287.117028 -428.802546) (xy 287.121126 -428.815957)
			(xy 287.135669 -428.839927) (xy 287.156176 -428.859047) (xy 287.181104 -428.871879) (xy 287.20858 -428.877458)
			(xy 287.236539 -428.875366) (xy 287.262879 -428.865759) (xy 287.274508 -428.857918) (xy 287.30062 -428.839623)
			(xy 287.356519 -428.808954) (xy 287.415812 -428.785512) (xy 287.47757 -428.769664) (xy 287.540825 -428.761659)
			(xy 287.572704 -428.761144) (xy 287.604662 -428.761742) (xy 287.668074 -428.769753) (xy 287.729981 -428.785649)
			(xy 287.789408 -428.809178) (xy 287.845418 -428.83997) (xy 287.897127 -428.877539) (xy 287.943719 -428.921293)
			(xy 287.98446 -428.970541) (xy 288.018708 -429.024507) (xy 288.045922 -429.082339) (xy 288.065673 -429.143127)
			(xy 288.077649 -429.20591) (xy 288.081663 -429.2697) (xy 288.077649 -429.33349) (xy 288.065673 -429.396273)
			(xy 288.045922 -429.457061) (xy 288.018708 -429.514893) (xy 287.98446 -429.568859) (xy 287.952937 -429.606964)
			(xy 301.74133 -429.606964) (xy 301.745401 -429.551342) (xy 301.757527 -429.496905) (xy 301.77745 -429.444814)
			(xy 301.804746 -429.396179) (xy 301.838832 -429.352036) (xy 301.878981 -429.313327) (xy 301.924339 -429.280876)
			(xy 301.973939 -429.255375) (xy 302.026723 -429.237368) (xy 302.081566 -429.227238) (xy 302.1373 -429.225201)
			(xy 302.192737 -429.231301) (xy 302.246694 -429.245407) (xy 302.298023 -429.267219) (xy 302.345629 -429.296273)
			(xy 302.388497 -429.331948) (xy 302.425714 -429.373485) (xy 302.456487 -429.419998) (xy 302.480159 -429.470495)
			(xy 302.496227 -429.523902) (xy 302.504347 -429.579078) (xy 302.504856 -429.606964) (xy 302.504814 -429.60925)
			(xy 305.638198 -429.60925) (xy 305.642269 -429.553628) (xy 305.654395 -429.499191) (xy 305.674318 -429.4471)
			(xy 305.701614 -429.398465) (xy 305.7357 -429.354322) (xy 305.775849 -429.315613) (xy 305.821207 -429.283162)
			(xy 305.870807 -429.257661) (xy 305.923591 -429.239654) (xy 305.978434 -429.229524) (xy 306.034168 -429.227487)
			(xy 306.089605 -429.233587) (xy 306.143562 -429.247693) (xy 306.194891 -429.269505) (xy 306.242497 -429.298559)
			(xy 306.285365 -429.334234) (xy 306.322582 -429.375771) (xy 306.353355 -429.422284) (xy 306.377027 -429.472781)
			(xy 306.393095 -429.526188) (xy 306.401215 -429.581364) (xy 306.401724 -429.60925) (xy 306.401215 -429.637136)
			(xy 306.393095 -429.692312) (xy 306.377027 -429.745719) (xy 306.353355 -429.796216) (xy 306.322582 -429.842729)
			(xy 306.285365 -429.884266) (xy 306.242497 -429.919941) (xy 306.194891 -429.948995) (xy 306.143562 -429.970807)
			(xy 306.089605 -429.984913) (xy 306.034168 -429.991013) (xy 305.978434 -429.988976) (xy 305.923591 -429.978846)
			(xy 305.870807 -429.960839) (xy 305.821207 -429.935338) (xy 305.775849 -429.902887) (xy 305.7357 -429.864178)
			(xy 305.701614 -429.820035) (xy 305.674318 -429.7714) (xy 305.654395 -429.719309) (xy 305.642269 -429.664872)
			(xy 305.638198 -429.60925) (xy 302.504814 -429.60925) (xy 302.504347 -429.63485) (xy 302.496227 -429.690026)
			(xy 302.480159 -429.743433) (xy 302.456487 -429.79393) (xy 302.425714 -429.840443) (xy 302.388497 -429.88198)
			(xy 302.345629 -429.917655) (xy 302.298023 -429.946709) (xy 302.246694 -429.968521) (xy 302.192737 -429.982627)
			(xy 302.1373 -429.988727) (xy 302.081566 -429.98669) (xy 302.026723 -429.97656) (xy 301.973939 -429.958553)
			(xy 301.924339 -429.933052) (xy 301.878981 -429.900601) (xy 301.838832 -429.861892) (xy 301.804746 -429.817749)
			(xy 301.77745 -429.769114) (xy 301.757527 -429.717023) (xy 301.745401 -429.662586) (xy 301.74133 -429.606964)
			(xy 287.952937 -429.606964) (xy 287.943719 -429.618107) (xy 287.897127 -429.661861) (xy 287.845418 -429.69943)
			(xy 287.789408 -429.730222) (xy 287.729981 -429.753751) (xy 287.668074 -429.769647) (xy 287.604662 -429.777658)
			(xy 287.572704 -429.77816) (xy 287.541727 -429.777625) (xy 287.480233 -429.770099) (xy 287.420108 -429.755156)
			(xy 287.362244 -429.733019) (xy 287.307499 -429.704016) (xy 287.256683 -429.668576) (xy 287.210549 -429.627225)
			(xy 287.169781 -429.580575) (xy 287.134983 -429.529317) (xy 287.106671 -429.474211) (xy 287.085263 -429.416074)
			(xy 287.071078 -429.355766) (xy 287.067244 -429.325024) (xy 287.065217 -429.311165) (xy 287.054686 -429.285226)
			(xy 287.037514 -429.263116) (xy 287.01499 -429.24649) (xy 286.9888 -429.236597) (xy 286.96091 -429.234178)
			(xy 286.933408 -429.239413) (xy 286.920686 -429.245268) (xy 286.893932 -429.258059) (xy 286.837467 -429.276165)
			(xy 286.778884 -429.285339) (xy 286.749236 -429.285908) (xy 286.721981 -429.285447) (xy 286.668027 -429.277694)
			(xy 286.615724 -429.262341) (xy 286.56614 -429.239701) (xy 286.520282 -429.210234) (xy 286.479085 -429.17454)
			(xy 286.443388 -429.133347) (xy 286.413916 -429.087492) (xy 286.391271 -429.037909) (xy 286.375913 -428.985609)
			(xy 286.368155 -428.931654) (xy 276.639225 -428.931654) (xy 276.64182 -428.952195) (xy 276.642322 -428.984156)
			(xy 276.642009 -429.00928) (xy 276.637048 -429.059283) (xy 276.632416 -429.083978) (xy 276.630384 -429.09363)
			(xy 276.63394 -429.11268) (xy 276.681946 -429.188626) (xy 276.697694 -429.199802) (xy 276.707092 -429.202342)
			(xy 276.734191 -429.209639) (xy 276.786003 -429.231208) (xy 276.834095 -429.260136) (xy 276.87743 -429.295799)
			(xy 276.91507 -429.337426) (xy 276.946205 -429.38412) (xy 276.970161 -429.434872) (xy 276.986422 -429.488587)
			(xy 276.994636 -429.544105) (xy 276.995128 -429.572166) (xy 276.994613 -429.599417) (xy 276.993936 -429.604127)
			(xy 278.665426 -429.604127) (xy 278.665426 -429.540205) (xy 278.673437 -429.476787) (xy 278.689334 -429.414873)
			(xy 278.712866 -429.35544) (xy 278.74366 -429.299425) (xy 278.781233 -429.24771) (xy 278.82499 -429.201113)
			(xy 278.874243 -429.160368) (xy 278.928214 -429.126117) (xy 278.986053 -429.0989) (xy 279.046846 -429.079147)
			(xy 279.109636 -429.067169) (xy 279.173432 -429.063156) (xy 279.237228 -429.067169) (xy 279.300018 -429.079147)
			(xy 279.360811 -429.0989) (xy 279.41865 -429.126117) (xy 279.472621 -429.160368) (xy 279.521874 -429.201113)
			(xy 279.565631 -429.24771) (xy 279.603204 -429.299425) (xy 279.633998 -429.35544) (xy 279.65753 -429.414873)
			(xy 279.673427 -429.476787) (xy 279.681438 -429.540205) (xy 279.68194 -429.572166) (xy 279.681438 -429.604127)
			(xy 279.673427 -429.667545) (xy 279.65753 -429.729459) (xy 279.633998 -429.788892) (xy 279.603204 -429.844907)
			(xy 279.565631 -429.896622) (xy 279.521874 -429.943219) (xy 279.472621 -429.983964) (xy 279.41865 -430.018215)
			(xy 279.360811 -430.045432) (xy 279.300018 -430.065185) (xy 279.237228 -430.077163) (xy 279.173432 -430.081177)
			(xy 279.109636 -430.077163) (xy 279.046846 -430.065185) (xy 278.986053 -430.045432) (xy 278.928214 -430.018215)
			(xy 278.874243 -429.983964) (xy 278.82499 -429.943219) (xy 278.781233 -429.896622) (xy 278.74366 -429.844907)
			(xy 278.712866 -429.788892) (xy 278.689334 -429.729459) (xy 278.673437 -429.667545) (xy 278.665426 -429.604127)
			(xy 276.993936 -429.604127) (xy 276.986861 -429.653365) (xy 276.971511 -429.705661) (xy 276.948874 -429.755239)
			(xy 276.919411 -429.801092) (xy 276.883723 -429.842284) (xy 276.842535 -429.877979) (xy 276.796687 -429.907448)
			(xy 276.747111 -429.930092) (xy 276.694818 -429.94545) (xy 276.640871 -429.953209) (xy 276.61362 -429.953674)
			(xy 276.587172 -429.953223) (xy 276.534786 -429.945892) (xy 276.483915 -429.931396) (xy 276.435533 -429.910012)
			(xy 276.390569 -429.882151) (xy 276.349884 -429.848346) (xy 276.314258 -429.809246) (xy 276.284374 -429.7656)
			(xy 276.260805 -429.718245) (xy 276.244003 -429.668088) (xy 276.234289 -429.616091) (xy 276.23262 -429.589692)
			(xy 276.232112 -429.579786) (xy 276.223984 -429.562006) (xy 276.159214 -429.50003) (xy 276.141434 -429.492664)
			(xy 276.131528 -429.492664) (xy 276.098331 -429.492002) (xy 276.032535 -429.483065) (xy 275.968462 -429.46564)
			(xy 275.907202 -429.440023) (xy 275.849798 -429.40665) (xy 275.797226 -429.366089) (xy 275.750382 -429.319031)
			(xy 275.710061 -429.266275) (xy 275.67695 -429.208719) (xy 275.651612 -429.147344) (xy 275.634479 -429.083192)
			(xy 275.625841 -429.017356) (xy 275.625306 -428.984156) (xy 265.530076 -428.984156) (xy 265.530076 -433.130706)
			(xy 266.885409 -433.130706) (xy 266.885409 -432.953414) (xy 266.893363 -432.7763) (xy 266.909256 -432.599721)
			(xy 266.933054 -432.424033) (xy 266.964711 -432.24959) (xy 267.004162 -432.076743) (xy 267.051329 -431.90584)
			(xy 267.106115 -431.737225) (xy 267.168411 -431.571237) (xy 267.238091 -431.408212) (xy 267.315016 -431.248477)
			(xy 267.399029 -431.092354) (xy 267.489962 -430.940158) (xy 267.587632 -430.792194) (xy 267.691842 -430.648762)
			(xy 267.802382 -430.510149) (xy 267.919029 -430.376635) (xy 268.041549 -430.248489) (xy 268.169695 -430.125969)
			(xy 268.303209 -430.009322) (xy 268.441822 -429.898782) (xy 268.585254 -429.794572) (xy 268.733218 -429.696902)
			(xy 268.885414 -429.605969) (xy 269.041537 -429.521956) (xy 269.201272 -429.445031) (xy 269.364297 -429.375351)
			(xy 269.530285 -429.313055) (xy 269.6989 -429.258269) (xy 269.869803 -429.211102) (xy 270.04265 -429.171651)
			(xy 270.217093 -429.139994) (xy 270.392781 -429.116196) (xy 270.56936 -429.100303) (xy 270.746474 -429.092349)
			(xy 270.923766 -429.092349) (xy 271.10088 -429.100303) (xy 271.277459 -429.116196) (xy 271.453147 -429.139994)
			(xy 271.62759 -429.171651) (xy 271.800437 -429.211102) (xy 271.97134 -429.258269) (xy 272.139955 -429.313055)
			(xy 272.305943 -429.375351) (xy 272.468968 -429.445031) (xy 272.628703 -429.521956) (xy 272.784826 -429.605969)
			(xy 272.937022 -429.696902) (xy 273.084986 -429.794572) (xy 273.228418 -429.898782) (xy 273.367031 -430.009322)
			(xy 273.500545 -430.125969) (xy 273.628691 -430.248489) (xy 273.751211 -430.376635) (xy 273.867858 -430.510149)
			(xy 273.978398 -430.648762) (xy 274.082006 -430.791366) (xy 277.234902 -430.791366) (xy 277.238973 -430.735744)
			(xy 277.251099 -430.681307) (xy 277.271022 -430.629216) (xy 277.298318 -430.580581) (xy 277.332404 -430.536438)
			(xy 277.372553 -430.497729) (xy 277.417911 -430.465278) (xy 277.467511 -430.439777) (xy 277.520295 -430.42177)
			(xy 277.575138 -430.41164) (xy 277.630872 -430.409603) (xy 277.686309 -430.415703) (xy 277.740266 -430.429809)
			(xy 277.791595 -430.451621) (xy 277.839201 -430.480675) (xy 277.882069 -430.51635) (xy 277.919286 -430.557887)
			(xy 277.950059 -430.6044) (xy 277.973731 -430.654897) (xy 277.989799 -430.708304) (xy 277.997919 -430.76348)
			(xy 277.998428 -430.791366) (xy 277.997919 -430.819252) (xy 277.989799 -430.874428) (xy 277.973731 -430.927835)
			(xy 277.950059 -430.978332) (xy 277.919286 -431.024845) (xy 277.882069 -431.066382) (xy 277.839201 -431.102057)
			(xy 277.791595 -431.131111) (xy 277.740266 -431.152923) (xy 277.686309 -431.167029) (xy 277.630872 -431.173129)
			(xy 277.575138 -431.171092) (xy 277.520295 -431.160962) (xy 277.467511 -431.142955) (xy 277.417911 -431.117454)
			(xy 277.372553 -431.085003) (xy 277.332404 -431.046294) (xy 277.298318 -431.002151) (xy 277.271022 -430.953516)
			(xy 277.251099 -430.901425) (xy 277.238973 -430.846988) (xy 277.234902 -430.791366) (xy 274.082006 -430.791366)
			(xy 274.082608 -430.792194) (xy 274.180278 -430.940158) (xy 274.271211 -431.092354) (xy 274.355224 -431.248477)
			(xy 274.432149 -431.408212) (xy 274.501829 -431.571237) (xy 274.564125 -431.737225) (xy 274.618911 -431.90584)
			(xy 274.666078 -432.076743) (xy 274.705529 -432.24959) (xy 274.737186 -432.424033) (xy 274.760984 -432.599721)
			(xy 274.776877 -432.7763) (xy 274.784831 -432.953414) (xy 274.785328 -433.04206) (xy 274.784831 -433.130706)
			(xy 274.776877 -433.30782) (xy 274.760984 -433.484399) (xy 274.737186 -433.660087) (xy 274.705529 -433.83453)
			(xy 274.676018 -433.963826) (xy 277.872188 -433.963826) (xy 277.876259 -433.908204) (xy 277.888385 -433.853767)
			(xy 277.908308 -433.801676) (xy 277.935604 -433.753041) (xy 277.96969 -433.708898) (xy 278.009839 -433.670189)
			(xy 278.055197 -433.637738) (xy 278.104797 -433.612237) (xy 278.157581 -433.59423) (xy 278.212424 -433.5841)
			(xy 278.268158 -433.582063) (xy 278.323595 -433.588163) (xy 278.377552 -433.602269) (xy 278.428881 -433.624081)
			(xy 278.476487 -433.653135) (xy 278.519355 -433.68881) (xy 278.556572 -433.730347) (xy 278.587345 -433.77686)
			(xy 278.611017 -433.827357) (xy 278.627085 -433.880764) (xy 278.635205 -433.93594) (xy 278.635714 -433.963826)
			(xy 278.635205 -433.991712) (xy 278.627085 -434.046888) (xy 278.611017 -434.100295) (xy 278.587345 -434.150792)
			(xy 278.556572 -434.197305) (xy 278.519355 -434.238842) (xy 278.476487 -434.274517) (xy 278.428881 -434.303571)
			(xy 278.377552 -434.325383) (xy 278.323595 -434.339489) (xy 278.268158 -434.345589) (xy 278.212424 -434.343552)
			(xy 278.157581 -434.333422) (xy 278.104797 -434.315415) (xy 278.055197 -434.289914) (xy 278.009839 -434.257463)
			(xy 277.96969 -434.218754) (xy 277.935604 -434.174611) (xy 277.908308 -434.125976) (xy 277.888385 -434.073885)
			(xy 277.876259 -434.019448) (xy 277.872188 -433.963826) (xy 274.676018 -433.963826) (xy 274.666078 -434.007377)
			(xy 274.618911 -434.17828) (xy 274.564125 -434.346895) (xy 274.501829 -434.512883) (xy 274.440668 -434.655976)
			(xy 282.434284 -434.655976) (xy 282.434786 -434.624015) (xy 282.442797 -434.560597) (xy 282.458694 -434.498683)
			(xy 282.482226 -434.43925) (xy 282.51302 -434.383235) (xy 282.550593 -434.33152) (xy 282.59435 -434.284923)
			(xy 282.643603 -434.244178) (xy 282.697574 -434.209927) (xy 282.755413 -434.18271) (xy 282.816206 -434.162957)
			(xy 282.878996 -434.150979) (xy 282.942792 -434.146966) (xy 283.006588 -434.150979) (xy 283.069378 -434.162957)
			(xy 283.130171 -434.18271) (xy 283.18801 -434.209927) (xy 283.241981 -434.244178) (xy 283.291234 -434.284923)
			(xy 283.334991 -434.33152) (xy 283.372564 -434.383235) (xy 283.403358 -434.43925) (xy 283.42689 -434.498683)
			(xy 283.442787 -434.560597) (xy 283.450798 -434.624015) (xy 283.4513 -434.655976) (xy 283.450818 -434.688126)
			(xy 283.442721 -434.751915) (xy 283.42664 -434.814173) (xy 283.402834 -434.873904) (xy 283.371681 -434.930154)
			(xy 283.33368 -434.982025) (xy 283.289439 -435.028686) (xy 283.264864 -435.049422) (xy 283.257244 -435.055772)
			(xy 283.247846 -435.07279) (xy 283.236924 -435.162452) (xy 283.242004 -435.180994) (xy 283.2481 -435.189122)
			(xy 283.266003 -435.21406) (xy 283.294466 -435.268448) (xy 283.31386 -435.326689) (xy 283.323685 -435.387283)
			(xy 283.3243 -435.417976) (xy 283.323814 -435.445227) (xy 283.316058 -435.499175) (xy 283.300703 -435.55147)
			(xy 283.278061 -435.601047) (xy 283.248595 -435.646897) (xy 283.212904 -435.688088) (xy 283.171713 -435.723779)
			(xy 283.125863 -435.753245) (xy 283.076286 -435.775887) (xy 283.023991 -435.791242) (xy 282.970043 -435.798998)
			(xy 282.915541 -435.798998) (xy 282.861593 -435.791242) (xy 282.809298 -435.775887) (xy 282.759721 -435.753245)
			(xy 282.713871 -435.723779) (xy 282.67268 -435.688088) (xy 282.636989 -435.646897) (xy 282.607523 -435.601047)
			(xy 282.584881 -435.55147) (xy 282.569526 -435.499175) (xy 282.56177 -435.445227) (xy 282.561284 -435.417976)
			(xy 282.561895 -435.387283) (xy 282.57172 -435.326688) (xy 282.591114 -435.268446) (xy 282.619576 -435.214057)
			(xy 282.637484 -435.189122) (xy 282.64358 -435.180994) (xy 282.64866 -435.162452) (xy 282.637738 -435.07279)
			(xy 282.62834 -435.055772) (xy 282.62072 -435.049422) (xy 282.596158 -435.028674) (xy 282.551932 -434.982004)
			(xy 282.513943 -434.930131) (xy 282.482795 -434.873883) (xy 282.458986 -434.814157) (xy 282.442896 -434.751906)
			(xy 282.434781 -434.688124) (xy 282.434284 -434.655976) (xy 274.440668 -434.655976) (xy 274.432149 -434.675908)
			(xy 274.355224 -434.835643) (xy 274.271211 -434.991766) (xy 274.180278 -435.143962) (xy 274.082608 -435.291926)
			(xy 273.978398 -435.435358) (xy 273.867858 -435.573971) (xy 273.751211 -435.707485) (xy 273.628691 -435.835631)
			(xy 273.500545 -435.958151) (xy 273.367031 -436.074798) (xy 273.228418 -436.185338) (xy 273.084986 -436.289548)
			(xy 273.037243 -436.321063) (xy 276.104713 -436.321063) (xy 276.109924 -436.258198) (xy 276.122871 -436.19646)
			(xy 276.143356 -436.136798) (xy 276.171062 -436.080128) (xy 276.205566 -436.027321) (xy 276.246337 -435.979187)
			(xy 276.292748 -435.936465) (xy 276.344088 -435.899812) (xy 276.399566 -435.869792) (xy 276.458333 -435.846864)
			(xy 276.519483 -435.831381) (xy 276.58208 -435.82358) (xy 276.61362 -435.823106) (xy 276.643941 -435.823541)
			(xy 276.704153 -435.830737) (xy 276.763084 -435.845037) (xy 276.819899 -435.866237) (xy 276.847046 -435.879748)
			(xy 276.860035 -435.885953) (xy 276.88826 -435.891548) (xy 276.916925 -435.889045) (xy 276.943753 -435.878643)
			(xy 276.966614 -435.861169) (xy 276.983691 -435.838011) (xy 276.993629 -435.811007) (xy 276.995128 -435.79669)
			(xy 276.997674 -435.768169) (xy 277.010192 -435.712296) (xy 277.030921 -435.658921) (xy 277.059397 -435.609245)
			(xy 277.094978 -435.564384) (xy 277.136866 -435.525346) (xy 277.184119 -435.493009) (xy 277.235675 -435.468098)
			(xy 277.290375 -435.451174) (xy 277.346991 -435.442618) (xy 277.37562 -435.442106) (xy 277.402871 -435.442565)
			(xy 277.456819 -435.450324) (xy 277.509113 -435.465682) (xy 277.55869 -435.488325) (xy 277.604539 -435.517793)
			(xy 277.645729 -435.553486) (xy 277.681419 -435.594677) (xy 277.710885 -435.640528) (xy 277.733525 -435.690106)
			(xy 277.74888 -435.742401) (xy 277.756636 -435.796349) (xy 277.756636 -435.850851) (xy 277.74888 -435.904799)
			(xy 277.733525 -435.957094) (xy 277.710885 -436.006672) (xy 277.681419 -436.052523) (xy 277.645729 -436.093714)
			(xy 277.604539 -436.129407) (xy 277.55869 -436.158875) (xy 277.509113 -436.181518) (xy 277.456819 -436.196876)
			(xy 277.402871 -436.204635) (xy 277.37562 -436.205122) (xy 277.344647 -436.204558) (xy 277.283508 -436.194598)
			(xy 277.253954 -436.18531) (xy 277.240167 -436.181197) (xy 277.211436 -436.179973) (xy 277.183505 -436.186814)
			(xy 277.158592 -436.201178) (xy 277.138677 -436.221923) (xy 277.125342 -436.247401) (xy 277.119646 -436.275588)
			(xy 277.12035 -436.289958) (xy 277.122128 -436.331614) (xy 277.121617 -436.363154) (xy 277.113813 -436.42575)
			(xy 277.098326 -436.4869) (xy 277.075394 -436.545664) (xy 277.04537 -436.601141) (xy 277.029252 -436.623714)
			(xy 282.066236 -436.623714) (xy 282.070307 -436.568092) (xy 282.082433 -436.513655) (xy 282.102356 -436.461564)
			(xy 282.129652 -436.412929) (xy 282.163738 -436.368786) (xy 282.203887 -436.330077) (xy 282.249245 -436.297626)
			(xy 282.298845 -436.272125) (xy 282.351629 -436.254118) (xy 282.406472 -436.243988) (xy 282.462206 -436.241951)
			(xy 282.517643 -436.248051) (xy 282.5716 -436.262157) (xy 282.622929 -436.283969) (xy 282.670535 -436.313023)
			(xy 282.713403 -436.348698) (xy 282.75062 -436.390235) (xy 282.781393 -436.436748) (xy 282.805065 -436.487245)
			(xy 282.821133 -436.540652) (xy 282.829253 -436.595828) (xy 282.829762 -436.623714) (xy 282.829253 -436.6516)
			(xy 282.821133 -436.706776) (xy 282.805065 -436.760183) (xy 282.781393 -436.81068) (xy 282.75062 -436.857193)
			(xy 282.713403 -436.89873) (xy 282.670535 -436.934405) (xy 282.622929 -436.963459) (xy 282.5716 -436.985271)
			(xy 282.517643 -436.999377) (xy 282.462206 -437.005477) (xy 282.406472 -437.00344) (xy 282.351629 -436.99331)
			(xy 282.298845 -436.975303) (xy 282.249245 -436.949802) (xy 282.203887 -436.917351) (xy 282.163738 -436.878642)
			(xy 282.129652 -436.834499) (xy 282.102356 -436.785864) (xy 282.082433 -436.733773) (xy 282.070307 -436.679336)
			(xy 282.066236 -436.623714) (xy 277.029252 -436.623714) (xy 277.008713 -436.652478) (xy 276.965989 -436.698887)
			(xy 276.917852 -436.739654) (xy 276.865042 -436.774154) (xy 276.80837 -436.801857) (xy 276.748707 -436.822338)
			(xy 276.686969 -436.835281) (xy 276.624103 -436.840488) (xy 276.561077 -436.837879) (xy 276.498857 -436.827495)
			(xy 276.4384 -436.809494) (xy 276.380633 -436.784153) (xy 276.326444 -436.751861) (xy 276.276666 -436.713114)
			(xy 276.232063 -436.668508) (xy 276.19332 -436.618727) (xy 276.161032 -436.564537) (xy 276.135695 -436.506769)
			(xy 276.117698 -436.44631) (xy 276.107317 -436.384089) (xy 276.104713 -436.321063) (xy 273.037243 -436.321063)
			(xy 272.937022 -436.387218) (xy 272.784826 -436.478151) (xy 272.628703 -436.562164) (xy 272.468968 -436.639089)
			(xy 272.305943 -436.708769) (xy 272.139955 -436.771065) (xy 271.97134 -436.825851) (xy 271.800437 -436.873018)
			(xy 271.62759 -436.912469) (xy 271.453147 -436.944126) (xy 271.277459 -436.967924) (xy 271.10088 -436.983817)
			(xy 270.923766 -436.991771) (xy 270.746474 -436.991771) (xy 270.56936 -436.983817) (xy 270.392781 -436.967924)
			(xy 270.217093 -436.944126) (xy 270.04265 -436.912469) (xy 269.869803 -436.873018) (xy 269.6989 -436.825851)
			(xy 269.530285 -436.771065) (xy 269.364297 -436.708769) (xy 269.201272 -436.639089) (xy 269.041537 -436.562164)
			(xy 268.885414 -436.478151) (xy 268.733218 -436.387218) (xy 268.585254 -436.289548) (xy 268.441822 -436.185338)
			(xy 268.303209 -436.074798) (xy 268.169695 -435.958151) (xy 268.041549 -435.835631) (xy 267.919029 -435.707485)
			(xy 267.802382 -435.573971) (xy 267.691842 -435.435358) (xy 267.587632 -435.291926) (xy 267.489962 -435.143962)
			(xy 267.399029 -434.991766) (xy 267.315016 -434.835643) (xy 267.238091 -434.675908) (xy 267.168411 -434.512883)
			(xy 267.106115 -434.346895) (xy 267.051329 -434.17828) (xy 267.004162 -434.007377) (xy 266.964711 -433.83453)
			(xy 266.933054 -433.660087) (xy 266.909256 -433.484399) (xy 266.893363 -433.30782) (xy 266.885409 -433.130706)
			(xy 265.530076 -433.130706) (xy 265.530076 -436.22468) (xy 265.529638 -436.234743) (xy 265.5219 -436.253324)
			(xy 265.51509 -436.260748) (xy 264.691368 -437.08447) (xy 264.683969 -437.091315) (xy 264.665371 -437.099042)
			(xy 264.6553 -437.099456) (xy 229.231698 -437.099456) (xy 229.212902 -437.107076) (xy 229.206044 -437.114188)
			(xy 207.181958 -437.114188) (xy 207.163162 -437.106314) (xy 207.156304 -437.099456) (xy 199.533002 -437.099456)
			(xy 199.522933 -437.099032) (xy 199.504332 -437.091313) (xy 199.496934 -437.08447) (xy 198.613268 -436.200804)
			(xy 198.61022 -436.198518) (xy 198.536696 -436.142527) (xy 198.394359 -436.024618) (xy 198.257693 -435.900181)
			(xy 198.126996 -435.769488) (xy 198.002555 -435.632826) (xy 197.884643 -435.490492) (xy 197.828662 -435.41696)
			(xy 197.826376 -435.413912) (xy 195.322698 -432.910234) (xy 195.315862 -432.902832) (xy 195.308152 -432.884234)
			(xy 195.307712 -432.874166) (xy 195.307712 -430.97958) (xy 195.307262 -430.969553) (xy 195.299672 -430.950994)
			(xy 195.29298 -430.943512) (xy 195.27139 -430.922176) (xy 195.264429 -430.915708) (xy 195.247075 -430.907996)
			(xy 195.237608 -430.90719) (xy 195.205227 -430.905366) (xy 195.141284 -430.894519) (xy 195.079239 -430.875628)
			(xy 195.020101 -430.848999) (xy 194.96483 -430.815066) (xy 194.914323 -430.774379) (xy 194.869401 -430.727599)
			(xy 194.830793 -430.675485) (xy 194.799126 -430.618885) (xy 194.774915 -430.558717) (xy 194.758552 -430.495958)
			(xy 194.750303 -430.431628) (xy 194.750304 -430.366771) (xy 194.758552 -430.302441) (xy 194.774915 -430.239683)
			(xy 194.799126 -430.179514) (xy 194.830793 -430.122914) (xy 194.869401 -430.070801) (xy 194.914324 -430.024021)
			(xy 194.964831 -429.983334) (xy 195.020102 -429.9494) (xy 195.07924 -429.922772) (xy 195.141285 -429.903881)
			(xy 195.205228 -429.893034) (xy 195.237608 -429.89119) (xy 195.247078 -429.890383) (xy 195.264441 -429.882687)
			(xy 195.27139 -429.876204) (xy 195.29298 -429.854868) (xy 195.299755 -429.847443) (xy 195.30734 -429.828846)
			(xy 195.307712 -429.8188) (xy 195.307712 -429.30318) (xy 195.307203 -429.293002) (xy 195.299206 -429.274276)
			(xy 195.292218 -429.266858) (xy 195.232528 -429.208692) (xy 195.213986 -429.201326) (xy 195.203318 -429.20158)
			(xy 195.189602 -429.201834) (xy 195.157638 -429.201353) (xy 195.094214 -429.193341) (xy 195.032294 -429.177443)
			(xy 194.972855 -429.15391) (xy 194.916834 -429.123112) (xy 194.865115 -429.085536) (xy 194.818514 -429.041775)
			(xy 194.777764 -428.992517) (xy 194.74351 -428.938541) (xy 194.71629 -428.880697) (xy 194.696536 -428.819898)
			(xy 194.684557 -428.757102) (xy 194.680542 -428.6933) (xy 194.684557 -428.629498) (xy 194.696536 -428.566702)
			(xy 194.71629 -428.505903) (xy 194.74351 -428.448059) (xy 194.777764 -428.394083) (xy 194.818514 -428.344825)
			(xy 194.865115 -428.301064) (xy 194.916834 -428.263488) (xy 194.972855 -428.23269) (xy 195.032294 -428.209157)
			(xy 195.094214 -428.193259) (xy 195.157638 -428.185247) (xy 195.189602 -428.184818) (xy 195.203318 -428.185072)
			(xy 195.213986 -428.185326) (xy 195.232528 -428.17796) (xy 195.292218 -428.119794) (xy 195.299242 -428.112398)
			(xy 195.307253 -428.09366) (xy 195.307712 -428.083472) (xy 195.307712 -426.240194) (xy 195.307333 -426.230767)
			(xy 195.300508 -426.213192) (xy 195.287785 -426.199277) (xy 195.279518 -426.194728) (xy 195.18503 -426.147738)
			(xy 195.156582 -426.150278) (xy 195.144898 -426.159168) (xy 195.119894 -426.177328) (xy 195.065243 -426.206169)
			(xy 195.006658 -426.225825) (xy 194.945671 -426.235781) (xy 194.914774 -426.236384) (xy 194.887526 -426.235896)
			(xy 194.833584 -426.228137) (xy 194.781296 -426.212781) (xy 194.731725 -426.190139) (xy 194.685881 -426.160674)
			(xy 194.644697 -426.124985) (xy 194.60901 -426.083798) (xy 194.579548 -426.037952) (xy 194.55691 -425.98838)
			(xy 194.541557 -425.93609) (xy 194.533802 -425.882148) (xy 194.533802 -425.827652) (xy 194.541557 -425.77371)
			(xy 194.55691 -425.72142) (xy 194.579548 -425.671848) (xy 194.60901 -425.626002) (xy 194.644697 -425.584815)
			(xy 194.685881 -425.549126) (xy 194.731725 -425.519661) (xy 194.781296 -425.497019) (xy 194.833584 -425.481663)
			(xy 194.887526 -425.473904) (xy 194.914774 -425.473368) (xy 194.945672 -425.473963) (xy 195.006661 -425.483918)
			(xy 195.065248 -425.503572) (xy 195.119903 -425.532411) (xy 195.144898 -425.550584) (xy 195.156582 -425.559474)
			(xy 195.18503 -425.562014) (xy 195.279518 -425.515024) (xy 195.287761 -425.510446) (xy 195.300466 -425.496536)
			(xy 195.30729 -425.478977) (xy 195.307712 -425.469558) (xy 195.307712 -412.953454) (xy 195.307281 -412.943387)
			(xy 195.299556 -412.924794) (xy 195.292726 -412.917386) (xy 194.732148 -412.356808) (xy 194.724747 -412.349969)
			(xy 194.706149 -412.342252) (xy 194.69608 -412.341822) (xy 193.183764 -412.341822) (xy 193.164714 -412.333694)
			(xy 193.15811 -412.326836) (xy 187.805568 -412.326836) (xy 187.787026 -412.319216) (xy 187.779914 -412.312104)
			(xy 187.64631 -412.376874) (xy 187.630816 -412.405068) (xy 187.632594 -412.421324) (xy 187.634229 -412.436002)
			(xy 187.636009 -412.465484) (xy 187.63615 -412.480252) (xy 187.635677 -412.511797) (xy 187.627879 -412.574403)
			(xy 187.612397 -412.635563) (xy 187.589468 -412.694339) (xy 187.559445 -412.749827) (xy 187.522788 -412.801175)
			(xy 187.480062 -412.847594) (xy 187.431922 -412.888372) (xy 187.379107 -412.922882) (xy 187.32243 -412.950593)
			(xy 187.262759 -412.971081) (xy 187.201013 -412.984031) (xy 187.138139 -412.989243) (xy 187.075103 -412.986638)
			(xy 187.012874 -412.976256) (xy 186.952406 -412.958256) (xy 186.89463 -412.932914) (xy 186.840432 -412.90062)
			(xy 186.790645 -412.86187) (xy 186.746034 -412.817259) (xy 186.707283 -412.767473) (xy 186.674989 -412.713275)
			(xy 186.649646 -412.655499) (xy 186.631645 -412.595032) (xy 186.621262 -412.532803) (xy 186.618656 -412.469767)
			(xy 186.623868 -412.406893) (xy 186.636817 -412.345147) (xy 186.657304 -412.285476) (xy 186.685015 -412.228798)
			(xy 186.719525 -412.175983) (xy 186.760302 -412.127842) (xy 186.806721 -412.085115) (xy 186.858068 -412.048459)
			(xy 186.913556 -412.018435) (xy 186.972331 -411.995505) (xy 187.033491 -411.980022) (xy 187.096097 -411.972223)
			(xy 187.127642 -411.971744) (xy 187.14241 -411.971879) (xy 187.171893 -411.97366) (xy 187.18657 -411.9753)
			(xy 187.202826 -411.977078) (xy 187.23102 -411.961584) (xy 187.280042 -411.860492) (xy 187.284144 -411.850782)
			(xy 187.284922 -411.829739) (xy 187.277206 -411.810147) (xy 187.270136 -411.802326) (xy 184.243472 -408.775662)
			(xy 184.234624 -408.767754) (xy 184.21211 -408.760351) (xy 184.200292 -408.761438) (xy 184.107582 -408.775154)
			(xy 184.08777 -408.789124) (xy 184.082182 -408.799792) (xy 184.067088 -408.826646) (xy 184.029666 -408.875573)
			(xy 183.984891 -408.917875) (xy 183.959754 -408.935682) (xy 183.951372 -408.94127) (xy 183.94045 -408.95778)
			(xy 183.922416 -409.046934) (xy 183.925972 -409.066238) (xy 183.931306 -409.07462) (xy 183.945687 -409.097817)
			(xy 183.968389 -409.14745) (xy 183.983786 -409.199811) (xy 183.991562 -409.253833) (xy 183.992012 -409.281122)
			(xy 183.991525 -409.308372) (xy 183.983766 -409.362318) (xy 183.968409 -409.41461) (xy 183.945766 -409.464185)
			(xy 183.9163 -409.510033) (xy 183.880608 -409.551221) (xy 183.839418 -409.58691) (xy 183.793569 -409.616375)
			(xy 183.743993 -409.639015) (xy 183.6917 -409.65437) (xy 183.637754 -409.662126) (xy 183.610504 -409.66263)
			(xy 183.581917 -409.662121) (xy 183.525381 -409.653592) (xy 183.470751 -409.636725) (xy 183.419248 -409.611897)
			(xy 183.372026 -409.579664) (xy 183.33014 -409.540747) (xy 183.294528 -409.496017) (xy 183.265988 -409.446475)
			(xy 183.245158 -409.393229) (xy 183.238394 -409.36545) (xy 183.235854 -409.354274) (xy 183.222392 -409.336748)
			(xy 183.133238 -409.29052) (xy 183.11114 -409.289504) (xy 183.100726 -409.293822) (xy 183.069872 -409.305953)
			(xy 183.00581 -409.323024) (xy 182.940073 -409.331628) (xy 182.906924 -409.332176) (xy 182.878873 -409.331774)
			(xy 182.823119 -409.325534) (xy 182.795672 -409.31973) (xy 182.782972 -409.316936) (xy 182.75808 -409.324048)
			(xy 182.678832 -409.40228) (xy 182.671212 -409.426918) (xy 182.674006 -409.439618) (xy 182.67901 -409.465297)
			(xy 182.684356 -409.517344) (xy 182.684674 -409.543504) (xy 182.684172 -409.575465) (xy 182.676161 -409.638883)
			(xy 182.660264 -409.700797) (xy 182.636732 -409.76023) (xy 182.605938 -409.816245) (xy 182.568365 -409.86796)
			(xy 182.524608 -409.914557) (xy 182.475355 -409.955302) (xy 182.421384 -409.989553) (xy 182.363545 -410.01677)
			(xy 182.302752 -410.036523) (xy 182.239962 -410.048501) (xy 182.176166 -410.052515) (xy 182.11237 -410.048501)
			(xy 182.04958 -410.036523) (xy 181.988787 -410.01677) (xy 181.930948 -409.989553) (xy 181.876977 -409.955302)
			(xy 181.827724 -409.914557) (xy 181.783967 -409.86796) (xy 181.746394 -409.816245) (xy 181.7156 -409.76023)
			(xy 181.692068 -409.700797) (xy 181.676171 -409.638883) (xy 181.66816 -409.575465) (xy 181.667658 -409.543504)
			(xy 181.667658 -409.527756) (xy 181.654704 -409.504642) (xy 181.557676 -409.44546) (xy 181.531006 -409.444444)
			(xy 181.519068 -409.450794) (xy 181.4918 -409.464469) (xy 181.434699 -409.485942) (xy 181.375441 -409.500429)
			(xy 181.314874 -409.507724) (xy 181.284372 -409.508198) (xy 181.252832 -409.507721) (xy 181.190237 -409.499915)
			(xy 181.129088 -409.484427) (xy 181.070325 -409.461494) (xy 181.014849 -409.431468) (xy 180.963513 -409.394812)
			(xy 180.917106 -409.352087) (xy 180.876339 -409.30395) (xy 180.84184 -409.25114) (xy 180.814138 -409.194469)
			(xy 180.793658 -409.134806) (xy 180.780715 -409.073069) (xy 180.775508 -409.010204) (xy 180.778117 -408.947178)
			(xy 180.788501 -408.884959) (xy 180.806501 -408.824502) (xy 180.831842 -408.766736) (xy 180.864132 -408.712547)
			(xy 180.902878 -408.662769) (xy 180.947483 -408.618166) (xy 180.997262 -408.579422) (xy 181.051452 -408.547133)
			(xy 181.109219 -408.521795) (xy 181.169676 -408.503797) (xy 181.231896 -408.493415) (xy 181.294922 -408.490808)
			(xy 181.357786 -408.496018) (xy 181.419524 -408.508963) (xy 181.479186 -408.529445) (xy 181.535856 -408.557149)
			(xy 181.588664 -408.59165) (xy 181.6368 -408.632418) (xy 181.679523 -408.678827) (xy 181.716178 -408.730164)
			(xy 181.746201 -408.785641) (xy 181.769132 -408.844405) (xy 181.784618 -408.905555) (xy 181.792422 -408.96815)
			(xy 181.79288 -408.99969) (xy 181.79288 -409.015438) (xy 181.805834 -409.038552) (xy 181.902862 -409.097734)
			(xy 181.929532 -409.09875) (xy 181.94147 -409.0924) (xy 181.968738 -409.078721) (xy 182.025837 -409.057242)
			(xy 182.085096 -409.042748) (xy 182.145663 -409.035446) (xy 182.176166 -409.034996) (xy 182.204217 -409.035397)
			(xy 182.259972 -409.041636) (xy 182.287418 -409.047442) (xy 182.300118 -409.050236) (xy 182.32501 -409.043124)
			(xy 182.404258 -408.964892) (xy 182.411878 -408.940254) (xy 182.409084 -408.927554) (xy 182.404081 -408.901875)
			(xy 182.398738 -408.849828) (xy 182.398416 -408.823668) (xy 182.398882 -408.792939) (xy 182.406294 -408.731929)
			(xy 182.421005 -408.672257) (xy 182.442802 -408.614794) (xy 182.471367 -408.560377) (xy 182.506282 -408.509799)
			(xy 182.547039 -408.463799) (xy 182.593043 -408.423047) (xy 182.643625 -408.388138) (xy 182.698045 -408.359579)
			(xy 182.755511 -408.337789) (xy 182.815184 -408.323084) (xy 182.876195 -408.315679) (xy 182.906924 -408.31516)
			(xy 182.939041 -408.315634) (xy 183.002767 -408.323691) (xy 183.06497 -408.339712) (xy 183.124659 -408.363442)
			(xy 183.180883 -408.394502) (xy 183.232747 -408.432397) (xy 183.256428 -408.454098) (xy 183.26481 -408.462226)
			(xy 183.287162 -408.469338) (xy 183.38927 -408.454098) (xy 183.408574 -408.44089) (xy 183.414416 -408.43073)
			(xy 183.428061 -408.407697) (xy 183.460817 -408.365352) (xy 183.499184 -408.328015) (xy 183.542404 -408.296424)
			(xy 183.5658 -408.28341) (xy 183.576468 -408.277822) (xy 183.590438 -408.25801) (xy 183.604154 -408.1653)
			(xy 183.605266 -408.15348) (xy 183.597856 -408.130957) (xy 183.58993 -408.12212) (xy 183.432704 -407.964894)
			(xy 183.425305 -407.958048) (xy 183.406708 -407.950313) (xy 183.396636 -407.949908) (xy 179.29479 -407.949908)
			(xy 179.284721 -407.950333) (xy 179.26612 -407.958051) (xy 179.258722 -407.964894) (xy 178.562508 -408.661108)
			(xy 178.555142 -408.67584) (xy 178.553872 -408.683968) (xy 178.547153 -408.727485) (xy 178.543207 -408.743615)
			(xy 179.583074 -408.743615) (xy 179.583074 -408.679693) (xy 179.591085 -408.616275) (xy 179.606982 -408.554361)
			(xy 179.630514 -408.494928) (xy 179.661308 -408.438913) (xy 179.698881 -408.387198) (xy 179.742638 -408.340601)
			(xy 179.791891 -408.299856) (xy 179.845862 -408.265605) (xy 179.903701 -408.238388) (xy 179.964494 -408.218635)
			(xy 180.027284 -408.206657) (xy 180.09108 -408.202644) (xy 180.154876 -408.206657) (xy 180.217666 -408.218635)
			(xy 180.278459 -408.238388) (xy 180.336298 -408.265605) (xy 180.390269 -408.299856) (xy 180.439522 -408.340601)
			(xy 180.483279 -408.387198) (xy 180.520852 -408.438913) (xy 180.551646 -408.494928) (xy 180.575178 -408.554361)
			(xy 180.591075 -408.616275) (xy 180.599086 -408.679693) (xy 180.599588 -408.711654) (xy 180.599086 -408.743615)
			(xy 180.591075 -408.807033) (xy 180.575178 -408.868947) (xy 180.551646 -408.92838) (xy 180.520852 -408.984395)
			(xy 180.483279 -409.03611) (xy 180.439522 -409.082707) (xy 180.390269 -409.123452) (xy 180.336298 -409.157703)
			(xy 180.278459 -409.18492) (xy 180.217666 -409.204673) (xy 180.154876 -409.216651) (xy 180.09108 -409.220665)
			(xy 180.027284 -409.216651) (xy 179.964494 -409.204673) (xy 179.903701 -409.18492) (xy 179.845862 -409.157703)
			(xy 179.791891 -409.123452) (xy 179.742638 -409.082707) (xy 179.698881 -409.03611) (xy 179.661308 -408.984395)
			(xy 179.630514 -408.92838) (xy 179.606982 -408.868947) (xy 179.591085 -408.807033) (xy 179.583074 -408.743615)
			(xy 178.543207 -408.743615) (xy 178.526225 -408.813022) (xy 178.496956 -408.896075) (xy 178.45963 -408.975832)
			(xy 178.414612 -409.051515) (xy 178.362342 -409.122384) (xy 178.303331 -409.187746) (xy 178.238156 -409.246962)
			(xy 178.167452 -409.299455) (xy 178.129946 -409.322524) (xy 178.12267 -409.32734) (xy 178.111629 -409.340835)
			(xy 178.105729 -409.357242) (xy 178.105308 -409.365958) (xy 178.105308 -410.377386) (xy 178.105433 -410.383175)
			(xy 178.107996 -410.394465) (xy 178.110388 -410.399738) (xy 178.12274 -410.42591) (xy 178.142117 -410.480444)
			(xy 178.155189 -410.536823) (xy 178.161787 -410.594321) (xy 178.162204 -410.623258) (xy 178.161802 -410.652197)
			(xy 178.155233 -410.709702) (xy 178.142165 -410.766086) (xy 178.122767 -410.820617) (xy 178.110388 -410.846778)
			(xy 178.108014 -410.852057) (xy 178.105451 -410.863343) (xy 178.105308 -410.86913) (xy 178.105308 -410.979323)
			(xy 179.644034 -410.979323) (xy 179.644034 -410.915401) (xy 179.652045 -410.851983) (xy 179.667942 -410.790069)
			(xy 179.691474 -410.730636) (xy 179.722268 -410.674621) (xy 179.759841 -410.622906) (xy 179.803598 -410.576309)
			(xy 179.852851 -410.535564) (xy 179.906822 -410.501313) (xy 179.964661 -410.474096) (xy 180.025454 -410.454343)
			(xy 180.088244 -410.442365) (xy 180.15204 -410.438352) (xy 180.215836 -410.442365) (xy 180.278626 -410.454343)
			(xy 180.339419 -410.474096) (xy 180.397258 -410.501313) (xy 180.451229 -410.535564) (xy 180.500482 -410.576309)
			(xy 180.544239 -410.622906) (xy 180.581812 -410.674621) (xy 180.612606 -410.730636) (xy 180.636138 -410.790069)
			(xy 180.652035 -410.851983) (xy 180.660046 -410.915401) (xy 180.660548 -410.947362) (xy 180.660046 -410.979323)
			(xy 180.652035 -411.042741) (xy 180.636138 -411.104655) (xy 180.612606 -411.164088) (xy 180.581812 -411.220103)
			(xy 180.544239 -411.271818) (xy 180.500482 -411.318415) (xy 180.451229 -411.35916) (xy 180.397258 -411.393411)
			(xy 180.339419 -411.420628) (xy 180.278626 -411.440381) (xy 180.215836 -411.452359) (xy 180.15204 -411.456373)
			(xy 180.088244 -411.452359) (xy 180.025454 -411.440381) (xy 179.964661 -411.420628) (xy 179.906822 -411.393411)
			(xy 179.852851 -411.35916) (xy 179.803598 -411.318415) (xy 179.759841 -411.271818) (xy 179.722268 -411.220103)
			(xy 179.691474 -411.164088) (xy 179.667942 -411.104655) (xy 179.652045 -411.042741) (xy 179.644034 -410.979323)
			(xy 178.105308 -410.979323) (xy 178.105308 -411.976824) (xy 178.104881 -411.986892) (xy 178.097161 -412.005491)
			(xy 178.090322 -412.012892) (xy 177.901314 -412.2019) (xy 181.289957 -412.2019) (xy 181.293971 -412.138102)
			(xy 181.305949 -412.07531) (xy 181.325702 -412.014514) (xy 181.352919 -411.956674) (xy 181.38717 -411.9027)
			(xy 181.427916 -411.853445) (xy 181.474514 -411.809685) (xy 181.526228 -411.772109) (xy 181.582245 -411.741312)
			(xy 181.641679 -411.717778) (xy 181.703594 -411.701878) (xy 181.767014 -411.693863) (xy 181.798976 -411.69336)
			(xy 181.830771 -411.693885) (xy 181.893866 -411.701811) (xy 181.955481 -411.717542) (xy 182.014653 -411.740833)
			(xy 182.070459 -411.77132) (xy 182.122028 -411.808528) (xy 182.168556 -411.851875) (xy 182.209315 -411.900685)
			(xy 182.243671 -411.954197) (xy 182.271086 -412.011575) (xy 182.281576 -412.041594) (xy 182.28592 -412.05258)
			(xy 182.302576 -412.069291) (xy 182.324922 -412.076861) (xy 182.336694 -412.075884) (xy 182.35363 -412.073742)
			(xy 182.387695 -412.071454) (xy 182.404766 -412.071312) (xy 182.436731 -412.071751) (xy 182.500157 -412.07976)
			(xy 182.56208 -412.095655) (xy 182.621521 -412.119186) (xy 182.667891 -412.144675) (xy 183.1058 -412.144675)
			(xy 183.1058 -412.080753) (xy 183.113811 -412.017335) (xy 183.129708 -411.955421) (xy 183.15324 -411.895988)
			(xy 183.184034 -411.839973) (xy 183.221607 -411.788258) (xy 183.265364 -411.741661) (xy 183.314617 -411.700916)
			(xy 183.368588 -411.666665) (xy 183.426427 -411.639448) (xy 183.48722 -411.619695) (xy 183.55001 -411.607717)
			(xy 183.613806 -411.603704) (xy 183.677602 -411.607717) (xy 183.740392 -411.619695) (xy 183.801185 -411.639448)
			(xy 183.859024 -411.666665) (xy 183.912995 -411.700916) (xy 183.962248 -411.741661) (xy 184.006005 -411.788258)
			(xy 184.043578 -411.839973) (xy 184.074372 -411.895988) (xy 184.097904 -411.955421) (xy 184.113801 -412.017335)
			(xy 184.121812 -412.080753) (xy 184.122314 -412.112714) (xy 184.121812 -412.144675) (xy 184.113801 -412.208093)
			(xy 184.097904 -412.270007) (xy 184.074372 -412.32944) (xy 184.043578 -412.385455) (xy 184.018988 -412.4193)
			(xy 184.230281 -412.4193) (xy 184.234295 -412.355505) (xy 184.246272 -412.292715) (xy 184.266025 -412.231922)
			(xy 184.293241 -412.174084) (xy 184.327491 -412.120113) (xy 184.368235 -412.07086) (xy 184.414831 -412.027102)
			(xy 184.466543 -411.989528) (xy 184.522557 -411.958732) (xy 184.581989 -411.9352) (xy 184.643902 -411.919301)
			(xy 184.707319 -411.911287) (xy 184.73928 -411.910784) (xy 184.770853 -411.911235) (xy 184.833512 -411.919052)
			(xy 184.894721 -411.934568) (xy 184.953538 -411.957544) (xy 185.009056 -411.987627) (xy 185.060423 -412.024353)
			(xy 185.083958 -412.045404) (xy 185.091324 -412.052008) (xy 185.109358 -412.058866) (xy 185.199782 -412.057088)
			(xy 185.217562 -412.049468) (xy 185.224674 -412.042356) (xy 185.248596 -412.019172) (xy 185.301427 -411.978594)
			(xy 185.359106 -411.945263) (xy 185.420643 -411.91975) (xy 185.484985 -411.902492) (xy 185.55103 -411.893784)
			(xy 185.584338 -411.893258) (xy 185.616295 -411.89383) (xy 185.679706 -411.901845) (xy 185.741611 -411.917744)
			(xy 185.801036 -411.941276) (xy 185.857044 -411.97207) (xy 185.90875 -412.00964) (xy 185.95534 -412.053395)
			(xy 185.99608 -412.102643) (xy 186.030325 -412.156609) (xy 186.057538 -412.214442) (xy 186.077288 -412.275229)
			(xy 186.089263 -412.338011) (xy 186.093277 -412.4018) (xy 186.089263 -412.465589) (xy 186.077288 -412.528371)
			(xy 186.057538 -412.589158) (xy 186.030325 -412.646991) (xy 185.99608 -412.700957) (xy 185.95534 -412.750205)
			(xy 185.90875 -412.79396) (xy 185.857044 -412.83153) (xy 185.801036 -412.862324) (xy 185.741611 -412.885856)
			(xy 185.679706 -412.901755) (xy 185.616295 -412.90977) (xy 185.584338 -412.910274) (xy 185.552765 -412.909823)
			(xy 185.490106 -412.902007) (xy 185.428896 -412.886492) (xy 185.370079 -412.863516) (xy 185.314561 -412.833433)
			(xy 185.263195 -412.796706) (xy 185.23966 -412.775654) (xy 185.232294 -412.76905) (xy 185.21426 -412.762192)
			(xy 185.123836 -412.76397) (xy 185.106056 -412.77159) (xy 185.098944 -412.778702) (xy 185.075007 -412.80187)
			(xy 185.02218 -412.842451) (xy 184.964505 -412.875785) (xy 184.90297 -412.901301) (xy 184.838631 -412.918562)
			(xy 184.772587 -412.927273) (xy 184.73928 -412.9278) (xy 184.707319 -412.927313) (xy 184.643902 -412.919299)
			(xy 184.581989 -412.9034) (xy 184.522557 -412.879868) (xy 184.466543 -412.849072) (xy 184.414831 -412.811498)
			(xy 184.368235 -412.76774) (xy 184.327491 -412.718487) (xy 184.293241 -412.664516) (xy 184.266025 -412.606678)
			(xy 184.246272 -412.545885) (xy 184.234295 -412.483095) (xy 184.230281 -412.4193) (xy 184.018988 -412.4193)
			(xy 184.006005 -412.43717) (xy 183.962248 -412.483767) (xy 183.912995 -412.524512) (xy 183.859024 -412.558763)
			(xy 183.801185 -412.58598) (xy 183.740392 -412.605733) (xy 183.677602 -412.617711) (xy 183.613806 -412.621725)
			(xy 183.55001 -412.617711) (xy 183.48722 -412.605733) (xy 183.426427 -412.58598) (xy 183.368588 -412.558763)
			(xy 183.314617 -412.524512) (xy 183.265364 -412.483767) (xy 183.221607 -412.43717) (xy 183.184034 -412.385455)
			(xy 183.15324 -412.32944) (xy 183.129708 -412.270007) (xy 183.113811 -412.208093) (xy 183.1058 -412.144675)
			(xy 182.667891 -412.144675) (xy 182.677545 -412.149982) (xy 182.729267 -412.187557) (xy 182.775871 -412.231318)
			(xy 182.816623 -412.280576) (xy 182.85088 -412.334553) (xy 182.878101 -412.392398) (xy 182.897857 -412.453199)
			(xy 182.909837 -412.515996) (xy 182.913852 -412.5798) (xy 182.909837 -412.643604) (xy 182.897857 -412.706401)
			(xy 182.878101 -412.767202) (xy 182.85088 -412.825047) (xy 182.816623 -412.879024) (xy 182.775871 -412.928282)
			(xy 182.729267 -412.972043) (xy 182.677545 -413.009618) (xy 182.621521 -413.040414) (xy 182.56208 -413.063945)
			(xy 182.500157 -413.07984) (xy 182.436731 -413.087849) (xy 182.404766 -413.088328) (xy 182.372971 -413.087774)
			(xy 182.309877 -413.079853) (xy 182.248263 -413.064126) (xy 182.189091 -413.040839) (xy 182.133285 -413.010356)
			(xy 182.081715 -412.973151) (xy 182.035187 -412.929806) (xy 181.994427 -412.880998) (xy 181.960071 -412.827489)
			(xy 181.932656 -412.770112) (xy 181.922166 -412.740094) (xy 181.917879 -412.72908) (xy 181.901198 -412.712369)
			(xy 181.878828 -412.704814) (xy 181.867048 -412.705804) (xy 181.850112 -412.707951) (xy 181.816047 -412.710236)
			(xy 181.798976 -412.710376) (xy 181.767014 -412.709937) (xy 181.703594 -412.701922) (xy 181.641679 -412.686022)
			(xy 181.582245 -412.662488) (xy 181.526228 -412.631691) (xy 181.474514 -412.594115) (xy 181.427916 -412.550355)
			(xy 181.38717 -412.5011) (xy 181.352919 -412.447126) (xy 181.325702 -412.389286) (xy 181.305949 -412.32849)
			(xy 181.293971 -412.265698) (xy 181.289957 -412.2019) (xy 177.901314 -412.2019) (xy 177.121058 -412.982156)
			(xy 177.113659 -412.989) (xy 177.095061 -412.996727) (xy 177.08499 -412.997142) (xy 176.748948 -412.997142)
			(xy 176.738949 -412.997631) (xy 176.720462 -413.00526) (xy 176.70627 -413.01935) (xy 176.701958 -413.028384)
			(xy 176.696116 -413.042862) (xy 176.701958 -413.072834) (xy 176.978905 -413.349694) (xy 179.114956 -413.349694)
			(xy 179.119027 -413.294072) (xy 179.131153 -413.239635) (xy 179.151076 -413.187544) (xy 179.178372 -413.138909)
			(xy 179.212458 -413.094766) (xy 179.252607 -413.056057) (xy 179.297965 -413.023606) (xy 179.347565 -412.998105)
			(xy 179.400349 -412.980098) (xy 179.455192 -412.969968) (xy 179.510926 -412.967931) (xy 179.566363 -412.974031)
			(xy 179.62032 -412.988137) (xy 179.671649 -413.009949) (xy 179.719255 -413.039003) (xy 179.762123 -413.074678)
			(xy 179.79934 -413.116215) (xy 179.830113 -413.162728) (xy 179.853785 -413.213225) (xy 179.869853 -413.266632)
			(xy 179.87123 -413.275991) (xy 188.38265 -413.275991) (xy 188.38265 -413.212069) (xy 188.390661 -413.148651)
			(xy 188.406558 -413.086737) (xy 188.43009 -413.027304) (xy 188.460884 -412.971289) (xy 188.498457 -412.919574)
			(xy 188.542214 -412.872977) (xy 188.591467 -412.832232) (xy 188.645438 -412.797981) (xy 188.703277 -412.770764)
			(xy 188.76407 -412.751011) (xy 188.82686 -412.739033) (xy 188.890656 -412.73502) (xy 188.954452 -412.739033)
			(xy 189.017242 -412.751011) (xy 189.078035 -412.770764) (xy 189.135874 -412.797981) (xy 189.189845 -412.832232)
			(xy 189.239098 -412.872977) (xy 189.282855 -412.919574) (xy 189.320428 -412.971289) (xy 189.351222 -413.027304)
			(xy 189.370841 -413.076855) (xy 192.461636 -413.076855) (xy 192.461636 -413.012933) (xy 192.469647 -412.949515)
			(xy 192.485544 -412.887601) (xy 192.509076 -412.828168) (xy 192.53987 -412.772153) (xy 192.577443 -412.720438)
			(xy 192.6212 -412.673841) (xy 192.670453 -412.633096) (xy 192.724424 -412.598845) (xy 192.782263 -412.571628)
			(xy 192.843056 -412.551875) (xy 192.905846 -412.539897) (xy 192.969642 -412.535884) (xy 193.033438 -412.539897)
			(xy 193.096228 -412.551875) (xy 193.157021 -412.571628) (xy 193.21486 -412.598845) (xy 193.268831 -412.633096)
			(xy 193.318084 -412.673841) (xy 193.361841 -412.720438) (xy 193.399414 -412.772153) (xy 193.430208 -412.828168)
			(xy 193.45374 -412.887601) (xy 193.469637 -412.949515) (xy 193.477648 -413.012933) (xy 193.47815 -413.044894)
			(xy 193.477648 -413.076855) (xy 193.469637 -413.140273) (xy 193.45374 -413.202187) (xy 193.430208 -413.26162)
			(xy 193.399414 -413.317635) (xy 193.361841 -413.36935) (xy 193.318084 -413.415947) (xy 193.268831 -413.456692)
			(xy 193.21486 -413.490943) (xy 193.157021 -413.51816) (xy 193.096228 -413.537913) (xy 193.033438 -413.549891)
			(xy 192.969642 -413.553905) (xy 192.905846 -413.549891) (xy 192.843056 -413.537913) (xy 192.782263 -413.51816)
			(xy 192.724424 -413.490943) (xy 192.670453 -413.456692) (xy 192.6212 -413.415947) (xy 192.577443 -413.36935)
			(xy 192.53987 -413.317635) (xy 192.509076 -413.26162) (xy 192.485544 -413.202187) (xy 192.469647 -413.140273)
			(xy 192.461636 -413.076855) (xy 189.370841 -413.076855) (xy 189.374754 -413.086737) (xy 189.390651 -413.148651)
			(xy 189.398662 -413.212069) (xy 189.399164 -413.24403) (xy 189.398662 -413.275991) (xy 189.390651 -413.339409)
			(xy 189.374754 -413.401323) (xy 189.351222 -413.460756) (xy 189.320428 -413.516771) (xy 189.28551 -413.564832)
			(xy 189.930276 -413.564832) (xy 189.934347 -413.50921) (xy 189.946473 -413.454773) (xy 189.966396 -413.402682)
			(xy 189.993692 -413.354047) (xy 190.027778 -413.309904) (xy 190.067927 -413.271195) (xy 190.113285 -413.238744)
			(xy 190.162885 -413.213243) (xy 190.215669 -413.195236) (xy 190.270512 -413.185106) (xy 190.326246 -413.183069)
			(xy 190.381683 -413.189169) (xy 190.43564 -413.203275) (xy 190.486969 -413.225087) (xy 190.534575 -413.254141)
			(xy 190.577443 -413.289816) (xy 190.61466 -413.331353) (xy 190.645433 -413.377866) (xy 190.669105 -413.428363)
			(xy 190.685173 -413.48177) (xy 190.693293 -413.536946) (xy 190.693802 -413.564832) (xy 190.693293 -413.592718)
			(xy 190.685173 -413.647894) (xy 190.669105 -413.701301) (xy 190.645433 -413.751798) (xy 190.61466 -413.798311)
			(xy 190.577443 -413.839848) (xy 190.534575 -413.875523) (xy 190.486969 -413.904577) (xy 190.43564 -413.926389)
			(xy 190.381683 -413.940495) (xy 190.326246 -413.946595) (xy 190.270512 -413.944558) (xy 190.215669 -413.934428)
			(xy 190.162885 -413.916421) (xy 190.113285 -413.89092) (xy 190.067927 -413.858469) (xy 190.027778 -413.81976)
			(xy 189.993692 -413.775617) (xy 189.966396 -413.726982) (xy 189.946473 -413.674891) (xy 189.934347 -413.620454)
			(xy 189.930276 -413.564832) (xy 189.28551 -413.564832) (xy 189.282855 -413.568486) (xy 189.239098 -413.615083)
			(xy 189.189845 -413.655828) (xy 189.135874 -413.690079) (xy 189.078035 -413.717296) (xy 189.017242 -413.737049)
			(xy 188.954452 -413.749027) (xy 188.890656 -413.753041) (xy 188.82686 -413.749027) (xy 188.76407 -413.737049)
			(xy 188.703277 -413.717296) (xy 188.645438 -413.690079) (xy 188.591467 -413.655828) (xy 188.542214 -413.615083)
			(xy 188.498457 -413.568486) (xy 188.460884 -413.516771) (xy 188.43009 -413.460756) (xy 188.406558 -413.401323)
			(xy 188.390661 -413.339409) (xy 188.38265 -413.275991) (xy 179.87123 -413.275991) (xy 179.877973 -413.321808)
			(xy 179.878482 -413.349694) (xy 179.877973 -413.37758) (xy 179.869853 -413.432756) (xy 179.853785 -413.486163)
			(xy 179.830113 -413.53666) (xy 179.79934 -413.583173) (xy 179.762123 -413.62471) (xy 179.719255 -413.660385)
			(xy 179.671649 -413.689439) (xy 179.62032 -413.711251) (xy 179.566363 -413.725357) (xy 179.510926 -413.731457)
			(xy 179.455192 -413.72942) (xy 179.400349 -413.71929) (xy 179.347565 -413.701283) (xy 179.297965 -413.675782)
			(xy 179.252607 -413.643331) (xy 179.212458 -413.604622) (xy 179.178372 -413.560479) (xy 179.151076 -413.511844)
			(xy 179.131153 -413.459753) (xy 179.119027 -413.405316) (xy 179.114956 -413.349694) (xy 176.978905 -413.349694)
			(xy 177.507138 -413.87776) (xy 177.524214 -413.895461) (xy 177.553142 -413.935237) (xy 177.575483 -413.979052)
			(xy 177.590685 -414.025825) (xy 177.598374 -414.074403) (xy 177.598832 -414.098994) (xy 177.598832 -414.369504)
			(xy 177.599308 -414.379471) (xy 177.606883 -414.397908) (xy 177.613564 -414.405318) (xy 178.134518 -414.926272)
			(xy 178.899564 -414.926272) (xy 178.903635 -414.87065) (xy 178.915761 -414.816213) (xy 178.935684 -414.764122)
			(xy 178.96298 -414.715487) (xy 178.997066 -414.671344) (xy 179.037215 -414.632635) (xy 179.082573 -414.600184)
			(xy 179.132173 -414.574683) (xy 179.184957 -414.556676) (xy 179.2398 -414.546546) (xy 179.295534 -414.544509)
			(xy 179.350971 -414.550609) (xy 179.404928 -414.564715) (xy 179.456257 -414.586527) (xy 179.503863 -414.615581)
			(xy 179.546731 -414.651256) (xy 179.583948 -414.692793) (xy 179.614721 -414.739306) (xy 179.638393 -414.789803)
			(xy 179.654461 -414.84321) (xy 179.662581 -414.898386) (xy 179.66309 -414.926272) (xy 179.662581 -414.954158)
			(xy 179.654461 -415.009334) (xy 179.638393 -415.062741) (xy 179.614721 -415.113238) (xy 179.583948 -415.159751)
			(xy 179.546731 -415.201288) (xy 179.503863 -415.236963) (xy 179.456257 -415.266017) (xy 179.404928 -415.287829)
			(xy 179.350971 -415.301935) (xy 179.295534 -415.308035) (xy 179.2398 -415.305998) (xy 179.184957 -415.295868)
			(xy 179.132173 -415.277861) (xy 179.082573 -415.25236) (xy 179.037215 -415.219909) (xy 178.997066 -415.1812)
			(xy 178.96298 -415.137057) (xy 178.935684 -415.088422) (xy 178.915761 -415.036331) (xy 178.903635 -414.981894)
			(xy 178.899564 -414.926272) (xy 178.134518 -414.926272) (xy 178.398932 -415.190686) (xy 178.406278 -415.197493)
			(xy 178.424741 -415.205216) (xy 178.434746 -415.205672) (xy 178.626008 -415.205672) (xy 178.650585 -415.206139)
			(xy 178.699139 -415.213797) (xy 178.745897 -415.228954) (xy 178.789709 -415.251238) (xy 178.829497 -415.2801)
			(xy 178.847242 -415.297112) (xy 179.888896 -416.338766) (xy 181.892956 -416.338766) (xy 181.893347 -416.309505)
			(xy 181.900063 -416.251368) (xy 181.913403 -416.194386) (xy 181.933191 -416.13931) (xy 181.959165 -416.086867)
			(xy 181.990983 -416.037749) (xy 182.009288 -416.014916) (xy 182.016282 -416.005502) (xy 182.021672 -415.982706)
			(xy 182.016463 -415.959867) (xy 182.009542 -415.9504) (xy 181.987885 -415.923031) (xy 181.951465 -415.863496)
			(xy 181.923532 -415.799537) (xy 181.904611 -415.732359) (xy 181.895059 -415.663224) (xy 181.89448 -415.628328)
			(xy 181.894982 -415.596367) (xy 181.902993 -415.532949) (xy 181.91889 -415.471035) (xy 181.942422 -415.411602)
			(xy 181.973216 -415.355587) (xy 182.010789 -415.303872) (xy 182.054546 -415.257275) (xy 182.103799 -415.21653)
			(xy 182.15777 -415.182279) (xy 182.215609 -415.155062) (xy 182.276402 -415.135309) (xy 182.339192 -415.123331)
			(xy 182.402988 -415.119318) (xy 182.466784 -415.123331) (xy 182.529574 -415.135309) (xy 182.590367 -415.155062)
			(xy 182.648206 -415.182279) (xy 182.702177 -415.21653) (xy 182.75143 -415.257275) (xy 182.795187 -415.303872)
			(xy 182.83276 -415.355587) (xy 182.863554 -415.411602) (xy 182.887086 -415.471035) (xy 182.902983 -415.532949)
			(xy 182.910994 -415.596367) (xy 182.911005 -415.597043) (xy 190.949574 -415.597043) (xy 190.949574 -415.533121)
			(xy 190.957585 -415.469703) (xy 190.973482 -415.407789) (xy 190.997014 -415.348356) (xy 191.027808 -415.292341)
			(xy 191.065381 -415.240626) (xy 191.109138 -415.194029) (xy 191.158391 -415.153284) (xy 191.212362 -415.119033)
			(xy 191.270201 -415.091816) (xy 191.330994 -415.072063) (xy 191.393784 -415.060085) (xy 191.45758 -415.056072)
			(xy 191.521376 -415.060085) (xy 191.584166 -415.072063) (xy 191.644959 -415.091816) (xy 191.702798 -415.119033)
			(xy 191.756769 -415.153284) (xy 191.806022 -415.194029) (xy 191.849779 -415.240626) (xy 191.887352 -415.292341)
			(xy 191.918146 -415.348356) (xy 191.941678 -415.407789) (xy 191.957575 -415.469703) (xy 191.965586 -415.533121)
			(xy 191.966088 -415.565082) (xy 191.965586 -415.597043) (xy 191.957575 -415.660461) (xy 191.941678 -415.722375)
			(xy 191.918146 -415.781808) (xy 191.887352 -415.837823) (xy 191.849779 -415.889538) (xy 191.806022 -415.936135)
			(xy 191.756769 -415.97688) (xy 191.702798 -416.011131) (xy 191.644959 -416.038348) (xy 191.584166 -416.058101)
			(xy 191.521376 -416.070079) (xy 191.45758 -416.074093) (xy 191.393784 -416.070079) (xy 191.330994 -416.058101)
			(xy 191.270201 -416.038348) (xy 191.212362 -416.011131) (xy 191.158391 -415.97688) (xy 191.109138 -415.936135)
			(xy 191.065381 -415.889538) (xy 191.027808 -415.837823) (xy 190.997014 -415.781808) (xy 190.973482 -415.722375)
			(xy 190.957585 -415.660461) (xy 190.949574 -415.597043) (xy 182.911005 -415.597043) (xy 182.911496 -415.628328)
			(xy 182.91109 -415.657589) (xy 182.904375 -415.715724) (xy 182.891037 -415.772706) (xy 182.871252 -415.827782)
			(xy 182.845281 -415.880225) (xy 182.813467 -415.929344) (xy 182.795164 -415.952178) (xy 182.788181 -415.961597)
			(xy 182.782794 -415.98439) (xy 182.787995 -416.007225) (xy 182.79491 -416.016694) (xy 182.816571 -416.044059)
			(xy 182.85299 -416.103596) (xy 182.878598 -416.162236) (xy 193.041522 -416.162236) (xy 193.045593 -416.106614)
			(xy 193.057719 -416.052177) (xy 193.077642 -416.000086) (xy 193.104938 -415.951451) (xy 193.139024 -415.907308)
			(xy 193.179173 -415.868599) (xy 193.224531 -415.836148) (xy 193.274131 -415.810647) (xy 193.326915 -415.79264)
			(xy 193.381758 -415.78251) (xy 193.437492 -415.780473) (xy 193.492929 -415.786573) (xy 193.546886 -415.800679)
			(xy 193.598215 -415.822491) (xy 193.645821 -415.851545) (xy 193.688689 -415.88722) (xy 193.725906 -415.928757)
			(xy 193.756679 -415.97527) (xy 193.780351 -416.025767) (xy 193.796419 -416.079174) (xy 193.804539 -416.13435)
			(xy 193.805048 -416.162236) (xy 193.804539 -416.190122) (xy 193.796419 -416.245298) (xy 193.780351 -416.298705)
			(xy 193.756679 -416.349202) (xy 193.725906 -416.395715) (xy 193.688689 -416.437252) (xy 193.645821 -416.472927)
			(xy 193.598215 -416.501981) (xy 193.546886 -416.523793) (xy 193.492929 -416.537899) (xy 193.437492 -416.543999)
			(xy 193.381758 -416.541962) (xy 193.326915 -416.531832) (xy 193.274131 -416.513825) (xy 193.224531 -416.488324)
			(xy 193.179173 -416.455873) (xy 193.139024 -416.417164) (xy 193.104938 -416.373021) (xy 193.077642 -416.324386)
			(xy 193.057719 -416.272295) (xy 193.045593 -416.217858) (xy 193.041522 -416.162236) (xy 182.878598 -416.162236)
			(xy 182.880921 -416.167556) (xy 182.899841 -416.234734) (xy 182.909393 -416.30387) (xy 182.909972 -416.338766)
			(xy 182.90947 -416.370727) (xy 182.901459 -416.434145) (xy 182.885562 -416.496059) (xy 182.86203 -416.555492)
			(xy 182.831236 -416.611507) (xy 182.793663 -416.663222) (xy 182.749906 -416.709819) (xy 182.700653 -416.750564)
			(xy 182.646682 -416.784815) (xy 182.588843 -416.812032) (xy 182.52805 -416.831785) (xy 182.46526 -416.843763)
			(xy 182.401464 -416.847777) (xy 182.337668 -416.843763) (xy 182.274878 -416.831785) (xy 182.214085 -416.812032)
			(xy 182.156246 -416.784815) (xy 182.102275 -416.750564) (xy 182.053022 -416.709819) (xy 182.009265 -416.663222)
			(xy 181.971692 -416.611507) (xy 181.940898 -416.555492) (xy 181.917366 -416.496059) (xy 181.901469 -416.434145)
			(xy 181.893458 -416.370727) (xy 181.892956 -416.338766) (xy 179.888896 -416.338766) (xy 180.954934 -417.404804)
			(xy 188.349888 -417.404804) (xy 188.353959 -417.349182) (xy 188.366085 -417.294745) (xy 188.386008 -417.242654)
			(xy 188.413304 -417.194019) (xy 188.44739 -417.149876) (xy 188.487539 -417.111167) (xy 188.532897 -417.078716)
			(xy 188.582497 -417.053215) (xy 188.635281 -417.035208) (xy 188.690124 -417.025078) (xy 188.745858 -417.023041)
			(xy 188.801295 -417.029141) (xy 188.855252 -417.043247) (xy 188.906581 -417.065059) (xy 188.954187 -417.094113)
			(xy 188.997055 -417.129788) (xy 189.034272 -417.171325) (xy 189.065045 -417.217838) (xy 189.088717 -417.268335)
			(xy 189.104785 -417.321742) (xy 189.112905 -417.376918) (xy 189.113414 -417.404804) (xy 189.112905 -417.43269)
			(xy 189.104785 -417.487866) (xy 189.088717 -417.541273) (xy 189.065045 -417.59177) (xy 189.034272 -417.638283)
			(xy 188.997055 -417.67982) (xy 188.954187 -417.715495) (xy 188.906581 -417.744549) (xy 188.855252 -417.766361)
			(xy 188.801295 -417.780467) (xy 188.745858 -417.786567) (xy 188.690124 -417.78453) (xy 188.635281 -417.7744)
			(xy 188.582497 -417.756393) (xy 188.532897 -417.730892) (xy 188.487539 -417.698441) (xy 188.44739 -417.659732)
			(xy 188.413304 -417.615589) (xy 188.386008 -417.566954) (xy 188.366085 -417.514863) (xy 188.353959 -417.460426)
			(xy 188.349888 -417.404804) (xy 180.954934 -417.404804) (xy 182.27853 -418.7284) (xy 186.344087 -418.7284)
			(xy 186.348101 -418.664606) (xy 186.360078 -418.601819) (xy 186.379829 -418.541027) (xy 186.407044 -418.48319)
			(xy 186.441293 -418.42922) (xy 186.482035 -418.379968) (xy 186.528629 -418.336211) (xy 186.58034 -418.298638)
			(xy 186.636352 -418.267842) (xy 186.695782 -418.244308) (xy 186.757693 -418.228409) (xy 186.821108 -418.220394)
			(xy 186.853068 -418.21989) (xy 186.884149 -418.220365) (xy 186.945846 -418.227949) (xy 187.00616 -418.242996)
			(xy 187.064189 -418.265282) (xy 187.11907 -418.294475) (xy 187.169985 -418.330138) (xy 187.216172 -418.37174)
			(xy 187.256946 -418.418662) (xy 187.274708 -418.444172) (xy 187.282836 -418.45611) (xy 187.30849 -418.468048)
			(xy 187.4266 -418.454332) (xy 187.448952 -418.436806) (xy 187.454032 -418.423344) (xy 187.465311 -418.394753)
			(xy 187.493888 -418.340335) (xy 187.528815 -418.289757) (xy 187.569583 -418.243757) (xy 187.615597 -418.203005)
			(xy 187.666187 -418.168096) (xy 187.720615 -418.139538) (xy 187.778089 -418.117748) (xy 187.837769 -418.103043)
			(xy 187.898787 -418.095638) (xy 187.92952 -418.095176) (xy 187.96337 -418.095719) (xy 188.030471 -418.104694)
			(xy 188.095787 -418.122497) (xy 188.158162 -418.148812) (xy 188.216493 -418.183173) (xy 188.243464 -418.203634)
			(xy 188.250582 -418.208768) (xy 188.267203 -418.214361) (xy 188.275976 -418.214556) (xy 188.305948 -418.213794)
			(xy 188.314694 -418.213243) (xy 188.33106 -418.207014) (xy 188.337952 -418.201602) (xy 188.361037 -418.182328)
			(xy 188.410971 -418.148809) (xy 188.46451 -418.121416) (xy 188.520908 -418.100531) (xy 188.579376 -418.086446)
			(xy 188.639098 -418.079358) (xy 188.669168 -418.07892) (xy 188.701133 -418.079343) (xy 188.764561 -418.087352)
			(xy 188.826484 -418.103248) (xy 188.885926 -418.126779) (xy 188.94195 -418.157576) (xy 188.993673 -418.195151)
			(xy 189.040278 -418.238914) (xy 189.08103 -418.288172) (xy 189.115287 -418.34215) (xy 189.142509 -418.399996)
			(xy 189.162265 -418.460797) (xy 189.174245 -418.523595) (xy 189.17826 -418.5874) (xy 189.174245 -418.651205)
			(xy 189.162265 -418.714003) (xy 189.142509 -418.774804) (xy 189.115287 -418.83265) (xy 189.08103 -418.886628)
			(xy 189.040278 -418.935886) (xy 188.993673 -418.979649) (xy 188.94195 -419.017224) (xy 188.885926 -419.048021)
			(xy 188.826484 -419.071552) (xy 188.764561 -419.087448) (xy 188.701133 -419.095457) (xy 188.669168 -419.095936)
			(xy 188.635318 -419.095397) (xy 188.568217 -419.086421) (xy 188.502901 -419.068617) (xy 188.440526 -419.042301)
			(xy 188.382195 -419.007939) (xy 188.355224 -418.987478) (xy 188.348108 -418.98234) (xy 188.331486 -418.976749)
			(xy 188.322712 -418.976556) (xy 188.29274 -418.977318) (xy 188.283993 -418.97786) (xy 188.267627 -418.984095)
			(xy 188.260736 -418.98951) (xy 188.237619 -419.008744) (xy 188.187693 -419.042267) (xy 188.13416 -419.069666)
			(xy 188.077768 -419.090558) (xy 188.019305 -419.104651) (xy 187.959589 -419.111749) (xy 187.92952 -419.112192)
			(xy 187.898438 -419.111734) (xy 187.83674 -419.104148) (xy 187.776426 -419.089099) (xy 187.718396 -419.066811)
			(xy 187.663515 -419.037616) (xy 187.612601 -419.00195) (xy 187.566414 -418.960345) (xy 187.525642 -418.913421)
			(xy 187.50788 -418.88791) (xy 187.499752 -418.875972) (xy 187.474098 -418.864034) (xy 187.355988 -418.87775)
			(xy 187.333636 -418.895276) (xy 187.328556 -418.908738) (xy 187.317193 -418.937294) (xy 187.288624 -418.99171)
			(xy 187.253707 -419.042286) (xy 187.212949 -419.088287) (xy 187.166944 -419.12904) (xy 187.116364 -419.163952)
			(xy 187.061945 -419.192515) (xy 187.00448 -419.214311) (xy 186.944808 -419.229024) (xy 186.883798 -419.236439)
			(xy 186.853068 -419.236906) (xy 186.821108 -419.236406) (xy 186.757693 -419.228391) (xy 186.695782 -419.212492)
			(xy 186.636352 -419.188958) (xy 186.58034 -419.158162) (xy 186.528629 -419.120589) (xy 186.482035 -419.076832)
			(xy 186.441293 -419.02758) (xy 186.407044 -418.97361) (xy 186.379829 -418.915773) (xy 186.360078 -418.854981)
			(xy 186.348101 -418.792194) (xy 186.344087 -418.7284) (xy 182.27853 -418.7284) (xy 183.731154 -420.181024)
			(xy 183.748231 -420.198725) (xy 183.777163 -420.2385) (xy 183.799507 -420.282314) (xy 183.814714 -420.329088)
			(xy 183.822408 -420.377666) (xy 183.822848 -420.402258) (xy 183.822848 -420.609522) (xy 183.823327 -420.620515)
			(xy 183.832417 -420.640529) (xy 183.840374 -420.64813) (xy 183.866915 -420.671649) (xy 183.913872 -420.724788)
			(xy 183.952996 -420.783931) (xy 183.983531 -420.847934) (xy 183.994806 -420.881556) (xy 183.999124 -420.895272)
			(xy 184.020714 -420.914068) (xy 184.13857 -420.933626) (xy 184.164986 -420.922958) (xy 184.173622 -420.911274)
			(xy 184.19174 -420.887656) (xy 184.234067 -420.845809) (xy 184.282378 -420.81104) (xy 184.335502 -420.784194)
			(xy 184.39215 -420.765922) (xy 184.450947 -420.756667) (xy 184.480708 -420.75608) (xy 184.50796 -420.756566)
			(xy 184.561908 -420.764324) (xy 184.614204 -420.77968) (xy 184.663782 -420.802323) (xy 184.709632 -420.83179)
			(xy 184.750823 -420.867483) (xy 184.786515 -420.908674) (xy 184.815981 -420.954526) (xy 184.838622 -421.004104)
			(xy 184.853978 -421.0564) (xy 184.861734 -421.110348) (xy 184.861734 -421.1447) (xy 185.11469 -421.1447)
			(xy 185.118761 -421.089078) (xy 185.130887 -421.034641) (xy 185.15081 -420.98255) (xy 185.178106 -420.933915)
			(xy 185.212192 -420.889772) (xy 185.252341 -420.851063) (xy 185.297699 -420.818612) (xy 185.347299 -420.793111)
			(xy 185.400083 -420.775104) (xy 185.454926 -420.764974) (xy 185.51066 -420.762937) (xy 185.566097 -420.769037)
			(xy 185.620054 -420.783143) (xy 185.671383 -420.804955) (xy 185.718989 -420.834009) (xy 185.761857 -420.869684)
			(xy 185.799074 -420.911221) (xy 185.829847 -420.957734) (xy 185.853519 -421.008231) (xy 185.869587 -421.061638)
			(xy 185.873438 -421.087804) (xy 186.288932 -421.087804) (xy 186.293003 -421.032182) (xy 186.305129 -420.977745)
			(xy 186.325052 -420.925654) (xy 186.352348 -420.877019) (xy 186.386434 -420.832876) (xy 186.426583 -420.794167)
			(xy 186.471941 -420.761716) (xy 186.521541 -420.736215) (xy 186.574325 -420.718208) (xy 186.629168 -420.708078)
			(xy 186.684902 -420.706041) (xy 186.740339 -420.712141) (xy 186.794296 -420.726247) (xy 186.845625 -420.748059)
			(xy 186.893231 -420.777113) (xy 186.936099 -420.812788) (xy 186.973316 -420.854325) (xy 187.004089 -420.900838)
			(xy 187.027761 -420.951335) (xy 187.030686 -420.961058) (xy 188.527942 -420.961058) (xy 188.532013 -420.905436)
			(xy 188.544139 -420.850999) (xy 188.564062 -420.798908) (xy 188.591358 -420.750273) (xy 188.625444 -420.70613)
			(xy 188.665593 -420.667421) (xy 188.710951 -420.63497) (xy 188.760551 -420.609469) (xy 188.813335 -420.591462)
			(xy 188.868178 -420.581332) (xy 188.923912 -420.579295) (xy 188.979349 -420.585395) (xy 189.033306 -420.599501)
			(xy 189.084635 -420.621313) (xy 189.132241 -420.650367) (xy 189.175109 -420.686042) (xy 189.212326 -420.727579)
			(xy 189.243099 -420.774092) (xy 189.266771 -420.824589) (xy 189.282839 -420.877996) (xy 189.290959 -420.933172)
			(xy 189.291468 -420.961058) (xy 189.290959 -420.988944) (xy 189.282839 -421.04412) (xy 189.266771 -421.097527)
			(xy 189.243099 -421.148024) (xy 189.212326 -421.194537) (xy 189.175109 -421.236074) (xy 189.132241 -421.271749)
			(xy 189.084635 -421.300803) (xy 189.033306 -421.322615) (xy 188.979349 -421.336721) (xy 188.923912 -421.342821)
			(xy 188.868178 -421.340784) (xy 188.813335 -421.330654) (xy 188.760551 -421.312647) (xy 188.710951 -421.287146)
			(xy 188.665593 -421.254695) (xy 188.625444 -421.215986) (xy 188.591358 -421.171843) (xy 188.564062 -421.123208)
			(xy 188.544139 -421.071117) (xy 188.532013 -421.01668) (xy 188.527942 -420.961058) (xy 187.030686 -420.961058)
			(xy 187.043829 -421.004742) (xy 187.051949 -421.059918) (xy 187.052458 -421.087804) (xy 187.051949 -421.11569)
			(xy 187.043829 -421.170866) (xy 187.027761 -421.224273) (xy 187.004089 -421.27477) (xy 186.973316 -421.321283)
			(xy 186.936099 -421.36282) (xy 186.893231 -421.398495) (xy 186.847947 -421.426132) (xy 190.504316 -421.426132)
			(xy 190.508387 -421.37051) (xy 190.520513 -421.316073) (xy 190.540436 -421.263982) (xy 190.567732 -421.215347)
			(xy 190.601818 -421.171204) (xy 190.641967 -421.132495) (xy 190.687325 -421.100044) (xy 190.736925 -421.074543)
			(xy 190.789709 -421.056536) (xy 190.844552 -421.046406) (xy 190.900286 -421.044369) (xy 190.955723 -421.050469)
			(xy 191.00968 -421.064575) (xy 191.061009 -421.086387) (xy 191.108615 -421.115441) (xy 191.151483 -421.151116)
			(xy 191.1887 -421.192653) (xy 191.219473 -421.239166) (xy 191.243145 -421.289663) (xy 191.259213 -421.34307)
			(xy 191.267333 -421.398246) (xy 191.267842 -421.426132) (xy 191.267333 -421.454018) (xy 191.259213 -421.509194)
			(xy 191.243145 -421.562601) (xy 191.219473 -421.613098) (xy 191.1887 -421.659611) (xy 191.151483 -421.701148)
			(xy 191.108615 -421.736823) (xy 191.061009 -421.765877) (xy 191.00968 -421.787689) (xy 190.955723 -421.801795)
			(xy 190.900286 -421.807895) (xy 190.844552 -421.805858) (xy 190.789709 -421.795728) (xy 190.736925 -421.777721)
			(xy 190.687325 -421.75222) (xy 190.641967 -421.719769) (xy 190.601818 -421.68106) (xy 190.567732 -421.636917)
			(xy 190.540436 -421.588282) (xy 190.520513 -421.536191) (xy 190.508387 -421.481754) (xy 190.504316 -421.426132)
			(xy 186.847947 -421.426132) (xy 186.845625 -421.427549) (xy 186.794296 -421.449361) (xy 186.740339 -421.463467)
			(xy 186.684902 -421.469567) (xy 186.629168 -421.46753) (xy 186.574325 -421.4574) (xy 186.521541 -421.439393)
			(xy 186.471941 -421.413892) (xy 186.426583 -421.381441) (xy 186.386434 -421.342732) (xy 186.352348 -421.298589)
			(xy 186.325052 -421.249954) (xy 186.305129 -421.197863) (xy 186.293003 -421.143426) (xy 186.288932 -421.087804)
			(xy 185.873438 -421.087804) (xy 185.877707 -421.116814) (xy 185.878216 -421.1447) (xy 185.877707 -421.172586)
			(xy 185.869587 -421.227762) (xy 185.853519 -421.281169) (xy 185.829847 -421.331666) (xy 185.799074 -421.378179)
			(xy 185.761857 -421.419716) (xy 185.718989 -421.455391) (xy 185.671383 -421.484445) (xy 185.620054 -421.506257)
			(xy 185.566097 -421.520363) (xy 185.51066 -421.526463) (xy 185.454926 -421.524426) (xy 185.400083 -421.514296)
			(xy 185.347299 -421.496289) (xy 185.297699 -421.470788) (xy 185.252341 -421.438337) (xy 185.212192 -421.399628)
			(xy 185.178106 -421.355485) (xy 185.15081 -421.30685) (xy 185.130887 -421.254759) (xy 185.118761 -421.200322)
			(xy 185.11469 -421.1447) (xy 184.861734 -421.1447) (xy 184.861734 -421.164852) (xy 184.853978 -421.2188)
			(xy 184.838622 -421.271096) (xy 184.815981 -421.320674) (xy 184.786515 -421.366526) (xy 184.750823 -421.407717)
			(xy 184.709632 -421.44341) (xy 184.663782 -421.472877) (xy 184.614204 -421.49552) (xy 184.561908 -421.510876)
			(xy 184.50796 -421.518634) (xy 184.480708 -421.519096) (xy 184.453342 -421.518618) (xy 184.399174 -421.510781)
			(xy 184.346682 -421.495281) (xy 184.296945 -421.472438) (xy 184.250984 -421.442719) (xy 184.209743 -421.406736)
			(xy 184.174069 -421.365226) (xy 184.144695 -421.319044) (xy 184.132982 -421.294306) (xy 184.126886 -421.281098)
			(xy 184.103264 -421.265096) (xy 183.984138 -421.259508) (xy 183.958992 -421.273224) (xy 183.95188 -421.285924)
			(xy 183.93485 -421.31477) (xy 183.894361 -421.368135) (xy 183.847216 -421.415723) (xy 183.794231 -421.456709)
			(xy 183.736324 -421.490384) (xy 183.674497 -421.516165) (xy 183.60982 -421.533605) (xy 183.543413 -421.542402)
			(xy 183.50992 -421.542972) (xy 183.479188 -421.542528) (xy 183.418172 -421.535121) (xy 183.358493 -421.520413)
			(xy 183.301023 -421.498618) (xy 183.246599 -421.470054) (xy 183.196015 -421.435139) (xy 183.150009 -421.39438)
			(xy 183.109251 -421.348372) (xy 183.074337 -421.297787) (xy 183.045775 -421.243363) (xy 183.023983 -421.185892)
			(xy 183.009276 -421.126213) (xy 183.001872 -421.065196) (xy 183.001412 -421.034464) (xy 183.001873 -421.003101)
			(xy 183.009587 -420.940852) (xy 183.024905 -420.880025) (xy 183.047593 -420.821547) (xy 183.077308 -420.766306)
			(xy 183.113596 -420.715144) (xy 183.155907 -420.668837) (xy 183.179466 -420.64813) (xy 183.187848 -420.640764)
			(xy 183.196992 -420.620698) (xy 183.196992 -420.55288) (xy 183.196514 -420.542914) (xy 183.188937 -420.524479)
			(xy 183.18226 -420.517066) (xy 178.5112 -415.846006) (xy 178.503855 -415.839195) (xy 178.485393 -415.831461)
			(xy 178.475386 -415.83102) (xy 178.284124 -415.83102) (xy 178.259546 -415.830556) (xy 178.21099 -415.822902)
			(xy 178.164229 -415.807748) (xy 178.120413 -415.785466) (xy 178.080622 -415.756606) (xy 178.06289 -415.73958)
			(xy 177.06467 -414.74136) (xy 177.047592 -414.723659) (xy 177.018661 -414.683885) (xy 176.996317 -414.64007)
			(xy 176.981111 -414.593296) (xy 176.973419 -414.544718) (xy 176.972976 -414.520126) (xy 176.972976 -414.249616)
			(xy 176.972486 -414.239656) (xy 176.964891 -414.221238) (xy 176.958244 -414.213802) (xy 176.00422 -413.259778)
			(xy 175.997096 -413.253215) (xy 175.979336 -413.245526) (xy 175.969676 -413.244792) (xy 175.889666 -413.24276)
			(xy 175.871632 -413.249618) (xy 175.864266 -413.256222) (xy 175.842811 -413.275137) (xy 175.796372 -413.308533)
			(xy 175.746468 -413.336487) (xy 175.720248 -413.347916) (xy 175.70831 -413.352742) (xy 175.692562 -413.3723)
			(xy 175.673766 -413.46755) (xy 175.672019 -413.479977) (xy 175.67933 -413.503954) (xy 175.687736 -413.51327)
			(xy 175.703992 -413.529526) (xy 175.726187 -413.552319) (xy 175.765865 -413.602052) (xy 175.799725 -413.655916)
			(xy 175.827339 -413.713232) (xy 175.848362 -413.773281) (xy 175.862528 -413.835306) (xy 175.86966 -413.898527)
			(xy 175.870108 -413.930338) (xy 175.870108 -414.442148) (xy 175.870591 -414.452111) (xy 175.878175 -414.47054)
			(xy 175.88484 -414.477962) (xy 177.68824 -416.281362) (xy 177.728372 -416.282632) (xy 177.743612 -416.268916)
			(xy 177.766984 -416.248588) (xy 177.817793 -416.213155) (xy 177.87253 -416.184157) (xy 177.930385 -416.162022)
			(xy 177.990499 -416.147079) (xy 178.051984 -416.13955) (xy 178.082956 -416.139122) (xy 178.113689 -416.139565)
			(xy 178.174708 -416.146969) (xy 178.234389 -416.161675) (xy 178.291862 -416.183469) (xy 178.346289 -416.212031)
			(xy 178.396876 -416.246946) (xy 178.442885 -416.287705) (xy 178.483645 -416.333713) (xy 178.518562 -416.384299)
			(xy 178.547126 -416.438725) (xy 178.56892 -416.496198) (xy 178.583628 -416.555878) (xy 178.591034 -416.616897)
			(xy 178.591464 -416.64763) (xy 178.590997 -416.679071) (xy 178.583237 -416.741472) (xy 178.56783 -416.802436)
			(xy 178.545009 -416.86103) (xy 178.530504 -416.88893) (xy 178.524154 -416.900868) (xy 178.524662 -416.927284)
			(xy 178.576478 -417.013898) (xy 178.581287 -417.021185) (xy 178.594778 -417.03225) (xy 178.61119 -417.038172)
			(xy 178.619912 -417.038536) (xy 178.705002 -417.038536) (xy 178.739919 -417.039073) (xy 178.809224 -417.047654)
			(xy 178.87695 -417.064684) (xy 178.942071 -417.089907) (xy 179.003598 -417.12294) (xy 179.032408 -417.142676)
			(xy 179.042031 -417.14871) (xy 179.064388 -417.152542) (xy 179.086224 -417.1464) (xy 179.095146 -417.139374)
			(xy 179.116125 -417.121644) (xy 179.162213 -417.091764) (xy 179.212109 -417.0688) (xy 179.264781 -417.053228)
			(xy 179.319143 -417.045368) (xy 179.346606 -417.044886) (xy 179.373857 -417.045372) (xy 179.427805 -417.05313)
			(xy 179.4801 -417.068485) (xy 179.529677 -417.091127) (xy 179.575528 -417.120594) (xy 179.616718 -417.156286)
			(xy 179.652409 -417.197477) (xy 179.681876 -417.243328) (xy 179.704517 -417.292905) (xy 179.719872 -417.345201)
			(xy 179.727628 -417.399149) (xy 179.727628 -417.453651) (xy 179.719872 -417.507599) (xy 179.704517 -417.559895)
			(xy 179.681876 -417.609472) (xy 179.652409 -417.655323) (xy 179.616718 -417.696514) (xy 179.575528 -417.732206)
			(xy 179.529677 -417.761673) (xy 179.4801 -417.784315) (xy 179.427805 -417.79967) (xy 179.373857 -417.807428)
			(xy 179.346606 -417.807902) (xy 179.329881 -417.807724) (xy 179.296558 -417.804803) (xy 179.280058 -417.80206)
			(xy 179.268771 -417.800663) (xy 179.246874 -417.806692) (xy 179.229727 -417.821586) (xy 179.224686 -417.831778)
			(xy 179.211132 -417.861752) (xy 179.178085 -417.918635) (xy 179.138672 -417.971307) (xy 179.093424 -418.01906)
			(xy 179.042951 -418.061252) (xy 178.98793 -418.097315) (xy 178.929104 -418.126763) (xy 178.867263 -418.1492)
			(xy 178.803239 -418.164324) (xy 178.737895 -418.171931) (xy 178.705002 -418.172392) (xy 178.210718 -418.172392)
			(xy 178.178906 -418.171963) (xy 178.115681 -418.164837) (xy 178.053653 -418.150674) (xy 177.993602 -418.129651)
			(xy 177.936284 -418.102033) (xy 177.882421 -418.068168) (xy 177.83269 -418.028482) (xy 177.809906 -418.006276)
			(xy 176.601628 -416.797998) (xy 176.595005 -416.791852) (xy 176.578634 -416.784238) (xy 176.560641 -416.782732)
			(xy 176.551844 -416.78479) (xy 176.453038 -416.81273) (xy 176.434242 -416.832288) (xy 176.43094 -416.84575)
			(xy 176.423809 -416.873132) (xy 176.402567 -416.925575) (xy 176.373815 -416.974306) (xy 176.338182 -417.018257)
			(xy 176.296449 -417.056464) (xy 176.249531 -417.088089) (xy 176.198458 -417.11244) (xy 176.144349 -417.128982)
			(xy 176.08839 -417.137352) (xy 176.0601 -417.13785) (xy 176.032848 -417.137364) (xy 175.978898 -417.129608)
			(xy 175.926601 -417.114253) (xy 175.877021 -417.091613) (xy 175.831167 -417.062147) (xy 175.789974 -417.026456)
			(xy 175.754278 -416.985266) (xy 175.724807 -416.939416) (xy 175.702161 -416.889839) (xy 175.686801 -416.837543)
			(xy 175.679039 -416.783594) (xy 175.678592 -416.756342) (xy 175.679104 -416.72805) (xy 175.687457 -416.672086)
			(xy 175.703987 -416.61797) (xy 175.728331 -416.566891) (xy 175.759955 -416.519968) (xy 175.798163 -416.478233)
			(xy 175.842118 -416.4426) (xy 175.890856 -416.413852) (xy 175.943306 -416.392621) (xy 175.970692 -416.385502)
			(xy 175.984154 -416.3822) (xy 176.003712 -416.363404) (xy 176.031652 -416.264598) (xy 176.033743 -416.255801)
			(xy 176.032268 -416.237792) (xy 176.024615 -416.221424) (xy 176.018444 -416.214814) (xy 174.902368 -415.098738)
			(xy 174.881076 -415.076871) (xy 174.842804 -415.029325) (xy 174.809855 -414.977946) (xy 174.78261 -414.923328)
			(xy 174.761384 -414.866101) (xy 174.753524 -414.83661) (xy 174.751054 -414.828267) (xy 174.741391 -414.813813)
			(xy 174.727438 -414.80344) (xy 174.719234 -414.800542) (xy 174.693491 -414.792224) (xy 174.644472 -414.769336)
			(xy 174.599178 -414.739753) (xy 174.558516 -414.704069) (xy 174.523303 -414.662999) (xy 174.494245 -414.617367)
			(xy 174.471924 -414.568087) (xy 174.456787 -414.516149) (xy 174.449139 -414.462593) (xy 174.448724 -414.435544)
			(xy 174.448821 -414.424148) (xy 174.450216 -414.401399) (xy 174.451518 -414.390078) (xy 174.452534 -414.38068)
			(xy 174.448216 -414.3629) (xy 174.399194 -414.292034) (xy 174.383954 -414.28162) (xy 174.37481 -414.279334)
			(xy 174.359842 -414.275485) (xy 174.330357 -414.266208) (xy 174.315882 -414.260792) (xy 174.303944 -414.256474)
			(xy 174.279306 -414.259268) (xy 174.200058 -414.314132) (xy 174.190303 -414.321699) (xy 174.178742 -414.343468)
			(xy 174.17796 -414.355788) (xy 174.17796 -415.38652) (xy 174.20209 -415.414968) (xy 174.220632 -415.418016)
			(xy 174.2526 -415.423876) (xy 174.31482 -415.442662) (xy 174.374138 -415.469225) (xy 174.429588 -415.50313)
			(xy 174.480264 -415.543826) (xy 174.525341 -415.590648) (xy 174.564083 -415.642833) (xy 174.595859 -415.69953)
			(xy 174.62015 -415.759814) (xy 174.63656 -415.822702) (xy 174.644822 -415.887169) (xy 174.64532 -415.919666)
			(xy 174.644793 -415.952285) (xy 174.636443 -416.016985) (xy 174.619888 -416.080087) (xy 174.595401 -416.140554)
			(xy 174.563383 -416.197393) (xy 174.524359 -416.249672) (xy 174.502064 -416.273488) (xy 174.494952 -416.2806)
			(xy 174.48784 -416.299142) (xy 174.488348 -416.380422) (xy 174.488918 -416.390346) (xy 174.496626 -416.408647)
			(xy 174.503334 -416.415982) (xy 174.850044 -416.762692) (xy 174.872242 -416.785483) (xy 174.911927 -416.835215)
			(xy 174.945792 -416.889077) (xy 174.973413 -416.946394) (xy 174.994441 -417.006443) (xy 175.008612 -417.068469)
			(xy 175.015748 -417.131692) (xy 175.01616 -417.163504) (xy 175.01616 -417.449) (xy 175.015716 -417.481065)
			(xy 175.008474 -417.544784) (xy 174.994084 -417.607278) (xy 174.97273 -417.667748) (xy 174.944683 -417.725419)
			(xy 174.910304 -417.779555) (xy 174.870032 -417.829462) (xy 174.824383 -417.874503) (xy 174.773939 -417.914102)
			(xy 174.719346 -417.94775) (xy 174.690532 -417.961826) (xy 174.67834 -417.967668) (xy 174.662846 -417.989766)
			(xy 174.652686 -418.104066) (xy 174.663862 -418.128704) (xy 174.675038 -418.136578) (xy 174.695905 -418.15199)
			(xy 174.733675 -418.187548) (xy 174.766278 -418.227898) (xy 174.793112 -418.272293) (xy 174.813683 -418.319915)
			(xy 174.82761 -418.369886) (xy 174.834637 -418.421282) (xy 174.835058 -418.44722) (xy 174.834572 -418.474471)
			(xy 174.826816 -418.528419) (xy 174.811461 -418.580714) (xy 174.788819 -418.630291) (xy 174.759353 -418.676141)
			(xy 174.723662 -418.717332) (xy 174.682471 -418.753023) (xy 174.636621 -418.782489) (xy 174.587044 -418.805131)
			(xy 174.534749 -418.820486) (xy 174.480801 -418.828242) (xy 174.426299 -418.828242) (xy 174.372351 -418.820486)
			(xy 174.320056 -418.805131) (xy 174.270479 -418.782489) (xy 174.224629 -418.753023) (xy 174.183438 -418.717332)
			(xy 174.147747 -418.676141) (xy 174.118281 -418.630291) (xy 174.095639 -418.580714) (xy 174.080284 -418.528419)
			(xy 174.072528 -418.474471) (xy 174.072042 -418.44722) (xy 174.072467 -418.421505) (xy 174.079383 -418.370541)
			(xy 174.093079 -418.320967) (xy 174.113306 -418.273681) (xy 174.139698 -418.229539) (xy 174.171778 -418.18934)
			(xy 174.208965 -418.153811) (xy 174.229522 -418.138356) (xy 174.240444 -418.130482) (xy 174.25162 -418.105844)
			(xy 174.24019 -417.991544) (xy 174.224696 -417.9697) (xy 174.21225 -417.963858) (xy 174.180388 -417.948593)
			(xy 174.120379 -417.9113) (xy 174.065469 -417.866841) (xy 174.016508 -417.815904) (xy 173.974254 -417.759279)
			(xy 173.939363 -417.697844) (xy 173.912374 -417.632549) (xy 173.893706 -417.564408) (xy 173.888146 -417.529518)
			(xy 173.886368 -417.517326) (xy 173.87189 -417.497006) (xy 173.77537 -417.448238) (xy 173.750478 -417.448746)
			(xy 173.739556 -417.454588) (xy 173.711724 -417.468977) (xy 173.653294 -417.491599) (xy 173.592528 -417.506874)
			(xy 173.530346 -417.514571) (xy 173.499018 -417.51504) (xy 173.468286 -417.514577) (xy 173.407269 -417.50717)
			(xy 173.347589 -417.492463) (xy 173.290118 -417.47067) (xy 173.235692 -417.442108) (xy 173.185106 -417.407195)
			(xy 173.139097 -417.366438) (xy 173.098336 -417.320433) (xy 173.063418 -417.269851) (xy 173.03485 -417.215428)
			(xy 173.013052 -417.157958) (xy 172.998339 -417.098281) (xy 172.990926 -417.037264) (xy 172.99051 -417.006532)
			(xy 172.992034 -416.967162) (xy 172.992796 -416.955986) (xy 172.985176 -416.935158) (xy 172.591984 -416.541966)
			(xy 172.574937 -416.524252) (xy 172.54607 -416.484461) (xy 172.523787 -416.440642) (xy 172.50864 -416.393874)
			(xy 172.501001 -416.345312) (xy 172.500544 -416.320732) (xy 172.500544 -413.047942) (xy 172.500064 -413.037926)
			(xy 172.492413 -413.019412) (xy 172.47826 -413.005235) (xy 172.45976 -412.997553) (xy 172.449744 -412.997142)
			(xy 171.609512 -412.997142) (xy 171.599442 -412.997564) (xy 171.580838 -413.00528) (xy 171.573444 -413.012128)
			(xy 171.36364 -413.221932) (xy 171.357015 -413.229259) (xy 171.349417 -413.247473) (xy 171.349237 -413.267207)
			(xy 171.352464 -413.276542) (xy 171.39285 -413.377634) (xy 171.417488 -413.394906) (xy 171.432982 -413.39516)
			(xy 171.45976 -413.396334) (xy 171.512613 -413.405256) (xy 171.563699 -413.421481) (xy 171.612015 -413.44469)
			(xy 171.65661 -413.474427) (xy 171.696608 -413.510108) (xy 171.731224 -413.551032) (xy 171.759778 -413.596394)
			(xy 171.781707 -413.645303) (xy 171.796582 -413.696799) (xy 171.804109 -413.749868) (xy 171.804584 -413.776668)
			(xy 171.804123 -413.803922) (xy 171.796369 -413.857875) (xy 171.781016 -413.910175) (xy 171.758375 -413.959758)
			(xy 171.728907 -414.005613) (xy 171.693213 -414.046808) (xy 171.65202 -414.082503) (xy 171.606165 -414.111971)
			(xy 171.556583 -414.134613) (xy 171.504283 -414.149968) (xy 171.45033 -414.157722) (xy 171.423076 -414.158176)
			(xy 171.396269 -414.157727) (xy 171.343182 -414.150233) (xy 171.291667 -414.135381) (xy 171.242738 -414.113465)
			(xy 171.197358 -414.084915) (xy 171.156422 -414.050294) (xy 171.120735 -414.010284) (xy 171.091 -413.965672)
			(xy 171.067802 -413.917337) (xy 171.051599 -413.866231) (xy 171.042709 -413.81336) (xy 171.041568 -413.786574)
			(xy 171.041314 -413.77108) (xy 171.024042 -413.746442) (xy 170.92295 -413.706056) (xy 170.913614 -413.70284)
			(xy 170.893887 -413.703016) (xy 170.875689 -413.710633) (xy 170.86834 -413.717232) (xy 170.86707 -413.718502)
			(xy 170.860252 -413.725844) (xy 170.852509 -413.744307) (xy 170.852084 -413.754316) (xy 170.852084 -414.333944)
			(xy 170.851669 -414.365749) (xy 170.844573 -414.428961) (xy 170.830443 -414.49098) (xy 170.809455 -414.551027)
			(xy 170.781874 -414.608345) (xy 170.748047 -414.662214) (xy 170.708399 -414.711955) (xy 170.686222 -414.734756)
			(xy 170.08475 -415.336228) (xy 170.077903 -415.343626) (xy 170.070171 -415.362224) (xy 170.069764 -415.372296)
			(xy 170.069764 -416.214052) (xy 170.070192 -416.223751) (xy 170.077369 -416.241774) (xy 170.083734 -416.249104)
			(xy 170.104308 -416.270948) (xy 170.110911 -416.277333) (xy 170.127455 -416.285278) (xy 170.136566 -416.286442)
			(xy 170.167773 -416.289742) (xy 170.229097 -416.303061) (xy 170.288317 -416.323824) (xy 170.344532 -416.351717)
			(xy 170.386433 -416.379406) (xy 170.80941 -416.379406) (xy 170.813481 -416.323784) (xy 170.825607 -416.269347)
			(xy 170.84553 -416.217256) (xy 170.872826 -416.168621) (xy 170.906912 -416.124478) (xy 170.947061 -416.085769)
			(xy 170.992419 -416.053318) (xy 171.042019 -416.027817) (xy 171.094803 -416.00981) (xy 171.149646 -415.99968)
			(xy 171.20538 -415.997643) (xy 171.260817 -416.003743) (xy 171.314774 -416.017849) (xy 171.366103 -416.039661)
			(xy 171.413709 -416.068715) (xy 171.456577 -416.10439) (xy 171.493794 -416.145927) (xy 171.524567 -416.19244)
			(xy 171.548239 -416.242937) (xy 171.564307 -416.296344) (xy 171.572427 -416.35152) (xy 171.572936 -416.379406)
			(xy 171.572427 -416.407292) (xy 171.564307 -416.462468) (xy 171.548239 -416.515875) (xy 171.524567 -416.566372)
			(xy 171.493794 -416.612885) (xy 171.456577 -416.654422) (xy 171.413709 -416.690097) (xy 171.366103 -416.719151)
			(xy 171.314774 -416.740963) (xy 171.260817 -416.755069) (xy 171.20538 -416.761169) (xy 171.149646 -416.759132)
			(xy 171.094803 -416.749002) (xy 171.042019 -416.730995) (xy 170.992419 -416.705494) (xy 170.947061 -416.673043)
			(xy 170.906912 -416.634334) (xy 170.872826 -416.590191) (xy 170.84553 -416.541556) (xy 170.825607 -416.489465)
			(xy 170.813481 -416.435028) (xy 170.80941 -416.379406) (xy 170.386433 -416.379406) (xy 170.396887 -416.386314)
			(xy 170.444588 -416.427091) (xy 170.486909 -416.473427) (xy 170.523207 -416.524618) (xy 170.55293 -416.579887)
			(xy 170.575627 -416.638393) (xy 170.590953 -416.699247) (xy 170.598674 -416.761524) (xy 170.598674 -416.824279)
			(xy 170.590952 -416.886556) (xy 170.575626 -416.94741) (xy 170.552929 -417.005916) (xy 170.523205 -417.061184)
			(xy 170.486907 -417.112376) (xy 170.444586 -417.158711) (xy 170.396885 -417.199488) (xy 170.344529 -417.234085)
			(xy 170.288314 -417.261977) (xy 170.229094 -417.28274) (xy 170.167769 -417.296059) (xy 170.136566 -417.299394)
			(xy 170.127468 -417.300605) (xy 170.110926 -417.30853) (xy 170.104308 -417.314888) (xy 170.083734 -417.336732)
			(xy 170.077354 -417.344054) (xy 170.070175 -417.362081) (xy 170.069764 -417.371784) (xy 170.069764 -417.605464)
			(xy 170.070214 -417.615249) (xy 170.077534 -417.6334) (xy 170.083988 -417.64077) (xy 170.10507 -417.66236)
			(xy 170.11187 -417.668762) (xy 170.128807 -417.676589) (xy 170.13809 -417.6776) (xy 170.172025 -417.680313)
			(xy 170.238942 -417.69284) (xy 170.303876 -417.713294) (xy 170.365892 -417.741381) (xy 170.424096 -417.776695)
			(xy 170.47765 -417.818728) (xy 170.502072 -417.842446) (xy 170.92422 -418.264848) (xy 170.931414 -418.271397)
			(xy 170.949309 -418.278988) (xy 170.959018 -418.27958) (xy 171.038774 -418.281612) (xy 171.056808 -418.275008)
			(xy 171.064174 -418.268404) (xy 171.085288 -418.250032) (xy 171.131888 -418.219038) (xy 171.18252 -418.195192)
			(xy 171.236095 -418.179006) (xy 171.291461 -418.170828) (xy 171.319444 -418.17036) (xy 171.346694 -418.170849)
			(xy 171.400639 -418.17861) (xy 171.45293 -418.193969) (xy 171.502504 -418.216612) (xy 171.548351 -418.246079)
			(xy 171.589538 -418.28177) (xy 171.625228 -418.322959) (xy 171.654694 -418.368807) (xy 171.677335 -418.418381)
			(xy 171.692692 -418.470673) (xy 171.700452 -418.524618) (xy 171.700952 -418.551868) (xy 171.700475 -418.579021)
			(xy 171.692775 -418.632779) (xy 171.677527 -418.6849) (xy 171.65504 -418.734332) (xy 171.625767 -418.780073)
			(xy 171.590301 -418.821199) (xy 171.570142 -418.839396) (xy 171.563988 -418.845127) (xy 171.555542 -418.859656)
			(xy 171.553632 -418.867844) (xy 171.548044 -418.897054) (xy 171.546747 -418.90555) (xy 171.54922 -418.922547)
			(xy 171.55287 -418.930328) (xy 171.568164 -418.960745) (xy 171.592191 -419.024449) (xy 171.60842 -419.090571)
			(xy 171.616617 -419.15816) (xy 171.617132 -419.192202) (xy 171.617132 -419.251087) (xy 177.902102 -419.251087)
			(xy 177.902102 -419.187165) (xy 177.910113 -419.123747) (xy 177.92601 -419.061833) (xy 177.949542 -419.0024)
			(xy 177.980336 -418.946385) (xy 178.017909 -418.89467) (xy 178.061666 -418.848073) (xy 178.110919 -418.807328)
			(xy 178.16489 -418.773077) (xy 178.222729 -418.74586) (xy 178.283522 -418.726107) (xy 178.346312 -418.714129)
			(xy 178.410108 -418.710116) (xy 178.473904 -418.714129) (xy 178.536694 -418.726107) (xy 178.597487 -418.74586)
			(xy 178.655326 -418.773077) (xy 178.709297 -418.807328) (xy 178.75855 -418.848073) (xy 178.802307 -418.89467)
			(xy 178.83988 -418.946385) (xy 178.870674 -419.0024) (xy 178.894206 -419.061833) (xy 178.910103 -419.123747)
			(xy 178.918114 -419.187165) (xy 178.918616 -419.219126) (xy 178.918114 -419.251087) (xy 178.910103 -419.314505)
			(xy 178.894206 -419.376419) (xy 178.870674 -419.435852) (xy 178.83988 -419.491867) (xy 178.802307 -419.543582)
			(xy 178.75855 -419.590179) (xy 178.709297 -419.630924) (xy 178.655326 -419.665175) (xy 178.597487 -419.692392)
			(xy 178.536694 -419.712145) (xy 178.473904 -419.724123) (xy 178.410108 -419.728137) (xy 178.346312 -419.724123)
			(xy 178.283522 -419.712145) (xy 178.222729 -419.692392) (xy 178.16489 -419.665175) (xy 178.110919 -419.630924)
			(xy 178.061666 -419.590179) (xy 178.017909 -419.543582) (xy 177.980336 -419.491867) (xy 177.949542 -419.435852)
			(xy 177.92601 -419.376419) (xy 177.910113 -419.314505) (xy 177.902102 -419.251087) (xy 171.617132 -419.251087)
			(xy 171.617132 -420.349172) (xy 178.894992 -420.349172) (xy 178.899063 -420.29355) (xy 178.911189 -420.239113)
			(xy 178.931112 -420.187022) (xy 178.958408 -420.138387) (xy 178.992494 -420.094244) (xy 179.032643 -420.055535)
			(xy 179.078001 -420.023084) (xy 179.127601 -419.997583) (xy 179.180385 -419.979576) (xy 179.235228 -419.969446)
			(xy 179.290962 -419.967409) (xy 179.346399 -419.973509) (xy 179.400356 -419.987615) (xy 179.451685 -420.009427)
			(xy 179.499291 -420.038481) (xy 179.542159 -420.074156) (xy 179.579376 -420.115693) (xy 179.610149 -420.162206)
			(xy 179.633821 -420.212703) (xy 179.649889 -420.26611) (xy 179.658009 -420.321286) (xy 179.658518 -420.349172)
			(xy 179.658476 -420.351458) (xy 179.899816 -420.351458) (xy 179.903887 -420.295836) (xy 179.916013 -420.241399)
			(xy 179.935936 -420.189308) (xy 179.963232 -420.140673) (xy 179.997318 -420.09653) (xy 180.037467 -420.057821)
			(xy 180.082825 -420.02537) (xy 180.132425 -419.999869) (xy 180.185209 -419.981862) (xy 180.240052 -419.971732)
			(xy 180.295786 -419.969695) (xy 180.351223 -419.975795) (xy 180.40518 -419.989901) (xy 180.456509 -420.011713)
			(xy 180.504115 -420.040767) (xy 180.546983 -420.076442) (xy 180.5842 -420.117979) (xy 180.614973 -420.164492)
			(xy 180.638645 -420.214989) (xy 180.654713 -420.268396) (xy 180.662833 -420.323572) (xy 180.663314 -420.349934)
			(xy 181.926228 -420.349934) (xy 181.930299 -420.294312) (xy 181.942425 -420.239875) (xy 181.962348 -420.187784)
			(xy 181.989644 -420.139149) (xy 182.02373 -420.095006) (xy 182.063879 -420.056297) (xy 182.109237 -420.023846)
			(xy 182.158837 -419.998345) (xy 182.211621 -419.980338) (xy 182.266464 -419.970208) (xy 182.322198 -419.968171)
			(xy 182.377635 -419.974271) (xy 182.431592 -419.988377) (xy 182.482921 -420.010189) (xy 182.530527 -420.039243)
			(xy 182.573395 -420.074918) (xy 182.610612 -420.116455) (xy 182.641385 -420.162968) (xy 182.665057 -420.213465)
			(xy 182.681125 -420.266872) (xy 182.689245 -420.322048) (xy 182.689754 -420.349934) (xy 182.689245 -420.37782)
			(xy 182.681125 -420.432996) (xy 182.665057 -420.486403) (xy 182.641385 -420.5369) (xy 182.610612 -420.583413)
			(xy 182.573395 -420.62495) (xy 182.530527 -420.660625) (xy 182.482921 -420.689679) (xy 182.431592 -420.711491)
			(xy 182.377635 -420.725597) (xy 182.322198 -420.731697) (xy 182.266464 -420.72966) (xy 182.211621 -420.71953)
			(xy 182.158837 -420.701523) (xy 182.109237 -420.676022) (xy 182.063879 -420.643571) (xy 182.02373 -420.604862)
			(xy 181.989644 -420.560719) (xy 181.962348 -420.512084) (xy 181.942425 -420.459993) (xy 181.930299 -420.405556)
			(xy 181.926228 -420.349934) (xy 180.663314 -420.349934) (xy 180.663342 -420.351458) (xy 180.662833 -420.379344)
			(xy 180.654713 -420.43452) (xy 180.638645 -420.487927) (xy 180.614973 -420.538424) (xy 180.5842 -420.584937)
			(xy 180.546983 -420.626474) (xy 180.504115 -420.662149) (xy 180.456509 -420.691203) (xy 180.40518 -420.713015)
			(xy 180.351223 -420.727121) (xy 180.295786 -420.733221) (xy 180.240052 -420.731184) (xy 180.185209 -420.721054)
			(xy 180.132425 -420.703047) (xy 180.082825 -420.677546) (xy 180.037467 -420.645095) (xy 179.997318 -420.606386)
			(xy 179.963232 -420.562243) (xy 179.935936 -420.513608) (xy 179.916013 -420.461517) (xy 179.903887 -420.40708)
			(xy 179.899816 -420.351458) (xy 179.658476 -420.351458) (xy 179.658009 -420.377058) (xy 179.649889 -420.432234)
			(xy 179.633821 -420.485641) (xy 179.610149 -420.536138) (xy 179.579376 -420.582651) (xy 179.542159 -420.624188)
			(xy 179.499291 -420.659863) (xy 179.451685 -420.688917) (xy 179.400356 -420.710729) (xy 179.346399 -420.724835)
			(xy 179.290962 -420.730935) (xy 179.235228 -420.728898) (xy 179.180385 -420.718768) (xy 179.127601 -420.700761)
			(xy 179.078001 -420.67526) (xy 179.032643 -420.642809) (xy 178.992494 -420.6041) (xy 178.958408 -420.559957)
			(xy 178.931112 -420.511322) (xy 178.911189 -420.459231) (xy 178.899063 -420.404794) (xy 178.894992 -420.349172)
			(xy 171.617132 -420.349172) (xy 171.617132 -420.553388) (xy 171.616702 -420.5852) (xy 171.609575 -420.648423)
			(xy 171.59541 -420.71045) (xy 171.574385 -420.770499) (xy 171.546764 -420.827815) (xy 171.512896 -420.881675)
			(xy 171.492313 -420.907464) (xy 173.080932 -420.907464) (xy 173.085003 -420.851842) (xy 173.097129 -420.797405)
			(xy 173.117052 -420.745314) (xy 173.144348 -420.696679) (xy 173.178434 -420.652536) (xy 173.218583 -420.613827)
			(xy 173.263941 -420.581376) (xy 173.313541 -420.555875) (xy 173.366325 -420.537868) (xy 173.421168 -420.527738)
			(xy 173.476902 -420.525701) (xy 173.532339 -420.531801) (xy 173.586296 -420.545907) (xy 173.637625 -420.567719)
			(xy 173.685231 -420.596773) (xy 173.728099 -420.632448) (xy 173.765316 -420.673985) (xy 173.796089 -420.720498)
			(xy 173.819761 -420.770995) (xy 173.835829 -420.824402) (xy 173.843949 -420.879578) (xy 173.844458 -420.907464)
			(xy 173.843949 -420.93535) (xy 173.835829 -420.990526) (xy 173.819761 -421.043933) (xy 173.796089 -421.09443)
			(xy 173.765316 -421.140943) (xy 173.728099 -421.18248) (xy 173.685231 -421.218155) (xy 173.637625 -421.247209)
			(xy 173.586296 -421.269021) (xy 173.532339 -421.283127) (xy 173.476902 -421.289227) (xy 173.421168 -421.28719)
			(xy 173.366325 -421.27706) (xy 173.313541 -421.259053) (xy 173.263941 -421.233552) (xy 173.218583 -421.201101)
			(xy 173.178434 -421.162392) (xy 173.144348 -421.118249) (xy 173.117052 -421.069614) (xy 173.097129 -421.017523)
			(xy 173.085003 -420.963086) (xy 173.080932 -420.907464) (xy 171.492313 -420.907464) (xy 171.473207 -420.931402)
			(xy 171.451016 -420.9542) (xy 170.087544 -422.317672) (xy 170.681902 -422.317672) (xy 170.685973 -422.26205)
			(xy 170.698099 -422.207613) (xy 170.718022 -422.155522) (xy 170.745318 -422.106887) (xy 170.779404 -422.062744)
			(xy 170.819553 -422.024035) (xy 170.864911 -421.991584) (xy 170.914511 -421.966083) (xy 170.967295 -421.948076)
			(xy 171.022138 -421.937946) (xy 171.077872 -421.935909) (xy 171.133309 -421.942009) (xy 171.187266 -421.956115)
			(xy 171.238595 -421.977927) (xy 171.286201 -422.006981) (xy 171.329069 -422.042656) (xy 171.366286 -422.084193)
			(xy 171.397059 -422.130706) (xy 171.420731 -422.181203) (xy 171.436799 -422.23461) (xy 171.444919 -422.289786)
			(xy 171.445428 -422.317672) (xy 171.444919 -422.345558) (xy 171.439871 -422.379859) (xy 171.733712 -422.379859)
			(xy 171.733712 -422.315937) (xy 171.741723 -422.252519) (xy 171.75762 -422.190605) (xy 171.781152 -422.131172)
			(xy 171.811946 -422.075157) (xy 171.849519 -422.023442) (xy 171.893276 -421.976845) (xy 171.942529 -421.9361)
			(xy 171.9965 -421.901849) (xy 172.054339 -421.874632) (xy 172.115132 -421.854879) (xy 172.177922 -421.842901)
			(xy 172.241718 -421.838888) (xy 172.305514 -421.842901) (xy 172.368304 -421.854879) (xy 172.429097 -421.874632)
			(xy 172.486936 -421.901849) (xy 172.540907 -421.9361) (xy 172.59016 -421.976845) (xy 172.591339 -421.9781)
			(xy 176.656763 -421.9781) (xy 176.660777 -421.914304) (xy 176.672754 -421.851514) (xy 176.692506 -421.79072)
			(xy 176.719722 -421.73288) (xy 176.753972 -421.678908) (xy 176.794716 -421.629654) (xy 176.841312 -421.585894)
			(xy 176.893024 -421.548319) (xy 176.949038 -421.517522) (xy 177.00847 -421.493987) (xy 177.070383 -421.478086)
			(xy 177.133801 -421.47007) (xy 177.165762 -421.469566) (xy 177.198261 -421.470117) (xy 177.262729 -421.478401)
			(xy 177.325617 -421.494826) (xy 177.385902 -421.519125) (xy 177.442602 -421.550903) (xy 177.494794 -421.589642)
			(xy 177.518568 -421.611806) (xy 177.525399 -421.617916) (xy 177.542206 -421.625197) (xy 177.551334 -421.62603)
			(xy 177.581814 -421.6273) (xy 177.591001 -421.627295) (xy 177.608443 -421.62156) (xy 177.61585 -421.616124)
			(xy 177.643041 -421.595049) (xy 177.702022 -421.559637) (xy 177.765241 -421.532507) (xy 177.831543 -421.514153)
			(xy 177.899714 -421.504914) (xy 177.934112 -421.504364) (xy 177.964842 -421.504845) (xy 178.025854 -421.512254)
			(xy 178.085529 -421.526963) (xy 178.142995 -421.548758) (xy 178.197415 -421.57732) (xy 178.247996 -421.612233)
			(xy 178.294001 -421.652988) (xy 178.334757 -421.698991) (xy 178.369672 -421.749571) (xy 178.398236 -421.803991)
			(xy 178.420032 -421.861456) (xy 178.434743 -421.92113) (xy 178.442154 -421.982142) (xy 178.44262 -422.012872)
			(xy 178.44262 -422.01338) (xy 178.443037 -422.023402) (xy 178.450704 -422.041923) (xy 178.464877 -422.056096)
			(xy 178.483398 -422.063763) (xy 178.49342 -422.06418) (xy 178.499262 -422.06418) (xy 178.510438 -422.06164)
			(xy 178.515518 -422.0591) (xy 178.541614 -422.047009) (xy 178.596527 -422.029912) (xy 178.653386 -422.021269)
			(xy 178.682142 -422.020746) (xy 178.709388 -422.021327) (xy 178.763325 -422.029087) (xy 178.815608 -422.044444)
			(xy 178.865174 -422.067085) (xy 178.911013 -422.096549) (xy 178.952194 -422.132236) (xy 178.987876 -422.17342)
			(xy 179.017335 -422.219263) (xy 179.03997 -422.268831) (xy 179.055321 -422.321116) (xy 179.063076 -422.375054)
			(xy 179.063076 -422.429546) (xy 179.055321 -422.483483) (xy 179.03997 -422.535769) (xy 179.017335 -422.585337)
			(xy 178.987876 -422.63118) (xy 178.952194 -422.672364) (xy 178.911013 -422.708051) (xy 178.865174 -422.737515)
			(xy 178.815608 -422.760156) (xy 178.763325 -422.775513) (xy 178.709388 -422.783273) (xy 178.682142 -422.783762)
			(xy 178.655452 -422.783307) (xy 178.602593 -422.775879) (xy 178.551287 -422.761148) (xy 178.502539 -422.739403)
			(xy 178.457301 -422.711069) (xy 178.416459 -422.6767) (xy 178.380812 -422.636968) (xy 178.351057 -422.592652)
			(xy 178.327777 -422.544617) (xy 178.319176 -422.519348) (xy 178.31562 -422.50868) (xy 178.300126 -422.49217)
			(xy 178.206908 -422.454578) (xy 178.184302 -422.455594) (xy 178.174396 -422.460928) (xy 178.146594 -422.475305)
			(xy 178.088223 -422.497901) (xy 178.027522 -422.51317) (xy 177.965408 -422.520882) (xy 177.934112 -422.52138)
			(xy 177.901612 -422.520861) (xy 177.837142 -422.512572) (xy 177.774253 -422.496142) (xy 177.713968 -422.471837)
			(xy 177.657268 -422.440053) (xy 177.605078 -422.401308) (xy 177.581306 -422.37914) (xy 177.574446 -422.373066)
			(xy 177.557662 -422.365763) (xy 177.54854 -422.364916) (xy 177.51806 -422.363646) (xy 177.508873 -422.363649)
			(xy 177.491432 -422.369386) (xy 177.484024 -422.374822) (xy 177.456847 -422.395915) (xy 177.397861 -422.431323)
			(xy 177.334639 -422.458449) (xy 177.268334 -422.476798) (xy 177.200161 -422.486034) (xy 177.165762 -422.486582)
			(xy 177.133801 -422.48613) (xy 177.070383 -422.478114) (xy 177.00847 -422.462213) (xy 176.949038 -422.438678)
			(xy 176.893024 -422.407881) (xy 176.841312 -422.370306) (xy 176.794716 -422.326546) (xy 176.753972 -422.277292)
			(xy 176.719722 -422.22332) (xy 176.692506 -422.16548) (xy 176.672754 -422.104686) (xy 176.660777 -422.041896)
			(xy 176.656763 -421.9781) (xy 172.591339 -421.9781) (xy 172.633917 -422.023442) (xy 172.67149 -422.075157)
			(xy 172.702284 -422.131172) (xy 172.725816 -422.190605) (xy 172.741713 -422.252519) (xy 172.749724 -422.315937)
			(xy 172.750226 -422.347898) (xy 172.749724 -422.379859) (xy 172.741713 -422.443277) (xy 172.725816 -422.505191)
			(xy 172.702284 -422.564624) (xy 172.67149 -422.620639) (xy 172.633917 -422.672354) (xy 172.59016 -422.718951)
			(xy 172.540907 -422.759696) (xy 172.486936 -422.793947) (xy 172.429097 -422.821164) (xy 172.368304 -422.840917)
			(xy 172.305514 -422.852895) (xy 172.241718 -422.856909) (xy 172.177922 -422.852895) (xy 172.115132 -422.840917)
			(xy 172.054339 -422.821164) (xy 171.9965 -422.793947) (xy 171.942529 -422.759696) (xy 171.893276 -422.718951)
			(xy 171.849519 -422.672354) (xy 171.811946 -422.620639) (xy 171.781152 -422.564624) (xy 171.75762 -422.505191)
			(xy 171.741723 -422.443277) (xy 171.733712 -422.379859) (xy 171.439871 -422.379859) (xy 171.436799 -422.400734)
			(xy 171.420731 -422.454141) (xy 171.397059 -422.504638) (xy 171.366286 -422.551151) (xy 171.329069 -422.592688)
			(xy 171.286201 -422.628363) (xy 171.238595 -422.657417) (xy 171.187266 -422.679229) (xy 171.133309 -422.693335)
			(xy 171.077872 -422.699435) (xy 171.022138 -422.697398) (xy 170.967295 -422.687268) (xy 170.914511 -422.669261)
			(xy 170.864911 -422.64376) (xy 170.819553 -422.611309) (xy 170.779404 -422.5726) (xy 170.745318 -422.528457)
			(xy 170.718022 -422.479822) (xy 170.698099 -422.427731) (xy 170.685973 -422.373294) (xy 170.681902 -422.317672)
			(xy 170.087544 -422.317672) (xy 170.08475 -422.320466) (xy 170.077908 -422.327866) (xy 170.07019 -422.346464)
			(xy 170.069764 -422.356534) (xy 170.069764 -425.331847) (xy 170.52518 -425.331847) (xy 170.52518 -425.267925)
			(xy 170.533191 -425.204507) (xy 170.549088 -425.142593) (xy 170.57262 -425.08316) (xy 170.603414 -425.027145)
			(xy 170.640987 -424.97543) (xy 170.684744 -424.928833) (xy 170.733997 -424.888088) (xy 170.787968 -424.853837)
			(xy 170.845807 -424.82662) (xy 170.9066 -424.806867) (xy 170.96939 -424.794889) (xy 171.033186 -424.790876)
			(xy 171.096982 -424.794889) (xy 171.159772 -424.806867) (xy 171.220565 -424.82662) (xy 171.278404 -424.853837)
			(xy 171.332375 -424.888088) (xy 171.381628 -424.928833) (xy 171.425385 -424.97543) (xy 171.462958 -425.027145)
			(xy 171.493752 -425.08316) (xy 171.517284 -425.142593) (xy 171.533181 -425.204507) (xy 171.541192 -425.267925)
			(xy 171.541694 -425.299886) (xy 171.541192 -425.331847) (xy 171.533181 -425.395265) (xy 171.517284 -425.457179)
			(xy 171.493752 -425.516612) (xy 171.487085 -425.52874) (xy 173.642782 -425.52874) (xy 173.643221 -425.498279)
			(xy 173.650497 -425.437792) (xy 173.664948 -425.378608) (xy 173.686369 -425.321576) (xy 173.714452 -425.267512)
			(xy 173.748794 -425.217191) (xy 173.768512 -425.193968) (xy 173.774023 -425.187117) (xy 173.780381 -425.170738)
			(xy 173.780958 -425.161964) (xy 173.781974 -425.132246) (xy 173.781889 -425.123424) (xy 173.776429 -425.106662)
			(xy 173.771306 -425.09948) (xy 173.751094 -425.072598) (xy 173.717135 -425.014547) (xy 173.691131 -424.952522)
			(xy 173.673538 -424.887609) (xy 173.664663 -424.820942) (xy 173.664118 -424.787314) (xy 173.664582 -424.755594)
			(xy 173.672477 -424.692646) (xy 173.688145 -424.631171) (xy 173.711343 -424.572124) (xy 173.741709 -424.516423)
			(xy 173.778773 -424.464935) (xy 173.800008 -424.441366) (xy 173.806029 -424.434155) (xy 173.81294 -424.416708)
			(xy 173.81347 -424.40733) (xy 173.813724 -424.376342) (xy 173.813349 -424.36694) (xy 173.806705 -424.349353)
			(xy 173.80077 -424.342052) (xy 173.780496 -424.318675) (xy 173.745138 -424.267889) (xy 173.716202 -424.21319)
			(xy 173.694116 -424.155384) (xy 173.679206 -424.095326) (xy 173.671691 -424.033903) (xy 173.67123 -424.002962)
			(xy 173.671732 -423.971001) (xy 173.679743 -423.907583) (xy 173.69564 -423.845669) (xy 173.719172 -423.786236)
			(xy 173.749966 -423.730221) (xy 173.787539 -423.678506) (xy 173.831296 -423.631909) (xy 173.880549 -423.591164)
			(xy 173.93452 -423.556913) (xy 173.992359 -423.529696) (xy 174.053152 -423.509943) (xy 174.115942 -423.497965)
			(xy 174.179738 -423.493952) (xy 174.243534 -423.497965) (xy 174.306324 -423.509943) (xy 174.367117 -423.529696)
			(xy 174.424956 -423.556913) (xy 174.478927 -423.591164) (xy 174.52818 -423.631909) (xy 174.571937 -423.678506)
			(xy 174.60951 -423.730221) (xy 174.640304 -423.786236) (xy 174.663836 -423.845669) (xy 174.664269 -423.847355)
			(xy 190.380537 -423.847355) (xy 190.380537 -423.792845) (xy 190.388295 -423.73889) (xy 190.403653 -423.686588)
			(xy 190.426298 -423.637004) (xy 190.455769 -423.591147) (xy 190.491466 -423.549952) (xy 190.532664 -423.514257)
			(xy 190.578521 -423.484788) (xy 190.628106 -423.462146) (xy 190.680409 -423.446791) (xy 190.734365 -423.439036)
			(xy 190.76162 -423.438574) (xy 190.790085 -423.439068) (xy 190.846385 -423.447525) (xy 190.900804 -423.46425)
			(xy 190.952136 -423.488871) (xy 190.999242 -423.520841) (xy 191.041078 -423.559453) (xy 191.059308 -423.581322)
			(xy 191.065658 -423.58945) (xy 191.083438 -423.599102) (xy 191.175386 -423.608754) (xy 191.19469 -423.603166)
			(xy 191.202564 -423.596562) (xy 191.229885 -423.575066) (xy 191.289277 -423.538935) (xy 191.353041 -423.51124)
			(xy 191.419985 -423.4925) (xy 191.48886 -423.483063) (xy 191.52362 -423.482516) (xy 191.554353 -423.482919)
			(xy 191.615372 -423.49033) (xy 191.675052 -423.505043) (xy 191.732524 -423.526842) (xy 191.786949 -423.555409)
			(xy 191.837534 -423.590328) (xy 191.883541 -423.63109) (xy 191.924299 -423.677101) (xy 191.959214 -423.727689)
			(xy 191.987776 -423.782116) (xy 192.002173 -423.820082) (xy 193.173602 -423.820082) (xy 193.177673 -423.76446)
			(xy 193.189799 -423.710023) (xy 193.209722 -423.657932) (xy 193.237018 -423.609297) (xy 193.271104 -423.565154)
			(xy 193.311253 -423.526445) (xy 193.356611 -423.493994) (xy 193.406211 -423.468493) (xy 193.458995 -423.450486)
			(xy 193.513838 -423.440356) (xy 193.569572 -423.438319) (xy 193.625009 -423.444419) (xy 193.678966 -423.458525)
			(xy 193.730295 -423.480337) (xy 193.777901 -423.509391) (xy 193.820769 -423.545066) (xy 193.857986 -423.586603)
			(xy 193.888759 -423.633116) (xy 193.912431 -423.683613) (xy 193.928499 -423.73702) (xy 193.936619 -423.792196)
			(xy 193.937128 -423.820082) (xy 193.936619 -423.847968) (xy 193.928499 -423.903144) (xy 193.912431 -423.956551)
			(xy 193.888759 -424.007048) (xy 193.857986 -424.053561) (xy 193.820769 -424.095098) (xy 193.777901 -424.130773)
			(xy 193.730295 -424.159827) (xy 193.678966 -424.181639) (xy 193.625009 -424.195745) (xy 193.569572 -424.201845)
			(xy 193.513838 -424.199808) (xy 193.458995 -424.189678) (xy 193.406211 -424.171671) (xy 193.356611 -424.14617)
			(xy 193.311253 -424.113719) (xy 193.271104 -424.07501) (xy 193.237018 -424.030867) (xy 193.209722 -423.982232)
			(xy 193.189799 -423.930141) (xy 193.177673 -423.875704) (xy 193.173602 -423.820082) (xy 192.002173 -423.820082)
			(xy 192.00957 -423.83959) (xy 192.024278 -423.899271) (xy 192.031684 -423.960291) (xy 192.032128 -423.991024)
			(xy 192.031706 -424.020827) (xy 192.024726 -424.080023) (xy 192.010876 -424.137998) (xy 191.990346 -424.193958)
			(xy 191.963417 -424.247134) (xy 191.947292 -424.272202) (xy 191.940688 -424.282108) (xy 191.93764 -424.305222)
			(xy 191.970914 -424.404028) (xy 191.987424 -424.420538) (xy 191.9986 -424.424348) (xy 192.023261 -424.433298)
			(xy 192.070009 -424.457111) (xy 192.113053 -424.487106) (xy 192.15158 -424.522718) (xy 192.184862 -424.563273)
			(xy 192.212273 -424.608007) (xy 192.233294 -424.656076) (xy 192.247529 -424.706572) (xy 192.254709 -424.758542)
			(xy 192.25514 -424.784774) (xy 192.254654 -424.812025) (xy 192.246898 -424.865973) (xy 192.231543 -424.918268)
			(xy 192.208901 -424.967845) (xy 192.179435 -425.013695) (xy 192.143744 -425.054886) (xy 192.102553 -425.090577)
			(xy 192.056703 -425.120043) (xy 192.007126 -425.142685) (xy 191.954831 -425.15804) (xy 191.900883 -425.165796)
			(xy 191.846381 -425.165796) (xy 191.792433 -425.15804) (xy 191.740138 -425.142685) (xy 191.690561 -425.120043)
			(xy 191.644711 -425.090577) (xy 191.60352 -425.054886) (xy 191.567829 -425.013695) (xy 191.538363 -424.967845)
			(xy 191.515721 -424.918268) (xy 191.500366 -424.865973) (xy 191.49261 -424.812025) (xy 191.492124 -424.784774)
			(xy 191.492538 -424.758915) (xy 191.499488 -424.707666) (xy 191.513299 -424.657827) (xy 191.523112 -424.633898)
			(xy 191.527938 -424.622976) (xy 191.526668 -424.599862) (xy 191.476376 -424.508676) (xy 191.457326 -424.495214)
			(xy 191.445388 -424.493436) (xy 191.414971 -424.488306) (xy 191.355612 -424.471519) (xy 191.298721 -424.447672)
			(xy 191.245133 -424.417116) (xy 191.195637 -424.3803) (xy 191.15096 -424.337764) (xy 191.111759 -424.290134)
			(xy 191.078609 -424.238111) (xy 191.064896 -424.21048) (xy 191.060578 -424.201336) (xy 191.045592 -424.187874)
			(xy 190.957962 -424.157394) (xy 190.937896 -424.158664) (xy 190.928752 -424.162982) (xy 190.902589 -424.175155)
			(xy 190.847513 -424.192364) (xy 190.790471 -424.201063) (xy 190.76162 -424.20159) (xy 190.734365 -424.201164)
			(xy 190.680409 -424.193409) (xy 190.628106 -424.178054) (xy 190.578521 -424.155412) (xy 190.532664 -424.125943)
			(xy 190.491466 -424.090248) (xy 190.455769 -424.049053) (xy 190.426298 -424.003196) (xy 190.403653 -423.953612)
			(xy 190.388295 -423.90131) (xy 190.380537 -423.847355) (xy 174.664269 -423.847355) (xy 174.679733 -423.907583)
			(xy 174.687744 -423.971001) (xy 174.688246 -424.002962) (xy 174.687777 -424.034682) (xy 174.679884 -424.09763)
			(xy 174.664218 -424.159106) (xy 174.641021 -424.218153) (xy 174.610655 -424.273854) (xy 174.573591 -424.325341)
			(xy 174.552356 -424.34891) (xy 174.546299 -424.356094) (xy 174.53941 -424.373562) (xy 174.538894 -424.382946)
			(xy 174.53864 -424.413934) (xy 174.539035 -424.423334) (xy 174.545666 -424.44092) (xy 174.551594 -424.448224)
			(xy 174.571899 -424.471576) (xy 174.607254 -424.522367) (xy 174.636186 -424.577071) (xy 174.658267 -424.634882)
			(xy 174.673171 -424.694945) (xy 174.680677 -424.756372) (xy 174.681134 -424.787314) (xy 174.680664 -424.817774)
			(xy 174.673394 -424.87826) (xy 174.658948 -424.937443) (xy 174.637533 -424.994475) (xy 174.609456 -425.04854)
			(xy 174.575119 -425.098862) (xy 174.555404 -425.122086) (xy 174.549914 -425.128951) (xy 174.543544 -425.145319)
			(xy 174.542958 -425.15409) (xy 174.542046 -425.18076) (xy 175.635412 -425.18076) (xy 175.635857 -425.150329)
			(xy 175.643131 -425.089904) (xy 175.657559 -425.030777) (xy 175.678935 -424.973793) (xy 175.706954 -424.919765)
			(xy 175.741215 -424.869463) (xy 175.760888 -424.846242) (xy 175.766301 -424.839554) (xy 175.772662 -424.823578)
			(xy 175.773334 -424.815) (xy 175.774604 -424.785536) (xy 175.774551 -424.777) (xy 175.769638 -424.760666)
			(xy 175.764952 -424.753532) (xy 175.746553 -424.727386) (xy 175.715761 -424.671356) (xy 175.692242 -424.611906)
			(xy 175.676366 -424.549975) (xy 175.668386 -424.486541) (xy 175.667924 -424.454574) (xy 175.668426 -424.422613)
			(xy 175.676437 -424.359195) (xy 175.692334 -424.297281) (xy 175.715866 -424.237848) (xy 175.74666 -424.181833)
			(xy 175.784233 -424.130118) (xy 175.82799 -424.083521) (xy 175.877243 -424.042776) (xy 175.931214 -424.008525)
			(xy 175.989053 -423.981308) (xy 176.049846 -423.961555) (xy 176.112636 -423.949577) (xy 176.176432 -423.945564)
			(xy 176.240228 -423.949577) (xy 176.303018 -423.961555) (xy 176.363811 -423.981308) (xy 176.42165 -424.008525)
			(xy 176.475621 -424.042776) (xy 176.524874 -424.083521) (xy 176.568631 -424.130118) (xy 176.606204 -424.181833)
			(xy 176.636998 -424.237848) (xy 176.66053 -424.297281) (xy 176.676427 -424.359195) (xy 176.684438 -424.422613)
			(xy 176.68494 -424.454574) (xy 176.684468 -424.485004) (xy 176.677201 -424.545429) (xy 176.662779 -424.604555)
			(xy 176.641408 -424.66154) (xy 176.613394 -424.715569) (xy 176.579135 -424.765871) (xy 176.559464 -424.789092)
			(xy 176.554043 -424.795775) (xy 176.547686 -424.811754) (xy 176.547018 -424.820334) (xy 176.545748 -424.849798)
			(xy 176.545777 -424.858336) (xy 176.550706 -424.87467) (xy 176.5554 -424.881802) (xy 176.57382 -424.907933)
			(xy 176.604607 -424.963968) (xy 176.628122 -425.023422) (xy 176.643993 -425.085356) (xy 176.651968 -425.148792)
			(xy 176.652428 -425.18076) (xy 176.651926 -425.212721) (xy 176.643915 -425.276139) (xy 176.628018 -425.338053)
			(xy 176.604486 -425.397486) (xy 176.590023 -425.423795) (xy 189.54851 -425.423795) (xy 189.54851 -425.359873)
			(xy 189.556521 -425.296455) (xy 189.572418 -425.234541) (xy 189.59595 -425.175108) (xy 189.626744 -425.119093)
			(xy 189.664317 -425.067378) (xy 189.708074 -425.020781) (xy 189.757327 -424.980036) (xy 189.811298 -424.945785)
			(xy 189.869137 -424.918568) (xy 189.92993 -424.898815) (xy 189.99272 -424.886837) (xy 190.056516 -424.882824)
			(xy 190.120312 -424.886837) (xy 190.183102 -424.898815) (xy 190.243895 -424.918568) (xy 190.301734 -424.945785)
			(xy 190.355705 -424.980036) (xy 190.404958 -425.020781) (xy 190.448715 -425.067378) (xy 190.486288 -425.119093)
			(xy 190.517082 -425.175108) (xy 190.540614 -425.234541) (xy 190.556511 -425.296455) (xy 190.564522 -425.359873)
			(xy 190.565024 -425.391834) (xy 190.564522 -425.423795) (xy 190.556511 -425.487213) (xy 190.540614 -425.549127)
			(xy 190.517082 -425.60856) (xy 190.486288 -425.664575) (xy 190.448715 -425.71629) (xy 190.404958 -425.762887)
			(xy 190.355705 -425.803632) (xy 190.301734 -425.837883) (xy 190.243895 -425.8651) (xy 190.183102 -425.884853)
			(xy 190.120312 -425.896831) (xy 190.056516 -425.900845) (xy 189.99272 -425.896831) (xy 189.92993 -425.884853)
			(xy 189.869137 -425.8651) (xy 189.811298 -425.837883) (xy 189.757327 -425.803632) (xy 189.708074 -425.762887)
			(xy 189.664317 -425.71629) (xy 189.626744 -425.664575) (xy 189.59595 -425.60856) (xy 189.572418 -425.549127)
			(xy 189.556521 -425.487213) (xy 189.54851 -425.423795) (xy 176.590023 -425.423795) (xy 176.573692 -425.453501)
			(xy 176.536119 -425.505216) (xy 176.492362 -425.551813) (xy 176.443109 -425.592558) (xy 176.389138 -425.626809)
			(xy 176.331299 -425.654026) (xy 176.270506 -425.673779) (xy 176.207716 -425.685757) (xy 176.14392 -425.689771)
			(xy 176.080124 -425.685757) (xy 176.017334 -425.673779) (xy 175.956541 -425.654026) (xy 175.898702 -425.626809)
			(xy 175.844731 -425.592558) (xy 175.795478 -425.551813) (xy 175.751721 -425.505216) (xy 175.714148 -425.453501)
			(xy 175.683354 -425.397486) (xy 175.659822 -425.338053) (xy 175.643925 -425.276139) (xy 175.635914 -425.212721)
			(xy 175.635412 -425.18076) (xy 174.542046 -425.18076) (xy 174.541942 -425.183808) (xy 174.542046 -425.192629)
			(xy 174.547493 -425.20939) (xy 174.55261 -425.216574) (xy 174.572849 -425.243436) (xy 174.606803 -425.301494)
			(xy 174.632801 -425.363523) (xy 174.650388 -425.428441) (xy 174.659256 -425.495111) (xy 174.659798 -425.52874)
			(xy 174.659296 -425.560701) (xy 174.651285 -425.624119) (xy 174.635388 -425.686033) (xy 174.611856 -425.745466)
			(xy 174.581062 -425.801481) (xy 174.543489 -425.853196) (xy 174.499732 -425.899793) (xy 174.450479 -425.940538)
			(xy 174.396508 -425.974789) (xy 174.338669 -426.002006) (xy 174.277876 -426.021759) (xy 174.215086 -426.033737)
			(xy 174.15129 -426.037751) (xy 174.087494 -426.033737) (xy 174.024704 -426.021759) (xy 173.963911 -426.002006)
			(xy 173.906072 -425.974789) (xy 173.852101 -425.940538) (xy 173.802848 -425.899793) (xy 173.759091 -425.853196)
			(xy 173.721518 -425.801481) (xy 173.690724 -425.745466) (xy 173.667192 -425.686033) (xy 173.651295 -425.624119)
			(xy 173.643284 -425.560701) (xy 173.642782 -425.52874) (xy 171.487085 -425.52874) (xy 171.462958 -425.572627)
			(xy 171.425385 -425.624342) (xy 171.381628 -425.670939) (xy 171.332375 -425.711684) (xy 171.278404 -425.745935)
			(xy 171.220565 -425.773152) (xy 171.159772 -425.792905) (xy 171.096982 -425.804883) (xy 171.033186 -425.808897)
			(xy 170.96939 -425.804883) (xy 170.9066 -425.792905) (xy 170.845807 -425.773152) (xy 170.787968 -425.745935)
			(xy 170.733997 -425.711684) (xy 170.684744 -425.670939) (xy 170.640987 -425.624342) (xy 170.603414 -425.572627)
			(xy 170.57262 -425.516612) (xy 170.549088 -425.457179) (xy 170.533191 -425.395265) (xy 170.52518 -425.331847)
			(xy 170.069764 -425.331847) (xy 170.069764 -425.717716) (xy 170.069337 -425.727784) (xy 170.061615 -425.746381)
			(xy 170.054778 -425.753784) (xy 169.619676 -426.188886) (xy 187.163962 -426.188886) (xy 187.168033 -426.133264)
			(xy 187.180159 -426.078827) (xy 187.200082 -426.026736) (xy 187.227378 -425.978101) (xy 187.261464 -425.933958)
			(xy 187.301613 -425.895249) (xy 187.346971 -425.862798) (xy 187.396571 -425.837297) (xy 187.449355 -425.81929)
			(xy 187.504198 -425.80916) (xy 187.559932 -425.807123) (xy 187.615369 -425.813223) (xy 187.669326 -425.827329)
			(xy 187.720655 -425.849141) (xy 187.768261 -425.878195) (xy 187.811129 -425.91387) (xy 187.848346 -425.955407)
			(xy 187.879119 -426.00192) (xy 187.902791 -426.052417) (xy 187.918859 -426.105824) (xy 187.926979 -426.161)
			(xy 187.927488 -426.188886) (xy 187.926979 -426.216772) (xy 187.918859 -426.271948) (xy 187.902791 -426.325355)
			(xy 187.879119 -426.375852) (xy 187.848346 -426.422365) (xy 187.811129 -426.463902) (xy 187.768261 -426.499577)
			(xy 187.720655 -426.528631) (xy 187.669326 -426.550443) (xy 187.615369 -426.564549) (xy 187.559932 -426.570649)
			(xy 187.504198 -426.568612) (xy 187.449355 -426.558482) (xy 187.396571 -426.540475) (xy 187.346971 -426.514974)
			(xy 187.301613 -426.482523) (xy 187.261464 -426.443814) (xy 187.227378 -426.399671) (xy 187.200082 -426.351036)
			(xy 187.180159 -426.298945) (xy 187.168033 -426.244508) (xy 187.163962 -426.188886) (xy 169.619676 -426.188886)
			(xy 169.217383 -426.591179) (xy 189.588896 -426.591179) (xy 189.588896 -426.527257) (xy 189.596907 -426.463839)
			(xy 189.612804 -426.401925) (xy 189.636336 -426.342492) (xy 189.66713 -426.286477) (xy 189.704703 -426.234762)
			(xy 189.74846 -426.188165) (xy 189.797713 -426.14742) (xy 189.851684 -426.113169) (xy 189.909523 -426.085952)
			(xy 189.970316 -426.066199) (xy 190.033106 -426.054221) (xy 190.096902 -426.050208) (xy 190.160698 -426.054221)
			(xy 190.223488 -426.066199) (xy 190.284281 -426.085952) (xy 190.34212 -426.113169) (xy 190.396091 -426.14742)
			(xy 190.445344 -426.188165) (xy 190.489101 -426.234762) (xy 190.526674 -426.286477) (xy 190.557468 -426.342492)
			(xy 190.581 -426.401925) (xy 190.596897 -426.463839) (xy 190.604908 -426.527257) (xy 190.60541 -426.559218)
			(xy 190.604908 -426.591179) (xy 190.596897 -426.654597) (xy 190.581 -426.716511) (xy 190.557468 -426.775944)
			(xy 190.526674 -426.831959) (xy 190.489101 -426.883674) (xy 190.445344 -426.930271) (xy 190.396091 -426.971016)
			(xy 190.34212 -427.005267) (xy 190.284281 -427.032484) (xy 190.223488 -427.052237) (xy 190.160698 -427.064215)
			(xy 190.096902 -427.068229) (xy 190.033106 -427.064215) (xy 189.970316 -427.052237) (xy 189.909523 -427.032484)
			(xy 189.851684 -427.005267) (xy 189.797713 -426.971016) (xy 189.74846 -426.930271) (xy 189.704703 -426.883674)
			(xy 189.66713 -426.831959) (xy 189.636336 -426.775944) (xy 189.612804 -426.716511) (xy 189.596907 -426.654597)
			(xy 189.588896 -426.591179) (xy 169.217383 -426.591179) (xy 168.514776 -427.293786) (xy 173.731172 -427.293786)
			(xy 173.735243 -427.238164) (xy 173.747369 -427.183727) (xy 173.767292 -427.131636) (xy 173.794588 -427.083001)
			(xy 173.828674 -427.038858) (xy 173.868823 -427.000149) (xy 173.914181 -426.967698) (xy 173.963781 -426.942197)
			(xy 174.016565 -426.92419) (xy 174.071408 -426.91406) (xy 174.127142 -426.912023) (xy 174.182579 -426.918123)
			(xy 174.236536 -426.932229) (xy 174.287865 -426.954041) (xy 174.335471 -426.983095) (xy 174.378339 -427.01877)
			(xy 174.415556 -427.060307) (xy 174.446329 -427.10682) (xy 174.470001 -427.157317) (xy 174.486069 -427.210724)
			(xy 174.494189 -427.2659) (xy 174.494698 -427.293786) (xy 174.494605 -427.298866) (xy 180.555898 -427.298866)
			(xy 180.559969 -427.243244) (xy 180.572095 -427.188807) (xy 180.592018 -427.136716) (xy 180.619314 -427.088081)
			(xy 180.6534 -427.043938) (xy 180.693549 -427.005229) (xy 180.738907 -426.972778) (xy 180.788507 -426.947277)
			(xy 180.841291 -426.92927) (xy 180.896134 -426.91914) (xy 180.951868 -426.917103) (xy 181.007305 -426.923203)
			(xy 181.061262 -426.937309) (xy 181.112591 -426.959121) (xy 181.160197 -426.988175) (xy 181.203065 -427.02385)
			(xy 181.240282 -427.065387) (xy 181.271055 -427.1119) (xy 181.294727 -427.162397) (xy 181.310795 -427.215804)
			(xy 181.318915 -427.27098) (xy 181.319424 -427.298866) (xy 181.318915 -427.326752) (xy 181.310795 -427.381928)
			(xy 181.294727 -427.435335) (xy 181.29097 -427.443349) (xy 182.147712 -427.443349) (xy 182.147712 -427.379427)
			(xy 182.155723 -427.316009) (xy 182.17162 -427.254095) (xy 182.195152 -427.194662) (xy 182.225946 -427.138647)
			(xy 182.263519 -427.086932) (xy 182.307276 -427.040335) (xy 182.356529 -426.99959) (xy 182.4105 -426.965339)
			(xy 182.468339 -426.938122) (xy 182.529132 -426.918369) (xy 182.591922 -426.906391) (xy 182.655718 -426.902378)
			(xy 182.719514 -426.906391) (xy 182.782304 -426.918369) (xy 182.843097 -426.938122) (xy 182.900936 -426.965339)
			(xy 182.954907 -426.99959) (xy 183.00416 -427.040335) (xy 183.047917 -427.086932) (xy 183.08549 -427.138647)
			(xy 183.116284 -427.194662) (xy 183.139816 -427.254095) (xy 183.155713 -427.316009) (xy 183.163724 -427.379427)
			(xy 183.164226 -427.411388) (xy 183.163724 -427.443349) (xy 183.158334 -427.486021) (xy 183.804046 -427.486021)
			(xy 183.804046 -427.422099) (xy 183.812057 -427.358681) (xy 183.827954 -427.296767) (xy 183.851486 -427.237334)
			(xy 183.88228 -427.181319) (xy 183.919853 -427.129604) (xy 183.96361 -427.083007) (xy 184.012863 -427.042262)
			(xy 184.066834 -427.008011) (xy 184.124673 -426.980794) (xy 184.185466 -426.961041) (xy 184.248256 -426.949063)
			(xy 184.312052 -426.94505) (xy 184.375848 -426.949063) (xy 184.438638 -426.961041) (xy 184.499431 -426.980794)
			(xy 184.55727 -427.008011) (xy 184.611241 -427.042262) (xy 184.660494 -427.083007) (xy 184.704251 -427.129604)
			(xy 184.741824 -427.181319) (xy 184.772618 -427.237334) (xy 184.79615 -427.296767) (xy 184.812047 -427.358681)
			(xy 184.820058 -427.422099) (xy 184.82056 -427.45406) (xy 184.820058 -427.486021) (xy 184.819673 -427.489069)
			(xy 185.000132 -427.489069) (xy 185.000132 -427.425147) (xy 185.008143 -427.361729) (xy 185.02404 -427.299815)
			(xy 185.047572 -427.240382) (xy 185.078366 -427.184367) (xy 185.115939 -427.132652) (xy 185.159696 -427.086055)
			(xy 185.208949 -427.04531) (xy 185.26292 -427.011059) (xy 185.320759 -426.983842) (xy 185.381552 -426.964089)
			(xy 185.444342 -426.952111) (xy 185.508138 -426.948098) (xy 185.571934 -426.952111) (xy 185.634724 -426.964089)
			(xy 185.695517 -426.983842) (xy 185.753356 -427.011059) (xy 185.807327 -427.04531) (xy 185.85658 -427.086055)
			(xy 185.900337 -427.132652) (xy 185.93791 -427.184367) (xy 185.968704 -427.240382) (xy 185.992236 -427.299815)
			(xy 186.008133 -427.361729) (xy 186.016144 -427.425147) (xy 186.016646 -427.457108) (xy 186.016144 -427.489069)
			(xy 186.008133 -427.552487) (xy 185.992236 -427.614401) (xy 185.968704 -427.673834) (xy 185.93791 -427.729849)
			(xy 185.900337 -427.781564) (xy 185.85658 -427.828161) (xy 185.83166 -427.848776) (xy 192.03746 -427.848776)
			(xy 192.041531 -427.793154) (xy 192.053657 -427.738717) (xy 192.07358 -427.686626) (xy 192.100876 -427.637991)
			(xy 192.134962 -427.593848) (xy 192.175111 -427.555139) (xy 192.220469 -427.522688) (xy 192.270069 -427.497187)
			(xy 192.322853 -427.47918) (xy 192.377696 -427.46905) (xy 192.43343 -427.467013) (xy 192.488867 -427.473113)
			(xy 192.542824 -427.487219) (xy 192.594153 -427.509031) (xy 192.641759 -427.538085) (xy 192.684627 -427.57376)
			(xy 192.721844 -427.615297) (xy 192.752617 -427.66181) (xy 192.776289 -427.712307) (xy 192.792357 -427.765714)
			(xy 192.800477 -427.82089) (xy 192.800986 -427.848776) (xy 192.800477 -427.876662) (xy 192.792357 -427.931838)
			(xy 192.776289 -427.985245) (xy 192.752617 -428.035742) (xy 192.721844 -428.082255) (xy 192.684627 -428.123792)
			(xy 192.641759 -428.159467) (xy 192.594153 -428.188521) (xy 192.542824 -428.210333) (xy 192.488867 -428.224439)
			(xy 192.43343 -428.230539) (xy 192.377696 -428.228502) (xy 192.322853 -428.218372) (xy 192.270069 -428.200365)
			(xy 192.220469 -428.174864) (xy 192.175111 -428.142413) (xy 192.134962 -428.103704) (xy 192.100876 -428.059561)
			(xy 192.07358 -428.010926) (xy 192.053657 -427.958835) (xy 192.041531 -427.904398) (xy 192.03746 -427.848776)
			(xy 185.83166 -427.848776) (xy 185.807327 -427.868906) (xy 185.753356 -427.903157) (xy 185.695517 -427.930374)
			(xy 185.634724 -427.950127) (xy 185.571934 -427.962105) (xy 185.508138 -427.966119) (xy 185.444342 -427.962105)
			(xy 185.381552 -427.950127) (xy 185.320759 -427.930374) (xy 185.26292 -427.903157) (xy 185.208949 -427.868906)
			(xy 185.159696 -427.828161) (xy 185.115939 -427.781564) (xy 185.078366 -427.729849) (xy 185.047572 -427.673834)
			(xy 185.02404 -427.614401) (xy 185.008143 -427.552487) (xy 185.000132 -427.489069) (xy 184.819673 -427.489069)
			(xy 184.812047 -427.549439) (xy 184.79615 -427.611353) (xy 184.772618 -427.670786) (xy 184.741824 -427.726801)
			(xy 184.704251 -427.778516) (xy 184.660494 -427.825113) (xy 184.611241 -427.865858) (xy 184.55727 -427.900109)
			(xy 184.499431 -427.927326) (xy 184.438638 -427.947079) (xy 184.375848 -427.959057) (xy 184.312052 -427.963071)
			(xy 184.248256 -427.959057) (xy 184.185466 -427.947079) (xy 184.124673 -427.927326) (xy 184.066834 -427.900109)
			(xy 184.012863 -427.865858) (xy 183.96361 -427.825113) (xy 183.919853 -427.778516) (xy 183.88228 -427.726801)
			(xy 183.851486 -427.670786) (xy 183.827954 -427.611353) (xy 183.812057 -427.549439) (xy 183.804046 -427.486021)
			(xy 183.158334 -427.486021) (xy 183.155713 -427.506767) (xy 183.139816 -427.568681) (xy 183.116284 -427.628114)
			(xy 183.08549 -427.684129) (xy 183.047917 -427.735844) (xy 183.00416 -427.782441) (xy 182.954907 -427.823186)
			(xy 182.900936 -427.857437) (xy 182.843097 -427.884654) (xy 182.782304 -427.904407) (xy 182.719514 -427.916385)
			(xy 182.655718 -427.920399) (xy 182.591922 -427.916385) (xy 182.529132 -427.904407) (xy 182.468339 -427.884654)
			(xy 182.4105 -427.857437) (xy 182.356529 -427.823186) (xy 182.307276 -427.782441) (xy 182.263519 -427.735844)
			(xy 182.225946 -427.684129) (xy 182.195152 -427.628114) (xy 182.17162 -427.568681) (xy 182.155723 -427.506767)
			(xy 182.147712 -427.443349) (xy 181.29097 -427.443349) (xy 181.271055 -427.485832) (xy 181.240282 -427.532345)
			(xy 181.203065 -427.573882) (xy 181.160197 -427.609557) (xy 181.112591 -427.638611) (xy 181.061262 -427.660423)
			(xy 181.007305 -427.674529) (xy 180.951868 -427.680629) (xy 180.896134 -427.678592) (xy 180.841291 -427.668462)
			(xy 180.788507 -427.650455) (xy 180.738907 -427.624954) (xy 180.693549 -427.592503) (xy 180.6534 -427.553794)
			(xy 180.619314 -427.509651) (xy 180.592018 -427.461016) (xy 180.572095 -427.408925) (xy 180.559969 -427.354488)
			(xy 180.555898 -427.298866) (xy 174.494605 -427.298866) (xy 174.494189 -427.321672) (xy 174.486069 -427.376848)
			(xy 174.470001 -427.430255) (xy 174.446329 -427.480752) (xy 174.415556 -427.527265) (xy 174.378339 -427.568802)
			(xy 174.335471 -427.604477) (xy 174.287865 -427.633531) (xy 174.236536 -427.655343) (xy 174.182579 -427.669449)
			(xy 174.127142 -427.675549) (xy 174.071408 -427.673512) (xy 174.016565 -427.663382) (xy 173.963781 -427.645375)
			(xy 173.914181 -427.619874) (xy 173.868823 -427.587423) (xy 173.828674 -427.548714) (xy 173.794588 -427.504571)
			(xy 173.767292 -427.455936) (xy 173.747369 -427.403845) (xy 173.735243 -427.349408) (xy 173.731172 -427.293786)
			(xy 168.514776 -427.293786) (xy 167.566011 -428.242551) (xy 176.250576 -428.242551) (xy 176.250576 -428.188049)
			(xy 176.258332 -428.134101) (xy 176.273688 -428.081806) (xy 176.296329 -428.032228) (xy 176.325795 -427.986377)
			(xy 176.361487 -427.945187) (xy 176.402677 -427.909495) (xy 176.448528 -427.880029) (xy 176.498106 -427.857388)
			(xy 176.550401 -427.842032) (xy 176.604349 -427.834276) (xy 176.6316 -427.83379) (xy 176.658438 -427.834271)
			(xy 176.711584 -427.841807) (xy 176.763144 -427.85673) (xy 176.78781 -427.867318) (xy 176.79797 -427.87189)
			(xy 176.819814 -427.871636) (xy 176.909476 -427.830488) (xy 176.9237 -427.814232) (xy 176.927002 -427.803564)
			(xy 176.935157 -427.777603) (xy 176.957836 -427.728139) (xy 176.987316 -427.682401) (xy 177.022998 -427.641318)
			(xy 177.064157 -427.605724) (xy 177.109959 -427.576343) (xy 177.159472 -427.55377) (xy 177.21169 -427.538466)
			(xy 177.265554 -427.530739) (xy 177.292762 -427.53026) (xy 177.320014 -427.530785) (xy 177.373965 -427.538537)
			(xy 177.426263 -427.553888) (xy 177.475844 -427.576526) (xy 177.521698 -427.605991) (xy 177.562891 -427.641682)
			(xy 177.598586 -427.682872) (xy 177.628055 -427.728723) (xy 177.638803 -427.752256) (xy 178.780946 -427.752256)
			(xy 178.785017 -427.696634) (xy 178.797143 -427.642197) (xy 178.817066 -427.590106) (xy 178.844362 -427.541471)
			(xy 178.878448 -427.497328) (xy 178.918597 -427.458619) (xy 178.963955 -427.426168) (xy 179.013555 -427.400667)
			(xy 179.066339 -427.38266) (xy 179.121182 -427.37253) (xy 179.176916 -427.370493) (xy 179.232353 -427.376593)
			(xy 179.28631 -427.390699) (xy 179.337639 -427.412511) (xy 179.385245 -427.441565) (xy 179.428113 -427.47724)
			(xy 179.46533 -427.518777) (xy 179.496103 -427.56529) (xy 179.519775 -427.615787) (xy 179.535843 -427.669194)
			(xy 179.543963 -427.72437) (xy 179.544472 -427.752256) (xy 179.543963 -427.780142) (xy 179.535843 -427.835318)
			(xy 179.519775 -427.888725) (xy 179.496103 -427.939222) (xy 179.46533 -427.985735) (xy 179.428113 -428.027272)
			(xy 179.385245 -428.062947) (xy 179.337639 -428.092001) (xy 179.28631 -428.113813) (xy 179.232353 -428.127919)
			(xy 179.176916 -428.134019) (xy 179.121182 -428.131982) (xy 179.066339 -428.121852) (xy 179.013555 -428.103845)
			(xy 178.963955 -428.078344) (xy 178.918597 -428.045893) (xy 178.878448 -428.007184) (xy 178.844362 -427.963041)
			(xy 178.817066 -427.914406) (xy 178.797143 -427.862315) (xy 178.785017 -427.807878) (xy 178.780946 -427.752256)
			(xy 177.638803 -427.752256) (xy 177.650699 -427.778301) (xy 177.666055 -427.830598) (xy 177.673813 -427.884548)
			(xy 177.673813 -427.939052) (xy 177.666055 -427.993002) (xy 177.650699 -428.045299) (xy 177.628055 -428.094877)
			(xy 177.598586 -428.140728) (xy 177.562891 -428.181918) (xy 177.521698 -428.217609) (xy 177.475844 -428.247074)
			(xy 177.426263 -428.269712) (xy 177.373965 -428.285063) (xy 177.320014 -428.292815) (xy 177.292762 -428.293276)
			(xy 177.265923 -428.292811) (xy 177.212777 -428.285269) (xy 177.161217 -428.27034) (xy 177.136552 -428.259748)
			(xy 177.126392 -428.255176) (xy 177.104548 -428.25543) (xy 177.014886 -428.296578) (xy 177.000662 -428.312834)
			(xy 176.99736 -428.323502) (xy 176.989217 -428.349468) (xy 176.96654 -428.398934) (xy 176.93706 -428.444675)
			(xy 176.901377 -428.485759) (xy 176.860216 -428.521354) (xy 176.814412 -428.550735) (xy 176.764897 -428.573305)
			(xy 176.712675 -428.588607) (xy 176.658809 -428.596329) (xy 176.6316 -428.596806) (xy 176.604349 -428.596324)
			(xy 176.550401 -428.588568) (xy 176.498106 -428.573212) (xy 176.448528 -428.550571) (xy 176.402677 -428.521105)
			(xy 176.361487 -428.485413) (xy 176.325795 -428.444223) (xy 176.296329 -428.398372) (xy 176.273688 -428.348794)
			(xy 176.258332 -428.296499) (xy 176.250576 -428.242551) (xy 167.566011 -428.242551) (xy 167.470836 -428.337726)
			(xy 167.463437 -428.34457) (xy 167.444838 -428.352293) (xy 167.434768 -428.352712) (xy 165.743382 -428.352712)
			(xy 165.732366 -428.353256) (xy 165.712357 -428.362481) (xy 165.704774 -428.370492) (xy 165.64737 -428.437294)
			(xy 165.641274 -428.45863) (xy 165.642798 -428.469552) (xy 165.64553 -428.488547) (xy 165.648454 -428.526816)
			(xy 165.64864 -428.546006) (xy 165.648176 -428.576737) (xy 165.640767 -428.637752) (xy 165.626058 -428.697429)
			(xy 165.604263 -428.754898) (xy 165.5757 -428.809321) (xy 165.540786 -428.859905) (xy 165.50003 -428.905911)
			(xy 165.454025 -428.94667) (xy 165.403443 -428.981587) (xy 165.380726 -428.993511) (xy 183.179968 -428.993511)
			(xy 183.179968 -428.929589) (xy 183.187979 -428.866171) (xy 183.203876 -428.804257) (xy 183.227408 -428.744824)
			(xy 183.258202 -428.688809) (xy 183.295775 -428.637094) (xy 183.339532 -428.590497) (xy 183.388785 -428.549752)
			(xy 183.442756 -428.515501) (xy 183.500595 -428.488284) (xy 183.561388 -428.468531) (xy 183.624178 -428.456553)
			(xy 183.687974 -428.45254) (xy 183.75177 -428.456553) (xy 183.81456 -428.468531) (xy 183.875353 -428.488284)
			(xy 183.933192 -428.515501) (xy 183.987163 -428.549752) (xy 184.036416 -428.590497) (xy 184.080173 -428.637094)
			(xy 184.117746 -428.688809) (xy 184.14854 -428.744824) (xy 184.172072 -428.804257) (xy 184.187969 -428.866171)
			(xy 184.19598 -428.929589) (xy 184.196482 -428.96155) (xy 184.19598 -428.993511) (xy 184.187969 -429.056929)
			(xy 184.172072 -429.118843) (xy 184.14854 -429.178276) (xy 184.117746 -429.234291) (xy 184.080173 -429.286006)
			(xy 184.036416 -429.332603) (xy 183.987163 -429.373348) (xy 183.969253 -429.384714) (xy 184.645298 -429.384714)
			(xy 184.649369 -429.329092) (xy 184.661495 -429.274655) (xy 184.681418 -429.222564) (xy 184.708714 -429.173929)
			(xy 184.7428 -429.129786) (xy 184.782949 -429.091077) (xy 184.828307 -429.058626) (xy 184.877907 -429.033125)
			(xy 184.930691 -429.015118) (xy 184.985534 -429.004988) (xy 185.041268 -429.002951) (xy 185.096705 -429.009051)
			(xy 185.150662 -429.023157) (xy 185.201991 -429.044969) (xy 185.249597 -429.074023) (xy 185.292465 -429.109698)
			(xy 185.329682 -429.151235) (xy 185.360455 -429.197748) (xy 185.384127 -429.248245) (xy 185.400195 -429.301652)
			(xy 185.408315 -429.356828) (xy 185.408824 -429.384714) (xy 185.408315 -429.4126) (xy 185.406102 -429.42764)
			(xy 185.656218 -429.42764) (xy 185.660289 -429.372018) (xy 185.672415 -429.317581) (xy 185.692338 -429.26549)
			(xy 185.719634 -429.216855) (xy 185.75372 -429.172712) (xy 185.793869 -429.134003) (xy 185.839227 -429.101552)
			(xy 185.888827 -429.076051) (xy 185.941611 -429.058044) (xy 185.996454 -429.047914) (xy 186.052188 -429.045877)
			(xy 186.107625 -429.051977) (xy 186.161582 -429.066083) (xy 186.212911 -429.087895) (xy 186.260517 -429.116949)
			(xy 186.303385 -429.152624) (xy 186.340602 -429.194161) (xy 186.371375 -429.240674) (xy 186.395047 -429.291171)
			(xy 186.411115 -429.344578) (xy 186.419235 -429.399754) (xy 186.419744 -429.42764) (xy 186.419235 -429.455526)
			(xy 186.411115 -429.510702) (xy 186.395047 -429.564109) (xy 186.371375 -429.614606) (xy 186.340602 -429.661119)
			(xy 186.303385 -429.702656) (xy 186.260517 -429.738331) (xy 186.212911 -429.767385) (xy 186.161582 -429.789197)
			(xy 186.107625 -429.803303) (xy 186.052188 -429.809403) (xy 185.996454 -429.807366) (xy 185.941611 -429.797236)
			(xy 185.888827 -429.779229) (xy 185.839227 -429.753728) (xy 185.793869 -429.721277) (xy 185.75372 -429.682568)
			(xy 185.719634 -429.638425) (xy 185.692338 -429.58979) (xy 185.672415 -429.537699) (xy 185.660289 -429.483262)
			(xy 185.656218 -429.42764) (xy 185.406102 -429.42764) (xy 185.400195 -429.467776) (xy 185.384127 -429.521183)
			(xy 185.360455 -429.57168) (xy 185.329682 -429.618193) (xy 185.292465 -429.65973) (xy 185.249597 -429.695405)
			(xy 185.201991 -429.724459) (xy 185.150662 -429.746271) (xy 185.096705 -429.760377) (xy 185.041268 -429.766477)
			(xy 184.985534 -429.76444) (xy 184.930691 -429.75431) (xy 184.877907 -429.736303) (xy 184.828307 -429.710802)
			(xy 184.782949 -429.678351) (xy 184.7428 -429.639642) (xy 184.708714 -429.595499) (xy 184.681418 -429.546864)
			(xy 184.661495 -429.494773) (xy 184.649369 -429.440336) (xy 184.645298 -429.384714) (xy 183.969253 -429.384714)
			(xy 183.933192 -429.407599) (xy 183.875353 -429.434816) (xy 183.81456 -429.454569) (xy 183.75177 -429.466547)
			(xy 183.687974 -429.470561) (xy 183.624178 -429.466547) (xy 183.561388 -429.454569) (xy 183.500595 -429.434816)
			(xy 183.442756 -429.407599) (xy 183.388785 -429.373348) (xy 183.339532 -429.332603) (xy 183.295775 -429.286006)
			(xy 183.258202 -429.234291) (xy 183.227408 -429.178276) (xy 183.203876 -429.118843) (xy 183.187979 -429.056929)
			(xy 183.179968 -428.993511) (xy 165.380726 -428.993511) (xy 165.349022 -429.010152) (xy 165.291554 -429.03195)
			(xy 165.231878 -429.046662) (xy 165.170863 -429.054074) (xy 165.140132 -429.054514) (xy 165.109246 -429.054061)
			(xy 165.047929 -429.046582) (xy 164.98797 -429.031731) (xy 164.930251 -429.009725) (xy 164.875623 -428.98089)
			(xy 164.82489 -428.94565) (xy 164.778799 -428.904524) (xy 164.73803 -428.858117) (xy 164.703182 -428.807114)
			(xy 164.674769 -428.752265) (xy 164.65321 -428.694378) (xy 164.638822 -428.634306) (xy 164.634926 -428.603664)
			(xy 164.633148 -428.588932) (xy 164.615114 -428.566326) (xy 164.514784 -428.531274) (xy 164.505676 -428.5285)
			(xy 164.486664 -428.529191) (xy 164.469212 -428.536766) (xy 164.462206 -428.543212) (xy 163.545774 -429.459644)
			(xy 170.212256 -429.459644) (xy 170.216327 -429.404022) (xy 170.228453 -429.349585) (xy 170.248376 -429.297494)
			(xy 170.275672 -429.248859) (xy 170.309758 -429.204716) (xy 170.349907 -429.166007) (xy 170.395265 -429.133556)
			(xy 170.444865 -429.108055) (xy 170.497649 -429.090048) (xy 170.552492 -429.079918) (xy 170.608226 -429.077881)
			(xy 170.663663 -429.083981) (xy 170.71762 -429.098087) (xy 170.768949 -429.119899) (xy 170.816555 -429.148953)
			(xy 170.859423 -429.184628) (xy 170.89664 -429.226165) (xy 170.927413 -429.272678) (xy 170.951085 -429.323175)
			(xy 170.967153 -429.376582) (xy 170.975273 -429.431758) (xy 170.975782 -429.459644) (xy 170.975273 -429.48753)
			(xy 170.967153 -429.542706) (xy 170.951085 -429.596113) (xy 170.927413 -429.64661) (xy 170.89664 -429.693123)
			(xy 170.859423 -429.73466) (xy 170.816555 -429.770335) (xy 170.768949 -429.799389) (xy 170.71762 -429.821201)
			(xy 170.663663 -429.835307) (xy 170.608226 -429.841407) (xy 170.552492 -429.83937) (xy 170.497649 -429.82924)
			(xy 170.444865 -429.811233) (xy 170.395265 -429.785732) (xy 170.349907 -429.753281) (xy 170.309758 -429.714572)
			(xy 170.275672 -429.670429) (xy 170.248376 -429.621794) (xy 170.228453 -429.569703) (xy 170.216327 -429.515266)
			(xy 170.212256 -429.459644) (xy 163.545774 -429.459644) (xy 161.920428 -431.08499) (xy 161.91357 -431.09769)
			(xy 161.912046 -431.105056) (xy 161.904745 -431.13671) (xy 161.883171 -431.197984) (xy 161.85397 -431.256012)
			(xy 161.817618 -431.309849) (xy 161.774706 -431.35862) (xy 161.734946 -431.3936) (xy 167.09009 -431.3936)
			(xy 167.090584 -431.361738) (xy 167.098546 -431.298513) (xy 167.114345 -431.236778) (xy 167.137734 -431.177502)
			(xy 167.168346 -431.121612) (xy 167.205702 -431.069985) (xy 167.249215 -431.02343) (xy 167.298204 -430.982676)
			(xy 167.324786 -430.965102) (xy 167.337263 -430.956505) (xy 167.356824 -430.933381) (xy 167.368757 -430.905543)
			(xy 167.372017 -430.875431) (xy 167.366316 -430.845685) (xy 167.352156 -430.818911) (xy 167.330776 -430.797457)
			(xy 167.317674 -430.789842) (xy 167.291883 -430.775503) (xy 167.244654 -430.740129) (xy 167.203439 -430.697901)
			(xy 167.169222 -430.649827) (xy 167.142821 -430.597055) (xy 167.124865 -430.540846) (xy 167.115783 -430.482542)
			(xy 167.115236 -430.453038) (xy 167.115722 -430.425787) (xy 167.123478 -430.371839) (xy 167.138833 -430.319544)
			(xy 167.161475 -430.269967) (xy 167.190941 -430.224117) (xy 167.226632 -430.182926) (xy 167.267823 -430.147235)
			(xy 167.313673 -430.117769) (xy 167.36325 -430.095127) (xy 167.415545 -430.079772) (xy 167.469493 -430.072016)
			(xy 167.523995 -430.072016) (xy 167.577943 -430.079772) (xy 167.630238 -430.095127) (xy 167.679815 -430.117769)
			(xy 167.725665 -430.147235) (xy 167.766856 -430.182926) (xy 167.802547 -430.224117) (xy 167.832013 -430.269967)
			(xy 167.854655 -430.319544) (xy 167.87001 -430.371839) (xy 167.877766 -430.425787) (xy 167.878252 -430.453038)
			(xy 167.877769 -430.480583) (xy 167.869859 -430.535103) (xy 167.85418 -430.587915) (xy 167.831059 -430.637918)
			(xy 167.800978 -430.684071) (xy 167.764565 -430.725411) (xy 167.743886 -430.743614) (xy 167.732754 -430.753914)
			(xy 167.716434 -430.77945) (xy 167.708306 -430.808646) (xy 167.708604 -430.820279) (xy 169.926248 -430.820279)
			(xy 169.926248 -430.756357) (xy 169.934259 -430.692939) (xy 169.950156 -430.631025) (xy 169.973688 -430.571592)
			(xy 170.004482 -430.515577) (xy 170.042055 -430.463862) (xy 170.085812 -430.417265) (xy 170.135065 -430.37652)
			(xy 170.189036 -430.342269) (xy 170.246875 -430.315052) (xy 170.307668 -430.295299) (xy 170.370458 -430.283321)
			(xy 170.434254 -430.279308) (xy 170.49805 -430.283321) (xy 170.56084 -430.295299) (xy 170.621633 -430.315052)
			(xy 170.679472 -430.342269) (xy 170.733443 -430.37652) (xy 170.782696 -430.417265) (xy 170.826453 -430.463862)
			(xy 170.864026 -430.515577) (xy 170.89482 -430.571592) (xy 170.918352 -430.631025) (xy 170.934249 -430.692939)
			(xy 170.94226 -430.756357) (xy 170.942762 -430.788318) (xy 170.94226 -430.820279) (xy 170.934249 -430.883697)
			(xy 170.918352 -430.945611) (xy 170.89482 -431.005044) (xy 170.864026 -431.061059) (xy 170.826453 -431.112774)
			(xy 170.782696 -431.159371) (xy 170.733443 -431.200116) (xy 170.679472 -431.234367) (xy 170.621633 -431.261584)
			(xy 170.56084 -431.281337) (xy 170.49805 -431.293315) (xy 170.434254 -431.297329) (xy 170.370458 -431.293315)
			(xy 170.307668 -431.281337) (xy 170.246875 -431.261584) (xy 170.189036 -431.234367) (xy 170.135065 -431.200116)
			(xy 170.085812 -431.159371) (xy 170.042055 -431.112774) (xy 170.004482 -431.061059) (xy 169.973688 -431.005044)
			(xy 169.950156 -430.945611) (xy 169.934259 -430.883697) (xy 169.926248 -430.820279) (xy 167.708604 -430.820279)
			(xy 167.709083 -430.838942) (xy 167.718695 -430.867683) (xy 167.736302 -430.89235) (xy 167.760359 -430.91078)
			(xy 167.774366 -430.916588) (xy 167.803274 -430.927707) (xy 167.858371 -430.956005) (xy 167.90962 -430.990789)
			(xy 167.956263 -431.031542) (xy 167.997609 -431.077661) (xy 168.033044 -431.128462) (xy 168.062044 -431.183192)
			(xy 168.084178 -431.241041) (xy 168.099119 -431.301151) (xy 168.106646 -431.362631) (xy 168.107106 -431.3936)
			(xy 168.106604 -431.425561) (xy 168.098593 -431.488979) (xy 168.082696 -431.550893) (xy 168.059164 -431.610326)
			(xy 168.02837 -431.666341) (xy 167.990797 -431.718056) (xy 167.94704 -431.764653) (xy 167.897787 -431.805398)
			(xy 167.843816 -431.839649) (xy 167.785977 -431.866866) (xy 167.725184 -431.886619) (xy 167.662394 -431.898597)
			(xy 167.598598 -431.902611) (xy 167.534802 -431.898597) (xy 167.472012 -431.886619) (xy 167.411219 -431.866866)
			(xy 167.35338 -431.839649) (xy 167.299409 -431.805398) (xy 167.250156 -431.764653) (xy 167.206399 -431.718056)
			(xy 167.168826 -431.666341) (xy 167.138032 -431.610326) (xy 167.1145 -431.550893) (xy 167.098603 -431.488979)
			(xy 167.090592 -431.425561) (xy 167.09009 -431.3936) (xy 161.734946 -431.3936) (xy 161.725934 -431.401529)
			(xy 161.672095 -431.437879) (xy 161.614066 -431.467078) (xy 161.552791 -431.488651) (xy 161.52114 -431.495962)
			(xy 161.513774 -431.497486) (xy 161.501074 -431.504344) (xy 160.996927 -432.008491) (xy 161.897308 -432.008491)
			(xy 161.897308 -431.944569) (xy 161.905319 -431.881151) (xy 161.921216 -431.819237) (xy 161.944748 -431.759804)
			(xy 161.975542 -431.703789) (xy 162.013115 -431.652074) (xy 162.056872 -431.605477) (xy 162.106125 -431.564732)
			(xy 162.160096 -431.530481) (xy 162.217935 -431.503264) (xy 162.278728 -431.483511) (xy 162.341518 -431.471533)
			(xy 162.405314 -431.46752) (xy 162.46911 -431.471533) (xy 162.5319 -431.483511) (xy 162.592693 -431.503264)
			(xy 162.650532 -431.530481) (xy 162.704503 -431.564732) (xy 162.753756 -431.605477) (xy 162.797513 -431.652074)
			(xy 162.835086 -431.703789) (xy 162.86588 -431.759804) (xy 162.889412 -431.819237) (xy 162.905309 -431.881151)
			(xy 162.91332 -431.944569) (xy 162.913822 -431.97653) (xy 162.91332 -432.008491) (xy 162.905309 -432.071909)
			(xy 162.889412 -432.133823) (xy 162.86588 -432.193256) (xy 162.835086 -432.249271) (xy 162.797513 -432.300986)
			(xy 162.753756 -432.347583) (xy 162.704503 -432.388328) (xy 162.650532 -432.422579) (xy 162.592693 -432.449796)
			(xy 162.5319 -432.469549) (xy 162.46911 -432.481527) (xy 162.405314 -432.485541) (xy 162.341518 -432.481527)
			(xy 162.278728 -432.469549) (xy 162.217935 -432.449796) (xy 162.160096 -432.422579) (xy 162.106125 -432.388328)
			(xy 162.056872 -432.347583) (xy 162.013115 -432.300986) (xy 161.975542 -432.249271) (xy 161.944748 -432.193256)
			(xy 161.921216 -432.133823) (xy 161.905319 -432.071909) (xy 161.897308 -432.008491) (xy 160.996927 -432.008491)
			(xy 160.871662 -432.133756) (xy 160.864818 -432.141154) (xy 160.857094 -432.159753) (xy 160.856676 -432.169824)
			(xy 160.856676 -432.590194) (xy 168.27322 -432.590194) (xy 168.277291 -432.534572) (xy 168.289417 -432.480135)
			(xy 168.30934 -432.428044) (xy 168.336636 -432.379409) (xy 168.370722 -432.335266) (xy 168.410871 -432.296557)
			(xy 168.456229 -432.264106) (xy 168.505829 -432.238605) (xy 168.558613 -432.220598) (xy 168.613456 -432.210468)
			(xy 168.66919 -432.208431) (xy 168.724627 -432.214531) (xy 168.778584 -432.228637) (xy 168.829913 -432.250449)
			(xy 168.877519 -432.279503) (xy 168.920387 -432.315178) (xy 168.957604 -432.356715) (xy 168.988377 -432.403228)
			(xy 169.012049 -432.453725) (xy 169.028117 -432.507132) (xy 169.036237 -432.562308) (xy 169.036746 -432.590194)
			(xy 169.036237 -432.61808) (xy 169.028117 -432.673256) (xy 169.012049 -432.726663) (xy 168.988377 -432.77716)
			(xy 168.957604 -432.823673) (xy 168.920387 -432.86521) (xy 168.877519 -432.900885) (xy 168.829913 -432.929939)
			(xy 168.778584 -432.951751) (xy 168.724627 -432.965857) (xy 168.66919 -432.971957) (xy 168.613456 -432.96992)
			(xy 168.558613 -432.95979) (xy 168.505829 -432.941783) (xy 168.456229 -432.916282) (xy 168.410871 -432.883831)
			(xy 168.370722 -432.845122) (xy 168.336636 -432.800979) (xy 168.30934 -432.752344) (xy 168.289417 -432.700253)
			(xy 168.277291 -432.645816) (xy 168.27322 -432.590194) (xy 160.856676 -432.590194) (xy 160.856676 -434.155596)
			(xy 164.598096 -434.155596) (xy 164.598608 -434.127101) (xy 164.607065 -434.070743) (xy 164.62382 -434.016273)
			(xy 164.648499 -433.964905) (xy 164.680552 -433.917785) (xy 164.719265 -433.875963) (xy 164.763774 -433.840372)
			(xy 164.813086 -433.811805) (xy 164.866102 -433.7909) (xy 164.893752 -433.783994) (xy 164.907058 -433.78039)
			(xy 164.93124 -433.767182) (xy 164.951016 -433.747995) (xy 164.964947 -433.724222) (xy 164.972022 -433.697592)
			(xy 164.971727 -433.670039) (xy 164.964083 -433.643567) (xy 164.957252 -433.631594) (xy 164.939385 -433.601408)
			(xy 164.911172 -433.537187) (xy 164.892059 -433.469697) (xy 164.882407 -433.40022) (xy 164.881814 -433.365148)
			(xy 164.882316 -433.333187) (xy 164.890327 -433.269769) (xy 164.906224 -433.207855) (xy 164.929756 -433.148422)
			(xy 164.96055 -433.092407) (xy 164.998123 -433.040692) (xy 165.04188 -432.994095) (xy 165.091133 -432.95335)
			(xy 165.145104 -432.919099) (xy 165.202943 -432.891882) (xy 165.263736 -432.872129) (xy 165.326526 -432.860151)
			(xy 165.390322 -432.856138) (xy 165.454118 -432.860151) (xy 165.516908 -432.872129) (xy 165.577701 -432.891882)
			(xy 165.63554 -432.919099) (xy 165.689511 -432.95335) (xy 165.738764 -432.994095) (xy 165.782521 -433.040692)
			(xy 165.820094 -433.092407) (xy 165.850888 -433.148422) (xy 165.87442 -433.207855) (xy 165.890317 -433.269769)
			(xy 165.898328 -433.333187) (xy 165.89883 -433.365148) (xy 165.898284 -433.397153) (xy 165.890233 -433.460656)
			(xy 165.874277 -433.522646) (xy 165.850669 -433.582145) (xy 165.832382 -433.615338) (xy 166.816278 -433.615338)
			(xy 166.81678 -433.583377) (xy 166.824791 -433.519959) (xy 166.840688 -433.458045) (xy 166.86422 -433.398612)
			(xy 166.895014 -433.342597) (xy 166.932587 -433.290882) (xy 166.976344 -433.244285) (xy 167.025597 -433.20354)
			(xy 167.079568 -433.169289) (xy 167.137407 -433.142072) (xy 167.1982 -433.122319) (xy 167.26099 -433.110341)
			(xy 167.324786 -433.106328) (xy 167.388582 -433.110341) (xy 167.401907 -433.112883) (xy 169.088048 -433.112883)
			(xy 169.088048 -433.048961) (xy 169.096059 -432.985543) (xy 169.111956 -432.923629) (xy 169.135488 -432.864196)
			(xy 169.166282 -432.808181) (xy 169.203855 -432.756466) (xy 169.247612 -432.709869) (xy 169.296865 -432.669124)
			(xy 169.350836 -432.634873) (xy 169.408675 -432.607656) (xy 169.469468 -432.587903) (xy 169.532258 -432.575925)
			(xy 169.596054 -432.571912) (xy 169.65985 -432.575925) (xy 169.72264 -432.587903) (xy 169.783433 -432.607656)
			(xy 169.841272 -432.634873) (xy 169.895243 -432.669124) (xy 169.944496 -432.709869) (xy 169.988253 -432.756466)
			(xy 170.025826 -432.808181) (xy 170.05662 -432.864196) (xy 170.080152 -432.923629) (xy 170.096049 -432.985543)
			(xy 170.10406 -433.048961) (xy 170.104562 -433.080922) (xy 170.10406 -433.112883) (xy 170.096049 -433.176301)
			(xy 170.080152 -433.238215) (xy 170.05662 -433.297648) (xy 170.025826 -433.353663) (xy 169.988253 -433.405378)
			(xy 169.944496 -433.451975) (xy 169.895243 -433.49272) (xy 169.841272 -433.526971) (xy 169.783433 -433.554188)
			(xy 169.72264 -433.573941) (xy 169.65985 -433.585919) (xy 169.596054 -433.589933) (xy 169.532258 -433.585919)
			(xy 169.469468 -433.573941) (xy 169.408675 -433.554188) (xy 169.350836 -433.526971) (xy 169.296865 -433.49272)
			(xy 169.247612 -433.451975) (xy 169.203855 -433.405378) (xy 169.166282 -433.353663) (xy 169.135488 -433.297648)
			(xy 169.111956 -433.238215) (xy 169.096059 -433.176301) (xy 169.088048 -433.112883) (xy 167.401907 -433.112883)
			(xy 167.451372 -433.122319) (xy 167.512165 -433.142072) (xy 167.570004 -433.169289) (xy 167.623975 -433.20354)
			(xy 167.673228 -433.244285) (xy 167.716985 -433.290882) (xy 167.754558 -433.342597) (xy 167.785352 -433.398612)
			(xy 167.808884 -433.458045) (xy 167.824781 -433.519959) (xy 167.832792 -433.583377) (xy 167.833294 -433.615338)
			(xy 167.832853 -433.6456) (xy 167.825665 -433.705695) (xy 167.811396 -433.764513) (xy 167.790247 -433.821221)
			(xy 167.762517 -433.875019) (xy 167.745918 -433.900326) (xy 167.741295 -433.907809) (xy 167.736868 -433.924815)
			(xy 167.737282 -433.9336) (xy 167.740076 -433.963318) (xy 167.741272 -433.971989) (xy 167.748655 -433.987842)
			(xy 167.754554 -433.994306) (xy 167.777437 -434.018184) (xy 167.81747 -434.070827) (xy 167.85034 -434.128216)
			(xy 167.875493 -434.189382) (xy 167.892504 -434.253293) (xy 167.901086 -434.31887) (xy 167.90162 -434.351938)
			(xy 167.901118 -434.383899) (xy 167.893107 -434.447317) (xy 167.87721 -434.509231) (xy 167.853678 -434.568664)
			(xy 167.822884 -434.624679) (xy 167.785311 -434.676394) (xy 167.741554 -434.722991) (xy 167.692301 -434.763736)
			(xy 167.63833 -434.797987) (xy 167.580491 -434.825204) (xy 167.519698 -434.844957) (xy 167.456908 -434.856935)
			(xy 167.393112 -434.860949) (xy 167.329316 -434.856935) (xy 167.266526 -434.844957) (xy 167.205733 -434.825204)
			(xy 167.147894 -434.797987) (xy 167.093923 -434.763736) (xy 167.04467 -434.722991) (xy 167.000913 -434.676394)
			(xy 166.96334 -434.624679) (xy 166.932546 -434.568664) (xy 166.909014 -434.509231) (xy 166.893117 -434.447317)
			(xy 166.885106 -434.383899) (xy 166.884604 -434.351938) (xy 166.885033 -434.321676) (xy 166.892224 -434.26158)
			(xy 166.906496 -434.202762) (xy 166.927647 -434.146054) (xy 166.95538 -434.092257) (xy 166.97198 -434.06695)
			(xy 166.976613 -434.059473) (xy 166.981034 -434.042462) (xy 166.980616 -434.033676) (xy 166.977822 -434.003958)
			(xy 166.976637 -433.995285) (xy 166.969247 -433.979433) (xy 166.963344 -433.97297) (xy 166.940449 -433.949103)
			(xy 166.900418 -433.896457) (xy 166.867549 -433.839066) (xy 166.842398 -433.777898) (xy 166.825389 -433.713985)
			(xy 166.81681 -433.648407) (xy 166.816278 -433.615338) (xy 165.832382 -433.615338) (xy 165.819781 -433.63821)
			(xy 165.782101 -433.689956) (xy 165.738227 -433.736565) (xy 165.68885 -433.7773) (xy 165.634752 -433.811517)
			(xy 165.576788 -433.838675) (xy 165.515874 -433.858345) (xy 165.452973 -433.870216) (xy 165.421056 -433.87264)
			(xy 165.407331 -433.874007) (xy 165.381262 -433.88296) (xy 165.358545 -433.898571) (xy 165.340841 -433.919697)
			(xy 165.329445 -433.944795) (xy 165.32519 -433.972029) (xy 165.328389 -433.999407) (xy 165.333172 -434.01234)
			(xy 165.342022 -434.035174) (xy 165.354462 -434.08254) (xy 165.360734 -434.13111) (xy 165.361112 -434.155596)
			(xy 165.360626 -434.182847) (xy 165.35287 -434.236795) (xy 165.337515 -434.28909) (xy 165.314873 -434.338667)
			(xy 165.285407 -434.384517) (xy 165.249716 -434.425708) (xy 165.208525 -434.461399) (xy 165.162675 -434.490865)
			(xy 165.113098 -434.513507) (xy 165.060803 -434.528862) (xy 165.006855 -434.536618) (xy 164.952353 -434.536618)
			(xy 164.898405 -434.528862) (xy 164.84611 -434.513507) (xy 164.796533 -434.490865) (xy 164.750683 -434.461399)
			(xy 164.709492 -434.425708) (xy 164.673801 -434.384517) (xy 164.644335 -434.338667) (xy 164.621693 -434.28909)
			(xy 164.606338 -434.236795) (xy 164.598582 -434.182847) (xy 164.598096 -434.155596) (xy 160.856676 -434.155596)
			(xy 160.856676 -434.389022) (xy 160.857153 -434.399256) (xy 160.865143 -434.418102) (xy 160.879821 -434.432369)
			(xy 160.889188 -434.43652) (xy 160.992312 -434.476144) (xy 161.022792 -434.469032) (xy 161.03346 -434.457348)
			(xy 161.054142 -434.435223) (xy 161.099898 -434.39554) (xy 161.150043 -434.361574) (xy 161.203868 -434.333804)
			(xy 161.260611 -434.312625) (xy 161.319467 -434.298336) (xy 161.379605 -434.29114) (xy 161.409888 -434.290724)
			(xy 161.441849 -434.291204) (xy 161.505267 -434.299214) (xy 161.56718 -434.31511) (xy 161.626614 -434.33864)
			(xy 161.682629 -434.369433) (xy 161.734343 -434.407005) (xy 161.780941 -434.450762) (xy 161.821686 -434.500014)
			(xy 161.855938 -434.553984) (xy 161.883155 -434.611822) (xy 161.902908 -434.672615) (xy 161.914886 -434.735404)
			(xy 161.9189 -434.7992) (xy 161.914886 -434.862996) (xy 161.902908 -434.925785) (xy 161.883155 -434.986578)
			(xy 161.855938 -435.044416) (xy 161.821686 -435.098386) (xy 161.780941 -435.147638) (xy 161.734343 -435.191395)
			(xy 161.682629 -435.228967) (xy 161.626614 -435.25976) (xy 161.56718 -435.28329) (xy 161.505267 -435.299186)
			(xy 161.441849 -435.307196) (xy 161.409888 -435.30774) (xy 161.379606 -435.307302) (xy 161.31947 -435.300107)
			(xy 161.260614 -435.28582) (xy 161.203873 -435.264644) (xy 161.150048 -435.236878) (xy 161.099901 -435.202916)
			(xy 161.054144 -435.163238) (xy 161.03346 -435.141116) (xy 161.022792 -435.129432) (xy 160.992312 -435.12232)
			(xy 160.889188 -435.161944) (xy 160.879789 -435.166051) (xy 160.865065 -435.180305) (xy 160.857114 -435.199193)
			(xy 160.856676 -435.209442) (xy 160.856676 -435.537208) (xy 167.01862 -435.537208) (xy 167.021228 -435.474184)
			(xy 167.031612 -435.411966) (xy 167.049611 -435.35151) (xy 167.07495 -435.293745) (xy 167.10724 -435.239558)
			(xy 167.145984 -435.18978) (xy 167.190588 -435.145177) (xy 167.240366 -435.106434) (xy 167.294554 -435.074146)
			(xy 167.35232 -435.048808) (xy 167.412776 -435.030809) (xy 167.474994 -435.020427) (xy 167.538018 -435.01782)
			(xy 167.600881 -435.023029) (xy 167.662617 -435.035973) (xy 167.722278 -435.056455) (xy 167.778948 -435.084158)
			(xy 167.831755 -435.118658) (xy 167.87989 -435.159425) (xy 167.922612 -435.205833) (xy 167.959266 -435.257169)
			(xy 167.989289 -435.312644) (xy 168.01222 -435.371407) (xy 168.027706 -435.432555) (xy 168.03551 -435.495149)
			(xy 168.035986 -435.526688) (xy 168.03563 -435.554231) (xy 168.029651 -435.608991) (xy 168.017783 -435.662783)
			(xy 168.009316 -435.688994) (xy 168.005506 -435.700678) (xy 168.009062 -435.724808) (xy 168.072054 -435.81193)
			(xy 168.093898 -435.822852) (xy 168.10863 -435.822852) (xy 168.13588 -435.82335) (xy 168.189825 -435.831109)
			(xy 168.242117 -435.846466) (xy 168.291692 -435.869108) (xy 168.33754 -435.898574) (xy 168.378729 -435.934264)
			(xy 168.41442 -435.975452) (xy 168.443887 -436.021299) (xy 168.46653 -436.070873) (xy 168.481889 -436.123165)
			(xy 168.48965 -436.17711) (xy 168.490138 -436.20436) (xy 168.48966 -436.232293) (xy 168.481511 -436.287561)
			(xy 168.465396 -436.341052) (xy 168.441659 -436.391625) (xy 168.426638 -436.41518) (xy 168.42105 -436.423816)
			(xy 168.41724 -436.443374) (xy 168.436036 -436.534306) (xy 168.447212 -436.550816) (xy 168.455848 -436.556404)
			(xy 168.482091 -436.574011) (xy 168.530376 -436.614787) (xy 168.573236 -436.661231) (xy 168.610011 -436.712627)
			(xy 168.640136 -436.768185) (xy 168.663144 -436.827046) (xy 168.678682 -436.888305) (xy 168.68651 -436.951017)
			(xy 168.686988 -436.982616) (xy 168.686577 -437.013349) (xy 168.679166 -437.074367) (xy 168.664455 -437.134047)
			(xy 168.642656 -437.191519) (xy 168.61409 -437.245943) (xy 168.579171 -437.296528) (xy 168.53841 -437.342535)
			(xy 168.4924 -437.383293) (xy 168.441813 -437.418208) (xy 168.387386 -437.446771) (xy 168.329913 -437.468565)
			(xy 168.270232 -437.483273) (xy 168.209213 -437.49068) (xy 168.17848 -437.491124) (xy 168.144934 -437.490606)
			(xy 168.078421 -437.481811) (xy 168.045892 -437.473598) (xy 168.03624 -437.471058) (xy 168.016682 -437.473344)
			(xy 167.937434 -437.517286) (xy 167.924988 -437.53278) (xy 167.922194 -437.542432) (xy 167.913857 -437.568213)
			(xy 167.891023 -437.617347) (xy 167.861467 -437.662757) (xy 167.825784 -437.703528) (xy 167.784692 -437.738841)
			(xy 167.739016 -437.767984) (xy 167.689678 -437.790373) (xy 167.637667 -437.805555) (xy 167.584032 -437.813227)
			(xy 167.556942 -437.813704) (xy 167.529687 -437.813252) (xy 167.475731 -437.805499) (xy 167.423427 -437.790147)
			(xy 167.373842 -437.767506) (xy 167.327983 -437.738039) (xy 167.286785 -437.702345) (xy 167.251086 -437.661151)
			(xy 167.221614 -437.615295) (xy 167.198968 -437.565712) (xy 167.18361 -437.51341) (xy 167.175851 -437.459455)
			(xy 167.175851 -437.404945) (xy 167.18361 -437.35099) (xy 167.198968 -437.298688) (xy 167.221614 -437.249105)
			(xy 167.251086 -437.203249) (xy 167.286785 -437.162055) (xy 167.327983 -437.126361) (xy 167.373842 -437.096894)
			(xy 167.423427 -437.074253) (xy 167.475731 -437.058901) (xy 167.529687 -437.051148) (xy 167.556942 -437.050688)
			(xy 167.566594 -437.050688) (xy 167.576754 -437.050942) (xy 167.595042 -437.044084) (xy 167.661844 -436.982616)
			(xy 167.670226 -436.964836) (xy 167.670734 -436.95493) (xy 167.672967 -436.922761) (xy 167.68459 -436.859331)
			(xy 167.70414 -436.79788) (xy 167.731304 -436.739394) (xy 167.765645 -436.684813) (xy 167.806612 -436.635012)
			(xy 167.829738 -436.612538) (xy 167.837104 -436.60568) (xy 167.845232 -436.587138) (xy 167.847518 -436.494682)
			(xy 167.840406 -436.475886) (xy 167.833294 -436.46852) (xy 167.81348 -436.447078) (xy 167.779967 -436.399275)
			(xy 167.754126 -436.346925) (xy 167.736558 -436.291251) (xy 167.727674 -436.23355) (xy 167.727122 -436.20436)
			(xy 167.727273 -436.189181) (xy 167.729691 -436.158919) (xy 167.731948 -436.143908) (xy 167.73398 -436.131716)
			(xy 167.72636 -436.108348) (xy 167.649906 -436.03291) (xy 167.626538 -436.025544) (xy 167.614346 -436.02783)
			(xy 167.592797 -436.0313) (xy 167.549303 -436.034985) (xy 167.527478 -436.035196) (xy 167.495939 -436.034709)
			(xy 167.433345 -436.026904) (xy 167.372197 -436.011417) (xy 167.313435 -435.988485) (xy 167.25796 -435.958461)
			(xy 167.206625 -435.921806) (xy 167.160218 -435.879082) (xy 167.119452 -435.830947) (xy 167.084953 -435.778139)
			(xy 167.057251 -435.721469) (xy 167.036771 -435.661808) (xy 167.023828 -435.600072) (xy 167.01862 -435.537208)
			(xy 160.856676 -435.537208) (xy 160.856676 -436.430166) (xy 165.86784 -436.430166) (xy 165.871911 -436.374544)
			(xy 165.884037 -436.320107) (xy 165.90396 -436.268016) (xy 165.931256 -436.219381) (xy 165.965342 -436.175238)
			(xy 166.005491 -436.136529) (xy 166.050849 -436.104078) (xy 166.100449 -436.078577) (xy 166.153233 -436.06057)
			(xy 166.208076 -436.05044) (xy 166.26381 -436.048403) (xy 166.319247 -436.054503) (xy 166.373204 -436.068609)
			(xy 166.424533 -436.090421) (xy 166.472139 -436.119475) (xy 166.515007 -436.15515) (xy 166.552224 -436.196687)
			(xy 166.582997 -436.2432) (xy 166.606669 -436.293697) (xy 166.622737 -436.347104) (xy 166.630857 -436.40228)
			(xy 166.631366 -436.430166) (xy 166.630857 -436.458052) (xy 166.622737 -436.513228) (xy 166.606669 -436.566635)
			(xy 166.582997 -436.617132) (xy 166.552224 -436.663645) (xy 166.515007 -436.705182) (xy 166.472139 -436.740857)
			(xy 166.424533 -436.769911) (xy 166.373204 -436.791723) (xy 166.319247 -436.805829) (xy 166.26381 -436.811929)
			(xy 166.208076 -436.809892) (xy 166.153233 -436.799762) (xy 166.100449 -436.781755) (xy 166.050849 -436.756254)
			(xy 166.005491 -436.723803) (xy 165.965342 -436.685094) (xy 165.931256 -436.640951) (xy 165.90396 -436.592316)
			(xy 165.884037 -436.540225) (xy 165.871911 -436.485788) (xy 165.86784 -436.430166) (xy 160.856676 -436.430166)
			(xy 160.856676 -437.27243) (xy 160.961322 -437.27243) (xy 160.965393 -437.216808) (xy 160.977519 -437.162371)
			(xy 160.997442 -437.11028) (xy 161.024738 -437.061645) (xy 161.058824 -437.017502) (xy 161.098973 -436.978793)
			(xy 161.144331 -436.946342) (xy 161.193931 -436.920841) (xy 161.246715 -436.902834) (xy 161.301558 -436.892704)
			(xy 161.357292 -436.890667) (xy 161.412729 -436.896767) (xy 161.466686 -436.910873) (xy 161.518015 -436.932685)
			(xy 161.565621 -436.961739) (xy 161.608489 -436.997414) (xy 161.645706 -437.038951) (xy 161.676479 -437.085464)
			(xy 161.700151 -437.135961) (xy 161.716219 -437.189368) (xy 161.724339 -437.244544) (xy 161.724848 -437.27243)
			(xy 161.724339 -437.300316) (xy 161.716219 -437.355492) (xy 161.700151 -437.408899) (xy 161.676479 -437.459396)
			(xy 161.645706 -437.505909) (xy 161.608489 -437.547446) (xy 161.565621 -437.583121) (xy 161.518015 -437.612175)
			(xy 161.466686 -437.633987) (xy 161.412729 -437.648093) (xy 161.357292 -437.654193) (xy 161.301558 -437.652156)
			(xy 161.246715 -437.642026) (xy 161.193931 -437.624019) (xy 161.144331 -437.598518) (xy 161.098973 -437.566067)
			(xy 161.058824 -437.527358) (xy 161.024738 -437.483215) (xy 160.997442 -437.43458) (xy 160.977519 -437.382489)
			(xy 160.965393 -437.328052) (xy 160.961322 -437.27243) (xy 160.856676 -437.27243) (xy 160.856676 -438.241905)
			(xy 163.315644 -438.241905) (xy 163.315644 -438.177983) (xy 163.323655 -438.114565) (xy 163.339552 -438.052651)
			(xy 163.363084 -437.993218) (xy 163.393878 -437.937203) (xy 163.431451 -437.885488) (xy 163.475208 -437.838891)
			(xy 163.524461 -437.798146) (xy 163.578432 -437.763895) (xy 163.636271 -437.736678) (xy 163.697064 -437.716925)
			(xy 163.759854 -437.704947) (xy 163.82365 -437.700934) (xy 163.887446 -437.704947) (xy 163.950236 -437.716925)
			(xy 164.011029 -437.736678) (xy 164.068868 -437.763895) (xy 164.122839 -437.798146) (xy 164.172092 -437.838891)
			(xy 164.215849 -437.885488) (xy 164.253422 -437.937203) (xy 164.284216 -437.993218) (xy 164.307748 -438.052651)
			(xy 164.323645 -438.114565) (xy 164.331656 -438.177983) (xy 164.332158 -438.209944) (xy 164.331656 -438.241905)
			(xy 164.323645 -438.305323) (xy 164.307748 -438.367237) (xy 164.284216 -438.42667) (xy 164.253422 -438.482685)
			(xy 164.215849 -438.5344) (xy 164.172092 -438.580997) (xy 164.122839 -438.621742) (xy 164.068868 -438.655993)
			(xy 164.011029 -438.68321) (xy 163.950236 -438.702963) (xy 163.887446 -438.714941) (xy 163.82365 -438.718955)
			(xy 163.759854 -438.714941) (xy 163.697064 -438.702963) (xy 163.636271 -438.68321) (xy 163.578432 -438.655993)
			(xy 163.524461 -438.621742) (xy 163.475208 -438.580997) (xy 163.431451 -438.5344) (xy 163.393878 -438.482685)
			(xy 163.363084 -438.42667) (xy 163.339552 -438.367237) (xy 163.323655 -438.305323) (xy 163.315644 -438.241905)
			(xy 160.856676 -438.241905) (xy 160.856676 -438.649364) (xy 160.85711 -438.65943) (xy 160.864838 -438.678019)
			(xy 160.871662 -438.685432) (xy 161.09823 -438.912) (xy 165.863014 -438.912) (xy 165.867085 -438.856378)
			(xy 165.879211 -438.801941) (xy 165.899134 -438.74985) (xy 165.92643 -438.701215) (xy 165.960516 -438.657072)
			(xy 166.000665 -438.618363) (xy 166.046023 -438.585912) (xy 166.095623 -438.560411) (xy 166.148407 -438.542404)
			(xy 166.20325 -438.532274) (xy 166.258984 -438.530237) (xy 166.314421 -438.536337) (xy 166.368378 -438.550443)
			(xy 166.419707 -438.572255) (xy 166.467313 -438.601309) (xy 166.510181 -438.636984) (xy 166.547398 -438.678521)
			(xy 166.578171 -438.725034) (xy 166.601843 -438.775531) (xy 166.617911 -438.828938) (xy 166.626031 -438.884114)
			(xy 166.62654 -438.912) (xy 166.626031 -438.939886) (xy 166.617911 -438.995062) (xy 166.601843 -439.048469)
			(xy 166.578171 -439.098966) (xy 166.547398 -439.145479) (xy 166.510181 -439.187016) (xy 166.467313 -439.222691)
			(xy 166.419707 -439.251745) (xy 166.368378 -439.273557) (xy 166.314421 -439.287663) (xy 166.258984 -439.293763)
			(xy 166.20325 -439.291726) (xy 166.148407 -439.281596) (xy 166.095623 -439.263589) (xy 166.046023 -439.238088)
			(xy 166.000665 -439.205637) (xy 165.960516 -439.166928) (xy 165.92643 -439.122785) (xy 165.899134 -439.07415)
			(xy 165.879211 -439.022059) (xy 165.867085 -438.967622) (xy 165.863014 -438.912) (xy 161.09823 -438.912)
			(xy 162.221926 -440.035696) (xy 162.229326 -440.042539) (xy 162.247924 -440.050264) (xy 162.257994 -440.050682)
			(xy 167.164512 -440.050682) (xy 167.190674 -440.031886) (xy 167.196008 -440.016392) (xy 167.205257 -439.990924)
			(xy 167.22993 -439.942684) (xy 167.261182 -439.898421) (xy 167.298381 -439.859025) (xy 167.340781 -439.825289)
			(xy 167.363902 -439.81116) (xy 167.37203 -439.806588) (xy 167.38346 -439.792618) (xy 167.410638 -439.711592)
			(xy 167.409876 -439.693558) (xy 167.40632 -439.684922) (xy 167.394107 -439.653955) (xy 167.376916 -439.589645)
			(xy 167.368256 -439.523642) (xy 167.367712 -439.490358) (xy 167.36823 -439.457513) (xy 167.376695 -439.392371)
			(xy 167.393478 -439.328862) (xy 167.4183 -439.268042) (xy 167.450748 -439.210926) (xy 167.490281 -439.158464)
			(xy 167.536241 -439.111529) (xy 167.587862 -439.070904) (xy 167.644285 -439.037266) (xy 167.704571 -439.011173)
			(xy 167.736012 -439.001662) (xy 167.744902 -438.999122) (xy 167.75938 -438.9882) (xy 167.805862 -438.917334)
			(xy 167.809926 -438.899808) (xy 167.808656 -438.890664) (xy 167.807106 -438.878149) (xy 167.805455 -438.852982)
			(xy 167.805354 -438.840372) (xy 167.80584 -438.813121) (xy 167.813596 -438.759173) (xy 167.828951 -438.706878)
			(xy 167.851593 -438.657301) (xy 167.881059 -438.611451) (xy 167.91675 -438.57026) (xy 167.957941 -438.534569)
			(xy 168.003791 -438.505103) (xy 168.053368 -438.482461) (xy 168.105663 -438.467106) (xy 168.159611 -438.45935)
			(xy 168.214113 -438.45935) (xy 168.268061 -438.467106) (xy 168.320356 -438.482461) (xy 168.369933 -438.505103)
			(xy 168.415783 -438.534569) (xy 168.456974 -438.57026) (xy 168.492665 -438.611451) (xy 168.522131 -438.657301)
			(xy 168.544773 -438.706878) (xy 168.560128 -438.759173) (xy 168.567884 -438.813121) (xy 168.56837 -438.840372)
			(xy 168.567863 -438.868278) (xy 168.559742 -438.923497) (xy 168.54367 -438.976946) (xy 168.519988 -439.027485)
			(xy 168.489201 -439.074039) (xy 168.451965 -439.115615) (xy 168.409073 -439.151328) (xy 168.38549 -439.166254)
			(xy 168.377362 -439.17108) (xy 168.366186 -439.185304) (xy 168.340278 -439.265822) (xy 168.34104 -439.283856)
			(xy 168.344596 -439.292492) (xy 168.357287 -439.323919) (xy 168.375164 -439.389295) (xy 168.384179 -439.45647)
			(xy 168.384728 -439.490358) (xy 168.384274 -439.521271) (xy 168.37678 -439.58264) (xy 168.361899 -439.642647)
			(xy 168.33985 -439.700407) (xy 168.310958 -439.755066) (xy 168.27565 -439.805817) (xy 168.234448 -439.851911)
			(xy 168.2115 -439.872628) (xy 168.199308 -439.883296) (xy 168.191688 -439.913776) (xy 168.230804 -440.017662)
			(xy 168.234894 -440.027168) (xy 168.249198 -440.042095) (xy 168.268218 -440.0502) (xy 168.278556 -440.050682)
			(xy 171.15282 -440.050682) (xy 171.162888 -440.050255) (xy 171.181486 -440.042533) (xy 171.188888 -440.035696)
			(xy 173.609254 -437.61533) (xy 173.616094 -437.60793) (xy 173.623811 -437.589331) (xy 173.62424 -437.579262)
			(xy 173.62424 -432.58359) (xy 173.624666 -432.573522) (xy 173.632388 -432.554924) (xy 173.639226 -432.547522)
			(xy 176.576736 -429.610012) (xy 176.584136 -429.60317) (xy 176.602734 -429.595447) (xy 176.612804 -429.595026)
			(xy 181.541674 -429.595026) (xy 181.551738 -429.595463) (xy 181.57032 -429.603199) (xy 181.577742 -429.610012)
			(xy 182.04434 -430.07661) (xy 187.209682 -430.07661) (xy 187.213753 -430.020988) (xy 187.225879 -429.966551)
			(xy 187.245802 -429.91446) (xy 187.273098 -429.865825) (xy 187.307184 -429.821682) (xy 187.347333 -429.782973)
			(xy 187.392691 -429.750522) (xy 187.442291 -429.725021) (xy 187.495075 -429.707014) (xy 187.549918 -429.696884)
			(xy 187.605652 -429.694847) (xy 187.661089 -429.700947) (xy 187.715046 -429.715053) (xy 187.766375 -429.736865)
			(xy 187.813981 -429.765919) (xy 187.856849 -429.801594) (xy 187.894066 -429.843131) (xy 187.924839 -429.889644)
			(xy 187.948511 -429.940141) (xy 187.964579 -429.993548) (xy 187.972699 -430.048724) (xy 187.973208 -430.07661)
			(xy 187.972699 -430.104496) (xy 187.964579 -430.159672) (xy 187.948511 -430.213079) (xy 187.924839 -430.263576)
			(xy 187.894066 -430.310089) (xy 187.856849 -430.351626) (xy 187.813981 -430.387301) (xy 187.766375 -430.416355)
			(xy 187.715046 -430.438167) (xy 187.661089 -430.452273) (xy 187.605652 -430.458373) (xy 187.549918 -430.456336)
			(xy 187.495075 -430.446206) (xy 187.442291 -430.428199) (xy 187.392691 -430.402698) (xy 187.347333 -430.370247)
			(xy 187.307184 -430.331538) (xy 187.273098 -430.287395) (xy 187.245802 -430.23876) (xy 187.225879 -430.186669)
			(xy 187.213753 -430.132232) (xy 187.209682 -430.07661) (xy 182.04434 -430.07661) (xy 182.67583 -430.7081)
			(xy 185.635322 -430.7081) (xy 185.639337 -430.644295) (xy 185.651316 -430.581496) (xy 185.671072 -430.520694)
			(xy 185.698293 -430.462848) (xy 185.73255 -430.408869) (xy 185.773301 -430.35961) (xy 185.819905 -430.315846)
			(xy 185.871627 -430.278269) (xy 185.927651 -430.24747) (xy 185.987092 -430.223937) (xy 186.049015 -430.208038)
			(xy 186.112442 -430.200027) (xy 186.144408 -430.199546) (xy 186.175812 -430.199996) (xy 186.238143 -430.207729)
			(xy 186.299048 -430.223075) (xy 186.3576 -430.245801) (xy 186.41291 -430.275562) (xy 186.464136 -430.311906)
			(xy 186.510498 -430.354278) (xy 186.53125 -430.377854) (xy 186.538108 -430.385982) (xy 186.556904 -430.395126)
			(xy 186.6519 -430.399698) (xy 186.671458 -430.392332) (xy 186.679078 -430.384966) (xy 186.700548 -430.364971)
			(xy 186.748481 -430.331144) (xy 186.801026 -430.30505) (xy 186.856945 -430.287302) (xy 186.91492 -430.278319)
			(xy 186.944254 -430.277778) (xy 186.972399 -430.278264) (xy 187.028077 -430.286543) (xy 187.081935 -430.302912)
			(xy 187.132803 -430.327017) (xy 187.179578 -430.358334) (xy 187.221243 -430.396184) (xy 187.256896 -430.439744)
			(xy 187.285761 -430.48807) (xy 187.307212 -430.540113) (xy 187.320784 -430.594743) (xy 187.323984 -430.62271)
			(xy 187.325254 -430.636426) (xy 187.341764 -430.659032) (xy 187.449968 -430.704752) (xy 187.477654 -430.700942)
			(xy 187.488576 -430.692306) (xy 187.522337 -430.666) (xy 187.594058 -430.619286) (xy 187.669934 -430.579674)
			(xy 187.749263 -430.547531) (xy 187.831311 -430.523153) (xy 187.91532 -430.506765) (xy 188.000516 -430.498519)
			(xy 188.043312 -430.497996) (xy 188.085237 -430.498488) (xy 188.168714 -430.50638) (xy 188.251077 -430.522093)
			(xy 188.331597 -430.545487) (xy 188.409558 -430.576355) (xy 188.484267 -430.614423) (xy 188.555063 -430.659352)
			(xy 188.621316 -430.710745) (xy 188.682439 -430.768144) (xy 188.704479 -430.793144) (xy 189.170056 -430.793144)
			(xy 189.170611 -430.760712) (xy 189.178854 -430.696375) (xy 189.195212 -430.633608) (xy 189.219419 -430.573431)
			(xy 189.251082 -430.516821) (xy 189.289687 -430.464697) (xy 189.334607 -430.417905) (xy 189.35954 -430.397158)
			(xy 189.366409 -430.391124) (xy 189.375649 -430.375363) (xy 189.377574 -430.366424) (xy 189.382908 -430.336452)
			(xy 189.384092 -430.327378) (xy 189.380724 -430.30941) (xy 189.376304 -430.3014) (xy 189.358882 -430.271478)
			(xy 189.331411 -430.207922) (xy 189.312823 -430.141225) (xy 189.303463 -430.072622) (xy 189.302898 -430.038002)
			(xy 189.3034 -430.006041) (xy 189.311411 -429.942623) (xy 189.327308 -429.880709) (xy 189.35084 -429.821276)
			(xy 189.381634 -429.765261) (xy 189.419207 -429.713546) (xy 189.462964 -429.666949) (xy 189.512217 -429.626204)
			(xy 189.566188 -429.591953) (xy 189.624027 -429.564736) (xy 189.68482 -429.544983) (xy 189.74761 -429.533005)
			(xy 189.811406 -429.528992) (xy 189.875202 -429.533005) (xy 189.937992 -429.544983) (xy 189.986342 -429.560693)
			(xy 190.547492 -429.560693) (xy 190.547492 -429.496771) (xy 190.555503 -429.433353) (xy 190.5714 -429.371439)
			(xy 190.594932 -429.312006) (xy 190.625726 -429.255991) (xy 190.663299 -429.204276) (xy 190.707056 -429.157679)
			(xy 190.756309 -429.116934) (xy 190.81028 -429.082683) (xy 190.868119 -429.055466) (xy 190.928912 -429.035713)
			(xy 190.991702 -429.023735) (xy 191.055498 -429.019722) (xy 191.119294 -429.023735) (xy 191.182084 -429.035713)
			(xy 191.242877 -429.055466) (xy 191.300716 -429.082683) (xy 191.354687 -429.116934) (xy 191.40394 -429.157679)
			(xy 191.447697 -429.204276) (xy 191.48527 -429.255991) (xy 191.516064 -429.312006) (xy 191.539596 -429.371439)
			(xy 191.555493 -429.433353) (xy 191.563504 -429.496771) (xy 191.564006 -429.528732) (xy 191.563504 -429.560693)
			(xy 191.555493 -429.624111) (xy 191.539596 -429.686025) (xy 191.516064 -429.745458) (xy 191.48527 -429.801473)
			(xy 191.447697 -429.853188) (xy 191.40394 -429.899785) (xy 191.354687 -429.94053) (xy 191.300716 -429.974781)
			(xy 191.242877 -430.001998) (xy 191.182084 -430.021751) (xy 191.119294 -430.033729) (xy 191.055498 -430.037743)
			(xy 190.991702 -430.033729) (xy 190.928912 -430.021751) (xy 190.868119 -430.001998) (xy 190.81028 -429.974781)
			(xy 190.756309 -429.94053) (xy 190.707056 -429.899785) (xy 190.663299 -429.853188) (xy 190.625726 -429.801473)
			(xy 190.594932 -429.745458) (xy 190.5714 -429.686025) (xy 190.555503 -429.624111) (xy 190.547492 -429.560693)
			(xy 189.986342 -429.560693) (xy 189.998785 -429.564736) (xy 190.056624 -429.591953) (xy 190.110595 -429.626204)
			(xy 190.159848 -429.666949) (xy 190.203605 -429.713546) (xy 190.241178 -429.765261) (xy 190.271972 -429.821276)
			(xy 190.295504 -429.880709) (xy 190.311401 -429.942623) (xy 190.319412 -430.006041) (xy 190.319914 -430.038002)
			(xy 190.319403 -430.070435) (xy 190.311154 -430.134775) (xy 190.294789 -430.197543) (xy 190.270575 -430.257721)
			(xy 190.238905 -430.314331) (xy 190.200293 -430.366453) (xy 190.155366 -430.413242) (xy 190.13043 -430.433988)
			(xy 190.123591 -430.440052) (xy 190.114332 -430.455791) (xy 190.112396 -430.464722) (xy 190.107062 -430.494694)
			(xy 190.105858 -430.503766) (xy 190.10924 -430.521736) (xy 190.113666 -430.529746) (xy 190.131103 -430.559659)
			(xy 190.158571 -430.623218) (xy 190.177155 -430.689918) (xy 190.18651 -430.758523) (xy 190.187072 -430.793144)
			(xy 190.18657 -430.825105) (xy 190.178559 -430.888523) (xy 190.169538 -430.923657) (xy 191.810888 -430.923657)
			(xy 191.810888 -430.859735) (xy 191.818899 -430.796317) (xy 191.834796 -430.734403) (xy 191.858328 -430.67497)
			(xy 191.889122 -430.618955) (xy 191.926695 -430.56724) (xy 191.970452 -430.520643) (xy 192.019705 -430.479898)
			(xy 192.073676 -430.445647) (xy 192.131515 -430.41843) (xy 192.192308 -430.398677) (xy 192.255098 -430.386699)
			(xy 192.318894 -430.382686) (xy 192.38269 -430.386699) (xy 192.44548 -430.398677) (xy 192.506273 -430.41843)
			(xy 192.564112 -430.445647) (xy 192.618083 -430.479898) (xy 192.667336 -430.520643) (xy 192.711093 -430.56724)
			(xy 192.748666 -430.618955) (xy 192.77946 -430.67497) (xy 192.802992 -430.734403) (xy 192.818889 -430.796317)
			(xy 192.8269 -430.859735) (xy 192.827402 -430.891696) (xy 192.8269 -430.923657) (xy 192.818889 -430.987075)
			(xy 192.802992 -431.048989) (xy 192.77946 -431.108422) (xy 192.748666 -431.164437) (xy 192.711093 -431.216152)
			(xy 192.667336 -431.262749) (xy 192.618083 -431.303494) (xy 192.564112 -431.337745) (xy 192.506273 -431.364962)
			(xy 192.44548 -431.384715) (xy 192.38269 -431.396693) (xy 192.318894 -431.400707) (xy 192.255098 -431.396693)
			(xy 192.192308 -431.384715) (xy 192.131515 -431.364962) (xy 192.073676 -431.337745) (xy 192.019705 -431.303494)
			(xy 191.970452 -431.262749) (xy 191.926695 -431.216152) (xy 191.889122 -431.164437) (xy 191.858328 -431.108422)
			(xy 191.834796 -431.048989) (xy 191.818899 -430.987075) (xy 191.810888 -430.923657) (xy 190.169538 -430.923657)
			(xy 190.162662 -430.950437) (xy 190.13913 -431.00987) (xy 190.108336 -431.065885) (xy 190.070763 -431.1176)
			(xy 190.027006 -431.164197) (xy 189.977753 -431.204942) (xy 189.923782 -431.239193) (xy 189.865943 -431.26641)
			(xy 189.80515 -431.286163) (xy 189.74236 -431.298141) (xy 189.678564 -431.302155) (xy 189.614768 -431.298141)
			(xy 189.551978 -431.286163) (xy 189.491185 -431.26641) (xy 189.433346 -431.239193) (xy 189.379375 -431.204942)
			(xy 189.330122 -431.164197) (xy 189.286365 -431.1176) (xy 189.248792 -431.065885) (xy 189.217998 -431.00987)
			(xy 189.194466 -430.950437) (xy 189.178569 -430.888523) (xy 189.170558 -430.825105) (xy 189.170056 -430.793144)
			(xy 188.704479 -430.793144) (xy 188.737889 -430.831041) (xy 188.787174 -430.898877) (xy 188.829856 -430.97105)
			(xy 188.865556 -431.046919) (xy 188.893959 -431.125811) (xy 188.91481 -431.207026) (xy 188.927927 -431.289843)
			(xy 188.933191 -431.373527) (xy 188.930556 -431.457335) (xy 188.920047 -431.540523) (xy 188.901755 -431.622353)
			(xy 188.875844 -431.702098) (xy 188.842543 -431.779051) (xy 188.802148 -431.852528) (xy 188.755017 -431.921878)
			(xy 188.701569 -431.986485) (xy 188.642279 -432.045775) (xy 188.577671 -432.099222) (xy 188.508321 -432.146352)
			(xy 188.434843 -432.186746) (xy 188.35789 -432.220047) (xy 188.278145 -432.245957) (xy 188.196315 -432.264248)
			(xy 188.113127 -432.274757) (xy 188.029319 -432.277391) (xy 187.945635 -432.272126) (xy 187.862819 -432.259009)
			(xy 187.781604 -432.238156) (xy 187.702712 -432.209753) (xy 187.626843 -432.174052) (xy 187.55467 -432.131369)
			(xy 187.486834 -432.082084) (xy 187.423938 -432.026634) (xy 187.366539 -431.96551) (xy 187.315147 -431.899257)
			(xy 187.270219 -431.82846) (xy 187.232152 -431.75375) (xy 187.201284 -431.675789) (xy 187.177891 -431.59527)
			(xy 187.162179 -431.512906) (xy 187.154288 -431.429429) (xy 187.153804 -431.387504) (xy 187.154281 -431.347032)
			(xy 187.161671 -431.266426) (xy 187.176346 -431.186823) (xy 187.186824 -431.147728) (xy 187.190634 -431.134266)
			(xy 187.183268 -431.107088) (xy 187.09894 -431.025554) (xy 187.071762 -431.019204) (xy 187.058554 -431.023268)
			(xy 187.030692 -431.03146) (xy 186.97329 -431.040254) (xy 186.944254 -431.040794) (xy 186.9134 -431.040188)
			(xy 186.852495 -431.030269) (xy 186.793978 -431.010682) (xy 186.739375 -430.981936) (xy 186.714384 -430.963832)
			(xy 186.706002 -430.957482) (xy 186.685682 -430.952402) (xy 186.591702 -430.968404) (xy 186.574176 -430.979834)
			(xy 186.568334 -430.988724) (xy 186.550664 -431.014619) (xy 186.509903 -431.062249) (xy 186.463593 -431.104506)
			(xy 186.412439 -431.140748) (xy 186.357217 -431.170425) (xy 186.298765 -431.193086) (xy 186.237969 -431.208388)
			(xy 186.175754 -431.216098) (xy 186.144408 -431.216562) (xy 186.112442 -431.216173) (xy 186.049015 -431.208162)
			(xy 185.987092 -431.192263) (xy 185.927651 -431.16873) (xy 185.871627 -431.137931) (xy 185.819905 -431.100354)
			(xy 185.773301 -431.05659) (xy 185.73255 -431.007331) (xy 185.698293 -430.953352) (xy 185.671072 -430.895506)
			(xy 185.651316 -430.834704) (xy 185.639337 -430.771905) (xy 185.635322 -430.7081) (xy 182.67583 -430.7081)
			(xy 184.471818 -432.504088) (xy 191.422032 -432.504088) (xy 191.425998 -432.419557) (xy 191.437863 -432.33577)
			(xy 191.457521 -432.253461) (xy 191.484801 -432.173355) (xy 191.519462 -432.096156) (xy 191.5612 -432.022541)
			(xy 191.609647 -431.953158) (xy 191.664379 -431.888617) (xy 191.724915 -431.829485) (xy 191.790721 -431.776281)
			(xy 191.861221 -431.729473) (xy 191.935793 -431.689472) (xy 192.013784 -431.65663) (xy 192.094508 -431.631236)
			(xy 192.177255 -431.613513) (xy 192.261297 -431.603615) (xy 192.345898 -431.601632) (xy 192.430312 -431.607579)
			(xy 192.513799 -431.621404) (xy 192.595624 -431.642987) (xy 192.675068 -431.672137) (xy 192.751434 -431.708598)
			(xy 192.82405 -431.75205) (xy 192.892278 -431.802111) (xy 192.955518 -431.858341) (xy 193.013215 -431.920246)
			(xy 193.064862 -431.987282) (xy 193.110004 -432.058859) (xy 193.148246 -432.134349) (xy 193.17925 -432.213088)
			(xy 193.202745 -432.294385) (xy 193.218524 -432.377524) (xy 193.226448 -432.461776) (xy 193.226944 -432.504088)
			(xy 193.226448 -432.5464) (xy 193.218524 -432.630652) (xy 193.202745 -432.713791) (xy 193.17925 -432.795088)
			(xy 193.148246 -432.873827) (xy 193.110004 -432.949317) (xy 193.064862 -433.020894) (xy 193.013215 -433.08793)
			(xy 192.955518 -433.149835) (xy 192.892278 -433.206065) (xy 192.82405 -433.256126) (xy 192.751434 -433.299578)
			(xy 192.675068 -433.336039) (xy 192.595624 -433.365189) (xy 192.513799 -433.386772) (xy 192.430312 -433.400597)
			(xy 192.345898 -433.406544) (xy 192.261297 -433.404561) (xy 192.177255 -433.394663) (xy 192.094508 -433.37694)
			(xy 192.013784 -433.351546) (xy 191.935793 -433.318704) (xy 191.861221 -433.278703) (xy 191.790721 -433.231895)
			(xy 191.724915 -433.178691) (xy 191.664379 -433.119559) (xy 191.609647 -433.055018) (xy 191.5612 -432.985635)
			(xy 191.519462 -432.91202) (xy 191.484801 -432.834821) (xy 191.457521 -432.754715) (xy 191.437863 -432.672406)
			(xy 191.425998 -432.588619) (xy 191.422032 -432.504088) (xy 184.471818 -432.504088) (xy 186.358784 -434.391054)
			(xy 186.365624 -434.398455) (xy 186.373341 -434.417053) (xy 186.37377 -434.427122) (xy 186.37377 -435.044088)
			(xy 191.295024 -435.044088) (xy 191.299053 -434.953082) (xy 191.31111 -434.862788) (xy 191.3311 -434.773913)
			(xy 191.358866 -434.687153) (xy 191.394192 -434.603186) (xy 191.4368 -434.52267) (xy 191.486358 -434.446234)
			(xy 191.542477 -434.374478) (xy 191.604718 -434.307962) (xy 191.672595 -434.247207) (xy 191.745575 -434.192689)
			(xy 191.823088 -434.144835) (xy 191.904527 -434.104018) (xy 191.989255 -434.070559) (xy 192.076609 -434.044718)
			(xy 192.165904 -434.0267) (xy 192.256442 -434.016643) (xy 192.347515 -434.014628) (xy 192.43841 -434.02067)
			(xy 192.528415 -434.034721) (xy 192.616826 -434.056672) (xy 192.702951 -434.086351) (xy 192.786116 -434.123525)
			(xy 192.86567 -434.167904) (xy 192.94099 -434.219141) (xy 193.011488 -434.276834) (xy 193.07661 -434.340531)
			(xy 193.135848 -434.409735) (xy 193.188738 -434.483904) (xy 193.234867 -434.562456) (xy 193.273872 -434.644779)
			(xy 193.305449 -434.730226) (xy 193.32935 -434.81813) (xy 193.345389 -434.907802) (xy 193.35344 -434.99854)
			(xy 193.353944 -435.044088) (xy 193.35344 -435.089636) (xy 193.345389 -435.180374) (xy 193.32935 -435.270046)
			(xy 193.305449 -435.35795) (xy 193.273872 -435.443397) (xy 193.234867 -435.52572) (xy 193.188738 -435.604272)
			(xy 193.135848 -435.678441) (xy 193.07661 -435.747645) (xy 193.011488 -435.811342) (xy 192.94099 -435.869035)
			(xy 192.86567 -435.920272) (xy 192.786116 -435.964651) (xy 192.702951 -436.001825) (xy 192.616826 -436.031504)
			(xy 192.528415 -436.053455) (xy 192.43841 -436.067506) (xy 192.347515 -436.073548) (xy 192.256442 -436.071533)
			(xy 192.165904 -436.061476) (xy 192.076609 -436.043458) (xy 191.989255 -436.017617) (xy 191.904527 -435.984158)
			(xy 191.823088 -435.943341) (xy 191.745575 -435.895487) (xy 191.672595 -435.840969) (xy 191.604718 -435.780214)
			(xy 191.542477 -435.713698) (xy 191.486358 -435.641942) (xy 191.4368 -435.565506) (xy 191.394192 -435.48499)
			(xy 191.358866 -435.401023) (xy 191.3311 -435.314263) (xy 191.31111 -435.225388) (xy 191.299053 -435.135094)
			(xy 191.295024 -435.044088) (xy 186.37377 -435.044088) (xy 186.37377 -437.584088) (xy 191.295024 -437.584088)
			(xy 191.299053 -437.493082) (xy 191.31111 -437.402788) (xy 191.3311 -437.313913) (xy 191.358866 -437.227153)
			(xy 191.394192 -437.143186) (xy 191.4368 -437.06267) (xy 191.486358 -436.986234) (xy 191.542477 -436.914478)
			(xy 191.604718 -436.847962) (xy 191.672595 -436.787207) (xy 191.745575 -436.732689) (xy 191.823088 -436.684835)
			(xy 191.904527 -436.644018) (xy 191.989255 -436.610559) (xy 192.076609 -436.584718) (xy 192.165904 -436.5667)
			(xy 192.256442 -436.556643) (xy 192.347515 -436.554628) (xy 192.43841 -436.56067) (xy 192.528415 -436.574721)
			(xy 192.616826 -436.596672) (xy 192.702951 -436.626351) (xy 192.786116 -436.663525) (xy 192.86567 -436.707904)
			(xy 192.94099 -436.759141) (xy 193.011488 -436.816834) (xy 193.07661 -436.880531) (xy 193.135848 -436.949735)
			(xy 193.188738 -437.023904) (xy 193.234867 -437.102456) (xy 193.273872 -437.184779) (xy 193.305449 -437.270226)
			(xy 193.32935 -437.35813) (xy 193.345389 -437.447802) (xy 193.35344 -437.53854) (xy 193.353944 -437.584088)
			(xy 193.353867 -437.591063) (xy 276.104713 -437.591063) (xy 276.109924 -437.528198) (xy 276.122871 -437.46646)
			(xy 276.143356 -437.406798) (xy 276.171062 -437.350128) (xy 276.205566 -437.297321) (xy 276.246337 -437.249187)
			(xy 276.292748 -437.206465) (xy 276.344088 -437.169812) (xy 276.399566 -437.139792) (xy 276.458333 -437.116864)
			(xy 276.519483 -437.101381) (xy 276.58208 -437.09358) (xy 276.61362 -437.093106) (xy 276.643941 -437.093541)
			(xy 276.704153 -437.100737) (xy 276.763084 -437.115037) (xy 276.819899 -437.136237) (xy 276.847046 -437.149748)
			(xy 276.860035 -437.155953) (xy 276.88826 -437.161548) (xy 276.916925 -437.159045) (xy 276.943753 -437.148643)
			(xy 276.966614 -437.131169) (xy 276.983691 -437.108011) (xy 276.993629 -437.081007) (xy 276.995128 -437.06669)
			(xy 276.997674 -437.038169) (xy 277.010192 -436.982296) (xy 277.030921 -436.928921) (xy 277.059397 -436.879245)
			(xy 277.094978 -436.834384) (xy 277.136866 -436.795346) (xy 277.184119 -436.763009) (xy 277.235675 -436.738098)
			(xy 277.290375 -436.721174) (xy 277.346991 -436.712618) (xy 277.37562 -436.712106) (xy 277.402871 -436.712565)
			(xy 277.456819 -436.720324) (xy 277.509113 -436.735682) (xy 277.55869 -436.758325) (xy 277.604539 -436.787793)
			(xy 277.645729 -436.823486) (xy 277.681419 -436.864677) (xy 277.710885 -436.910528) (xy 277.733525 -436.960106)
			(xy 277.74888 -437.012401) (xy 277.756636 -437.066349) (xy 277.756636 -437.120851) (xy 277.74888 -437.174799)
			(xy 277.733525 -437.227094) (xy 277.710885 -437.276672) (xy 277.681419 -437.322523) (xy 277.645729 -437.363714)
			(xy 277.604539 -437.399407) (xy 277.55869 -437.428875) (xy 277.509113 -437.451518) (xy 277.456819 -437.466876)
			(xy 277.402871 -437.474635) (xy 277.37562 -437.475122) (xy 277.344647 -437.474558) (xy 277.283508 -437.464598)
			(xy 277.253954 -437.45531) (xy 277.240167 -437.451197) (xy 277.211436 -437.449973) (xy 277.183505 -437.456814)
			(xy 277.158592 -437.471178) (xy 277.138677 -437.491923) (xy 277.125342 -437.517401) (xy 277.119646 -437.545588)
			(xy 277.12035 -437.559958) (xy 277.122128 -437.601614) (xy 277.121617 -437.633154) (xy 277.113813 -437.69575)
			(xy 277.098326 -437.7569) (xy 277.075394 -437.815664) (xy 277.04537 -437.871141) (xy 277.008713 -437.922478)
			(xy 277.007601 -437.923686) (xy 281.436316 -437.923686) (xy 281.440387 -437.868064) (xy 281.452513 -437.813627)
			(xy 281.472436 -437.761536) (xy 281.499732 -437.712901) (xy 281.533818 -437.668758) (xy 281.573967 -437.630049)
			(xy 281.619325 -437.597598) (xy 281.668925 -437.572097) (xy 281.721709 -437.55409) (xy 281.776552 -437.54396)
			(xy 281.832286 -437.541923) (xy 281.887723 -437.548023) (xy 281.94168 -437.562129) (xy 281.993009 -437.583941)
			(xy 282.040615 -437.612995) (xy 282.083483 -437.64867) (xy 282.1207 -437.690207) (xy 282.151473 -437.73672)
			(xy 282.175145 -437.787217) (xy 282.191213 -437.840624) (xy 282.199333 -437.8958) (xy 282.199842 -437.923686)
			(xy 282.199333 -437.951572) (xy 282.191213 -438.006748) (xy 282.175145 -438.060155) (xy 282.151473 -438.110652)
			(xy 282.1207 -438.157165) (xy 282.083483 -438.198702) (xy 282.040615 -438.234377) (xy 281.993009 -438.263431)
			(xy 281.94168 -438.285243) (xy 281.887723 -438.299349) (xy 281.832286 -438.305449) (xy 281.776552 -438.303412)
			(xy 281.721709 -438.293282) (xy 281.668925 -438.275275) (xy 281.619325 -438.249774) (xy 281.573967 -438.217323)
			(xy 281.533818 -438.178614) (xy 281.499732 -438.134471) (xy 281.472436 -438.085836) (xy 281.452513 -438.033745)
			(xy 281.440387 -437.979308) (xy 281.436316 -437.923686) (xy 277.007601 -437.923686) (xy 276.965989 -437.968887)
			(xy 276.917852 -438.009654) (xy 276.865042 -438.044154) (xy 276.80837 -438.071857) (xy 276.748707 -438.092338)
			(xy 276.686969 -438.105281) (xy 276.624103 -438.110488) (xy 276.561077 -438.107879) (xy 276.498857 -438.097495)
			(xy 276.4384 -438.079494) (xy 276.380633 -438.054153) (xy 276.326444 -438.021861) (xy 276.276666 -437.983114)
			(xy 276.232063 -437.938508) (xy 276.19332 -437.888727) (xy 276.161032 -437.834537) (xy 276.135695 -437.776769)
			(xy 276.117698 -437.71631) (xy 276.107317 -437.654089) (xy 276.104713 -437.591063) (xy 193.353867 -437.591063)
			(xy 193.35344 -437.629636) (xy 193.345389 -437.720374) (xy 193.32935 -437.810046) (xy 193.305449 -437.89795)
			(xy 193.273872 -437.983397) (xy 193.234867 -438.06572) (xy 193.188738 -438.144272) (xy 193.135848 -438.218441)
			(xy 193.07661 -438.287645) (xy 193.011488 -438.351342) (xy 192.949936 -438.401714) (xy 276.993602 -438.401714)
			(xy 276.997673 -438.346092) (xy 277.009799 -438.291655) (xy 277.029722 -438.239564) (xy 277.057018 -438.190929)
			(xy 277.091104 -438.146786) (xy 277.131253 -438.108077) (xy 277.176611 -438.075626) (xy 277.226211 -438.050125)
			(xy 277.278995 -438.032118) (xy 277.333838 -438.021988) (xy 277.389572 -438.019951) (xy 277.445009 -438.026051)
			(xy 277.498966 -438.040157) (xy 277.550295 -438.061969) (xy 277.597901 -438.091023) (xy 277.640769 -438.126698)
			(xy 277.677986 -438.168235) (xy 277.708759 -438.214748) (xy 277.732431 -438.265245) (xy 277.748499 -438.318652)
			(xy 277.756619 -438.373828) (xy 277.757128 -438.401714) (xy 277.756619 -438.4296) (xy 277.748499 -438.484776)
			(xy 277.732431 -438.538183) (xy 277.708759 -438.58868) (xy 277.677986 -438.635193) (xy 277.640769 -438.67673)
			(xy 277.597901 -438.712405) (xy 277.550295 -438.741459) (xy 277.498966 -438.763271) (xy 277.445009 -438.777377)
			(xy 277.389572 -438.783477) (xy 277.333838 -438.78144) (xy 277.278995 -438.77131) (xy 277.226211 -438.753303)
			(xy 277.176611 -438.727802) (xy 277.131253 -438.695351) (xy 277.091104 -438.656642) (xy 277.057018 -438.612499)
			(xy 277.029722 -438.563864) (xy 277.009799 -438.511773) (xy 276.997673 -438.457336) (xy 276.993602 -438.401714)
			(xy 192.949936 -438.401714) (xy 192.94099 -438.409035) (xy 192.86567 -438.460272) (xy 192.786116 -438.504651)
			(xy 192.702951 -438.541825) (xy 192.616826 -438.571504) (xy 192.528415 -438.593455) (xy 192.43841 -438.607506)
			(xy 192.347515 -438.613548) (xy 192.256442 -438.611533) (xy 192.165904 -438.601476) (xy 192.076609 -438.583458)
			(xy 191.989255 -438.557617) (xy 191.904527 -438.524158) (xy 191.823088 -438.483341) (xy 191.745575 -438.435487)
			(xy 191.672595 -438.380969) (xy 191.604718 -438.320214) (xy 191.542477 -438.253698) (xy 191.486358 -438.181942)
			(xy 191.4368 -438.105506) (xy 191.394192 -438.02499) (xy 191.358866 -437.941023) (xy 191.3311 -437.854263)
			(xy 191.31111 -437.765388) (xy 191.299053 -437.675094) (xy 191.295024 -437.584088) (xy 186.37377 -437.584088)
			(xy 186.37377 -440.083702) (xy 186.374193 -440.093773) (xy 186.381904 -440.112379) (xy 186.388756 -440.11977)
			(xy 186.62142 -440.352434) (xy 186.628816 -440.359284) (xy 186.647415 -440.367022) (xy 186.657488 -440.36742)
			(xy 193.545714 -440.36742) (xy 193.555784 -440.366995) (xy 193.574386 -440.359279) (xy 193.581782 -440.352434)
			(xy 194.684904 -439.249312) (xy 194.692302 -439.242465) (xy 194.7109 -439.23473) (xy 194.720972 -439.234326)
			(xy 278.072342 -439.234326) (xy 278.082408 -439.234757) (xy 278.100999 -439.242485) (xy 278.10841 -439.249312)
			(xy 279.35936 -440.500262) (xy 279.36676 -440.507103) (xy 279.385359 -440.514822) (xy 279.395428 -440.515248)
		)
		(stroke
			(width 0)
			(type solid)
		)
		(fill yes)
		(layer "In11.Cu")
		(net "P3V3_AUX")
	)
	(gr_poly
		(pts
			(xy 329.82916 -373.5324) (xy 329.836677 -373.530795) (xy 329.85036 -373.523814) (xy 329.856084 -373.518684)
			(xy 338.059014 -365.315754) (xy 338.066411 -365.308904) (xy 338.085009 -365.301166) (xy 338.095082 -365.300768)
			(xy 346.307918 -365.300768) (xy 346.316554 -365.300006) (xy 346.324071 -365.298402) (xy 346.337756 -365.291423)
			(xy 346.343478 -365.28629) (xy 353.216972 -358.412796) (xy 353.223068 -358.383586) (xy 353.217734 -358.369362)
			(xy 353.209534 -358.347303) (xy 353.198009 -358.301672) (xy 353.192181 -358.254971) (xy 353.191826 -358.23144)
			(xy 353.192287 -358.204186) (xy 353.200039 -358.150233) (xy 353.215392 -358.097932) (xy 353.238033 -358.048349)
			(xy 353.2675 -358.002493) (xy 353.303194 -357.961299) (xy 353.344389 -357.925604) (xy 353.390244 -357.896136)
			(xy 353.439826 -357.873494) (xy 353.492127 -357.85814) (xy 353.54608 -357.850387) (xy 353.573334 -357.849932)
			(xy 353.596865 -357.850295) (xy 353.643567 -357.856115) (xy 353.689198 -357.867637) (xy 353.711256 -357.87584)
			(xy 353.72548 -357.881174) (xy 353.75469 -357.875078) (xy 354.09124 -357.538528) (xy 354.097336 -357.509318)
			(xy 354.092002 -357.495094) (xy 354.083807 -357.473034) (xy 354.07229 -357.427403) (xy 354.066471 -357.380703)
			(xy 354.066094 -357.357172) (xy 354.066582 -357.329922) (xy 354.074341 -357.275978) (xy 354.089699 -357.223686)
			(xy 354.112342 -357.174113) (xy 354.141809 -357.128266) (xy 354.1775 -357.087079) (xy 354.21869 -357.051391)
			(xy 354.264539 -357.021927) (xy 354.314114 -356.999289) (xy 354.366407 -356.983935) (xy 354.420352 -356.97618)
			(xy 354.447602 -356.975664) (xy 354.471134 -356.976025) (xy 354.517836 -356.981842) (xy 354.563468 -356.993361)
			(xy 354.585524 -357.001572) (xy 354.599748 -357.006906) (xy 354.628958 -357.00081) (xy 354.858066 -356.771702)
			(xy 354.862638 -356.73792) (xy 354.854256 -356.723188) (xy 354.842706 -356.701745) (xy 354.824538 -356.656554)
			(xy 354.81227 -356.609419) (xy 354.806101 -356.561105) (xy 354.805742 -356.536752) (xy 354.806209 -356.509503)
			(xy 354.813971 -356.45556) (xy 354.829332 -356.40327) (xy 354.851978 -356.353699) (xy 354.881448 -356.307856)
			(xy 354.917143 -356.266673) (xy 354.958335 -356.230989) (xy 355.004186 -356.201531) (xy 355.053762 -356.178898)
			(xy 355.106056 -356.163551) (xy 355.160001 -356.155802) (xy 355.18725 -356.155244) (xy 355.211603 -356.155612)
			(xy 355.259916 -356.161779) (xy 355.307052 -356.174043) (xy 355.352244 -356.192207) (xy 355.373686 -356.203758)
			(xy 355.388418 -356.21214) (xy 355.4222 -356.207568) (xy 359.720896 -351.908872) (xy 359.726738 -351.903284)
			(xy 360.662728 -350.132142) (xy 360.655108 -350.096074) (xy 360.64063 -350.084644) (xy 360.618369 -350.066447)
			(xy 360.57905 -350.024501) (xy 360.546467 -349.977132) (xy 360.521357 -349.925412) (xy 360.504288 -349.870511)
			(xy 360.495646 -349.813671) (xy 360.495088 -349.784924) (xy 360.49555 -349.75767) (xy 360.503304 -349.703716)
			(xy 360.518658 -349.651415) (xy 360.541299 -349.601832) (xy 360.570766 -349.555975) (xy 360.60646 -349.51478)
			(xy 360.647653 -349.479083) (xy 360.693507 -349.449612) (xy 360.743089 -349.426968) (xy 360.795389 -349.41161)
			(xy 360.849342 -349.403852) (xy 360.876596 -349.403416) (xy 360.905768 -349.403988) (xy 360.963426 -349.412916)
			(xy 360.991404 -349.421196) (xy 361.00893 -349.426784) (xy 361.042966 -349.412814) (xy 361.356148 -348.820232)
			(xy 361.355894 -348.807278) (xy 361.355894 -348.80296) (xy 361.356345 -348.776132) (xy 361.363851 -348.723003)
			(xy 361.378723 -348.671449) (xy 361.400669 -348.622486) (xy 361.429255 -348.577079) (xy 361.463918 -348.536123)
			(xy 361.503976 -348.500424) (xy 361.526074 -348.485206) (xy 361.531662 -348.48165) (xy 361.53979 -348.472506)
			(xy 362.48721 -346.680028) (xy 362.488734 -346.675202) (xy 362.496205 -346.65173) (xy 362.516362 -346.606785)
			(xy 362.542136 -346.564808) (xy 362.557314 -346.545408) (xy 362.560362 -346.541598) (xy 362.958888 -345.787472)
			(xy 362.961682 -345.771724) (xy 362.960412 -345.763596) (xy 362.958604 -345.75008) (xy 362.956695 -345.722876)
			(xy 362.956602 -345.70924) (xy 362.957067 -345.682638) (xy 362.964465 -345.62995) (xy 362.979108 -345.578801)
			(xy 363.000712 -345.53018) (xy 363.02886 -345.485031) (xy 363.063006 -345.44423) (xy 363.102487 -345.408565)
			(xy 363.146538 -345.37873) (xy 363.170216 -345.366594) (xy 363.177582 -345.363038) (xy 363.189012 -345.351862)
			(xy 363.499146 -344.765376) (xy 363.501876 -344.75979) (xy 363.504825 -344.747716) (xy 363.504988 -344.7415)
			(xy 363.504988 -341.049356) (xy 363.50448 -341.042244) (xy 362.605828 -334.705706) (xy 362.596684 -334.68945)
			(xy 362.58881 -334.6831) (xy 362.567054 -334.664882) (xy 362.528652 -334.623107) (xy 362.49686 -334.576105)
			(xy 362.472378 -334.524914) (xy 362.455747 -334.470662) (xy 362.447333 -334.414546) (xy 362.446824 -334.386174)
			(xy 362.447374 -334.357052) (xy 362.456223 -334.299484) (xy 362.473711 -334.243927) (xy 362.499433 -334.19167)
			(xy 362.515658 -334.16748) (xy 362.5215 -334.159352) (xy 362.525818 -334.141064) (xy 362.509562 -334.026256)
			(xy 362.486956 -334.002888) (xy 362.470446 -334.000094) (xy 362.444355 -333.994929) (xy 362.393825 -333.978332)
			(xy 362.346087 -333.954883) (xy 362.302065 -333.925035) (xy 362.262612 -333.889367) (xy 362.228491 -333.848568)
			(xy 362.200362 -333.803429) (xy 362.17877 -333.754823) (xy 362.164133 -333.70369) (xy 362.156734 -333.651021)
			(xy 362.156248 -333.624428) (xy 362.156709 -333.597898) (xy 362.164069 -333.54535) (xy 362.178637 -333.494329)
			(xy 362.200133 -333.445817) (xy 362.228141 -333.400751) (xy 362.262122 -333.359999) (xy 362.30142 -333.324347)
			(xy 362.345279 -333.294483) (xy 362.368846 -333.28229) (xy 362.383832 -333.274924) (xy 362.398818 -333.246222)
			(xy 362.096558 -331.113892) (xy 362.095086 -331.105761) (xy 362.087706 -331.090987) (xy 362.08208 -331.084936)
			(xy 358.626156 -327.629012) (xy 358.618756 -327.622171) (xy 358.600157 -327.614451) (xy 358.590088 -327.614026)
			(xy 354.832412 -327.614026) (xy 354.822732 -327.614456) (xy 354.804741 -327.621613) (xy 354.790647 -327.63489)
			(xy 354.786184 -327.64349) (xy 354.746814 -327.715118) (xy 354.74656 -327.715626) (xy 354.74656 -327.71588)
			(xy 354.744022 -327.720804) (xy 354.740949 -327.731444) (xy 354.740464 -327.736962) (xy 354.739956 -327.746106)
			(xy 354.747068 -327.769982) (xy 354.750624 -327.776078) (xy 354.750878 -327.776332) (xy 354.764195 -327.798936)
			(xy 354.785186 -327.847017) (xy 354.799398 -327.897519) (xy 354.806563 -327.94949) (xy 354.807012 -327.975722)
			(xy 354.805234 -328.013314) (xy 354.804472 -328.020426) (xy 354.800731 -328.047918) (xy 354.786324 -328.101495)
			(xy 354.764306 -328.15242) (xy 354.735142 -328.199618) (xy 354.699448 -328.242091) (xy 354.657976 -328.278945)
			(xy 354.611602 -328.309401) (xy 354.561304 -328.332816) (xy 354.508144 -328.348697) (xy 354.453245 -328.356707)
			(xy 354.425504 -328.35723) (xy 354.398134 -328.356758) (xy 354.343957 -328.348934) (xy 354.291454 -328.333445)
			(xy 354.241705 -328.31061) (xy 354.195731 -328.280898) (xy 354.174806 -328.26325) (xy 354.167694 -328.257154)
			(xy 354.15093 -328.250804) (xy 354.065078 -328.250804) (xy 354.048314 -328.257154) (xy 354.041202 -328.26325)
			(xy 354.020269 -328.280891) (xy 353.974301 -328.310615) (xy 353.924555 -328.333461) (xy 353.872053 -328.348957)
			(xy 353.817875 -328.356786) (xy 353.763133 -328.356786) (xy 353.708955 -328.348957) (xy 353.656453 -328.333461)
			(xy 353.606707 -328.310615) (xy 353.560739 -328.280891) (xy 353.539806 -328.26325) (xy 353.532694 -328.257154)
			(xy 353.51593 -328.250804) (xy 353.430078 -328.250804) (xy 353.413314 -328.257154) (xy 353.406202 -328.26325)
			(xy 353.385272 -328.280894) (xy 353.339306 -328.310624) (xy 353.28956 -328.333471) (xy 353.237056 -328.348963)
			(xy 353.182875 -328.356783) (xy 353.155504 -328.35723) (xy 353.128252 -328.356745) (xy 353.074303 -328.348989)
			(xy 353.022006 -328.333634) (xy 352.972427 -328.310993) (xy 352.926575 -328.281528) (xy 352.885382 -328.245836)
			(xy 352.849688 -328.204646) (xy 352.820219 -328.158796) (xy 352.797575 -328.109218) (xy 352.782217 -328.056923)
			(xy 352.774457 -328.002974) (xy 352.773996 -327.975722) (xy 352.774411 -327.949488) (xy 352.781565 -327.897509)
			(xy 352.795781 -327.847004) (xy 352.816792 -327.798926) (xy 352.83013 -327.776332) (xy 352.830384 -327.776078)
			(xy 352.83394 -327.769982) (xy 352.838512 -327.754488) (xy 352.84025 -327.747882) (xy 352.840511 -327.73423)
			(xy 352.83902 -327.727564) (xy 352.837242 -327.72096) (xy 352.793046 -327.640442) (xy 352.788353 -327.632674)
			(xy 352.774638 -327.620806) (xy 352.757662 -327.614425) (xy 352.748596 -327.614026) (xy 350.819212 -327.614026)
			(xy 350.809532 -327.614456) (xy 350.791541 -327.621613) (xy 350.777447 -327.63489) (xy 350.772984 -327.64349)
			(xy 350.733614 -327.715118) (xy 350.73336 -327.715626) (xy 350.73336 -327.71588) (xy 350.730822 -327.720804)
			(xy 350.727749 -327.731444) (xy 350.727264 -327.736962) (xy 350.726756 -327.746106) (xy 350.733868 -327.769982)
			(xy 350.737424 -327.776078) (xy 350.737678 -327.776332) (xy 350.750995 -327.798936) (xy 350.771986 -327.847017)
			(xy 350.786198 -327.897519) (xy 350.793363 -327.94949) (xy 350.793812 -327.975722) (xy 350.792034 -328.013314)
			(xy 350.791272 -328.020426) (xy 350.787531 -328.047918) (xy 350.773124 -328.101495) (xy 350.751106 -328.15242)
			(xy 350.721942 -328.199618) (xy 350.686248 -328.242091) (xy 350.644776 -328.278945) (xy 350.598402 -328.309401)
			(xy 350.548104 -328.332816) (xy 350.494944 -328.348697) (xy 350.440045 -328.356707) (xy 350.412304 -328.35723)
			(xy 350.384934 -328.356758) (xy 350.330757 -328.348934) (xy 350.278254 -328.333445) (xy 350.228505 -328.31061)
			(xy 350.182531 -328.280898) (xy 350.161606 -328.26325) (xy 350.154494 -328.257154) (xy 350.13773 -328.250804)
			(xy 350.051878 -328.250804) (xy 350.035114 -328.257154) (xy 350.028002 -328.26325) (xy 350.007069 -328.280891)
			(xy 349.961101 -328.310615) (xy 349.911355 -328.333461) (xy 349.858853 -328.348957) (xy 349.804675 -328.356786)
			(xy 349.749933 -328.356786) (xy 349.695755 -328.348957) (xy 349.643253 -328.333461) (xy 349.593507 -328.310615)
			(xy 349.547539 -328.280891) (xy 349.526606 -328.26325) (xy 349.519494 -328.257154) (xy 349.50273 -328.250804)
			(xy 349.416878 -328.250804) (xy 349.400114 -328.257154) (xy 349.393002 -328.26325) (xy 349.372072 -328.280894)
			(xy 349.326106 -328.310624) (xy 349.27636 -328.333471) (xy 349.223856 -328.348963) (xy 349.169675 -328.356783)
			(xy 349.142304 -328.35723) (xy 349.115052 -328.356745) (xy 349.061103 -328.348989) (xy 349.008806 -328.333634)
			(xy 348.959227 -328.310993) (xy 348.913375 -328.281528) (xy 348.872182 -328.245836) (xy 348.836488 -328.204646)
			(xy 348.807019 -328.158796) (xy 348.784375 -328.109218) (xy 348.769017 -328.056923) (xy 348.761257 -328.002974)
			(xy 348.760796 -327.975722) (xy 348.761211 -327.949488) (xy 348.768365 -327.897509) (xy 348.782581 -327.847004)
			(xy 348.803592 -327.798926) (xy 348.81693 -327.776332) (xy 348.817184 -327.776078) (xy 348.82074 -327.769982)
			(xy 348.825312 -327.754488) (xy 348.82705 -327.747882) (xy 348.827311 -327.73423) (xy 348.82582 -327.727564)
			(xy 348.824042 -327.72096) (xy 348.779846 -327.640442) (xy 348.775153 -327.632674) (xy 348.761438 -327.620806)
			(xy 348.744462 -327.614425) (xy 348.735396 -327.614026) (xy 322.245228 -327.614026) (xy 322.235205 -327.614441)
			(xy 322.216683 -327.622107) (xy 322.202508 -327.636281) (xy 322.194842 -327.654803) (xy 322.194428 -327.664826)
			(xy 322.194428 -327.677526) (xy 318.610488 -331.261466) (xy 318.60309 -331.268314) (xy 318.584492 -331.27605)
			(xy 318.57442 -331.276452) (xy 316.71641 -331.276452) (xy 316.70634 -331.276875) (xy 316.687738 -331.284592)
			(xy 316.680342 -331.291438) (xy 314.370212 -333.601568) (xy 312.655712 -335.316322) (xy 312.649108 -335.32826)
			(xy 312.64733 -335.335118) (xy 312.645492 -335.341886) (xy 312.638659 -335.354126) (xy 312.633868 -335.359248)
			(xy 311.34304 -336.650076) (xy 314.281312 -336.650076) (xy 314.28181 -336.622166) (xy 314.289946 -336.566941)
			(xy 314.306042 -336.513491) (xy 314.329753 -336.462956) (xy 314.360573 -336.416415) (xy 314.378848 -336.395314)
			(xy 314.385198 -336.388202) (xy 314.391802 -336.37093) (xy 314.391802 -336.283808) (xy 314.385198 -336.266536)
			(xy 314.378848 -336.259424) (xy 314.360552 -336.23834) (xy 314.329729 -336.191796) (xy 314.306018 -336.141258)
			(xy 314.289925 -336.087803) (xy 314.281795 -336.032574) (xy 314.281312 -336.004662) (xy 314.281798 -335.977411)
			(xy 314.289554 -335.923463) (xy 314.304909 -335.871168) (xy 314.327551 -335.821591) (xy 314.357017 -335.775741)
			(xy 314.392708 -335.73455) (xy 314.433899 -335.698859) (xy 314.479749 -335.669393) (xy 314.529326 -335.646751)
			(xy 314.581621 -335.631396) (xy 314.635569 -335.62364) (xy 314.690071 -335.62364) (xy 314.744019 -335.631396)
			(xy 314.796314 -335.646751) (xy 314.845891 -335.669393) (xy 314.891741 -335.698859) (xy 314.932932 -335.73455)
			(xy 314.968623 -335.775741) (xy 314.998089 -335.821591) (xy 315.020731 -335.871168) (xy 315.036086 -335.923463)
			(xy 315.043842 -335.977411) (xy 315.044328 -336.004662) (xy 315.043868 -336.032574) (xy 315.035725 -336.087801)
			(xy 315.019621 -336.141252) (xy 314.995902 -336.191786) (xy 314.965071 -336.238325) (xy 314.946792 -336.259424)
			(xy 314.940442 -336.266536) (xy 314.933838 -336.283808) (xy 314.933838 -336.37093) (xy 314.940442 -336.388202)
			(xy 314.946792 -336.395314) (xy 314.965049 -336.416431) (xy 314.99588 -336.462964) (xy 315.0196 -336.513494)
			(xy 315.035701 -336.566942) (xy 315.04384 -336.622166) (xy 315.044328 -336.650076) (xy 315.043842 -336.677327)
			(xy 315.036086 -336.731275) (xy 315.020731 -336.78357) (xy 314.998089 -336.833147) (xy 314.968623 -336.878997)
			(xy 314.932932 -336.920188) (xy 314.891741 -336.955879) (xy 314.848606 -336.9836) (xy 318.663538 -336.9836)
			(xy 318.667705 -336.927983) (xy 318.680116 -336.873608) (xy 318.700492 -336.821691) (xy 318.728379 -336.77339)
			(xy 318.763153 -336.729785) (xy 318.804037 -336.69185) (xy 318.850119 -336.660432) (xy 318.900368 -336.636233)
			(xy 318.953664 -336.619793) (xy 319.008814 -336.611481) (xy 319.0367 -336.61096) (xy 319.063121 -336.611427)
			(xy 319.115436 -336.618876) (xy 319.166174 -336.63364) (xy 319.214319 -336.655421) (xy 319.258904 -336.683784)
			(xy 319.27927 -336.700622) (xy 319.286128 -336.706718) (xy 319.303146 -336.712814) (xy 319.387474 -336.712814)
			(xy 319.404492 -336.706718) (xy 319.41135 -336.700622) (xy 319.431716 -336.683783) (xy 319.476302 -336.655418)
			(xy 319.524446 -336.633631) (xy 319.575183 -336.61886) (xy 319.627498 -336.6114) (xy 319.680342 -336.6114)
			(xy 319.732657 -336.61886) (xy 319.783394 -336.633631) (xy 319.831538 -336.655418) (xy 319.876124 -336.683783)
			(xy 319.89649 -336.700622) (xy 319.903348 -336.706718) (xy 319.920366 -336.712814) (xy 320.004694 -336.712814)
			(xy 320.021712 -336.706718) (xy 320.02857 -336.700622) (xy 320.052017 -336.681287) (xy 320.103963 -336.649751)
			(xy 320.160337 -336.627059) (xy 320.18986 -336.61985) (xy 320.20256 -336.617056) (xy 320.221864 -336.600546)
			(xy 320.261234 -336.497422) (xy 320.257932 -336.472022) (xy 320.250566 -336.461608) (xy 320.233767 -336.437185)
			(xy 320.207124 -336.384235) (xy 320.188982 -336.327805) (xy 320.179776 -336.269249) (xy 320.179192 -336.239612)
			(xy 320.179669 -336.212038) (xy 320.187619 -336.157466) (xy 320.203342 -336.104606) (xy 320.22651 -336.05456)
			(xy 320.256641 -336.00837) (xy 320.293106 -335.966998) (xy 320.313812 -335.948782) (xy 320.321936 -335.941184)
			(xy 320.331287 -335.921029) (xy 320.331846 -335.90992) (xy 320.331846 -335.832704) (xy 320.331309 -335.82159)
			(xy 320.321951 -335.80143) (xy 320.313812 -335.793842) (xy 320.29312 -335.77561) (xy 320.256648 -335.734246)
			(xy 320.226513 -335.68806) (xy 320.203344 -335.638016) (xy 320.187623 -335.585157) (xy 320.17968 -335.530586)
			(xy 320.179192 -335.503012) (xy 320.179678 -335.475761) (xy 320.187434 -335.421813) (xy 320.202789 -335.369518)
			(xy 320.225431 -335.319941) (xy 320.254897 -335.274091) (xy 320.290588 -335.2329) (xy 320.331779 -335.197209)
			(xy 320.377629 -335.167743) (xy 320.427206 -335.145101) (xy 320.479501 -335.129746) (xy 320.533449 -335.12199)
			(xy 320.587951 -335.12199) (xy 320.641899 -335.129746) (xy 320.694194 -335.145101) (xy 320.743771 -335.167743)
			(xy 320.789621 -335.197209) (xy 320.830812 -335.2329) (xy 320.866503 -335.274091) (xy 320.895969 -335.319941)
			(xy 320.918611 -335.369518) (xy 320.933966 -335.421813) (xy 320.941722 -335.475761) (xy 320.942208 -335.503012)
			(xy 320.941679 -335.530584) (xy 320.933739 -335.585154) (xy 320.918026 -335.638013) (xy 320.894868 -335.688059)
			(xy 320.864747 -335.73425) (xy 320.82829 -335.775624) (xy 320.807588 -335.793842) (xy 320.799453 -335.80143)
			(xy 320.790109 -335.821592) (xy 320.789554 -335.832704) (xy 320.789554 -335.90992) (xy 320.790078 -335.921036)
			(xy 320.799446 -335.941195) (xy 320.807588 -335.948782) (xy 320.828291 -335.967002) (xy 320.864763 -336.008368)
			(xy 320.894896 -336.054556) (xy 320.918063 -336.104603) (xy 320.933781 -336.157464) (xy 320.941722 -336.212038)
			(xy 320.942208 -336.239612) (xy 320.941626 -336.268528) (xy 320.932909 -336.3257) (xy 320.915662 -336.380901)
			(xy 320.89028 -336.432865) (xy 320.857344 -336.480403) (xy 320.81761 -336.522424) (xy 320.771988 -336.557966)
			(xy 320.721524 -336.586213) (xy 320.667373 -336.606519) (xy 320.639186 -336.612992) (xy 320.62674 -336.615532)
			(xy 320.607182 -336.632042) (xy 320.602856 -336.642964) (xy 322.636896 -336.642964) (xy 322.637366 -336.615052)
			(xy 322.645505 -336.559825) (xy 322.661606 -336.506374) (xy 322.685324 -336.45584) (xy 322.716153 -336.409301)
			(xy 322.734432 -336.388202) (xy 322.740782 -336.38109) (xy 322.747386 -336.363818) (xy 322.747386 -336.276696)
			(xy 322.740782 -336.259424) (xy 322.734432 -336.252312) (xy 322.716127 -336.231235) (xy 322.685306 -336.184689)
			(xy 322.661597 -336.134149) (xy 322.645507 -336.080693) (xy 322.637378 -336.025463) (xy 322.636896 -335.99755)
			(xy 322.637382 -335.970299) (xy 322.645138 -335.916351) (xy 322.660493 -335.864056) (xy 322.683135 -335.814479)
			(xy 322.712601 -335.768629) (xy 322.748292 -335.727438) (xy 322.789483 -335.691747) (xy 322.835333 -335.662281)
			(xy 322.88491 -335.639639) (xy 322.937205 -335.624284) (xy 322.991153 -335.616528) (xy 323.045655 -335.616528)
			(xy 323.099603 -335.624284) (xy 323.151898 -335.639639) (xy 323.201475 -335.662281) (xy 323.247325 -335.691747)
			(xy 323.288516 -335.727438) (xy 323.324207 -335.768629) (xy 323.353673 -335.814479) (xy 323.376315 -335.864056)
			(xy 323.39167 -335.916351) (xy 323.399426 -335.970299) (xy 323.399912 -335.99755) (xy 323.399449 -336.025462)
			(xy 323.391307 -336.080689) (xy 323.375205 -336.13414) (xy 323.351485 -336.184674) (xy 323.320655 -336.231213)
			(xy 323.302376 -336.252312) (xy 323.296026 -336.259424) (xy 323.289422 -336.276696) (xy 323.289422 -336.363818)
			(xy 323.296026 -336.38109) (xy 323.302376 -336.388202) (xy 323.320625 -336.409326) (xy 323.351457 -336.455857)
			(xy 323.375179 -336.506385) (xy 323.391282 -336.559832) (xy 323.399423 -336.615054) (xy 323.399912 -336.642964)
			(xy 323.399426 -336.670215) (xy 323.39167 -336.724163) (xy 323.376315 -336.776458) (xy 323.353673 -336.826035)
			(xy 323.324207 -336.871885) (xy 323.288516 -336.913076) (xy 323.247325 -336.948767) (xy 323.204172 -336.9765)
			(xy 327.019125 -336.9765) (xy 327.023293 -336.920883) (xy 327.035704 -336.866508) (xy 327.056079 -336.81459)
			(xy 327.083965 -336.766288) (xy 327.118739 -336.722682) (xy 327.159622 -336.684746) (xy 327.205703 -336.653327)
			(xy 327.255953 -336.629126) (xy 327.309247 -336.612685) (xy 327.364397 -336.60437) (xy 327.392284 -336.603848)
			(xy 327.418705 -336.604327) (xy 327.471019 -336.611774) (xy 327.521757 -336.626535) (xy 327.569901 -336.648313)
			(xy 327.614488 -336.676673) (xy 327.634854 -336.69351) (xy 327.641712 -336.699606) (xy 327.65873 -336.705702)
			(xy 327.743058 -336.705702) (xy 327.760076 -336.699606) (xy 327.766934 -336.69351) (xy 327.7873 -336.676671)
			(xy 327.831886 -336.648306) (xy 327.88003 -336.626519) (xy 327.930767 -336.611748) (xy 327.983082 -336.604288)
			(xy 328.035926 -336.604288) (xy 328.088241 -336.611748) (xy 328.138978 -336.626519) (xy 328.187122 -336.648306)
			(xy 328.231708 -336.676671) (xy 328.252074 -336.69351) (xy 328.258932 -336.699606) (xy 328.27595 -336.705702)
			(xy 328.360278 -336.705702) (xy 328.377296 -336.699606) (xy 328.384154 -336.69351) (xy 328.406536 -336.675093)
			(xy 328.455867 -336.644668) (xy 328.509312 -336.622245) (xy 328.537316 -336.61477) (xy 328.549508 -336.611722)
			(xy 328.567796 -336.59572) (xy 328.607674 -336.495644) (xy 328.605134 -336.47126) (xy 328.59853 -336.460846)
			(xy 328.584049 -336.437615) (xy 328.561184 -336.387877) (xy 328.545663 -336.335382) (xy 328.537805 -336.281207)
			(xy 328.537316 -336.253836) (xy 328.537801 -336.226262) (xy 328.545749 -336.17169) (xy 328.56147 -336.11883)
			(xy 328.584636 -336.068784) (xy 328.614765 -336.022594) (xy 328.65123 -335.981222) (xy 328.671936 -335.963006)
			(xy 328.680053 -335.955402) (xy 328.689407 -335.935252) (xy 328.68997 -335.924144) (xy 328.68997 -335.846928)
			(xy 328.689412 -335.835817) (xy 328.680067 -335.815657) (xy 328.671936 -335.808066) (xy 328.651212 -335.789868)
			(xy 328.614742 -335.748498) (xy 328.58461 -335.702305) (xy 328.561446 -335.652254) (xy 328.545733 -335.599389)
			(xy 328.537798 -335.544812) (xy 328.537316 -335.517236) (xy 328.537802 -335.489985) (xy 328.545558 -335.436037)
			(xy 328.560913 -335.383742) (xy 328.583555 -335.334165) (xy 328.613021 -335.288315) (xy 328.648712 -335.247124)
			(xy 328.689903 -335.211433) (xy 328.735753 -335.181967) (xy 328.78533 -335.159325) (xy 328.837625 -335.14397)
			(xy 328.891573 -335.136214) (xy 328.946075 -335.136214) (xy 329.000023 -335.14397) (xy 329.052318 -335.159325)
			(xy 329.101895 -335.181967) (xy 329.147745 -335.211433) (xy 329.188936 -335.247124) (xy 329.224627 -335.288315)
			(xy 329.254093 -335.334165) (xy 329.276735 -335.383742) (xy 329.29209 -335.436037) (xy 329.299846 -335.489985)
			(xy 329.300332 -335.517236) (xy 329.299811 -335.544808) (xy 329.291868 -335.599378) (xy 329.276153 -335.652237)
			(xy 329.252994 -335.702283) (xy 329.222871 -335.748474) (xy 329.186414 -335.789848) (xy 329.165712 -335.808066)
			(xy 329.157615 -335.815688) (xy 329.148248 -335.835825) (xy 329.147678 -335.846928) (xy 329.147678 -335.924144)
			(xy 329.148236 -335.935256) (xy 329.157579 -335.955416) (xy 329.165712 -335.963006) (xy 329.186432 -335.981208)
			(xy 329.222901 -336.022579) (xy 329.253032 -336.068771) (xy 329.276196 -336.118821) (xy 329.29191 -336.171685)
			(xy 329.299848 -336.226261) (xy 329.300332 -336.253836) (xy 329.299861 -336.282294) (xy 329.291415 -336.338579)
			(xy 329.274699 -336.392985) (xy 329.250086 -336.444304) (xy 329.218122 -336.491396) (xy 329.179515 -336.533216)
			(xy 329.135124 -336.568837) (xy 329.085933 -336.597466) (xy 329.033035 -336.61847) (xy 329.005438 -336.625438)
			(xy 328.993246 -336.628232) (xy 328.992947 -336.628486) (xy 330.994512 -336.628486) (xy 330.995016 -336.600576)
			(xy 331.003151 -336.545351) (xy 331.019245 -336.491901) (xy 331.042954 -336.441367) (xy 331.073774 -336.394825)
			(xy 331.092048 -336.373724) (xy 331.098398 -336.366612) (xy 331.105002 -336.34934) (xy 331.105002 -336.262218)
			(xy 331.098398 -336.244946) (xy 331.092048 -336.237834) (xy 331.073756 -336.216746) (xy 331.042933 -336.170204)
			(xy 331.019221 -336.119666) (xy 331.003127 -336.066212) (xy 330.994996 -336.010984) (xy 330.994512 -335.983072)
			(xy 330.994998 -335.955821) (xy 331.002754 -335.901873) (xy 331.018109 -335.849578) (xy 331.040751 -335.800001)
			(xy 331.070217 -335.754151) (xy 331.105908 -335.71296) (xy 331.147099 -335.677269) (xy 331.192949 -335.647803)
			(xy 331.242526 -335.625161) (xy 331.294821 -335.609806) (xy 331.348769 -335.60205) (xy 331.403271 -335.60205)
			(xy 331.457219 -335.609806) (xy 331.509514 -335.625161) (xy 331.559091 -335.647803) (xy 331.604941 -335.677269)
			(xy 331.646132 -335.71296) (xy 331.681823 -335.754151) (xy 331.711289 -335.800001) (xy 331.733931 -335.849578)
			(xy 331.749286 -335.901873) (xy 331.757042 -335.955821) (xy 331.757528 -335.983072) (xy 331.757074 -336.010984)
			(xy 331.748929 -336.066211) (xy 331.732825 -336.119663) (xy 331.709103 -336.170197) (xy 331.678272 -336.216735)
			(xy 331.659992 -336.237834) (xy 331.653642 -336.244946) (xy 331.647038 -336.262218) (xy 331.647038 -336.34934)
			(xy 331.653642 -336.366612) (xy 331.659992 -336.373724) (xy 331.678254 -336.394837) (xy 331.709084 -336.441371)
			(xy 331.732803 -336.491903) (xy 331.748903 -336.545351) (xy 331.757041 -336.600576) (xy 331.757528 -336.628486)
			(xy 331.757042 -336.655737) (xy 331.749286 -336.709685) (xy 331.733931 -336.76198) (xy 331.711289 -336.811557)
			(xy 331.681823 -336.857407) (xy 331.646132 -336.898598) (xy 331.604941 -336.934289) (xy 331.561822 -336.962)
			(xy 335.376748 -336.962) (xy 335.380915 -336.906385) (xy 335.393326 -336.852011) (xy 335.413701 -336.800095)
			(xy 335.441587 -336.751796) (xy 335.47636 -336.708192) (xy 335.517243 -336.670258) (xy 335.563324 -336.63884)
			(xy 335.613572 -336.614642) (xy 335.666866 -336.598203) (xy 335.722014 -336.589891) (xy 335.7499 -336.58937)
			(xy 335.776321 -336.589835) (xy 335.828636 -336.597284) (xy 335.879375 -336.612048) (xy 335.927519 -336.63383)
			(xy 335.972104 -336.662193) (xy 335.99247 -336.679032) (xy 335.999328 -336.685128) (xy 336.016346 -336.691224)
			(xy 336.100674 -336.691224) (xy 336.117692 -336.685128) (xy 336.12455 -336.679032) (xy 336.144916 -336.662193)
			(xy 336.189502 -336.633828) (xy 336.237646 -336.612041) (xy 336.288383 -336.59727) (xy 336.340698 -336.58981)
			(xy 336.393542 -336.58981) (xy 336.445857 -336.59727) (xy 336.496594 -336.612041) (xy 336.544738 -336.633828)
			(xy 336.589324 -336.662193) (xy 336.60969 -336.679032) (xy 336.616548 -336.685128) (xy 336.633566 -336.691224)
			(xy 336.717894 -336.691224) (xy 336.734912 -336.685128) (xy 336.74177 -336.679032) (xy 336.763705 -336.660961)
			(xy 336.811982 -336.630975) (xy 336.864242 -336.608646) (xy 336.89163 -336.601054) (xy 336.903314 -336.598006)
			(xy 336.921602 -336.582258) (xy 336.96148 -336.484722) (xy 336.959702 -336.460592) (xy 336.953606 -336.450432)
			(xy 336.940633 -336.428091) (xy 336.920214 -336.380636) (xy 336.906392 -336.330857) (xy 336.899422 -336.279667)
			(xy 336.898996 -336.253836) (xy 336.899488 -336.226262) (xy 336.907435 -336.171691) (xy 336.923155 -336.118831)
			(xy 336.94632 -336.068785) (xy 336.976448 -336.022595) (xy 337.012911 -335.981223) (xy 337.033616 -335.963006)
			(xy 337.04173 -335.955399) (xy 337.051086 -335.935251) (xy 337.05165 -335.924144) (xy 337.05165 -335.846928)
			(xy 337.051098 -335.835816) (xy 337.04175 -335.815656) (xy 337.033616 -335.808066) (xy 337.012888 -335.789873)
			(xy 336.976419 -335.748501) (xy 336.946288 -335.702307) (xy 336.923125 -335.652255) (xy 336.907413 -335.59939)
			(xy 336.899478 -335.544812) (xy 336.898996 -335.517236) (xy 336.899482 -335.489985) (xy 336.907238 -335.436037)
			(xy 336.922593 -335.383742) (xy 336.945235 -335.334165) (xy 336.974701 -335.288315) (xy 337.010392 -335.247124)
			(xy 337.051583 -335.211433) (xy 337.097433 -335.181967) (xy 337.14701 -335.159325) (xy 337.199305 -335.14397)
			(xy 337.253253 -335.136214) (xy 337.307755 -335.136214) (xy 337.361703 -335.14397) (xy 337.413998 -335.159325)
			(xy 337.463575 -335.181967) (xy 337.509425 -335.211433) (xy 337.550616 -335.247124) (xy 337.586307 -335.288315)
			(xy 337.615773 -335.334165) (xy 337.638415 -335.383742) (xy 337.65377 -335.436037) (xy 337.661526 -335.489985)
			(xy 337.662012 -335.517236) (xy 337.661498 -335.544809) (xy 337.653555 -335.599379) (xy 337.637839 -335.652238)
			(xy 337.614678 -335.702284) (xy 337.584554 -335.748475) (xy 337.548095 -335.789849) (xy 337.527392 -335.808066)
			(xy 337.519292 -335.815685) (xy 337.509928 -335.835824) (xy 337.509358 -335.846928) (xy 337.509358 -335.924144)
			(xy 337.509923 -335.935255) (xy 337.519261 -335.955415) (xy 337.527392 -335.963006) (xy 337.548108 -335.981212)
			(xy 337.584578 -336.022582) (xy 337.61471 -336.068773) (xy 337.637875 -336.118822) (xy 337.65359 -336.171685)
			(xy 337.661528 -336.226261) (xy 337.662012 -336.253836) (xy 337.661456 -336.282114) (xy 337.653115 -336.338051)
			(xy 337.636607 -336.392144) (xy 337.612293 -336.443206) (xy 337.580706 -336.490119) (xy 337.542539 -336.531855)
			(xy 337.498629 -336.567497) (xy 337.449937 -336.596266) (xy 337.397531 -336.61753) (xy 337.370166 -336.624676)
			(xy 337.358482 -336.62747) (xy 337.340194 -336.642964) (xy 337.298792 -336.739992) (xy 337.300316 -336.764122)
			(xy 337.306412 -336.774536) (xy 337.318417 -336.795967) (xy 337.337324 -336.841304) (xy 337.350114 -336.888731)
			(xy 337.356566 -336.937427) (xy 337.356958 -336.961988) (xy 337.356432 -336.988602) (xy 337.348859 -337.041289)
			(xy 337.333866 -337.092362) (xy 337.311756 -337.140781) (xy 337.282982 -337.185561) (xy 337.248127 -337.22579)
			(xy 337.207903 -337.26065) (xy 337.163126 -337.289431) (xy 337.11471 -337.311547) (xy 337.06364 -337.326548)
			(xy 337.010954 -337.334129) (xy 336.98434 -337.334606) (xy 336.957917 -337.334182) (xy 336.9056 -337.326723)
			(xy 336.854861 -337.311951) (xy 336.806718 -337.290159) (xy 336.762134 -337.261787) (xy 336.74177 -337.244944)
			(xy 336.734912 -337.238848) (xy 336.717894 -337.232752) (xy 336.633566 -337.232752) (xy 336.616548 -337.238848)
			(xy 336.60969 -337.244944) (xy 336.589324 -337.261783) (xy 336.544738 -337.290148) (xy 336.496594 -337.311935)
			(xy 336.445857 -337.326706) (xy 336.393542 -337.334166) (xy 336.340698 -337.334166) (xy 336.288383 -337.326706)
			(xy 336.237646 -337.311935) (xy 336.189502 -337.290148) (xy 336.144916 -337.261783) (xy 336.12455 -337.244944)
			(xy 336.117692 -337.238848) (xy 336.100674 -337.232752) (xy 336.016346 -337.232752) (xy 335.999328 -337.238848)
			(xy 335.99247 -337.244944) (xy 335.972109 -337.261787) (xy 335.927518 -337.290144) (xy 335.879373 -337.311923)
			(xy 335.828635 -337.326689) (xy 335.776321 -337.334147) (xy 335.7499 -337.334606) (xy 335.722014 -337.334109)
			(xy 335.666866 -337.325797) (xy 335.613572 -337.309358) (xy 335.563324 -337.28516) (xy 335.517243 -337.253742)
			(xy 335.47636 -337.215808) (xy 335.441587 -337.172204) (xy 335.413701 -337.123905) (xy 335.393326 -337.071989)
			(xy 335.380915 -337.017615) (xy 335.376748 -336.962) (xy 331.561822 -336.962) (xy 331.559091 -336.963755)
			(xy 331.509514 -336.986397) (xy 331.457219 -337.001752) (xy 331.403271 -337.009508) (xy 331.348769 -337.009508)
			(xy 331.294821 -337.001752) (xy 331.242526 -336.986397) (xy 331.192949 -336.963755) (xy 331.147099 -336.934289)
			(xy 331.105908 -336.898598) (xy 331.070217 -336.857407) (xy 331.040751 -336.811557) (xy 331.018109 -336.76198)
			(xy 331.002754 -336.709685) (xy 330.994998 -336.655737) (xy 330.994512 -336.628486) (xy 328.992947 -336.628486)
			(xy 328.974704 -336.64398) (xy 328.933556 -336.743548) (xy 328.935588 -336.767932) (xy 328.942192 -336.778346)
			(xy 328.955716 -336.800704) (xy 328.977062 -336.848398) (xy 328.991544 -336.898604) (xy 328.998881 -336.95034)
			(xy 328.999342 -336.976466) (xy 328.998834 -337.003082) (xy 328.991263 -337.055772) (xy 328.976271 -337.106849)
			(xy 328.954161 -337.155272) (xy 328.925386 -337.200056) (xy 328.89053 -337.240289) (xy 328.850303 -337.275151)
			(xy 328.805523 -337.303934) (xy 328.757104 -337.32605) (xy 328.706029 -337.341051) (xy 328.65334 -337.34863)
			(xy 328.626724 -337.349084) (xy 328.600304 -337.348593) (xy 328.54799 -337.341148) (xy 328.497253 -337.326389)
			(xy 328.449108 -337.304614) (xy 328.404521 -337.276257) (xy 328.384154 -337.259422) (xy 328.377296 -337.253326)
			(xy 328.360278 -337.24723) (xy 328.27595 -337.24723) (xy 328.258932 -337.253326) (xy 328.252074 -337.259422)
			(xy 328.231708 -337.276261) (xy 328.187122 -337.304626) (xy 328.138978 -337.326413) (xy 328.088241 -337.341184)
			(xy 328.035926 -337.348644) (xy 327.983082 -337.348644) (xy 327.930767 -337.341184) (xy 327.88003 -337.326413)
			(xy 327.831886 -337.304626) (xy 327.7873 -337.276261) (xy 327.766934 -337.259422) (xy 327.760076 -337.253326)
			(xy 327.743058 -337.24723) (xy 327.65873 -337.24723) (xy 327.641712 -337.253326) (xy 327.634854 -337.259422)
			(xy 327.614496 -337.27627) (xy 327.569905 -337.304626) (xy 327.521759 -337.326404) (xy 327.47102 -337.34117)
			(xy 327.418706 -337.348626) (xy 327.392284 -337.349084) (xy 327.364397 -337.34863) (xy 327.309247 -337.340315)
			(xy 327.255953 -337.323874) (xy 327.205703 -337.299673) (xy 327.159622 -337.268254) (xy 327.118739 -337.230318)
			(xy 327.083965 -337.186712) (xy 327.056079 -337.13841) (xy 327.035704 -337.086492) (xy 327.023293 -337.032117)
			(xy 327.019125 -336.9765) (xy 323.204172 -336.9765) (xy 323.201475 -336.978233) (xy 323.151898 -337.000875)
			(xy 323.099603 -337.01623) (xy 323.045655 -337.023986) (xy 322.991153 -337.023986) (xy 322.937205 -337.01623)
			(xy 322.88491 -337.000875) (xy 322.835333 -336.978233) (xy 322.789483 -336.948767) (xy 322.748292 -336.913076)
			(xy 322.712601 -336.871885) (xy 322.683135 -336.826035) (xy 322.660493 -336.776458) (xy 322.645138 -336.724163)
			(xy 322.637382 -336.670215) (xy 322.636896 -336.642964) (xy 320.602856 -336.642964) (xy 320.566542 -336.734658)
			(xy 320.56959 -336.760058) (xy 320.576702 -336.770472) (xy 320.592505 -336.794045) (xy 320.617534 -336.844979)
			(xy 320.634565 -336.899114) (xy 320.643204 -336.955203) (xy 320.643758 -336.983578) (xy 320.643223 -337.010192)
			(xy 320.635651 -337.062878) (xy 320.620659 -337.113951) (xy 320.598551 -337.16237) (xy 320.569777 -337.20715)
			(xy 320.534924 -337.24738) (xy 320.4947 -337.28224) (xy 320.449924 -337.311021) (xy 320.401509 -337.333137)
			(xy 320.350439 -337.348138) (xy 320.297754 -337.355719) (xy 320.27114 -337.356196) (xy 320.244717 -337.355774)
			(xy 320.1924 -337.348316) (xy 320.141661 -337.333542) (xy 320.093517 -337.311751) (xy 320.048934 -337.283377)
			(xy 320.02857 -337.266534) (xy 320.021712 -337.260438) (xy 320.004694 -337.254342) (xy 319.920366 -337.254342)
			(xy 319.903348 -337.260438) (xy 319.89649 -337.266534) (xy 319.876124 -337.283373) (xy 319.831538 -337.311738)
			(xy 319.783394 -337.333525) (xy 319.732657 -337.348296) (xy 319.680342 -337.355756) (xy 319.627498 -337.355756)
			(xy 319.575183 -337.348296) (xy 319.524446 -337.333525) (xy 319.476302 -337.311738) (xy 319.431716 -337.283373)
			(xy 319.41135 -337.266534) (xy 319.404492 -337.260438) (xy 319.387474 -337.254342) (xy 319.303146 -337.254342)
			(xy 319.286128 -337.260438) (xy 319.27927 -337.266534) (xy 319.258907 -337.283376) (xy 319.214318 -337.311733)
			(xy 319.166172 -337.333512) (xy 319.115435 -337.348279) (xy 319.063121 -337.355737) (xy 319.0367 -337.356196)
			(xy 319.008814 -337.355719) (xy 318.953664 -337.347407) (xy 318.900368 -337.330967) (xy 318.850119 -337.306768)
			(xy 318.804037 -337.27535) (xy 318.763153 -337.237415) (xy 318.728379 -337.19381) (xy 318.700492 -337.145509)
			(xy 318.680116 -337.093592) (xy 318.667705 -337.039217) (xy 318.663538 -336.9836) (xy 314.848606 -336.9836)
			(xy 314.845891 -336.985345) (xy 314.796314 -337.007987) (xy 314.744019 -337.023342) (xy 314.690071 -337.031098)
			(xy 314.635569 -337.031098) (xy 314.581621 -337.023342) (xy 314.529326 -337.007987) (xy 314.479749 -336.985345)
			(xy 314.433899 -336.955879) (xy 314.392708 -336.920188) (xy 314.357017 -336.878997) (xy 314.327551 -336.833147)
			(xy 314.304909 -336.78357) (xy 314.289554 -336.731275) (xy 314.281798 -336.677327) (xy 314.281312 -336.650076)
			(xy 311.34304 -336.650076) (xy 310.879998 -337.113118) (xy 310.872603 -337.119973) (xy 310.854004 -337.12772)
			(xy 310.84393 -337.128104) (xy 304.200306 -337.128104) (xy 304.18786 -337.129628) (xy 304.180494 -337.131406)
			(xy 304.15484 -337.145884) (xy 304.14595 -337.15198) (xy 304.14087 -337.156298) (xy 304.125621 -337.178196)
			(xy 304.089979 -337.217909) (xy 304.049148 -337.252263) (xy 304.003925 -337.280588) (xy 303.955194 -337.30233)
			(xy 303.903907 -337.317065) (xy 303.851067 -337.324504) (xy 303.824386 -337.324954) (xy 303.797627 -337.324503)
			(xy 303.744633 -337.317028) (xy 303.693202 -337.302227) (xy 303.644341 -337.280389) (xy 303.599009 -337.251943)
			(xy 303.57826 -337.235038) (xy 303.577752 -337.23453) (xy 303.577498 -337.234276) (xy 303.57031 -337.228952)
			(xy 303.553419 -337.223108) (xy 303.544478 -337.222846) (xy 303.468532 -337.224116) (xy 303.451768 -337.23072)
			(xy 303.44491 -337.23707) (xy 303.423766 -337.255439) (xy 303.377108 -337.286425) (xy 303.326424 -337.31026)
			(xy 303.272801 -337.326435) (xy 303.217391 -337.334602) (xy 303.189386 -337.335114) (xy 303.162728 -337.334655)
			(xy 303.10993 -337.32725) (xy 303.058675 -337.31257) (xy 303.009961 -337.290903) (xy 302.964736 -337.262668)
			(xy 302.923878 -337.228417) (xy 302.888183 -337.188813) (xy 302.872902 -337.166966) (xy 302.870362 -337.162902)
			(xy 302.869854 -337.162394) (xy 302.866298 -337.157314) (xy 302.86198 -337.15325) (xy 302.852328 -337.146138)
			(xy 302.832262 -337.134708) (xy 302.826446 -337.13161) (xy 302.813704 -337.128264) (xy 302.807116 -337.128104)
			(xy 264.968482 -337.128104) (xy 264.958413 -337.128531) (xy 264.939814 -337.13625) (xy 264.932414 -337.14309)
			(xy 264.193782 -337.881722) (xy 315.239144 -337.881722) (xy 315.243215 -337.8261) (xy 315.255341 -337.771663)
			(xy 315.275264 -337.719572) (xy 315.30256 -337.670937) (xy 315.336646 -337.626794) (xy 315.376795 -337.588085)
			(xy 315.422153 -337.555634) (xy 315.471753 -337.530133) (xy 315.524537 -337.512126) (xy 315.57938 -337.501996)
			(xy 315.635114 -337.499959) (xy 315.690551 -337.506059) (xy 315.744508 -337.520165) (xy 315.795837 -337.541977)
			(xy 315.843443 -337.571031) (xy 315.886311 -337.606706) (xy 315.923528 -337.648243) (xy 315.954301 -337.694756)
			(xy 315.977973 -337.745253) (xy 315.994041 -337.79866) (xy 316.002161 -337.853836) (xy 316.00267 -337.881722)
			(xy 316.002161 -337.909608) (xy 315.994041 -337.964784) (xy 315.977973 -338.018191) (xy 315.954301 -338.068688)
			(xy 315.923528 -338.115201) (xy 315.886311 -338.156738) (xy 315.843443 -338.192413) (xy 315.795837 -338.221467)
			(xy 315.744508 -338.243279) (xy 315.690551 -338.257385) (xy 315.635114 -338.263485) (xy 315.57938 -338.261448)
			(xy 315.524537 -338.251318) (xy 315.471753 -338.233311) (xy 315.422153 -338.20781) (xy 315.376795 -338.175359)
			(xy 315.336646 -338.13665) (xy 315.30256 -338.092507) (xy 315.275264 -338.043872) (xy 315.255341 -337.991781)
			(xy 315.243215 -337.937344) (xy 315.239144 -337.881722) (xy 264.193782 -337.881722) (xy 263.298432 -338.777072)
			(xy 314.660024 -338.777072) (xy 314.664095 -338.72145) (xy 314.676221 -338.667013) (xy 314.696144 -338.614922)
			(xy 314.72344 -338.566287) (xy 314.757526 -338.522144) (xy 314.797675 -338.483435) (xy 314.843033 -338.450984)
			(xy 314.892633 -338.425483) (xy 314.945417 -338.407476) (xy 315.00026 -338.397346) (xy 315.055994 -338.395309)
			(xy 315.111431 -338.401409) (xy 315.165388 -338.415515) (xy 315.216717 -338.437327) (xy 315.264323 -338.466381)
			(xy 315.307191 -338.502056) (xy 315.344408 -338.543593) (xy 315.375181 -338.590106) (xy 315.398853 -338.640603)
			(xy 315.414921 -338.69401) (xy 315.423041 -338.749186) (xy 315.42355 -338.777072) (xy 315.423041 -338.804958)
			(xy 315.414921 -338.860134) (xy 315.398853 -338.913541) (xy 315.375181 -338.964038) (xy 315.344408 -339.010551)
			(xy 315.307191 -339.052088) (xy 315.264323 -339.087763) (xy 315.216717 -339.116817) (xy 315.165388 -339.138629)
			(xy 315.111431 -339.152735) (xy 315.055994 -339.158835) (xy 315.00026 -339.156798) (xy 314.945417 -339.146668)
			(xy 314.892633 -339.128661) (xy 314.843033 -339.10316) (xy 314.797675 -339.070709) (xy 314.757526 -339.032)
			(xy 314.72344 -338.987857) (xy 314.696144 -338.939222) (xy 314.676221 -338.887131) (xy 314.664095 -338.832694)
			(xy 314.660024 -338.777072) (xy 263.298432 -338.777072) (xy 262.767064 -339.30844) (xy 262.760217 -339.315838)
			(xy 262.752487 -339.334436) (xy 262.752078 -339.344508) (xy 262.752078 -339.452712) (xy 315.99886 -339.452712)
			(xy 315.999363 -339.425238) (xy 316.007253 -339.37086) (xy 316.022869 -339.318178) (xy 316.04589 -339.268285)
			(xy 316.075837 -339.222215) (xy 316.093602 -339.201252) (xy 316.099698 -339.19414) (xy 316.106048 -339.177122)
			(xy 316.106048 -339.09127) (xy 316.099698 -339.074252) (xy 316.093602 -339.06714) (xy 316.075876 -339.046147)
			(xy 316.045945 -339.000074) (xy 316.022925 -338.950187) (xy 316.007291 -338.897517) (xy 315.999364 -338.84315)
			(xy 315.99886 -338.81568) (xy 315.999346 -338.788429) (xy 316.007102 -338.734481) (xy 316.022457 -338.682186)
			(xy 316.045099 -338.632609) (xy 316.074565 -338.586759) (xy 316.110256 -338.545568) (xy 316.151447 -338.509877)
			(xy 316.197297 -338.480411) (xy 316.246874 -338.457769) (xy 316.299169 -338.442414) (xy 316.353117 -338.434658)
			(xy 316.407619 -338.434658) (xy 316.461567 -338.442414) (xy 316.513862 -338.457769) (xy 316.563439 -338.480411)
			(xy 316.609289 -338.509877) (xy 316.65048 -338.545568) (xy 316.686171 -338.586759) (xy 316.715637 -338.632609)
			(xy 316.738279 -338.682186) (xy 316.753634 -338.734481) (xy 316.76139 -338.788429) (xy 316.761876 -338.81568)
			(xy 316.761384 -338.843154) (xy 316.753494 -338.897534) (xy 316.737876 -338.950217) (xy 316.73523 -338.95595)
			(xy 317.003688 -338.95595) (xy 317.003688 -338.90145) (xy 317.011444 -338.847505) (xy 317.026798 -338.795213)
			(xy 317.049437 -338.745639) (xy 317.078901 -338.69979) (xy 317.11459 -338.658601) (xy 317.155777 -338.622911)
			(xy 317.201624 -338.593445) (xy 317.251198 -338.570804) (xy 317.30349 -338.555447) (xy 317.357434 -338.547689)
			(xy 317.384684 -338.547202) (xy 317.409921 -338.547562) (xy 317.459956 -338.554191) (xy 317.508676 -338.567375)
			(xy 317.555227 -338.586882) (xy 317.577216 -338.599272) (xy 317.586868 -338.605114) (xy 317.608966 -338.607146)
			(xy 317.703454 -338.573618) (xy 317.719456 -338.558124) (xy 317.72352 -338.54771) (xy 317.734188 -338.520921)
			(xy 317.762478 -338.470677) (xy 317.798011 -338.425266) (xy 317.839977 -338.385723) (xy 317.887418 -338.352951)
			(xy 317.939254 -338.327695) (xy 317.994301 -338.310533) (xy 318.051306 -338.301856) (xy 318.080136 -338.30133)
			(xy 318.107392 -338.301722) (xy 318.161347 -338.309484) (xy 318.213649 -338.324847) (xy 318.263231 -338.347496)
			(xy 318.309086 -338.376972) (xy 318.35028 -338.412673) (xy 318.385973 -338.453873) (xy 318.415439 -338.499734)
			(xy 318.438079 -338.549321) (xy 318.450802 -338.592668) (xy 320.591688 -338.592668) (xy 320.592205 -338.565095)
			(xy 320.600147 -338.510525) (xy 320.615863 -338.457666) (xy 320.639023 -338.40762) (xy 320.669146 -338.361429)
			(xy 320.705605 -338.320056) (xy 320.726308 -338.301838) (xy 320.734406 -338.294217) (xy 320.743771 -338.27408)
			(xy 320.744342 -338.262976) (xy 320.744342 -338.18576) (xy 320.743831 -338.174643) (xy 320.734454 -338.154484)
			(xy 320.726308 -338.146898) (xy 320.705594 -338.12869) (xy 320.669124 -338.08732) (xy 320.638992 -338.04113)
			(xy 320.615826 -337.991082) (xy 320.600111 -337.938218) (xy 320.592172 -337.883643) (xy 320.591688 -337.856068)
			(xy 320.592148 -337.828816) (xy 320.599909 -337.774868) (xy 320.615268 -337.722573) (xy 320.637912 -337.672996)
			(xy 320.667382 -337.627146) (xy 320.703076 -337.585956) (xy 320.744268 -337.550265) (xy 320.79012 -337.520799)
			(xy 320.839699 -337.498158) (xy 320.891995 -337.482803) (xy 320.945944 -337.475046) (xy 320.973196 -337.47456)
			(xy 321.007486 -337.476084) (xy 321.017646 -337.4771) (xy 321.03695 -337.471004) (xy 321.107562 -337.411822)
			(xy 321.11696 -337.393788) (xy 321.117976 -337.383628) (xy 321.120916 -337.355454) (xy 321.134093 -337.300362)
			(xy 321.155274 -337.247825) (xy 321.183994 -337.199) (xy 321.21962 -337.154959) (xy 321.261368 -337.116673)
			(xy 321.30832 -337.084984) (xy 321.359444 -337.060588) (xy 321.413613 -337.044023) (xy 321.469637 -337.035653)
			(xy 321.49796 -337.03514) (xy 321.515979 -337.035357) (xy 321.551854 -337.038794) (xy 321.569588 -337.041998)
			(xy 321.578986 -337.043776) (xy 321.598036 -337.039966) (xy 321.67322 -336.992214) (xy 321.68465 -336.976466)
			(xy 321.686936 -336.967068) (xy 321.694324 -336.940021) (xy 321.715954 -336.888293) (xy 321.744918 -336.840287)
			(xy 321.780595 -336.797034) (xy 321.822215 -336.759467) (xy 321.868884 -336.728393) (xy 321.919597 -336.704481)
			(xy 321.973263 -336.688246) (xy 322.028726 -336.680037) (xy 322.05676 -336.67954) (xy 322.084014 -336.679993)
			(xy 322.137968 -336.687745) (xy 322.190269 -336.703099) (xy 322.239852 -336.72574) (xy 322.285708 -336.755208)
			(xy 322.326902 -336.790904) (xy 322.362596 -336.832099) (xy 322.392064 -336.877955) (xy 322.414704 -336.927539)
			(xy 322.430056 -336.97984) (xy 322.437808 -337.033794) (xy 322.438268 -337.061048) (xy 322.437778 -337.088622)
			(xy 322.429832 -337.143194) (xy 322.414112 -337.196054) (xy 322.390947 -337.2461) (xy 322.360818 -337.29229)
			(xy 322.324354 -337.333662) (xy 322.303648 -337.351878) (xy 322.295536 -337.359486) (xy 322.28618 -337.379634)
			(xy 322.285614 -337.39074) (xy 322.285614 -337.467956) (xy 322.286186 -337.479066) (xy 322.295521 -337.499225)
			(xy 322.303648 -337.506818) (xy 322.324404 -337.52498) (xy 322.360872 -337.566356) (xy 322.391002 -337.612553)
			(xy 322.414166 -337.662607) (xy 322.42988 -337.715475) (xy 322.437818 -337.770054) (xy 322.437813 -337.825208)
			(xy 322.430621 -337.87461) (xy 323.594728 -337.87461) (xy 323.598799 -337.818988) (xy 323.610925 -337.764551)
			(xy 323.630848 -337.71246) (xy 323.658144 -337.663825) (xy 323.69223 -337.619682) (xy 323.732379 -337.580973)
			(xy 323.777737 -337.548522) (xy 323.827337 -337.523021) (xy 323.880121 -337.505014) (xy 323.934964 -337.494884)
			(xy 323.990698 -337.492847) (xy 324.046135 -337.498947) (xy 324.100092 -337.513053) (xy 324.151421 -337.534865)
			(xy 324.199027 -337.563919) (xy 324.241895 -337.599594) (xy 324.279112 -337.641131) (xy 324.309885 -337.687644)
			(xy 324.333557 -337.738141) (xy 324.349625 -337.791548) (xy 324.357745 -337.846724) (xy 324.358254 -337.87461)
			(xy 324.357745 -337.902496) (xy 324.349625 -337.957672) (xy 324.333557 -338.011079) (xy 324.309885 -338.061576)
			(xy 324.279112 -338.108089) (xy 324.241895 -338.149626) (xy 324.199027 -338.185301) (xy 324.151421 -338.214355)
			(xy 324.100092 -338.236167) (xy 324.046135 -338.250273) (xy 323.990698 -338.256373) (xy 323.934964 -338.254336)
			(xy 323.880121 -338.244206) (xy 323.827337 -338.226199) (xy 323.777737 -338.200698) (xy 323.732379 -338.168247)
			(xy 323.69223 -338.129538) (xy 323.658144 -338.085395) (xy 323.630848 -338.03676) (xy 323.610925 -337.984669)
			(xy 323.598799 -337.930232) (xy 323.594728 -337.87461) (xy 322.430621 -337.87461) (xy 322.429867 -337.879786)
			(xy 322.414144 -337.932651) (xy 322.390972 -337.982701) (xy 322.360834 -338.028893) (xy 322.324359 -338.070264)
			(xy 322.303648 -338.088478) (xy 322.295536 -338.096086) (xy 322.28618 -338.116234) (xy 322.285614 -338.12734)
			(xy 322.285614 -338.204556) (xy 322.286186 -338.215666) (xy 322.295521 -338.235825) (xy 322.303648 -338.243418)
			(xy 322.324381 -338.261605) (xy 322.360847 -338.30298) (xy 322.390975 -338.349176) (xy 322.414137 -338.399228)
			(xy 322.429849 -338.452094) (xy 322.437785 -338.506672) (xy 322.438268 -338.534248) (xy 322.437867 -338.561502)
			(xy 322.430103 -338.615455) (xy 322.414739 -338.667754) (xy 322.39209 -338.717334) (xy 322.362615 -338.763186)
			(xy 322.356744 -338.76996) (xy 323.015608 -338.76996) (xy 323.019679 -338.714338) (xy 323.031805 -338.659901)
			(xy 323.051728 -338.60781) (xy 323.079024 -338.559175) (xy 323.11311 -338.515032) (xy 323.153259 -338.476323)
			(xy 323.198617 -338.443872) (xy 323.248217 -338.418371) (xy 323.301001 -338.400364) (xy 323.355844 -338.390234)
			(xy 323.411578 -338.388197) (xy 323.467015 -338.394297) (xy 323.520972 -338.408403) (xy 323.572301 -338.430215)
			(xy 323.619907 -338.459269) (xy 323.662775 -338.494944) (xy 323.699992 -338.536481) (xy 323.730765 -338.582994)
			(xy 323.754437 -338.633491) (xy 323.770505 -338.686898) (xy 323.778625 -338.742074) (xy 323.779134 -338.76996)
			(xy 323.778625 -338.797846) (xy 323.770505 -338.853022) (xy 323.754437 -338.906429) (xy 323.730765 -338.956926)
			(xy 323.699992 -339.003439) (xy 323.662775 -339.044976) (xy 323.619907 -339.080651) (xy 323.572301 -339.109705)
			(xy 323.520972 -339.131517) (xy 323.467015 -339.145623) (xy 323.411578 -339.151723) (xy 323.355844 -339.149686)
			(xy 323.301001 -339.139556) (xy 323.248217 -339.121549) (xy 323.198617 -339.096048) (xy 323.153259 -339.063597)
			(xy 323.11311 -339.024888) (xy 323.079024 -338.980745) (xy 323.051728 -338.93211) (xy 323.031805 -338.880019)
			(xy 323.019679 -338.825582) (xy 323.015608 -338.76996) (xy 322.356744 -338.76996) (xy 322.326914 -338.804377)
			(xy 322.285715 -338.840068) (xy 322.239857 -338.869532) (xy 322.190271 -338.89217) (xy 322.137969 -338.907521)
			(xy 322.084014 -338.915273) (xy 322.05676 -338.915756) (xy 322.028902 -338.915302) (xy 321.973782 -338.907171)
			(xy 321.920428 -338.891118) (xy 321.869973 -338.867483) (xy 321.823488 -338.836768) (xy 321.781959 -338.799624)
			(xy 321.746268 -338.75684) (xy 321.717172 -338.709324) (xy 321.695289 -338.658085) (xy 321.687698 -338.631276)
			(xy 321.685412 -338.622386) (xy 321.674744 -338.607146) (xy 321.602862 -338.559394) (xy 321.584828 -338.55533)
			(xy 321.575684 -338.5566) (xy 321.562667 -338.558269) (xy 321.536483 -338.560049) (xy 321.52336 -338.560156)
			(xy 321.509211 -338.560066) (xy 321.480988 -338.558029) (xy 321.466972 -338.556092) (xy 321.456812 -338.554568)
			(xy 321.437254 -338.559394) (xy 321.362832 -338.615274) (xy 321.352672 -338.6328) (xy 321.351402 -338.64296)
			(xy 321.34734 -338.670118) (xy 321.332364 -338.72295) (xy 321.30997 -338.773089) (xy 321.280619 -338.8195)
			(xy 321.244919 -338.861224) (xy 321.203606 -338.8974) (xy 321.157534 -338.92728) (xy 321.107655 -338.950248)
			(xy 321.054999 -338.965828) (xy 321.000653 -338.973699) (xy 320.973196 -338.974176) (xy 320.945942 -338.973748)
			(xy 320.891988 -338.96599) (xy 320.839687 -338.950632) (xy 320.790105 -338.927986) (xy 320.74425 -338.898515)
			(xy 320.703057 -338.862818) (xy 320.667363 -338.821621) (xy 320.637896 -338.775763) (xy 320.615256 -338.726179)
			(xy 320.599902 -338.673877) (xy 320.592149 -338.619922) (xy 320.591688 -338.592668) (xy 318.450802 -338.592668)
			(xy 318.453431 -338.601625) (xy 318.461184 -338.655582) (xy 318.461644 -338.682838) (xy 318.460991 -338.714401)
			(xy 318.450602 -338.776667) (xy 318.430113 -338.836376) (xy 318.41567 -338.864448) (xy 318.410844 -338.873338)
			(xy 318.408812 -338.892896) (xy 318.434466 -338.981034) (xy 318.446912 -338.996528) (xy 318.455802 -339.001608)
			(xy 318.480891 -339.016175) (xy 318.526773 -339.051676) (xy 318.566749 -339.093717) (xy 318.599895 -339.141327)
			(xy 318.625448 -339.193409) (xy 318.642817 -339.24876) (xy 318.651603 -339.306104) (xy 318.652144 -339.33511)
			(xy 318.651658 -339.362361) (xy 318.643902 -339.416309) (xy 318.635301 -339.4456) (xy 324.354444 -339.4456)
			(xy 324.35492 -339.418125) (xy 324.362812 -339.363744) (xy 324.378434 -339.311061) (xy 324.401462 -339.261169)
			(xy 324.431417 -339.215101) (xy 324.449186 -339.19414) (xy 324.455282 -339.187028) (xy 324.461632 -339.17001)
			(xy 324.461632 -339.084158) (xy 324.455282 -339.06714) (xy 324.449186 -339.060028) (xy 324.431452 -339.039042)
			(xy 324.401523 -338.992966) (xy 324.378505 -338.943078) (xy 324.362872 -338.890407) (xy 324.354947 -338.836039)
			(xy 324.354444 -338.808568) (xy 324.35493 -338.781317) (xy 324.362686 -338.727369) (xy 324.378041 -338.675074)
			(xy 324.400683 -338.625497) (xy 324.430149 -338.579647) (xy 324.46584 -338.538456) (xy 324.507031 -338.502765)
			(xy 324.552881 -338.473299) (xy 324.602458 -338.450657) (xy 324.654753 -338.435302) (xy 324.708701 -338.427546)
			(xy 324.763203 -338.427546) (xy 324.817151 -338.435302) (xy 324.869446 -338.450657) (xy 324.919023 -338.473299)
			(xy 324.964873 -338.502765) (xy 325.006064 -338.538456) (xy 325.041755 -338.579647) (xy 325.071221 -338.625497)
			(xy 325.093863 -338.675074) (xy 325.109218 -338.727369) (xy 325.116974 -338.781317) (xy 325.11746 -338.808568)
			(xy 325.116965 -338.836042) (xy 325.109076 -338.890422) (xy 325.093459 -338.943105) (xy 325.090808 -338.94885)
			(xy 325.359276 -338.94885) (xy 325.359276 -338.89435) (xy 325.367031 -338.840405) (xy 325.382385 -338.788112)
			(xy 325.405024 -338.738537) (xy 325.434487 -338.692688) (xy 325.470176 -338.651498) (xy 325.511362 -338.615807)
			(xy 325.557209 -338.586339) (xy 325.606782 -338.563696) (xy 325.659074 -338.548338) (xy 325.713018 -338.540578)
			(xy 325.740268 -338.54009) (xy 325.765504 -338.540458) (xy 325.815539 -338.547085) (xy 325.86426 -338.560267)
			(xy 325.91081 -338.579771) (xy 325.9328 -338.59216) (xy 325.942452 -338.598002) (xy 325.96455 -338.600034)
			(xy 326.059038 -338.566506) (xy 326.07504 -338.551012) (xy 326.079104 -338.540598) (xy 326.089779 -338.513812)
			(xy 326.118069 -338.46357) (xy 326.153601 -338.418159) (xy 326.195566 -338.378617) (xy 326.243007 -338.345844)
			(xy 326.294841 -338.320588) (xy 326.349887 -338.303424) (xy 326.40689 -338.294745) (xy 326.43572 -338.294218)
			(xy 326.462975 -338.294636) (xy 326.516928 -338.302397) (xy 326.569229 -338.317757) (xy 326.618811 -338.340403)
			(xy 326.664665 -338.369876) (xy 326.705858 -338.405574) (xy 326.741552 -338.446772) (xy 326.771019 -338.49263)
			(xy 326.793659 -338.542214) (xy 326.806382 -338.585556) (xy 328.947272 -338.585556) (xy 328.947786 -338.557983)
			(xy 328.95573 -338.503413) (xy 328.971446 -338.450554) (xy 328.994607 -338.400509) (xy 329.024731 -338.354318)
			(xy 329.061189 -338.312944) (xy 329.081892 -338.294726) (xy 329.089993 -338.287108) (xy 329.099357 -338.266968)
			(xy 329.099926 -338.255864) (xy 329.099926 -338.178648) (xy 329.099371 -338.167536) (xy 329.090026 -338.147376)
			(xy 329.081892 -338.139786) (xy 329.061169 -338.121587) (xy 329.0247 -338.080216) (xy 328.99457 -338.034023)
			(xy 328.971406 -337.983973) (xy 328.955692 -337.931108) (xy 328.947756 -337.876531) (xy 328.947272 -337.848956)
			(xy 328.947737 -337.821705) (xy 328.955499 -337.767757) (xy 328.970859 -337.715463) (xy 328.993503 -337.665887)
			(xy 329.022972 -337.620038) (xy 329.058666 -337.578849) (xy 329.099857 -337.543158) (xy 329.145708 -337.513692)
			(xy 329.195286 -337.49105) (xy 329.247581 -337.475694) (xy 329.301529 -337.467935) (xy 329.32878 -337.467448)
			(xy 329.36307 -337.468972) (xy 329.37323 -337.469988) (xy 329.392534 -337.463892) (xy 329.463146 -337.40471)
			(xy 329.472544 -337.386676) (xy 329.47356 -337.376516) (xy 329.476506 -337.348343) (xy 329.489684 -337.293252)
			(xy 329.510865 -337.240716) (xy 329.539585 -337.191892) (xy 329.57521 -337.147852) (xy 329.616957 -337.109566)
			(xy 329.663909 -337.077877) (xy 329.715031 -337.05348) (xy 329.769199 -337.036914) (xy 329.825221 -337.028542)
			(xy 329.853544 -337.028028) (xy 329.871563 -337.028248) (xy 329.907438 -337.031683) (xy 329.925172 -337.034886)
			(xy 329.93457 -337.036664) (xy 329.95362 -337.032854) (xy 330.028804 -336.985102) (xy 330.040234 -336.969354)
			(xy 330.04252 -336.959956) (xy 330.049915 -336.932911) (xy 330.071545 -336.881184) (xy 330.100509 -336.833179)
			(xy 330.136185 -336.789927) (xy 330.177804 -336.75236) (xy 330.224472 -336.721286) (xy 330.275184 -336.697373)
			(xy 330.328848 -336.681137) (xy 330.384311 -336.672927) (xy 330.412344 -336.672428) (xy 330.439598 -336.672837)
			(xy 330.49355 -336.6806) (xy 330.545849 -336.695963) (xy 330.595428 -336.718612) (xy 330.64128 -336.748086)
			(xy 330.682471 -336.783786) (xy 330.718162 -336.824984) (xy 330.747627 -336.870842) (xy 330.770265 -336.920426)
			(xy 330.785617 -336.972728) (xy 330.793369 -337.026682) (xy 330.793852 -337.053936) (xy 330.793359 -337.08151)
			(xy 330.785414 -337.136082) (xy 330.769696 -337.188942) (xy 330.746531 -337.238989) (xy 330.716403 -337.285179)
			(xy 330.679938 -337.32655) (xy 330.659232 -337.344766) (xy 330.651122 -337.352376) (xy 330.641766 -337.372522)
			(xy 330.641198 -337.383628) (xy 330.641198 -337.460844) (xy 330.641782 -337.471952) (xy 330.651109 -337.492111)
			(xy 330.659232 -337.499706) (xy 330.679972 -337.517883) (xy 330.716433 -337.559261) (xy 330.746556 -337.605457)
			(xy 330.769715 -337.655508) (xy 330.785426 -337.708373) (xy 330.793363 -337.762948) (xy 330.79336 -337.818098)
			(xy 330.787241 -337.860132) (xy 331.952344 -337.860132) (xy 331.956415 -337.80451) (xy 331.968541 -337.750073)
			(xy 331.988464 -337.697982) (xy 332.01576 -337.649347) (xy 332.049846 -337.605204) (xy 332.089995 -337.566495)
			(xy 332.135353 -337.534044) (xy 332.184953 -337.508543) (xy 332.237737 -337.490536) (xy 332.29258 -337.480406)
			(xy 332.348314 -337.478369) (xy 332.403751 -337.484469) (xy 332.457708 -337.498575) (xy 332.509037 -337.520387)
			(xy 332.556643 -337.549441) (xy 332.599511 -337.585116) (xy 332.636728 -337.626653) (xy 332.667501 -337.673166)
			(xy 332.691173 -337.723663) (xy 332.707241 -337.77707) (xy 332.715361 -337.832246) (xy 332.71587 -337.860132)
			(xy 332.715361 -337.888018) (xy 332.707241 -337.943194) (xy 332.691173 -337.996601) (xy 332.667501 -338.047098)
			(xy 332.636728 -338.093611) (xy 332.599511 -338.135148) (xy 332.556643 -338.170823) (xy 332.509037 -338.199877)
			(xy 332.457708 -338.221689) (xy 332.403751 -338.235795) (xy 332.348314 -338.241895) (xy 332.29258 -338.239858)
			(xy 332.237737 -338.229728) (xy 332.184953 -338.211721) (xy 332.135353 -338.18622) (xy 332.089995 -338.153769)
			(xy 332.049846 -338.11506) (xy 332.01576 -338.070917) (xy 331.988464 -338.022282) (xy 331.968541 -337.970191)
			(xy 331.956415 -337.915754) (xy 331.952344 -337.860132) (xy 330.787241 -337.860132) (xy 330.785416 -337.872673)
			(xy 330.769699 -337.925535) (xy 330.746534 -337.975584) (xy 330.716404 -338.021776) (xy 330.679939 -338.06315)
			(xy 330.659232 -338.081366) (xy 330.651122 -338.088976) (xy 330.641766 -338.109122) (xy 330.641198 -338.120228)
			(xy 330.641198 -338.197444) (xy 330.641782 -338.208552) (xy 330.651109 -338.228711) (xy 330.659232 -338.236306)
			(xy 330.679956 -338.254503) (xy 330.716424 -338.295876) (xy 330.746553 -338.342069) (xy 330.769717 -338.392119)
			(xy 330.785431 -338.444984) (xy 330.793368 -338.499561) (xy 330.793852 -338.527136) (xy 330.793356 -338.554386)
			(xy 330.785596 -338.608331) (xy 330.770238 -338.660623) (xy 330.747596 -338.710197) (xy 330.718492 -338.755482)
			(xy 331.373224 -338.755482) (xy 331.377295 -338.69986) (xy 331.389421 -338.645423) (xy 331.409344 -338.593332)
			(xy 331.43664 -338.544697) (xy 331.470726 -338.500554) (xy 331.510875 -338.461845) (xy 331.556233 -338.429394)
			(xy 331.605833 -338.403893) (xy 331.658617 -338.385886) (xy 331.71346 -338.375756) (xy 331.769194 -338.373719)
			(xy 331.824631 -338.379819) (xy 331.878588 -338.393925) (xy 331.929917 -338.415737) (xy 331.977523 -338.444791)
			(xy 332.020391 -338.480466) (xy 332.057608 -338.522003) (xy 332.088381 -338.568516) (xy 332.112053 -338.619013)
			(xy 332.128121 -338.67242) (xy 332.136241 -338.727596) (xy 332.13675 -338.755482) (xy 332.136241 -338.783368)
			(xy 332.128121 -338.838544) (xy 332.112053 -338.891951) (xy 332.088381 -338.942448) (xy 332.057608 -338.988961)
			(xy 332.020391 -339.030498) (xy 331.977523 -339.066173) (xy 331.929917 -339.095227) (xy 331.878588 -339.117039)
			(xy 331.824631 -339.131145) (xy 331.769194 -339.137245) (xy 331.71346 -339.135208) (xy 331.658617 -339.125078)
			(xy 331.605833 -339.107071) (xy 331.556233 -339.08157) (xy 331.510875 -339.049119) (xy 331.470726 -339.01041)
			(xy 331.43664 -338.966267) (xy 331.409344 -338.917632) (xy 331.389421 -338.865541) (xy 331.377295 -338.811104)
			(xy 331.373224 -338.755482) (xy 330.718492 -338.755482) (xy 330.71813 -338.756046) (xy 330.68244 -338.797234)
			(xy 330.641252 -338.832925) (xy 330.595405 -338.862392) (xy 330.545831 -338.885035) (xy 330.493539 -338.900394)
			(xy 330.439594 -338.908155) (xy 330.412344 -338.908644) (xy 330.384492 -338.908049) (xy 330.329381 -338.899932)
			(xy 330.276034 -338.883895) (xy 330.225583 -338.860277) (xy 330.1791 -338.829579) (xy 330.13757 -338.792453)
			(xy 330.101875 -338.749687) (xy 330.072772 -338.702188) (xy 330.050879 -338.650965) (xy 330.043282 -338.624164)
			(xy 330.040996 -338.615274) (xy 330.030328 -338.600034) (xy 329.958446 -338.552282) (xy 329.940412 -338.548218)
			(xy 329.931268 -338.549488) (xy 329.918252 -338.551158) (xy 329.892067 -338.552937) (xy 329.878944 -338.553044)
			(xy 329.864795 -338.552945) (xy 329.836572 -338.550914) (xy 329.822556 -338.54898) (xy 329.812396 -338.547456)
			(xy 329.792838 -338.552282) (xy 329.718416 -338.608162) (xy 329.708256 -338.625688) (xy 329.706986 -338.635848)
			(xy 329.70293 -338.663007) (xy 329.687955 -338.71584) (xy 329.665561 -338.76598) (xy 329.63621 -338.812392)
			(xy 329.600509 -338.854117) (xy 329.559195 -338.890293) (xy 329.513122 -338.920173) (xy 329.463242 -338.94314)
			(xy 329.410584 -338.958719) (xy 329.356237 -338.966588) (xy 329.32878 -338.967064) (xy 329.301525 -338.966664)
			(xy 329.247569 -338.958903) (xy 329.195267 -338.943542) (xy 329.145684 -338.920894) (xy 329.099829 -338.89142)
			(xy 329.058635 -338.855719) (xy 329.022942 -338.81452) (xy 328.993475 -338.76866) (xy 328.970836 -338.719073)
			(xy 328.955484 -338.666768) (xy 328.947732 -338.612811) (xy 328.947272 -338.585556) (xy 326.806382 -338.585556)
			(xy 326.809013 -338.594517) (xy 326.816767 -338.648471) (xy 326.817228 -338.675726) (xy 326.81656 -338.707288)
			(xy 326.806176 -338.769553) (xy 326.785693 -338.829263) (xy 326.771254 -338.857336) (xy 326.766428 -338.866226)
			(xy 326.764396 -338.885784) (xy 326.79005 -338.973922) (xy 326.802496 -338.989416) (xy 326.811386 -338.994496)
			(xy 326.83651 -339.009007) (xy 326.882393 -339.044516) (xy 326.922368 -339.086566) (xy 326.955511 -339.134186)
			(xy 326.981058 -339.186277) (xy 326.998419 -339.241637) (xy 327.007193 -339.298989) (xy 327.007728 -339.327998)
			(xy 327.007242 -339.355249) (xy 326.999486 -339.409197) (xy 326.993048 -339.431122) (xy 332.71206 -339.431122)
			(xy 332.712569 -339.403648) (xy 332.720457 -339.34927) (xy 332.736072 -339.296588) (xy 332.759092 -339.246695)
			(xy 332.789037 -339.200625) (xy 332.806802 -339.179662) (xy 332.812898 -339.17255) (xy 332.819248 -339.155532)
			(xy 332.819248 -339.06968) (xy 332.812898 -339.052662) (xy 332.806802 -339.04555) (xy 332.789034 -339.024591)
			(xy 332.75911 -338.978509) (xy 332.736098 -338.928613) (xy 332.720473 -338.875936) (xy 332.712558 -338.821563)
			(xy 332.71206 -338.79409) (xy 332.712546 -338.766839) (xy 332.720302 -338.712891) (xy 332.735657 -338.660596)
			(xy 332.758299 -338.611019) (xy 332.787765 -338.565169) (xy 332.823456 -338.523978) (xy 332.864647 -338.488287)
			(xy 332.910497 -338.458821) (xy 332.960074 -338.436179) (xy 333.012369 -338.420824) (xy 333.066317 -338.413068)
			(xy 333.120819 -338.413068) (xy 333.174767 -338.420824) (xy 333.227062 -338.436179) (xy 333.276639 -338.458821)
			(xy 333.322489 -338.488287) (xy 333.36368 -338.523978) (xy 333.399371 -338.565169) (xy 333.428837 -338.611019)
			(xy 333.451479 -338.660596) (xy 333.466834 -338.712891) (xy 333.47459 -338.766839) (xy 333.475076 -338.79409)
			(xy 333.47459 -338.821565) (xy 333.466699 -338.875945) (xy 333.451079 -338.928627) (xy 333.448438 -338.934349)
			(xy 333.716898 -338.934349) (xy 333.716898 -338.879851) (xy 333.724654 -338.825908) (xy 333.740007 -338.773617)
			(xy 333.762646 -338.724043) (xy 333.792109 -338.678196) (xy 333.827797 -338.637009) (xy 333.868983 -338.601319)
			(xy 333.914829 -338.571854) (xy 333.964402 -338.549213) (xy 334.016692 -338.533857) (xy 334.070635 -338.526099)
			(xy 334.097884 -338.525612) (xy 334.123121 -338.52597) (xy 334.173156 -338.5326) (xy 334.221876 -338.545784)
			(xy 334.268427 -338.565292) (xy 334.290416 -338.577682) (xy 334.300068 -338.583524) (xy 334.322166 -338.585556)
			(xy 334.416654 -338.552028) (xy 334.432656 -338.536534) (xy 334.43672 -338.52612) (xy 334.447394 -338.499334)
			(xy 334.475682 -338.449089) (xy 334.511214 -338.403678) (xy 334.553179 -338.364135) (xy 334.60062 -338.331361)
			(xy 334.652455 -338.306106) (xy 334.707502 -338.288944) (xy 334.764506 -338.280266) (xy 334.793336 -338.27974)
			(xy 334.820592 -338.280122) (xy 334.874548 -338.287885) (xy 334.926851 -338.303248) (xy 334.976434 -338.325898)
			(xy 335.02229 -338.355374) (xy 335.063483 -338.391076) (xy 335.099176 -338.432278) (xy 335.128642 -338.47814)
			(xy 335.151282 -338.527728) (xy 335.164005 -338.571078) (xy 337.304888 -338.571078) (xy 337.305412 -338.543506)
			(xy 337.313353 -338.488935) (xy 337.329067 -338.436077) (xy 337.352226 -338.386031) (xy 337.382348 -338.33984)
			(xy 337.418806 -338.298466) (xy 337.439508 -338.280248) (xy 337.447602 -338.272623) (xy 337.456969 -338.252489)
			(xy 337.457542 -338.241386) (xy 337.457542 -338.16417) (xy 337.457025 -338.153053) (xy 337.447652 -338.132894)
			(xy 337.439508 -338.125308) (xy 337.418799 -338.107094) (xy 337.382328 -338.065726) (xy 337.352196 -338.019537)
			(xy 337.329029 -337.969489) (xy 337.313313 -337.916627) (xy 337.305373 -337.862053) (xy 337.304888 -337.834478)
			(xy 337.305357 -337.807226) (xy 337.313117 -337.753278) (xy 337.328474 -337.700983) (xy 337.351118 -337.651406)
			(xy 337.380586 -337.605556) (xy 337.416279 -337.564366) (xy 337.457471 -337.528675) (xy 337.503322 -337.499209)
			(xy 337.5529 -337.476568) (xy 337.605196 -337.461213) (xy 337.659144 -337.453456) (xy 337.686396 -337.45297)
			(xy 337.720686 -337.454494) (xy 337.730846 -337.45551) (xy 337.75015 -337.449414) (xy 337.820762 -337.390232)
			(xy 337.83016 -337.372198) (xy 337.831176 -337.362038) (xy 337.834125 -337.333865) (xy 337.8473 -337.278773)
			(xy 337.86848 -337.226236) (xy 337.897198 -337.177411) (xy 337.932823 -337.13337) (xy 337.974571 -337.095084)
			(xy 338.021522 -337.063394) (xy 338.072645 -337.038998) (xy 338.126814 -337.022433) (xy 338.182837 -337.014063)
			(xy 338.21116 -337.01355) (xy 338.229179 -337.013767) (xy 338.265054 -337.017204) (xy 338.282788 -337.020408)
			(xy 338.292186 -337.022186) (xy 338.311236 -337.018376) (xy 338.38642 -336.970624) (xy 338.39785 -336.954876)
			(xy 338.400136 -336.945478) (xy 338.407531 -336.918433) (xy 338.429159 -336.866705) (xy 338.458122 -336.818698)
			(xy 338.493798 -336.775445) (xy 338.535417 -336.737878) (xy 338.582086 -336.706803) (xy 338.632798 -336.682891)
			(xy 338.686463 -336.666656) (xy 338.741926 -336.658447) (xy 338.76996 -336.65795) (xy 338.797208 -336.658515)
			(xy 338.851151 -336.666265) (xy 338.895514 -336.679286) (xy 339.325712 -336.679286) (xy 339.326216 -336.651376)
			(xy 339.334351 -336.596151) (xy 339.350445 -336.542701) (xy 339.374154 -336.492167) (xy 339.404974 -336.445625)
			(xy 339.423248 -336.424524) (xy 339.429598 -336.417412) (xy 339.436202 -336.40014) (xy 339.436202 -336.313018)
			(xy 339.429598 -336.295746) (xy 339.423248 -336.288634) (xy 339.404956 -336.267546) (xy 339.374133 -336.221004)
			(xy 339.350421 -336.170466) (xy 339.334327 -336.117012) (xy 339.326196 -336.061784) (xy 339.325712 -336.033872)
			(xy 339.326198 -336.006621) (xy 339.333954 -335.952673) (xy 339.349309 -335.900378) (xy 339.371951 -335.850801)
			(xy 339.401417 -335.804951) (xy 339.437108 -335.76376) (xy 339.478299 -335.728069) (xy 339.524149 -335.698603)
			(xy 339.573726 -335.675961) (xy 339.626021 -335.660606) (xy 339.679969 -335.65285) (xy 339.734471 -335.65285)
			(xy 339.788419 -335.660606) (xy 339.840714 -335.675961) (xy 339.890291 -335.698603) (xy 339.936141 -335.728069)
			(xy 339.977332 -335.76376) (xy 340.013023 -335.804951) (xy 340.042489 -335.850801) (xy 340.065131 -335.900378)
			(xy 340.080486 -335.952673) (xy 340.088242 -336.006621) (xy 340.088728 -336.033872) (xy 340.088274 -336.061784)
			(xy 340.080129 -336.117011) (xy 340.064025 -336.170463) (xy 340.040303 -336.220997) (xy 340.009472 -336.267535)
			(xy 339.991192 -336.288634) (xy 339.984842 -336.295746) (xy 339.978238 -336.313018) (xy 339.978238 -336.40014)
			(xy 339.984842 -336.417412) (xy 339.991192 -336.424524) (xy 340.009454 -336.445637) (xy 340.040284 -336.492171)
			(xy 340.064003 -336.542703) (xy 340.080103 -336.596151) (xy 340.088241 -336.651376) (xy 340.088728 -336.679286)
			(xy 340.088242 -336.706537) (xy 340.080486 -336.760485) (xy 340.065131 -336.81278) (xy 340.042489 -336.862357)
			(xy 340.013023 -336.908207) (xy 339.977332 -336.949398) (xy 339.936141 -336.985089) (xy 339.893022 -337.0128)
			(xy 343.707948 -337.0128) (xy 343.712115 -336.957185) (xy 343.724526 -336.902811) (xy 343.744901 -336.850895)
			(xy 343.772787 -336.802596) (xy 343.80756 -336.758992) (xy 343.848443 -336.721058) (xy 343.894524 -336.68964)
			(xy 343.944772 -336.665442) (xy 343.998066 -336.649003) (xy 344.053214 -336.640691) (xy 344.0811 -336.64017)
			(xy 344.107521 -336.640635) (xy 344.159836 -336.648084) (xy 344.210575 -336.662848) (xy 344.258719 -336.68463)
			(xy 344.303304 -336.712993) (xy 344.32367 -336.729832) (xy 344.330528 -336.735928) (xy 344.347546 -336.742024)
			(xy 344.431874 -336.742024) (xy 344.448892 -336.735928) (xy 344.45575 -336.729832) (xy 344.476116 -336.712993)
			(xy 344.520702 -336.684628) (xy 344.568846 -336.662841) (xy 344.619583 -336.64807) (xy 344.671898 -336.64061)
			(xy 344.724742 -336.64061) (xy 344.777057 -336.64807) (xy 344.827794 -336.662841) (xy 344.875938 -336.684628)
			(xy 344.920524 -336.712993) (xy 344.94089 -336.729832) (xy 344.947748 -336.735928) (xy 344.964766 -336.742024)
			(xy 345.049094 -336.742024) (xy 345.066112 -336.735928) (xy 345.07297 -336.729832) (xy 345.09535 -336.711413)
			(xy 345.144682 -336.680989) (xy 345.198128 -336.658566) (xy 345.226132 -336.651092) (xy 345.237816 -336.648298)
			(xy 345.25585 -336.632804) (xy 345.297506 -336.537046) (xy 345.29649 -336.513424) (xy 345.290648 -336.50301)
			(xy 345.279175 -336.481643) (xy 345.261122 -336.43663) (xy 345.248921 -336.389692) (xy 345.242769 -336.341585)
			(xy 345.242388 -336.317336) (xy 345.242883 -336.289763) (xy 345.25083 -336.235191) (xy 345.266549 -336.182332)
			(xy 345.289714 -336.132286) (xy 345.319841 -336.086096) (xy 345.356303 -336.044723) (xy 345.377008 -336.026506)
			(xy 345.385121 -336.018898) (xy 345.394478 -335.998751) (xy 345.395042 -335.987644) (xy 345.395042 -335.910428)
			(xy 345.394493 -335.899315) (xy 345.385143 -335.879156) (xy 345.377008 -335.871566) (xy 345.356279 -335.853374)
			(xy 345.31981 -335.812002) (xy 345.289679 -335.765808) (xy 345.266517 -335.715756) (xy 345.250804 -335.66289)
			(xy 345.24287 -335.608312) (xy 345.242388 -335.580736) (xy 345.242874 -335.553485) (xy 345.25063 -335.499537)
			(xy 345.265985 -335.447242) (xy 345.288627 -335.397665) (xy 345.318093 -335.351815) (xy 345.353784 -335.310624)
			(xy 345.394975 -335.274933) (xy 345.440825 -335.245467) (xy 345.490402 -335.222825) (xy 345.542697 -335.20747)
			(xy 345.596645 -335.199714) (xy 345.651147 -335.199714) (xy 345.705095 -335.20747) (xy 345.75739 -335.222825)
			(xy 345.806967 -335.245467) (xy 345.852817 -335.274933) (xy 345.894008 -335.310624) (xy 345.929699 -335.351815)
			(xy 345.959165 -335.397665) (xy 345.981807 -335.447242) (xy 345.997162 -335.499537) (xy 346.004918 -335.553485)
			(xy 346.005404 -335.580736) (xy 346.004893 -335.608309) (xy 345.996949 -335.66288) (xy 345.981233 -335.715739)
			(xy 345.958072 -335.765785) (xy 345.927947 -335.811976) (xy 345.891488 -335.853349) (xy 345.870784 -335.871566)
			(xy 345.862683 -335.879184) (xy 345.85332 -335.899324) (xy 345.85275 -335.910428) (xy 345.85275 -335.987644)
			(xy 345.853317 -335.998754) (xy 345.862655 -336.018914) (xy 345.870784 -336.026506) (xy 345.891498 -336.044714)
			(xy 345.927969 -336.086083) (xy 345.958101 -336.132273) (xy 345.981266 -336.182322) (xy 345.996982 -336.235185)
			(xy 346.00492 -336.289761) (xy 346.005404 -336.317336) (xy 346.004864 -336.345812) (xy 345.99638 -336.402129)
			(xy 345.979619 -336.45656) (xy 345.954956 -336.507895) (xy 345.922936 -336.554994) (xy 345.884272 -336.596812)
			(xy 345.839823 -336.632418) (xy 345.790575 -336.661023) (xy 345.737623 -336.681992) (xy 345.710002 -336.688938)
			(xy 345.698572 -336.691732) (xy 345.680284 -336.706718) (xy 345.637104 -336.801968) (xy 345.637866 -336.82559)
			(xy 345.643708 -336.836004) (xy 345.657683 -336.863356) (xy 345.677513 -336.921486) (xy 345.687548 -336.982079)
			(xy 345.688158 -337.012788) (xy 345.687632 -337.039402) (xy 345.680059 -337.092089) (xy 345.665066 -337.143162)
			(xy 345.642956 -337.191581) (xy 345.614182 -337.236361) (xy 345.579327 -337.27659) (xy 345.539103 -337.31145)
			(xy 345.494326 -337.340231) (xy 345.44591 -337.362347) (xy 345.39484 -337.377348) (xy 345.342154 -337.384929)
			(xy 345.31554 -337.385406) (xy 345.289117 -337.384982) (xy 345.2368 -337.377523) (xy 345.186061 -337.362751)
			(xy 345.137918 -337.340959) (xy 345.093334 -337.312587) (xy 345.07297 -337.295744) (xy 345.066112 -337.289648)
			(xy 345.049094 -337.283552) (xy 344.964766 -337.283552) (xy 344.947748 -337.289648) (xy 344.94089 -337.295744)
			(xy 344.920524 -337.312583) (xy 344.875938 -337.340948) (xy 344.827794 -337.362735) (xy 344.777057 -337.377506)
			(xy 344.724742 -337.384966) (xy 344.671898 -337.384966) (xy 344.619583 -337.377506) (xy 344.568846 -337.362735)
			(xy 344.520702 -337.340948) (xy 344.476116 -337.312583) (xy 344.45575 -337.295744) (xy 344.448892 -337.289648)
			(xy 344.431874 -337.283552) (xy 344.347546 -337.283552) (xy 344.330528 -337.289648) (xy 344.32367 -337.295744)
			(xy 344.303309 -337.312587) (xy 344.258718 -337.340944) (xy 344.210573 -337.362723) (xy 344.159835 -337.377489)
			(xy 344.107521 -337.384947) (xy 344.0811 -337.385406) (xy 344.053214 -337.384909) (xy 343.998066 -337.376597)
			(xy 343.944772 -337.360158) (xy 343.894524 -337.33596) (xy 343.848443 -337.304542) (xy 343.80756 -337.266608)
			(xy 343.772787 -337.223004) (xy 343.744901 -337.174705) (xy 343.724526 -337.122789) (xy 343.712115 -337.068415)
			(xy 343.707948 -337.0128) (xy 339.893022 -337.0128) (xy 339.890291 -337.014555) (xy 339.840714 -337.037197)
			(xy 339.788419 -337.052552) (xy 339.734471 -337.060308) (xy 339.679969 -337.060308) (xy 339.626021 -337.052552)
			(xy 339.573726 -337.037197) (xy 339.524149 -337.014555) (xy 339.478299 -336.985089) (xy 339.437108 -336.949398)
			(xy 339.401417 -336.908207) (xy 339.371951 -336.862357) (xy 339.349309 -336.81278) (xy 339.333954 -336.760485)
			(xy 339.326198 -336.706537) (xy 339.325712 -336.679286) (xy 338.895514 -336.679286) (xy 338.903442 -336.681613)
			(xy 338.953016 -336.704247) (xy 338.998864 -336.733705) (xy 339.040054 -336.769388) (xy 339.075746 -336.81057)
			(xy 339.105214 -336.856412) (xy 339.127858 -336.905981) (xy 339.143217 -336.958269) (xy 339.150979 -337.01221)
			(xy 339.151468 -337.039458) (xy 339.150985 -337.067032) (xy 339.143037 -337.121605) (xy 339.127316 -337.174465)
			(xy 339.10415 -337.224511) (xy 339.07402 -337.270701) (xy 339.037554 -337.312072) (xy 339.016848 -337.330288)
			(xy 339.008731 -337.337892) (xy 338.999378 -337.358043) (xy 338.998814 -337.36915) (xy 338.998814 -337.446366)
			(xy 338.999381 -337.457476) (xy 339.00872 -337.477635) (xy 339.016848 -337.485228) (xy 339.037514 -337.503488)
			(xy 339.073982 -337.544852) (xy 339.104114 -337.591035) (xy 339.127281 -337.641077) (xy 339.143001 -337.693932)
			(xy 339.150945 -337.748501) (xy 339.150949 -337.803645) (xy 339.143012 -337.858215) (xy 339.127342 -337.910932)
			(xy 340.283544 -337.910932) (xy 340.287615 -337.85531) (xy 340.299741 -337.800873) (xy 340.319664 -337.748782)
			(xy 340.34696 -337.700147) (xy 340.381046 -337.656004) (xy 340.421195 -337.617295) (xy 340.466553 -337.584844)
			(xy 340.516153 -337.559343) (xy 340.568937 -337.541336) (xy 340.62378 -337.531206) (xy 340.679514 -337.529169)
			(xy 340.734951 -337.535269) (xy 340.788908 -337.549375) (xy 340.840237 -337.571187) (xy 340.887843 -337.600241)
			(xy 340.930711 -337.635916) (xy 340.967928 -337.677453) (xy 340.998701 -337.723966) (xy 341.022373 -337.774463)
			(xy 341.038441 -337.82787) (xy 341.046561 -337.883046) (xy 341.04707 -337.910932) (xy 341.046561 -337.938818)
			(xy 341.038441 -337.993994) (xy 341.022373 -338.047401) (xy 340.998701 -338.097898) (xy 340.967928 -338.144411)
			(xy 340.930711 -338.185948) (xy 340.887843 -338.221623) (xy 340.840237 -338.250677) (xy 340.788908 -338.272489)
			(xy 340.734951 -338.286595) (xy 340.679514 -338.292695) (xy 340.62378 -338.290658) (xy 340.568937 -338.280528)
			(xy 340.516153 -338.262521) (xy 340.466553 -338.23702) (xy 340.421195 -338.204569) (xy 340.381046 -338.16586)
			(xy 340.34696 -338.121717) (xy 340.319664 -338.073082) (xy 340.299741 -338.020991) (xy 340.287615 -337.966554)
			(xy 340.283544 -337.910932) (xy 339.127342 -337.910932) (xy 339.1273 -337.911073) (xy 339.10414 -337.961117)
			(xy 339.074015 -338.007305) (xy 339.037553 -338.048674) (xy 339.016848 -338.066888) (xy 339.008731 -338.074492)
			(xy 338.999378 -338.094643) (xy 338.998814 -338.10575) (xy 338.998814 -338.182966) (xy 338.999381 -338.194076)
			(xy 339.00872 -338.214235) (xy 339.016848 -338.221828) (xy 339.037586 -338.24001) (xy 339.074052 -338.281386)
			(xy 339.104179 -338.327583) (xy 339.12734 -338.377636) (xy 339.143051 -338.430503) (xy 339.150985 -338.485082)
			(xy 339.151468 -338.512658) (xy 339.151006 -338.539912) (xy 339.143253 -338.593865) (xy 339.1279 -338.646165)
			(xy 339.10526 -338.695748) (xy 339.075793 -338.741603) (xy 339.040099 -338.782797) (xy 339.012995 -338.806282)
			(xy 339.704424 -338.806282) (xy 339.708495 -338.75066) (xy 339.720621 -338.696223) (xy 339.740544 -338.644132)
			(xy 339.76784 -338.595497) (xy 339.801926 -338.551354) (xy 339.842075 -338.512645) (xy 339.887433 -338.480194)
			(xy 339.937033 -338.454693) (xy 339.989817 -338.436686) (xy 340.04466 -338.426556) (xy 340.100394 -338.424519)
			(xy 340.155831 -338.430619) (xy 340.209788 -338.444725) (xy 340.261117 -338.466537) (xy 340.308723 -338.495591)
			(xy 340.351591 -338.531266) (xy 340.388808 -338.572803) (xy 340.419581 -338.619316) (xy 340.443253 -338.669813)
			(xy 340.459321 -338.72322) (xy 340.467441 -338.778396) (xy 340.46795 -338.806282) (xy 340.467441 -338.834168)
			(xy 340.459321 -338.889344) (xy 340.443253 -338.942751) (xy 340.419581 -338.993248) (xy 340.388808 -339.039761)
			(xy 340.351591 -339.081298) (xy 340.308723 -339.116973) (xy 340.261117 -339.146027) (xy 340.209788 -339.167839)
			(xy 340.155831 -339.181945) (xy 340.100394 -339.188045) (xy 340.04466 -339.186008) (xy 339.989817 -339.175878)
			(xy 339.937033 -339.157871) (xy 339.887433 -339.13237) (xy 339.842075 -339.099919) (xy 339.801926 -339.06121)
			(xy 339.76784 -339.017067) (xy 339.740544 -338.968432) (xy 339.720621 -338.916341) (xy 339.708495 -338.861904)
			(xy 339.704424 -338.806282) (xy 339.012995 -338.806282) (xy 338.998905 -338.818491) (xy 338.953049 -338.847959)
			(xy 338.903467 -338.8706) (xy 338.851167 -338.885953) (xy 338.797214 -338.893705) (xy 338.76996 -338.894166)
			(xy 338.742102 -338.893704) (xy 338.686983 -338.885574) (xy 338.63363 -338.869521) (xy 338.583175 -338.845887)
			(xy 338.53669 -338.815173) (xy 338.495161 -338.77803) (xy 338.45947 -338.735247) (xy 338.430373 -338.687732)
			(xy 338.40849 -338.636494) (xy 338.400898 -338.609686) (xy 338.398612 -338.600796) (xy 338.387944 -338.585556)
			(xy 338.316062 -338.537804) (xy 338.298028 -338.53374) (xy 338.288884 -338.53501) (xy 338.275867 -338.536679)
			(xy 338.249683 -338.538459) (xy 338.23656 -338.538566) (xy 338.222411 -338.538477) (xy 338.194188 -338.53644)
			(xy 338.180172 -338.534502) (xy 338.170012 -338.532978) (xy 338.150454 -338.537804) (xy 338.076032 -338.593684)
			(xy 338.065872 -338.61121) (xy 338.064602 -338.62137) (xy 338.060548 -338.648529) (xy 338.045571 -338.701361)
			(xy 338.023175 -338.7515) (xy 337.993824 -338.797911) (xy 337.958122 -338.839635) (xy 337.916809 -338.875811)
			(xy 337.870736 -338.905691) (xy 337.820856 -338.928658) (xy 337.768199 -338.944238) (xy 337.713853 -338.952109)
			(xy 337.686396 -338.952586) (xy 337.659142 -338.952148) (xy 337.605189 -338.94439) (xy 337.552889 -338.929033)
			(xy 337.503308 -338.906388) (xy 337.457454 -338.876918) (xy 337.41626 -338.841221) (xy 337.380567 -338.800026)
			(xy 337.3511 -338.754169) (xy 337.328458 -338.704586) (xy 337.313104 -338.652285) (xy 337.30535 -338.598332)
			(xy 337.304888 -338.571078) (xy 335.164005 -338.571078) (xy 335.166633 -338.580034) (xy 335.174384 -338.633992)
			(xy 335.174844 -338.661248) (xy 335.174195 -338.692811) (xy 335.163804 -338.755077) (xy 335.143314 -338.814786)
			(xy 335.12887 -338.842858) (xy 335.124044 -338.851748) (xy 335.122012 -338.871306) (xy 335.147666 -338.959444)
			(xy 335.160112 -338.974938) (xy 335.169002 -338.980018) (xy 335.194096 -338.994578) (xy 335.239978 -339.03008)
			(xy 335.279953 -339.072122) (xy 335.313099 -339.119734) (xy 335.338651 -339.171817) (xy 335.356019 -339.227169)
			(xy 335.364803 -339.284513) (xy 335.365344 -339.31352) (xy 335.364858 -339.340771) (xy 335.357102 -339.394719)
			(xy 335.341747 -339.447014) (xy 335.319105 -339.496591) (xy 335.289639 -339.542441) (xy 335.253948 -339.583632)
			(xy 335.212757 -339.619323) (xy 335.166907 -339.648789) (xy 335.11733 -339.671431) (xy 335.065035 -339.686786)
			(xy 335.011087 -339.694542) (xy 334.956585 -339.694542) (xy 334.902637 -339.686786) (xy 334.850342 -339.671431)
			(xy 334.800765 -339.648789) (xy 334.754915 -339.619323) (xy 334.713724 -339.583632) (xy 334.678033 -339.542441)
			(xy 334.648567 -339.496591) (xy 334.625925 -339.447014) (xy 334.61057 -339.394719) (xy 334.602814 -339.340771)
			(xy 334.602328 -339.31352) (xy 334.602968 -339.281956) (xy 334.613363 -339.21969) (xy 334.633857 -339.159982)
			(xy 334.648302 -339.13191) (xy 334.653128 -339.12302) (xy 334.65516 -339.103462) (xy 334.629506 -339.015324)
			(xy 334.61706 -338.99983) (xy 334.60817 -338.99475) (xy 334.600804 -338.990686) (xy 334.591152 -338.984844)
			(xy 334.569054 -338.982812) (xy 334.474566 -339.01634) (xy 334.458564 -339.031834) (xy 334.4545 -339.042248)
			(xy 334.443846 -339.069042) (xy 334.415551 -339.119284) (xy 334.380014 -339.164692) (xy 334.338046 -339.204233)
			(xy 334.290603 -339.237004) (xy 334.238767 -339.262259) (xy 334.183719 -339.279421) (xy 334.126715 -339.2881)
			(xy 334.097884 -339.288628) (xy 334.070635 -339.288101) (xy 334.016692 -339.280343) (xy 333.964402 -339.264987)
			(xy 333.914829 -339.242346) (xy 333.868983 -339.212881) (xy 333.827797 -339.177191) (xy 333.792109 -339.136004)
			(xy 333.762646 -339.090157) (xy 333.740007 -339.040583) (xy 333.724654 -338.988292) (xy 333.716898 -338.934349)
			(xy 333.448438 -338.934349) (xy 333.428054 -338.97852) (xy 333.398102 -339.024588) (xy 333.380334 -339.04555)
			(xy 333.374238 -339.052662) (xy 333.367888 -339.06968) (xy 333.367888 -339.155532) (xy 333.374238 -339.17255)
			(xy 333.380334 -339.179662) (xy 333.398066 -339.20065) (xy 333.427995 -339.246725) (xy 333.451013 -339.296613)
			(xy 333.466646 -339.349284) (xy 333.474572 -339.403651) (xy 333.475076 -339.431122) (xy 333.47459 -339.458373)
			(xy 333.466834 -339.512321) (xy 333.451479 -339.564616) (xy 333.428837 -339.614193) (xy 333.399371 -339.660043)
			(xy 333.36368 -339.701234) (xy 333.322489 -339.736925) (xy 333.276639 -339.766391) (xy 333.227062 -339.789033)
			(xy 333.174767 -339.804388) (xy 333.120819 -339.812144) (xy 333.066317 -339.812144) (xy 333.012369 -339.804388)
			(xy 332.960074 -339.789033) (xy 332.910497 -339.766391) (xy 332.864647 -339.736925) (xy 332.823456 -339.701234)
			(xy 332.787765 -339.660043) (xy 332.758299 -339.614193) (xy 332.735657 -339.564616) (xy 332.720302 -339.512321)
			(xy 332.712546 -339.458373) (xy 332.71206 -339.431122) (xy 326.993048 -339.431122) (xy 326.984131 -339.461492)
			(xy 326.961489 -339.511069) (xy 326.932023 -339.556919) (xy 326.896332 -339.59811) (xy 326.855141 -339.633801)
			(xy 326.809291 -339.663267) (xy 326.759714 -339.685909) (xy 326.707419 -339.701264) (xy 326.653471 -339.70902)
			(xy 326.598969 -339.70902) (xy 326.545021 -339.701264) (xy 326.492726 -339.685909) (xy 326.443149 -339.663267)
			(xy 326.397299 -339.633801) (xy 326.356108 -339.59811) (xy 326.320417 -339.556919) (xy 326.290951 -339.511069)
			(xy 326.268309 -339.461492) (xy 326.252954 -339.409197) (xy 326.245198 -339.355249) (xy 326.244712 -339.327998)
			(xy 326.245385 -339.296436) (xy 326.255766 -339.234171) (xy 326.276247 -339.174461) (xy 326.290686 -339.146388)
			(xy 326.295512 -339.137498) (xy 326.297544 -339.11794) (xy 326.27189 -339.029802) (xy 326.259444 -339.014308)
			(xy 326.250554 -339.009228) (xy 326.243188 -339.005164) (xy 326.233536 -338.999322) (xy 326.211438 -338.99729)
			(xy 326.11695 -339.030818) (xy 326.100948 -339.046312) (xy 326.096884 -339.056726) (xy 326.086232 -339.083521)
			(xy 326.057938 -339.133764) (xy 326.022402 -339.179173) (xy 325.980433 -339.218715) (xy 325.93299 -339.251486)
			(xy 325.881153 -339.276741) (xy 325.826104 -339.293902) (xy 325.769099 -339.30258) (xy 325.740268 -339.303106)
			(xy 325.713018 -339.302622) (xy 325.659074 -339.294862) (xy 325.606782 -339.279504) (xy 325.557209 -339.256861)
			(xy 325.511362 -339.227393) (xy 325.470176 -339.191702) (xy 325.434487 -339.150512) (xy 325.405024 -339.104663)
			(xy 325.382385 -339.055088) (xy 325.367031 -339.002795) (xy 325.359276 -338.94885) (xy 325.090808 -338.94885)
			(xy 325.070436 -338.992998) (xy 325.040485 -339.039066) (xy 325.022718 -339.060028) (xy 325.016622 -339.06714)
			(xy 325.010272 -339.084158) (xy 325.010272 -339.17001) (xy 325.016622 -339.187028) (xy 325.022718 -339.19414)
			(xy 325.040484 -339.2151) (xy 325.070408 -339.261183) (xy 325.09342 -339.311077) (xy 325.109046 -339.363755)
			(xy 325.116961 -339.418127) (xy 325.11746 -339.4456) (xy 325.116974 -339.472851) (xy 325.109218 -339.526799)
			(xy 325.093863 -339.579094) (xy 325.071221 -339.628671) (xy 325.041755 -339.674521) (xy 325.006064 -339.715712)
			(xy 324.964873 -339.751403) (xy 324.919023 -339.780869) (xy 324.869446 -339.803511) (xy 324.817151 -339.818866)
			(xy 324.763203 -339.826622) (xy 324.708701 -339.826622) (xy 324.654753 -339.818866) (xy 324.602458 -339.803511)
			(xy 324.552881 -339.780869) (xy 324.507031 -339.751403) (xy 324.46584 -339.715712) (xy 324.430149 -339.674521)
			(xy 324.400683 -339.628671) (xy 324.378041 -339.579094) (xy 324.362686 -339.526799) (xy 324.35493 -339.472851)
			(xy 324.354444 -339.4456) (xy 318.635301 -339.4456) (xy 318.628547 -339.468604) (xy 318.605905 -339.518181)
			(xy 318.576439 -339.564031) (xy 318.540748 -339.605222) (xy 318.499557 -339.640913) (xy 318.453707 -339.670379)
			(xy 318.40413 -339.693021) (xy 318.351835 -339.708376) (xy 318.297887 -339.716132) (xy 318.243385 -339.716132)
			(xy 318.189437 -339.708376) (xy 318.137142 -339.693021) (xy 318.087565 -339.670379) (xy 318.041715 -339.640913)
			(xy 318.000524 -339.605222) (xy 317.964833 -339.564031) (xy 317.935367 -339.518181) (xy 317.912725 -339.468604)
			(xy 317.89737 -339.416309) (xy 317.889614 -339.362361) (xy 317.889128 -339.33511) (xy 317.889764 -339.303546)
			(xy 317.900161 -339.24128) (xy 317.920656 -339.181572) (xy 317.935102 -339.1535) (xy 317.939928 -339.14461)
			(xy 317.94196 -339.125052) (xy 317.916306 -339.036914) (xy 317.90386 -339.02142) (xy 317.89497 -339.01634)
			(xy 317.887604 -339.012276) (xy 317.877952 -339.006434) (xy 317.855854 -339.004402) (xy 317.761366 -339.03793)
			(xy 317.745364 -339.053424) (xy 317.7413 -339.063838) (xy 317.730641 -339.09063) (xy 317.702347 -339.140872)
			(xy 317.666811 -339.186281) (xy 317.624844 -339.225822) (xy 317.577401 -339.258593) (xy 317.525566 -339.283849)
			(xy 317.470518 -339.301011) (xy 317.413514 -339.30969) (xy 317.384684 -339.310218) (xy 317.357434 -339.309711)
			(xy 317.30349 -339.301953) (xy 317.251198 -339.286596) (xy 317.201624 -339.263955) (xy 317.155777 -339.234489)
			(xy 317.11459 -339.198799) (xy 317.078901 -339.15761) (xy 317.049437 -339.111761) (xy 317.026798 -339.062187)
			(xy 317.011444 -339.009895) (xy 317.003688 -338.95595) (xy 316.73523 -338.95595) (xy 316.714852 -339.000109)
			(xy 316.684901 -339.046178) (xy 316.667134 -339.06714) (xy 316.661038 -339.074252) (xy 316.654688 -339.09127)
			(xy 316.654688 -339.177122) (xy 316.661038 -339.19414) (xy 316.667134 -339.201252) (xy 316.684862 -339.222243)
			(xy 316.714791 -339.268318) (xy 316.73781 -339.318204) (xy 316.753444 -339.370875) (xy 316.761371 -339.425242)
			(xy 316.761876 -339.452712) (xy 316.76139 -339.479963) (xy 316.753634 -339.533911) (xy 316.738279 -339.586206)
			(xy 316.715637 -339.635783) (xy 316.686171 -339.681633) (xy 316.65048 -339.722824) (xy 316.609289 -339.758515)
			(xy 316.563439 -339.787981) (xy 316.513862 -339.810623) (xy 316.461567 -339.825978) (xy 316.407619 -339.833734)
			(xy 316.353117 -339.833734) (xy 316.299169 -339.825978) (xy 316.246874 -339.810623) (xy 316.197297 -339.787981)
			(xy 316.151447 -339.758515) (xy 316.110256 -339.722824) (xy 316.074565 -339.681633) (xy 316.045099 -339.635783)
			(xy 316.022457 -339.586206) (xy 316.007102 -339.533911) (xy 315.999346 -339.479963) (xy 315.99886 -339.452712)
			(xy 262.752078 -339.452712) (xy 262.752078 -348.37116) (xy 271.357598 -348.37116) (xy 271.358065 -348.343248)
			(xy 271.366205 -348.288021) (xy 271.382307 -348.23457) (xy 271.406025 -348.184036) (xy 271.436855 -348.137497)
			(xy 271.455134 -348.116398) (xy 271.461484 -348.109286) (xy 271.468088 -348.092014) (xy 271.468088 -348.004892)
			(xy 271.461484 -347.98762) (xy 271.455134 -347.980508) (xy 271.436828 -347.959432) (xy 271.406007 -347.912886)
			(xy 271.382298 -347.862345) (xy 271.366208 -347.808889) (xy 271.35808 -347.753659) (xy 271.357598 -347.725746)
			(xy 271.358084 -347.698495) (xy 271.36584 -347.644547) (xy 271.381195 -347.592252) (xy 271.403837 -347.542675)
			(xy 271.433303 -347.496825) (xy 271.468994 -347.455634) (xy 271.510185 -347.419943) (xy 271.556035 -347.390477)
			(xy 271.605612 -347.367835) (xy 271.657907 -347.35248) (xy 271.711855 -347.344724) (xy 271.766357 -347.344724)
			(xy 271.820305 -347.35248) (xy 271.8726 -347.367835) (xy 271.922177 -347.390477) (xy 271.968027 -347.419943)
			(xy 272.009218 -347.455634) (xy 272.044909 -347.496825) (xy 272.074375 -347.542675) (xy 272.097017 -347.592252)
			(xy 272.112372 -347.644547) (xy 272.120128 -347.698495) (xy 272.120614 -347.725746) (xy 272.120148 -347.753658)
			(xy 272.112007 -347.808885) (xy 272.095905 -347.862336) (xy 272.072186 -347.91287) (xy 272.041357 -347.959409)
			(xy 272.023078 -347.980508) (xy 272.016728 -347.98762) (xy 272.010124 -348.004892) (xy 272.010124 -348.092014)
			(xy 272.016728 -348.109286) (xy 272.023078 -348.116398) (xy 272.041326 -348.137523) (xy 272.072158 -348.184054)
			(xy 272.09588 -348.234582) (xy 272.111983 -348.288028) (xy 272.120125 -348.34325) (xy 272.120614 -348.37116)
			(xy 272.120128 -348.398411) (xy 272.112372 -348.452359) (xy 272.097017 -348.504654) (xy 272.074375 -348.554231)
			(xy 272.044909 -348.600081) (xy 272.009218 -348.641272) (xy 271.968027 -348.676963) (xy 271.924867 -348.7047)
			(xy 275.739821 -348.7047) (xy 275.743989 -348.649082) (xy 275.7564 -348.594706) (xy 275.776776 -348.542788)
			(xy 275.804662 -348.494485) (xy 275.839436 -348.450879) (xy 275.880321 -348.412942) (xy 275.926403 -348.381523)
			(xy 275.976653 -348.357322) (xy 276.029948 -348.340881) (xy 276.085099 -348.332566) (xy 276.112986 -348.332044)
			(xy 276.139407 -348.332523) (xy 276.191721 -348.33997) (xy 276.242459 -348.354731) (xy 276.290603 -348.376509)
			(xy 276.33519 -348.404869) (xy 276.355556 -348.421706) (xy 276.362414 -348.427802) (xy 276.379432 -348.433898)
			(xy 276.46376 -348.433898) (xy 276.480778 -348.427802) (xy 276.487636 -348.421706) (xy 276.508002 -348.404867)
			(xy 276.552588 -348.376502) (xy 276.600732 -348.354715) (xy 276.651469 -348.339944) (xy 276.703784 -348.332484)
			(xy 276.756628 -348.332484) (xy 276.808943 -348.339944) (xy 276.85968 -348.354715) (xy 276.907824 -348.376502)
			(xy 276.95241 -348.404867) (xy 276.972776 -348.421706) (xy 276.979634 -348.427802) (xy 276.996652 -348.433898)
			(xy 277.08098 -348.433898) (xy 277.097998 -348.427802) (xy 277.104856 -348.421706) (xy 277.128853 -348.401962)
			(xy 277.182096 -348.369922) (xy 277.210774 -348.357952) (xy 277.221188 -348.353888) (xy 277.236428 -348.33814)
			(xy 277.269448 -348.244668) (xy 277.267416 -348.223078) (xy 277.261828 -348.213426) (xy 277.250031 -348.191825)
			(xy 277.231486 -348.146234) (xy 277.218961 -348.098636) (xy 277.212665 -348.049822) (xy 277.212298 -348.025212)
			(xy 277.212773 -347.997638) (xy 277.220723 -347.943065) (xy 277.236447 -347.890206) (xy 277.259615 -347.84016)
			(xy 277.289746 -347.79397) (xy 277.326212 -347.752598) (xy 277.346918 -347.734382) (xy 277.355043 -347.726785)
			(xy 277.364393 -347.706629) (xy 277.364952 -347.69552) (xy 277.364952 -347.618304) (xy 277.364413 -347.60719)
			(xy 277.355056 -347.587031) (xy 277.346918 -347.579442) (xy 277.326228 -347.561208) (xy 277.289755 -347.519845)
			(xy 277.25962 -347.47366) (xy 277.23645 -347.423616) (xy 277.22073 -347.370757) (xy 277.212786 -347.316185)
			(xy 277.212298 -347.288612) (xy 277.212784 -347.261361) (xy 277.22054 -347.207413) (xy 277.235895 -347.155118)
			(xy 277.258537 -347.105541) (xy 277.288003 -347.059691) (xy 277.323694 -347.0185) (xy 277.364885 -346.982809)
			(xy 277.410735 -346.953343) (xy 277.460312 -346.930701) (xy 277.512607 -346.915346) (xy 277.566555 -346.90759)
			(xy 277.621057 -346.90759) (xy 277.675005 -346.915346) (xy 277.7273 -346.930701) (xy 277.776877 -346.953343)
			(xy 277.822727 -346.982809) (xy 277.863918 -347.0185) (xy 277.899609 -347.059691) (xy 277.929075 -347.105541)
			(xy 277.951717 -347.155118) (xy 277.967072 -347.207413) (xy 277.974828 -347.261361) (xy 277.975314 -347.288612)
			(xy 277.974783 -347.316184) (xy 277.966843 -347.370754) (xy 277.951131 -347.423612) (xy 277.927973 -347.473658)
			(xy 277.897852 -347.51985) (xy 277.861396 -347.561224) (xy 277.840694 -347.579442) (xy 277.83256 -347.587031)
			(xy 277.823215 -347.607193) (xy 277.82266 -347.618304) (xy 277.82266 -347.69552) (xy 277.823182 -347.706636)
			(xy 277.832551 -347.726795) (xy 277.840694 -347.734382) (xy 277.861398 -347.7526) (xy 277.89787 -347.793967)
			(xy 277.928003 -347.840156) (xy 277.95117 -347.890202) (xy 277.966887 -347.943064) (xy 277.974828 -347.997638)
			(xy 277.975314 -348.025212) (xy 277.974776 -348.054113) (xy 277.966042 -348.111252) (xy 277.948791 -348.16642)
			(xy 277.923417 -348.218355) (xy 277.890501 -348.265869) (xy 277.850796 -348.307877) (xy 277.80521 -348.343415)
			(xy 277.755699 -348.37116) (xy 279.637998 -348.37116) (xy 279.638465 -348.343248) (xy 279.646605 -348.288021)
			(xy 279.662707 -348.23457) (xy 279.686425 -348.184036) (xy 279.717255 -348.137497) (xy 279.735534 -348.116398)
			(xy 279.741884 -348.109286) (xy 279.748488 -348.092014) (xy 279.748488 -348.004892) (xy 279.741884 -347.98762)
			(xy 279.735534 -347.980508) (xy 279.717228 -347.959432) (xy 279.686407 -347.912886) (xy 279.662698 -347.862345)
			(xy 279.646608 -347.808889) (xy 279.63848 -347.753659) (xy 279.637998 -347.725746) (xy 279.638484 -347.698495)
			(xy 279.64624 -347.644547) (xy 279.661595 -347.592252) (xy 279.684237 -347.542675) (xy 279.713703 -347.496825)
			(xy 279.749394 -347.455634) (xy 279.790585 -347.419943) (xy 279.836435 -347.390477) (xy 279.886012 -347.367835)
			(xy 279.938307 -347.35248) (xy 279.992255 -347.344724) (xy 280.046757 -347.344724) (xy 280.100705 -347.35248)
			(xy 280.153 -347.367835) (xy 280.202577 -347.390477) (xy 280.248427 -347.419943) (xy 280.289618 -347.455634)
			(xy 280.325309 -347.496825) (xy 280.354775 -347.542675) (xy 280.377417 -347.592252) (xy 280.392772 -347.644547)
			(xy 280.400528 -347.698495) (xy 280.401014 -347.725746) (xy 280.400548 -347.753658) (xy 280.392407 -347.808885)
			(xy 280.376305 -347.862336) (xy 280.352586 -347.91287) (xy 280.321757 -347.959409) (xy 280.303478 -347.980508)
			(xy 280.297128 -347.98762) (xy 280.290524 -348.004892) (xy 280.290524 -348.092014) (xy 280.297128 -348.109286)
			(xy 280.303478 -348.116398) (xy 280.321726 -348.137523) (xy 280.352558 -348.184054) (xy 280.37628 -348.234582)
			(xy 280.392383 -348.288028) (xy 280.400525 -348.34325) (xy 280.401014 -348.37116) (xy 280.400528 -348.398411)
			(xy 280.392772 -348.452359) (xy 280.377417 -348.504654) (xy 280.354775 -348.554231) (xy 280.325309 -348.600081)
			(xy 280.289618 -348.641272) (xy 280.248427 -348.676963) (xy 280.205267 -348.7047) (xy 284.020221 -348.7047)
			(xy 284.024389 -348.649082) (xy 284.0368 -348.594706) (xy 284.057176 -348.542788) (xy 284.085062 -348.494485)
			(xy 284.119836 -348.450879) (xy 284.160721 -348.412942) (xy 284.206803 -348.381523) (xy 284.257053 -348.357322)
			(xy 284.310348 -348.340881) (xy 284.365499 -348.332566) (xy 284.393386 -348.332044) (xy 284.419807 -348.332523)
			(xy 284.472121 -348.33997) (xy 284.522859 -348.354731) (xy 284.571003 -348.376509) (xy 284.61559 -348.404869)
			(xy 284.635956 -348.421706) (xy 284.642814 -348.427802) (xy 284.659832 -348.433898) (xy 284.74416 -348.433898)
			(xy 284.761178 -348.427802) (xy 284.768036 -348.421706) (xy 284.788402 -348.404867) (xy 284.832988 -348.376502)
			(xy 284.881132 -348.354715) (xy 284.931869 -348.339944) (xy 284.984184 -348.332484) (xy 285.037028 -348.332484)
			(xy 285.089343 -348.339944) (xy 285.14008 -348.354715) (xy 285.188224 -348.376502) (xy 285.23281 -348.404867)
			(xy 285.253176 -348.421706) (xy 285.260034 -348.427802) (xy 285.277052 -348.433898) (xy 285.36138 -348.433898)
			(xy 285.378398 -348.427802) (xy 285.385256 -348.421706) (xy 285.403098 -348.4069) (xy 285.441797 -348.381362)
			(xy 285.483363 -348.360819) (xy 285.505144 -348.352872) (xy 285.516574 -348.348808) (xy 285.533084 -348.332044)
			(xy 285.565596 -348.232222) (xy 285.562294 -348.208854) (xy 285.555436 -348.198948) (xy 285.539474 -348.174897)
			(xy 285.514145 -348.123033) (xy 285.496913 -348.067945) (xy 285.488173 -348.010891) (xy 285.487618 -347.982032)
			(xy 285.488099 -347.954458) (xy 285.496048 -347.899886) (xy 285.511769 -347.847026) (xy 285.534936 -347.79698)
			(xy 285.565066 -347.75079) (xy 285.601532 -347.709418) (xy 285.622238 -347.691202) (xy 285.630357 -347.6836)
			(xy 285.63971 -347.663448) (xy 285.640272 -347.65234) (xy 285.640272 -347.575124) (xy 285.639716 -347.564013)
			(xy 285.63037 -347.543853) (xy 285.622238 -347.536262) (xy 285.601513 -347.518066) (xy 285.565042 -347.476695)
			(xy 285.534911 -347.430502) (xy 285.511747 -347.380451) (xy 285.496034 -347.327585) (xy 285.4881 -347.273008)
			(xy 285.487618 -347.245432) (xy 285.488104 -347.218181) (xy 285.49586 -347.164233) (xy 285.511215 -347.111938)
			(xy 285.533857 -347.062361) (xy 285.563323 -347.016511) (xy 285.599014 -346.97532) (xy 285.640205 -346.939629)
			(xy 285.686055 -346.910163) (xy 285.735632 -346.887521) (xy 285.787927 -346.872166) (xy 285.841875 -346.86441)
			(xy 285.896377 -346.86441) (xy 285.950325 -346.872166) (xy 286.00262 -346.887521) (xy 286.052197 -346.910163)
			(xy 286.098047 -346.939629) (xy 286.139238 -346.97532) (xy 286.174929 -347.016511) (xy 286.204395 -347.062361)
			(xy 286.227037 -347.111938) (xy 286.242392 -347.164233) (xy 286.250148 -347.218181) (xy 286.250634 -347.245432)
			(xy 286.250145 -347.273006) (xy 286.2422 -347.327579) (xy 286.226481 -347.380439) (xy 286.203316 -347.430486)
			(xy 286.173186 -347.476676) (xy 286.136721 -347.518047) (xy 286.116014 -347.536262) (xy 286.107919 -347.543886)
			(xy 286.098551 -347.564021) (xy 286.09798 -347.575124) (xy 286.09798 -347.65234) (xy 286.098484 -347.663458)
			(xy 286.107865 -347.683618) (xy 286.116014 -347.691202) (xy 286.136732 -347.709405) (xy 286.173201 -347.750776)
			(xy 286.203332 -347.796968) (xy 286.226497 -347.847017) (xy 286.242212 -347.899881) (xy 286.25015 -347.954457)
			(xy 286.250634 -347.982032) (xy 286.250151 -348.008525) (xy 286.242802 -348.061) (xy 286.228264 -348.111954)
			(xy 286.206817 -348.160406) (xy 286.178873 -348.205426) (xy 286.144969 -348.246146) (xy 286.105757 -348.281785)
			(xy 286.061993 -348.311655) (xy 286.014516 -348.335184) (xy 285.989522 -348.343982) (xy 285.978092 -348.347792)
			(xy 285.961328 -348.364556) (xy 285.959076 -348.37116) (xy 287.943798 -348.37116) (xy 287.944265 -348.343248)
			(xy 287.952405 -348.288021) (xy 287.968507 -348.23457) (xy 287.992225 -348.184036) (xy 288.023055 -348.137497)
			(xy 288.041334 -348.116398) (xy 288.047684 -348.109286) (xy 288.054288 -348.092014) (xy 288.054288 -348.004892)
			(xy 288.047684 -347.98762) (xy 288.041334 -347.980508) (xy 288.023028 -347.959432) (xy 287.992207 -347.912886)
			(xy 287.968498 -347.862345) (xy 287.952408 -347.808889) (xy 287.94428 -347.753659) (xy 287.943798 -347.725746)
			(xy 287.944284 -347.698495) (xy 287.95204 -347.644547) (xy 287.967395 -347.592252) (xy 287.990037 -347.542675)
			(xy 288.019503 -347.496825) (xy 288.055194 -347.455634) (xy 288.096385 -347.419943) (xy 288.142235 -347.390477)
			(xy 288.191812 -347.367835) (xy 288.244107 -347.35248) (xy 288.298055 -347.344724) (xy 288.352557 -347.344724)
			(xy 288.406505 -347.35248) (xy 288.4588 -347.367835) (xy 288.508377 -347.390477) (xy 288.554227 -347.419943)
			(xy 288.595418 -347.455634) (xy 288.631109 -347.496825) (xy 288.660575 -347.542675) (xy 288.683217 -347.592252)
			(xy 288.698572 -347.644547) (xy 288.706328 -347.698495) (xy 288.706814 -347.725746) (xy 288.706348 -347.753658)
			(xy 288.698207 -347.808885) (xy 288.682105 -347.862336) (xy 288.658386 -347.91287) (xy 288.627557 -347.959409)
			(xy 288.609278 -347.980508) (xy 288.602928 -347.98762) (xy 288.596324 -348.004892) (xy 288.596324 -348.092014)
			(xy 288.602928 -348.109286) (xy 288.609278 -348.116398) (xy 288.627526 -348.137523) (xy 288.658358 -348.184054)
			(xy 288.68208 -348.234582) (xy 288.698183 -348.288028) (xy 288.706325 -348.34325) (xy 288.706814 -348.37116)
			(xy 288.706328 -348.398411) (xy 288.698572 -348.452359) (xy 288.683217 -348.504654) (xy 288.660575 -348.554231)
			(xy 288.631109 -348.600081) (xy 288.595418 -348.641272) (xy 288.554227 -348.676963) (xy 288.511067 -348.7047)
			(xy 292.326021 -348.7047) (xy 292.330189 -348.649082) (xy 292.3426 -348.594706) (xy 292.362976 -348.542788)
			(xy 292.390862 -348.494485) (xy 292.425636 -348.450879) (xy 292.466521 -348.412942) (xy 292.512603 -348.381523)
			(xy 292.562853 -348.357322) (xy 292.616148 -348.340881) (xy 292.671299 -348.332566) (xy 292.699186 -348.332044)
			(xy 292.725607 -348.332523) (xy 292.777921 -348.33997) (xy 292.828659 -348.354731) (xy 292.876803 -348.376509)
			(xy 292.92139 -348.404869) (xy 292.941756 -348.421706) (xy 292.948614 -348.427802) (xy 292.965632 -348.433898)
			(xy 293.04996 -348.433898) (xy 293.066978 -348.427802) (xy 293.073836 -348.421706) (xy 293.094202 -348.404867)
			(xy 293.138788 -348.376502) (xy 293.186932 -348.354715) (xy 293.237669 -348.339944) (xy 293.289984 -348.332484)
			(xy 293.342828 -348.332484) (xy 293.395143 -348.339944) (xy 293.44588 -348.354715) (xy 293.494024 -348.376502)
			(xy 293.53861 -348.404867) (xy 293.558976 -348.421706) (xy 293.565834 -348.427802) (xy 293.582852 -348.433898)
			(xy 293.66718 -348.433898) (xy 293.684198 -348.427802) (xy 293.691056 -348.421706) (xy 293.716613 -348.400749)
			(xy 293.77359 -348.367271) (xy 293.80434 -348.355158) (xy 293.81577 -348.351094) (xy 293.83228 -348.33306)
			(xy 293.860982 -348.23019) (xy 293.856156 -348.206314) (xy 293.848536 -348.196662) (xy 293.832909 -348.17632)
			(xy 293.806631 -348.132266) (xy 293.786484 -348.085093) (xy 293.772831 -348.035647) (xy 293.765917 -347.984819)
			(xy 293.765478 -347.959172) (xy 293.766001 -347.9316) (xy 293.773943 -347.87703) (xy 293.789657 -347.824171)
			(xy 293.812816 -347.774125) (xy 293.842938 -347.727934) (xy 293.879396 -347.68656) (xy 293.900098 -347.668342)
			(xy 293.908193 -347.660718) (xy 293.91756 -347.640583) (xy 293.918132 -347.62948) (xy 293.918132 -347.552264)
			(xy 293.917622 -347.541147) (xy 293.908245 -347.520987) (xy 293.900098 -347.513402) (xy 293.879384 -347.495194)
			(xy 293.842914 -347.453824) (xy 293.812782 -347.407634) (xy 293.789617 -347.357585) (xy 293.773901 -347.304722)
			(xy 293.765963 -347.250147) (xy 293.765478 -347.222572) (xy 293.765964 -347.195321) (xy 293.77372 -347.141373)
			(xy 293.789075 -347.089078) (xy 293.811717 -347.039501) (xy 293.841183 -346.993651) (xy 293.876874 -346.95246)
			(xy 293.918065 -346.916769) (xy 293.963915 -346.887303) (xy 294.013492 -346.864661) (xy 294.065787 -346.849306)
			(xy 294.119735 -346.84155) (xy 294.174237 -346.84155) (xy 294.228185 -346.849306) (xy 294.28048 -346.864661)
			(xy 294.330057 -346.887303) (xy 294.375907 -346.916769) (xy 294.417098 -346.95246) (xy 294.452789 -346.993651)
			(xy 294.482255 -347.039501) (xy 294.504897 -347.089078) (xy 294.520252 -347.141373) (xy 294.528008 -347.195321)
			(xy 294.528494 -347.222572) (xy 294.528011 -347.250146) (xy 294.520062 -347.304718) (xy 294.504341 -347.357578)
			(xy 294.481174 -347.407624) (xy 294.451045 -347.453814) (xy 294.41458 -347.495186) (xy 294.393874 -347.513402)
			(xy 294.385755 -347.521004) (xy 294.376402 -347.541156) (xy 294.37584 -347.552264) (xy 294.37584 -347.62948)
			(xy 294.37639 -347.640592) (xy 294.38574 -347.660752) (xy 294.393874 -347.668342) (xy 294.414555 -347.686586)
			(xy 294.451029 -347.727947) (xy 294.481165 -347.77413) (xy 294.504337 -347.824172) (xy 294.520059 -347.877029)
			(xy 294.528005 -347.931599) (xy 294.528494 -347.959172) (xy 294.527984 -347.988496) (xy 294.518985 -348.046451)
			(xy 294.501226 -348.102346) (xy 294.475124 -348.154867) (xy 294.441295 -348.202776) (xy 294.400534 -348.244945)
			(xy 294.353802 -348.280382) (xy 294.302198 -348.308253) (xy 294.274748 -348.318582) (xy 294.263064 -348.3229)
			(xy 294.2463 -348.340426) (xy 294.237323 -348.37116) (xy 296.300398 -348.37116) (xy 296.300865 -348.343248)
			(xy 296.309005 -348.288021) (xy 296.325107 -348.23457) (xy 296.348825 -348.184036) (xy 296.379655 -348.137497)
			(xy 296.397934 -348.116398) (xy 296.404284 -348.109286) (xy 296.410888 -348.092014) (xy 296.410888 -348.004892)
			(xy 296.404284 -347.98762) (xy 296.397934 -347.980508) (xy 296.379628 -347.959432) (xy 296.348807 -347.912886)
			(xy 296.325098 -347.862345) (xy 296.309008 -347.808889) (xy 296.30088 -347.753659) (xy 296.300398 -347.725746)
			(xy 296.300884 -347.698495) (xy 296.30864 -347.644547) (xy 296.323995 -347.592252) (xy 296.346637 -347.542675)
			(xy 296.376103 -347.496825) (xy 296.411794 -347.455634) (xy 296.452985 -347.419943) (xy 296.498835 -347.390477)
			(xy 296.548412 -347.367835) (xy 296.600707 -347.35248) (xy 296.654655 -347.344724) (xy 296.709157 -347.344724)
			(xy 296.763105 -347.35248) (xy 296.8154 -347.367835) (xy 296.864977 -347.390477) (xy 296.910827 -347.419943)
			(xy 296.952018 -347.455634) (xy 296.987709 -347.496825) (xy 297.017175 -347.542675) (xy 297.039817 -347.592252)
			(xy 297.055172 -347.644547) (xy 297.062928 -347.698495) (xy 297.063414 -347.725746) (xy 297.062948 -347.753658)
			(xy 297.054807 -347.808885) (xy 297.038705 -347.862336) (xy 297.014986 -347.91287) (xy 296.984157 -347.959409)
			(xy 296.965878 -347.980508) (xy 296.959528 -347.98762) (xy 296.952924 -348.004892) (xy 296.952924 -348.092014)
			(xy 296.959528 -348.109286) (xy 296.965878 -348.116398) (xy 296.984126 -348.137523) (xy 297.014958 -348.184054)
			(xy 297.03868 -348.234582) (xy 297.054783 -348.288028) (xy 297.062925 -348.34325) (xy 297.063414 -348.37116)
			(xy 297.062928 -348.398411) (xy 297.055172 -348.452359) (xy 297.039817 -348.504654) (xy 297.017175 -348.554231)
			(xy 296.987709 -348.600081) (xy 296.952018 -348.641272) (xy 296.910827 -348.676963) (xy 296.867667 -348.7047)
			(xy 300.682621 -348.7047) (xy 300.686789 -348.649082) (xy 300.6992 -348.594706) (xy 300.719576 -348.542788)
			(xy 300.747462 -348.494485) (xy 300.782236 -348.450879) (xy 300.823121 -348.412942) (xy 300.869203 -348.381523)
			(xy 300.919453 -348.357322) (xy 300.972748 -348.340881) (xy 301.027899 -348.332566) (xy 301.055786 -348.332044)
			(xy 301.082207 -348.332523) (xy 301.134521 -348.33997) (xy 301.185259 -348.354731) (xy 301.233403 -348.376509)
			(xy 301.27799 -348.404869) (xy 301.298356 -348.421706) (xy 301.305214 -348.427802) (xy 301.322232 -348.433898)
			(xy 301.40656 -348.433898) (xy 301.423578 -348.427802) (xy 301.430436 -348.421706) (xy 301.450802 -348.404867)
			(xy 301.495388 -348.376502) (xy 301.543532 -348.354715) (xy 301.594269 -348.339944) (xy 301.646584 -348.332484)
			(xy 301.699428 -348.332484) (xy 301.751743 -348.339944) (xy 301.80248 -348.354715) (xy 301.850624 -348.376502)
			(xy 301.89521 -348.404867) (xy 301.915576 -348.421706) (xy 301.922434 -348.427802) (xy 301.939452 -348.433898)
			(xy 302.02378 -348.433898) (xy 302.040798 -348.427802) (xy 302.047656 -348.421706) (xy 302.072125 -348.40159)
			(xy 302.12653 -348.369155) (xy 302.15586 -348.35719) (xy 302.166782 -348.352872) (xy 302.182276 -348.336616)
			(xy 302.214026 -348.239842) (xy 302.211232 -348.21749) (xy 302.204882 -348.207584) (xy 302.190712 -348.184479)
			(xy 302.168299 -348.13513) (xy 302.153099 -348.083105) (xy 302.145418 -348.029452) (xy 302.144938 -348.002352)
			(xy 302.145426 -347.974778) (xy 302.153372 -347.920206) (xy 302.169092 -347.867346) (xy 302.192258 -347.817299)
			(xy 302.222387 -347.771109) (xy 302.258852 -347.729738) (xy 302.279558 -347.711522) (xy 302.287671 -347.703915)
			(xy 302.297026 -347.683767) (xy 302.297592 -347.67266) (xy 302.297592 -347.595444) (xy 302.297018 -347.584335)
			(xy 302.287684 -347.564176) (xy 302.279558 -347.556582) (xy 302.258827 -347.538393) (xy 302.22236 -347.497019)
			(xy 302.192231 -347.450824) (xy 302.169069 -347.400772) (xy 302.153357 -347.347906) (xy 302.145421 -347.293328)
			(xy 302.144938 -347.265752) (xy 302.145424 -347.238501) (xy 302.15318 -347.184553) (xy 302.168535 -347.132258)
			(xy 302.191177 -347.082681) (xy 302.220643 -347.036831) (xy 302.256334 -346.99564) (xy 302.297525 -346.959949)
			(xy 302.343375 -346.930483) (xy 302.392952 -346.907841) (xy 302.445247 -346.892486) (xy 302.499195 -346.88473)
			(xy 302.553697 -346.88473) (xy 302.607645 -346.892486) (xy 302.65994 -346.907841) (xy 302.709517 -346.930483)
			(xy 302.755367 -346.959949) (xy 302.796558 -346.99564) (xy 302.832249 -347.036831) (xy 302.861715 -347.082681)
			(xy 302.884357 -347.132258) (xy 302.899712 -347.184553) (xy 302.907468 -347.238501) (xy 302.907954 -347.265752)
			(xy 302.907471 -347.293326) (xy 302.899525 -347.347899) (xy 302.883804 -347.400759) (xy 302.860637 -347.450806)
			(xy 302.830507 -347.496995) (xy 302.794041 -347.538367) (xy 302.773334 -347.556582) (xy 302.765218 -347.564186)
			(xy 302.755865 -347.584337) (xy 302.7553 -347.595444) (xy 302.7553 -347.67266) (xy 302.755874 -347.683769)
			(xy 302.765208 -347.703928) (xy 302.773334 -347.711522) (xy 302.794066 -347.72971) (xy 302.830533 -347.771085)
			(xy 302.860662 -347.81728) (xy 302.883824 -347.867332) (xy 302.899536 -347.920198) (xy 302.907471 -347.974776)
			(xy 302.907954 -348.002352) (xy 302.907398 -348.031389) (xy 302.898589 -348.088791) (xy 302.881184 -348.144195)
			(xy 302.855582 -348.196322) (xy 302.822378 -348.243967) (xy 302.782336 -348.28603) (xy 302.736382 -348.321538)
			(xy 302.685578 -348.349673) (xy 302.658526 -348.360238) (xy 302.647604 -348.364302) (xy 302.640855 -348.37116)
			(xy 304.631598 -348.37116) (xy 304.632065 -348.343248) (xy 304.640205 -348.288021) (xy 304.656307 -348.23457)
			(xy 304.680025 -348.184036) (xy 304.710855 -348.137497) (xy 304.729134 -348.116398) (xy 304.735484 -348.109286)
			(xy 304.742088 -348.092014) (xy 304.742088 -348.004892) (xy 304.735484 -347.98762) (xy 304.729134 -347.980508)
			(xy 304.710828 -347.959432) (xy 304.680007 -347.912886) (xy 304.656298 -347.862345) (xy 304.640208 -347.808889)
			(xy 304.63208 -347.753659) (xy 304.631598 -347.725746) (xy 304.632084 -347.698495) (xy 304.63984 -347.644547)
			(xy 304.655195 -347.592252) (xy 304.677837 -347.542675) (xy 304.707303 -347.496825) (xy 304.742994 -347.455634)
			(xy 304.784185 -347.419943) (xy 304.830035 -347.390477) (xy 304.879612 -347.367835) (xy 304.931907 -347.35248)
			(xy 304.985855 -347.344724) (xy 305.040357 -347.344724) (xy 305.094305 -347.35248) (xy 305.1466 -347.367835)
			(xy 305.196177 -347.390477) (xy 305.242027 -347.419943) (xy 305.283218 -347.455634) (xy 305.318909 -347.496825)
			(xy 305.348375 -347.542675) (xy 305.371017 -347.592252) (xy 305.386372 -347.644547) (xy 305.394128 -347.698495)
			(xy 305.394614 -347.725746) (xy 305.394148 -347.753658) (xy 305.386007 -347.808885) (xy 305.369905 -347.862336)
			(xy 305.346186 -347.91287) (xy 305.315357 -347.959409) (xy 305.297078 -347.980508) (xy 305.290728 -347.98762)
			(xy 305.284124 -348.004892) (xy 305.284124 -348.092014) (xy 305.290728 -348.109286) (xy 305.297078 -348.116398)
			(xy 305.315326 -348.137523) (xy 305.346158 -348.184054) (xy 305.36988 -348.234582) (xy 305.385983 -348.288028)
			(xy 305.394125 -348.34325) (xy 305.394614 -348.37116) (xy 305.394128 -348.398411) (xy 305.386372 -348.452359)
			(xy 305.371017 -348.504654) (xy 305.348375 -348.554231) (xy 305.318909 -348.600081) (xy 305.283218 -348.641272)
			(xy 305.242027 -348.676963) (xy 305.198867 -348.7047) (xy 309.013821 -348.7047) (xy 309.017989 -348.649082)
			(xy 309.0304 -348.594706) (xy 309.050776 -348.542788) (xy 309.078662 -348.494485) (xy 309.113436 -348.450879)
			(xy 309.154321 -348.412942) (xy 309.200403 -348.381523) (xy 309.250653 -348.357322) (xy 309.303948 -348.340881)
			(xy 309.359099 -348.332566) (xy 309.386986 -348.332044) (xy 309.413407 -348.332523) (xy 309.465721 -348.33997)
			(xy 309.516459 -348.354731) (xy 309.564603 -348.376509) (xy 309.60919 -348.404869) (xy 309.629556 -348.421706)
			(xy 309.636414 -348.427802) (xy 309.653432 -348.433898) (xy 309.73776 -348.433898) (xy 309.754778 -348.427802)
			(xy 309.761636 -348.421706) (xy 309.782002 -348.404867) (xy 309.826588 -348.376502) (xy 309.874732 -348.354715)
			(xy 309.925469 -348.339944) (xy 309.977784 -348.332484) (xy 310.030628 -348.332484) (xy 310.082943 -348.339944)
			(xy 310.13368 -348.354715) (xy 310.181824 -348.376502) (xy 310.22641 -348.404867) (xy 310.246776 -348.421706)
			(xy 310.253634 -348.427802) (xy 310.270652 -348.433898) (xy 310.35498 -348.433898) (xy 310.371998 -348.427802)
			(xy 310.378856 -348.421706) (xy 310.404711 -348.400478) (xy 310.462474 -348.366746) (xy 310.493664 -348.35465)
			(xy 310.504332 -348.35084) (xy 310.520334 -348.33433) (xy 310.553608 -348.23781) (xy 310.550814 -348.21495)
			(xy 310.544718 -348.205298) (xy 310.530854 -348.182405) (xy 310.509015 -348.133543) (xy 310.494215 -348.082109)
			(xy 310.486745 -348.029112) (xy 310.486298 -348.002352) (xy 310.4868 -347.974779) (xy 310.494745 -347.920208)
			(xy 310.510463 -347.867348) (xy 310.533626 -347.817302) (xy 310.563752 -347.771112) (xy 310.600214 -347.729739)
			(xy 310.620918 -347.711522) (xy 310.629025 -347.703909) (xy 310.638385 -347.683765) (xy 310.638952 -347.67266)
			(xy 310.638952 -347.595444) (xy 310.638391 -347.584333) (xy 310.629049 -347.564173) (xy 310.620918 -347.556582)
			(xy 310.600199 -347.53838) (xy 310.563728 -347.49701) (xy 310.533597 -347.450818) (xy 310.510432 -347.400768)
			(xy 310.494718 -347.347904) (xy 310.486781 -347.293327) (xy 310.486298 -347.265752) (xy 310.486784 -347.238501)
			(xy 310.49454 -347.184553) (xy 310.509895 -347.132258) (xy 310.532537 -347.082681) (xy 310.562003 -347.036831)
			(xy 310.597694 -346.99564) (xy 310.638885 -346.959949) (xy 310.684735 -346.930483) (xy 310.734312 -346.907841)
			(xy 310.786607 -346.892486) (xy 310.840555 -346.88473) (xy 310.895057 -346.88473) (xy 310.949005 -346.892486)
			(xy 311.0013 -346.907841) (xy 311.050877 -346.930483) (xy 311.096727 -346.959949) (xy 311.137918 -346.99564)
			(xy 311.173609 -347.036831) (xy 311.203075 -347.082681) (xy 311.225717 -347.132258) (xy 311.241072 -347.184553)
			(xy 311.248828 -347.238501) (xy 311.249314 -347.265752) (xy 311.24881 -347.293325) (xy 311.240865 -347.347896)
			(xy 311.225147 -347.400755) (xy 311.201984 -347.450801) (xy 311.171859 -347.496992) (xy 311.135398 -347.538365)
			(xy 311.114694 -347.556582) (xy 311.106587 -347.564195) (xy 311.097227 -347.584339) (xy 311.09666 -347.595444)
			(xy 311.09666 -347.67266) (xy 311.097215 -347.683772) (xy 311.106561 -347.703932) (xy 311.114694 -347.711522)
			(xy 311.135418 -347.729719) (xy 311.171887 -347.771091) (xy 311.202018 -347.817284) (xy 311.225182 -347.867334)
			(xy 311.240895 -347.920199) (xy 311.248831 -347.974776) (xy 311.249314 -348.002352) (xy 311.248909 -348.028552)
			(xy 311.241751 -348.08046) (xy 311.227549 -348.130898) (xy 311.206572 -348.178915) (xy 311.179215 -348.223605)
			(xy 311.145994 -348.264127) (xy 311.107534 -348.299715) (xy 311.064562 -348.3297) (xy 311.017888 -348.353515)
			(xy 310.993282 -348.362524) (xy 310.98236 -348.366334) (xy 310.966104 -348.38259) (xy 310.93156 -348.478602)
			(xy 310.933846 -348.501462) (xy 310.939942 -348.511368) (xy 310.95275 -348.533323) (xy 310.972985 -348.579949)
			(xy 310.98669 -348.628894) (xy 310.993609 -348.679248) (xy 310.994044 -348.704662) (xy 310.993531 -348.731278)
			(xy 310.98596 -348.783968) (xy 310.970968 -348.835044) (xy 310.94886 -348.883467) (xy 310.920085 -348.928251)
			(xy 310.885229 -348.968484) (xy 310.845002 -349.003346) (xy 310.800224 -349.032129) (xy 310.751805 -349.054246)
			(xy 310.700731 -349.069247) (xy 310.648042 -349.076826) (xy 310.621426 -349.07728) (xy 310.595006 -349.076788)
			(xy 310.542692 -349.069344) (xy 310.491955 -349.054585) (xy 310.44381 -349.03281) (xy 310.399223 -349.004453)
			(xy 310.378856 -348.987618) (xy 310.371998 -348.981522) (xy 310.35498 -348.975426) (xy 310.270652 -348.975426)
			(xy 310.253634 -348.981522) (xy 310.246776 -348.987618) (xy 310.22641 -349.004457) (xy 310.181824 -349.032822)
			(xy 310.13368 -349.054609) (xy 310.082943 -349.06938) (xy 310.030628 -349.07684) (xy 309.977784 -349.07684)
			(xy 309.925469 -349.06938) (xy 309.874732 -349.054609) (xy 309.826588 -349.032822) (xy 309.782002 -349.004457)
			(xy 309.761636 -348.987618) (xy 309.754778 -348.981522) (xy 309.73776 -348.975426) (xy 309.653432 -348.975426)
			(xy 309.636414 -348.981522) (xy 309.629556 -348.987618) (xy 309.609197 -349.004464) (xy 309.564606 -349.032821)
			(xy 309.51646 -349.0546) (xy 309.465722 -349.069365) (xy 309.413408 -349.076822) (xy 309.386986 -349.07728)
			(xy 309.359099 -349.076834) (xy 309.303948 -349.068519) (xy 309.250653 -349.052078) (xy 309.200403 -349.027877)
			(xy 309.154321 -348.996458) (xy 309.113436 -348.958521) (xy 309.078662 -348.914915) (xy 309.050776 -348.866612)
			(xy 309.0304 -348.814694) (xy 309.017989 -348.760318) (xy 309.013821 -348.7047) (xy 305.198867 -348.7047)
			(xy 305.196177 -348.706429) (xy 305.1466 -348.729071) (xy 305.094305 -348.744426) (xy 305.040357 -348.752182)
			(xy 304.985855 -348.752182) (xy 304.931907 -348.744426) (xy 304.879612 -348.729071) (xy 304.830035 -348.706429)
			(xy 304.784185 -348.676963) (xy 304.742994 -348.641272) (xy 304.707303 -348.600081) (xy 304.677837 -348.554231)
			(xy 304.655195 -348.504654) (xy 304.63984 -348.452359) (xy 304.632084 -348.398411) (xy 304.631598 -348.37116)
			(xy 302.640855 -348.37116) (xy 302.631856 -348.380304) (xy 302.598582 -348.47657) (xy 302.601122 -348.498922)
			(xy 302.607218 -348.508828) (xy 302.620417 -348.530985) (xy 302.641215 -348.57818) (xy 302.655303 -348.627793)
			(xy 302.66241 -348.678875) (xy 302.662844 -348.704662) (xy 302.662331 -348.731278) (xy 302.65476 -348.783968)
			(xy 302.639768 -348.835044) (xy 302.61766 -348.883467) (xy 302.588885 -348.928251) (xy 302.554029 -348.968484)
			(xy 302.513802 -349.003346) (xy 302.469024 -349.032129) (xy 302.420605 -349.054246) (xy 302.369531 -349.069247)
			(xy 302.316842 -349.076826) (xy 302.290226 -349.07728) (xy 302.263806 -349.076788) (xy 302.211492 -349.069344)
			(xy 302.160755 -349.054585) (xy 302.11261 -349.03281) (xy 302.068023 -349.004453) (xy 302.047656 -348.987618)
			(xy 302.040798 -348.981522) (xy 302.02378 -348.975426) (xy 301.939452 -348.975426) (xy 301.922434 -348.981522)
			(xy 301.915576 -348.987618) (xy 301.89521 -349.004457) (xy 301.850624 -349.032822) (xy 301.80248 -349.054609)
			(xy 301.751743 -349.06938) (xy 301.699428 -349.07684) (xy 301.646584 -349.07684) (xy 301.594269 -349.06938)
			(xy 301.543532 -349.054609) (xy 301.495388 -349.032822) (xy 301.450802 -349.004457) (xy 301.430436 -348.987618)
			(xy 301.423578 -348.981522) (xy 301.40656 -348.975426) (xy 301.322232 -348.975426) (xy 301.305214 -348.981522)
			(xy 301.298356 -348.987618) (xy 301.277997 -349.004464) (xy 301.233406 -349.032821) (xy 301.18526 -349.0546)
			(xy 301.134522 -349.069365) (xy 301.082208 -349.076822) (xy 301.055786 -349.07728) (xy 301.027899 -349.076834)
			(xy 300.972748 -349.068519) (xy 300.919453 -349.052078) (xy 300.869203 -349.027877) (xy 300.823121 -348.996458)
			(xy 300.782236 -348.958521) (xy 300.747462 -348.914915) (xy 300.719576 -348.866612) (xy 300.6992 -348.814694)
			(xy 300.686789 -348.760318) (xy 300.682621 -348.7047) (xy 296.867667 -348.7047) (xy 296.864977 -348.706429)
			(xy 296.8154 -348.729071) (xy 296.763105 -348.744426) (xy 296.709157 -348.752182) (xy 296.654655 -348.752182)
			(xy 296.600707 -348.744426) (xy 296.548412 -348.729071) (xy 296.498835 -348.706429) (xy 296.452985 -348.676963)
			(xy 296.411794 -348.641272) (xy 296.376103 -348.600081) (xy 296.346637 -348.554231) (xy 296.323995 -348.504654)
			(xy 296.30864 -348.452359) (xy 296.300884 -348.398411) (xy 296.300398 -348.37116) (xy 294.237323 -348.37116)
			(xy 294.216328 -348.443042) (xy 294.2209 -348.466918) (xy 294.228266 -348.47657) (xy 294.246588 -348.501214)
			(xy 294.275706 -348.555277) (xy 294.295563 -348.613383) (xy 294.305622 -348.673959) (xy 294.306244 -348.704662)
			(xy 294.305731 -348.731278) (xy 294.29816 -348.783968) (xy 294.283168 -348.835044) (xy 294.26106 -348.883467)
			(xy 294.232285 -348.928251) (xy 294.197429 -348.968484) (xy 294.157202 -349.003346) (xy 294.112424 -349.032129)
			(xy 294.064005 -349.054246) (xy 294.012931 -349.069247) (xy 293.960242 -349.076826) (xy 293.933626 -349.07728)
			(xy 293.907206 -349.076788) (xy 293.854892 -349.069344) (xy 293.804155 -349.054585) (xy 293.75601 -349.03281)
			(xy 293.711423 -349.004453) (xy 293.691056 -348.987618) (xy 293.684198 -348.981522) (xy 293.66718 -348.975426)
			(xy 293.582852 -348.975426) (xy 293.565834 -348.981522) (xy 293.558976 -348.987618) (xy 293.53861 -349.004457)
			(xy 293.494024 -349.032822) (xy 293.44588 -349.054609) (xy 293.395143 -349.06938) (xy 293.342828 -349.07684)
			(xy 293.289984 -349.07684) (xy 293.237669 -349.06938) (xy 293.186932 -349.054609) (xy 293.138788 -349.032822)
			(xy 293.094202 -349.004457) (xy 293.073836 -348.987618) (xy 293.066978 -348.981522) (xy 293.04996 -348.975426)
			(xy 292.965632 -348.975426) (xy 292.948614 -348.981522) (xy 292.941756 -348.987618) (xy 292.921397 -349.004464)
			(xy 292.876806 -349.032821) (xy 292.82866 -349.0546) (xy 292.777922 -349.069365) (xy 292.725608 -349.076822)
			(xy 292.699186 -349.07728) (xy 292.671299 -349.076834) (xy 292.616148 -349.068519) (xy 292.562853 -349.052078)
			(xy 292.512603 -349.027877) (xy 292.466521 -348.996458) (xy 292.425636 -348.958521) (xy 292.390862 -348.914915)
			(xy 292.362976 -348.866612) (xy 292.3426 -348.814694) (xy 292.330189 -348.760318) (xy 292.326021 -348.7047)
			(xy 288.511067 -348.7047) (xy 288.508377 -348.706429) (xy 288.4588 -348.729071) (xy 288.406505 -348.744426)
			(xy 288.352557 -348.752182) (xy 288.298055 -348.752182) (xy 288.244107 -348.744426) (xy 288.191812 -348.729071)
			(xy 288.142235 -348.706429) (xy 288.096385 -348.676963) (xy 288.055194 -348.641272) (xy 288.019503 -348.600081)
			(xy 287.990037 -348.554231) (xy 287.967395 -348.504654) (xy 287.95204 -348.452359) (xy 287.944284 -348.398411)
			(xy 287.943798 -348.37116) (xy 285.959076 -348.37116) (xy 285.927546 -348.463616) (xy 285.930594 -348.486984)
			(xy 285.937198 -348.497144) (xy 285.952118 -348.520284) (xy 285.975735 -348.570018) (xy 285.991787 -348.622682)
			(xy 285.999927 -348.677134) (xy 286.000444 -348.704662) (xy 285.999931 -348.731278) (xy 285.99236 -348.783968)
			(xy 285.977368 -348.835044) (xy 285.95526 -348.883467) (xy 285.926485 -348.928251) (xy 285.891629 -348.968484)
			(xy 285.851402 -349.003346) (xy 285.806624 -349.032129) (xy 285.758205 -349.054246) (xy 285.707131 -349.069247)
			(xy 285.654442 -349.076826) (xy 285.627826 -349.07728) (xy 285.601406 -349.076788) (xy 285.549092 -349.069344)
			(xy 285.498355 -349.054585) (xy 285.45021 -349.03281) (xy 285.405623 -349.004453) (xy 285.385256 -348.987618)
			(xy 285.378398 -348.981522) (xy 285.36138 -348.975426) (xy 285.277052 -348.975426) (xy 285.260034 -348.981522)
			(xy 285.253176 -348.987618) (xy 285.23281 -349.004457) (xy 285.188224 -349.032822) (xy 285.14008 -349.054609)
			(xy 285.089343 -349.06938) (xy 285.037028 -349.07684) (xy 284.984184 -349.07684) (xy 284.931869 -349.06938)
			(xy 284.881132 -349.054609) (xy 284.832988 -349.032822) (xy 284.788402 -349.004457) (xy 284.768036 -348.987618)
			(xy 284.761178 -348.981522) (xy 284.74416 -348.975426) (xy 284.659832 -348.975426) (xy 284.642814 -348.981522)
			(xy 284.635956 -348.987618) (xy 284.615597 -349.004464) (xy 284.571006 -349.032821) (xy 284.52286 -349.0546)
			(xy 284.472122 -349.069365) (xy 284.419808 -349.076822) (xy 284.393386 -349.07728) (xy 284.365499 -349.076834)
			(xy 284.310348 -349.068519) (xy 284.257053 -349.052078) (xy 284.206803 -349.027877) (xy 284.160721 -348.996458)
			(xy 284.119836 -348.958521) (xy 284.085062 -348.914915) (xy 284.057176 -348.866612) (xy 284.0368 -348.814694)
			(xy 284.024389 -348.760318) (xy 284.020221 -348.7047) (xy 280.205267 -348.7047) (xy 280.202577 -348.706429)
			(xy 280.153 -348.729071) (xy 280.100705 -348.744426) (xy 280.046757 -348.752182) (xy 279.992255 -348.752182)
			(xy 279.938307 -348.744426) (xy 279.886012 -348.729071) (xy 279.836435 -348.706429) (xy 279.790585 -348.676963)
			(xy 279.749394 -348.641272) (xy 279.713703 -348.600081) (xy 279.684237 -348.554231) (xy 279.661595 -348.504654)
			(xy 279.64624 -348.452359) (xy 279.638484 -348.398411) (xy 279.637998 -348.37116) (xy 277.755699 -348.37116)
			(xy 277.754785 -348.371672) (xy 277.727918 -348.382336) (xy 277.717504 -348.3864) (xy 277.70201 -348.40164)
			(xy 277.667466 -348.494604) (xy 277.669244 -348.516194) (xy 277.674578 -348.5261) (xy 277.688923 -348.553648)
			(xy 277.709201 -348.612352) (xy 277.719452 -348.673608) (xy 277.720044 -348.704662) (xy 277.719531 -348.731278)
			(xy 277.71196 -348.783968) (xy 277.696968 -348.835044) (xy 277.67486 -348.883467) (xy 277.646085 -348.928251)
			(xy 277.611229 -348.968484) (xy 277.571002 -349.003346) (xy 277.526224 -349.032129) (xy 277.477805 -349.054246)
			(xy 277.426731 -349.069247) (xy 277.374042 -349.076826) (xy 277.347426 -349.07728) (xy 277.321006 -349.076788)
			(xy 277.268692 -349.069344) (xy 277.217955 -349.054585) (xy 277.16981 -349.03281) (xy 277.125223 -349.004453)
			(xy 277.104856 -348.987618) (xy 277.097998 -348.981522) (xy 277.08098 -348.975426) (xy 276.996652 -348.975426)
			(xy 276.979634 -348.981522) (xy 276.972776 -348.987618) (xy 276.95241 -349.004457) (xy 276.907824 -349.032822)
			(xy 276.85968 -349.054609) (xy 276.808943 -349.06938) (xy 276.756628 -349.07684) (xy 276.703784 -349.07684)
			(xy 276.651469 -349.06938) (xy 276.600732 -349.054609) (xy 276.552588 -349.032822) (xy 276.508002 -349.004457)
			(xy 276.487636 -348.987618) (xy 276.480778 -348.981522) (xy 276.46376 -348.975426) (xy 276.379432 -348.975426)
			(xy 276.362414 -348.981522) (xy 276.355556 -348.987618) (xy 276.335197 -349.004464) (xy 276.290606 -349.032821)
			(xy 276.24246 -349.0546) (xy 276.191722 -349.069365) (xy 276.139408 -349.076822) (xy 276.112986 -349.07728)
			(xy 276.085099 -349.076834) (xy 276.029948 -349.068519) (xy 275.976653 -349.052078) (xy 275.926403 -349.027877)
			(xy 275.880321 -348.996458) (xy 275.839436 -348.958521) (xy 275.804662 -348.914915) (xy 275.776776 -348.866612)
			(xy 275.7564 -348.814694) (xy 275.743989 -348.760318) (xy 275.739821 -348.7047) (xy 271.924867 -348.7047)
			(xy 271.922177 -348.706429) (xy 271.8726 -348.729071) (xy 271.820305 -348.744426) (xy 271.766357 -348.752182)
			(xy 271.711855 -348.752182) (xy 271.657907 -348.744426) (xy 271.605612 -348.729071) (xy 271.556035 -348.706429)
			(xy 271.510185 -348.676963) (xy 271.468994 -348.641272) (xy 271.433303 -348.600081) (xy 271.403837 -348.554231)
			(xy 271.381195 -348.504654) (xy 271.36584 -348.452359) (xy 271.358084 -348.398411) (xy 271.357598 -348.37116)
			(xy 262.752078 -348.37116) (xy 262.752078 -349.602806) (xy 272.31543 -349.602806) (xy 272.319501 -349.547184)
			(xy 272.331627 -349.492747) (xy 272.35155 -349.440656) (xy 272.378846 -349.392021) (xy 272.412932 -349.347878)
			(xy 272.453081 -349.309169) (xy 272.498439 -349.276718) (xy 272.548039 -349.251217) (xy 272.600823 -349.23321)
			(xy 272.655666 -349.22308) (xy 272.7114 -349.221043) (xy 272.766837 -349.227143) (xy 272.820794 -349.241249)
			(xy 272.872123 -349.263061) (xy 272.919729 -349.292115) (xy 272.962597 -349.32779) (xy 272.999814 -349.369327)
			(xy 273.030587 -349.41584) (xy 273.054259 -349.466337) (xy 273.070327 -349.519744) (xy 273.078447 -349.57492)
			(xy 273.078956 -349.602806) (xy 273.078447 -349.630692) (xy 273.070327 -349.685868) (xy 273.054259 -349.739275)
			(xy 273.030587 -349.789772) (xy 272.999814 -349.836285) (xy 272.962597 -349.877822) (xy 272.919729 -349.913497)
			(xy 272.872123 -349.942551) (xy 272.820794 -349.964363) (xy 272.766837 -349.978469) (xy 272.7114 -349.984569)
			(xy 272.655666 -349.982532) (xy 272.600823 -349.972402) (xy 272.548039 -349.954395) (xy 272.498439 -349.928894)
			(xy 272.453081 -349.896443) (xy 272.412932 -349.857734) (xy 272.378846 -349.813591) (xy 272.35155 -349.764956)
			(xy 272.331627 -349.712865) (xy 272.319501 -349.658428) (xy 272.31543 -349.602806) (xy 262.752078 -349.602806)
			(xy 262.752078 -349.65513) (xy 262.752506 -349.665198) (xy 262.760226 -349.683797) (xy 262.767064 -349.691198)
			(xy 263.574022 -350.498156) (xy 271.73631 -350.498156) (xy 271.740381 -350.442534) (xy 271.752507 -350.388097)
			(xy 271.77243 -350.336006) (xy 271.799726 -350.287371) (xy 271.833812 -350.243228) (xy 271.873961 -350.204519)
			(xy 271.919319 -350.172068) (xy 271.968919 -350.146567) (xy 272.021703 -350.12856) (xy 272.076546 -350.11843)
			(xy 272.13228 -350.116393) (xy 272.187717 -350.122493) (xy 272.241674 -350.136599) (xy 272.293003 -350.158411)
			(xy 272.340609 -350.187465) (xy 272.383477 -350.22314) (xy 272.420694 -350.264677) (xy 272.451467 -350.31119)
			(xy 272.475139 -350.361687) (xy 272.491207 -350.415094) (xy 272.499327 -350.47027) (xy 272.499836 -350.498156)
			(xy 272.499327 -350.526042) (xy 272.491207 -350.581218) (xy 272.475139 -350.634625) (xy 272.451467 -350.685122)
			(xy 272.420694 -350.731635) (xy 272.383477 -350.773172) (xy 272.340609 -350.808847) (xy 272.293003 -350.837901)
			(xy 272.241674 -350.859713) (xy 272.187717 -350.873819) (xy 272.13228 -350.879919) (xy 272.076546 -350.877882)
			(xy 272.021703 -350.867752) (xy 271.968919 -350.849745) (xy 271.919319 -350.824244) (xy 271.873961 -350.791793)
			(xy 271.833812 -350.753084) (xy 271.799726 -350.708941) (xy 271.77243 -350.660306) (xy 271.752507 -350.608215)
			(xy 271.740381 -350.553778) (xy 271.73631 -350.498156) (xy 263.574022 -350.498156) (xy 264.249662 -351.173796)
			(xy 273.075146 -351.173796) (xy 273.075619 -351.146321) (xy 273.083512 -351.09194) (xy 273.099135 -351.039257)
			(xy 273.122163 -350.989365) (xy 273.152118 -350.943297) (xy 273.169888 -350.922336) (xy 273.175984 -350.915224)
			(xy 273.182334 -350.898206) (xy 273.182334 -350.812354) (xy 273.175984 -350.795336) (xy 273.169888 -350.788224)
			(xy 273.152152 -350.767239) (xy 273.122224 -350.721163) (xy 273.099206 -350.671275) (xy 273.083573 -350.618603)
			(xy 273.075649 -350.564235) (xy 273.075146 -350.536764) (xy 273.075632 -350.509513) (xy 273.083388 -350.455565)
			(xy 273.098743 -350.40327) (xy 273.121385 -350.353693) (xy 273.150851 -350.307843) (xy 273.186542 -350.266652)
			(xy 273.227733 -350.230961) (xy 273.273583 -350.201495) (xy 273.32316 -350.178853) (xy 273.375455 -350.163498)
			(xy 273.429403 -350.155742) (xy 273.483905 -350.155742) (xy 273.537853 -350.163498) (xy 273.590148 -350.178853)
			(xy 273.639725 -350.201495) (xy 273.685575 -350.230961) (xy 273.726766 -350.266652) (xy 273.762457 -350.307843)
			(xy 273.791923 -350.353693) (xy 273.814565 -350.40327) (xy 273.82992 -350.455565) (xy 273.837676 -350.509513)
			(xy 273.838162 -350.536764) (xy 273.837664 -350.564238) (xy 273.829776 -350.618618) (xy 273.814159 -350.6713)
			(xy 273.811506 -350.67705) (xy 274.079972 -350.67705) (xy 274.079972 -350.62255) (xy 274.087728 -350.568604)
			(xy 274.103081 -350.516311) (xy 274.125721 -350.466735) (xy 274.155185 -350.420885) (xy 274.190874 -350.379695)
			(xy 274.232061 -350.344003) (xy 274.277908 -350.314535) (xy 274.327482 -350.291892) (xy 274.379774 -350.276534)
			(xy 274.43372 -350.268774) (xy 274.46097 -350.268286) (xy 274.486206 -350.268654) (xy 274.536241 -350.275281)
			(xy 274.584962 -350.288463) (xy 274.631512 -350.307967) (xy 274.653502 -350.320356) (xy 274.663154 -350.326198)
			(xy 274.685252 -350.32823) (xy 274.77974 -350.294702) (xy 274.795742 -350.279208) (xy 274.799806 -350.268794)
			(xy 274.810477 -350.242007) (xy 274.838768 -350.191764) (xy 274.874301 -350.146354) (xy 274.916266 -350.106811)
			(xy 274.963707 -350.074039) (xy 275.015542 -350.048783) (xy 275.070589 -350.03162) (xy 275.127592 -350.022941)
			(xy 275.156422 -350.022414) (xy 275.183675 -350.022857) (xy 275.237625 -350.030617) (xy 275.289922 -350.045977)
			(xy 275.339501 -350.068622) (xy 275.385352 -350.098092) (xy 275.426543 -350.133788) (xy 275.462234 -350.174983)
			(xy 275.491699 -350.220838) (xy 275.514339 -350.270419) (xy 275.52706 -350.313752) (xy 277.667974 -350.313752)
			(xy 277.668485 -350.286179) (xy 277.676429 -350.231609) (xy 277.692146 -350.17875) (xy 277.715308 -350.128704)
			(xy 277.745432 -350.082513) (xy 277.781891 -350.04114) (xy 277.802594 -350.022922) (xy 277.810697 -350.015306)
			(xy 277.82006 -349.995165) (xy 277.820628 -349.98406) (xy 277.820628 -349.906844) (xy 277.820075 -349.895732)
			(xy 277.810728 -349.875572) (xy 277.802594 -349.867982) (xy 277.78187 -349.849785) (xy 277.745401 -349.808413)
			(xy 277.71527 -349.76222) (xy 277.692107 -349.71217) (xy 277.676393 -349.659304) (xy 277.668457 -349.604728)
			(xy 277.667974 -349.577152) (xy 277.668433 -349.5499) (xy 277.676196 -349.495953) (xy 277.691556 -349.443659)
			(xy 277.714201 -349.394082) (xy 277.743671 -349.348233) (xy 277.779365 -349.307044) (xy 277.820557 -349.271353)
			(xy 277.866409 -349.241887) (xy 277.915987 -349.219245) (xy 277.968282 -349.203889) (xy 278.02223 -349.196131)
			(xy 278.049482 -349.195644) (xy 278.083772 -349.197168) (xy 278.093932 -349.198184) (xy 278.113236 -349.192088)
			(xy 278.183848 -349.132906) (xy 278.193246 -349.114872) (xy 278.194262 -349.104712) (xy 278.197203 -349.076538)
			(xy 278.210381 -349.021447) (xy 278.231563 -348.968911) (xy 278.260283 -348.920087) (xy 278.295909 -348.876047)
			(xy 278.337657 -348.837761) (xy 278.384609 -348.806072) (xy 278.435731 -348.781676) (xy 278.4899 -348.76511)
			(xy 278.545923 -348.756738) (xy 278.574246 -348.756224) (xy 278.592265 -348.756444) (xy 278.62814 -348.759879)
			(xy 278.645874 -348.763082) (xy 278.655272 -348.76486) (xy 278.674322 -348.76105) (xy 278.749506 -348.713298)
			(xy 278.760936 -348.69755) (xy 278.763222 -348.688152) (xy 278.770612 -348.661106) (xy 278.792243 -348.609379)
			(xy 278.821208 -348.561373) (xy 278.856884 -348.518122) (xy 278.898505 -348.480555) (xy 278.945173 -348.449481)
			(xy 278.995885 -348.425569) (xy 279.04955 -348.409333) (xy 279.105013 -348.401122) (xy 279.133046 -348.400624)
			(xy 279.1603 -348.401035) (xy 279.214252 -348.408799) (xy 279.26655 -348.424161) (xy 279.31613 -348.44681)
			(xy 279.361981 -348.476284) (xy 279.403172 -348.511983) (xy 279.438863 -348.553181) (xy 279.468327 -348.599039)
			(xy 279.490966 -348.648623) (xy 279.506318 -348.700924) (xy 279.51407 -348.754878) (xy 279.514554 -348.782132)
			(xy 279.514058 -348.809706) (xy 279.506114 -348.864278) (xy 279.490396 -348.917138) (xy 279.467232 -348.967184)
			(xy 279.437104 -349.013375) (xy 279.40064 -349.054746) (xy 279.379934 -349.072962) (xy 279.371827 -349.080574)
			(xy 279.362469 -349.100719) (xy 279.3619 -349.111824) (xy 279.3619 -349.18904) (xy 279.36243 -349.200154)
			(xy 279.371796 -349.220313) (xy 279.379934 -349.227902) (xy 279.40067 -349.246084) (xy 279.43713 -349.287461)
			(xy 279.467254 -349.333656) (xy 279.490413 -349.383707) (xy 279.506124 -349.436571) (xy 279.514061 -349.491146)
			(xy 279.514058 -349.546295) (xy 279.506115 -349.60087) (xy 279.505539 -349.602806) (xy 280.59583 -349.602806)
			(xy 280.599901 -349.547184) (xy 280.612027 -349.492747) (xy 280.63195 -349.440656) (xy 280.659246 -349.392021)
			(xy 280.693332 -349.347878) (xy 280.733481 -349.309169) (xy 280.778839 -349.276718) (xy 280.828439 -349.251217)
			(xy 280.881223 -349.23321) (xy 280.936066 -349.22308) (xy 280.9918 -349.221043) (xy 281.047237 -349.227143)
			(xy 281.101194 -349.241249) (xy 281.152523 -349.263061) (xy 281.200129 -349.292115) (xy 281.242997 -349.32779)
			(xy 281.280214 -349.369327) (xy 281.310987 -349.41584) (xy 281.334659 -349.466337) (xy 281.350727 -349.519744)
			(xy 281.358847 -349.57492) (xy 281.359356 -349.602806) (xy 281.358847 -349.630692) (xy 281.350727 -349.685868)
			(xy 281.334659 -349.739275) (xy 281.310987 -349.789772) (xy 281.280214 -349.836285) (xy 281.242997 -349.877822)
			(xy 281.200129 -349.913497) (xy 281.152523 -349.942551) (xy 281.101194 -349.964363) (xy 281.047237 -349.978469)
			(xy 280.9918 -349.984569) (xy 280.936066 -349.982532) (xy 280.881223 -349.972402) (xy 280.828439 -349.954395)
			(xy 280.778839 -349.928894) (xy 280.733481 -349.896443) (xy 280.693332 -349.857734) (xy 280.659246 -349.813591)
			(xy 280.63195 -349.764956) (xy 280.612027 -349.712865) (xy 280.599901 -349.658428) (xy 280.59583 -349.602806)
			(xy 279.505539 -349.602806) (xy 279.490398 -349.653732) (xy 279.467234 -349.70378) (xy 279.437105 -349.749972)
			(xy 279.40064 -349.791345) (xy 279.379934 -349.809562) (xy 279.371827 -349.817174) (xy 279.362469 -349.837319)
			(xy 279.3619 -349.848424) (xy 279.3619 -349.92564) (xy 279.36243 -349.936754) (xy 279.371796 -349.956913)
			(xy 279.379934 -349.964502) (xy 279.400656 -349.982701) (xy 279.437124 -350.024073) (xy 279.467254 -350.070266)
			(xy 279.490418 -350.120316) (xy 279.506132 -350.17318) (xy 279.51407 -350.227757) (xy 279.514554 -350.255332)
			(xy 279.514052 -350.282582) (xy 279.506292 -350.336527) (xy 279.490936 -350.388818) (xy 279.468294 -350.438393)
			(xy 279.438829 -350.484241) (xy 279.426771 -350.498156) (xy 280.01671 -350.498156) (xy 280.020781 -350.442534)
			(xy 280.032907 -350.388097) (xy 280.05283 -350.336006) (xy 280.080126 -350.287371) (xy 280.114212 -350.243228)
			(xy 280.154361 -350.204519) (xy 280.199719 -350.172068) (xy 280.249319 -350.146567) (xy 280.302103 -350.12856)
			(xy 280.356946 -350.11843) (xy 280.41268 -350.116393) (xy 280.468117 -350.122493) (xy 280.522074 -350.136599)
			(xy 280.573403 -350.158411) (xy 280.621009 -350.187465) (xy 280.663877 -350.22314) (xy 280.701094 -350.264677)
			(xy 280.731867 -350.31119) (xy 280.755539 -350.361687) (xy 280.771607 -350.415094) (xy 280.779727 -350.47027)
			(xy 280.780236 -350.498156) (xy 280.779727 -350.526042) (xy 280.771607 -350.581218) (xy 280.755539 -350.634625)
			(xy 280.731867 -350.685122) (xy 280.701094 -350.731635) (xy 280.663877 -350.773172) (xy 280.621009 -350.808847)
			(xy 280.573403 -350.837901) (xy 280.522074 -350.859713) (xy 280.468117 -350.873819) (xy 280.41268 -350.879919)
			(xy 280.356946 -350.877882) (xy 280.302103 -350.867752) (xy 280.249319 -350.849745) (xy 280.199719 -350.824244)
			(xy 280.154361 -350.791793) (xy 280.114212 -350.753084) (xy 280.080126 -350.708941) (xy 280.05283 -350.660306)
			(xy 280.032907 -350.608215) (xy 280.020781 -350.553778) (xy 280.01671 -350.498156) (xy 279.426771 -350.498156)
			(xy 279.403139 -350.525429) (xy 279.361952 -350.56112) (xy 279.316105 -350.590587) (xy 279.266531 -350.613231)
			(xy 279.21424 -350.628589) (xy 279.160296 -350.636351) (xy 279.133046 -350.63684) (xy 279.105193 -350.636246)
			(xy 279.050082 -350.62813) (xy 278.996735 -350.612092) (xy 278.946285 -350.588474) (xy 278.899801 -350.557776)
			(xy 278.858271 -350.52065) (xy 278.822576 -350.477884) (xy 278.793473 -350.430385) (xy 278.771581 -350.379161)
			(xy 278.763984 -350.35236) (xy 278.761698 -350.34347) (xy 278.75103 -350.32823) (xy 278.679148 -350.280478)
			(xy 278.661114 -350.276414) (xy 278.65197 -350.277684) (xy 278.638954 -350.279354) (xy 278.612769 -350.281133)
			(xy 278.599646 -350.28124) (xy 278.585497 -350.281141) (xy 278.557274 -350.27911) (xy 278.543258 -350.277176)
			(xy 278.533098 -350.275652) (xy 278.51354 -350.280478) (xy 278.439118 -350.336358) (xy 278.428958 -350.353884)
			(xy 278.427688 -350.364044) (xy 278.423627 -350.391202) (xy 278.408653 -350.444035) (xy 278.386259 -350.494175)
			(xy 278.356909 -350.540587) (xy 278.321209 -350.582312) (xy 278.279895 -350.618488) (xy 278.233823 -350.648368)
			(xy 278.183943 -350.671335) (xy 278.131286 -350.686914) (xy 278.076939 -350.694784) (xy 278.049482 -350.69526)
			(xy 278.022226 -350.694862) (xy 277.968271 -350.687101) (xy 277.915969 -350.67174) (xy 277.866385 -350.649092)
			(xy 277.82053 -350.619618) (xy 277.779336 -350.583917) (xy 277.743643 -350.542717) (xy 277.714176 -350.496857)
			(xy 277.691537 -350.447269) (xy 277.676185 -350.394965) (xy 277.668434 -350.341008) (xy 277.667974 -350.313752)
			(xy 275.52706 -350.313752) (xy 275.529692 -350.322718) (xy 275.537446 -350.376669) (xy 275.53793 -350.403922)
			(xy 275.53726 -350.435484) (xy 275.526876 -350.497749) (xy 275.506395 -350.557459) (xy 275.491956 -350.585532)
			(xy 275.48713 -350.594422) (xy 275.485098 -350.61398) (xy 275.510752 -350.702118) (xy 275.523198 -350.717612)
			(xy 275.532088 -350.722692) (xy 275.557211 -350.737205) (xy 275.603094 -350.772714) (xy 275.643068 -350.814763)
			(xy 275.676212 -350.862383) (xy 275.701759 -350.914474) (xy 275.71912 -350.969834) (xy 275.727895 -351.027185)
			(xy 275.72843 -351.056194) (xy 275.727944 -351.083445) (xy 275.720188 -351.137393) (xy 275.709499 -351.173796)
			(xy 281.355546 -351.173796) (xy 281.356019 -351.146321) (xy 281.363912 -351.09194) (xy 281.379535 -351.039257)
			(xy 281.402563 -350.989365) (xy 281.432518 -350.943297) (xy 281.450288 -350.922336) (xy 281.456384 -350.915224)
			(xy 281.462734 -350.898206) (xy 281.462734 -350.812354) (xy 281.456384 -350.795336) (xy 281.450288 -350.788224)
			(xy 281.432552 -350.767239) (xy 281.402624 -350.721163) (xy 281.379606 -350.671275) (xy 281.363973 -350.618603)
			(xy 281.356049 -350.564235) (xy 281.355546 -350.536764) (xy 281.356032 -350.509513) (xy 281.363788 -350.455565)
			(xy 281.379143 -350.40327) (xy 281.401785 -350.353693) (xy 281.431251 -350.307843) (xy 281.466942 -350.266652)
			(xy 281.508133 -350.230961) (xy 281.553983 -350.201495) (xy 281.60356 -350.178853) (xy 281.655855 -350.163498)
			(xy 281.709803 -350.155742) (xy 281.764305 -350.155742) (xy 281.818253 -350.163498) (xy 281.870548 -350.178853)
			(xy 281.920125 -350.201495) (xy 281.965975 -350.230961) (xy 282.007166 -350.266652) (xy 282.042857 -350.307843)
			(xy 282.072323 -350.353693) (xy 282.094965 -350.40327) (xy 282.11032 -350.455565) (xy 282.118076 -350.509513)
			(xy 282.118562 -350.536764) (xy 282.118064 -350.564238) (xy 282.110176 -350.618618) (xy 282.094559 -350.6713)
			(xy 282.091906 -350.67705) (xy 282.360372 -350.67705) (xy 282.360372 -350.62255) (xy 282.368128 -350.568604)
			(xy 282.383481 -350.516311) (xy 282.406121 -350.466735) (xy 282.435585 -350.420885) (xy 282.471274 -350.379695)
			(xy 282.512461 -350.344003) (xy 282.558308 -350.314535) (xy 282.607882 -350.291892) (xy 282.660174 -350.276534)
			(xy 282.71412 -350.268774) (xy 282.74137 -350.268286) (xy 282.766606 -350.268654) (xy 282.816641 -350.275281)
			(xy 282.865362 -350.288463) (xy 282.911912 -350.307967) (xy 282.933902 -350.320356) (xy 282.943554 -350.326198)
			(xy 282.965652 -350.32823) (xy 283.06014 -350.294702) (xy 283.076142 -350.279208) (xy 283.080206 -350.268794)
			(xy 283.090877 -350.242007) (xy 283.119168 -350.191764) (xy 283.154701 -350.146354) (xy 283.196666 -350.106811)
			(xy 283.244107 -350.074039) (xy 283.295942 -350.048783) (xy 283.350989 -350.03162) (xy 283.407992 -350.022941)
			(xy 283.436822 -350.022414) (xy 283.464075 -350.022857) (xy 283.518025 -350.030617) (xy 283.570322 -350.045977)
			(xy 283.619901 -350.068622) (xy 283.665752 -350.098092) (xy 283.706943 -350.133788) (xy 283.742634 -350.174983)
			(xy 283.772099 -350.220838) (xy 283.794739 -350.270419) (xy 283.80746 -350.313752) (xy 285.948374 -350.313752)
			(xy 285.948885 -350.286179) (xy 285.956829 -350.231609) (xy 285.972546 -350.17875) (xy 285.995708 -350.128704)
			(xy 286.025832 -350.082513) (xy 286.062291 -350.04114) (xy 286.082994 -350.022922) (xy 286.091097 -350.015306)
			(xy 286.10046 -349.995165) (xy 286.101028 -349.98406) (xy 286.101028 -349.906844) (xy 286.100475 -349.895732)
			(xy 286.091128 -349.875572) (xy 286.082994 -349.867982) (xy 286.06227 -349.849785) (xy 286.025801 -349.808413)
			(xy 285.99567 -349.76222) (xy 285.972507 -349.71217) (xy 285.956793 -349.659304) (xy 285.948857 -349.604728)
			(xy 285.948374 -349.577152) (xy 285.948833 -349.5499) (xy 285.956596 -349.495953) (xy 285.971956 -349.443659)
			(xy 285.994601 -349.394082) (xy 286.024071 -349.348233) (xy 286.059765 -349.307044) (xy 286.100957 -349.271353)
			(xy 286.146809 -349.241887) (xy 286.196387 -349.219245) (xy 286.248682 -349.203889) (xy 286.30263 -349.196131)
			(xy 286.329882 -349.195644) (xy 286.364172 -349.197168) (xy 286.374332 -349.198184) (xy 286.393636 -349.192088)
			(xy 286.464248 -349.132906) (xy 286.473646 -349.114872) (xy 286.474662 -349.104712) (xy 286.477603 -349.076538)
			(xy 286.490781 -349.021447) (xy 286.511963 -348.968911) (xy 286.540683 -348.920087) (xy 286.576309 -348.876047)
			(xy 286.618057 -348.837761) (xy 286.665009 -348.806072) (xy 286.716131 -348.781676) (xy 286.7703 -348.76511)
			(xy 286.826323 -348.756738) (xy 286.854646 -348.756224) (xy 286.872665 -348.756444) (xy 286.90854 -348.759879)
			(xy 286.926274 -348.763082) (xy 286.935672 -348.76486) (xy 286.954722 -348.76105) (xy 287.029906 -348.713298)
			(xy 287.041336 -348.69755) (xy 287.043622 -348.688152) (xy 287.051012 -348.661106) (xy 287.072643 -348.609379)
			(xy 287.101608 -348.561373) (xy 287.137284 -348.518122) (xy 287.178905 -348.480555) (xy 287.225573 -348.449481)
			(xy 287.276285 -348.425569) (xy 287.32995 -348.409333) (xy 287.385413 -348.401122) (xy 287.413446 -348.400624)
			(xy 287.4407 -348.401035) (xy 287.494652 -348.408799) (xy 287.54695 -348.424161) (xy 287.59653 -348.44681)
			(xy 287.642381 -348.476284) (xy 287.683572 -348.511983) (xy 287.719263 -348.553181) (xy 287.748727 -348.599039)
			(xy 287.771366 -348.648623) (xy 287.786718 -348.700924) (xy 287.79447 -348.754878) (xy 287.794954 -348.782132)
			(xy 287.794458 -348.809706) (xy 287.786514 -348.864278) (xy 287.770796 -348.917138) (xy 287.747632 -348.967184)
			(xy 287.717504 -349.013375) (xy 287.68104 -349.054746) (xy 287.660334 -349.072962) (xy 287.652227 -349.080574)
			(xy 287.642869 -349.100719) (xy 287.6423 -349.111824) (xy 287.6423 -349.18904) (xy 287.64283 -349.200154)
			(xy 287.652196 -349.220313) (xy 287.660334 -349.227902) (xy 287.68107 -349.246084) (xy 287.71753 -349.287461)
			(xy 287.747654 -349.333656) (xy 287.770813 -349.383707) (xy 287.786524 -349.436571) (xy 287.794461 -349.491146)
			(xy 287.794458 -349.546295) (xy 287.786515 -349.60087) (xy 287.785939 -349.602806) (xy 288.90163 -349.602806)
			(xy 288.905701 -349.547184) (xy 288.917827 -349.492747) (xy 288.93775 -349.440656) (xy 288.965046 -349.392021)
			(xy 288.999132 -349.347878) (xy 289.039281 -349.309169) (xy 289.084639 -349.276718) (xy 289.134239 -349.251217)
			(xy 289.187023 -349.23321) (xy 289.241866 -349.22308) (xy 289.2976 -349.221043) (xy 289.353037 -349.227143)
			(xy 289.406994 -349.241249) (xy 289.458323 -349.263061) (xy 289.505929 -349.292115) (xy 289.548797 -349.32779)
			(xy 289.586014 -349.369327) (xy 289.616787 -349.41584) (xy 289.640459 -349.466337) (xy 289.656527 -349.519744)
			(xy 289.664647 -349.57492) (xy 289.665156 -349.602806) (xy 289.664647 -349.630692) (xy 289.656527 -349.685868)
			(xy 289.640459 -349.739275) (xy 289.616787 -349.789772) (xy 289.586014 -349.836285) (xy 289.548797 -349.877822)
			(xy 289.505929 -349.913497) (xy 289.458323 -349.942551) (xy 289.406994 -349.964363) (xy 289.353037 -349.978469)
			(xy 289.2976 -349.984569) (xy 289.241866 -349.982532) (xy 289.187023 -349.972402) (xy 289.134239 -349.954395)
			(xy 289.084639 -349.928894) (xy 289.039281 -349.896443) (xy 288.999132 -349.857734) (xy 288.965046 -349.813591)
			(xy 288.93775 -349.764956) (xy 288.917827 -349.712865) (xy 288.905701 -349.658428) (xy 288.90163 -349.602806)
			(xy 287.785939 -349.602806) (xy 287.770798 -349.653732) (xy 287.747634 -349.70378) (xy 287.717505 -349.749972)
			(xy 287.68104 -349.791345) (xy 287.660334 -349.809562) (xy 287.652227 -349.817174) (xy 287.642869 -349.837319)
			(xy 287.6423 -349.848424) (xy 287.6423 -349.92564) (xy 287.64283 -349.936754) (xy 287.652196 -349.956913)
			(xy 287.660334 -349.964502) (xy 287.681056 -349.982701) (xy 287.717524 -350.024073) (xy 287.747654 -350.070266)
			(xy 287.770818 -350.120316) (xy 287.786532 -350.17318) (xy 287.79447 -350.227757) (xy 287.794954 -350.255332)
			(xy 287.794452 -350.282582) (xy 287.786692 -350.336527) (xy 287.771336 -350.388818) (xy 287.748694 -350.438393)
			(xy 287.719229 -350.484241) (xy 287.707171 -350.498156) (xy 288.32251 -350.498156) (xy 288.326581 -350.442534)
			(xy 288.338707 -350.388097) (xy 288.35863 -350.336006) (xy 288.385926 -350.287371) (xy 288.420012 -350.243228)
			(xy 288.460161 -350.204519) (xy 288.505519 -350.172068) (xy 288.555119 -350.146567) (xy 288.607903 -350.12856)
			(xy 288.662746 -350.11843) (xy 288.71848 -350.116393) (xy 288.773917 -350.122493) (xy 288.827874 -350.136599)
			(xy 288.879203 -350.158411) (xy 288.926809 -350.187465) (xy 288.969677 -350.22314) (xy 289.006894 -350.264677)
			(xy 289.037667 -350.31119) (xy 289.061339 -350.361687) (xy 289.077407 -350.415094) (xy 289.085527 -350.47027)
			(xy 289.086036 -350.498156) (xy 289.085527 -350.526042) (xy 289.077407 -350.581218) (xy 289.061339 -350.634625)
			(xy 289.037667 -350.685122) (xy 289.006894 -350.731635) (xy 288.969677 -350.773172) (xy 288.926809 -350.808847)
			(xy 288.879203 -350.837901) (xy 288.827874 -350.859713) (xy 288.773917 -350.873819) (xy 288.71848 -350.879919)
			(xy 288.662746 -350.877882) (xy 288.607903 -350.867752) (xy 288.555119 -350.849745) (xy 288.505519 -350.824244)
			(xy 288.460161 -350.791793) (xy 288.420012 -350.753084) (xy 288.385926 -350.708941) (xy 288.35863 -350.660306)
			(xy 288.338707 -350.608215) (xy 288.326581 -350.553778) (xy 288.32251 -350.498156) (xy 287.707171 -350.498156)
			(xy 287.683539 -350.525429) (xy 287.642352 -350.56112) (xy 287.596505 -350.590587) (xy 287.546931 -350.613231)
			(xy 287.49464 -350.628589) (xy 287.440696 -350.636351) (xy 287.413446 -350.63684) (xy 287.385593 -350.636246)
			(xy 287.330482 -350.62813) (xy 287.277135 -350.612092) (xy 287.226685 -350.588474) (xy 287.180201 -350.557776)
			(xy 287.138671 -350.52065) (xy 287.102976 -350.477884) (xy 287.073873 -350.430385) (xy 287.051981 -350.379161)
			(xy 287.044384 -350.35236) (xy 287.042098 -350.34347) (xy 287.03143 -350.32823) (xy 286.959548 -350.280478)
			(xy 286.941514 -350.276414) (xy 286.93237 -350.277684) (xy 286.919354 -350.279354) (xy 286.893169 -350.281133)
			(xy 286.880046 -350.28124) (xy 286.865897 -350.281141) (xy 286.837674 -350.27911) (xy 286.823658 -350.277176)
			(xy 286.813498 -350.275652) (xy 286.79394 -350.280478) (xy 286.719518 -350.336358) (xy 286.709358 -350.353884)
			(xy 286.708088 -350.364044) (xy 286.704027 -350.391202) (xy 286.689053 -350.444035) (xy 286.666659 -350.494175)
			(xy 286.637309 -350.540587) (xy 286.601609 -350.582312) (xy 286.560295 -350.618488) (xy 286.514223 -350.648368)
			(xy 286.464343 -350.671335) (xy 286.411686 -350.686914) (xy 286.357339 -350.694784) (xy 286.329882 -350.69526)
			(xy 286.302626 -350.694862) (xy 286.248671 -350.687101) (xy 286.196369 -350.67174) (xy 286.146785 -350.649092)
			(xy 286.10093 -350.619618) (xy 286.059736 -350.583917) (xy 286.024043 -350.542717) (xy 285.994576 -350.496857)
			(xy 285.971937 -350.447269) (xy 285.956585 -350.394965) (xy 285.948834 -350.341008) (xy 285.948374 -350.313752)
			(xy 283.80746 -350.313752) (xy 283.810092 -350.322718) (xy 283.817846 -350.376669) (xy 283.81833 -350.403922)
			(xy 283.81766 -350.435484) (xy 283.807276 -350.497749) (xy 283.786795 -350.557459) (xy 283.772356 -350.585532)
			(xy 283.76753 -350.594422) (xy 283.765498 -350.61398) (xy 283.791152 -350.702118) (xy 283.803598 -350.717612)
			(xy 283.812488 -350.722692) (xy 283.837611 -350.737205) (xy 283.883494 -350.772714) (xy 283.923468 -350.814763)
			(xy 283.956612 -350.862383) (xy 283.982159 -350.914474) (xy 283.99952 -350.969834) (xy 284.008295 -351.027185)
			(xy 284.00883 -351.056194) (xy 284.008344 -351.083445) (xy 284.000588 -351.137393) (xy 283.985233 -351.189688)
			(xy 283.962591 -351.239265) (xy 283.933125 -351.285115) (xy 283.897434 -351.326306) (xy 283.856243 -351.361997)
			(xy 283.810393 -351.391463) (xy 283.760816 -351.414105) (xy 283.708521 -351.42946) (xy 283.654573 -351.437216)
			(xy 283.600071 -351.437216) (xy 283.546123 -351.42946) (xy 283.493828 -351.414105) (xy 283.444251 -351.391463)
			(xy 283.398401 -351.361997) (xy 283.35721 -351.326306) (xy 283.321519 -351.285115) (xy 283.292053 -351.239265)
			(xy 283.269411 -351.189688) (xy 283.254056 -351.137393) (xy 283.2463 -351.083445) (xy 283.245814 -351.056194)
			(xy 283.246485 -351.024632) (xy 283.256867 -350.962367) (xy 283.277349 -350.902657) (xy 283.291788 -350.874584)
			(xy 283.296614 -350.865694) (xy 283.298646 -350.846136) (xy 283.272992 -350.757998) (xy 283.260546 -350.742504)
			(xy 283.251656 -350.737424) (xy 283.24429 -350.73336) (xy 283.234638 -350.727518) (xy 283.21254 -350.725486)
			(xy 283.118052 -350.759014) (xy 283.10205 -350.774508) (xy 283.097986 -350.784922) (xy 283.08733 -350.811715)
			(xy 283.059037 -350.861958) (xy 283.023501 -350.907368) (xy 282.981533 -350.94691) (xy 282.93409 -350.979681)
			(xy 282.882254 -351.004936) (xy 282.827205 -351.022098) (xy 282.770201 -351.030775) (xy 282.74137 -351.031302)
			(xy 282.71412 -351.030826) (xy 282.660174 -351.023066) (xy 282.607882 -351.007708) (xy 282.558308 -350.985065)
			(xy 282.512461 -350.955597) (xy 282.471274 -350.919905) (xy 282.435585 -350.878715) (xy 282.406121 -350.832865)
			(xy 282.383481 -350.783289) (xy 282.368128 -350.730996) (xy 282.360372 -350.67705) (xy 282.091906 -350.67705)
			(xy 282.071537 -350.721193) (xy 282.041587 -350.767262) (xy 282.02382 -350.788224) (xy 282.017724 -350.795336)
			(xy 282.011374 -350.812354) (xy 282.011374 -350.898206) (xy 282.017724 -350.915224) (xy 282.02382 -350.922336)
			(xy 282.041585 -350.943297) (xy 282.071509 -350.98938) (xy 282.094521 -351.039274) (xy 282.110147 -351.091951)
			(xy 282.118063 -351.146324) (xy 282.118562 -351.173796) (xy 282.118076 -351.201047) (xy 282.11032 -351.254995)
			(xy 282.094965 -351.30729) (xy 282.072323 -351.356867) (xy 282.042857 -351.402717) (xy 282.007166 -351.443908)
			(xy 281.965975 -351.479599) (xy 281.920125 -351.509065) (xy 281.870548 -351.531707) (xy 281.818253 -351.547062)
			(xy 281.764305 -351.554818) (xy 281.709803 -351.554818) (xy 281.655855 -351.547062) (xy 281.60356 -351.531707)
			(xy 281.553983 -351.509065) (xy 281.508133 -351.479599) (xy 281.466942 -351.443908) (xy 281.431251 -351.402717)
			(xy 281.401785 -351.356867) (xy 281.379143 -351.30729) (xy 281.363788 -351.254995) (xy 281.356032 -351.201047)
			(xy 281.355546 -351.173796) (xy 275.709499 -351.173796) (xy 275.704833 -351.189688) (xy 275.682191 -351.239265)
			(xy 275.652725 -351.285115) (xy 275.617034 -351.326306) (xy 275.575843 -351.361997) (xy 275.529993 -351.391463)
			(xy 275.480416 -351.414105) (xy 275.428121 -351.42946) (xy 275.374173 -351.437216) (xy 275.319671 -351.437216)
			(xy 275.265723 -351.42946) (xy 275.213428 -351.414105) (xy 275.163851 -351.391463) (xy 275.118001 -351.361997)
			(xy 275.07681 -351.326306) (xy 275.041119 -351.285115) (xy 275.011653 -351.239265) (xy 274.989011 -351.189688)
			(xy 274.973656 -351.137393) (xy 274.9659 -351.083445) (xy 274.965414 -351.056194) (xy 274.966085 -351.024632)
			(xy 274.976467 -350.962367) (xy 274.996949 -350.902657) (xy 275.011388 -350.874584) (xy 275.016214 -350.865694)
			(xy 275.018246 -350.846136) (xy 274.992592 -350.757998) (xy 274.980146 -350.742504) (xy 274.971256 -350.737424)
			(xy 274.96389 -350.73336) (xy 274.954238 -350.727518) (xy 274.93214 -350.725486) (xy 274.837652 -350.759014)
			(xy 274.82165 -350.774508) (xy 274.817586 -350.784922) (xy 274.80693 -350.811715) (xy 274.778637 -350.861958)
			(xy 274.743101 -350.907368) (xy 274.701133 -350.94691) (xy 274.65369 -350.979681) (xy 274.601854 -351.004936)
			(xy 274.546805 -351.022098) (xy 274.489801 -351.030775) (xy 274.46097 -351.031302) (xy 274.43372 -351.030826)
			(xy 274.379774 -351.023066) (xy 274.327482 -351.007708) (xy 274.277908 -350.985065) (xy 274.232061 -350.955597)
			(xy 274.190874 -350.919905) (xy 274.155185 -350.878715) (xy 274.125721 -350.832865) (xy 274.103081 -350.783289)
			(xy 274.087728 -350.730996) (xy 274.079972 -350.67705) (xy 273.811506 -350.67705) (xy 273.791137 -350.721193)
			(xy 273.761187 -350.767262) (xy 273.74342 -350.788224) (xy 273.737324 -350.795336) (xy 273.730974 -350.812354)
			(xy 273.730974 -350.898206) (xy 273.737324 -350.915224) (xy 273.74342 -350.922336) (xy 273.761185 -350.943297)
			(xy 273.791109 -350.98938) (xy 273.814121 -351.039274) (xy 273.829747 -351.091951) (xy 273.837663 -351.146324)
			(xy 273.838162 -351.173796) (xy 273.837676 -351.201047) (xy 273.82992 -351.254995) (xy 273.814565 -351.30729)
			(xy 273.791923 -351.356867) (xy 273.762457 -351.402717) (xy 273.726766 -351.443908) (xy 273.685575 -351.479599)
			(xy 273.639725 -351.509065) (xy 273.590148 -351.531707) (xy 273.537853 -351.547062) (xy 273.483905 -351.554818)
			(xy 273.429403 -351.554818) (xy 273.375455 -351.547062) (xy 273.32316 -351.531707) (xy 273.273583 -351.509065)
			(xy 273.227733 -351.479599) (xy 273.186542 -351.443908) (xy 273.150851 -351.402717) (xy 273.121385 -351.356867)
			(xy 273.098743 -351.30729) (xy 273.083388 -351.254995) (xy 273.075632 -351.201047) (xy 273.075146 -351.173796)
			(xy 264.249662 -351.173796) (xy 265.100562 -352.024696) (xy 289.079432 -352.024696) (xy 289.079432 -351.066608)
			(xy 289.080072 -351.041626) (xy 289.089807 -350.99262) (xy 289.108906 -350.94645) (xy 289.136637 -350.904888)
			(xy 289.153854 -350.886776) (xy 289.683698 -350.356932) (xy 289.692193 -350.348565) (xy 289.710514 -350.333301)
			(xy 289.720274 -350.326452) (xy 289.723885 -350.323892) (xy 289.730276 -350.317769) (xy 289.732974 -350.31426)
			(xy 289.748368 -350.293494) (xy 289.783911 -350.255958) (xy 289.824198 -350.223566) (xy 289.86849 -350.196912)
			(xy 289.915976 -350.176484) (xy 289.965786 -350.162657) (xy 290.017007 -350.155683) (xy 290.042854 -350.155256)
			(xy 290.070104 -350.155798) (xy 290.12405 -350.163548) (xy 290.176345 -350.178896) (xy 290.225922 -350.201531)
			(xy 290.271774 -350.230991) (xy 290.312966 -350.266676) (xy 290.34866 -350.307861) (xy 290.37813 -350.353706)
			(xy 290.400775 -350.403279) (xy 290.416135 -350.455569) (xy 290.423896 -350.509514) (xy 290.424362 -350.536764)
			(xy 290.423864 -350.564238) (xy 290.415976 -350.618618) (xy 290.400359 -350.6713) (xy 290.397706 -350.67705)
			(xy 290.666172 -350.67705) (xy 290.666172 -350.62255) (xy 290.673928 -350.568604) (xy 290.689281 -350.516311)
			(xy 290.711921 -350.466735) (xy 290.741385 -350.420885) (xy 290.777074 -350.379695) (xy 290.818261 -350.344003)
			(xy 290.864108 -350.314535) (xy 290.913682 -350.291892) (xy 290.965974 -350.276534) (xy 291.01992 -350.268774)
			(xy 291.04717 -350.268286) (xy 291.072406 -350.268654) (xy 291.122441 -350.275281) (xy 291.171162 -350.288463)
			(xy 291.217712 -350.307967) (xy 291.239702 -350.320356) (xy 291.249354 -350.326198) (xy 291.271452 -350.32823)
			(xy 291.36594 -350.294702) (xy 291.381942 -350.279208) (xy 291.386006 -350.268794) (xy 291.396677 -350.242007)
			(xy 291.424968 -350.191764) (xy 291.460501 -350.146354) (xy 291.502466 -350.106811) (xy 291.549907 -350.074039)
			(xy 291.601742 -350.048783) (xy 291.656789 -350.03162) (xy 291.713792 -350.022941) (xy 291.742622 -350.022414)
			(xy 291.769875 -350.022857) (xy 291.823825 -350.030617) (xy 291.876122 -350.045977) (xy 291.925701 -350.068622)
			(xy 291.971552 -350.098092) (xy 292.012743 -350.133788) (xy 292.048434 -350.174983) (xy 292.077899 -350.220838)
			(xy 292.100539 -350.270419) (xy 292.11326 -350.313752) (xy 294.254174 -350.313752) (xy 294.254685 -350.286179)
			(xy 294.262629 -350.231609) (xy 294.278346 -350.17875) (xy 294.301508 -350.128704) (xy 294.331632 -350.082513)
			(xy 294.368091 -350.04114) (xy 294.388794 -350.022922) (xy 294.396897 -350.015306) (xy 294.40626 -349.995165)
			(xy 294.406828 -349.98406) (xy 294.406828 -349.906844) (xy 294.406275 -349.895732) (xy 294.396928 -349.875572)
			(xy 294.388794 -349.867982) (xy 294.36807 -349.849785) (xy 294.331601 -349.808413) (xy 294.30147 -349.76222)
			(xy 294.278307 -349.71217) (xy 294.262593 -349.659304) (xy 294.254657 -349.604728) (xy 294.254174 -349.577152)
			(xy 294.254633 -349.5499) (xy 294.262396 -349.495953) (xy 294.277756 -349.443659) (xy 294.300401 -349.394082)
			(xy 294.329871 -349.348233) (xy 294.365565 -349.307044) (xy 294.406757 -349.271353) (xy 294.452609 -349.241887)
			(xy 294.502187 -349.219245) (xy 294.554482 -349.203889) (xy 294.60843 -349.196131) (xy 294.635682 -349.195644)
			(xy 294.669972 -349.197168) (xy 294.680132 -349.198184) (xy 294.699436 -349.192088) (xy 294.770048 -349.132906)
			(xy 294.779446 -349.114872) (xy 294.780462 -349.104712) (xy 294.783403 -349.076538) (xy 294.796581 -349.021447)
			(xy 294.817763 -348.968911) (xy 294.846483 -348.920087) (xy 294.882109 -348.876047) (xy 294.923857 -348.837761)
			(xy 294.970809 -348.806072) (xy 295.021931 -348.781676) (xy 295.0761 -348.76511) (xy 295.132123 -348.756738)
			(xy 295.160446 -348.756224) (xy 295.178465 -348.756444) (xy 295.21434 -348.759879) (xy 295.232074 -348.763082)
			(xy 295.241472 -348.76486) (xy 295.260522 -348.76105) (xy 295.335706 -348.713298) (xy 295.347136 -348.69755)
			(xy 295.349422 -348.688152) (xy 295.356812 -348.661106) (xy 295.378443 -348.609379) (xy 295.407408 -348.561373)
			(xy 295.443084 -348.518122) (xy 295.484705 -348.480555) (xy 295.531373 -348.449481) (xy 295.582085 -348.425569)
			(xy 295.63575 -348.409333) (xy 295.691213 -348.401122) (xy 295.719246 -348.400624) (xy 295.7465 -348.401035)
			(xy 295.800452 -348.408799) (xy 295.85275 -348.424161) (xy 295.90233 -348.44681) (xy 295.948181 -348.476284)
			(xy 295.989372 -348.511983) (xy 296.025063 -348.553181) (xy 296.054527 -348.599039) (xy 296.077166 -348.648623)
			(xy 296.092518 -348.700924) (xy 296.10027 -348.754878) (xy 296.100754 -348.782132) (xy 296.100258 -348.809706)
			(xy 296.092314 -348.864278) (xy 296.076596 -348.917138) (xy 296.053432 -348.967184) (xy 296.023304 -349.013375)
			(xy 295.98684 -349.054746) (xy 295.966134 -349.072962) (xy 295.958027 -349.080574) (xy 295.948669 -349.100719)
			(xy 295.9481 -349.111824) (xy 295.9481 -349.18904) (xy 295.94863 -349.200154) (xy 295.957996 -349.220313)
			(xy 295.966134 -349.227902) (xy 295.98687 -349.246084) (xy 296.02333 -349.287461) (xy 296.053454 -349.333656)
			(xy 296.076613 -349.383707) (xy 296.092324 -349.436571) (xy 296.100261 -349.491146) (xy 296.100258 -349.546295)
			(xy 296.092315 -349.60087) (xy 296.091739 -349.602806) (xy 297.25823 -349.602806) (xy 297.262301 -349.547184)
			(xy 297.274427 -349.492747) (xy 297.29435 -349.440656) (xy 297.321646 -349.392021) (xy 297.355732 -349.347878)
			(xy 297.395881 -349.309169) (xy 297.441239 -349.276718) (xy 297.490839 -349.251217) (xy 297.543623 -349.23321)
			(xy 297.598466 -349.22308) (xy 297.6542 -349.221043) (xy 297.709637 -349.227143) (xy 297.763594 -349.241249)
			(xy 297.814923 -349.263061) (xy 297.862529 -349.292115) (xy 297.905397 -349.32779) (xy 297.942614 -349.369327)
			(xy 297.973387 -349.41584) (xy 297.997059 -349.466337) (xy 298.013127 -349.519744) (xy 298.021247 -349.57492)
			(xy 298.021756 -349.602806) (xy 298.021247 -349.630692) (xy 298.013127 -349.685868) (xy 297.997059 -349.739275)
			(xy 297.973387 -349.789772) (xy 297.942614 -349.836285) (xy 297.905397 -349.877822) (xy 297.862529 -349.913497)
			(xy 297.814923 -349.942551) (xy 297.763594 -349.964363) (xy 297.709637 -349.978469) (xy 297.6542 -349.984569)
			(xy 297.598466 -349.982532) (xy 297.543623 -349.972402) (xy 297.490839 -349.954395) (xy 297.441239 -349.928894)
			(xy 297.395881 -349.896443) (xy 297.355732 -349.857734) (xy 297.321646 -349.813591) (xy 297.29435 -349.764956)
			(xy 297.274427 -349.712865) (xy 297.262301 -349.658428) (xy 297.25823 -349.602806) (xy 296.091739 -349.602806)
			(xy 296.076598 -349.653732) (xy 296.053434 -349.70378) (xy 296.023305 -349.749972) (xy 295.98684 -349.791345)
			(xy 295.966134 -349.809562) (xy 295.958027 -349.817174) (xy 295.948669 -349.837319) (xy 295.9481 -349.848424)
			(xy 295.9481 -349.92564) (xy 295.94863 -349.936754) (xy 295.957996 -349.956913) (xy 295.966134 -349.964502)
			(xy 295.986856 -349.982701) (xy 296.023324 -350.024073) (xy 296.053454 -350.070266) (xy 296.076618 -350.120316)
			(xy 296.092332 -350.17318) (xy 296.10027 -350.227757) (xy 296.100754 -350.255332) (xy 296.100252 -350.282582)
			(xy 296.092492 -350.336527) (xy 296.077136 -350.388818) (xy 296.054494 -350.438393) (xy 296.025029 -350.484241)
			(xy 296.012971 -350.498156) (xy 296.67911 -350.498156) (xy 296.683181 -350.442534) (xy 296.695307 -350.388097)
			(xy 296.71523 -350.336006) (xy 296.742526 -350.287371) (xy 296.776612 -350.243228) (xy 296.816761 -350.204519)
			(xy 296.862119 -350.172068) (xy 296.911719 -350.146567) (xy 296.964503 -350.12856) (xy 297.019346 -350.11843)
			(xy 297.07508 -350.116393) (xy 297.130517 -350.122493) (xy 297.184474 -350.136599) (xy 297.235803 -350.158411)
			(xy 297.283409 -350.187465) (xy 297.326277 -350.22314) (xy 297.363494 -350.264677) (xy 297.394267 -350.31119)
			(xy 297.417939 -350.361687) (xy 297.434007 -350.415094) (xy 297.442127 -350.47027) (xy 297.442636 -350.498156)
			(xy 297.442127 -350.526042) (xy 297.434007 -350.581218) (xy 297.417939 -350.634625) (xy 297.394267 -350.685122)
			(xy 297.363494 -350.731635) (xy 297.326277 -350.773172) (xy 297.283409 -350.808847) (xy 297.235803 -350.837901)
			(xy 297.184474 -350.859713) (xy 297.130517 -350.873819) (xy 297.07508 -350.879919) (xy 297.019346 -350.877882)
			(xy 296.964503 -350.867752) (xy 296.911719 -350.849745) (xy 296.862119 -350.824244) (xy 296.816761 -350.791793)
			(xy 296.776612 -350.753084) (xy 296.742526 -350.708941) (xy 296.71523 -350.660306) (xy 296.695307 -350.608215)
			(xy 296.683181 -350.553778) (xy 296.67911 -350.498156) (xy 296.012971 -350.498156) (xy 295.989339 -350.525429)
			(xy 295.948152 -350.56112) (xy 295.902305 -350.590587) (xy 295.852731 -350.613231) (xy 295.80044 -350.628589)
			(xy 295.746496 -350.636351) (xy 295.719246 -350.63684) (xy 295.691393 -350.636246) (xy 295.636282 -350.62813)
			(xy 295.582935 -350.612092) (xy 295.532485 -350.588474) (xy 295.486001 -350.557776) (xy 295.444471 -350.52065)
			(xy 295.408776 -350.477884) (xy 295.379673 -350.430385) (xy 295.357781 -350.379161) (xy 295.350184 -350.35236)
			(xy 295.347898 -350.34347) (xy 295.33723 -350.32823) (xy 295.265348 -350.280478) (xy 295.247314 -350.276414)
			(xy 295.23817 -350.277684) (xy 295.225154 -350.279354) (xy 295.198969 -350.281133) (xy 295.185846 -350.28124)
			(xy 295.171697 -350.281141) (xy 295.143474 -350.27911) (xy 295.129458 -350.277176) (xy 295.119298 -350.275652)
			(xy 295.09974 -350.280478) (xy 295.025318 -350.336358) (xy 295.015158 -350.353884) (xy 295.013888 -350.364044)
			(xy 295.009827 -350.391202) (xy 294.994853 -350.444035) (xy 294.972459 -350.494175) (xy 294.943109 -350.540587)
			(xy 294.907409 -350.582312) (xy 294.866095 -350.618488) (xy 294.820023 -350.648368) (xy 294.770143 -350.671335)
			(xy 294.717486 -350.686914) (xy 294.663139 -350.694784) (xy 294.635682 -350.69526) (xy 294.608426 -350.694862)
			(xy 294.554471 -350.687101) (xy 294.502169 -350.67174) (xy 294.452585 -350.649092) (xy 294.40673 -350.619618)
			(xy 294.365536 -350.583917) (xy 294.329843 -350.542717) (xy 294.300376 -350.496857) (xy 294.277737 -350.447269)
			(xy 294.262385 -350.394965) (xy 294.254634 -350.341008) (xy 294.254174 -350.313752) (xy 292.11326 -350.313752)
			(xy 292.115892 -350.322718) (xy 292.123646 -350.376669) (xy 292.12413 -350.403922) (xy 292.12346 -350.435484)
			(xy 292.113076 -350.497749) (xy 292.092595 -350.557459) (xy 292.078156 -350.585532) (xy 292.07333 -350.594422)
			(xy 292.071298 -350.61398) (xy 292.096952 -350.702118) (xy 292.109398 -350.717612) (xy 292.118288 -350.722692)
			(xy 292.143411 -350.737205) (xy 292.189294 -350.772714) (xy 292.229268 -350.814763) (xy 292.262412 -350.862383)
			(xy 292.287959 -350.914474) (xy 292.30532 -350.969834) (xy 292.314095 -351.027185) (xy 292.31463 -351.056194)
			(xy 292.314144 -351.083445) (xy 292.306388 -351.137393) (xy 292.291033 -351.189688) (xy 292.268391 -351.239265)
			(xy 292.238925 -351.285115) (xy 292.203234 -351.326306) (xy 292.162043 -351.361997) (xy 292.116193 -351.391463)
			(xy 292.066616 -351.414105) (xy 292.014321 -351.42946) (xy 291.960373 -351.437216) (xy 291.905871 -351.437216)
			(xy 291.851923 -351.42946) (xy 291.799628 -351.414105) (xy 291.750051 -351.391463) (xy 291.704201 -351.361997)
			(xy 291.66301 -351.326306) (xy 291.627319 -351.285115) (xy 291.597853 -351.239265) (xy 291.575211 -351.189688)
			(xy 291.559856 -351.137393) (xy 291.5521 -351.083445) (xy 291.551614 -351.056194) (xy 291.552285 -351.024632)
			(xy 291.562667 -350.962367) (xy 291.583149 -350.902657) (xy 291.597588 -350.874584) (xy 291.602414 -350.865694)
			(xy 291.604446 -350.846136) (xy 291.578792 -350.757998) (xy 291.566346 -350.742504) (xy 291.557456 -350.737424)
			(xy 291.55009 -350.73336) (xy 291.540438 -350.727518) (xy 291.51834 -350.725486) (xy 291.423852 -350.759014)
			(xy 291.40785 -350.774508) (xy 291.403786 -350.784922) (xy 291.39313 -350.811715) (xy 291.364837 -350.861958)
			(xy 291.329301 -350.907368) (xy 291.287333 -350.94691) (xy 291.23989 -350.979681) (xy 291.188054 -351.004936)
			(xy 291.133005 -351.022098) (xy 291.076001 -351.030775) (xy 291.04717 -351.031302) (xy 291.01992 -351.030826)
			(xy 290.965974 -351.023066) (xy 290.913682 -351.007708) (xy 290.864108 -350.985065) (xy 290.818261 -350.955597)
			(xy 290.777074 -350.919905) (xy 290.741385 -350.878715) (xy 290.711921 -350.832865) (xy 290.689281 -350.783289)
			(xy 290.673928 -350.730996) (xy 290.666172 -350.67705) (xy 290.397706 -350.67705) (xy 290.377337 -350.721193)
			(xy 290.347387 -350.767262) (xy 290.32962 -350.788224) (xy 290.323524 -350.795336) (xy 290.317174 -350.812354)
			(xy 290.317174 -350.898206) (xy 290.323524 -350.915224) (xy 290.32962 -350.922336) (xy 290.347385 -350.943297)
			(xy 290.377309 -350.98938) (xy 290.400321 -351.039274) (xy 290.415947 -351.091951) (xy 290.423863 -351.146324)
			(xy 290.424362 -351.173796) (xy 290.423821 -351.201684) (xy 290.4157 -351.256866) (xy 290.399631 -351.310277)
			(xy 290.375956 -351.36078) (xy 290.34518 -351.407297) (xy 290.307959 -351.448837) (xy 290.265086 -351.484514)
			(xy 290.217475 -351.513569) (xy 290.166141 -351.535382) (xy 290.112178 -351.549488) (xy 290.08451 -351.553018)
			(xy 290.064952 -351.55505) (xy 290.039044 -351.584006) (xy 290.039044 -351.81032) (xy 290.039447 -351.820392)
			(xy 290.047182 -351.83899) (xy 290.05403 -351.846388) (xy 291.379402 -353.17176) (xy 291.38689 -353.178445)
			(xy 291.405444 -353.18604) (xy 291.41547 -353.186492) (xy 303.911 -353.186492) (xy 303.935997 -353.187108)
			(xy 303.985022 -353.196915) (xy 304.031193 -353.216095) (xy 304.072738 -353.243909) (xy 304.090832 -353.261168)
			(xy 308.344824 -357.51516) (xy 308.352304 -357.521855) (xy 308.370864 -357.529444) (xy 308.380892 -357.529892)
			(xy 309.765192 -357.529892) (xy 309.775226 -357.529505) (xy 309.793778 -357.521865) (xy 309.807965 -357.507678)
			(xy 309.815605 -357.489126) (xy 309.815992 -357.479092) (xy 309.815992 -356.616508) (xy 309.816246 -356.616508)
			(xy 309.815707 -356.606507) (xy 309.808058 -356.588024) (xy 309.793922 -356.573872) (xy 309.775447 -356.566204)
			(xy 309.765446 -356.565708) (xy 307.969412 -356.565708) (xy 307.944415 -356.565085) (xy 307.895391 -356.55528)
			(xy 307.84922 -356.536103) (xy 307.807675 -356.50829) (xy 307.78958 -356.491032) (xy 304.343816 -353.045268)
			(xy 304.336353 -353.038551) (xy 304.31778 -353.030974) (xy 304.307748 -353.030536) (xy 298.487338 -353.030536)
			(xy 298.462342 -353.029889) (xy 298.41332 -353.02009) (xy 298.367149 -353.00092) (xy 298.325602 -352.973114)
			(xy 298.307506 -352.95586) (xy 297.510454 -352.158808) (xy 297.493222 -352.140707) (xy 297.465483 -352.099145)
			(xy 297.446378 -352.052972) (xy 297.436641 -352.003961) (xy 297.436032 -351.978976) (xy 297.436032 -351.066608)
			(xy 297.436672 -351.041626) (xy 297.446407 -350.99262) (xy 297.465506 -350.94645) (xy 297.493237 -350.904888)
			(xy 297.510454 -350.886776) (xy 298.040298 -350.356932) (xy 298.048793 -350.348565) (xy 298.067114 -350.333301)
			(xy 298.076874 -350.326452) (xy 298.080485 -350.323892) (xy 298.086876 -350.317769) (xy 298.089574 -350.31426)
			(xy 298.104968 -350.293494) (xy 298.140511 -350.255958) (xy 298.180798 -350.223566) (xy 298.22509 -350.196912)
			(xy 298.272576 -350.176484) (xy 298.322386 -350.162657) (xy 298.373607 -350.155683) (xy 298.399454 -350.155256)
			(xy 298.426704 -350.155798) (xy 298.48065 -350.163548) (xy 298.532945 -350.178896) (xy 298.582522 -350.201531)
			(xy 298.628374 -350.230991) (xy 298.669566 -350.266676) (xy 298.70526 -350.307861) (xy 298.73473 -350.353706)
			(xy 298.757375 -350.403279) (xy 298.772735 -350.455569) (xy 298.780496 -350.509514) (xy 298.780962 -350.536764)
			(xy 298.780464 -350.564238) (xy 298.772576 -350.618618) (xy 298.756959 -350.6713) (xy 298.754306 -350.67705)
			(xy 299.022772 -350.67705) (xy 299.022772 -350.62255) (xy 299.030528 -350.568604) (xy 299.045881 -350.516311)
			(xy 299.068521 -350.466735) (xy 299.097985 -350.420885) (xy 299.133674 -350.379695) (xy 299.174861 -350.344003)
			(xy 299.220708 -350.314535) (xy 299.270282 -350.291892) (xy 299.322574 -350.276534) (xy 299.37652 -350.268774)
			(xy 299.40377 -350.268286) (xy 299.429006 -350.268654) (xy 299.479041 -350.275281) (xy 299.527762 -350.288463)
			(xy 299.574312 -350.307967) (xy 299.596302 -350.320356) (xy 299.605954 -350.326198) (xy 299.628052 -350.32823)
			(xy 299.72254 -350.294702) (xy 299.738542 -350.279208) (xy 299.742606 -350.268794) (xy 299.753277 -350.242007)
			(xy 299.781568 -350.191764) (xy 299.817101 -350.146354) (xy 299.859066 -350.106811) (xy 299.906507 -350.074039)
			(xy 299.958342 -350.048783) (xy 300.013389 -350.03162) (xy 300.070392 -350.022941) (xy 300.099222 -350.022414)
			(xy 300.126475 -350.022857) (xy 300.180425 -350.030617) (xy 300.232722 -350.045977) (xy 300.282301 -350.068622)
			(xy 300.328152 -350.098092) (xy 300.369343 -350.133788) (xy 300.405034 -350.174983) (xy 300.434499 -350.220838)
			(xy 300.457139 -350.270419) (xy 300.46986 -350.313752) (xy 302.610774 -350.313752) (xy 302.611285 -350.286179)
			(xy 302.619229 -350.231609) (xy 302.634946 -350.17875) (xy 302.658108 -350.128704) (xy 302.688232 -350.082513)
			(xy 302.724691 -350.04114) (xy 302.745394 -350.022922) (xy 302.753497 -350.015306) (xy 302.76286 -349.995165)
			(xy 302.763428 -349.98406) (xy 302.763428 -349.906844) (xy 302.762875 -349.895732) (xy 302.753528 -349.875572)
			(xy 302.745394 -349.867982) (xy 302.72467 -349.849785) (xy 302.688201 -349.808413) (xy 302.65807 -349.76222)
			(xy 302.634907 -349.71217) (xy 302.619193 -349.659304) (xy 302.611257 -349.604728) (xy 302.610774 -349.577152)
			(xy 302.611233 -349.5499) (xy 302.618996 -349.495953) (xy 302.634356 -349.443659) (xy 302.657001 -349.394082)
			(xy 302.686471 -349.348233) (xy 302.722165 -349.307044) (xy 302.763357 -349.271353) (xy 302.809209 -349.241887)
			(xy 302.858787 -349.219245) (xy 302.911082 -349.203889) (xy 302.96503 -349.196131) (xy 302.992282 -349.195644)
			(xy 303.026572 -349.197168) (xy 303.036732 -349.198184) (xy 303.056036 -349.192088) (xy 303.126648 -349.132906)
			(xy 303.136046 -349.114872) (xy 303.137062 -349.104712) (xy 303.140003 -349.076538) (xy 303.153181 -349.021447)
			(xy 303.174363 -348.968911) (xy 303.203083 -348.920087) (xy 303.238709 -348.876047) (xy 303.280457 -348.837761)
			(xy 303.327409 -348.806072) (xy 303.378531 -348.781676) (xy 303.4327 -348.76511) (xy 303.488723 -348.756738)
			(xy 303.517046 -348.756224) (xy 303.535065 -348.756444) (xy 303.57094 -348.759879) (xy 303.588674 -348.763082)
			(xy 303.598072 -348.76486) (xy 303.617122 -348.76105) (xy 303.692306 -348.713298) (xy 303.703736 -348.69755)
			(xy 303.706022 -348.688152) (xy 303.713412 -348.661106) (xy 303.735043 -348.609379) (xy 303.764008 -348.561373)
			(xy 303.799684 -348.518122) (xy 303.841305 -348.480555) (xy 303.887973 -348.449481) (xy 303.938685 -348.425569)
			(xy 303.99235 -348.409333) (xy 304.047813 -348.401122) (xy 304.075846 -348.400624) (xy 304.1031 -348.401035)
			(xy 304.157052 -348.408799) (xy 304.20935 -348.424161) (xy 304.25893 -348.44681) (xy 304.304781 -348.476284)
			(xy 304.345972 -348.511983) (xy 304.381663 -348.553181) (xy 304.411127 -348.599039) (xy 304.433766 -348.648623)
			(xy 304.449118 -348.700924) (xy 304.45687 -348.754878) (xy 304.457354 -348.782132) (xy 304.456858 -348.809706)
			(xy 304.448914 -348.864278) (xy 304.433196 -348.917138) (xy 304.410032 -348.967184) (xy 304.379904 -349.013375)
			(xy 304.34344 -349.054746) (xy 304.322734 -349.072962) (xy 304.314627 -349.080574) (xy 304.305269 -349.100719)
			(xy 304.3047 -349.111824) (xy 304.3047 -349.18904) (xy 304.30523 -349.200154) (xy 304.314596 -349.220313)
			(xy 304.322734 -349.227902) (xy 304.34347 -349.246084) (xy 304.37993 -349.287461) (xy 304.410054 -349.333656)
			(xy 304.433213 -349.383707) (xy 304.448924 -349.436571) (xy 304.456861 -349.491146) (xy 304.456858 -349.546295)
			(xy 304.448915 -349.60087) (xy 304.448339 -349.602806) (xy 305.58943 -349.602806) (xy 305.593501 -349.547184)
			(xy 305.605627 -349.492747) (xy 305.62555 -349.440656) (xy 305.652846 -349.392021) (xy 305.686932 -349.347878)
			(xy 305.727081 -349.309169) (xy 305.772439 -349.276718) (xy 305.822039 -349.251217) (xy 305.874823 -349.23321)
			(xy 305.929666 -349.22308) (xy 305.9854 -349.221043) (xy 306.040837 -349.227143) (xy 306.094794 -349.241249)
			(xy 306.146123 -349.263061) (xy 306.193729 -349.292115) (xy 306.236597 -349.32779) (xy 306.273814 -349.369327)
			(xy 306.304587 -349.41584) (xy 306.328259 -349.466337) (xy 306.344327 -349.519744) (xy 306.352447 -349.57492)
			(xy 306.352956 -349.602806) (xy 306.352447 -349.630692) (xy 306.344327 -349.685868) (xy 306.328259 -349.739275)
			(xy 306.304587 -349.789772) (xy 306.273814 -349.836285) (xy 306.236597 -349.877822) (xy 306.193729 -349.913497)
			(xy 306.146123 -349.942551) (xy 306.094794 -349.964363) (xy 306.040837 -349.978469) (xy 305.9854 -349.984569)
			(xy 305.929666 -349.982532) (xy 305.874823 -349.972402) (xy 305.822039 -349.954395) (xy 305.772439 -349.928894)
			(xy 305.727081 -349.896443) (xy 305.686932 -349.857734) (xy 305.652846 -349.813591) (xy 305.62555 -349.764956)
			(xy 305.605627 -349.712865) (xy 305.593501 -349.658428) (xy 305.58943 -349.602806) (xy 304.448339 -349.602806)
			(xy 304.433198 -349.653732) (xy 304.410034 -349.70378) (xy 304.379905 -349.749972) (xy 304.34344 -349.791345)
			(xy 304.322734 -349.809562) (xy 304.314627 -349.817174) (xy 304.305269 -349.837319) (xy 304.3047 -349.848424)
			(xy 304.3047 -349.92564) (xy 304.30523 -349.936754) (xy 304.314596 -349.956913) (xy 304.322734 -349.964502)
			(xy 304.343456 -349.982701) (xy 304.379924 -350.024073) (xy 304.410054 -350.070266) (xy 304.433218 -350.120316)
			(xy 304.448932 -350.17318) (xy 304.45687 -350.227757) (xy 304.457354 -350.255332) (xy 304.456852 -350.282582)
			(xy 304.449092 -350.336527) (xy 304.433736 -350.388818) (xy 304.411094 -350.438393) (xy 304.381629 -350.484241)
			(xy 304.369571 -350.498156) (xy 305.01031 -350.498156) (xy 305.014381 -350.442534) (xy 305.026507 -350.388097)
			(xy 305.04643 -350.336006) (xy 305.073726 -350.287371) (xy 305.107812 -350.243228) (xy 305.147961 -350.204519)
			(xy 305.193319 -350.172068) (xy 305.242919 -350.146567) (xy 305.295703 -350.12856) (xy 305.350546 -350.11843)
			(xy 305.40628 -350.116393) (xy 305.461717 -350.122493) (xy 305.515674 -350.136599) (xy 305.567003 -350.158411)
			(xy 305.614609 -350.187465) (xy 305.657477 -350.22314) (xy 305.694694 -350.264677) (xy 305.725467 -350.31119)
			(xy 305.749139 -350.361687) (xy 305.765207 -350.415094) (xy 305.773327 -350.47027) (xy 305.773836 -350.498156)
			(xy 305.773327 -350.526042) (xy 305.765207 -350.581218) (xy 305.749139 -350.634625) (xy 305.725467 -350.685122)
			(xy 305.694694 -350.731635) (xy 305.657477 -350.773172) (xy 305.614609 -350.808847) (xy 305.567003 -350.837901)
			(xy 305.515674 -350.859713) (xy 305.461717 -350.873819) (xy 305.40628 -350.879919) (xy 305.350546 -350.877882)
			(xy 305.295703 -350.867752) (xy 305.242919 -350.849745) (xy 305.193319 -350.824244) (xy 305.147961 -350.791793)
			(xy 305.107812 -350.753084) (xy 305.073726 -350.708941) (xy 305.04643 -350.660306) (xy 305.026507 -350.608215)
			(xy 305.014381 -350.553778) (xy 305.01031 -350.498156) (xy 304.369571 -350.498156) (xy 304.345939 -350.525429)
			(xy 304.304752 -350.56112) (xy 304.258905 -350.590587) (xy 304.209331 -350.613231) (xy 304.15704 -350.628589)
			(xy 304.103096 -350.636351) (xy 304.075846 -350.63684) (xy 304.047993 -350.636246) (xy 303.992882 -350.62813)
			(xy 303.939535 -350.612092) (xy 303.889085 -350.588474) (xy 303.842601 -350.557776) (xy 303.801071 -350.52065)
			(xy 303.765376 -350.477884) (xy 303.736273 -350.430385) (xy 303.714381 -350.379161) (xy 303.706784 -350.35236)
			(xy 303.704498 -350.34347) (xy 303.69383 -350.32823) (xy 303.621948 -350.280478) (xy 303.603914 -350.276414)
			(xy 303.59477 -350.277684) (xy 303.581754 -350.279354) (xy 303.555569 -350.281133) (xy 303.542446 -350.28124)
			(xy 303.528297 -350.281141) (xy 303.500074 -350.27911) (xy 303.486058 -350.277176) (xy 303.475898 -350.275652)
			(xy 303.45634 -350.280478) (xy 303.381918 -350.336358) (xy 303.371758 -350.353884) (xy 303.370488 -350.364044)
			(xy 303.366427 -350.391202) (xy 303.351453 -350.444035) (xy 303.329059 -350.494175) (xy 303.299709 -350.540587)
			(xy 303.264009 -350.582312) (xy 303.222695 -350.618488) (xy 303.176623 -350.648368) (xy 303.126743 -350.671335)
			(xy 303.074086 -350.686914) (xy 303.019739 -350.694784) (xy 302.992282 -350.69526) (xy 302.965026 -350.694862)
			(xy 302.911071 -350.687101) (xy 302.858769 -350.67174) (xy 302.809185 -350.649092) (xy 302.76333 -350.619618)
			(xy 302.722136 -350.583917) (xy 302.686443 -350.542717) (xy 302.656976 -350.496857) (xy 302.634337 -350.447269)
			(xy 302.618985 -350.394965) (xy 302.611234 -350.341008) (xy 302.610774 -350.313752) (xy 300.46986 -350.313752)
			(xy 300.472492 -350.322718) (xy 300.480246 -350.376669) (xy 300.48073 -350.403922) (xy 300.48006 -350.435484)
			(xy 300.469676 -350.497749) (xy 300.449195 -350.557459) (xy 300.434756 -350.585532) (xy 300.42993 -350.594422)
			(xy 300.427898 -350.61398) (xy 300.453552 -350.702118) (xy 300.465998 -350.717612) (xy 300.474888 -350.722692)
			(xy 300.500011 -350.737205) (xy 300.545894 -350.772714) (xy 300.585868 -350.814763) (xy 300.619012 -350.862383)
			(xy 300.644559 -350.914474) (xy 300.66192 -350.969834) (xy 300.670695 -351.027185) (xy 300.67123 -351.056194)
			(xy 300.670744 -351.083445) (xy 300.662988 -351.137393) (xy 300.647633 -351.189688) (xy 300.624991 -351.239265)
			(xy 300.595525 -351.285115) (xy 300.559834 -351.326306) (xy 300.518643 -351.361997) (xy 300.472793 -351.391463)
			(xy 300.423216 -351.414105) (xy 300.370921 -351.42946) (xy 300.316973 -351.437216) (xy 300.262471 -351.437216)
			(xy 300.208523 -351.42946) (xy 300.156228 -351.414105) (xy 300.106651 -351.391463) (xy 300.060801 -351.361997)
			(xy 300.01961 -351.326306) (xy 299.983919 -351.285115) (xy 299.954453 -351.239265) (xy 299.931811 -351.189688)
			(xy 299.916456 -351.137393) (xy 299.9087 -351.083445) (xy 299.908214 -351.056194) (xy 299.908885 -351.024632)
			(xy 299.919267 -350.962367) (xy 299.939749 -350.902657) (xy 299.954188 -350.874584) (xy 299.959014 -350.865694)
			(xy 299.961046 -350.846136) (xy 299.935392 -350.757998) (xy 299.922946 -350.742504) (xy 299.914056 -350.737424)
			(xy 299.90669 -350.73336) (xy 299.897038 -350.727518) (xy 299.87494 -350.725486) (xy 299.780452 -350.759014)
			(xy 299.76445 -350.774508) (xy 299.760386 -350.784922) (xy 299.74973 -350.811715) (xy 299.721437 -350.861958)
			(xy 299.685901 -350.907368) (xy 299.643933 -350.94691) (xy 299.59649 -350.979681) (xy 299.544654 -351.004936)
			(xy 299.489605 -351.022098) (xy 299.432601 -351.030775) (xy 299.40377 -351.031302) (xy 299.37652 -351.030826)
			(xy 299.322574 -351.023066) (xy 299.270282 -351.007708) (xy 299.220708 -350.985065) (xy 299.174861 -350.955597)
			(xy 299.133674 -350.919905) (xy 299.097985 -350.878715) (xy 299.068521 -350.832865) (xy 299.045881 -350.783289)
			(xy 299.030528 -350.730996) (xy 299.022772 -350.67705) (xy 298.754306 -350.67705) (xy 298.733937 -350.721193)
			(xy 298.703987 -350.767262) (xy 298.68622 -350.788224) (xy 298.680124 -350.795336) (xy 298.673774 -350.812354)
			(xy 298.673774 -350.898206) (xy 298.680124 -350.915224) (xy 298.68622 -350.922336) (xy 298.703985 -350.943297)
			(xy 298.733909 -350.98938) (xy 298.756921 -351.039274) (xy 298.772547 -351.091951) (xy 298.780463 -351.146324)
			(xy 298.780962 -351.173796) (xy 298.780522 -351.201426) (xy 298.772576 -351.256111) (xy 298.756822 -351.309077)
			(xy 298.733589 -351.359216) (xy 298.703364 -351.405476) (xy 298.666778 -351.44689) (xy 298.6246 -351.482591)
			(xy 298.57771 -351.511832) (xy 298.527092 -351.533999) (xy 298.473804 -351.548629) (xy 298.446444 -351.55251)
			(xy 298.427394 -351.554796) (xy 298.40174 -351.583498) (xy 298.40174 -351.658936) (xy 298.402136 -351.669009)
			(xy 298.409876 -351.687607) (xy 298.416726 -351.695004) (xy 298.84751 -352.125788) (xy 298.854992 -352.13248)
			(xy 298.873551 -352.14007) (xy 298.883578 -352.14052) (xy 304.592228 -352.14052) (xy 304.617225 -352.14114)
			(xy 304.666248 -352.150949) (xy 304.712418 -352.170128) (xy 304.753964 -352.197939) (xy 304.77206 -352.215196)
			(xy 307.060854 -354.50399) (xy 307.068658 -354.51099) (xy 307.088156 -354.518628) (xy 307.109086 -354.517918)
			(xy 307.118766 -354.513896) (xy 307.219858 -354.465382) (xy 307.235352 -354.437442) (xy 307.233574 -354.421186)
			(xy 307.232598 -354.411118) (xy 307.231581 -354.390915) (xy 307.231542 -354.3808) (xy 307.232092 -354.351613)
			(xy 307.240992 -354.29392) (xy 307.258568 -354.238254) (xy 307.284413 -354.185911) (xy 307.317922 -354.138112)
			(xy 307.358316 -354.095969) (xy 307.381148 -354.077778) (xy 307.391054 -354.070412) (xy 307.401468 -354.048568)
			(xy 307.398674 -353.941888) (xy 307.387244 -353.920552) (xy 307.377084 -353.913694) (xy 307.355646 -353.898378)
			(xy 307.316848 -353.862732) (xy 307.283322 -353.822087) (xy 307.255704 -353.777219) (xy 307.234519 -353.728978)
			(xy 307.220171 -353.678281) (xy 307.212932 -353.626094) (xy 307.212492 -353.59975) (xy 307.212979 -353.573243)
			(xy 307.220338 -353.520741) (xy 307.234895 -353.469763) (xy 307.256368 -353.421292) (xy 307.284344 -353.376259)
			(xy 307.318285 -353.335533) (xy 307.357537 -353.299897) (xy 307.401343 -353.270038) (xy 307.448862 -353.246531)
			(xy 307.499177 -353.229828) (xy 307.525166 -353.224592) (xy 307.53304 -353.223068) (xy 307.546248 -353.21621)
			(xy 307.551836 -353.210368) (xy 307.55859 -353.203004) (xy 307.566217 -353.184551) (xy 307.566204 -353.164584)
			(xy 307.558554 -353.146141) (xy 307.551836 -353.13874) (xy 307.495194 -353.081844) (xy 307.487707 -353.075158)
			(xy 307.469152 -353.067564) (xy 307.459126 -353.067112) (xy 306.747418 -353.067112) (xy 306.722421 -353.066484)
			(xy 306.673397 -353.05668) (xy 306.627226 -353.037505) (xy 306.585681 -353.009693) (xy 306.567586 -352.992436)
			(xy 305.841654 -352.266504) (xy 305.82442 -352.248404) (xy 305.796681 -352.206842) (xy 305.777577 -352.160668)
			(xy 305.76784 -352.111657) (xy 305.767232 -352.086672) (xy 305.767232 -351.066608) (xy 305.767872 -351.041626)
			(xy 305.777607 -350.99262) (xy 305.796706 -350.94645) (xy 305.824437 -350.904888) (xy 305.841654 -350.886776)
			(xy 306.371498 -350.356932) (xy 306.379993 -350.348565) (xy 306.398314 -350.333301) (xy 306.408074 -350.326452)
			(xy 306.411685 -350.323892) (xy 306.418076 -350.317769) (xy 306.420774 -350.31426) (xy 306.436168 -350.293494)
			(xy 306.471711 -350.255958) (xy 306.511998 -350.223566) (xy 306.55629 -350.196912) (xy 306.603776 -350.176484)
			(xy 306.653586 -350.162657) (xy 306.704807 -350.155683) (xy 306.730654 -350.155256) (xy 306.757904 -350.155798)
			(xy 306.81185 -350.163548) (xy 306.864145 -350.178896) (xy 306.913722 -350.201531) (xy 306.959574 -350.230991)
			(xy 307.000766 -350.266676) (xy 307.03646 -350.307861) (xy 307.06593 -350.353706) (xy 307.088575 -350.403279)
			(xy 307.103935 -350.455569) (xy 307.111696 -350.509514) (xy 307.112162 -350.536764) (xy 307.111664 -350.564238)
			(xy 307.103776 -350.618618) (xy 307.088159 -350.6713) (xy 307.085506 -350.67705) (xy 307.353972 -350.67705)
			(xy 307.353972 -350.62255) (xy 307.361728 -350.568604) (xy 307.377081 -350.516311) (xy 307.399721 -350.466735)
			(xy 307.429185 -350.420885) (xy 307.464874 -350.379695) (xy 307.506061 -350.344003) (xy 307.551908 -350.314535)
			(xy 307.601482 -350.291892) (xy 307.653774 -350.276534) (xy 307.70772 -350.268774) (xy 307.73497 -350.268286)
			(xy 307.760206 -350.268654) (xy 307.810241 -350.275281) (xy 307.858962 -350.288463) (xy 307.905512 -350.307967)
			(xy 307.927502 -350.320356) (xy 307.937154 -350.326198) (xy 307.959252 -350.32823) (xy 308.05374 -350.294702)
			(xy 308.069742 -350.279208) (xy 308.073806 -350.268794) (xy 308.084477 -350.242007) (xy 308.112768 -350.191764)
			(xy 308.148301 -350.146354) (xy 308.190266 -350.106811) (xy 308.237707 -350.074039) (xy 308.289542 -350.048783)
			(xy 308.344589 -350.03162) (xy 308.401592 -350.022941) (xy 308.430422 -350.022414) (xy 308.457675 -350.022857)
			(xy 308.511625 -350.030617) (xy 308.563922 -350.045977) (xy 308.613501 -350.068622) (xy 308.659352 -350.098092)
			(xy 308.700543 -350.133788) (xy 308.736234 -350.174983) (xy 308.765699 -350.220838) (xy 308.788339 -350.270419)
			(xy 308.80106 -350.313752) (xy 310.941974 -350.313752) (xy 310.942485 -350.286179) (xy 310.950429 -350.231609)
			(xy 310.966146 -350.17875) (xy 310.989308 -350.128704) (xy 311.019432 -350.082513) (xy 311.055891 -350.04114)
			(xy 311.076594 -350.022922) (xy 311.084697 -350.015306) (xy 311.09406 -349.995165) (xy 311.094628 -349.98406)
			(xy 311.094628 -349.906844) (xy 311.094075 -349.895732) (xy 311.084728 -349.875572) (xy 311.076594 -349.867982)
			(xy 311.05587 -349.849785) (xy 311.019401 -349.808413) (xy 310.98927 -349.76222) (xy 310.966107 -349.71217)
			(xy 310.950393 -349.659304) (xy 310.942457 -349.604728) (xy 310.941974 -349.577152) (xy 310.942433 -349.5499)
			(xy 310.950196 -349.495953) (xy 310.965556 -349.443659) (xy 310.988201 -349.394082) (xy 311.017671 -349.348233)
			(xy 311.053365 -349.307044) (xy 311.094557 -349.271353) (xy 311.140409 -349.241887) (xy 311.189987 -349.219245)
			(xy 311.242282 -349.203889) (xy 311.29623 -349.196131) (xy 311.323482 -349.195644) (xy 311.357772 -349.197168)
			(xy 311.367932 -349.198184) (xy 311.387236 -349.192088) (xy 311.457848 -349.132906) (xy 311.467246 -349.114872)
			(xy 311.468262 -349.104712) (xy 311.471203 -349.076538) (xy 311.484381 -349.021447) (xy 311.505563 -348.968911)
			(xy 311.534283 -348.920087) (xy 311.569909 -348.876047) (xy 311.611657 -348.837761) (xy 311.658609 -348.806072)
			(xy 311.709731 -348.781676) (xy 311.7639 -348.76511) (xy 311.819923 -348.756738) (xy 311.848246 -348.756224)
			(xy 311.866265 -348.756444) (xy 311.90214 -348.759879) (xy 311.919874 -348.763082) (xy 311.929272 -348.76486)
			(xy 311.948322 -348.76105) (xy 312.023506 -348.713298) (xy 312.034936 -348.69755) (xy 312.037222 -348.688152)
			(xy 312.044612 -348.661106) (xy 312.066243 -348.609379) (xy 312.095208 -348.561373) (xy 312.130884 -348.518122)
			(xy 312.172505 -348.480555) (xy 312.219173 -348.449481) (xy 312.269885 -348.425569) (xy 312.32355 -348.409333)
			(xy 312.379013 -348.401122) (xy 312.407046 -348.400624) (xy 312.4343 -348.401035) (xy 312.488252 -348.408799)
			(xy 312.54055 -348.424161) (xy 312.59013 -348.44681) (xy 312.635981 -348.476284) (xy 312.677172 -348.511983)
			(xy 312.712863 -348.553181) (xy 312.742327 -348.599039) (xy 312.764966 -348.648623) (xy 312.780318 -348.700924)
			(xy 312.78807 -348.754878) (xy 312.788554 -348.782132) (xy 312.788058 -348.809706) (xy 312.780114 -348.864278)
			(xy 312.764396 -348.917138) (xy 312.741232 -348.967184) (xy 312.711104 -349.013375) (xy 312.67464 -349.054746)
			(xy 312.653934 -349.072962) (xy 312.645827 -349.080574) (xy 312.636469 -349.100719) (xy 312.6359 -349.111824)
			(xy 312.6359 -349.18904) (xy 312.63643 -349.200154) (xy 312.645796 -349.220313) (xy 312.653934 -349.227902)
			(xy 312.67467 -349.246084) (xy 312.71113 -349.287461) (xy 312.741254 -349.333656) (xy 312.764413 -349.383707)
			(xy 312.780124 -349.436571) (xy 312.788061 -349.491146) (xy 312.788058 -349.546295) (xy 312.780115 -349.60087)
			(xy 312.764398 -349.653732) (xy 312.741234 -349.70378) (xy 312.711105 -349.749972) (xy 312.67464 -349.791345)
			(xy 312.653934 -349.809562) (xy 312.645827 -349.817174) (xy 312.636469 -349.837319) (xy 312.6359 -349.848424)
			(xy 312.6359 -349.92564) (xy 312.63643 -349.936754) (xy 312.645796 -349.956913) (xy 312.653934 -349.964502)
			(xy 312.674656 -349.982701) (xy 312.711124 -350.024073) (xy 312.741254 -350.070266) (xy 312.764418 -350.120316)
			(xy 312.780132 -350.17318) (xy 312.78807 -350.227757) (xy 312.788554 -350.255332) (xy 312.788052 -350.282582)
			(xy 312.780292 -350.336527) (xy 312.764936 -350.388818) (xy 312.742294 -350.438393) (xy 312.712829 -350.484241)
			(xy 312.677139 -350.525429) (xy 312.635952 -350.56112) (xy 312.590105 -350.590587) (xy 312.540531 -350.613231)
			(xy 312.48824 -350.628589) (xy 312.434296 -350.636351) (xy 312.407046 -350.63684) (xy 312.379193 -350.636246)
			(xy 312.324082 -350.62813) (xy 312.270735 -350.612092) (xy 312.220285 -350.588474) (xy 312.173801 -350.557776)
			(xy 312.132271 -350.52065) (xy 312.096576 -350.477884) (xy 312.067473 -350.430385) (xy 312.045581 -350.379161)
			(xy 312.037984 -350.35236) (xy 312.035698 -350.34347) (xy 312.02503 -350.32823) (xy 311.953148 -350.280478)
			(xy 311.935114 -350.276414) (xy 311.92597 -350.277684) (xy 311.912954 -350.279354) (xy 311.886769 -350.281133)
			(xy 311.873646 -350.28124) (xy 311.859497 -350.281141) (xy 311.831274 -350.27911) (xy 311.817258 -350.277176)
			(xy 311.807098 -350.275652) (xy 311.78754 -350.280478) (xy 311.713118 -350.336358) (xy 311.702958 -350.353884)
			(xy 311.701688 -350.364044) (xy 311.697627 -350.391202) (xy 311.682653 -350.444035) (xy 311.660259 -350.494175)
			(xy 311.630909 -350.540587) (xy 311.595209 -350.582312) (xy 311.553895 -350.618488) (xy 311.507823 -350.648368)
			(xy 311.457943 -350.671335) (xy 311.405286 -350.686914) (xy 311.350939 -350.694784) (xy 311.323482 -350.69526)
			(xy 311.296226 -350.694862) (xy 311.242271 -350.687101) (xy 311.189969 -350.67174) (xy 311.140385 -350.649092)
			(xy 311.09453 -350.619618) (xy 311.053336 -350.583917) (xy 311.017643 -350.542717) (xy 310.988176 -350.496857)
			(xy 310.965537 -350.447269) (xy 310.950185 -350.394965) (xy 310.942434 -350.341008) (xy 310.941974 -350.313752)
			(xy 308.80106 -350.313752) (xy 308.803692 -350.322718) (xy 308.811446 -350.376669) (xy 308.81193 -350.403922)
			(xy 308.81126 -350.435484) (xy 308.800876 -350.497749) (xy 308.780395 -350.557459) (xy 308.765956 -350.585532)
			(xy 308.76113 -350.594422) (xy 308.759098 -350.61398) (xy 308.784752 -350.702118) (xy 308.797198 -350.717612)
			(xy 308.806088 -350.722692) (xy 308.831211 -350.737205) (xy 308.877094 -350.772714) (xy 308.917068 -350.814763)
			(xy 308.950212 -350.862383) (xy 308.975759 -350.914474) (xy 308.99312 -350.969834) (xy 309.001895 -351.027185)
			(xy 309.00243 -351.056194) (xy 309.001944 -351.083445) (xy 308.994188 -351.137393) (xy 308.978833 -351.189688)
			(xy 308.956191 -351.239265) (xy 308.926725 -351.285115) (xy 308.891034 -351.326306) (xy 308.849843 -351.361997)
			(xy 308.803993 -351.391463) (xy 308.754416 -351.414105) (xy 308.702121 -351.42946) (xy 308.648173 -351.437216)
			(xy 308.593671 -351.437216) (xy 308.539723 -351.42946) (xy 308.487428 -351.414105) (xy 308.437851 -351.391463)
			(xy 308.392001 -351.361997) (xy 308.35081 -351.326306) (xy 308.315119 -351.285115) (xy 308.285653 -351.239265)
			(xy 308.263011 -351.189688) (xy 308.247656 -351.137393) (xy 308.2399 -351.083445) (xy 308.239414 -351.056194)
			(xy 308.240085 -351.024632) (xy 308.250467 -350.962367) (xy 308.270949 -350.902657) (xy 308.285388 -350.874584)
			(xy 308.290214 -350.865694) (xy 308.292246 -350.846136) (xy 308.266592 -350.757998) (xy 308.254146 -350.742504)
			(xy 308.245256 -350.737424) (xy 308.23789 -350.73336) (xy 308.228238 -350.727518) (xy 308.20614 -350.725486)
			(xy 308.111652 -350.759014) (xy 308.09565 -350.774508) (xy 308.091586 -350.784922) (xy 308.08093 -350.811715)
			(xy 308.052637 -350.861958) (xy 308.017101 -350.907368) (xy 307.975133 -350.94691) (xy 307.92769 -350.979681)
			(xy 307.875854 -351.004936) (xy 307.820805 -351.022098) (xy 307.763801 -351.030775) (xy 307.73497 -351.031302)
			(xy 307.70772 -351.030826) (xy 307.653774 -351.023066) (xy 307.601482 -351.007708) (xy 307.551908 -350.985065)
			(xy 307.506061 -350.955597) (xy 307.464874 -350.919905) (xy 307.429185 -350.878715) (xy 307.399721 -350.832865)
			(xy 307.377081 -350.783289) (xy 307.361728 -350.730996) (xy 307.353972 -350.67705) (xy 307.085506 -350.67705)
			(xy 307.065137 -350.721193) (xy 307.035187 -350.767262) (xy 307.01742 -350.788224) (xy 307.011324 -350.795336)
			(xy 307.004974 -350.812354) (xy 307.004974 -350.898206) (xy 307.011324 -350.915224) (xy 307.01742 -350.922336)
			(xy 307.035185 -350.943297) (xy 307.065109 -350.98938) (xy 307.088121 -351.039274) (xy 307.103747 -351.091951)
			(xy 307.111663 -351.146324) (xy 307.112162 -351.173796) (xy 307.11174 -351.201074) (xy 307.103969 -351.255074)
			(xy 307.088585 -351.307416) (xy 307.065903 -351.357033) (xy 307.036384 -351.402912) (xy 307.00063 -351.44412)
			(xy 306.959372 -351.479814) (xy 306.913449 -351.509267) (xy 306.863799 -351.531878) (xy 306.811435 -351.547186)
			(xy 306.757425 -351.554878) (xy 306.730146 -351.555304) (xy 306.719732 -351.555304) (xy 306.70119 -351.562924)
			(xy 306.67833 -351.585784) (xy 306.671509 -351.593199) (xy 306.663777 -351.611787) (xy 306.663344 -351.621852)
			(xy 306.663344 -351.799398) (xy 306.663759 -351.809469) (xy 306.671486 -351.828067) (xy 306.67833 -351.835466)
			(xy 306.998624 -352.15576) (xy 307.006104 -352.162455) (xy 307.024664 -352.170044) (xy 307.034692 -352.170492)
			(xy 307.7464 -352.170492) (xy 307.771397 -352.171108) (xy 307.820422 -352.180915) (xy 307.866593 -352.200095)
			(xy 307.908138 -352.227909) (xy 307.926232 -352.245168) (xy 309.244492 -353.563428) (xy 309.2513 -353.569603)
			(xy 309.268069 -353.577094) (xy 309.286402 -353.578208) (xy 309.295292 -353.575874) (xy 309.39486 -353.54514)
			(xy 309.413402 -353.524312) (xy 309.416196 -353.510342) (xy 309.42153 -353.484447) (xy 309.438351 -353.434327)
			(xy 309.461934 -353.38701) (xy 309.491825 -353.343404) (xy 309.527453 -353.304344) (xy 309.568133 -353.270579)
			(xy 309.613088 -353.242755) (xy 309.661454 -353.221408) (xy 309.712305 -353.206944) (xy 309.764666 -353.199643)
			(xy 309.7911 -353.199192) (xy 309.818351 -353.199678) (xy 309.872299 -353.207434) (xy 309.924594 -353.222789)
			(xy 309.974171 -353.245431) (xy 310.020021 -353.274897) (xy 310.061212 -353.310588) (xy 310.096903 -353.351779)
			(xy 310.126369 -353.397629) (xy 310.149011 -353.447206) (xy 310.164366 -353.499501) (xy 310.172122 -353.553449)
			(xy 310.172608 -353.5807) (xy 310.172495 -353.593183) (xy 310.170842 -353.618095) (xy 310.169306 -353.630484)
			(xy 310.167782 -353.64166) (xy 310.174132 -353.662234) (xy 310.23179 -353.72802) (xy 310.239352 -353.735891)
			(xy 310.259238 -353.74484) (xy 310.270144 -353.745292) (xy 310.597296 -353.745292) (xy 310.609327 -353.744648)
			(xy 310.630791 -353.733771) (xy 310.638444 -353.724464) (xy 310.654635 -353.703037) (xy 310.692003 -353.664467)
			(xy 310.734409 -353.631516) (xy 310.781015 -353.604835) (xy 310.830901 -353.584951) (xy 310.856884 -353.57816)
			(xy 310.873902 -353.574096) (xy 310.895492 -353.54641) (xy 310.895492 -352.9584) (xy 310.896108 -352.933403)
			(xy 310.905915 -352.884378) (xy 310.925095 -352.838207) (xy 310.952909 -352.796662) (xy 310.970168 -352.778568)
			(xy 313.637168 -350.111568) (xy 313.655226 -350.094267) (xy 313.69678 -350.066452) (xy 313.742963 -350.047279)
			(xy 313.791998 -350.037484) (xy 313.817 -350.036892) (xy 317.669164 -350.036892) (xy 317.67921 -350.036533)
			(xy 317.697806 -350.028936) (xy 317.705232 -350.02216) (xy 326.501252 -341.22614) (xy 326.519338 -341.208873)
			(xy 326.560885 -341.181063) (xy 326.60706 -341.161892) (xy 326.656087 -341.152098) (xy 326.681084 -341.151464)
			(xy 339.894672 -341.151464) (xy 339.90472 -341.151116) (xy 339.923316 -341.143512) (xy 339.93074 -341.136732)
			(xy 340.460584 -340.606888) (xy 340.467276 -340.599406) (xy 340.474866 -340.580847) (xy 340.475316 -340.57082)
			(xy 340.475316 -339.44052) (xy 340.475966 -339.415525) (xy 340.485766 -339.366503) (xy 340.504936 -339.320332)
			(xy 340.532739 -339.278785) (xy 340.549992 -339.260688) (xy 341.048594 -338.762086) (xy 341.054944 -338.751164)
			(xy 341.056722 -338.744306) (xy 341.064478 -338.71776) (xy 341.086618 -338.667081) (xy 341.115842 -338.620128)
			(xy 341.151537 -338.577886) (xy 341.192956 -338.541239) (xy 341.239231 -338.510954) (xy 341.289393 -338.487666)
			(xy 341.342392 -338.471863) (xy 341.397116 -338.463876) (xy 341.424768 -338.463382) (xy 341.45202 -338.463885)
			(xy 341.505969 -338.471637) (xy 341.558265 -338.486989) (xy 341.607844 -338.509627) (xy 341.653697 -338.539091)
			(xy 341.69489 -338.57478) (xy 341.730584 -338.615969) (xy 341.760053 -338.661819) (xy 341.782696 -338.711396)
			(xy 341.798054 -338.76369) (xy 341.805812 -338.817638) (xy 341.806276 -338.84489) (xy 341.80579 -338.872365)
			(xy 341.797899 -338.926745) (xy 341.782279 -338.979427) (xy 341.779638 -338.985149) (xy 342.048098 -338.985149)
			(xy 342.048098 -338.930651) (xy 342.055854 -338.876708) (xy 342.071207 -338.824417) (xy 342.093846 -338.774843)
			(xy 342.123309 -338.728996) (xy 342.158997 -338.687809) (xy 342.200183 -338.652119) (xy 342.246029 -338.622654)
			(xy 342.295602 -338.600013) (xy 342.347892 -338.584657) (xy 342.401835 -338.576899) (xy 342.429084 -338.576412)
			(xy 342.454321 -338.57677) (xy 342.504356 -338.5834) (xy 342.553076 -338.596584) (xy 342.599627 -338.616092)
			(xy 342.621616 -338.628482) (xy 342.631268 -338.634324) (xy 342.653366 -338.636356) (xy 342.747854 -338.602828)
			(xy 342.763856 -338.587334) (xy 342.76792 -338.57692) (xy 342.778594 -338.550134) (xy 342.806882 -338.499889)
			(xy 342.842414 -338.454478) (xy 342.884379 -338.414935) (xy 342.93182 -338.382161) (xy 342.983655 -338.356906)
			(xy 343.038702 -338.339744) (xy 343.095706 -338.331066) (xy 343.124536 -338.33054) (xy 343.151792 -338.330922)
			(xy 343.205748 -338.338685) (xy 343.258051 -338.354048) (xy 343.307634 -338.376698) (xy 343.35349 -338.406174)
			(xy 343.394683 -338.441876) (xy 343.430376 -338.483078) (xy 343.459842 -338.52894) (xy 343.482482 -338.578528)
			(xy 343.497833 -338.630834) (xy 343.505584 -338.684792) (xy 343.506044 -338.712048) (xy 343.505395 -338.743611)
			(xy 343.495004 -338.805877) (xy 343.474514 -338.865586) (xy 343.46007 -338.893658) (xy 343.455244 -338.902548)
			(xy 343.453212 -338.922106) (xy 343.478866 -339.010244) (xy 343.491312 -339.025738) (xy 343.500202 -339.030818)
			(xy 343.525296 -339.045378) (xy 343.571178 -339.08088) (xy 343.611153 -339.122922) (xy 343.644299 -339.170534)
			(xy 343.669851 -339.222617) (xy 343.687219 -339.277969) (xy 343.696003 -339.335313) (xy 343.696435 -339.358478)
			(xy 345.636088 -339.358478) (xy 345.636612 -339.330906) (xy 345.644553 -339.276335) (xy 345.660267 -339.223477)
			(xy 345.683426 -339.173431) (xy 345.713548 -339.12724) (xy 345.750006 -339.085866) (xy 345.770708 -339.067648)
			(xy 345.778802 -339.060023) (xy 345.788169 -339.039889) (xy 345.788742 -339.028786) (xy 345.788742 -338.95157)
			(xy 345.788225 -338.940453) (xy 345.778852 -338.920294) (xy 345.770708 -338.912708) (xy 345.74998 -338.894516)
			(xy 345.713516 -338.853142) (xy 345.683389 -338.806949) (xy 345.660227 -338.756899) (xy 345.644513 -338.704036)
			(xy 345.636575 -338.649461) (xy 345.636577 -338.594311) (xy 345.644519 -338.539737) (xy 345.660237 -338.486874)
			(xy 345.683403 -338.436826) (xy 345.713533 -338.390635) (xy 345.750001 -338.349264) (xy 345.770708 -338.331048)
			(xy 345.778802 -338.323423) (xy 345.788169 -338.303289) (xy 345.788742 -338.292186) (xy 345.788742 -338.21497)
			(xy 345.788225 -338.203853) (xy 345.778852 -338.183694) (xy 345.770708 -338.176108) (xy 345.749999 -338.157894)
			(xy 345.713528 -338.116526) (xy 345.683396 -338.070337) (xy 345.660229 -338.020289) (xy 345.644513 -337.967427)
			(xy 345.636573 -337.912853) (xy 345.636088 -337.885278) (xy 345.636557 -337.858026) (xy 345.644317 -337.804078)
			(xy 345.659674 -337.751783) (xy 345.682318 -337.702206) (xy 345.711786 -337.656356) (xy 345.747479 -337.615166)
			(xy 345.788671 -337.579475) (xy 345.834522 -337.550009) (xy 345.8841 -337.527368) (xy 345.936396 -337.512013)
			(xy 345.990344 -337.504256) (xy 346.017596 -337.50377) (xy 346.051886 -337.505294) (xy 346.062046 -337.50631)
			(xy 346.08135 -337.500214) (xy 346.151962 -337.441032) (xy 346.16136 -337.422998) (xy 346.162376 -337.412838)
			(xy 346.165325 -337.384665) (xy 346.1785 -337.329573) (xy 346.19968 -337.277036) (xy 346.228398 -337.228211)
			(xy 346.264023 -337.18417) (xy 346.305771 -337.145884) (xy 346.352722 -337.114194) (xy 346.403845 -337.089798)
			(xy 346.458014 -337.073233) (xy 346.514037 -337.064863) (xy 346.54236 -337.06435) (xy 346.569608 -337.064915)
			(xy 346.623551 -337.072665) (xy 346.675842 -337.088013) (xy 346.725416 -337.110647) (xy 346.771264 -337.140105)
			(xy 346.812454 -337.175788) (xy 346.848146 -337.21697) (xy 346.877614 -337.262812) (xy 346.900258 -337.312381)
			(xy 346.915617 -337.364669) (xy 346.923379 -337.41861) (xy 346.923868 -337.445858) (xy 346.923337 -337.473719)
			(xy 346.915242 -337.528849) (xy 346.899218 -337.582216) (xy 346.875606 -337.632687) (xy 346.844907 -337.679189)
			(xy 346.807773 -337.720733) (xy 346.786708 -337.738974) (xy 346.777564 -337.746594) (xy 346.767912 -337.767676)
			(xy 346.771468 -337.871562) (xy 346.78239 -337.892136) (xy 346.792042 -337.899248) (xy 346.8126 -337.914661)
			(xy 346.849734 -337.950174) (xy 346.881765 -337.990351) (xy 346.908113 -338.034465) (xy 346.9283 -338.081715)
			(xy 346.941963 -338.131248) (xy 346.948852 -338.182167) (xy 346.949268 -338.207858) (xy 346.948732 -338.236774)
			(xy 346.940008 -338.293945) (xy 346.922755 -338.349144) (xy 346.897366 -338.401106) (xy 346.864425 -338.448641)
			(xy 346.824687 -338.490658) (xy 346.802202 -338.508848) (xy 346.793423 -338.516394) (xy 346.783249 -338.537165)
			(xy 346.782644 -338.548726) (xy 346.782644 -338.62899) (xy 346.783205 -338.64056) (xy 346.793405 -338.661331)
			(xy 346.802202 -338.668868) (xy 346.822945 -338.68567) (xy 346.860078 -338.724016) (xy 346.891503 -338.767164)
			(xy 346.916606 -338.814272) (xy 346.934896 -338.864419) (xy 346.946016 -338.916626) (xy 346.94975 -338.969874)
			(xy 346.946024 -339.023123) (xy 346.93491 -339.075332) (xy 346.916627 -339.125481) (xy 346.891531 -339.172592)
			(xy 346.860112 -339.215745) (xy 346.822984 -339.254096) (xy 346.802202 -339.270848) (xy 346.793423 -339.278394)
			(xy 346.783249 -339.299165) (xy 346.782644 -339.310726) (xy 346.782644 -339.39099) (xy 346.783205 -339.40256)
			(xy 346.793405 -339.423331) (xy 346.802202 -339.430868) (xy 346.824671 -339.449077) (xy 346.864407 -339.491093)
			(xy 346.897347 -339.538624) (xy 346.922738 -339.590582) (xy 346.939998 -339.645776) (xy 346.948731 -339.702943)
			(xy 346.949268 -339.731858) (xy 346.948806 -339.759112) (xy 346.941053 -339.813065) (xy 346.9257 -339.865365)
			(xy 346.90306 -339.914948) (xy 346.873593 -339.960803) (xy 346.837899 -340.001997) (xy 346.796705 -340.037691)
			(xy 346.750849 -340.067159) (xy 346.701267 -340.0898) (xy 346.648967 -340.105153) (xy 346.595014 -340.112905)
			(xy 346.56776 -340.113366) (xy 346.539022 -340.112852) (xy 346.482198 -340.104211) (xy 346.427313 -340.087145)
			(xy 346.375608 -340.06204) (xy 346.328253 -340.029464) (xy 346.28632 -339.990155) (xy 346.250757 -339.945001)
			(xy 346.222368 -339.895024) (xy 346.201796 -339.841355) (xy 346.195142 -339.813392) (xy 346.192856 -339.80374)
			(xy 346.182188 -339.787738) (xy 346.10802 -339.737446) (xy 346.089224 -339.733382) (xy 346.079318 -339.734906)
			(xy 346.063998 -339.737279) (xy 346.033098 -339.739824) (xy 346.017596 -339.739986) (xy 345.990342 -339.739548)
			(xy 345.936389 -339.73179) (xy 345.884089 -339.716433) (xy 345.834508 -339.693788) (xy 345.788654 -339.664318)
			(xy 345.74746 -339.628621) (xy 345.711767 -339.587426) (xy 345.6823 -339.541569) (xy 345.659658 -339.491986)
			(xy 345.644304 -339.439685) (xy 345.63655 -339.385732) (xy 345.636088 -339.358478) (xy 343.696435 -339.358478)
			(xy 343.696544 -339.36432) (xy 343.696058 -339.391571) (xy 343.688302 -339.445519) (xy 343.672947 -339.497814)
			(xy 343.650305 -339.547391) (xy 343.620839 -339.593241) (xy 343.585148 -339.634432) (xy 343.543957 -339.670123)
			(xy 343.498107 -339.699589) (xy 343.44853 -339.722231) (xy 343.396235 -339.737586) (xy 343.342287 -339.745342)
			(xy 343.287785 -339.745342) (xy 343.233837 -339.737586) (xy 343.181542 -339.722231) (xy 343.131965 -339.699589)
			(xy 343.086115 -339.670123) (xy 343.044924 -339.634432) (xy 343.009233 -339.593241) (xy 342.979767 -339.547391)
			(xy 342.957125 -339.497814) (xy 342.94177 -339.445519) (xy 342.934014 -339.391571) (xy 342.933528 -339.36432)
			(xy 342.934168 -339.332756) (xy 342.944563 -339.27049) (xy 342.965057 -339.210782) (xy 342.979502 -339.18271)
			(xy 342.984328 -339.17382) (xy 342.98636 -339.154262) (xy 342.960706 -339.066124) (xy 342.94826 -339.05063)
			(xy 342.93937 -339.04555) (xy 342.932004 -339.041486) (xy 342.922352 -339.035644) (xy 342.900254 -339.033612)
			(xy 342.805766 -339.06714) (xy 342.789764 -339.082634) (xy 342.7857 -339.093048) (xy 342.775046 -339.119842)
			(xy 342.746751 -339.170084) (xy 342.711214 -339.215492) (xy 342.669246 -339.255033) (xy 342.621803 -339.287804)
			(xy 342.569967 -339.313059) (xy 342.514919 -339.330221) (xy 342.457915 -339.3389) (xy 342.429084 -339.339428)
			(xy 342.401835 -339.338901) (xy 342.347892 -339.331143) (xy 342.295602 -339.315787) (xy 342.246029 -339.293146)
			(xy 342.200183 -339.263681) (xy 342.158997 -339.227991) (xy 342.123309 -339.186804) (xy 342.093846 -339.140957)
			(xy 342.071207 -339.091383) (xy 342.055854 -339.039092) (xy 342.048098 -338.985149) (xy 341.779638 -338.985149)
			(xy 341.759254 -339.02932) (xy 341.729302 -339.075388) (xy 341.711534 -339.09635) (xy 341.705438 -339.103462)
			(xy 341.699088 -339.12048) (xy 341.699088 -339.206332) (xy 341.705438 -339.22335) (xy 341.711534 -339.230462)
			(xy 341.729266 -339.25145) (xy 341.759195 -339.297525) (xy 341.782213 -339.347413) (xy 341.797846 -339.400084)
			(xy 341.805772 -339.454451) (xy 341.806276 -339.481922) (xy 341.805864 -339.5092) (xy 341.79809 -339.563199)
			(xy 341.782704 -339.615541) (xy 341.76002 -339.665157) (xy 341.730499 -339.711036) (xy 341.694745 -339.752243)
			(xy 341.653485 -339.787936) (xy 341.607563 -339.817389) (xy 341.557913 -339.840001) (xy 341.505549 -339.85531)
			(xy 341.451539 -339.863004) (xy 341.42426 -339.86343) (xy 341.413846 -339.86343) (xy 341.395304 -339.87105)
			(xy 341.380064 -339.88629) (xy 341.373344 -339.89375) (xy 341.365769 -339.912325) (xy 341.365332 -339.922358)
			(xy 341.365332 -340.8553) (xy 341.364709 -340.880297) (xy 341.354903 -340.929321) (xy 341.335725 -340.975492)
			(xy 341.307913 -341.017037) (xy 341.290656 -341.035132) (xy 340.736428 -341.58936) (xy 347.60154 -341.58936)
			(xy 347.602021 -341.561449) (xy 347.610161 -341.506223) (xy 347.626259 -341.452773) (xy 347.649974 -341.402238)
			(xy 347.680799 -341.355698) (xy 347.699076 -341.334598) (xy 347.705426 -341.327486) (xy 347.71203 -341.310214)
			(xy 347.71203 -341.223092) (xy 347.705426 -341.20582) (xy 347.699076 -341.198708) (xy 347.680777 -341.177626)
			(xy 347.649953 -341.131083) (xy 347.626242 -341.080543) (xy 347.610151 -341.027088) (xy 347.602022 -340.971858)
			(xy 347.60154 -340.943946) (xy 347.602026 -340.916695) (xy 347.609782 -340.862747) (xy 347.625137 -340.810452)
			(xy 347.647779 -340.760875) (xy 347.677245 -340.715025) (xy 347.712936 -340.673834) (xy 347.754127 -340.638143)
			(xy 347.799977 -340.608677) (xy 347.849554 -340.586035) (xy 347.901849 -340.57068) (xy 347.955797 -340.562924)
			(xy 348.010299 -340.562924) (xy 348.064247 -340.57068) (xy 348.116542 -340.586035) (xy 348.166119 -340.608677)
			(xy 348.211969 -340.638143) (xy 348.25316 -340.673834) (xy 348.288851 -340.715025) (xy 348.318317 -340.760875)
			(xy 348.340959 -340.810452) (xy 348.356314 -340.862747) (xy 348.36407 -340.916695) (xy 348.364556 -340.943946)
			(xy 348.364079 -340.971857) (xy 348.355939 -341.027083) (xy 348.339839 -341.080534) (xy 348.316123 -341.131068)
			(xy 348.285297 -341.177608) (xy 348.26702 -341.198708) (xy 348.26067 -341.20582) (xy 348.254066 -341.223092)
			(xy 348.254066 -341.310214) (xy 348.26067 -341.327486) (xy 348.26702 -341.334598) (xy 348.285274 -341.355717)
			(xy 348.316105 -341.40225) (xy 348.339824 -341.45278) (xy 348.355926 -341.506227) (xy 348.364067 -341.56145)
			(xy 348.364556 -341.58936) (xy 348.36407 -341.616611) (xy 348.356314 -341.670559) (xy 348.340959 -341.722854)
			(xy 348.318317 -341.772431) (xy 348.288851 -341.818281) (xy 348.25316 -341.859472) (xy 348.211969 -341.895163)
			(xy 348.168809 -341.9229) (xy 351.983695 -341.9229) (xy 351.987864 -341.867274) (xy 352.000278 -341.812891)
			(xy 352.020658 -341.760965) (xy 352.04855 -341.712658) (xy 352.083331 -341.669047) (xy 352.124223 -341.631107)
			(xy 352.170314 -341.599686) (xy 352.220573 -341.575486) (xy 352.273878 -341.559047) (xy 352.329037 -341.550737)
			(xy 352.356928 -341.550244) (xy 352.38335 -341.550699) (xy 352.435665 -341.558151) (xy 352.486403 -341.572918)
			(xy 352.534547 -341.594702) (xy 352.579132 -341.623067) (xy 352.599498 -341.639906) (xy 352.606356 -341.646002)
			(xy 352.623374 -341.652098) (xy 352.707702 -341.652098) (xy 352.72472 -341.646002) (xy 352.731578 -341.639906)
			(xy 352.751944 -341.623067) (xy 352.79653 -341.594702) (xy 352.844674 -341.572915) (xy 352.895411 -341.558144)
			(xy 352.947726 -341.550684) (xy 353.00057 -341.550684) (xy 353.052885 -341.558144) (xy 353.103622 -341.572915)
			(xy 353.151766 -341.594702) (xy 353.196352 -341.623067) (xy 353.216718 -341.639906) (xy 353.223576 -341.646002)
			(xy 353.240594 -341.652098) (xy 353.324922 -341.652098) (xy 353.34194 -341.646002) (xy 353.348798 -341.639906)
			(xy 353.37117 -341.621476) (xy 353.420505 -341.591056) (xy 353.473954 -341.568638) (xy 353.50196 -341.561166)
			(xy 353.513644 -341.558372) (xy 353.531678 -341.542878) (xy 353.573334 -341.44712) (xy 353.572318 -341.423498)
			(xy 353.566476 -341.413084) (xy 353.554996 -341.391721) (xy 353.536944 -341.346707) (xy 353.524745 -341.299767)
			(xy 353.518595 -341.251659) (xy 353.518216 -341.22741) (xy 353.518683 -341.199835) (xy 353.526634 -341.145262)
			(xy 353.542359 -341.092402) (xy 353.565529 -341.042356) (xy 353.595661 -340.996167) (xy 353.632129 -340.954796)
			(xy 353.652836 -340.93658) (xy 353.660965 -340.928987) (xy 353.670312 -340.908828) (xy 353.67087 -340.897718)
			(xy 353.67087 -340.820502) (xy 353.670326 -340.809389) (xy 353.660972 -340.78923) (xy 353.652836 -340.78164)
			(xy 353.632148 -340.763403) (xy 353.595675 -340.722041) (xy 353.565539 -340.675857) (xy 353.542368 -340.625813)
			(xy 353.526647 -340.572955) (xy 353.518703 -340.518383) (xy 353.518216 -340.49081) (xy 353.518702 -340.463559)
			(xy 353.526458 -340.409611) (xy 353.541813 -340.357316) (xy 353.564455 -340.307739) (xy 353.593921 -340.261889)
			(xy 353.629612 -340.220698) (xy 353.670803 -340.185007) (xy 353.716653 -340.155541) (xy 353.76623 -340.132899)
			(xy 353.818525 -340.117544) (xy 353.872473 -340.109788) (xy 353.926975 -340.109788) (xy 353.980923 -340.117544)
			(xy 354.033218 -340.132899) (xy 354.082795 -340.155541) (xy 354.128645 -340.185007) (xy 354.169836 -340.220698)
			(xy 354.205527 -340.261889) (xy 354.234993 -340.307739) (xy 354.257635 -340.357316) (xy 354.27299 -340.409611)
			(xy 354.280746 -340.463559) (xy 354.281232 -340.49081) (xy 354.280693 -340.518382) (xy 354.272754 -340.572951)
			(xy 354.257043 -340.625809) (xy 354.233886 -340.675855) (xy 354.203767 -340.722046) (xy 354.167313 -340.763422)
			(xy 354.146612 -340.78164) (xy 354.138482 -340.789232) (xy 354.129133 -340.809391) (xy 354.128578 -340.820502)
			(xy 354.128578 -340.897718) (xy 354.129095 -340.908835) (xy 354.138467 -340.928995) (xy 354.146612 -340.93658)
			(xy 354.167319 -340.954795) (xy 354.203789 -340.996164) (xy 354.233922 -341.042353) (xy 354.257088 -341.0924)
			(xy 354.272805 -341.145261) (xy 354.280746 -341.199836) (xy 354.281232 -341.22741) (xy 354.280647 -341.255884)
			(xy 354.272167 -341.312198) (xy 354.255412 -341.366627) (xy 354.230754 -341.41796) (xy 354.19874 -341.465059)
			(xy 354.160082 -341.506877) (xy 354.115638 -341.542485) (xy 354.066396 -341.571092) (xy 354.013449 -341.592064)
			(xy 353.98583 -341.599012) (xy 353.9744 -341.601806) (xy 353.956112 -341.616792) (xy 353.912932 -341.712042)
			(xy 353.913694 -341.735664) (xy 353.919536 -341.746078) (xy 353.93354 -341.773417) (xy 353.953359 -341.831553)
			(xy 353.963382 -341.892151) (xy 353.963986 -341.922862) (xy 353.96353 -341.94948) (xy 353.955959 -342.002176)
			(xy 353.940964 -342.053257) (xy 353.918851 -342.101684) (xy 353.89007 -342.14647) (xy 353.855208 -342.186704)
			(xy 353.814975 -342.221567) (xy 353.770189 -342.250348) (xy 353.721762 -342.272461) (xy 353.670682 -342.287457)
			(xy 353.617986 -342.29503) (xy 353.591368 -342.29548) (xy 353.564946 -342.295022) (xy 353.512632 -342.287569)
			(xy 353.461894 -342.272803) (xy 353.41375 -342.25102) (xy 353.369164 -342.222656) (xy 353.348798 -342.205818)
			(xy 353.34194 -342.199722) (xy 353.324922 -342.193626) (xy 353.240594 -342.193626) (xy 353.223576 -342.199722)
			(xy 353.216718 -342.205818) (xy 353.196352 -342.222657) (xy 353.151766 -342.251022) (xy 353.103622 -342.272809)
			(xy 353.052885 -342.28758) (xy 353.00057 -342.29504) (xy 352.947726 -342.29504) (xy 352.895411 -342.28758)
			(xy 352.844674 -342.272809) (xy 352.79653 -342.251022) (xy 352.751944 -342.222657) (xy 352.731578 -342.205818)
			(xy 352.72472 -342.199722) (xy 352.707702 -342.193626) (xy 352.623374 -342.193626) (xy 352.606356 -342.199722)
			(xy 352.599498 -342.205818) (xy 352.579123 -342.222644) (xy 352.534537 -342.251004) (xy 352.486395 -342.272787)
			(xy 352.43566 -342.287557) (xy 352.383348 -342.295019) (xy 352.356928 -342.29548) (xy 352.329037 -342.295063)
			(xy 352.273878 -342.286753) (xy 352.220573 -342.270314) (xy 352.170314 -342.246114) (xy 352.124223 -342.214693)
			(xy 352.083331 -342.176753) (xy 352.04855 -342.133142) (xy 352.020658 -342.084835) (xy 352.000278 -342.032909)
			(xy 351.987864 -341.978526) (xy 351.983695 -341.9229) (xy 348.168809 -341.9229) (xy 348.166119 -341.924629)
			(xy 348.116542 -341.947271) (xy 348.064247 -341.962626) (xy 348.010299 -341.970382) (xy 347.955797 -341.970382)
			(xy 347.901849 -341.962626) (xy 347.849554 -341.947271) (xy 347.799977 -341.924629) (xy 347.754127 -341.895163)
			(xy 347.712936 -341.859472) (xy 347.677245 -341.818281) (xy 347.647779 -341.772431) (xy 347.625137 -341.722854)
			(xy 347.609782 -341.670559) (xy 347.602026 -341.616611) (xy 347.60154 -341.58936) (xy 340.736428 -341.58936)
			(xy 340.358984 -341.966804) (xy 340.34089 -341.984061) (xy 340.299344 -342.011871) (xy 340.253173 -342.031044)
			(xy 340.204148 -342.040843) (xy 340.179152 -342.04148) (xy 326.965564 -342.04148) (xy 326.955517 -342.041835)
			(xy 326.93692 -342.049432) (xy 326.929496 -342.056212) (xy 318.133476 -350.852232) (xy 318.115374 -350.869481)
			(xy 318.073833 -350.897296) (xy 318.027663 -350.916471) (xy 317.97864 -350.926272) (xy 317.953644 -350.926908)
			(xy 314.10148 -350.926908) (xy 314.091436 -350.927291) (xy 314.07284 -350.934871) (xy 314.065412 -350.94164)
			(xy 312.531252 -352.476054) (xy 312.525156 -352.505772) (xy 312.531252 -352.52025) (xy 312.535466 -352.52931)
			(xy 312.549561 -352.543448) (xy 312.568006 -352.551085) (xy 312.577988 -352.551492) (xy 313.613292 -352.551492)
			(xy 313.623326 -352.551105) (xy 313.641878 -352.543465) (xy 313.656065 -352.529278) (xy 313.663705 -352.510726)
			(xy 313.664092 -352.500692) (xy 313.664092 -352.2472) (xy 313.664708 -352.222203) (xy 313.674515 -352.173178)
			(xy 313.693695 -352.127007) (xy 313.721509 -352.085462) (xy 313.738768 -352.067368) (xy 314.373768 -351.432368)
			(xy 314.391826 -351.415067) (xy 314.43338 -351.387252) (xy 314.479563 -351.368079) (xy 314.528598 -351.358284)
			(xy 314.5536 -351.357692) (xy 318.911224 -351.357692) (xy 318.921268 -351.357311) (xy 318.939864 -351.34973)
			(xy 318.947292 -351.34296) (xy 327.692512 -342.59774) (xy 327.710615 -342.580492) (xy 327.752157 -342.552679)
			(xy 327.798326 -342.533503) (xy 327.847348 -342.523701) (xy 327.872344 -342.523064) (xy 343.747344 -342.523064)
			(xy 343.772339 -342.523723) (xy 343.821361 -342.533518) (xy 343.867532 -342.552685) (xy 343.909079 -342.580487)
			(xy 343.927176 -342.59774) (xy 344.150442 -342.821006) (xy 348.559372 -342.821006) (xy 348.563443 -342.765384)
			(xy 348.575569 -342.710947) (xy 348.595492 -342.658856) (xy 348.622788 -342.610221) (xy 348.656874 -342.566078)
			(xy 348.697023 -342.527369) (xy 348.742381 -342.494918) (xy 348.791981 -342.469417) (xy 348.844765 -342.45141)
			(xy 348.899608 -342.44128) (xy 348.955342 -342.439243) (xy 349.010779 -342.445343) (xy 349.064736 -342.459449)
			(xy 349.116065 -342.481261) (xy 349.163671 -342.510315) (xy 349.206539 -342.54599) (xy 349.243756 -342.587527)
			(xy 349.274529 -342.63404) (xy 349.298201 -342.684537) (xy 349.314269 -342.737944) (xy 349.322389 -342.79312)
			(xy 349.322898 -342.821006) (xy 349.322389 -342.848892) (xy 349.314269 -342.904068) (xy 349.298201 -342.957475)
			(xy 349.274529 -343.007972) (xy 349.243756 -343.054485) (xy 349.206539 -343.096022) (xy 349.163671 -343.131697)
			(xy 349.116065 -343.160751) (xy 349.064736 -343.182563) (xy 349.010779 -343.196669) (xy 348.955342 -343.202769)
			(xy 348.899608 -343.200732) (xy 348.844765 -343.190602) (xy 348.791981 -343.172595) (xy 348.742381 -343.147094)
			(xy 348.697023 -343.114643) (xy 348.656874 -343.075934) (xy 348.622788 -343.031791) (xy 348.595492 -342.983156)
			(xy 348.575569 -342.931065) (xy 348.563443 -342.876628) (xy 348.559372 -342.821006) (xy 344.150442 -342.821006)
			(xy 345.045792 -343.716356) (xy 347.980252 -343.716356) (xy 347.984323 -343.660734) (xy 347.996449 -343.606297)
			(xy 348.016372 -343.554206) (xy 348.043668 -343.505571) (xy 348.077754 -343.461428) (xy 348.117903 -343.422719)
			(xy 348.163261 -343.390268) (xy 348.212861 -343.364767) (xy 348.265645 -343.34676) (xy 348.320488 -343.33663)
			(xy 348.376222 -343.334593) (xy 348.431659 -343.340693) (xy 348.485616 -343.354799) (xy 348.536945 -343.376611)
			(xy 348.584551 -343.405665) (xy 348.627419 -343.44134) (xy 348.664636 -343.482877) (xy 348.695409 -343.52939)
			(xy 348.719081 -343.579887) (xy 348.735149 -343.633294) (xy 348.743269 -343.68847) (xy 348.743778 -343.716356)
			(xy 348.743269 -343.744242) (xy 348.735149 -343.799418) (xy 348.719081 -343.852825) (xy 348.695409 -343.903322)
			(xy 348.664636 -343.949835) (xy 348.627419 -343.991372) (xy 348.584551 -344.027047) (xy 348.536945 -344.056101)
			(xy 348.485616 -344.077913) (xy 348.431659 -344.092019) (xy 348.376222 -344.098119) (xy 348.320488 -344.096082)
			(xy 348.265645 -344.085952) (xy 348.212861 -344.067945) (xy 348.163261 -344.042444) (xy 348.117903 -344.009993)
			(xy 348.077754 -343.971284) (xy 348.043668 -343.927141) (xy 348.016372 -343.878506) (xy 347.996449 -343.826415)
			(xy 347.984323 -343.771978) (xy 347.980252 -343.716356) (xy 345.045792 -343.716356) (xy 346.865448 -345.536012)
			(xy 346.872925 -345.542711) (xy 346.891487 -345.550299) (xy 346.901516 -345.550744) (xy 348.62516 -345.550744)
			(xy 348.635208 -345.550395) (xy 348.653804 -345.542793) (xy 348.661228 -345.536012) (xy 348.736412 -345.460828)
			(xy 348.743121 -345.453359) (xy 348.750703 -345.434791) (xy 348.751144 -345.42476) (xy 348.751144 -344.351102)
			(xy 348.751775 -344.326106) (xy 348.76158 -344.277082) (xy 348.780755 -344.230912) (xy 348.808564 -344.189366)
			(xy 348.82582 -344.17127) (xy 349.323914 -343.672922) (xy 349.330518 -343.661492) (xy 349.332296 -343.655142)
			(xy 349.340038 -343.628545) (xy 349.36213 -343.577749) (xy 349.391331 -343.53068) (xy 349.427029 -343.488325)
			(xy 349.468473 -343.451573) (xy 349.514794 -343.421198) (xy 349.565018 -343.397836) (xy 349.618092 -343.381978)
			(xy 349.6729 -343.373958) (xy 349.700596 -343.373456) (xy 349.727846 -343.373981) (xy 349.78179 -343.381736)
			(xy 349.834082 -343.397089) (xy 349.883657 -343.419727) (xy 349.929505 -343.44919) (xy 349.970695 -343.484877)
			(xy 350.006386 -343.526063) (xy 350.035854 -343.571908) (xy 350.058497 -343.621481) (xy 350.073855 -343.673771)
			(xy 350.081616 -343.727715) (xy 350.082104 -343.754964) (xy 350.081596 -343.782438) (xy 350.073709 -343.836816)
			(xy 350.058094 -343.889498) (xy 350.055438 -343.895254) (xy 350.323849 -343.895254) (xy 350.323849 -343.840746)
			(xy 350.331607 -343.786793) (xy 350.346964 -343.734494) (xy 350.369607 -343.684912) (xy 350.399077 -343.639058)
			(xy 350.434772 -343.597864) (xy 350.475967 -343.56217) (xy 350.521823 -343.532702) (xy 350.571405 -343.510059)
			(xy 350.623705 -343.494704) (xy 350.677658 -343.486949) (xy 350.704912 -343.486486) (xy 350.730147 -343.48688)
			(xy 350.780181 -343.493499) (xy 350.828902 -343.506673) (xy 350.875454 -343.526171) (xy 350.897444 -343.538556)
			(xy 350.907096 -343.544398) (xy 350.929194 -343.54643) (xy 351.023682 -343.512902) (xy 351.039684 -343.497408)
			(xy 351.043748 -343.486994) (xy 351.054468 -343.460228) (xy 351.082752 -343.409987) (xy 351.118279 -343.364577)
			(xy 351.160237 -343.325035) (xy 351.207671 -343.29226) (xy 351.259499 -343.267) (xy 351.314539 -343.249831)
			(xy 351.371536 -343.241145) (xy 351.400364 -343.240614) (xy 351.427617 -343.241089) (xy 351.481569 -343.248842)
			(xy 351.533868 -343.264194) (xy 351.583449 -343.286834) (xy 351.629303 -343.3163) (xy 351.670497 -343.351993)
			(xy 351.706191 -343.393185) (xy 351.735659 -343.439039) (xy 351.758301 -343.488619) (xy 351.771024 -343.531952)
			(xy 353.911916 -343.531952) (xy 353.912412 -343.504378) (xy 353.920357 -343.449807) (xy 353.936076 -343.396947)
			(xy 353.95924 -343.346901) (xy 353.989368 -343.300711) (xy 354.025831 -343.259338) (xy 354.046536 -343.241122)
			(xy 354.054646 -343.233512) (xy 354.064004 -343.213366) (xy 354.06457 -343.20226) (xy 354.06457 -343.125044)
			(xy 354.064003 -343.113934) (xy 354.054665 -343.093775) (xy 354.046536 -343.086182) (xy 354.02582 -343.067976)
			(xy 353.989349 -343.026607) (xy 353.959216 -342.980416) (xy 353.936051 -342.930367) (xy 353.920336 -342.877503)
			(xy 353.912399 -342.822927) (xy 353.911916 -342.795352) (xy 353.912333 -342.768098) (xy 353.920097 -342.714147)
			(xy 353.935459 -342.66185) (xy 353.958108 -342.612271) (xy 353.987581 -342.566419) (xy 354.02328 -342.525229)
			(xy 354.064477 -342.489538) (xy 354.110334 -342.460073) (xy 354.159917 -342.437434) (xy 354.212217 -342.422082)
			(xy 354.26617 -342.414328) (xy 354.293424 -342.413844) (xy 354.327714 -342.415368) (xy 354.337874 -342.416384)
			(xy 354.357178 -342.410288) (xy 354.42779 -342.351106) (xy 354.437188 -342.333072) (xy 354.438204 -342.322912)
			(xy 354.441103 -342.294733) (xy 354.454284 -342.239638) (xy 354.475469 -342.1871) (xy 354.504193 -342.138273)
			(xy 354.539824 -342.094232) (xy 354.581577 -342.055946) (xy 354.628534 -342.024258) (xy 354.679662 -341.999864)
			(xy 354.733836 -341.983302) (xy 354.789863 -341.974935) (xy 354.818188 -341.974424) (xy 354.836208 -341.974638)
			(xy 354.872082 -341.978077) (xy 354.889816 -341.981282) (xy 354.899214 -341.98306) (xy 354.918264 -341.97925)
			(xy 354.993448 -341.931498) (xy 355.004878 -341.91575) (xy 355.007164 -341.906352) (xy 355.014516 -341.879294)
			(xy 355.03615 -341.827565) (xy 355.065119 -341.779558) (xy 355.1008 -341.736305) (xy 355.142425 -341.698739)
			(xy 355.189099 -341.667666) (xy 355.239816 -341.643757) (xy 355.293486 -341.627525) (xy 355.348953 -341.619319)
			(xy 355.376988 -341.618824) (xy 355.404242 -341.619267) (xy 355.458195 -341.627023) (xy 355.510496 -341.642379)
			(xy 355.560078 -341.665022) (xy 355.605932 -341.694492) (xy 355.647126 -341.730188) (xy 355.68282 -341.771384)
			(xy 355.712287 -341.81724) (xy 355.734928 -341.866823) (xy 355.750282 -341.919124) (xy 355.758035 -341.973078)
			(xy 355.758496 -342.000332) (xy 355.757985 -342.027905) (xy 355.750042 -342.082476) (xy 355.734326 -342.135335)
			(xy 355.711164 -342.185381) (xy 355.68104 -342.231572) (xy 355.64458 -342.272945) (xy 355.623876 -342.291162)
			(xy 355.615776 -342.298781) (xy 355.606412 -342.31892) (xy 355.605842 -342.330024) (xy 355.605842 -342.40724)
			(xy 355.606358 -342.418356) (xy 355.615732 -342.438515) (xy 355.623876 -342.446102) (xy 355.644614 -342.464282)
			(xy 355.68108 -342.505657) (xy 355.711208 -342.551852) (xy 355.734371 -342.601903) (xy 355.750085 -342.654768)
			(xy 355.758023 -342.709345) (xy 355.75802 -342.764496) (xy 355.750076 -342.819072) (xy 355.734356 -342.871935)
			(xy 355.711188 -342.921984) (xy 355.681055 -342.968176) (xy 355.644585 -343.009547) (xy 355.623876 -343.027762)
			(xy 355.615776 -343.035381) (xy 355.606412 -343.05552) (xy 355.605842 -343.066624) (xy 355.605842 -343.14384)
			(xy 355.606358 -343.154956) (xy 355.615732 -343.175115) (xy 355.623876 -343.182702) (xy 355.644587 -343.200914)
			(xy 355.681058 -343.242282) (xy 355.711191 -343.288471) (xy 355.734357 -343.338519) (xy 355.750073 -343.391382)
			(xy 355.758012 -343.445957) (xy 355.758496 -343.473532) (xy 355.758052 -343.500785) (xy 355.750291 -343.554734)
			(xy 355.734931 -343.607031) (xy 355.712285 -343.656609) (xy 355.682814 -343.70246) (xy 355.647119 -343.74365)
			(xy 355.605924 -343.779341) (xy 355.56007 -343.808806) (xy 355.510489 -343.831446) (xy 355.458191 -343.8468)
			(xy 355.404241 -343.854555) (xy 355.376988 -343.85504) (xy 355.349134 -343.854498) (xy 355.29402 -343.846374)
			(xy 355.240672 -343.830329) (xy 355.190221 -343.806703) (xy 355.143738 -343.775999) (xy 355.102208 -343.738867)
			(xy 355.066514 -343.696095) (xy 355.037413 -343.648591) (xy 355.015522 -343.597363) (xy 355.007926 -343.57056)
			(xy 355.00564 -343.56167) (xy 354.994972 -343.54643) (xy 354.92309 -343.498678) (xy 354.905056 -343.494614)
			(xy 354.895912 -343.495884) (xy 354.882895 -343.49755) (xy 354.856711 -343.499332) (xy 354.843588 -343.49944)
			(xy 354.829439 -343.499347) (xy 354.801216 -343.497312) (xy 354.7872 -343.495376) (xy 354.77704 -343.493852)
			(xy 354.757482 -343.498678) (xy 354.68306 -343.554558) (xy 354.6729 -343.572084) (xy 354.67163 -343.582244)
			(xy 354.667529 -343.609395) (xy 354.652557 -343.662224) (xy 354.630166 -343.712362) (xy 354.60082 -343.758772)
			(xy 354.565124 -343.800496) (xy 354.523816 -343.836673) (xy 354.477749 -343.866554) (xy 354.427874 -343.889524)
			(xy 354.375221 -343.905107) (xy 354.320879 -343.912981) (xy 354.293424 -343.91346) (xy 354.26617 -343.913022)
			(xy 354.212215 -343.905267) (xy 354.159914 -343.889912) (xy 354.110331 -343.867269) (xy 354.064475 -343.837799)
			(xy 354.023281 -343.802102) (xy 353.987587 -343.760906) (xy 353.95812 -343.715048) (xy 353.93548 -343.665464)
			(xy 353.920128 -343.613161) (xy 353.912376 -343.559206) (xy 353.911916 -343.531952) (xy 351.771024 -343.531952)
			(xy 351.773656 -343.540918) (xy 351.78141 -343.594869) (xy 351.781872 -343.622122) (xy 351.781209 -343.653685)
			(xy 351.770824 -343.71595) (xy 351.750339 -343.775659) (xy 351.735898 -343.803732) (xy 351.731072 -343.812622)
			(xy 351.72904 -343.83218) (xy 351.754694 -343.920318) (xy 351.76714 -343.935812) (xy 351.77603 -343.940892)
			(xy 351.801163 -343.955389) (xy 351.847044 -343.990902) (xy 351.887016 -344.032955) (xy 351.920157 -344.080578)
			(xy 351.945703 -344.132671) (xy 351.963063 -344.188032) (xy 351.971837 -344.245384) (xy 351.972372 -344.274394)
			(xy 351.971886 -344.301645) (xy 351.96413 -344.355593) (xy 351.948775 -344.407888) (xy 351.926133 -344.457465)
			(xy 351.896667 -344.503315) (xy 351.860976 -344.544506) (xy 351.819785 -344.580197) (xy 351.773935 -344.609663)
			(xy 351.724358 -344.632305) (xy 351.672063 -344.64766) (xy 351.618115 -344.655416) (xy 351.563613 -344.655416)
			(xy 351.509665 -344.64766) (xy 351.45737 -344.632305) (xy 351.407793 -344.609663) (xy 351.361943 -344.580197)
			(xy 351.320752 -344.544506) (xy 351.285061 -344.503315) (xy 351.255595 -344.457465) (xy 351.232953 -344.407888)
			(xy 351.217598 -344.355593) (xy 351.209842 -344.301645) (xy 351.209356 -344.274394) (xy 351.210022 -344.242831)
			(xy 351.220406 -344.180566) (xy 351.240889 -344.120857) (xy 351.25533 -344.092784) (xy 351.260156 -344.083894)
			(xy 351.262188 -344.064336) (xy 351.236534 -343.976198) (xy 351.224088 -343.960704) (xy 351.215198 -343.955624)
			(xy 351.207832 -343.95156) (xy 351.19818 -343.945718) (xy 351.176082 -343.943686) (xy 351.081594 -343.977214)
			(xy 351.065592 -343.992708) (xy 351.061528 -344.003122) (xy 351.050837 -344.0299) (xy 351.022548 -344.080142)
			(xy 350.987017 -344.125551) (xy 350.945054 -344.165093) (xy 350.897616 -344.197866) (xy 350.845785 -344.223124)
			(xy 350.790741 -344.24029) (xy 350.733741 -344.248972) (xy 350.704912 -344.249502) (xy 350.677658 -344.249051)
			(xy 350.623705 -344.241296) (xy 350.571405 -344.225941) (xy 350.521823 -344.203298) (xy 350.475967 -344.17383)
			(xy 350.434772 -344.138136) (xy 350.399077 -344.096942) (xy 350.369607 -344.051088) (xy 350.346964 -344.001506)
			(xy 350.331607 -343.949207) (xy 350.323849 -343.895254) (xy 350.055438 -343.895254) (xy 350.035074 -343.939392)
			(xy 350.005127 -343.985461) (xy 349.987362 -344.006424) (xy 349.981266 -344.013536) (xy 349.974916 -344.030554)
			(xy 349.974916 -344.116406) (xy 349.981266 -344.133424) (xy 349.987362 -344.140536) (xy 350.005133 -344.161492)
			(xy 350.035055 -344.207576) (xy 350.058065 -344.257472) (xy 350.07369 -344.31015) (xy 350.081605 -344.364523)
			(xy 350.082104 -344.391996) (xy 350.08164 -344.419272) (xy 350.07387 -344.473268) (xy 350.058489 -344.525607)
			(xy 350.035809 -344.575221) (xy 350.006294 -344.621099) (xy 349.970545 -344.662305) (xy 349.929291 -344.697999)
			(xy 349.883374 -344.727453) (xy 349.83373 -344.750066) (xy 349.781371 -344.765378) (xy 349.727365 -344.773076)
			(xy 349.700088 -344.773504) (xy 349.689674 -344.773504) (xy 349.671132 -344.781124) (xy 349.655892 -344.796364)
			(xy 349.649187 -344.803836) (xy 349.641602 -344.822402) (xy 349.64116 -344.832432) (xy 349.64116 -345.765374)
			(xy 349.640513 -345.79037) (xy 349.630713 -345.839392) (xy 349.611543 -345.885563) (xy 349.583738 -345.927109)
			(xy 349.566484 -345.945206) (xy 349.145606 -346.366084) (xy 349.127499 -346.383328) (xy 349.085958 -346.411141)
			(xy 349.039791 -346.430317) (xy 348.990769 -346.440121) (xy 348.965774 -346.44076) (xy 346.617036 -346.44076)
			(xy 346.592041 -346.440107) (xy 346.543019 -346.430309) (xy 346.496848 -346.41114) (xy 346.455301 -346.383337)
			(xy 346.437204 -346.366084) (xy 343.498932 -343.427812) (xy 343.49147 -343.421094) (xy 343.472896 -343.413519)
			(xy 343.462864 -343.41308) (xy 328.156824 -343.41308) (xy 328.146774 -343.413414) (xy 328.128178 -343.421026)
			(xy 328.120756 -343.427812) (xy 322.07461 -349.473958) (xy 327.06208 -349.473958) (xy 327.06208 -349.389262)
			(xy 327.070131 -349.304948) (xy 327.08616 -349.221782) (xy 327.110021 -349.140515) (xy 327.1415 -349.061885)
			(xy 327.180311 -348.986604) (xy 327.226101 -348.915352) (xy 327.278457 -348.848776) (xy 327.336905 -348.787478)
			(xy 327.400915 -348.732013) (xy 327.469907 -348.682884) (xy 327.543257 -348.640535) (xy 327.6203 -348.605351)
			(xy 327.700339 -348.577649) (xy 327.782648 -348.557681) (xy 327.866483 -348.545628) (xy 327.951084 -348.541598)
			(xy 328.035685 -348.545628) (xy 328.11952 -348.557681) (xy 328.201829 -348.577649) (xy 328.281868 -348.605351)
			(xy 328.358911 -348.640535) (xy 328.432261 -348.682884) (xy 328.501253 -348.732013) (xy 328.565263 -348.787478)
			(xy 328.623711 -348.848776) (xy 328.676067 -348.915352) (xy 328.721857 -348.986604) (xy 328.760668 -349.061885)
			(xy 328.792147 -349.140515) (xy 328.816008 -349.221782) (xy 328.832037 -349.304948) (xy 328.840088 -349.389262)
			(xy 328.840592 -349.43161) (xy 328.840088 -349.473958) (xy 334.52206 -349.473958) (xy 334.52206 -349.389262)
			(xy 334.530111 -349.304948) (xy 334.54614 -349.221782) (xy 334.570001 -349.140515) (xy 334.60148 -349.061885)
			(xy 334.640291 -348.986604) (xy 334.686081 -348.915352) (xy 334.738437 -348.848776) (xy 334.796885 -348.787478)
			(xy 334.860895 -348.732013) (xy 334.929887 -348.682884) (xy 335.003237 -348.640535) (xy 335.08028 -348.605351)
			(xy 335.160319 -348.577649) (xy 335.242628 -348.557681) (xy 335.326463 -348.545628) (xy 335.411064 -348.541598)
			(xy 335.495665 -348.545628) (xy 335.5795 -348.557681) (xy 335.661809 -348.577649) (xy 335.741848 -348.605351)
			(xy 335.818891 -348.640535) (xy 335.892241 -348.682884) (xy 335.961233 -348.732013) (xy 336.025243 -348.787478)
			(xy 336.083691 -348.848776) (xy 336.136047 -348.915352) (xy 336.181837 -348.986604) (xy 336.220648 -349.061885)
			(xy 336.252127 -349.140515) (xy 336.275988 -349.221782) (xy 336.292017 -349.304948) (xy 336.300068 -349.389262)
			(xy 336.300572 -349.43161) (xy 336.300068 -349.473958) (xy 336.292017 -349.558272) (xy 336.275988 -349.641438)
			(xy 336.252127 -349.722705) (xy 336.220648 -349.801335) (xy 336.181837 -349.876616) (xy 336.136047 -349.947868)
			(xy 336.083691 -350.014444) (xy 336.025243 -350.075742) (xy 335.961233 -350.131207) (xy 335.892241 -350.180336)
			(xy 335.818891 -350.222685) (xy 335.741848 -350.257869) (xy 335.661809 -350.285571) (xy 335.5795 -350.305539)
			(xy 335.495665 -350.317592) (xy 335.411064 -350.321623) (xy 335.326463 -350.317592) (xy 335.242628 -350.305539)
			(xy 335.160319 -350.285571) (xy 335.08028 -350.257869) (xy 335.003237 -350.222685) (xy 334.929887 -350.180336)
			(xy 334.860895 -350.131207) (xy 334.796885 -350.075742) (xy 334.738437 -350.014444) (xy 334.686081 -349.947868)
			(xy 334.640291 -349.876616) (xy 334.60148 -349.801335) (xy 334.570001 -349.722705) (xy 334.54614 -349.641438)
			(xy 334.530111 -349.558272) (xy 334.52206 -349.473958) (xy 328.840088 -349.473958) (xy 328.832037 -349.558272)
			(xy 328.816008 -349.641438) (xy 328.792147 -349.722705) (xy 328.760668 -349.801335) (xy 328.721857 -349.876616)
			(xy 328.676067 -349.947868) (xy 328.623711 -350.014444) (xy 328.565263 -350.075742) (xy 328.501253 -350.131207)
			(xy 328.432261 -350.180336) (xy 328.358911 -350.222685) (xy 328.281868 -350.257869) (xy 328.201829 -350.285571)
			(xy 328.11952 -350.305539) (xy 328.035685 -350.317592) (xy 327.951084 -350.321623) (xy 327.866483 -350.317592)
			(xy 327.782648 -350.305539) (xy 327.700339 -350.285571) (xy 327.6203 -350.257869) (xy 327.543257 -350.222685)
			(xy 327.469907 -350.180336) (xy 327.400915 -350.131207) (xy 327.336905 -350.075742) (xy 327.278457 -350.014444)
			(xy 327.226101 -349.947868) (xy 327.180311 -349.876616) (xy 327.1415 -349.801335) (xy 327.110021 -349.722705)
			(xy 327.08616 -349.641438) (xy 327.070131 -349.558272) (xy 327.06208 -349.473958) (xy 322.07461 -349.473958)
			(xy 319.616836 -351.931732) (xy 326.984875 -351.931732) (xy 326.988878 -351.84387) (xy 327.000854 -351.756736)
			(xy 327.020705 -351.671052) (xy 327.048264 -351.587528) (xy 327.083305 -351.506856) (xy 327.125536 -351.429705)
			(xy 327.174608 -351.356714) (xy 327.230115 -351.288488) (xy 327.291595 -351.225592) (xy 327.35854 -351.168547)
			(xy 327.430395 -351.117826) (xy 327.506565 -351.073849) (xy 327.586418 -351.036981) (xy 327.669293 -351.007528)
			(xy 327.754503 -350.985732) (xy 327.841342 -350.971776) (xy 327.92909 -350.965773) (xy 328.01702 -350.967775)
			(xy 328.104405 -350.977765) (xy 328.190518 -350.99566) (xy 328.274648 -351.021311) (xy 328.356096 -351.054506)
			(xy 328.434189 -351.09497) (xy 328.508278 -351.142368) (xy 328.57775 -351.196307) (xy 328.642029 -351.25634)
			(xy 328.700583 -351.321969) (xy 328.752927 -351.392651) (xy 328.798626 -351.4678) (xy 328.837302 -351.546793)
			(xy 328.868634 -351.628976) (xy 328.892364 -351.713668) (xy 328.908294 -351.800167) (xy 328.916292 -351.887755)
			(xy 328.916792 -351.931732) (xy 334.444855 -351.931732) (xy 334.448858 -351.84387) (xy 334.460834 -351.756736)
			(xy 334.480685 -351.671052) (xy 334.508244 -351.587528) (xy 334.543285 -351.506856) (xy 334.585516 -351.429705)
			(xy 334.634588 -351.356714) (xy 334.690095 -351.288488) (xy 334.751575 -351.225592) (xy 334.81852 -351.168547)
			(xy 334.890375 -351.117826) (xy 334.966545 -351.073849) (xy 335.046398 -351.036981) (xy 335.129273 -351.007528)
			(xy 335.214483 -350.985732) (xy 335.301322 -350.971776) (xy 335.38907 -350.965773) (xy 335.477 -350.967775)
			(xy 335.564385 -350.977765) (xy 335.650498 -350.99566) (xy 335.734628 -351.021311) (xy 335.816076 -351.054506)
			(xy 335.894169 -351.09497) (xy 335.968258 -351.142368) (xy 336.03773 -351.196307) (xy 336.102009 -351.25634)
			(xy 336.160563 -351.321969) (xy 336.212907 -351.392651) (xy 336.258606 -351.4678) (xy 336.297282 -351.546793)
			(xy 336.328614 -351.628976) (xy 336.352344 -351.713668) (xy 336.368274 -351.800167) (xy 336.376272 -351.887755)
			(xy 336.376772 -351.931732) (xy 336.376272 -351.975709) (xy 336.368274 -352.063297) (xy 336.352344 -352.149796)
			(xy 336.328614 -352.234488) (xy 336.297282 -352.316671) (xy 336.258606 -352.395664) (xy 336.212907 -352.470813)
			(xy 336.160563 -352.541495) (xy 336.102009 -352.607124) (xy 336.03773 -352.667157) (xy 335.968258 -352.721096)
			(xy 335.894169 -352.768494) (xy 335.816076 -352.808958) (xy 335.734628 -352.842153) (xy 335.650498 -352.867804)
			(xy 335.564385 -352.885699) (xy 335.477 -352.895689) (xy 335.38907 -352.897691) (xy 335.301322 -352.891688)
			(xy 335.214483 -352.877732) (xy 335.129273 -352.855936) (xy 335.046398 -352.826483) (xy 334.966545 -352.789615)
			(xy 334.890375 -352.745638) (xy 334.81852 -352.694917) (xy 334.751575 -352.637872) (xy 334.690095 -352.574976)
			(xy 334.634588 -352.50675) (xy 334.585516 -352.433759) (xy 334.543285 -352.356608) (xy 334.508244 -352.275936)
			(xy 334.480685 -352.192412) (xy 334.460834 -352.106728) (xy 334.448858 -352.019594) (xy 334.444855 -351.931732)
			(xy 328.916792 -351.931732) (xy 328.916292 -351.975709) (xy 328.908294 -352.063297) (xy 328.892364 -352.149796)
			(xy 328.868634 -352.234488) (xy 328.837302 -352.316671) (xy 328.798626 -352.395664) (xy 328.752927 -352.470813)
			(xy 328.700583 -352.541495) (xy 328.642029 -352.607124) (xy 328.57775 -352.667157) (xy 328.508278 -352.721096)
			(xy 328.434189 -352.768494) (xy 328.356096 -352.808958) (xy 328.274648 -352.842153) (xy 328.190518 -352.867804)
			(xy 328.104405 -352.885699) (xy 328.01702 -352.895689) (xy 327.92909 -352.897691) (xy 327.841342 -352.891688)
			(xy 327.754503 -352.877732) (xy 327.669293 -352.855936) (xy 327.586418 -352.826483) (xy 327.506565 -352.789615)
			(xy 327.430395 -352.745638) (xy 327.35854 -352.694917) (xy 327.291595 -352.637872) (xy 327.230115 -352.574976)
			(xy 327.174608 -352.50675) (xy 327.125536 -352.433759) (xy 327.083305 -352.356608) (xy 327.048264 -352.275936)
			(xy 327.020705 -352.192412) (xy 327.000854 -352.106728) (xy 326.988878 -352.019594) (xy 326.984875 -351.931732)
			(xy 319.616836 -351.931732) (xy 319.375536 -352.173032) (xy 319.357476 -352.190331) (xy 319.315923 -352.218147)
			(xy 319.269741 -352.23732) (xy 319.220706 -352.247116) (xy 319.195704 -352.247708) (xy 314.858146 -352.247708)
			(xy 314.8481 -352.248073) (xy 314.829504 -352.255665) (xy 314.822078 -352.26244) (xy 314.613544 -352.470974)
			(xy 314.606454 -352.478893) (xy 314.598827 -352.498701) (xy 314.598812 -352.509328) (xy 314.602876 -352.59518)
			(xy 314.612528 -352.61423) (xy 314.62091 -352.621342) (xy 314.622434 -352.622358) (xy 314.631475 -352.629017)
			(xy 314.653189 -352.634608) (xy 314.675225 -352.630468) (xy 314.684664 -352.62439) (xy 314.709268 -352.607181)
			(xy 314.762766 -352.579926) (xy 314.819873 -352.561389) (xy 314.879179 -352.552029) (xy 314.9092 -352.551492)
			(xy 314.936451 -352.551978) (xy 314.990399 -352.559734) (xy 315.042694 -352.575089) (xy 315.092271 -352.597731)
			(xy 315.138121 -352.627197) (xy 315.179312 -352.662888) (xy 315.215003 -352.704079) (xy 315.244469 -352.749929)
			(xy 315.267111 -352.799506) (xy 315.282466 -352.851801) (xy 315.290222 -352.905749) (xy 315.290708 -352.933)
			(xy 315.29008 -352.964224) (xy 315.288612 -352.973132) (xy 339.357462 -352.973132) (xy 339.357989 -352.944427)
			(xy 339.366594 -352.887665) (xy 339.3836 -352.832831) (xy 339.408623 -352.781161) (xy 339.4411 -352.73382)
			(xy 339.480298 -352.691874) (xy 339.502496 -352.673666) (xy 339.511894 -352.6663) (xy 339.5218 -352.645726)
			(xy 339.5218 -352.542348) (xy 339.511894 -352.521774) (xy 339.502496 -352.514408) (xy 339.480306 -352.496237)
			(xy 339.441174 -352.454308) (xy 339.408755 -352.406996) (xy 339.383781 -352.355366) (xy 339.366812 -352.30058)
			(xy 339.358231 -352.243873) (xy 339.357716 -352.215196) (xy 339.358226 -352.186279) (xy 339.366956 -352.129107)
			(xy 339.384215 -352.073908) (xy 339.409608 -352.021946) (xy 339.442553 -351.974412) (xy 339.482296 -351.932396)
			(xy 339.504782 -351.914206) (xy 339.513551 -351.906651) (xy 339.523727 -351.885887) (xy 339.52434 -351.874328)
			(xy 339.52434 -351.794064) (xy 339.523754 -351.782498) (xy 339.513572 -351.761725) (xy 339.504782 -351.754186)
			(xy 339.482288 -351.736007) (xy 339.442554 -351.693985) (xy 339.409617 -351.646447) (xy 339.384231 -351.594483)
			(xy 339.366977 -351.539284) (xy 339.35825 -351.482113) (xy 339.357716 -351.453196) (xy 339.358152 -351.425942)
			(xy 339.36591 -351.371989) (xy 339.381268 -351.319689) (xy 339.403912 -351.270107) (xy 339.433383 -351.224253)
			(xy 339.46908 -351.18306) (xy 339.510275 -351.147366) (xy 339.556132 -351.117899) (xy 339.605715 -351.095258)
			(xy 339.658016 -351.079904) (xy 339.71197 -351.07215) (xy 339.739224 -351.071688) (xy 339.768141 -351.072228)
			(xy 339.825312 -351.080948) (xy 339.880512 -351.098199) (xy 339.932475 -351.123587) (xy 339.980009 -351.156528)
			(xy 340.022025 -351.196269) (xy 340.040214 -351.218754) (xy 340.047765 -351.227527) (xy 340.068532 -351.237702)
			(xy 340.080092 -351.238312) (xy 340.160356 -351.238312) (xy 340.17192 -351.237712) (xy 340.192691 -351.227538)
			(xy 340.200234 -351.218754) (xy 340.216987 -351.197971) (xy 340.255341 -351.160841) (xy 340.298495 -351.129419)
			(xy 340.345609 -351.10432) (xy 340.395761 -351.086034) (xy 340.447972 -351.074917) (xy 340.501224 -351.071187)
			(xy 340.554476 -351.074917) (xy 340.606687 -351.086034) (xy 340.656839 -351.10432) (xy 340.703953 -351.129419)
			(xy 340.747107 -351.160841) (xy 340.785461 -351.197971) (xy 340.802214 -351.218754) (xy 340.809765 -351.227527)
			(xy 340.830532 -351.237702) (xy 340.842092 -351.238312) (xy 340.922356 -351.238312) (xy 340.93392 -351.237712)
			(xy 340.954691 -351.227538) (xy 340.962234 -351.218754) (xy 340.978987 -351.197971) (xy 341.017341 -351.160841)
			(xy 341.060495 -351.129419) (xy 341.107609 -351.10432) (xy 341.157761 -351.086034) (xy 341.209972 -351.074917)
			(xy 341.263224 -351.071187) (xy 341.316476 -351.074917) (xy 341.368687 -351.086034) (xy 341.418839 -351.10432)
			(xy 341.465953 -351.129419) (xy 341.509107 -351.160841) (xy 341.547461 -351.197971) (xy 341.564214 -351.218754)
			(xy 341.571765 -351.227527) (xy 341.592532 -351.237702) (xy 341.604092 -351.238312) (xy 341.684356 -351.238312)
			(xy 341.69592 -351.237712) (xy 341.716691 -351.227538) (xy 341.724234 -351.218754) (xy 341.740987 -351.197971)
			(xy 341.779341 -351.160841) (xy 341.822495 -351.129419) (xy 341.869609 -351.10432) (xy 341.919761 -351.086034)
			(xy 341.971972 -351.074917) (xy 342.025224 -351.071187) (xy 342.078476 -351.074917) (xy 342.130687 -351.086034)
			(xy 342.180839 -351.10432) (xy 342.227953 -351.129419) (xy 342.271107 -351.160841) (xy 342.309461 -351.197971)
			(xy 342.326214 -351.218754) (xy 342.333765 -351.227527) (xy 342.354532 -351.237702) (xy 342.366092 -351.238312)
			(xy 342.446356 -351.238312) (xy 342.45792 -351.237712) (xy 342.478691 -351.227538) (xy 342.486234 -351.218754)
			(xy 342.504394 -351.196245) (xy 342.546422 -351.156513) (xy 342.593963 -351.123579) (xy 342.645931 -351.098195)
			(xy 342.701133 -351.080944) (xy 342.758306 -351.07222) (xy 342.787224 -351.071688) (xy 342.813553 -351.072133)
			(xy 342.865711 -351.07936) (xy 342.916378 -351.093701) (xy 342.964587 -351.114883) (xy 343.009419 -351.142502)
			(xy 343.050021 -351.176032) (xy 343.068148 -351.195132) (xy 343.075006 -351.202752) (xy 343.09304 -351.211134)
			(xy 343.184734 -351.215452) (xy 343.203276 -351.208848) (xy 343.210896 -351.20199) (xy 343.231996 -351.183769)
			(xy 343.278502 -351.153026) (xy 343.328986 -351.129378) (xy 343.382374 -351.113327) (xy 343.43753 -351.105215)
			(xy 343.465404 -351.104708) (xy 343.492658 -351.105152) (xy 343.54661 -351.11291) (xy 343.598909 -351.128267)
			(xy 343.648491 -351.150911) (xy 343.694344 -351.180381) (xy 343.735537 -351.216077) (xy 343.771231 -351.257272)
			(xy 343.800699 -351.303127) (xy 343.82334 -351.352709) (xy 343.838695 -351.405009) (xy 343.84645 -351.458962)
			(xy 343.846912 -351.486216) (xy 343.846367 -351.515132) (xy 343.837648 -351.572304) (xy 343.820398 -351.627503)
			(xy 343.795011 -351.679466) (xy 343.762071 -351.727) (xy 343.722331 -351.769016) (xy 343.699846 -351.787206)
			(xy 343.691077 -351.79476) (xy 343.680899 -351.815525) (xy 343.680288 -351.827084) (xy 343.680288 -351.907348)
			(xy 343.680892 -351.918911) (xy 343.691063 -351.939683) (xy 343.699846 -351.947226) (xy 343.722352 -351.965391)
			(xy 343.762083 -352.007417) (xy 343.795018 -352.054958) (xy 343.820402 -352.106924) (xy 343.837654 -352.162126)
			(xy 343.846379 -352.219299) (xy 343.846912 -352.248216) (xy 343.846392 -352.276921) (xy 343.837781 -352.333682)
			(xy 343.820772 -352.388515) (xy 343.795747 -352.440184) (xy 343.763271 -352.487526) (xy 343.724074 -352.529473)
			(xy 343.701878 -352.547682) (xy 343.69248 -352.555048) (xy 343.682574 -352.575622) (xy 343.682574 -352.679)
			(xy 343.69248 -352.699574) (xy 343.701878 -352.70694) (xy 343.724038 -352.725146) (xy 343.763173 -352.767067)
			(xy 343.795596 -352.814372) (xy 343.820576 -352.865995) (xy 343.837551 -352.920775) (xy 343.846139 -352.977477)
			(xy 343.846658 -353.006152) (xy 343.846172 -353.033403) (xy 343.838416 -353.087351) (xy 343.823061 -353.139646)
			(xy 343.800419 -353.189223) (xy 343.770953 -353.235073) (xy 343.735262 -353.276264) (xy 343.694071 -353.311955)
			(xy 343.648221 -353.341421) (xy 343.598644 -353.364063) (xy 343.546349 -353.379418) (xy 343.492401 -353.387174)
			(xy 343.437899 -353.387174) (xy 343.383951 -353.379418) (xy 343.331656 -353.364063) (xy 343.282079 -353.341421)
			(xy 343.236229 -353.311955) (xy 343.195038 -353.276264) (xy 343.159347 -353.235073) (xy 343.129881 -353.189223)
			(xy 343.107239 -353.139646) (xy 343.091884 -353.087351) (xy 343.084128 -353.033403) (xy 343.083642 -353.006152)
			(xy 343.08419 -352.977448) (xy 343.092792 -352.920687) (xy 343.109794 -352.865854) (xy 343.134813 -352.814184)
			(xy 343.167286 -352.766842) (xy 343.20648 -352.724895) (xy 343.228676 -352.706686) (xy 343.238074 -352.69932)
			(xy 343.24798 -352.678746) (xy 343.24798 -352.575368) (xy 343.238074 -352.554794) (xy 343.228676 -352.547428)
			(xy 343.216925 -352.537922) (xy 343.194803 -352.517321) (xy 343.18448 -352.50628) (xy 343.177622 -352.49866)
			(xy 343.159588 -352.490278) (xy 343.067894 -352.48596) (xy 343.049352 -352.492564) (xy 343.041732 -352.499422)
			(xy 343.020373 -352.517836) (xy 342.973249 -352.548808) (xy 342.92208 -352.572511) (xy 342.895174 -352.580956)
			(xy 342.882474 -352.584766) (xy 342.864186 -352.603562) (xy 342.834722 -352.713036) (xy 342.841072 -352.738436)
			(xy 342.850216 -352.748342) (xy 342.869675 -352.769691) (xy 342.902554 -352.817185) (xy 342.927894 -352.869094)
			(xy 342.945115 -352.924231) (xy 342.953825 -352.981334) (xy 342.954356 -353.010216) (xy 342.953837 -353.037465)
			(xy 342.94608 -353.09141) (xy 342.930725 -353.143701) (xy 342.908086 -353.193275) (xy 342.878622 -353.239123)
			(xy 342.842934 -353.280312) (xy 342.801748 -353.316003) (xy 342.755903 -353.34547) (xy 342.706331 -353.368114)
			(xy 342.654041 -353.383473) (xy 342.600097 -353.391235) (xy 342.572848 -353.391724) (xy 342.545478 -353.391248)
			(xy 342.491298 -353.383436) (xy 342.438795 -353.36795) (xy 342.389048 -353.34511) (xy 342.343081 -353.315386)
			(xy 342.32215 -353.297744) (xy 342.315038 -353.291648) (xy 342.29802 -353.285298) (xy 342.212676 -353.285298)
			(xy 342.195658 -353.291648) (xy 342.188546 -353.297744) (xy 342.167613 -353.315385) (xy 342.121645 -353.345109)
			(xy 342.071899 -353.367955) (xy 342.019397 -353.383451) (xy 341.965219 -353.39128) (xy 341.910477 -353.39128)
			(xy 341.856299 -353.383451) (xy 341.803797 -353.367955) (xy 341.754051 -353.345109) (xy 341.708083 -353.315385)
			(xy 341.68715 -353.297744) (xy 341.680038 -353.291648) (xy 341.66302 -353.285298) (xy 341.577676 -353.285298)
			(xy 341.560658 -353.291648) (xy 341.553546 -353.297744) (xy 341.532613 -353.315385) (xy 341.486645 -353.345109)
			(xy 341.436899 -353.367955) (xy 341.384397 -353.383451) (xy 341.330219 -353.39128) (xy 341.275477 -353.39128)
			(xy 341.221299 -353.383451) (xy 341.168797 -353.367955) (xy 341.119051 -353.345109) (xy 341.073083 -353.315385)
			(xy 341.05215 -353.297744) (xy 341.045038 -353.291648) (xy 341.02802 -353.285298) (xy 340.942676 -353.285298)
			(xy 340.925658 -353.291648) (xy 340.918546 -353.297744) (xy 340.897613 -353.315382) (xy 340.85164 -353.345093)
			(xy 340.801893 -353.367928) (xy 340.749392 -353.38342) (xy 340.695217 -353.391249) (xy 340.667848 -353.391724)
			(xy 340.640597 -353.3912) (xy 340.586649 -353.38345) (xy 340.534353 -353.368101) (xy 340.484774 -353.345465)
			(xy 340.438922 -353.316004) (xy 340.397729 -353.280316) (xy 340.362035 -353.239129) (xy 340.332566 -353.193282)
			(xy 340.309921 -353.143707) (xy 340.294564 -353.091413) (xy 340.286804 -353.037467) (xy 340.28634 -353.010216)
			(xy 340.286927 -352.979985) (xy 340.296473 -352.920281) (xy 340.315313 -352.86283) (xy 340.342975 -352.809067)
			(xy 340.378769 -352.760338) (xy 340.399878 -352.73869) (xy 340.409022 -352.729546) (xy 340.416642 -352.704908)
			(xy 340.393782 -352.595688) (xy 340.377018 -352.57613) (xy 340.364826 -352.571558) (xy 340.340772 -352.561862)
			(xy 340.295307 -352.536913) (xy 340.253633 -352.506045) (xy 340.216515 -352.469825) (xy 340.200234 -352.449638)
			(xy 340.192664 -352.440885) (xy 340.171911 -352.430699) (xy 340.160356 -352.43008) (xy 340.080092 -352.43008)
			(xy 340.068525 -352.430653) (xy 340.047754 -352.440847) (xy 340.040214 -352.449638) (xy 340.025838 -352.467546)
			(xy 339.993492 -352.500146) (xy 339.975698 -352.514662) (xy 339.9663 -352.522028) (xy 339.956394 -352.542602)
			(xy 339.956394 -352.64598) (xy 339.9663 -352.666554) (xy 339.975698 -352.67392) (xy 339.997852 -352.692132)
			(xy 340.036987 -352.734053) (xy 340.06941 -352.781356) (xy 340.094391 -352.832978) (xy 340.111367 -352.887756)
			(xy 340.119957 -352.944458) (xy 340.120478 -352.973132) (xy 340.119992 -353.000383) (xy 340.112236 -353.054331)
			(xy 340.096881 -353.106626) (xy 340.074239 -353.156203) (xy 340.044773 -353.202053) (xy 340.009082 -353.243244)
			(xy 339.967891 -353.278935) (xy 339.922041 -353.308401) (xy 339.872464 -353.331043) (xy 339.820169 -353.346398)
			(xy 339.766221 -353.354154) (xy 339.711719 -353.354154) (xy 339.657771 -353.346398) (xy 339.605476 -353.331043)
			(xy 339.555899 -353.308401) (xy 339.510049 -353.278935) (xy 339.468858 -353.243244) (xy 339.433167 -353.202053)
			(xy 339.403701 -353.156203) (xy 339.381059 -353.106626) (xy 339.365704 -353.054331) (xy 339.357948 -353.000383)
			(xy 339.357462 -352.973132) (xy 315.288612 -352.973132) (xy 315.279928 -353.025841) (xy 315.259894 -353.084988)
			(xy 315.24575 -353.112832) (xy 315.241126 -353.122635) (xy 315.239719 -353.144242) (xy 315.247345 -353.164507)
			(xy 315.25464 -353.172522) (xy 316.242192 -354.160328) (xy 316.242446 -354.160328) (xy 316.259118 -354.177603)
			(xy 316.287374 -354.216415) (xy 316.309209 -354.25917) (xy 316.324087 -354.304814) (xy 316.33164 -354.352224)
			(xy 316.332108 -354.376228) (xy 316.332108 -356.037642) (xy 316.331757 -356.058418) (xy 316.326103 -356.099584)
			(xy 316.314905 -356.139599) (xy 316.306962 -356.1588) (xy 316.303286 -356.168411) (xy 316.303159 -356.18897)
			(xy 316.311098 -356.207936) (xy 316.318138 -356.215442) (xy 316.337683 -356.235137) (xy 316.371446 -356.279169)
			(xy 316.398474 -356.327627) (xy 316.418197 -356.379489) (xy 316.4302 -356.433661) (xy 316.432843 -356.46995)
			(xy 317.016382 -356.46995) (xy 317.020453 -356.414328) (xy 317.032579 -356.359891) (xy 317.052502 -356.3078)
			(xy 317.079798 -356.259165) (xy 317.113884 -356.215022) (xy 317.154033 -356.176313) (xy 317.199391 -356.143862)
			(xy 317.248991 -356.118361) (xy 317.301775 -356.100354) (xy 317.356618 -356.090224) (xy 317.412352 -356.088187)
			(xy 317.467789 -356.094287) (xy 317.521746 -356.108393) (xy 317.573075 -356.130205) (xy 317.620681 -356.159259)
			(xy 317.663549 -356.194934) (xy 317.700766 -356.236471) (xy 317.731539 -356.282984) (xy 317.755211 -356.333481)
			(xy 317.771279 -356.386888) (xy 317.779399 -356.442064) (xy 317.779908 -356.46995) (xy 317.779399 -356.497836)
			(xy 317.771279 -356.553012) (xy 317.755211 -356.606419) (xy 317.731539 -356.656916) (xy 317.700766 -356.703429)
			(xy 317.663549 -356.744966) (xy 317.620681 -356.780641) (xy 317.573075 -356.809695) (xy 317.521746 -356.831507)
			(xy 317.467789 -356.845613) (xy 317.412352 -356.851713) (xy 317.356618 -356.849676) (xy 317.301775 -356.839546)
			(xy 317.248991 -356.821539) (xy 317.199391 -356.796038) (xy 317.154033 -356.763587) (xy 317.113884 -356.724878)
			(xy 317.079798 -356.680735) (xy 317.052502 -356.6321) (xy 317.032579 -356.580009) (xy 317.020453 -356.525572)
			(xy 317.016382 -356.46995) (xy 316.432843 -356.46995) (xy 316.43423 -356.489) (xy 316.4302 -356.544339)
			(xy 316.418197 -356.598511) (xy 316.398474 -356.650373) (xy 316.371446 -356.698831) (xy 316.337683 -356.742863)
			(xy 316.318138 -356.762558) (xy 316.311071 -356.770048) (xy 316.303104 -356.789015) (xy 316.303269 -356.809587)
			(xy 316.306962 -356.8192) (xy 316.314884 -356.838408) (xy 316.326069 -356.878423) (xy 316.331737 -356.919584)
			(xy 316.332108 -356.940358) (xy 316.332108 -362.942124) (xy 316.331612 -362.967118) (xy 316.32343 -363.016432)
			(xy 316.307323 -363.063754) (xy 316.283719 -363.107819) (xy 316.253251 -363.147449) (xy 316.235334 -363.164882)
			(xy 316.228076 -363.172383) (xy 316.219829 -363.191539) (xy 316.219332 -363.201966) (xy 316.219332 -363.276134)
			(xy 316.219802 -363.286566) (xy 316.228069 -363.305717) (xy 316.235334 -363.313218) (xy 316.253272 -363.330629)
			(xy 316.283725 -363.370271) (xy 316.307315 -363.414342) (xy 316.323414 -363.461667) (xy 316.33159 -363.510982)
			(xy 316.332108 -363.535976) (xy 316.332108 -364.088172) (xy 316.331639 -364.112176) (xy 316.324096 -364.159589)
			(xy 316.309223 -364.205237) (xy 316.287386 -364.247992) (xy 316.259125 -364.286802) (xy 316.242446 -364.304072)
			(xy 316.242192 -364.304072) (xy 315.71184 -364.834424) (xy 315.709061 -364.837132) (xy 315.702806 -364.84172)
			(xy 315.699394 -364.843568) (xy 315.628274 -364.880398) (xy 315.6246 -364.882211) (xy 315.616814 -364.88476)
			(xy 315.61278 -364.885478) (xy 315.573664 -364.891574) (xy 315.572648 -364.891828) (xy 315.557447 -364.894949)
			(xy 315.529121 -364.907608) (xy 315.504683 -364.926724) (xy 315.485578 -364.95117) (xy 315.472932 -364.979502)
			(xy 315.469778 -364.994698) (xy 315.469524 -364.995714) (xy 315.463428 -365.03483) (xy 315.462715 -365.038865)
			(xy 315.460166 -365.046652) (xy 315.458348 -365.050324) (xy 315.421518 -365.121444) (xy 315.419656 -365.124846)
			(xy 315.415063 -365.131095) (xy 315.412374 -365.13389) (xy 314.951872 -365.594392) (xy 314.951872 -365.594646)
			(xy 314.934597 -365.611318) (xy 314.895785 -365.639574) (xy 314.85303 -365.661409) (xy 314.807386 -365.676287)
			(xy 314.759976 -365.68384) (xy 314.735972 -365.684308) (xy 313.177428 -365.684308) (xy 313.153424 -365.683839)
			(xy 313.106011 -365.676296) (xy 313.060363 -365.661423) (xy 313.017608 -365.639586) (xy 312.978798 -365.611325)
			(xy 312.961528 -365.594646) (xy 312.961528 -365.594392) (xy 312.560208 -365.193072) (xy 312.559954 -365.193072)
			(xy 312.543282 -365.175797) (xy 312.515026 -365.136985) (xy 312.493191 -365.09423) (xy 312.478313 -365.048586)
			(xy 312.47076 -365.001176) (xy 312.470292 -364.977172) (xy 312.470292 -357.946706) (xy 312.453528 -357.921306)
			(xy 312.43905 -357.915464) (xy 312.429626 -357.912077) (xy 312.40962 -357.912068) (xy 312.391119 -357.919683)
			(xy 312.383678 -357.926386) (xy 311.964832 -358.345232) (xy 311.946774 -358.362533) (xy 311.90522 -358.390348)
			(xy 311.859037 -358.409521) (xy 311.810002 -358.419316) (xy 311.785 -358.419908) (xy 308.096412 -358.419908)
			(xy 308.071415 -358.419285) (xy 308.022391 -358.40948) (xy 307.97622 -358.390303) (xy 307.934675 -358.36249)
			(xy 307.91658 -358.345232) (xy 303.662588 -354.09124) (xy 303.655104 -354.084551) (xy 303.636547 -354.076958)
			(xy 303.62652 -354.076508) (xy 291.13099 -354.076508) (xy 291.105992 -354.075898) (xy 291.056967 -354.066089)
			(xy 291.010796 -354.046908) (xy 290.969252 -354.019092) (xy 290.951158 -354.001832) (xy 289.153854 -352.204528)
			(xy 289.136632 -352.186418) (xy 289.10889 -352.144859) (xy 289.089783 -352.098689) (xy 289.080043 -352.04968)
			(xy 289.079432 -352.024696) (xy 265.100562 -352.024696) (xy 267.786866 -354.711) (xy 302.969166 -354.711)
			(xy 302.973237 -354.655378) (xy 302.985363 -354.600941) (xy 303.005286 -354.54885) (xy 303.032582 -354.500215)
			(xy 303.066668 -354.456072) (xy 303.106817 -354.417363) (xy 303.152175 -354.384912) (xy 303.201775 -354.359411)
			(xy 303.254559 -354.341404) (xy 303.309402 -354.331274) (xy 303.365136 -354.329237) (xy 303.420573 -354.335337)
			(xy 303.47453 -354.349443) (xy 303.525859 -354.371255) (xy 303.573465 -354.400309) (xy 303.616333 -354.435984)
			(xy 303.65355 -354.477521) (xy 303.684323 -354.524034) (xy 303.707995 -354.574531) (xy 303.724063 -354.627938)
			(xy 303.732183 -354.683114) (xy 303.732692 -354.711) (xy 303.732183 -354.738886) (xy 303.724063 -354.794062)
			(xy 303.707995 -354.847469) (xy 303.684323 -354.897966) (xy 303.65355 -354.944479) (xy 303.616333 -354.986016)
			(xy 303.573465 -355.021691) (xy 303.525859 -355.050745) (xy 303.47453 -355.072557) (xy 303.420573 -355.086663)
			(xy 303.365136 -355.092763) (xy 303.309402 -355.090726) (xy 303.254559 -355.080596) (xy 303.201775 -355.062589)
			(xy 303.152175 -355.037088) (xy 303.106817 -355.004637) (xy 303.066668 -354.965928) (xy 303.032582 -354.921785)
			(xy 303.005286 -354.87315) (xy 302.985363 -354.821059) (xy 302.973237 -354.766622) (xy 302.969166 -354.711)
			(xy 267.786866 -354.711) (xy 268.355064 -355.279198) (xy 285.984442 -355.279198) (xy 285.984854 -355.251943)
			(xy 285.992612 -355.197987) (xy 286.007971 -355.145686) (xy 286.030617 -355.096102) (xy 286.06009 -355.050247)
			(xy 286.095789 -355.009053) (xy 286.136988 -354.973359) (xy 286.182848 -354.943892) (xy 286.232434 -354.921253)
			(xy 286.284738 -354.905901) (xy 286.338695 -354.89815) (xy 286.36595 -354.89769) (xy 286.393319 -354.898188)
			(xy 286.447497 -354.905998) (xy 286.499999 -354.92148) (xy 286.549747 -354.944315) (xy 286.595715 -354.974032)
			(xy 286.616648 -354.99167) (xy 286.62376 -354.997766) (xy 286.640778 -355.004116) (xy 286.726122 -355.004116)
			(xy 286.74314 -354.997766) (xy 286.750252 -354.99167) (xy 286.771185 -354.974029) (xy 286.817153 -354.944305)
			(xy 286.866899 -354.921459) (xy 286.919401 -354.905963) (xy 286.973579 -354.898134) (xy 287.028321 -354.898134)
			(xy 287.082499 -354.905963) (xy 287.135001 -354.921459) (xy 287.184747 -354.944305) (xy 287.230715 -354.974029)
			(xy 287.251648 -354.99167) (xy 287.25876 -354.997766) (xy 287.275778 -355.004116) (xy 287.361122 -355.004116)
			(xy 287.37814 -354.997766) (xy 287.385252 -354.99167) (xy 287.406185 -354.974029) (xy 287.452153 -354.944305)
			(xy 287.501899 -354.921459) (xy 287.554401 -354.905963) (xy 287.608579 -354.898134) (xy 287.663321 -354.898134)
			(xy 287.717499 -354.905963) (xy 287.770001 -354.921459) (xy 287.819747 -354.944305) (xy 287.865715 -354.974029)
			(xy 287.886648 -354.99167) (xy 287.89376 -354.997766) (xy 287.910778 -355.004116) (xy 287.996122 -355.004116)
			(xy 288.01314 -354.997766) (xy 288.020252 -354.99167) (xy 288.041185 -354.974029) (xy 288.087153 -354.944305)
			(xy 288.136899 -354.921459) (xy 288.189401 -354.905963) (xy 288.243579 -354.898134) (xy 288.298321 -354.898134)
			(xy 288.352499 -354.905963) (xy 288.405001 -354.921459) (xy 288.454747 -354.944305) (xy 288.500715 -354.974029)
			(xy 288.521648 -354.99167) (xy 288.52876 -354.997766) (xy 288.545778 -355.004116) (xy 288.631122 -355.004116)
			(xy 288.64814 -354.997766) (xy 288.655252 -354.99167) (xy 288.676187 -354.974035) (xy 288.72216 -354.944324)
			(xy 288.771907 -354.921488) (xy 288.824406 -354.905995) (xy 288.878581 -354.898165) (xy 288.90595 -354.89769)
			(xy 288.933202 -354.898202) (xy 288.987151 -354.905952) (xy 289.039447 -354.921302) (xy 289.089027 -354.943938)
			(xy 289.134881 -354.973401) (xy 289.176074 -355.009089) (xy 289.211768 -355.050278) (xy 289.241237 -355.096127)
			(xy 289.26388 -355.145704) (xy 289.279237 -355.197999) (xy 289.286994 -355.251947) (xy 289.287458 -355.279198)
			(xy 289.286959 -355.307902) (xy 289.278357 -355.364663) (xy 289.261346 -355.419494) (xy 289.236312 -355.471157)
			(xy 289.203819 -355.518485) (xy 289.184588 -355.539802) (xy 289.17773 -355.547168) (xy 289.170618 -355.565202)
			(xy 289.172142 -355.65588) (xy 289.179508 -355.67366) (xy 289.18662 -355.680772) (xy 289.207284 -355.702351)
			(xy 289.242299 -355.750757) (xy 289.269336 -355.804033) (xy 289.285509 -355.854) (xy 302.893982 -355.854)
			(xy 302.898053 -355.798378) (xy 302.910179 -355.743941) (xy 302.930102 -355.69185) (xy 302.957398 -355.643215)
			(xy 302.991484 -355.599072) (xy 303.031633 -355.560363) (xy 303.076991 -355.527912) (xy 303.126591 -355.502411)
			(xy 303.179375 -355.484404) (xy 303.234218 -355.474274) (xy 303.289952 -355.472237) (xy 303.345389 -355.478337)
			(xy 303.399346 -355.492443) (xy 303.450675 -355.514255) (xy 303.498281 -355.543309) (xy 303.541149 -355.578984)
			(xy 303.578366 -355.620521) (xy 303.609139 -355.667034) (xy 303.632811 -355.717531) (xy 303.648879 -355.770938)
			(xy 303.656999 -355.826114) (xy 303.657508 -355.854) (xy 303.656999 -355.881886) (xy 303.648879 -355.937062)
			(xy 303.632811 -355.990469) (xy 303.609139 -356.040966) (xy 303.578366 -356.087479) (xy 303.541149 -356.129016)
			(xy 303.498281 -356.164691) (xy 303.450675 -356.193745) (xy 303.399346 -356.215557) (xy 303.345389 -356.229663)
			(xy 303.289952 -356.235763) (xy 303.234218 -356.233726) (xy 303.179375 -356.223596) (xy 303.126591 -356.205589)
			(xy 303.076991 -356.180088) (xy 303.031633 -356.147637) (xy 302.991484 -356.108928) (xy 302.957398 -356.064785)
			(xy 302.930102 -356.01615) (xy 302.910179 -355.964059) (xy 302.898053 -355.909622) (xy 302.893982 -355.854)
			(xy 289.285509 -355.854) (xy 289.287734 -355.860873) (xy 289.297042 -355.919886) (xy 289.297618 -355.949758)
			(xy 289.297147 -355.977128) (xy 289.289334 -356.031308) (xy 289.273847 -356.083812) (xy 289.251006 -356.133559)
			(xy 289.22128 -356.179525) (xy 289.203638 -356.200456) (xy 289.197542 -356.207568) (xy 289.191192 -356.224586)
			(xy 289.191192 -356.30993) (xy 289.197542 -356.326948) (xy 289.203638 -356.33406) (xy 289.221278 -356.354991)
			(xy 289.250989 -356.400965) (xy 289.273824 -356.450713) (xy 289.289315 -356.503213) (xy 289.297144 -356.557389)
			(xy 289.297618 -356.584758) (xy 289.297106 -356.612009) (xy 289.289355 -356.665958) (xy 289.274004 -356.718254)
			(xy 289.251368 -356.767834) (xy 289.221905 -356.813687) (xy 289.186216 -356.854879) (xy 289.145028 -356.890574)
			(xy 289.099179 -356.920043) (xy 289.049603 -356.942686) (xy 288.997309 -356.958044) (xy 288.943361 -356.965802)
			(xy 288.91611 -356.966266) (xy 288.88874 -356.965802) (xy 288.83456 -356.957985) (xy 288.782057 -356.942496)
			(xy 288.73231 -356.919654) (xy 288.686343 -356.889928) (xy 288.665412 -356.872286) (xy 288.6583 -356.86619)
			(xy 288.641282 -356.85984) (xy 288.555938 -356.85984) (xy 288.53892 -356.86619) (xy 288.531808 -356.872286)
			(xy 288.510875 -356.889927) (xy 288.464907 -356.919651) (xy 288.415161 -356.942497) (xy 288.362659 -356.957993)
			(xy 288.308481 -356.965822) (xy 288.253739 -356.965822) (xy 288.199561 -356.957993) (xy 288.147059 -356.942497)
			(xy 288.097313 -356.919651) (xy 288.051345 -356.889927) (xy 288.030412 -356.872286) (xy 288.0233 -356.86619)
			(xy 288.006282 -356.85984) (xy 287.920938 -356.85984) (xy 287.90392 -356.86619) (xy 287.896808 -356.872286)
			(xy 287.875875 -356.889927) (xy 287.829907 -356.919651) (xy 287.780161 -356.942497) (xy 287.727659 -356.957993)
			(xy 287.673481 -356.965822) (xy 287.618739 -356.965822) (xy 287.564561 -356.957993) (xy 287.512059 -356.942497)
			(xy 287.462313 -356.919651) (xy 287.416345 -356.889927) (xy 287.395412 -356.872286) (xy 287.3883 -356.86619)
			(xy 287.371282 -356.85984) (xy 287.285938 -356.85984) (xy 287.26892 -356.86619) (xy 287.261808 -356.872286)
			(xy 287.240875 -356.889927) (xy 287.194907 -356.919651) (xy 287.145161 -356.942497) (xy 287.092659 -356.957993)
			(xy 287.038481 -356.965822) (xy 286.983739 -356.965822) (xy 286.929561 -356.957993) (xy 286.877059 -356.942497)
			(xy 286.827313 -356.919651) (xy 286.781345 -356.889927) (xy 286.760412 -356.872286) (xy 286.7533 -356.86619)
			(xy 286.736282 -356.85984) (xy 286.650938 -356.85984) (xy 286.63392 -356.86619) (xy 286.626808 -356.872286)
			(xy 286.605882 -356.889933) (xy 286.559908 -356.919644) (xy 286.510159 -356.942479) (xy 286.457657 -356.957968)
			(xy 286.40348 -356.965793) (xy 286.37611 -356.966266) (xy 286.348855 -356.965835) (xy 286.294901 -356.958079)
			(xy 286.2426 -356.942722) (xy 286.193017 -356.920077) (xy 286.147162 -356.890606) (xy 286.105968 -356.854909)
			(xy 286.070274 -356.813712) (xy 286.040807 -356.767855) (xy 286.018167 -356.71827) (xy 286.002815 -356.665967)
			(xy 285.995062 -356.612013) (xy 285.994602 -356.584758) (xy 285.995102 -356.557389) (xy 286.002911 -356.503211)
			(xy 286.018392 -356.450709) (xy 286.041227 -356.400961) (xy 286.070944 -356.354993) (xy 286.088582 -356.33406)
			(xy 286.094678 -356.326948) (xy 286.101028 -356.30993) (xy 286.101028 -356.224586) (xy 286.094678 -356.207568)
			(xy 286.088582 -356.200456) (xy 286.070953 -356.179516) (xy 286.04124 -356.133545) (xy 286.018403 -356.0838)
			(xy 286.002909 -356.031301) (xy 285.995078 -355.977127) (xy 285.994602 -355.949758) (xy 285.995146 -355.921055)
			(xy 286.003739 -355.864297) (xy 286.020739 -355.809467) (xy 286.045764 -355.757803) (xy 286.078246 -355.710473)
			(xy 286.097472 -355.689154) (xy 286.10433 -355.681788) (xy 286.111442 -355.663754) (xy 286.109918 -355.573076)
			(xy 286.102552 -355.555296) (xy 286.09544 -355.548184) (xy 286.074796 -355.526587) (xy 286.03978 -355.478185)
			(xy 286.01274 -355.424914) (xy 285.994337 -355.368078) (xy 285.985022 -355.309068) (xy 285.984442 -355.279198)
			(xy 268.355064 -355.279198) (xy 270.072866 -356.997) (xy 302.986946 -356.997) (xy 302.991017 -356.941378)
			(xy 303.003143 -356.886941) (xy 303.023066 -356.83485) (xy 303.050362 -356.786215) (xy 303.084448 -356.742072)
			(xy 303.124597 -356.703363) (xy 303.169955 -356.670912) (xy 303.219555 -356.645411) (xy 303.272339 -356.627404)
			(xy 303.327182 -356.617274) (xy 303.382916 -356.615237) (xy 303.438353 -356.621337) (xy 303.49231 -356.635443)
			(xy 303.543639 -356.657255) (xy 303.591245 -356.686309) (xy 303.634113 -356.721984) (xy 303.67133 -356.763521)
			(xy 303.702103 -356.810034) (xy 303.725775 -356.860531) (xy 303.741843 -356.913938) (xy 303.749963 -356.969114)
			(xy 303.750472 -356.997) (xy 303.749963 -357.024886) (xy 303.741843 -357.080062) (xy 303.725775 -357.133469)
			(xy 303.702103 -357.183966) (xy 303.67133 -357.230479) (xy 303.634113 -357.272016) (xy 303.591245 -357.307691)
			(xy 303.543639 -357.336745) (xy 303.49231 -357.358557) (xy 303.438353 -357.372663) (xy 303.382916 -357.378763)
			(xy 303.327182 -357.376726) (xy 303.272339 -357.366596) (xy 303.219555 -357.348589) (xy 303.169955 -357.323088)
			(xy 303.124597 -357.290637) (xy 303.084448 -357.251928) (xy 303.050362 -357.207785) (xy 303.023066 -357.15915)
			(xy 303.003143 -357.107059) (xy 302.991017 -357.052622) (xy 302.986946 -356.997) (xy 270.072866 -356.997)
			(xy 270.568928 -357.493062) (xy 305.065174 -357.493062) (xy 305.069245 -357.43744) (xy 305.081371 -357.383003)
			(xy 305.101294 -357.330912) (xy 305.12859 -357.282277) (xy 305.162676 -357.238134) (xy 305.202825 -357.199425)
			(xy 305.248183 -357.166974) (xy 305.297783 -357.141473) (xy 305.350567 -357.123466) (xy 305.40541 -357.113336)
			(xy 305.461144 -357.111299) (xy 305.516581 -357.117399) (xy 305.570538 -357.131505) (xy 305.621867 -357.153317)
			(xy 305.669473 -357.182371) (xy 305.712341 -357.218046) (xy 305.749558 -357.259583) (xy 305.780331 -357.306096)
			(xy 305.804003 -357.356593) (xy 305.820071 -357.41) (xy 305.828191 -357.465176) (xy 305.8287 -357.493062)
			(xy 305.828191 -357.520948) (xy 305.820071 -357.576124) (xy 305.804003 -357.629531) (xy 305.780331 -357.680028)
			(xy 305.749558 -357.726541) (xy 305.712341 -357.768078) (xy 305.669473 -357.803753) (xy 305.621867 -357.832807)
			(xy 305.570538 -357.854619) (xy 305.516581 -357.868725) (xy 305.461144 -357.874825) (xy 305.40541 -357.872788)
			(xy 305.350567 -357.862658) (xy 305.297783 -357.844651) (xy 305.248183 -357.81915) (xy 305.202825 -357.786699)
			(xy 305.162676 -357.74799) (xy 305.12859 -357.703847) (xy 305.101294 -357.655212) (xy 305.081371 -357.603121)
			(xy 305.069245 -357.548684) (xy 305.065174 -357.493062) (xy 270.568928 -357.493062) (xy 271.753584 -358.677718)
			(xy 271.760983 -358.68456) (xy 271.779582 -358.692277) (xy 271.789652 -358.692704) (xy 273.40941 -358.692704)
			(xy 273.40941 -358.696768) (xy 273.40941 -358.697022) (xy 273.409902 -358.707026) (xy 273.417566 -358.725509)
			(xy 273.431718 -358.739652) (xy 273.450206 -358.747304) (xy 273.46021 -358.747822) (xy 274.98294 -358.747822)
			(xy 274.993007 -358.748253) (xy 275.011598 -358.75598) (xy 275.019008 -358.762808) (xy 275.068214 -358.812014)
			(xy 295.410886 -358.812014) (xy 295.410886 -358.727318) (xy 295.418937 -358.643004) (xy 295.434966 -358.559838)
			(xy 295.458827 -358.478571) (xy 295.490306 -358.399941) (xy 295.529117 -358.32466) (xy 295.574907 -358.253408)
			(xy 295.627263 -358.186832) (xy 295.685711 -358.125534) (xy 295.749721 -358.070069) (xy 295.818713 -358.02094)
			(xy 295.892063 -357.978591) (xy 295.969106 -357.943407) (xy 296.049145 -357.915705) (xy 296.131454 -357.895737)
			(xy 296.215289 -357.883684) (xy 296.29989 -357.879654) (xy 296.384491 -357.883684) (xy 296.468326 -357.895737)
			(xy 296.550635 -357.915705) (xy 296.630674 -357.943407) (xy 296.707717 -357.978591) (xy 296.781067 -358.02094)
			(xy 296.850059 -358.070069) (xy 296.914069 -358.125534) (xy 296.927862 -358.14) (xy 302.875948 -358.14)
			(xy 302.880019 -358.084378) (xy 302.892145 -358.029941) (xy 302.912068 -357.97785) (xy 302.939364 -357.929215)
			(xy 302.97345 -357.885072) (xy 303.013599 -357.846363) (xy 303.058957 -357.813912) (xy 303.108557 -357.788411)
			(xy 303.161341 -357.770404) (xy 303.216184 -357.760274) (xy 303.271918 -357.758237) (xy 303.327355 -357.764337)
			(xy 303.381312 -357.778443) (xy 303.432641 -357.800255) (xy 303.480247 -357.829309) (xy 303.523115 -357.864984)
			(xy 303.560332 -357.906521) (xy 303.591105 -357.953034) (xy 303.614777 -358.003531) (xy 303.630845 -358.056938)
			(xy 303.638965 -358.112114) (xy 303.639474 -358.14) (xy 303.638965 -358.167886) (xy 303.630845 -358.223062)
			(xy 303.614777 -358.276469) (xy 303.591105 -358.326966) (xy 303.560332 -358.373479) (xy 303.523115 -358.415016)
			(xy 303.480247 -358.450691) (xy 303.432641 -358.479745) (xy 303.381312 -358.501557) (xy 303.327355 -358.515663)
			(xy 303.271918 -358.521763) (xy 303.216184 -358.519726) (xy 303.161341 -358.509596) (xy 303.108557 -358.491589)
			(xy 303.058957 -358.466088) (xy 303.013599 -358.433637) (xy 302.97345 -358.394928) (xy 302.939364 -358.350785)
			(xy 302.912068 -358.30215) (xy 302.892145 -358.250059) (xy 302.880019 -358.195622) (xy 302.875948 -358.14)
			(xy 296.927862 -358.14) (xy 296.972517 -358.186832) (xy 297.024873 -358.253408) (xy 297.070663 -358.32466)
			(xy 297.109474 -358.399941) (xy 297.140953 -358.478571) (xy 297.164814 -358.559838) (xy 297.180843 -358.643004)
			(xy 297.188894 -358.727318) (xy 297.189322 -358.763316) (xy 305.14366 -358.763316) (xy 305.147731 -358.707694)
			(xy 305.159857 -358.653257) (xy 305.17978 -358.601166) (xy 305.207076 -358.552531) (xy 305.241162 -358.508388)
			(xy 305.281311 -358.469679) (xy 305.326669 -358.437228) (xy 305.376269 -358.411727) (xy 305.429053 -358.39372)
			(xy 305.483896 -358.38359) (xy 305.53963 -358.381553) (xy 305.595067 -358.387653) (xy 305.649024 -358.401759)
			(xy 305.700353 -358.423571) (xy 305.747959 -358.452625) (xy 305.790827 -358.4883) (xy 305.828044 -358.529837)
			(xy 305.858817 -358.57635) (xy 305.882489 -358.626847) (xy 305.898557 -358.680254) (xy 305.906677 -358.73543)
			(xy 305.907186 -358.763316) (xy 305.906677 -358.791202) (xy 305.898557 -358.846378) (xy 305.882489 -358.899785)
			(xy 305.858817 -358.950282) (xy 305.828044 -358.996795) (xy 305.790827 -359.038332) (xy 305.747959 -359.074007)
			(xy 305.700353 -359.103061) (xy 305.649024 -359.124873) (xy 305.595067 -359.138979) (xy 305.53963 -359.145079)
			(xy 305.483896 -359.143042) (xy 305.429053 -359.132912) (xy 305.376269 -359.114905) (xy 305.326669 -359.089404)
			(xy 305.281311 -359.056953) (xy 305.241162 -359.018244) (xy 305.207076 -358.974101) (xy 305.17978 -358.925466)
			(xy 305.159857 -358.873375) (xy 305.147731 -358.818938) (xy 305.14366 -358.763316) (xy 297.189322 -358.763316)
			(xy 297.189398 -358.769666) (xy 297.188894 -358.812014) (xy 297.180843 -358.896328) (xy 297.164814 -358.979494)
			(xy 297.140953 -359.060761) (xy 297.109474 -359.139391) (xy 297.070663 -359.214672) (xy 297.026752 -359.283)
			(xy 302.893982 -359.283) (xy 302.898053 -359.227378) (xy 302.910179 -359.172941) (xy 302.930102 -359.12085)
			(xy 302.957398 -359.072215) (xy 302.991484 -359.028072) (xy 303.031633 -358.989363) (xy 303.076991 -358.956912)
			(xy 303.126591 -358.931411) (xy 303.179375 -358.913404) (xy 303.234218 -358.903274) (xy 303.289952 -358.901237)
			(xy 303.345389 -358.907337) (xy 303.399346 -358.921443) (xy 303.450675 -358.943255) (xy 303.498281 -358.972309)
			(xy 303.541149 -359.007984) (xy 303.578366 -359.049521) (xy 303.609139 -359.096034) (xy 303.632811 -359.146531)
			(xy 303.648879 -359.199938) (xy 303.656999 -359.255114) (xy 303.657508 -359.283) (xy 303.656999 -359.310886)
			(xy 303.648879 -359.366062) (xy 303.632811 -359.419469) (xy 303.609139 -359.469966) (xy 303.578366 -359.516479)
			(xy 303.541149 -359.558016) (xy 303.498281 -359.593691) (xy 303.450675 -359.622745) (xy 303.399346 -359.644557)
			(xy 303.345389 -359.658663) (xy 303.289952 -359.664763) (xy 303.234218 -359.662726) (xy 303.179375 -359.652596)
			(xy 303.126591 -359.634589) (xy 303.076991 -359.609088) (xy 303.031633 -359.576637) (xy 302.991484 -359.537928)
			(xy 302.957398 -359.493785) (xy 302.930102 -359.44515) (xy 302.910179 -359.393059) (xy 302.898053 -359.338622)
			(xy 302.893982 -359.283) (xy 297.026752 -359.283) (xy 297.024873 -359.285924) (xy 296.972517 -359.3525)
			(xy 296.914069 -359.413798) (xy 296.850059 -359.469263) (xy 296.781067 -359.518392) (xy 296.707717 -359.560741)
			(xy 296.630674 -359.595925) (xy 296.550635 -359.623627) (xy 296.468326 -359.643595) (xy 296.384491 -359.655648)
			(xy 296.29989 -359.659679) (xy 296.215289 -359.655648) (xy 296.131454 -359.643595) (xy 296.049145 -359.623627)
			(xy 295.969106 -359.595925) (xy 295.892063 -359.560741) (xy 295.818713 -359.518392) (xy 295.749721 -359.469263)
			(xy 295.685711 -359.413798) (xy 295.627263 -359.3525) (xy 295.574907 -359.285924) (xy 295.529117 -359.214672)
			(xy 295.490306 -359.139391) (xy 295.458827 -359.060761) (xy 295.434966 -358.979494) (xy 295.418937 -358.896328)
			(xy 295.410886 -358.812014) (xy 275.068214 -358.812014) (xy 276.28596 -360.02976) (xy 305.24145 -360.02976)
			(xy 305.245521 -359.974138) (xy 305.257647 -359.919701) (xy 305.27757 -359.86761) (xy 305.304866 -359.818975)
			(xy 305.338952 -359.774832) (xy 305.379101 -359.736123) (xy 305.424459 -359.703672) (xy 305.474059 -359.678171)
			(xy 305.526843 -359.660164) (xy 305.581686 -359.650034) (xy 305.63742 -359.647997) (xy 305.692857 -359.654097)
			(xy 305.746814 -359.668203) (xy 305.798143 -359.690015) (xy 305.845749 -359.719069) (xy 305.888617 -359.754744)
			(xy 305.925834 -359.796281) (xy 305.956607 -359.842794) (xy 305.980279 -359.893291) (xy 305.996347 -359.946698)
			(xy 306.004467 -360.001874) (xy 306.004976 -360.02976) (xy 306.004467 -360.057646) (xy 305.996347 -360.112822)
			(xy 305.980279 -360.166229) (xy 305.956607 -360.216726) (xy 305.925834 -360.263239) (xy 305.888617 -360.304776)
			(xy 305.845749 -360.340451) (xy 305.798143 -360.369505) (xy 305.746814 -360.391317) (xy 305.692857 -360.405423)
			(xy 305.63742 -360.411523) (xy 305.581686 -360.409486) (xy 305.526843 -360.399356) (xy 305.474059 -360.381349)
			(xy 305.424459 -360.355848) (xy 305.379101 -360.323397) (xy 305.338952 -360.284688) (xy 305.304866 -360.240545)
			(xy 305.27757 -360.19191) (xy 305.257647 -360.139819) (xy 305.245521 -360.085382) (xy 305.24145 -360.02976)
			(xy 276.28596 -360.02976) (xy 276.496018 -360.239818) (xy 276.503414 -360.24667) (xy 276.522013 -360.254411)
			(xy 276.532086 -360.254804) (xy 281.978862 -360.254804) (xy 281.988927 -360.255239) (xy 282.007515 -360.262969)
			(xy 282.01493 -360.26979) (xy 283.25318 -361.50804) (xy 283.260022 -361.51544) (xy 283.267745 -361.534038)
			(xy 283.268166 -361.544108) (xy 283.268166 -361.565952) (xy 285.209742 -361.565952) (xy 285.21011 -361.538696)
			(xy 285.217875 -361.484739) (xy 285.23324 -361.432436) (xy 285.255892 -361.382852) (xy 285.285369 -361.336997)
			(xy 285.321073 -361.295803) (xy 285.362276 -361.26011) (xy 285.408138 -361.230645) (xy 285.457728 -361.208006)
			(xy 285.510035 -361.192654) (xy 285.563994 -361.184903) (xy 285.59125 -361.184444) (xy 285.61862 -361.184929)
			(xy 285.672798 -361.19274) (xy 285.725302 -361.208224) (xy 285.775049 -361.231062) (xy 285.821016 -361.260784)
			(xy 285.841948 -361.278424) (xy 285.84906 -361.28452) (xy 285.866078 -361.29087) (xy 285.951422 -361.29087)
			(xy 285.96844 -361.28452) (xy 285.975552 -361.278424) (xy 285.996494 -361.260798) (xy 286.042464 -361.231083)
			(xy 286.092209 -361.208244) (xy 286.144707 -361.19275) (xy 286.198881 -361.184919) (xy 286.22625 -361.184444)
			(xy 286.252898 -361.184913) (xy 286.305674 -361.192349) (xy 286.356902 -361.207056) (xy 286.405586 -361.228747)
			(xy 286.450777 -361.257001) (xy 286.491599 -361.291268) (xy 286.527255 -361.330882) (xy 286.557053 -361.375071)
			(xy 286.56915 -361.39882) (xy 286.57423 -361.409234) (xy 286.592264 -361.423458) (xy 286.692594 -361.446064)
			(xy 286.714946 -361.44073) (xy 286.72409 -361.433618) (xy 286.744487 -361.417796) (xy 286.788733 -361.391204)
			(xy 286.836157 -361.370812) (xy 286.885894 -361.356991) (xy 286.937039 -361.349993) (xy 286.96285 -361.349544)
			(xy 286.99022 -361.350029) (xy 287.044398 -361.35784) (xy 287.096902 -361.373324) (xy 287.146649 -361.396162)
			(xy 287.192616 -361.425884) (xy 287.213548 -361.443524) (xy 287.22066 -361.44962) (xy 287.237678 -361.45597)
			(xy 287.323022 -361.45597) (xy 287.34004 -361.44962) (xy 287.347152 -361.443524) (xy 287.368085 -361.425883)
			(xy 287.414053 -361.396159) (xy 287.463799 -361.373313) (xy 287.516301 -361.357817) (xy 287.570479 -361.349988)
			(xy 287.625221 -361.349988) (xy 287.679399 -361.357817) (xy 287.731901 -361.373313) (xy 287.781647 -361.396159)
			(xy 287.827615 -361.425883) (xy 287.848548 -361.443524) (xy 287.85566 -361.44962) (xy 287.872678 -361.45597)
			(xy 287.958022 -361.45597) (xy 287.97504 -361.44962) (xy 287.982152 -361.443524) (xy 288.003085 -361.425883)
			(xy 288.049053 -361.396159) (xy 288.098799 -361.373313) (xy 288.151301 -361.357817) (xy 288.205479 -361.349988)
			(xy 288.260221 -361.349988) (xy 288.314399 -361.357817) (xy 288.366901 -361.373313) (xy 288.416647 -361.396159)
			(xy 288.462615 -361.425883) (xy 288.483548 -361.443524) (xy 288.49066 -361.44962) (xy 288.507678 -361.45597)
			(xy 288.593022 -361.45597) (xy 288.61004 -361.44962) (xy 288.617152 -361.443524) (xy 288.638094 -361.425898)
			(xy 288.684064 -361.396183) (xy 288.733809 -361.373344) (xy 288.786307 -361.35785) (xy 288.840481 -361.350019)
			(xy 288.86785 -361.349544) (xy 288.893663 -361.35) (xy 288.944816 -361.356964) (xy 288.994561 -361.370771)
			(xy 289.041985 -361.391168) (xy 289.086222 -361.417781) (xy 289.10661 -361.433618) (xy 289.115754 -361.44073)
			(xy 289.138106 -361.446064) (xy 289.238436 -361.423458) (xy 289.25647 -361.409234) (xy 289.26155 -361.39882)
			(xy 289.273615 -361.375051) (xy 289.303402 -361.330844) (xy 289.339054 -361.291217) (xy 289.379878 -361.256941)
			(xy 289.425077 -361.228684) (xy 289.473771 -361.206996) (xy 289.525011 -361.192301) (xy 289.577797 -361.184885)
			(xy 289.60445 -361.184444) (xy 289.63182 -361.184929) (xy 289.685998 -361.19274) (xy 289.738502 -361.208224)
			(xy 289.788249 -361.231062) (xy 289.834216 -361.260784) (xy 289.855148 -361.278424) (xy 289.86226 -361.28452)
			(xy 289.879278 -361.29087) (xy 289.964622 -361.29087) (xy 289.98164 -361.28452) (xy 289.988752 -361.278424)
			(xy 290.009694 -361.260798) (xy 290.055664 -361.231083) (xy 290.105409 -361.208244) (xy 290.157907 -361.19275)
			(xy 290.212081 -361.184919) (xy 290.23945 -361.184444) (xy 290.265295 -361.184875) (xy 290.316511 -361.19186)
			(xy 290.366315 -361.205696) (xy 290.413795 -361.226128) (xy 290.458082 -361.252783) (xy 290.498365 -361.285173)
			(xy 290.533907 -361.322705) (xy 290.54933 -361.343448) (xy 290.556442 -361.353354) (xy 290.57727 -361.364276)
			(xy 290.682934 -361.366816) (xy 290.70427 -361.356656) (xy 290.71189 -361.347004) (xy 290.73011 -361.324759)
			(xy 290.772036 -361.285413) (xy 290.819395 -361.25281) (xy 290.871113 -361.227688) (xy 290.926017 -361.210617)
			(xy 290.982862 -361.201984) (xy 291.01161 -361.201462) (xy 291.03886 -361.201968) (xy 291.092806 -361.209725)
			(xy 291.145098 -361.22508) (xy 291.194673 -361.24772) (xy 291.229012 -361.269788) (xy 295.333681 -361.269788)
			(xy 295.337684 -361.181926) (xy 295.34966 -361.094792) (xy 295.369511 -361.009108) (xy 295.39707 -360.925584)
			(xy 295.432111 -360.844912) (xy 295.474342 -360.767761) (xy 295.523414 -360.69477) (xy 295.578921 -360.626544)
			(xy 295.640401 -360.563648) (xy 295.707346 -360.506603) (xy 295.779201 -360.455882) (xy 295.855371 -360.411905)
			(xy 295.935224 -360.375037) (xy 296.018099 -360.345584) (xy 296.103309 -360.323788) (xy 296.190148 -360.309832)
			(xy 296.277896 -360.303829) (xy 296.365826 -360.305831) (xy 296.453211 -360.315821) (xy 296.539324 -360.333716)
			(xy 296.623454 -360.359367) (xy 296.704902 -360.392562) (xy 296.782995 -360.433026) (xy 296.857084 -360.480424)
			(xy 296.926556 -360.534363) (xy 296.990835 -360.594396) (xy 297.049389 -360.660025) (xy 297.101733 -360.730707)
			(xy 297.147432 -360.805856) (xy 297.186108 -360.884849) (xy 297.21744 -360.967032) (xy 297.24117 -361.051724)
			(xy 297.2571 -361.138223) (xy 297.265098 -361.225811) (xy 297.265598 -361.269788) (xy 297.265098 -361.313765)
			(xy 297.2571 -361.401353) (xy 297.254292 -361.4166) (xy 300.099982 -361.4166) (xy 300.104053 -361.360978)
			(xy 300.116179 -361.306541) (xy 300.136102 -361.25445) (xy 300.163398 -361.205815) (xy 300.197484 -361.161672)
			(xy 300.237633 -361.122963) (xy 300.282991 -361.090512) (xy 300.332591 -361.065011) (xy 300.385375 -361.047004)
			(xy 300.440218 -361.036874) (xy 300.495952 -361.034837) (xy 300.551389 -361.040937) (xy 300.605346 -361.055043)
			(xy 300.656675 -361.076855) (xy 300.704281 -361.105909) (xy 300.747149 -361.141584) (xy 300.784366 -361.183121)
			(xy 300.815139 -361.229634) (xy 300.838811 -361.280131) (xy 300.854879 -361.333538) (xy 300.862999 -361.388714)
			(xy 300.863508 -361.4166) (xy 300.862999 -361.444486) (xy 300.854879 -361.499662) (xy 300.838811 -361.553069)
			(xy 300.815139 -361.603566) (xy 300.784366 -361.650079) (xy 300.747149 -361.691616) (xy 300.704281 -361.727291)
			(xy 300.656675 -361.756345) (xy 300.605346 -361.778157) (xy 300.551389 -361.792263) (xy 300.495952 -361.798363)
			(xy 300.440218 -361.796326) (xy 300.385375 -361.786196) (xy 300.332591 -361.768189) (xy 300.282991 -361.742688)
			(xy 300.237633 -361.710237) (xy 300.197484 -361.671528) (xy 300.163398 -361.627385) (xy 300.136102 -361.57875)
			(xy 300.116179 -361.526659) (xy 300.104053 -361.472222) (xy 300.099982 -361.4166) (xy 297.254292 -361.4166)
			(xy 297.24117 -361.487852) (xy 297.21744 -361.572544) (xy 297.186108 -361.654727) (xy 297.147432 -361.73372)
			(xy 297.101733 -361.808869) (xy 297.049389 -361.879551) (xy 296.990835 -361.94518) (xy 296.926556 -362.005213)
			(xy 296.857084 -362.059152) (xy 296.782995 -362.10655) (xy 296.704902 -362.147014) (xy 296.623454 -362.180209)
			(xy 296.539324 -362.20586) (xy 296.453211 -362.223755) (xy 296.365826 -362.233745) (xy 296.277896 -362.235747)
			(xy 296.190148 -362.229744) (xy 296.103309 -362.215788) (xy 296.018099 -362.193992) (xy 295.935224 -362.164539)
			(xy 295.855371 -362.127671) (xy 295.779201 -362.083694) (xy 295.707346 -362.032973) (xy 295.640401 -361.975928)
			(xy 295.578921 -361.913032) (xy 295.523414 -361.844806) (xy 295.474342 -361.771815) (xy 295.432111 -361.694664)
			(xy 295.39707 -361.613992) (xy 295.369511 -361.530468) (xy 295.34966 -361.444784) (xy 295.337684 -361.35765)
			(xy 295.333681 -361.269788) (xy 291.229012 -361.269788) (xy 291.240522 -361.277185) (xy 291.281712 -361.312874)
			(xy 291.317403 -361.354062) (xy 291.34687 -361.399909) (xy 291.369513 -361.449483) (xy 291.38487 -361.501775)
			(xy 291.39263 -361.55572) (xy 291.393118 -361.58297) (xy 291.3926 -361.612245) (xy 291.383625 -361.670104)
			(xy 291.365911 -361.725911) (xy 291.339876 -361.778355) (xy 291.306131 -361.826203) (xy 291.286184 -361.847638)
			(xy 291.279072 -361.855004) (xy 291.27196 -361.873546) (xy 291.27323 -361.965494) (xy 291.281104 -361.983782)
			(xy 291.28847 -361.990894) (xy 291.30629 -362.008912) (xy 291.33752 -362.048822) (xy 291.36319 -362.092515)
			(xy 291.38285 -362.139223) (xy 291.396152 -362.188122) (xy 291.402863 -362.238352) (xy 291.403278 -362.26369)
			(xy 291.402811 -362.29106) (xy 291.394995 -362.34524) (xy 291.379506 -362.397743) (xy 291.356664 -362.44749)
			(xy 291.326939 -362.493456) (xy 291.309298 -362.514388) (xy 291.303202 -362.5215) (xy 291.296852 -362.538518)
			(xy 291.296852 -362.623862) (xy 291.303202 -362.64088) (xy 291.309298 -362.647992) (xy 291.326928 -362.668933)
			(xy 291.356651 -362.7149) (xy 291.379496 -362.764645) (xy 291.394992 -362.817146) (xy 291.402821 -362.871323)
			(xy 291.402822 -362.926062) (xy 291.394995 -362.98024) (xy 291.379501 -363.032741) (xy 291.356658 -363.082487)
			(xy 291.326937 -363.128455) (xy 291.309298 -363.149388) (xy 291.303202 -363.1565) (xy 291.296852 -363.173518)
			(xy 291.296852 -363.258862) (xy 291.303202 -363.27588) (xy 291.309298 -363.282992) (xy 291.326928 -363.303933)
			(xy 291.356651 -363.3499) (xy 291.379496 -363.399645) (xy 291.394992 -363.452146) (xy 291.402821 -363.506323)
			(xy 291.402822 -363.561062) (xy 291.394995 -363.61524) (xy 291.379501 -363.667741) (xy 291.356658 -363.717487)
			(xy 291.326937 -363.763455) (xy 291.309298 -363.784388) (xy 291.303202 -363.7915) (xy 291.296852 -363.808518)
			(xy 291.296852 -363.893862) (xy 291.303202 -363.91088) (xy 291.309298 -363.917992) (xy 291.326946 -363.938917)
			(xy 291.356657 -363.984891) (xy 291.379491 -364.034641) (xy 291.39498 -364.087143) (xy 291.402805 -364.14132)
			(xy 291.403278 -364.16869) (xy 291.402835 -364.195944) (xy 291.395079 -364.249897) (xy 291.379723 -364.302197)
			(xy 291.357079 -364.351779) (xy 291.327609 -364.397634) (xy 291.291913 -364.438828) (xy 291.250718 -364.474521)
			(xy 291.204862 -364.503989) (xy 291.155278 -364.52663) (xy 291.102978 -364.541983) (xy 291.049024 -364.549737)
			(xy 291.02177 -364.550198) (xy 290.995926 -364.549734) (xy 290.944713 -364.542753) (xy 290.89491 -364.528922)
			(xy 290.847431 -364.508494) (xy 290.803143 -364.481845) (xy 290.762859 -364.44946) (xy 290.727315 -364.411934)
			(xy 290.71189 -364.391194) (xy 290.704778 -364.381288) (xy 290.68395 -364.370366) (xy 290.578286 -364.367826)
			(xy 290.55695 -364.377986) (xy 290.54933 -364.387638) (xy 290.531166 -364.40993) (xy 290.489227 -364.449271)
			(xy 290.441856 -364.481868) (xy 290.390127 -364.506981) (xy 290.335214 -364.524042) (xy 290.278361 -364.532664)
			(xy 290.24961 -364.53318) (xy 290.22224 -364.532713) (xy 290.168061 -364.524896) (xy 290.115557 -364.509408)
			(xy 290.06581 -364.486566) (xy 290.019844 -364.456841) (xy 289.998912 -364.4392) (xy 289.9918 -364.433104)
			(xy 289.974782 -364.426754) (xy 289.889438 -364.426754) (xy 289.87242 -364.433104) (xy 289.865308 -364.4392)
			(xy 289.844384 -364.456849) (xy 289.798409 -364.486559) (xy 289.748659 -364.509393) (xy 289.696157 -364.524882)
			(xy 289.64198 -364.532707) (xy 289.61461 -364.53318) (xy 289.587035 -364.532714) (xy 289.532462 -364.524763)
			(xy 289.479602 -364.509038) (xy 289.429556 -364.485868) (xy 289.383366 -364.455735) (xy 289.341996 -364.419267)
			(xy 289.32378 -364.39856) (xy 289.316188 -364.390431) (xy 289.296028 -364.381084) (xy 289.284918 -364.380526)
			(xy 289.207702 -364.380526) (xy 289.196589 -364.381071) (xy 289.17643 -364.390425) (xy 289.16884 -364.39856)
			(xy 289.150602 -364.419247) (xy 289.10924 -364.455721) (xy 289.063056 -364.485857) (xy 289.013013 -364.509027)
			(xy 288.960155 -364.524748) (xy 288.905583 -364.532693) (xy 288.87801 -364.53318) (xy 288.85064 -364.532713)
			(xy 288.796461 -364.524896) (xy 288.743957 -364.509408) (xy 288.69421 -364.486566) (xy 288.648244 -364.456841)
			(xy 288.627312 -364.4392) (xy 288.6202 -364.433104) (xy 288.603182 -364.426754) (xy 288.517838 -364.426754)
			(xy 288.50082 -364.433104) (xy 288.493708 -364.4392) (xy 288.472775 -364.456841) (xy 288.426807 -364.486565)
			(xy 288.377061 -364.509411) (xy 288.324559 -364.524907) (xy 288.270381 -364.532736) (xy 288.215639 -364.532736)
			(xy 288.161461 -364.524907) (xy 288.108959 -364.509411) (xy 288.059213 -364.486565) (xy 288.013245 -364.456841)
			(xy 287.992312 -364.4392) (xy 287.9852 -364.433104) (xy 287.968182 -364.426754) (xy 287.882838 -364.426754)
			(xy 287.86582 -364.433104) (xy 287.858708 -364.4392) (xy 287.837775 -364.456841) (xy 287.791807 -364.486565)
			(xy 287.742061 -364.509411) (xy 287.689559 -364.524907) (xy 287.635381 -364.532736) (xy 287.580639 -364.532736)
			(xy 287.526461 -364.524907) (xy 287.473959 -364.509411) (xy 287.424213 -364.486565) (xy 287.378245 -364.456841)
			(xy 287.357312 -364.4392) (xy 287.3502 -364.433104) (xy 287.333182 -364.426754) (xy 287.247838 -364.426754)
			(xy 287.23082 -364.433104) (xy 287.223708 -364.4392) (xy 287.202784 -364.456849) (xy 287.156809 -364.486559)
			(xy 287.107059 -364.509393) (xy 287.054557 -364.524882) (xy 287.00038 -364.532707) (xy 286.97301 -364.53318)
			(xy 286.945435 -364.532714) (xy 286.890862 -364.524763) (xy 286.838002 -364.509038) (xy 286.787956 -364.485868)
			(xy 286.741766 -364.455735) (xy 286.700396 -364.419267) (xy 286.68218 -364.39856) (xy 286.674588 -364.390431)
			(xy 286.654428 -364.381084) (xy 286.643318 -364.380526) (xy 286.566102 -364.380526) (xy 286.554989 -364.381071)
			(xy 286.53483 -364.390425) (xy 286.52724 -364.39856) (xy 286.509002 -364.419247) (xy 286.46764 -364.455721)
			(xy 286.421456 -364.485857) (xy 286.371413 -364.509027) (xy 286.318555 -364.524748) (xy 286.263983 -364.532693)
			(xy 286.23641 -364.53318) (xy 286.20904 -364.532713) (xy 286.154861 -364.524896) (xy 286.102357 -364.509408)
			(xy 286.05261 -364.486566) (xy 286.006644 -364.456841) (xy 285.985712 -364.4392) (xy 285.9786 -364.433104)
			(xy 285.961582 -364.426754) (xy 285.876238 -364.426754) (xy 285.85922 -364.433104) (xy 285.852108 -364.4392)
			(xy 285.831184 -364.456849) (xy 285.785209 -364.486559) (xy 285.735459 -364.509393) (xy 285.682957 -364.524882)
			(xy 285.62878 -364.532707) (xy 285.60141 -364.53318) (xy 285.574156 -364.532735) (xy 285.520203 -364.524979)
			(xy 285.467903 -364.509623) (xy 285.418321 -364.486979) (xy 285.372467 -364.45751) (xy 285.331273 -364.421814)
			(xy 285.295579 -364.380619) (xy 285.266112 -364.334763) (xy 285.243471 -364.28518) (xy 285.228117 -364.232879)
			(xy 285.220363 -364.178926) (xy 285.219902 -364.151672) (xy 285.220351 -364.124301) (xy 285.228173 -364.070121)
			(xy 285.243666 -364.017618) (xy 285.266511 -363.967871) (xy 285.296239 -363.921905) (xy 285.313882 -363.900974)
			(xy 285.319978 -363.893862) (xy 285.326328 -363.876844) (xy 285.326328 -363.7915) (xy 285.319978 -363.774482)
			(xy 285.313882 -363.76737) (xy 285.296216 -363.746459) (xy 285.266496 -363.700486) (xy 285.243655 -363.650736)
			(xy 285.228162 -363.598231) (xy 285.220337 -363.54405) (xy 285.22034 -363.489308) (xy 285.228171 -363.435128)
			(xy 285.243669 -363.382625) (xy 285.266516 -363.332877) (xy 285.296241 -363.286908) (xy 285.313882 -363.265974)
			(xy 285.319978 -363.258862) (xy 285.326328 -363.241844) (xy 285.326328 -363.1565) (xy 285.319978 -363.139482)
			(xy 285.313882 -363.13237) (xy 285.296216 -363.111459) (xy 285.266496 -363.065486) (xy 285.243655 -363.015736)
			(xy 285.228162 -362.963231) (xy 285.220337 -362.90905) (xy 285.22034 -362.854308) (xy 285.228171 -362.800128)
			(xy 285.243669 -362.747625) (xy 285.266516 -362.697877) (xy 285.296241 -362.651908) (xy 285.313882 -362.630974)
			(xy 285.319978 -362.623862) (xy 285.326328 -362.606844) (xy 285.326328 -362.5215) (xy 285.319978 -362.504482)
			(xy 285.313882 -362.49737) (xy 285.296259 -362.476425) (xy 285.266546 -362.430455) (xy 285.243707 -362.380711)
			(xy 285.228212 -362.328213) (xy 285.220379 -362.27404) (xy 285.219902 -362.246672) (xy 285.22044 -362.217398)
			(xy 285.22941 -362.159539) (xy 285.247118 -362.103732) (xy 285.273149 -362.051288) (xy 285.306891 -362.003439)
			(xy 285.326836 -361.982004) (xy 285.333948 -361.974638) (xy 285.34106 -361.956096) (xy 285.33979 -361.864148)
			(xy 285.331916 -361.84586) (xy 285.32455 -361.838748) (xy 285.306706 -361.820753) (xy 285.275478 -361.780839)
			(xy 285.24981 -361.73714) (xy 285.230155 -361.690428) (xy 285.216858 -361.641525) (xy 285.210153 -361.591291)
			(xy 285.209742 -361.565952) (xy 283.268166 -361.565952) (xy 283.268166 -365.198152) (xy 283.2686 -365.208217)
			(xy 283.276335 -365.226801) (xy 283.283152 -365.23422) (xy 283.442918 -365.393986) (xy 283.450317 -365.400831)
			(xy 283.468915 -365.408561) (xy 283.478986 -365.408972) (xy 293.115492 -365.408972) (xy 293.120318 -365.404146)
			(xy 294.563292 -365.404146) (xy 294.573362 -365.404569) (xy 294.591964 -365.412287) (xy 294.59936 -365.419132)
			(xy 296.132758 -366.95253) (xy 296.139604 -366.959928) (xy 296.147335 -366.978527) (xy 296.147744 -366.988598)
			(xy 296.147744 -368.892074) (xy 296.148145 -368.905461) (xy 296.155103 -368.931315) (xy 296.168548 -368.954469)
			(xy 296.187553 -368.973329) (xy 296.210809 -368.986595) (xy 296.236716 -368.993355) (xy 296.250106 -368.993674)
			(xy 296.2529 -368.993674) (xy 296.282025 -368.994224) (xy 296.339597 -369.003078) (xy 296.395155 -369.020581)
			(xy 296.447406 -369.046326) (xy 296.495137 -369.079714) (xy 296.537238 -369.119969) (xy 296.572731 -369.166156)
			(xy 296.60079 -369.217202) (xy 296.611294 -369.244372) (xy 296.613326 -369.248944) (xy 296.619491 -369.260864)
			(xy 296.636987 -369.281203) (xy 296.659175 -369.296284) (xy 296.684524 -369.305067) (xy 296.711287 -369.306947)
			(xy 296.737615 -369.301793) (xy 296.761693 -369.289962) (xy 296.772076 -369.281456) (xy 296.774362 -369.27917)
			(xy 297.184826 -368.868706) (xy 297.190092 -368.862298) (xy 297.196448 -368.846987) (xy 297.197272 -368.838734)
			(xy 297.197272 -367.91265) (xy 297.197526 -367.904268) (xy 297.197526 -367.804192) (xy 297.198065 -367.794206)
			(xy 297.205784 -367.775778) (xy 297.212512 -367.768378) (xy 297.279822 -367.701068) (xy 297.28033 -367.700306)
			(xy 297.288966 -367.691416) (xy 300.398942 -364.581694) (xy 300.4058 -364.56874) (xy 300.407324 -364.561628)
			(xy 300.413933 -364.533584) (xy 300.434449 -364.479745) (xy 300.462823 -364.429601) (xy 300.49841 -364.38429)
			(xy 300.540403 -364.344843) (xy 300.587847 -364.312154) (xy 300.639665 -364.286967) (xy 300.69468 -364.269853)
			(xy 300.751642 -364.261202) (xy 300.78045 -364.260638) (xy 300.809218 -364.261157) (xy 300.866103 -364.269783)
			(xy 300.92105 -364.286848) (xy 300.972814 -364.311966) (xy 301.020222 -364.344567) (xy 301.062201 -364.383913)
			(xy 301.080424 -364.40618) (xy 301.089275 -364.41675) (xy 301.111449 -364.433111) (xy 301.137196 -364.442932)
			(xy 301.164634 -364.445494) (xy 301.191754 -364.440609) (xy 301.216574 -364.428636) (xy 301.227236 -364.419896)
			(xy 301.229776 -364.41761) (xy 301.426626 -364.220506) (xy 301.431892 -364.214098) (xy 301.438248 -364.198787)
			(xy 301.439072 -364.190534) (xy 301.439072 -363.14253) (xy 301.439072 -363.13872) (xy 301.437418 -363.123648)
			(xy 301.426452 -363.095397) (xy 301.407685 -363.071602) (xy 301.382766 -363.054357) (xy 301.353885 -363.045175)
			(xy 301.323582 -363.044865) (xy 301.29452 -363.053454) (xy 301.269253 -363.070187) (xy 301.25924 -363.08157)
			(xy 301.241026 -363.102936) (xy 301.199397 -363.140608) (xy 301.152698 -363.171773) (xy 301.101936 -363.19576)
			(xy 301.048207 -363.212049) (xy 300.992672 -363.22029) (xy 300.9646 -363.220762) (xy 300.937331 -363.220276)
			(xy 300.883347 -363.212514) (xy 300.831017 -363.197149) (xy 300.781407 -363.174492) (xy 300.735526 -363.145006)
			(xy 300.694309 -363.109291) (xy 300.658594 -363.068074) (xy 300.629108 -363.022193) (xy 300.606451 -362.972583)
			(xy 300.591086 -362.920253) (xy 300.583324 -362.866269) (xy 300.583324 -362.811731) (xy 300.591086 -362.757747)
			(xy 300.606451 -362.705417) (xy 300.629108 -362.655807) (xy 300.658594 -362.609926) (xy 300.694309 -362.568709)
			(xy 300.735526 -362.532994) (xy 300.781407 -362.503508) (xy 300.831017 -362.480851) (xy 300.883347 -362.465486)
			(xy 300.937331 -362.457724) (xy 300.9646 -362.457238) (xy 300.992671 -362.457737) (xy 301.048205 -362.465967)
			(xy 301.101933 -362.482251) (xy 301.152693 -362.506236) (xy 301.199388 -362.537403) (xy 301.241009 -362.575079)
			(xy 301.25924 -362.59643) (xy 301.269289 -362.607774) (xy 301.294542 -362.624498) (xy 301.323589 -362.633082)
			(xy 301.353877 -362.632772) (xy 301.382742 -362.623596) (xy 301.407649 -362.606359) (xy 301.426406 -362.582577)
			(xy 301.437366 -362.55434) (xy 301.439072 -362.53928) (xy 301.439072 -360.870754) (xy 301.439006 -360.867149)
			(xy 301.437981 -360.860011) (xy 301.43704 -360.85653) (xy 301.431198 -360.836464) (xy 301.42561 -360.82732)
			(xy 301.420784 -360.819192) (xy 301.408772 -360.797452) (xy 301.389858 -360.751527) (xy 301.377065 -360.703535)
			(xy 301.370611 -360.654288) (xy 301.370238 -360.629454) (xy 301.370238 -360.6292) (xy 301.370724 -360.601931)
			(xy 301.378486 -360.547947) (xy 301.393851 -360.495617) (xy 301.416508 -360.446007) (xy 301.445994 -360.400126)
			(xy 301.481709 -360.358909) (xy 301.522926 -360.323194) (xy 301.568807 -360.293708) (xy 301.618417 -360.271051)
			(xy 301.670747 -360.255686) (xy 301.724731 -360.247924) (xy 301.779269 -360.247924) (xy 301.833253 -360.255686)
			(xy 301.885583 -360.271051) (xy 301.935193 -360.293708) (xy 301.981074 -360.323194) (xy 302.022291 -360.358909)
			(xy 302.058006 -360.400126) (xy 302.087492 -360.446007) (xy 302.110149 -360.495617) (xy 302.125514 -360.547947)
			(xy 302.133276 -360.601931) (xy 302.133762 -360.6292) (xy 302.133762 -360.629454) (xy 302.133344 -360.654285)
			(xy 302.126874 -360.703523) (xy 302.114088 -360.751511) (xy 302.095201 -360.797441) (xy 302.083216 -360.819192)
			(xy 302.07839 -360.82732) (xy 302.072802 -360.836464) (xy 302.06696 -360.85653) (xy 302.066009 -360.860009)
			(xy 302.064984 -360.867148) (xy 302.064928 -360.870754) (xy 302.064928 -361.696) (xy 302.893982 -361.696)
			(xy 302.898053 -361.640378) (xy 302.910179 -361.585941) (xy 302.930102 -361.53385) (xy 302.957398 -361.485215)
			(xy 302.991484 -361.441072) (xy 303.031633 -361.402363) (xy 303.076991 -361.369912) (xy 303.126591 -361.344411)
			(xy 303.179375 -361.326404) (xy 303.234218 -361.316274) (xy 303.289952 -361.314237) (xy 303.345389 -361.320337)
			(xy 303.399346 -361.334443) (xy 303.450675 -361.356255) (xy 303.498281 -361.385309) (xy 303.541149 -361.420984)
			(xy 303.578366 -361.462521) (xy 303.609139 -361.509034) (xy 303.632811 -361.559531) (xy 303.648879 -361.612938)
			(xy 303.656999 -361.668114) (xy 303.657508 -361.696) (xy 303.656999 -361.723886) (xy 303.648879 -361.779062)
			(xy 303.632811 -361.832469) (xy 303.609139 -361.882966) (xy 303.578366 -361.929479) (xy 303.541149 -361.971016)
			(xy 303.498281 -362.006691) (xy 303.450675 -362.035745) (xy 303.399346 -362.057557) (xy 303.345389 -362.071663)
			(xy 303.289952 -362.077763) (xy 303.234218 -362.075726) (xy 303.179375 -362.065596) (xy 303.126591 -362.047589)
			(xy 303.076991 -362.022088) (xy 303.031633 -361.989637) (xy 302.991484 -361.950928) (xy 302.957398 -361.906785)
			(xy 302.930102 -361.85815) (xy 302.910179 -361.806059) (xy 302.898053 -361.751622) (xy 302.893982 -361.696)
			(xy 302.064928 -361.696) (xy 302.064928 -361.846368) (xy 302.064928 -361.850178) (xy 302.066471 -361.864753)
			(xy 302.076799 -361.89217) (xy 302.09448 -361.91553) (xy 302.118062 -361.932916) (xy 302.145606 -361.942897)
			(xy 302.174851 -361.944656) (xy 302.203393 -361.938046) (xy 302.228888 -361.923611) (xy 302.239426 -361.913424)
			(xy 302.257461 -361.89532) (xy 302.297534 -361.863608) (xy 302.341482 -361.837532) (xy 302.388519 -361.817559)
			(xy 302.437803 -361.804046) (xy 302.488449 -361.797235) (xy 302.514 -361.796838) (xy 302.541269 -361.797324)
			(xy 302.595253 -361.805086) (xy 302.647583 -361.820451) (xy 302.697193 -361.843108) (xy 302.743074 -361.872594)
			(xy 302.784291 -361.908309) (xy 302.820006 -361.949526) (xy 302.849492 -361.995407) (xy 302.872149 -362.045017)
			(xy 302.887514 -362.097347) (xy 302.895276 -362.151331) (xy 302.895276 -362.205869) (xy 302.887514 -362.259853)
			(xy 302.872149 -362.312183) (xy 302.849492 -362.361793) (xy 302.820006 -362.407674) (xy 302.784291 -362.448891)
			(xy 302.743074 -362.484606) (xy 302.697193 -362.514092) (xy 302.647583 -362.536749) (xy 302.595253 -362.552114)
			(xy 302.541269 -362.559876) (xy 302.514 -362.560362) (xy 302.488449 -362.559953) (xy 302.437804 -362.553136)
			(xy 302.388521 -362.539624) (xy 302.341481 -362.519657) (xy 302.297525 -362.493595) (xy 302.257439 -362.461901)
			(xy 302.239426 -362.443776) (xy 302.228907 -362.433564) (xy 302.203413 -362.419113) (xy 302.174865 -362.412493)
			(xy 302.145613 -362.41425) (xy 302.118063 -362.424238) (xy 302.094481 -362.441636) (xy 302.076808 -362.465013)
			(xy 302.066498 -362.492444) (xy 302.064928 -362.507022) (xy 302.064928 -364.3376) (xy 302.064674 -364.345982)
			(xy 302.064674 -364.446058) (xy 302.064144 -364.456048) (xy 302.056438 -364.474489) (xy 302.049688 -364.481872)
			(xy 301.982378 -364.549182) (xy 301.98187 -364.549944) (xy 301.973234 -364.558834) (xy 301.407068 -365.125)
			(xy 302.893982 -365.125) (xy 302.898053 -365.069378) (xy 302.910179 -365.014941) (xy 302.930102 -364.96285)
			(xy 302.957398 -364.914215) (xy 302.991484 -364.870072) (xy 303.031633 -364.831363) (xy 303.076991 -364.798912)
			(xy 303.126591 -364.773411) (xy 303.179375 -364.755404) (xy 303.234218 -364.745274) (xy 303.289952 -364.743237)
			(xy 303.345389 -364.749337) (xy 303.399346 -364.763443) (xy 303.450675 -364.785255) (xy 303.498281 -364.814309)
			(xy 303.541149 -364.849984) (xy 303.578366 -364.891521) (xy 303.609139 -364.938034) (xy 303.632811 -364.988531)
			(xy 303.648879 -365.041938) (xy 303.656999 -365.097114) (xy 303.657508 -365.125) (xy 303.656999 -365.152886)
			(xy 303.648879 -365.208062) (xy 303.632811 -365.261469) (xy 303.609139 -365.311966) (xy 303.578366 -365.358479)
			(xy 303.541149 -365.400016) (xy 303.498281 -365.435691) (xy 303.450675 -365.464745) (xy 303.399346 -365.486557)
			(xy 303.345389 -365.500663) (xy 303.289952 -365.506763) (xy 303.234218 -365.504726) (xy 303.179375 -365.494596)
			(xy 303.126591 -365.476589) (xy 303.076991 -365.451088) (xy 303.031633 -365.418637) (xy 302.991484 -365.379928)
			(xy 302.957398 -365.335785) (xy 302.930102 -365.28715) (xy 302.910179 -365.235059) (xy 302.898053 -365.180622)
			(xy 302.893982 -365.125) (xy 301.407068 -365.125) (xy 298.292774 -368.239294) (xy 298.287508 -368.245702)
			(xy 298.281152 -368.261013) (xy 298.280328 -368.269266) (xy 298.280328 -369.443) (xy 298.280074 -369.451382)
			(xy 298.280074 -369.551458) (xy 298.279544 -369.561448) (xy 298.271838 -369.579889) (xy 298.265088 -369.587272)
			(xy 298.197778 -369.654582) (xy 298.19727 -369.65509) (xy 298.188634 -369.664234) (xy 297.756834 -370.096034)
			(xy 298.449492 -370.096034) (xy 298.450015 -370.066743) (xy 298.45896 -370.008847) (xy 298.476646 -369.952998)
			(xy 298.502657 -369.900507) (xy 298.536382 -369.852606) (xy 298.57703 -369.81042) (xy 298.623646 -369.77494)
			(xy 298.649136 -369.7605) (xy 298.652383 -369.758729) (xy 298.658375 -369.754393) (xy 298.661074 -369.751864)
			(xy 301.893986 -366.518952) (xy 301.914577 -366.499132) (xy 301.960783 -366.4655) (xy 302.011682 -366.439512)
			(xy 302.06602 -366.421808) (xy 302.12246 -366.412824) (xy 302.151034 -366.412272) (xy 302.723296 -366.412272)
			(xy 302.733339 -366.411882) (xy 302.751936 -366.404308) (xy 302.759364 -366.39754) (xy 302.93183 -366.225074)
			(xy 302.934364 -366.222379) (xy 302.938702 -366.216388) (xy 302.940466 -366.213136) (xy 302.954898 -366.187642)
			(xy 302.990384 -366.141032) (xy 303.032574 -366.100389) (xy 303.080476 -366.066668) (xy 303.132967 -366.040659)
			(xy 303.188815 -366.022973) (xy 303.246709 -366.014025) (xy 303.276 -366.013492) (xy 303.303251 -366.013978)
			(xy 303.357199 -366.021734) (xy 303.409494 -366.037089) (xy 303.459071 -366.059731) (xy 303.504921 -366.089197)
			(xy 303.546112 -366.124888) (xy 303.581803 -366.166079) (xy 303.611269 -366.211929) (xy 303.633911 -366.261506)
			(xy 303.649266 -366.313801) (xy 303.657022 -366.367749) (xy 303.657508 -366.395) (xy 303.657013 -366.424292)
			(xy 303.648062 -366.482189) (xy 303.630372 -366.538039) (xy 303.604356 -366.59053) (xy 303.570627 -366.63843)
			(xy 303.529975 -366.680615) (xy 303.483356 -366.716095) (xy 303.457864 -366.730534) (xy 303.454614 -366.732301)
			(xy 303.448624 -366.73664) (xy 303.445926 -366.73917) (xy 303.191164 -366.994186) (xy 303.184455 -367.001586)
			(xy 303.176822 -367.020023) (xy 303.176822 -367.039977) (xy 303.184455 -367.058414) (xy 303.191164 -367.065814)
			(xy 303.445926 -367.32083) (xy 303.448621 -367.323364) (xy 303.454612 -367.327702) (xy 303.457864 -367.329466)
			(xy 303.483358 -367.343898) (xy 303.529968 -367.379384) (xy 303.570611 -367.421574) (xy 303.604332 -367.469476)
			(xy 303.630341 -367.521967) (xy 303.648027 -367.577815) (xy 303.656975 -367.635709) (xy 303.657508 -367.665)
			(xy 303.657022 -367.692251) (xy 303.649266 -367.746199) (xy 303.633911 -367.798494) (xy 303.611269 -367.848071)
			(xy 303.581803 -367.893921) (xy 303.546112 -367.935112) (xy 303.504921 -367.970803) (xy 303.459071 -368.000269)
			(xy 303.409494 -368.022911) (xy 303.357199 -368.038266) (xy 303.303251 -368.046022) (xy 303.276 -368.046508)
			(xy 303.246708 -368.046013) (xy 303.188811 -368.037062) (xy 303.132961 -368.019372) (xy 303.08047 -367.993356)
			(xy 303.03257 -367.959627) (xy 302.990385 -367.918975) (xy 302.954905 -367.872356) (xy 302.940466 -367.846864)
			(xy 302.938699 -367.843614) (xy 302.93436 -367.837624) (xy 302.93183 -367.834926) (xy 302.708564 -367.61166)
			(xy 302.701086 -367.604963) (xy 302.682524 -367.597374) (xy 302.672496 -367.596928) (xy 302.482504 -367.596928)
			(xy 302.472461 -367.597318) (xy 302.453864 -367.604892) (xy 302.446436 -367.61166) (xy 301.453296 -368.6048)
			(xy 304.113692 -368.6048) (xy 304.113692 -361.061) (xy 304.114178 -361.033749) (xy 304.121934 -360.979801)
			(xy 304.137289 -360.927506) (xy 304.159931 -360.877929) (xy 304.189397 -360.832079) (xy 304.225088 -360.790888)
			(xy 304.266279 -360.755197) (xy 304.312129 -360.725731) (xy 304.361706 -360.703089) (xy 304.414001 -360.687734)
			(xy 304.467949 -360.679978) (xy 304.522451 -360.679978) (xy 304.576399 -360.687734) (xy 304.628694 -360.703089)
			(xy 304.678271 -360.725731) (xy 304.724121 -360.755197) (xy 304.765312 -360.790888) (xy 304.801003 -360.832079)
			(xy 304.830469 -360.877929) (xy 304.853111 -360.927506) (xy 304.868466 -360.979801) (xy 304.876222 -361.033749)
			(xy 304.876708 -361.061) (xy 304.876708 -361.302808) (xy 305.2097 -361.302808) (xy 305.213771 -361.247186)
			(xy 305.225897 -361.192749) (xy 305.24582 -361.140658) (xy 305.273116 -361.092023) (xy 305.307202 -361.04788)
			(xy 305.347351 -361.009171) (xy 305.392709 -360.97672) (xy 305.442309 -360.951219) (xy 305.495093 -360.933212)
			(xy 305.549936 -360.923082) (xy 305.60567 -360.921045) (xy 305.661107 -360.927145) (xy 305.715064 -360.941251)
			(xy 305.766393 -360.963063) (xy 305.813999 -360.992117) (xy 305.856867 -361.027792) (xy 305.894084 -361.069329)
			(xy 305.924857 -361.115842) (xy 305.948529 -361.166339) (xy 305.964597 -361.219746) (xy 305.972717 -361.274922)
			(xy 305.973226 -361.302808) (xy 305.972717 -361.330694) (xy 305.964597 -361.38587) (xy 305.948529 -361.439277)
			(xy 305.924857 -361.489774) (xy 305.894084 -361.536287) (xy 305.856867 -361.577824) (xy 305.813999 -361.613499)
			(xy 305.766393 -361.642553) (xy 305.715064 -361.664365) (xy 305.661107 -361.678471) (xy 305.60567 -361.684571)
			(xy 305.549936 -361.682534) (xy 305.495093 -361.672404) (xy 305.442309 -361.654397) (xy 305.392709 -361.628896)
			(xy 305.347351 -361.596445) (xy 305.307202 -361.557736) (xy 305.273116 -361.513593) (xy 305.24582 -361.464958)
			(xy 305.225897 -361.412867) (xy 305.213771 -361.35843) (xy 305.2097 -361.302808) (xy 304.876708 -361.302808)
			(xy 304.876708 -362.56214) (xy 305.030376 -362.56214) (xy 305.034447 -362.506518) (xy 305.046573 -362.452081)
			(xy 305.066496 -362.39999) (xy 305.093792 -362.351355) (xy 305.127878 -362.307212) (xy 305.168027 -362.268503)
			(xy 305.213385 -362.236052) (xy 305.262985 -362.210551) (xy 305.315769 -362.192544) (xy 305.370612 -362.182414)
			(xy 305.426346 -362.180377) (xy 305.481783 -362.186477) (xy 305.53574 -362.200583) (xy 305.587069 -362.222395)
			(xy 305.634675 -362.251449) (xy 305.677543 -362.287124) (xy 305.71476 -362.328661) (xy 305.745533 -362.375174)
			(xy 305.769205 -362.425671) (xy 305.785273 -362.479078) (xy 305.793393 -362.534254) (xy 305.793902 -362.56214)
			(xy 305.793393 -362.590026) (xy 305.785273 -362.645202) (xy 305.769205 -362.698609) (xy 305.745533 -362.749106)
			(xy 305.71476 -362.795619) (xy 305.677543 -362.837156) (xy 305.634675 -362.872831) (xy 305.587069 -362.901885)
			(xy 305.53574 -362.923697) (xy 305.481783 -362.937803) (xy 305.426346 -362.943903) (xy 305.370612 -362.941866)
			(xy 305.315769 -362.931736) (xy 305.262985 -362.913729) (xy 305.213385 -362.888228) (xy 305.168027 -362.855777)
			(xy 305.127878 -362.817068) (xy 305.093792 -362.772925) (xy 305.066496 -362.72429) (xy 305.046573 -362.672199)
			(xy 305.034447 -362.617762) (xy 305.030376 -362.56214) (xy 304.876708 -362.56214) (xy 304.876708 -363.846872)
			(xy 305.046632 -363.846872) (xy 305.050703 -363.79125) (xy 305.062829 -363.736813) (xy 305.082752 -363.684722)
			(xy 305.110048 -363.636087) (xy 305.144134 -363.591944) (xy 305.184283 -363.553235) (xy 305.229641 -363.520784)
			(xy 305.279241 -363.495283) (xy 305.332025 -363.477276) (xy 305.386868 -363.467146) (xy 305.442602 -363.465109)
			(xy 305.498039 -363.471209) (xy 305.551996 -363.485315) (xy 305.603325 -363.507127) (xy 305.650931 -363.536181)
			(xy 305.693799 -363.571856) (xy 305.731016 -363.613393) (xy 305.761789 -363.659906) (xy 305.785461 -363.710403)
			(xy 305.801529 -363.76381) (xy 305.809649 -363.818986) (xy 305.810158 -363.846872) (xy 305.809649 -363.874758)
			(xy 305.801529 -363.929934) (xy 305.785461 -363.983341) (xy 305.761789 -364.033838) (xy 305.731016 -364.080351)
			(xy 305.693799 -364.121888) (xy 305.650931 -364.157563) (xy 305.603325 -364.186617) (xy 305.551996 -364.208429)
			(xy 305.498039 -364.222535) (xy 305.442602 -364.228635) (xy 305.386868 -364.226598) (xy 305.332025 -364.216468)
			(xy 305.279241 -364.198461) (xy 305.229641 -364.17296) (xy 305.184283 -364.140509) (xy 305.144134 -364.1018)
			(xy 305.110048 -364.057657) (xy 305.082752 -364.009022) (xy 305.062829 -363.956931) (xy 305.050703 -363.902494)
			(xy 305.046632 -363.846872) (xy 304.876708 -363.846872) (xy 304.876708 -365.125) (xy 305.190142 -365.125)
			(xy 305.194213 -365.069378) (xy 305.206339 -365.014941) (xy 305.226262 -364.96285) (xy 305.253558 -364.914215)
			(xy 305.287644 -364.870072) (xy 305.327793 -364.831363) (xy 305.373151 -364.798912) (xy 305.422751 -364.773411)
			(xy 305.475535 -364.755404) (xy 305.530378 -364.745274) (xy 305.586112 -364.743237) (xy 305.641549 -364.749337)
			(xy 305.695506 -364.763443) (xy 305.746835 -364.785255) (xy 305.794441 -364.814309) (xy 305.837309 -364.849984)
			(xy 305.874526 -364.891521) (xy 305.878979 -364.898251) (xy 306.984378 -364.898251) (xy 306.984378 -364.843749)
			(xy 306.992134 -364.789801) (xy 307.007489 -364.737506) (xy 307.030131 -364.687929) (xy 307.059597 -364.642079)
			(xy 307.095288 -364.600888) (xy 307.136479 -364.565197) (xy 307.182329 -364.535731) (xy 307.231906 -364.513089)
			(xy 307.284201 -364.497734) (xy 307.338149 -364.489978) (xy 307.3654 -364.489492) (xy 307.391858 -364.489953)
			(xy 307.444268 -364.497261) (xy 307.495166 -364.511736) (xy 307.543578 -364.533102) (xy 307.566314 -364.546642)
			(xy 307.579346 -364.554087) (xy 307.608341 -364.561787) (xy 307.638322 -364.56074) (xy 307.666709 -364.551035)
			(xy 307.691056 -364.533507) (xy 307.709267 -364.509668) (xy 307.719774 -364.481568) (xy 307.721254 -364.466632)
			(xy 307.723585 -364.437914) (xy 307.735709 -364.381591) (xy 307.756165 -364.327731) (xy 307.78449 -364.277561)
			(xy 307.820038 -364.232222) (xy 307.862001 -364.192745) (xy 307.909424 -364.160029) (xy 307.961228 -364.134817)
			(xy 308.016235 -364.117684) (xy 308.073193 -364.109019) (xy 308.102 -364.108492) (xy 308.129251 -364.108978)
			(xy 308.183199 -364.116734) (xy 308.235494 -364.132089) (xy 308.285071 -364.154731) (xy 308.330921 -364.184197)
			(xy 308.372112 -364.219888) (xy 308.407803 -364.261079) (xy 308.437269 -364.306929) (xy 308.459911 -364.356506)
			(xy 308.475266 -364.408801) (xy 308.483022 -364.462749) (xy 308.483022 -364.517251) (xy 308.475266 -364.571199)
			(xy 308.459911 -364.623494) (xy 308.437269 -364.673071) (xy 308.407803 -364.718921) (xy 308.386073 -364.744)
			(xy 309.370982 -364.744) (xy 309.375053 -364.688378) (xy 309.387179 -364.633941) (xy 309.407102 -364.58185)
			(xy 309.434398 -364.533215) (xy 309.468484 -364.489072) (xy 309.508633 -364.450363) (xy 309.553991 -364.417912)
			(xy 309.603591 -364.392411) (xy 309.656375 -364.374404) (xy 309.711218 -364.364274) (xy 309.766952 -364.362237)
			(xy 309.822389 -364.368337) (xy 309.876346 -364.382443) (xy 309.927675 -364.404255) (xy 309.975281 -364.433309)
			(xy 310.018149 -364.468984) (xy 310.055366 -364.510521) (xy 310.086139 -364.557034) (xy 310.109811 -364.607531)
			(xy 310.125879 -364.660938) (xy 310.133999 -364.716114) (xy 310.134508 -364.744) (xy 310.133999 -364.771886)
			(xy 310.125879 -364.827062) (xy 310.109811 -364.880469) (xy 310.086139 -364.930966) (xy 310.055366 -364.977479)
			(xy 310.018149 -365.019016) (xy 309.975281 -365.054691) (xy 309.927675 -365.083745) (xy 309.876346 -365.105557)
			(xy 309.822389 -365.119663) (xy 309.766952 -365.125763) (xy 309.711218 -365.123726) (xy 309.656375 -365.113596)
			(xy 309.603591 -365.095589) (xy 309.553991 -365.070088) (xy 309.508633 -365.037637) (xy 309.468484 -364.998928)
			(xy 309.434398 -364.954785) (xy 309.407102 -364.90615) (xy 309.387179 -364.854059) (xy 309.375053 -364.799622)
			(xy 309.370982 -364.744) (xy 308.386073 -364.744) (xy 308.372112 -364.760112) (xy 308.330921 -364.795803)
			(xy 308.285071 -364.825269) (xy 308.235494 -364.847911) (xy 308.183199 -364.863266) (xy 308.129251 -364.871022)
			(xy 308.102 -364.871508) (xy 308.075542 -364.871047) (xy 308.023132 -364.863739) (xy 307.972234 -364.849264)
			(xy 307.923822 -364.827898) (xy 307.901086 -364.814358) (xy 307.888054 -364.806913) (xy 307.859059 -364.799213)
			(xy 307.829078 -364.80026) (xy 307.800691 -364.809965) (xy 307.776344 -364.827493) (xy 307.758133 -364.851332)
			(xy 307.747626 -364.879432) (xy 307.746146 -364.894368) (xy 307.743815 -364.923086) (xy 307.731691 -364.979409)
			(xy 307.711235 -365.033269) (xy 307.68291 -365.083439) (xy 307.647362 -365.128778) (xy 307.605399 -365.168255)
			(xy 307.557976 -365.200971) (xy 307.506172 -365.226183) (xy 307.451165 -365.243316) (xy 307.394207 -365.251981)
			(xy 307.3654 -365.252508) (xy 307.338149 -365.252022) (xy 307.284201 -365.244266) (xy 307.231906 -365.228911)
			(xy 307.182329 -365.206269) (xy 307.136479 -365.176803) (xy 307.095288 -365.141112) (xy 307.059597 -365.099921)
			(xy 307.030131 -365.054071) (xy 307.007489 -365.004494) (xy 306.992134 -364.952199) (xy 306.984378 -364.898251)
			(xy 305.878979 -364.898251) (xy 305.905299 -364.938034) (xy 305.928971 -364.988531) (xy 305.945039 -365.041938)
			(xy 305.953159 -365.097114) (xy 305.953668 -365.125) (xy 305.953159 -365.152886) (xy 305.945039 -365.208062)
			(xy 305.928971 -365.261469) (xy 305.905299 -365.311966) (xy 305.874526 -365.358479) (xy 305.837309 -365.400016)
			(xy 305.794441 -365.435691) (xy 305.746835 -365.464745) (xy 305.695506 -365.486557) (xy 305.641549 -365.500663)
			(xy 305.586112 -365.506763) (xy 305.530378 -365.504726) (xy 305.475535 -365.494596) (xy 305.422751 -365.476589)
			(xy 305.373151 -365.451088) (xy 305.327793 -365.418637) (xy 305.287644 -365.379928) (xy 305.253558 -365.335785)
			(xy 305.226262 -365.28715) (xy 305.206339 -365.235059) (xy 305.194213 -365.180622) (xy 305.190142 -365.125)
			(xy 304.876708 -365.125) (xy 304.876708 -365.76) (xy 307.059582 -365.76) (xy 307.063653 -365.704378)
			(xy 307.075779 -365.649941) (xy 307.095702 -365.59785) (xy 307.122998 -365.549215) (xy 307.157084 -365.505072)
			(xy 307.197233 -365.466363) (xy 307.242591 -365.433912) (xy 307.292191 -365.408411) (xy 307.344975 -365.390404)
			(xy 307.399818 -365.380274) (xy 307.455552 -365.378237) (xy 307.510989 -365.384337) (xy 307.564946 -365.398443)
			(xy 307.616275 -365.420255) (xy 307.663881 -365.449309) (xy 307.706749 -365.484984) (xy 307.743966 -365.526521)
			(xy 307.774739 -365.573034) (xy 307.798411 -365.623531) (xy 307.814479 -365.676938) (xy 307.819227 -365.7092)
			(xy 308.202582 -365.7092) (xy 308.206653 -365.653578) (xy 308.218779 -365.599141) (xy 308.238702 -365.54705)
			(xy 308.265998 -365.498415) (xy 308.300084 -365.454272) (xy 308.340233 -365.415563) (xy 308.385591 -365.383112)
			(xy 308.435191 -365.357611) (xy 308.487975 -365.339604) (xy 308.542818 -365.329474) (xy 308.598552 -365.327437)
			(xy 308.653989 -365.333537) (xy 308.707946 -365.347643) (xy 308.759275 -365.369455) (xy 308.806881 -365.398509)
			(xy 308.849749 -365.434184) (xy 308.868579 -365.4552) (xy 309.96458 -365.4552) (xy 309.968651 -365.399578)
			(xy 309.980777 -365.345141) (xy 310.0007 -365.29305) (xy 310.027996 -365.244415) (xy 310.062082 -365.200272)
			(xy 310.102231 -365.161563) (xy 310.147589 -365.129112) (xy 310.197189 -365.103611) (xy 310.249973 -365.085604)
			(xy 310.304816 -365.075474) (xy 310.36055 -365.073437) (xy 310.415987 -365.079537) (xy 310.469944 -365.093643)
			(xy 310.521273 -365.115455) (xy 310.568879 -365.144509) (xy 310.611747 -365.180184) (xy 310.648964 -365.221721)
			(xy 310.679737 -365.268234) (xy 310.703409 -365.318731) (xy 310.719477 -365.372138) (xy 310.727597 -365.427314)
			(xy 310.728106 -365.4552) (xy 310.727597 -365.483086) (xy 310.719477 -365.538262) (xy 310.703409 -365.591669)
			(xy 310.679737 -365.642166) (xy 310.648964 -365.688679) (xy 310.611747 -365.730216) (xy 310.568879 -365.765891)
			(xy 310.521273 -365.794945) (xy 310.469944 -365.816757) (xy 310.415987 -365.830863) (xy 310.36055 -365.836963)
			(xy 310.304816 -365.834926) (xy 310.249973 -365.824796) (xy 310.197189 -365.806789) (xy 310.147589 -365.781288)
			(xy 310.102231 -365.748837) (xy 310.062082 -365.710128) (xy 310.027996 -365.665985) (xy 310.0007 -365.61735)
			(xy 309.980777 -365.565259) (xy 309.968651 -365.510822) (xy 309.96458 -365.4552) (xy 308.868579 -365.4552)
			(xy 308.886966 -365.475721) (xy 308.917739 -365.522234) (xy 308.941411 -365.572731) (xy 308.957479 -365.626138)
			(xy 308.965599 -365.681314) (xy 308.966108 -365.7092) (xy 308.965599 -365.737086) (xy 308.957479 -365.792262)
			(xy 308.941411 -365.845669) (xy 308.917739 -365.896166) (xy 308.886966 -365.942679) (xy 308.849749 -365.984216)
			(xy 308.806881 -366.019891) (xy 308.759275 -366.048945) (xy 308.707946 -366.070757) (xy 308.653989 -366.084863)
			(xy 308.598552 -366.090963) (xy 308.542818 -366.088926) (xy 308.487975 -366.078796) (xy 308.435191 -366.060789)
			(xy 308.385591 -366.035288) (xy 308.340233 -366.002837) (xy 308.300084 -365.964128) (xy 308.265998 -365.919985)
			(xy 308.238702 -365.87135) (xy 308.218779 -365.819259) (xy 308.206653 -365.764822) (xy 308.202582 -365.7092)
			(xy 307.819227 -365.7092) (xy 307.822599 -365.732114) (xy 307.823108 -365.76) (xy 307.822599 -365.787886)
			(xy 307.814479 -365.843062) (xy 307.798411 -365.896469) (xy 307.774739 -365.946966) (xy 307.743966 -365.993479)
			(xy 307.706749 -366.035016) (xy 307.663881 -366.070691) (xy 307.616275 -366.099745) (xy 307.564946 -366.121557)
			(xy 307.510989 -366.135663) (xy 307.455552 -366.141763) (xy 307.399818 -366.139726) (xy 307.344975 -366.129596)
			(xy 307.292191 -366.111589) (xy 307.242591 -366.086088) (xy 307.197233 -366.053637) (xy 307.157084 -366.014928)
			(xy 307.122998 -365.970785) (xy 307.095702 -365.92215) (xy 307.075779 -365.870059) (xy 307.063653 -365.815622)
			(xy 307.059582 -365.76) (xy 304.876708 -365.76) (xy 304.876708 -366.268) (xy 311.951876 -366.268)
			(xy 311.955947 -366.212378) (xy 311.968073 -366.157941) (xy 311.987996 -366.10585) (xy 312.015292 -366.057215)
			(xy 312.049378 -366.013072) (xy 312.089527 -365.974363) (xy 312.134885 -365.941912) (xy 312.184485 -365.916411)
			(xy 312.237269 -365.898404) (xy 312.292112 -365.888274) (xy 312.347846 -365.886237) (xy 312.403283 -365.892337)
			(xy 312.45724 -365.906443) (xy 312.508569 -365.928255) (xy 312.556175 -365.957309) (xy 312.599043 -365.992984)
			(xy 312.63626 -366.034521) (xy 312.667033 -366.081034) (xy 312.690705 -366.131531) (xy 312.706773 -366.184938)
			(xy 312.714893 -366.240114) (xy 312.715402 -366.268) (xy 312.714893 -366.295886) (xy 312.706773 -366.351062)
			(xy 312.690705 -366.404469) (xy 312.667033 -366.454966) (xy 312.63626 -366.501479) (xy 312.599043 -366.543016)
			(xy 312.556175 -366.578691) (xy 312.508569 -366.607745) (xy 312.45724 -366.629557) (xy 312.403283 -366.643663)
			(xy 312.347846 -366.649763) (xy 312.292112 -366.647726) (xy 312.237269 -366.637596) (xy 312.184485 -366.619589)
			(xy 312.134885 -366.594088) (xy 312.089527 -366.561637) (xy 312.049378 -366.522928) (xy 312.015292 -366.478785)
			(xy 311.987996 -366.43015) (xy 311.968073 -366.378059) (xy 311.955947 -366.323622) (xy 311.951876 -366.268)
			(xy 304.876708 -366.268) (xy 304.876708 -366.8522) (xy 311.072782 -366.8522) (xy 311.076853 -366.796578)
			(xy 311.088979 -366.742141) (xy 311.108902 -366.69005) (xy 311.136198 -366.641415) (xy 311.170284 -366.597272)
			(xy 311.210433 -366.558563) (xy 311.255791 -366.526112) (xy 311.305391 -366.500611) (xy 311.358175 -366.482604)
			(xy 311.413018 -366.472474) (xy 311.468752 -366.470437) (xy 311.524189 -366.476537) (xy 311.578146 -366.490643)
			(xy 311.629475 -366.512455) (xy 311.677081 -366.541509) (xy 311.719949 -366.577184) (xy 311.757166 -366.618721)
			(xy 311.787939 -366.665234) (xy 311.811611 -366.715731) (xy 311.827679 -366.769138) (xy 311.835799 -366.824314)
			(xy 311.836308 -366.8522) (xy 311.835799 -366.880086) (xy 311.827679 -366.935262) (xy 311.811611 -366.988669)
			(xy 311.787939 -367.039166) (xy 311.757166 -367.085679) (xy 311.719949 -367.127216) (xy 311.677081 -367.162891)
			(xy 311.629475 -367.191945) (xy 311.578146 -367.213757) (xy 311.524189 -367.227863) (xy 311.468752 -367.233963)
			(xy 311.413018 -367.231926) (xy 311.358175 -367.221796) (xy 311.305391 -367.203789) (xy 311.255791 -367.178288)
			(xy 311.210433 -367.145837) (xy 311.170284 -367.107128) (xy 311.136198 -367.062985) (xy 311.108902 -367.01435)
			(xy 311.088979 -366.962259) (xy 311.076853 -366.907822) (xy 311.072782 -366.8522) (xy 304.876708 -366.8522)
			(xy 304.876708 -367.3602) (xy 310.183782 -367.3602) (xy 310.187853 -367.304578) (xy 310.199979 -367.250141)
			(xy 310.219902 -367.19805) (xy 310.247198 -367.149415) (xy 310.281284 -367.105272) (xy 310.321433 -367.066563)
			(xy 310.366791 -367.034112) (xy 310.416391 -367.008611) (xy 310.469175 -366.990604) (xy 310.524018 -366.980474)
			(xy 310.579752 -366.978437) (xy 310.635189 -366.984537) (xy 310.689146 -366.998643) (xy 310.740475 -367.020455)
			(xy 310.788081 -367.049509) (xy 310.830949 -367.085184) (xy 310.868166 -367.126721) (xy 310.898939 -367.173234)
			(xy 310.922611 -367.223731) (xy 310.938679 -367.277138) (xy 310.946799 -367.332314) (xy 310.947308 -367.3602)
			(xy 310.946799 -367.388086) (xy 310.938679 -367.443262) (xy 310.922611 -367.496669) (xy 310.898939 -367.547166)
			(xy 310.868166 -367.593679) (xy 310.830949 -367.635216) (xy 310.788081 -367.670891) (xy 310.740475 -367.699945)
			(xy 310.689146 -367.721757) (xy 310.635189 -367.735863) (xy 310.579752 -367.741963) (xy 310.524018 -367.739926)
			(xy 310.469175 -367.729796) (xy 310.416391 -367.711789) (xy 310.366791 -367.686288) (xy 310.321433 -367.653837)
			(xy 310.281284 -367.615128) (xy 310.247198 -367.570985) (xy 310.219902 -367.52235) (xy 310.199979 -367.470259)
			(xy 310.187853 -367.415822) (xy 310.183782 -367.3602) (xy 304.876708 -367.3602) (xy 304.876708 -368.0714)
			(xy 309.548782 -368.0714) (xy 309.552853 -368.015778) (xy 309.564979 -367.961341) (xy 309.584902 -367.90925)
			(xy 309.612198 -367.860615) (xy 309.646284 -367.816472) (xy 309.686433 -367.777763) (xy 309.731791 -367.745312)
			(xy 309.781391 -367.719811) (xy 309.834175 -367.701804) (xy 309.889018 -367.691674) (xy 309.944752 -367.689637)
			(xy 310.000189 -367.695737) (xy 310.054146 -367.709843) (xy 310.105475 -367.731655) (xy 310.153081 -367.760709)
			(xy 310.195949 -367.796384) (xy 310.233166 -367.837921) (xy 310.263939 -367.884434) (xy 310.287611 -367.934931)
			(xy 310.303679 -367.988338) (xy 310.311799 -368.043514) (xy 310.312308 -368.0714) (xy 310.311799 -368.099286)
			(xy 310.303679 -368.154462) (xy 310.287611 -368.207869) (xy 310.263939 -368.258366) (xy 310.233166 -368.304879)
			(xy 310.195949 -368.346416) (xy 310.153081 -368.382091) (xy 310.105475 -368.411145) (xy 310.054146 -368.432957)
			(xy 310.000189 -368.447063) (xy 309.944752 -368.453163) (xy 309.889018 -368.451126) (xy 309.834175 -368.440996)
			(xy 309.781391 -368.422989) (xy 309.731791 -368.397488) (xy 309.686433 -368.365037) (xy 309.646284 -368.326328)
			(xy 309.612198 -368.282185) (xy 309.584902 -368.23355) (xy 309.564979 -368.181459) (xy 309.552853 -368.127022)
			(xy 309.548782 -368.0714) (xy 304.876708 -368.0714) (xy 304.876708 -368.42573) (xy 304.877085 -368.435774)
			(xy 304.884669 -368.45437) (xy 304.89144 -368.461798) (xy 306.416202 -369.98656) (xy 306.42369 -369.993245)
			(xy 306.442244 -370.00084) (xy 306.45227 -370.001292) (xy 313.28233 -370.001292) (xy 313.292374 -370.000915)
			(xy 313.31097 -369.993331) (xy 313.318398 -369.98656) (xy 317.02756 -366.277398) (xy 317.034245 -366.26991)
			(xy 317.04184 -366.251356) (xy 317.042292 -366.24133) (xy 317.042292 -359.5878) (xy 317.042873 -359.557822)
			(xy 317.052264 -359.498606) (xy 317.070801 -359.441587) (xy 317.098026 -359.388169) (xy 317.13327 -359.339665)
			(xy 317.154052 -359.318052) (xy 317.712852 -358.759252) (xy 317.734461 -358.738462) (xy 317.782959 -358.703205)
			(xy 317.836377 -358.675972) (xy 317.893399 -358.657435) (xy 317.95262 -358.64805) (xy 317.9826 -358.647492)
			(xy 318.2874 -358.647492) (xy 318.314651 -358.647978) (xy 318.368599 -358.655734) (xy 318.420894 -358.671089)
			(xy 318.470471 -358.693731) (xy 318.516321 -358.723197) (xy 318.557512 -358.758888) (xy 318.593203 -358.800079)
			(xy 318.622669 -358.845929) (xy 318.645311 -358.895506) (xy 318.660666 -358.947801) (xy 318.668422 -359.001749)
			(xy 318.668422 -359.056251) (xy 318.661823 -359.102152) (xy 335.533238 -359.102152) (xy 335.533763 -359.074042)
			(xy 335.542002 -359.018429) (xy 335.558308 -358.964625) (xy 335.582329 -358.913795) (xy 335.613546 -358.867038)
			(xy 335.632044 -358.845866) (xy 335.638648 -358.838754) (xy 335.645252 -358.82199) (xy 335.646522 -358.736138)
			(xy 335.640426 -358.71912) (xy 335.63433 -358.711754) (xy 335.61724 -358.690976) (xy 335.58848 -358.645509)
			(xy 335.566395 -358.596451) (xy 335.551422 -358.544777) (xy 335.54386 -358.491512) (xy 335.543398 -358.464612)
			(xy 335.543867 -358.437359) (xy 335.551622 -358.383408) (xy 335.566977 -358.33111) (xy 335.589618 -358.28153)
			(xy 335.619086 -358.235676) (xy 335.654779 -358.194483) (xy 335.695971 -358.158789) (xy 335.741824 -358.129321)
			(xy 335.791404 -358.106679) (xy 335.843702 -358.091323) (xy 335.897653 -358.083567) (xy 335.924906 -358.083104)
			(xy 335.953823 -358.083617) (xy 336.010995 -358.092347) (xy 336.066194 -358.109606) (xy 336.118155 -358.134998)
			(xy 336.165689 -358.167943) (xy 336.207706 -358.207684) (xy 336.225896 -358.23017) (xy 336.233452 -358.238937)
			(xy 336.254216 -358.249115) (xy 336.265774 -358.249728) (xy 336.346038 -358.249728) (xy 336.357605 -358.249147)
			(xy 336.378378 -358.238962) (xy 336.385916 -358.23017) (xy 336.402669 -358.209387) (xy 336.441023 -358.172257)
			(xy 336.484177 -358.140835) (xy 336.531291 -358.115736) (xy 336.581443 -358.09745) (xy 336.633654 -358.086333)
			(xy 336.686906 -358.082603) (xy 336.740158 -358.086333) (xy 336.792369 -358.09745) (xy 336.842521 -358.115736)
			(xy 336.889635 -358.140835) (xy 336.932789 -358.172257) (xy 336.971143 -358.209387) (xy 336.987896 -358.23017)
			(xy 336.995452 -358.238937) (xy 337.016216 -358.249115) (xy 337.027774 -358.249728) (xy 337.108038 -358.249728)
			(xy 337.119605 -358.249147) (xy 337.140378 -358.238962) (xy 337.147916 -358.23017) (xy 337.16609 -358.207673)
			(xy 337.208115 -358.16794) (xy 337.255653 -358.135003) (xy 337.307618 -358.109617) (xy 337.362818 -358.092364)
			(xy 337.419989 -358.083638) (xy 337.448906 -358.083104) (xy 337.477834 -358.083626) (xy 337.535025 -358.092383)
			(xy 337.590236 -358.109678) (xy 337.642201 -358.135116) (xy 337.689727 -358.168113) (xy 337.731722 -358.207911)
			(xy 337.749896 -358.230424) (xy 337.757262 -358.239568) (xy 337.777582 -358.249728) (xy 337.880452 -358.251252)
			(xy 337.90128 -358.2416) (xy 337.908646 -358.232456) (xy 337.915758 -358.224074) (xy 337.921854 -358.216962)
			(xy 337.928204 -358.199944) (xy 337.928204 -358.1146) (xy 337.921854 -358.097582) (xy 337.915758 -358.09047)
			(xy 337.898131 -358.069528) (xy 337.868419 -358.023557) (xy 337.845581 -357.973812) (xy 337.830087 -357.921314)
			(xy 337.822254 -357.86714) (xy 337.821778 -357.839772) (xy 337.822252 -357.812521) (xy 337.830012 -357.758573)
			(xy 337.84537 -357.706279) (xy 337.868013 -357.656703) (xy 337.897481 -357.610853) (xy 337.933174 -357.569664)
			(xy 337.974364 -357.533973) (xy 338.020215 -357.504506) (xy 338.069792 -357.481865) (xy 338.122087 -357.466509)
			(xy 338.176035 -357.458751) (xy 338.203286 -357.458264) (xy 338.232204 -357.458768) (xy 338.289377 -357.467497)
			(xy 338.344577 -357.484756) (xy 338.396539 -357.51015) (xy 338.444072 -357.543097) (xy 338.486087 -357.582842)
			(xy 338.504276 -357.60533) (xy 338.511847 -357.614082) (xy 338.532599 -357.62427) (xy 338.544154 -357.624888)
			(xy 338.624418 -357.624888) (xy 338.635988 -357.624332) (xy 338.656759 -357.614128) (xy 338.664296 -357.60533)
			(xy 338.681049 -357.584547) (xy 338.719403 -357.547417) (xy 338.762557 -357.515995) (xy 338.809671 -357.490896)
			(xy 338.859823 -357.47261) (xy 338.912034 -357.461493) (xy 338.965286 -357.457763) (xy 339.018538 -357.461493)
			(xy 339.070749 -357.47261) (xy 339.120901 -357.490896) (xy 339.168015 -357.515995) (xy 339.211169 -357.547417)
			(xy 339.249523 -357.584547) (xy 339.266276 -357.60533) (xy 339.273847 -357.614082) (xy 339.294599 -357.62427)
			(xy 339.306154 -357.624888) (xy 339.386418 -357.624888) (xy 339.397988 -357.624332) (xy 339.418759 -357.614128)
			(xy 339.426296 -357.60533) (xy 339.444497 -357.582855) (xy 339.486514 -357.543118) (xy 339.534046 -357.510177)
			(xy 339.586006 -357.484787) (xy 339.641202 -357.467529) (xy 339.69837 -357.458799) (xy 339.727286 -357.458264)
			(xy 339.754536 -357.458791) (xy 339.80848 -357.466545) (xy 339.860773 -357.481897) (xy 339.910348 -357.504534)
			(xy 339.956197 -357.533997) (xy 339.997386 -357.569684) (xy 340.033078 -357.610869) (xy 340.062545 -357.656715)
			(xy 340.085188 -357.706288) (xy 340.100546 -357.758579) (xy 340.108306 -357.812522) (xy 340.108794 -357.839772)
			(xy 340.108313 -357.867142) (xy 340.100499 -357.92132) (xy 340.085013 -357.973823) (xy 340.062175 -358.02357)
			(xy 340.032454 -358.069538) (xy 340.030165 -358.072254) (xy 340.314959 -358.072254) (xy 340.314959 -358.017746)
			(xy 340.322717 -357.963791) (xy 340.338075 -357.911491) (xy 340.360721 -357.861908) (xy 340.390192 -357.816054)
			(xy 340.42589 -357.77486) (xy 340.467087 -357.739167) (xy 340.512945 -357.709701) (xy 340.56253 -357.687061)
			(xy 340.614833 -357.671708) (xy 340.668787 -357.663956) (xy 340.696042 -357.663496) (xy 340.723411 -357.663997)
			(xy 340.777589 -357.671807) (xy 340.830091 -357.687288) (xy 340.879839 -357.710121) (xy 340.925807 -357.739838)
			(xy 340.94674 -357.757476) (xy 340.953852 -357.763572) (xy 340.97087 -357.769922) (xy 341.056214 -357.769922)
			(xy 341.073232 -357.763572) (xy 341.080344 -357.757476) (xy 341.101277 -357.739835) (xy 341.147245 -357.710111)
			(xy 341.196991 -357.687265) (xy 341.249493 -357.671769) (xy 341.303671 -357.66394) (xy 341.358413 -357.66394)
			(xy 341.412591 -357.671769) (xy 341.465093 -357.687265) (xy 341.514839 -357.710111) (xy 341.560807 -357.739835)
			(xy 341.58174 -357.757476) (xy 341.588852 -357.763572) (xy 341.60587 -357.769922) (xy 341.691214 -357.769922)
			(xy 341.708232 -357.763572) (xy 341.715344 -357.757476) (xy 341.736277 -357.739835) (xy 341.782245 -357.710111)
			(xy 341.831991 -357.687265) (xy 341.884493 -357.671769) (xy 341.938671 -357.66394) (xy 341.993413 -357.66394)
			(xy 342.047591 -357.671769) (xy 342.100093 -357.687265) (xy 342.149839 -357.710111) (xy 342.195807 -357.739835)
			(xy 342.21674 -357.757476) (xy 342.223852 -357.763572) (xy 342.24087 -357.769922) (xy 342.326214 -357.769922)
			(xy 342.343232 -357.763572) (xy 342.350344 -357.757476) (xy 342.371283 -357.739846) (xy 342.417254 -357.710134)
			(xy 342.467 -357.687296) (xy 342.519499 -357.671803) (xy 342.573673 -357.663972) (xy 342.601042 -357.663496)
			(xy 342.628292 -357.663977) (xy 342.682235 -357.671738) (xy 342.734526 -357.687097) (xy 342.784098 -357.709741)
			(xy 342.829944 -357.739209) (xy 342.871129 -357.7749) (xy 342.906817 -357.81609) (xy 342.936279 -357.861939)
			(xy 342.958918 -357.911514) (xy 342.974271 -357.963806) (xy 342.982026 -358.01775) (xy 342.982026 -358.07225)
			(xy 342.974271 -358.126194) (xy 342.958918 -358.178486) (xy 342.936279 -358.228061) (xy 342.906817 -358.27391)
			(xy 342.871129 -358.3151) (xy 342.829944 -358.350791) (xy 342.784098 -358.380259) (xy 342.734526 -358.402903)
			(xy 342.682235 -358.418262) (xy 342.628292 -358.426023) (xy 342.601042 -358.426512) (xy 342.573673 -358.426018)
			(xy 342.519495 -358.418207) (xy 342.466992 -358.402724) (xy 342.417245 -358.379888) (xy 342.371277 -358.35017)
			(xy 342.350344 -358.332532) (xy 342.343232 -358.326436) (xy 342.326214 -358.320086) (xy 342.24087 -358.320086)
			(xy 342.223852 -358.326436) (xy 342.21674 -358.332532) (xy 342.195807 -358.350173) (xy 342.149839 -358.379897)
			(xy 342.100093 -358.402743) (xy 342.047591 -358.418239) (xy 341.993413 -358.426068) (xy 341.938671 -358.426068)
			(xy 341.884493 -358.418239) (xy 341.831991 -358.402743) (xy 341.782245 -358.379897) (xy 341.736277 -358.350173)
			(xy 341.715344 -358.332532) (xy 341.708232 -358.326436) (xy 341.691214 -358.320086) (xy 341.60587 -358.320086)
			(xy 341.588852 -358.326436) (xy 341.58174 -358.332532) (xy 341.560807 -358.350173) (xy 341.514839 -358.379897)
			(xy 341.465093 -358.402743) (xy 341.412591 -358.418239) (xy 341.358413 -358.426068) (xy 341.303671 -358.426068)
			(xy 341.249493 -358.418239) (xy 341.196991 -358.402743) (xy 341.147245 -358.379897) (xy 341.101277 -358.350173)
			(xy 341.080344 -358.332532) (xy 341.073232 -358.326436) (xy 341.056214 -358.320086) (xy 340.97087 -358.320086)
			(xy 340.953852 -358.326436) (xy 340.94674 -358.332532) (xy 340.925808 -358.350171) (xy 340.879835 -358.379882)
			(xy 340.830087 -358.402717) (xy 340.777587 -358.418208) (xy 340.723411 -358.426037) (xy 340.696042 -358.426512)
			(xy 340.668787 -358.426044) (xy 340.614833 -358.418292) (xy 340.56253 -358.402939) (xy 340.512945 -358.380299)
			(xy 340.467087 -358.350833) (xy 340.42589 -358.31514) (xy 340.390192 -358.273946) (xy 340.360721 -358.228092)
			(xy 340.338075 -358.178509) (xy 340.322717 -358.126209) (xy 340.314959 -358.072254) (xy 340.030165 -358.072254)
			(xy 340.014814 -358.09047) (xy 340.008718 -358.097582) (xy 340.002368 -358.1146) (xy 340.002368 -358.199944)
			(xy 340.008718 -358.216962) (xy 340.014814 -358.224074) (xy 340.032457 -358.245003) (xy 340.062167 -358.290977)
			(xy 340.085002 -358.340725) (xy 340.100493 -358.393227) (xy 340.10832 -358.447403) (xy 340.108794 -358.474772)
			(xy 340.1083 -358.502884) (xy 340.100057 -358.558499) (xy 340.083744 -358.612304) (xy 340.059716 -358.663133)
			(xy 340.02849 -358.709888) (xy 340.009988 -358.731058) (xy 340.003384 -358.73817) (xy 339.99678 -358.754934)
			(xy 339.99551 -358.840786) (xy 340.001606 -358.857804) (xy 340.007702 -358.86517) (xy 340.024793 -358.885948)
			(xy 340.053555 -358.931414) (xy 340.075641 -358.980471) (xy 340.090613 -359.032146) (xy 340.098173 -359.085412)
			(xy 340.098634 -359.112312) (xy 340.098109 -359.141265) (xy 340.089351 -359.198505) (xy 340.072036 -359.253762)
			(xy 340.046565 -359.305765) (xy 340.013522 -359.353319) (xy 339.993986 -359.374694) (xy 339.987128 -359.38206)
			(xy 339.980016 -359.400348) (xy 339.981286 -359.491534) (xy 339.988906 -359.509568) (xy 339.996018 -359.51668)
			(xy 340.004582 -359.525305) (xy 340.020722 -359.543481) (xy 340.028276 -359.553002) (xy 340.035852 -359.561749)
			(xy 340.0566 -359.57194) (xy 340.068154 -359.57256) (xy 340.148418 -359.57256) (xy 340.159989 -359.572014)
			(xy 340.180761 -359.561803) (xy 340.188296 -359.553002) (xy 340.206705 -359.530327) (xy 340.249229 -359.490296)
			(xy 340.29736 -359.457215) (xy 340.323424 -359.444036) (xy 340.332822 -359.439464) (xy 340.346284 -359.423716)
			(xy 340.37524 -359.3338) (xy 340.373462 -359.313226) (xy 340.368382 -359.304082) (xy 340.353844 -359.27595)
			(xy 340.333234 -359.216076) (xy 340.322781 -359.153624) (xy 340.322154 -359.121964) (xy 340.322644 -359.094714)
			(xy 340.330405 -359.040768) (xy 340.345762 -358.988476) (xy 340.368405 -358.938901) (xy 340.397871 -358.893052)
			(xy 340.433562 -358.851864) (xy 340.474751 -358.816173) (xy 340.520599 -358.786706) (xy 340.570174 -358.764063)
			(xy 340.622466 -358.748705) (xy 340.676412 -358.740944) (xy 340.703662 -358.740456) (xy 340.731032 -358.740931)
			(xy 340.785211 -358.748744) (xy 340.837715 -358.764231) (xy 340.887462 -358.787071) (xy 340.933429 -358.816795)
			(xy 340.95436 -358.834436) (xy 340.961472 -358.840532) (xy 340.97849 -358.846882) (xy 341.063834 -358.846882)
			(xy 341.080852 -358.840532) (xy 341.087964 -358.834436) (xy 341.108897 -358.816795) (xy 341.154865 -358.787071)
			(xy 341.204611 -358.764225) (xy 341.257113 -358.748729) (xy 341.311291 -358.7409) (xy 341.366033 -358.7409)
			(xy 341.420211 -358.748729) (xy 341.472713 -358.764225) (xy 341.522459 -358.787071) (xy 341.568427 -358.816795)
			(xy 341.58936 -358.834436) (xy 341.596472 -358.840532) (xy 341.61349 -358.846882) (xy 341.698834 -358.846882)
			(xy 341.715852 -358.840532) (xy 341.722964 -358.834436) (xy 341.743897 -358.816795) (xy 341.789865 -358.787071)
			(xy 341.839611 -358.764225) (xy 341.892113 -358.748729) (xy 341.946291 -358.7409) (xy 342.001033 -358.7409)
			(xy 342.055211 -358.748729) (xy 342.107713 -358.764225) (xy 342.157459 -358.787071) (xy 342.203427 -358.816795)
			(xy 342.22436 -358.834436) (xy 342.231472 -358.840532) (xy 342.24849 -358.846882) (xy 342.333834 -358.846882)
			(xy 342.350852 -358.840532) (xy 342.357964 -358.834436) (xy 342.378903 -358.816806) (xy 342.424874 -358.787091)
			(xy 342.474619 -358.764253) (xy 342.527118 -358.74876) (xy 342.581293 -358.740931) (xy 342.608662 -358.740456)
			(xy 342.635912 -358.740991) (xy 342.689859 -358.748741) (xy 342.742153 -358.764091) (xy 342.791731 -358.786726)
			(xy 342.837582 -358.816187) (xy 342.878774 -358.851873) (xy 342.914469 -358.893058) (xy 342.943938 -358.938904)
			(xy 342.966583 -358.988477) (xy 342.981943 -359.040769) (xy 342.989704 -359.094714) (xy 342.99017 -359.121964)
			(xy 342.989735 -359.147938) (xy 342.982694 -359.199406) (xy 342.968738 -359.249444) (xy 342.948123 -359.297126)
			(xy 342.935052 -359.319576) (xy 342.929718 -359.328212) (xy 342.92667 -359.348278) (xy 342.949276 -359.43794)
			(xy 342.961214 -359.454196) (xy 342.970104 -359.45953) (xy 342.990317 -359.47195) (xy 343.027799 -359.501031)
			(xy 343.061396 -359.534525) (xy 343.076276 -359.553002) (xy 343.083852 -359.561749) (xy 343.1046 -359.57194)
			(xy 343.116154 -359.57256) (xy 343.196418 -359.57256) (xy 343.207989 -359.572014) (xy 343.228761 -359.561803)
			(xy 343.236296 -359.553002) (xy 343.243109 -359.544383) (xy 343.257596 -359.527862) (xy 343.265252 -359.519982)
			(xy 343.272364 -359.512616) (xy 343.279984 -359.494328) (xy 343.279984 -359.402888) (xy 343.272364 -359.3846)
			(xy 343.265252 -359.377234) (xy 343.244854 -359.3557) (xy 343.210314 -359.307482) (xy 343.183653 -359.254498)
			(xy 343.165516 -359.198027) (xy 343.156339 -359.139428) (xy 343.155778 -359.109772) (xy 343.156209 -359.0824)
			(xy 343.164032 -359.028219) (xy 343.179528 -358.975715) (xy 343.202379 -358.925968) (xy 343.232112 -358.880004)
			(xy 343.249758 -358.859074) (xy 343.255854 -358.851962) (xy 343.262204 -358.834944) (xy 343.262204 -358.7496)
			(xy 343.255854 -358.732582) (xy 343.249758 -358.72547) (xy 343.232089 -358.70456) (xy 343.202363 -358.658589)
			(xy 343.179517 -358.608839) (xy 343.164022 -358.556333) (xy 343.156195 -358.502151) (xy 343.156198 -358.447407)
			(xy 343.164031 -358.393225) (xy 343.179532 -358.340721) (xy 343.202383 -358.290974) (xy 343.232114 -358.245006)
			(xy 343.249758 -358.224074) (xy 343.255854 -358.216962) (xy 343.262204 -358.199944) (xy 343.262204 -358.1146)
			(xy 343.255854 -358.097582) (xy 343.249758 -358.09047) (xy 343.232131 -358.069528) (xy 343.202419 -358.023557)
			(xy 343.179581 -357.973812) (xy 343.164087 -357.921314) (xy 343.156254 -357.86714) (xy 343.155778 -357.839772)
			(xy 343.156252 -357.812521) (xy 343.164012 -357.758573) (xy 343.17937 -357.706279) (xy 343.202013 -357.656703)
			(xy 343.231481 -357.610853) (xy 343.267174 -357.569664) (xy 343.308364 -357.533973) (xy 343.354215 -357.504506)
			(xy 343.403792 -357.481865) (xy 343.456087 -357.466509) (xy 343.510035 -357.458751) (xy 343.537286 -357.458264)
			(xy 343.566204 -357.458768) (xy 343.623377 -357.467497) (xy 343.678577 -357.484756) (xy 343.730539 -357.51015)
			(xy 343.778072 -357.543097) (xy 343.820087 -357.582842) (xy 343.838276 -357.60533) (xy 343.845847 -357.614082)
			(xy 343.866599 -357.62427) (xy 343.878154 -357.624888) (xy 343.958418 -357.624888) (xy 343.969988 -357.624332)
			(xy 343.990759 -357.614128) (xy 343.998296 -357.60533) (xy 344.015049 -357.584547) (xy 344.053403 -357.547417)
			(xy 344.096557 -357.515995) (xy 344.143671 -357.490896) (xy 344.193823 -357.47261) (xy 344.246034 -357.461493)
			(xy 344.299286 -357.457763) (xy 344.352538 -357.461493) (xy 344.404749 -357.47261) (xy 344.454901 -357.490896)
			(xy 344.502015 -357.515995) (xy 344.545169 -357.547417) (xy 344.583523 -357.584547) (xy 344.600276 -357.60533)
			(xy 344.607847 -357.614082) (xy 344.628599 -357.62427) (xy 344.640154 -357.624888) (xy 344.720418 -357.624888)
			(xy 344.731988 -357.624332) (xy 344.752759 -357.614128) (xy 344.760296 -357.60533) (xy 344.778497 -357.582855)
			(xy 344.820514 -357.543118) (xy 344.868046 -357.510177) (xy 344.920006 -357.484787) (xy 344.975202 -357.467529)
			(xy 345.03237 -357.458799) (xy 345.061286 -357.458264) (xy 345.088536 -357.458791) (xy 345.14248 -357.466545)
			(xy 345.194773 -357.481897) (xy 345.244348 -357.504534) (xy 345.290197 -357.533997) (xy 345.331386 -357.569684)
			(xy 345.367078 -357.610869) (xy 345.396545 -357.656715) (xy 345.419188 -357.706288) (xy 345.434546 -357.758579)
			(xy 345.442306 -357.812522) (xy 345.442794 -357.839772) (xy 345.442313 -357.867142) (xy 345.434499 -357.92132)
			(xy 345.419013 -357.973823) (xy 345.396175 -358.02357) (xy 345.366454 -358.069538) (xy 345.348814 -358.09047)
			(xy 345.342718 -358.097582) (xy 345.336368 -358.1146) (xy 345.336368 -358.199944) (xy 345.342718 -358.216962)
			(xy 345.348814 -358.224074) (xy 345.366426 -358.24503) (xy 345.396148 -358.290995) (xy 345.418993 -358.340737)
			(xy 345.43449 -358.393235) (xy 345.44232 -358.44741) (xy 345.442323 -358.502148) (xy 345.434499 -358.556323)
			(xy 345.419008 -358.608823) (xy 345.396169 -358.658568) (xy 345.366451 -358.704536) (xy 345.348814 -358.72547)
			(xy 345.342718 -358.732582) (xy 345.336368 -358.7496) (xy 345.336368 -358.834944) (xy 345.342718 -358.851962)
			(xy 345.348814 -358.859074) (xy 345.366457 -358.880003) (xy 345.396167 -358.925977) (xy 345.419002 -358.975725)
			(xy 345.434493 -359.028227) (xy 345.44232 -359.082403) (xy 345.442794 -359.109772) (xy 345.442239 -359.139428)
			(xy 345.433051 -359.198023) (xy 345.414908 -359.254492) (xy 345.388247 -359.307474) (xy 345.35371 -359.355693)
			(xy 345.33332 -359.377234) (xy 345.326208 -359.3846) (xy 345.318588 -359.402888) (xy 345.318588 -359.494328)
			(xy 345.326208 -359.512616) (xy 345.33332 -359.519982) (xy 345.353721 -359.541514) (xy 345.388262 -359.589732)
			(xy 345.414922 -359.642716) (xy 345.433059 -359.699188) (xy 345.442234 -359.757787) (xy 345.442794 -359.787444)
			(xy 345.442363 -359.814697) (xy 345.4346 -359.868647) (xy 345.419239 -359.920944) (xy 345.396592 -359.970522)
			(xy 345.367119 -360.016373) (xy 345.331422 -360.057563) (xy 345.290227 -360.093254) (xy 345.244371 -360.122719)
			(xy 345.19479 -360.145359) (xy 345.142491 -360.160713) (xy 345.088539 -360.168467) (xy 345.061286 -360.168952)
			(xy 345.03237 -360.16839) (xy 344.975201 -360.159673) (xy 344.920002 -360.142424) (xy 344.86804 -360.117041)
			(xy 344.820505 -360.084104) (xy 344.778487 -360.044369) (xy 344.760296 -360.021886) (xy 344.752734 -360.013125)
			(xy 344.731975 -360.002942) (xy 344.720418 -360.002328) (xy 344.640154 -360.002328) (xy 344.628589 -360.00292)
			(xy 344.607817 -360.013098) (xy 344.600276 -360.021886) (xy 344.588084 -360.036618) (xy 344.581988 -360.04373)
			(xy 344.575638 -360.061256) (xy 344.576908 -360.147616) (xy 344.583766 -360.164888) (xy 344.59037 -360.171746)
			(xy 344.609168 -360.19302) (xy 344.640975 -360.240039) (xy 344.665456 -360.291255) (xy 344.682071 -360.345536)
			(xy 344.690451 -360.40168) (xy 344.690954 -360.430064) (xy 344.690388 -360.457312) (xy 344.682638 -360.511255)
			(xy 344.66729 -360.563545) (xy 344.644656 -360.613119) (xy 344.615198 -360.658967) (xy 344.579515 -360.700157)
			(xy 344.538333 -360.735849) (xy 344.492491 -360.765317) (xy 344.442922 -360.787961) (xy 344.390635 -360.803321)
			(xy 344.336694 -360.811083) (xy 344.309446 -360.811572) (xy 344.28053 -360.811031) (xy 344.223359 -360.802308)
			(xy 344.16816 -360.785056) (xy 344.116198 -360.759668) (xy 344.068664 -360.726728) (xy 344.026646 -360.68699)
			(xy 344.008456 -360.664506) (xy 344.000908 -360.65573) (xy 343.980139 -360.645554) (xy 343.968578 -360.644948)
			(xy 343.888314 -360.644948) (xy 343.876745 -360.64551) (xy 343.855973 -360.655709) (xy 343.848436 -360.664506)
			(xy 343.836244 -360.679492) (xy 343.830148 -360.68635) (xy 343.823798 -360.703876) (xy 343.824814 -360.789728)
			(xy 343.831418 -360.807) (xy 343.837768 -360.814112) (xy 343.856251 -360.835263) (xy 343.887441 -360.881978)
			(xy 343.911455 -360.932756) (xy 343.927775 -360.986503) (xy 343.936051 -361.04206) (xy 343.936574 -361.070144)
			(xy 343.936163 -361.097398) (xy 343.9284 -361.15135) (xy 343.913037 -361.203648) (xy 343.890388 -361.253228)
			(xy 343.860914 -361.29908) (xy 343.825215 -361.34027) (xy 343.784017 -361.375961) (xy 343.738159 -361.405426)
			(xy 343.688575 -361.428064) (xy 343.636274 -361.443416) (xy 343.58232 -361.451169) (xy 343.555066 -361.451652)
			(xy 343.52615 -361.451104) (xy 343.468979 -361.442384) (xy 343.41378 -361.425133) (xy 343.361818 -361.399747)
			(xy 343.314284 -361.366807) (xy 343.272267 -361.32707) (xy 343.254076 -361.304586) (xy 343.246522 -361.295816)
			(xy 343.225757 -361.285637) (xy 343.214198 -361.285028) (xy 343.133934 -361.285028) (xy 343.122367 -361.285608)
			(xy 343.101596 -361.295795) (xy 343.094056 -361.304586) (xy 343.077303 -361.325369) (xy 343.038949 -361.362499)
			(xy 342.995795 -361.393921) (xy 342.948681 -361.41902) (xy 342.898529 -361.437306) (xy 342.846318 -361.448423)
			(xy 342.793066 -361.452153) (xy 342.739814 -361.448423) (xy 342.687603 -361.437306) (xy 342.637451 -361.41902)
			(xy 342.590337 -361.393921) (xy 342.547183 -361.362499) (xy 342.508829 -361.325369) (xy 342.492076 -361.304586)
			(xy 342.484522 -361.295816) (xy 342.463757 -361.285637) (xy 342.452198 -361.285028) (xy 342.371934 -361.285028)
			(xy 342.360367 -361.285608) (xy 342.339596 -361.295795) (xy 342.332056 -361.304586) (xy 342.315303 -361.325369)
			(xy 342.276949 -361.362499) (xy 342.233795 -361.393921) (xy 342.186681 -361.41902) (xy 342.136529 -361.437306)
			(xy 342.084318 -361.448423) (xy 342.031066 -361.452153) (xy 341.977814 -361.448423) (xy 341.925603 -361.437306)
			(xy 341.875451 -361.41902) (xy 341.828337 -361.393921) (xy 341.785183 -361.362499) (xy 341.746829 -361.325369)
			(xy 341.730076 -361.304586) (xy 341.722522 -361.295816) (xy 341.701757 -361.285637) (xy 341.690198 -361.285028)
			(xy 341.609934 -361.285028) (xy 341.598367 -361.285608) (xy 341.577596 -361.295795) (xy 341.570056 -361.304586)
			(xy 341.553303 -361.325369) (xy 341.514949 -361.362499) (xy 341.471795 -361.393921) (xy 341.424681 -361.41902)
			(xy 341.374529 -361.437306) (xy 341.322318 -361.448423) (xy 341.269066 -361.452153) (xy 341.215814 -361.448423)
			(xy 341.163603 -361.437306) (xy 341.113451 -361.41902) (xy 341.066337 -361.393921) (xy 341.023183 -361.362499)
			(xy 340.984829 -361.325369) (xy 340.968076 -361.304586) (xy 340.960522 -361.295816) (xy 340.939757 -361.285637)
			(xy 340.928198 -361.285028) (xy 340.847934 -361.285028) (xy 340.836367 -361.285608) (xy 340.815596 -361.295795)
			(xy 340.808056 -361.304586) (xy 340.791303 -361.325369) (xy 340.752949 -361.362499) (xy 340.709795 -361.393921)
			(xy 340.662681 -361.41902) (xy 340.612529 -361.437306) (xy 340.560318 -361.448423) (xy 340.507066 -361.452153)
			(xy 340.453814 -361.448423) (xy 340.401603 -361.437306) (xy 340.351451 -361.41902) (xy 340.304337 -361.393921)
			(xy 340.261183 -361.362499) (xy 340.222829 -361.325369) (xy 340.206076 -361.304586) (xy 340.198522 -361.295816)
			(xy 340.177757 -361.285637) (xy 340.166198 -361.285028) (xy 340.085934 -361.285028) (xy 340.074367 -361.285608)
			(xy 340.053596 -361.295795) (xy 340.046056 -361.304586) (xy 340.029303 -361.325369) (xy 339.990949 -361.362499)
			(xy 339.947795 -361.393921) (xy 339.900681 -361.41902) (xy 339.850529 -361.437306) (xy 339.798318 -361.448423)
			(xy 339.745066 -361.452153) (xy 339.691814 -361.448423) (xy 339.639603 -361.437306) (xy 339.589451 -361.41902)
			(xy 339.542337 -361.393921) (xy 339.499183 -361.362499) (xy 339.460829 -361.325369) (xy 339.444076 -361.304586)
			(xy 339.436522 -361.295816) (xy 339.415757 -361.285637) (xy 339.404198 -361.285028) (xy 339.323934 -361.285028)
			(xy 339.312367 -361.285608) (xy 339.291596 -361.295795) (xy 339.284056 -361.304586) (xy 339.267303 -361.325369)
			(xy 339.228949 -361.362499) (xy 339.185795 -361.393921) (xy 339.138681 -361.41902) (xy 339.088529 -361.437306)
			(xy 339.036318 -361.448423) (xy 338.983066 -361.452153) (xy 338.929814 -361.448423) (xy 338.877603 -361.437306)
			(xy 338.827451 -361.41902) (xy 338.780337 -361.393921) (xy 338.737183 -361.362499) (xy 338.698829 -361.325369)
			(xy 338.682076 -361.304586) (xy 338.674522 -361.295816) (xy 338.653757 -361.285637) (xy 338.642198 -361.285028)
			(xy 338.561934 -361.285028) (xy 338.550367 -361.285608) (xy 338.529596 -361.295795) (xy 338.522056 -361.304586)
			(xy 338.503886 -361.327088) (xy 338.461863 -361.366822) (xy 338.414323 -361.39976) (xy 338.362358 -361.425145)
			(xy 338.307156 -361.442397) (xy 338.249983 -361.45112) (xy 338.221066 -361.451652) (xy 338.192139 -361.451095)
			(xy 338.134949 -361.442348) (xy 338.079737 -361.425061) (xy 338.027772 -361.399629) (xy 337.980246 -361.366638)
			(xy 337.93825 -361.326844) (xy 337.920076 -361.304332) (xy 337.91271 -361.295188) (xy 337.89239 -361.285028)
			(xy 337.78952 -361.283504) (xy 337.768692 -361.293156) (xy 337.761326 -361.3023) (xy 337.743109 -361.323664)
			(xy 337.701484 -361.361338) (xy 337.654786 -361.392503) (xy 337.604023 -361.416485) (xy 337.550294 -361.432766)
			(xy 337.494757 -361.440995) (xy 337.466686 -361.441492) (xy 337.437771 -361.440915) (xy 337.380603 -361.432199)
			(xy 337.325405 -361.414953) (xy 337.273443 -361.389572) (xy 337.225907 -361.356639) (xy 337.183888 -361.316907)
			(xy 337.165696 -361.294426) (xy 337.158144 -361.285654) (xy 337.137377 -361.275479) (xy 337.125818 -361.274868)
			(xy 337.045554 -361.274868) (xy 337.033987 -361.275446) (xy 337.013214 -361.285633) (xy 337.005676 -361.294426)
			(xy 336.988923 -361.315209) (xy 336.950569 -361.352339) (xy 336.907415 -361.383761) (xy 336.860301 -361.40886)
			(xy 336.810149 -361.427146) (xy 336.757938 -361.438263) (xy 336.704686 -361.441993) (xy 336.651434 -361.438263)
			(xy 336.599223 -361.427146) (xy 336.549071 -361.40886) (xy 336.501957 -361.383761) (xy 336.458803 -361.352339)
			(xy 336.420449 -361.315209) (xy 336.403696 -361.294426) (xy 336.396144 -361.285654) (xy 336.375377 -361.275479)
			(xy 336.363818 -361.274868) (xy 336.283554 -361.274868) (xy 336.271987 -361.275446) (xy 336.251214 -361.285633)
			(xy 336.243676 -361.294426) (xy 336.225505 -361.316926) (xy 336.18348 -361.356659) (xy 336.135941 -361.389596)
			(xy 336.083976 -361.414981) (xy 336.028775 -361.432234) (xy 335.971603 -361.440959) (xy 335.942686 -361.441492)
			(xy 335.915432 -361.441058) (xy 335.861479 -361.433299) (xy 335.80918 -361.41794) (xy 335.759598 -361.395295)
			(xy 335.713745 -361.365824) (xy 335.672552 -361.330127) (xy 335.636858 -361.288931) (xy 335.607391 -361.243075)
			(xy 335.584749 -361.193492) (xy 335.569395 -361.141191) (xy 335.56164 -361.087238) (xy 335.561178 -361.059984)
			(xy 335.561627 -361.032788) (xy 335.569312 -360.978943) (xy 335.584579 -360.926739) (xy 335.607118 -360.877238)
			(xy 335.63647 -360.831447) (xy 335.653888 -360.810556) (xy 335.659984 -360.803698) (xy 335.666334 -360.786172)
			(xy 335.665318 -360.70032) (xy 335.658714 -360.683048) (xy 335.652364 -360.675936) (xy 335.633861 -360.654801)
			(xy 335.602673 -360.608082) (xy 335.578663 -360.5573) (xy 335.562347 -360.50355) (xy 335.554077 -360.44799)
			(xy 335.553558 -360.419904) (xy 335.554016 -360.392735) (xy 335.561743 -360.338949) (xy 335.577025 -360.286804)
			(xy 335.599554 -360.237356) (xy 335.628874 -360.191607) (xy 335.646268 -360.17073) (xy 335.652364 -360.163618)
			(xy 335.658714 -360.146092) (xy 335.657444 -360.059732) (xy 335.650586 -360.04246) (xy 335.643982 -360.035602)
			(xy 335.625151 -360.014356) (xy 335.593351 -359.967329) (xy 335.568877 -359.916105) (xy 335.552269 -359.861819)
			(xy 335.543897 -359.805669) (xy 335.543398 -359.777284) (xy 335.543939 -359.748332) (xy 335.552696 -359.691093)
			(xy 335.570008 -359.635837) (xy 335.595475 -359.583834) (xy 335.628512 -359.536279) (xy 335.648046 -359.514902)
			(xy 335.654904 -359.507536) (xy 335.662016 -359.489248) (xy 335.660746 -359.398062) (xy 335.653126 -359.380028)
			(xy 335.646014 -359.372916) (xy 335.625019 -359.351305) (xy 335.589452 -359.302673) (xy 335.561974 -359.249053)
			(xy 335.54327 -359.191779) (xy 335.533803 -359.132277) (xy 335.533238 -359.102152) (xy 318.661823 -359.102152)
			(xy 318.660666 -359.110199) (xy 318.645311 -359.162494) (xy 318.622669 -359.212071) (xy 318.593203 -359.257921)
			(xy 318.557512 -359.299112) (xy 318.516321 -359.334803) (xy 318.470471 -359.364269) (xy 318.420894 -359.386911)
			(xy 318.368599 -359.402266) (xy 318.314651 -359.410022) (xy 318.2874 -359.410508) (xy 318.16167 -359.410508)
			(xy 318.151626 -359.410885) (xy 318.13303 -359.418469) (xy 318.125602 -359.42524) (xy 317.82004 -359.730802)
			(xy 317.813355 -359.73829) (xy 317.80576 -359.756844) (xy 317.805308 -359.76687) (xy 317.805308 -359.918)
			(xy 319.046858 -359.918) (xy 319.050929 -359.862378) (xy 319.063055 -359.807941) (xy 319.082978 -359.75585)
			(xy 319.110274 -359.707215) (xy 319.14436 -359.663072) (xy 319.184509 -359.624363) (xy 319.229867 -359.591912)
			(xy 319.279467 -359.566411) (xy 319.332251 -359.548404) (xy 319.387094 -359.538274) (xy 319.442828 -359.536237)
			(xy 319.498265 -359.542337) (xy 319.552222 -359.556443) (xy 319.603551 -359.578255) (xy 319.651157 -359.607309)
			(xy 319.694025 -359.642984) (xy 319.731242 -359.684521) (xy 319.762015 -359.731034) (xy 319.785687 -359.781531)
			(xy 319.801755 -359.834938) (xy 319.809875 -359.890114) (xy 319.810384 -359.918) (xy 319.809875 -359.945886)
			(xy 319.801755 -360.001062) (xy 319.785687 -360.054469) (xy 319.762015 -360.104966) (xy 319.731242 -360.151479)
			(xy 319.694025 -360.193016) (xy 319.651157 -360.228691) (xy 319.603551 -360.257745) (xy 319.552222 -360.279557)
			(xy 319.498265 -360.293663) (xy 319.442828 -360.299763) (xy 319.387094 -360.297726) (xy 319.332251 -360.287596)
			(xy 319.279467 -360.269589) (xy 319.229867 -360.244088) (xy 319.184509 -360.211637) (xy 319.14436 -360.172928)
			(xy 319.110274 -360.128785) (xy 319.082978 -360.08015) (xy 319.063055 -360.028059) (xy 319.050929 -359.973622)
			(xy 319.046858 -359.918) (xy 317.805308 -359.918) (xy 317.805308 -360.361992) (xy 322.46265 -360.361992)
			(xy 322.466721 -360.30637) (xy 322.478847 -360.251933) (xy 322.49877 -360.199842) (xy 322.526066 -360.151207)
			(xy 322.560152 -360.107064) (xy 322.600301 -360.068355) (xy 322.645659 -360.035904) (xy 322.695259 -360.010403)
			(xy 322.748043 -359.992396) (xy 322.802886 -359.982266) (xy 322.85862 -359.980229) (xy 322.914057 -359.986329)
			(xy 322.968014 -360.000435) (xy 323.019343 -360.022247) (xy 323.066949 -360.051301) (xy 323.109817 -360.086976)
			(xy 323.147034 -360.128513) (xy 323.177807 -360.175026) (xy 323.201479 -360.225523) (xy 323.217547 -360.27893)
			(xy 323.225667 -360.334106) (xy 323.226176 -360.361992) (xy 323.225667 -360.389878) (xy 323.217547 -360.445054)
			(xy 323.201479 -360.498461) (xy 323.177807 -360.548958) (xy 323.147034 -360.595471) (xy 323.109817 -360.637008)
			(xy 323.066949 -360.672683) (xy 323.019343 -360.701737) (xy 322.968014 -360.723549) (xy 322.914057 -360.737655)
			(xy 322.85862 -360.743755) (xy 322.802886 -360.741718) (xy 322.748043 -360.731588) (xy 322.695259 -360.713581)
			(xy 322.645659 -360.68808) (xy 322.600301 -360.655629) (xy 322.560152 -360.61692) (xy 322.526066 -360.572777)
			(xy 322.49877 -360.524142) (xy 322.478847 -360.472051) (xy 322.466721 -360.417614) (xy 322.46265 -360.361992)
			(xy 317.805308 -360.361992) (xy 317.805308 -361.598718) (xy 321.434966 -361.598718) (xy 321.439037 -361.543096)
			(xy 321.451163 -361.488659) (xy 321.471086 -361.436568) (xy 321.498382 -361.387933) (xy 321.532468 -361.34379)
			(xy 321.572617 -361.305081) (xy 321.617975 -361.27263) (xy 321.667575 -361.247129) (xy 321.720359 -361.229122)
			(xy 321.775202 -361.218992) (xy 321.830936 -361.216955) (xy 321.886373 -361.223055) (xy 321.94033 -361.237161)
			(xy 321.991659 -361.258973) (xy 322.039265 -361.288027) (xy 322.082133 -361.323702) (xy 322.11935 -361.365239)
			(xy 322.150123 -361.411752) (xy 322.173795 -361.462249) (xy 322.175345 -361.4674) (xy 326.668382 -361.4674)
			(xy 326.672453 -361.411778) (xy 326.684579 -361.357341) (xy 326.704502 -361.30525) (xy 326.731798 -361.256615)
			(xy 326.765884 -361.212472) (xy 326.806033 -361.173763) (xy 326.851391 -361.141312) (xy 326.900991 -361.115811)
			(xy 326.953775 -361.097804) (xy 327.008618 -361.087674) (xy 327.064352 -361.085637) (xy 327.119789 -361.091737)
			(xy 327.173746 -361.105843) (xy 327.225075 -361.127655) (xy 327.240715 -361.1372) (xy 328.725782 -361.1372)
			(xy 328.729853 -361.081578) (xy 328.741979 -361.027141) (xy 328.761902 -360.97505) (xy 328.789198 -360.926415)
			(xy 328.823284 -360.882272) (xy 328.863433 -360.843563) (xy 328.908791 -360.811112) (xy 328.958391 -360.785611)
			(xy 329.011175 -360.767604) (xy 329.066018 -360.757474) (xy 329.121752 -360.755437) (xy 329.177189 -360.761537)
			(xy 329.231146 -360.775643) (xy 329.282475 -360.797455) (xy 329.330081 -360.826509) (xy 329.372949 -360.862184)
			(xy 329.410166 -360.903721) (xy 329.440939 -360.950234) (xy 329.464611 -361.000731) (xy 329.480679 -361.054138)
			(xy 329.488799 -361.109314) (xy 329.489308 -361.1372) (xy 330.021182 -361.1372) (xy 330.025253 -361.081578)
			(xy 330.037379 -361.027141) (xy 330.057302 -360.97505) (xy 330.084598 -360.926415) (xy 330.118684 -360.882272)
			(xy 330.158833 -360.843563) (xy 330.204191 -360.811112) (xy 330.253791 -360.785611) (xy 330.306575 -360.767604)
			(xy 330.361418 -360.757474) (xy 330.417152 -360.755437) (xy 330.472589 -360.761537) (xy 330.526546 -360.775643)
			(xy 330.577875 -360.797455) (xy 330.625481 -360.826509) (xy 330.668349 -360.862184) (xy 330.705566 -360.903721)
			(xy 330.736339 -360.950234) (xy 330.760011 -361.000731) (xy 330.776079 -361.054138) (xy 330.784199 -361.109314)
			(xy 330.784708 -361.1372) (xy 330.784199 -361.165086) (xy 330.776079 -361.220262) (xy 330.760011 -361.273669)
			(xy 330.736339 -361.324166) (xy 330.705566 -361.370679) (xy 330.668349 -361.412216) (xy 330.625481 -361.447891)
			(xy 330.577875 -361.476945) (xy 330.526546 -361.498757) (xy 330.472589 -361.512863) (xy 330.417152 -361.518963)
			(xy 330.361418 -361.516926) (xy 330.306575 -361.506796) (xy 330.253791 -361.488789) (xy 330.204191 -361.463288)
			(xy 330.158833 -361.430837) (xy 330.118684 -361.392128) (xy 330.084598 -361.347985) (xy 330.057302 -361.29935)
			(xy 330.037379 -361.247259) (xy 330.025253 -361.192822) (xy 330.021182 -361.1372) (xy 329.489308 -361.1372)
			(xy 329.488799 -361.165086) (xy 329.480679 -361.220262) (xy 329.464611 -361.273669) (xy 329.440939 -361.324166)
			(xy 329.410166 -361.370679) (xy 329.372949 -361.412216) (xy 329.330081 -361.447891) (xy 329.282475 -361.476945)
			(xy 329.231146 -361.498757) (xy 329.177189 -361.512863) (xy 329.121752 -361.518963) (xy 329.066018 -361.516926)
			(xy 329.011175 -361.506796) (xy 328.958391 -361.488789) (xy 328.908791 -361.463288) (xy 328.863433 -361.430837)
			(xy 328.823284 -361.392128) (xy 328.789198 -361.347985) (xy 328.761902 -361.29935) (xy 328.741979 -361.247259)
			(xy 328.729853 -361.192822) (xy 328.725782 -361.1372) (xy 327.240715 -361.1372) (xy 327.272681 -361.156709)
			(xy 327.315549 -361.192384) (xy 327.352766 -361.233921) (xy 327.383539 -361.280434) (xy 327.407211 -361.330931)
			(xy 327.423279 -361.384338) (xy 327.431399 -361.439514) (xy 327.431908 -361.4674) (xy 327.431399 -361.495286)
			(xy 327.423279 -361.550462) (xy 327.407211 -361.603869) (xy 327.383539 -361.654366) (xy 327.352766 -361.700879)
			(xy 327.315549 -361.742416) (xy 327.272681 -361.778091) (xy 327.225075 -361.807145) (xy 327.173746 -361.828957)
			(xy 327.119789 -361.843063) (xy 327.064352 -361.849163) (xy 327.008618 -361.847126) (xy 326.953775 -361.836996)
			(xy 326.900991 -361.818989) (xy 326.851391 -361.793488) (xy 326.806033 -361.761037) (xy 326.765884 -361.722328)
			(xy 326.731798 -361.678185) (xy 326.704502 -361.62955) (xy 326.684579 -361.577459) (xy 326.672453 -361.523022)
			(xy 326.668382 -361.4674) (xy 322.175345 -361.4674) (xy 322.189863 -361.515656) (xy 322.197983 -361.570832)
			(xy 322.198492 -361.598718) (xy 322.197983 -361.626604) (xy 322.189863 -361.68178) (xy 322.173795 -361.735187)
			(xy 322.150123 -361.785684) (xy 322.11935 -361.832197) (xy 322.082133 -361.873734) (xy 322.039265 -361.909409)
			(xy 321.991659 -361.938463) (xy 321.94033 -361.960275) (xy 321.886373 -361.974381) (xy 321.830936 -361.980481)
			(xy 321.775202 -361.978444) (xy 321.720359 -361.968314) (xy 321.667575 -361.950307) (xy 321.617975 -361.924806)
			(xy 321.572617 -361.892355) (xy 321.532468 -361.853646) (xy 321.498382 -361.809503) (xy 321.471086 -361.760868)
			(xy 321.451163 -361.708777) (xy 321.439037 -361.65434) (xy 321.434966 -361.598718) (xy 317.805308 -361.598718)
			(xy 317.805308 -362.788962) (xy 320.244722 -362.788962) (xy 320.248793 -362.73334) (xy 320.260919 -362.678903)
			(xy 320.280842 -362.626812) (xy 320.308138 -362.578177) (xy 320.342224 -362.534034) (xy 320.382373 -362.495325)
			(xy 320.427731 -362.462874) (xy 320.477331 -362.437373) (xy 320.530115 -362.419366) (xy 320.584958 -362.409236)
			(xy 320.640692 -362.407199) (xy 320.696129 -362.413299) (xy 320.750086 -362.427405) (xy 320.801415 -362.449217)
			(xy 320.849021 -362.478271) (xy 320.891889 -362.513946) (xy 320.929106 -362.555483) (xy 320.959879 -362.601996)
			(xy 320.963819 -362.6104) (xy 326.668382 -362.6104) (xy 326.672453 -362.554778) (xy 326.684579 -362.500341)
			(xy 326.704502 -362.44825) (xy 326.731798 -362.399615) (xy 326.765884 -362.355472) (xy 326.806033 -362.316763)
			(xy 326.851391 -362.284312) (xy 326.900991 -362.258811) (xy 326.953775 -362.240804) (xy 327.008618 -362.230674)
			(xy 327.064352 -362.228637) (xy 327.119789 -362.234737) (xy 327.173746 -362.248843) (xy 327.225075 -362.270655)
			(xy 327.272681 -362.299709) (xy 327.315549 -362.335384) (xy 327.352766 -362.376921) (xy 327.383539 -362.423434)
			(xy 327.407211 -362.473931) (xy 327.423279 -362.527338) (xy 327.431399 -362.582514) (xy 327.431908 -362.6104)
			(xy 327.431444 -362.6358) (xy 328.801982 -362.6358) (xy 328.806053 -362.580178) (xy 328.818179 -362.525741)
			(xy 328.838102 -362.47365) (xy 328.865398 -362.425015) (xy 328.899484 -362.380872) (xy 328.939633 -362.342163)
			(xy 328.984991 -362.309712) (xy 329.034591 -362.284211) (xy 329.087375 -362.266204) (xy 329.142218 -362.256074)
			(xy 329.197952 -362.254037) (xy 329.253389 -362.260137) (xy 329.307346 -362.274243) (xy 329.358675 -362.296055)
			(xy 329.406281 -362.325109) (xy 329.449149 -362.360784) (xy 329.486366 -362.402321) (xy 329.517139 -362.448834)
			(xy 329.540811 -362.499331) (xy 329.556879 -362.552738) (xy 329.564999 -362.607914) (xy 329.565508 -362.6358)
			(xy 330.300582 -362.6358) (xy 330.304653 -362.580178) (xy 330.316779 -362.525741) (xy 330.336702 -362.47365)
			(xy 330.363998 -362.425015) (xy 330.398084 -362.380872) (xy 330.438233 -362.342163) (xy 330.483591 -362.309712)
			(xy 330.533191 -362.284211) (xy 330.585975 -362.266204) (xy 330.640818 -362.256074) (xy 330.696552 -362.254037)
			(xy 330.751989 -362.260137) (xy 330.805946 -362.274243) (xy 330.857275 -362.296055) (xy 330.904881 -362.325109)
			(xy 330.947749 -362.360784) (xy 330.984966 -362.402321) (xy 331.015739 -362.448834) (xy 331.039411 -362.499331)
			(xy 331.055479 -362.552738) (xy 331.063599 -362.607914) (xy 331.064108 -362.6358) (xy 331.063599 -362.663686)
			(xy 331.055479 -362.718862) (xy 331.039411 -362.772269) (xy 331.015739 -362.822766) (xy 330.984966 -362.869279)
			(xy 330.947749 -362.910816) (xy 330.904881 -362.946491) (xy 330.857275 -362.975545) (xy 330.805946 -362.997357)
			(xy 330.751989 -363.011463) (xy 330.696552 -363.017563) (xy 330.640818 -363.015526) (xy 330.585975 -363.005396)
			(xy 330.533191 -362.987389) (xy 330.483591 -362.961888) (xy 330.438233 -362.929437) (xy 330.398084 -362.890728)
			(xy 330.363998 -362.846585) (xy 330.336702 -362.79795) (xy 330.316779 -362.745859) (xy 330.304653 -362.691422)
			(xy 330.300582 -362.6358) (xy 329.565508 -362.6358) (xy 329.564999 -362.663686) (xy 329.556879 -362.718862)
			(xy 329.540811 -362.772269) (xy 329.517139 -362.822766) (xy 329.486366 -362.869279) (xy 329.449149 -362.910816)
			(xy 329.406281 -362.946491) (xy 329.358675 -362.975545) (xy 329.307346 -362.997357) (xy 329.253389 -363.011463)
			(xy 329.197952 -363.017563) (xy 329.142218 -363.015526) (xy 329.087375 -363.005396) (xy 329.034591 -362.987389)
			(xy 328.984991 -362.961888) (xy 328.939633 -362.929437) (xy 328.899484 -362.890728) (xy 328.865398 -362.846585)
			(xy 328.838102 -362.79795) (xy 328.818179 -362.745859) (xy 328.806053 -362.691422) (xy 328.801982 -362.6358)
			(xy 327.431444 -362.6358) (xy 327.431399 -362.638286) (xy 327.423279 -362.693462) (xy 327.407211 -362.746869)
			(xy 327.383539 -362.797366) (xy 327.352766 -362.843879) (xy 327.315549 -362.885416) (xy 327.272681 -362.921091)
			(xy 327.225075 -362.950145) (xy 327.173746 -362.971957) (xy 327.119789 -362.986063) (xy 327.064352 -362.992163)
			(xy 327.008618 -362.990126) (xy 326.953775 -362.979996) (xy 326.900991 -362.961989) (xy 326.851391 -362.936488)
			(xy 326.806033 -362.904037) (xy 326.765884 -362.865328) (xy 326.731798 -362.821185) (xy 326.704502 -362.77255)
			(xy 326.684579 -362.720459) (xy 326.672453 -362.666022) (xy 326.668382 -362.6104) (xy 320.963819 -362.6104)
			(xy 320.983551 -362.652493) (xy 320.999619 -362.7059) (xy 321.007739 -362.761076) (xy 321.008248 -362.788962)
			(xy 321.007739 -362.816848) (xy 320.999619 -362.872024) (xy 320.983551 -362.925431) (xy 320.959879 -362.975928)
			(xy 320.929106 -363.022441) (xy 320.891889 -363.063978) (xy 320.849021 -363.099653) (xy 320.801415 -363.128707)
			(xy 320.750086 -363.150519) (xy 320.696129 -363.164625) (xy 320.640692 -363.170725) (xy 320.584958 -363.168688)
			(xy 320.530115 -363.158558) (xy 320.477331 -363.140551) (xy 320.427731 -363.11505) (xy 320.382373 -363.082599)
			(xy 320.342224 -363.04389) (xy 320.308138 -362.999747) (xy 320.280842 -362.951112) (xy 320.260919 -362.899021)
			(xy 320.248793 -362.844584) (xy 320.244722 -362.788962) (xy 317.805308 -362.788962) (xy 317.805308 -363.23905)
			(xy 318.698878 -363.23905) (xy 318.702949 -363.183428) (xy 318.715075 -363.128991) (xy 318.734998 -363.0769)
			(xy 318.762294 -363.028265) (xy 318.79638 -362.984122) (xy 318.836529 -362.945413) (xy 318.881887 -362.912962)
			(xy 318.931487 -362.887461) (xy 318.984271 -362.869454) (xy 319.039114 -362.859324) (xy 319.094848 -362.857287)
			(xy 319.150285 -362.863387) (xy 319.204242 -362.877493) (xy 319.255571 -362.899305) (xy 319.303177 -362.928359)
			(xy 319.346045 -362.964034) (xy 319.383262 -363.005571) (xy 319.414035 -363.052084) (xy 319.437707 -363.102581)
			(xy 319.453775 -363.155988) (xy 319.461895 -363.211164) (xy 319.462404 -363.23905) (xy 319.461895 -363.266936)
			(xy 319.453775 -363.322112) (xy 319.437707 -363.375519) (xy 319.414035 -363.426016) (xy 319.383262 -363.472529)
			(xy 319.346045 -363.514066) (xy 319.303177 -363.549741) (xy 319.255571 -363.578795) (xy 319.204242 -363.600607)
			(xy 319.150285 -363.614713) (xy 319.094848 -363.620813) (xy 319.039114 -363.618776) (xy 318.984271 -363.608646)
			(xy 318.931487 -363.590639) (xy 318.881887 -363.565138) (xy 318.836529 -363.532687) (xy 318.79638 -363.493978)
			(xy 318.762294 -363.449835) (xy 318.734998 -363.4012) (xy 318.715075 -363.349109) (xy 318.702949 -363.294672)
			(xy 318.698878 -363.23905) (xy 317.805308 -363.23905) (xy 317.805308 -363.755251) (xy 323.849978 -363.755251)
			(xy 323.849978 -363.700749) (xy 323.857734 -363.646801) (xy 323.873089 -363.594506) (xy 323.895731 -363.544929)
			(xy 323.925197 -363.499079) (xy 323.960888 -363.457888) (xy 324.002079 -363.422197) (xy 324.047929 -363.392731)
			(xy 324.097506 -363.370089) (xy 324.149801 -363.354734) (xy 324.203749 -363.346978) (xy 324.231 -363.346492)
			(xy 324.260231 -363.347055) (xy 324.318006 -363.355987) (xy 324.373743 -363.373627) (xy 324.426137 -363.399561)
			(xy 324.473962 -363.433183) (xy 324.5161 -363.473706) (xy 324.534276 -363.496606) (xy 324.542714 -363.507003)
			(xy 324.563918 -363.52334) (xy 324.588637 -363.533613) (xy 324.615175 -363.537118) (xy 324.641713 -363.533613)
			(xy 324.666432 -363.52334) (xy 324.687636 -363.507003) (xy 324.696074 -363.496606) (xy 324.714223 -363.473681)
			(xy 324.756356 -363.433141) (xy 324.804183 -363.399509) (xy 324.856584 -363.373571) (xy 324.912331 -363.355937)
			(xy 324.970115 -363.347019) (xy 324.99935 -363.346492) (xy 325.026605 -363.346952) (xy 325.080562 -363.354703)
			(xy 325.132865 -363.370055) (xy 325.182452 -363.392694) (xy 325.228311 -363.422161) (xy 325.26951 -363.457855)
			(xy 325.305209 -363.499049) (xy 325.334682 -363.544904) (xy 325.357328 -363.594488) (xy 325.372686 -363.64679)
			(xy 325.373406 -363.6518) (xy 326.693782 -363.6518) (xy 326.697853 -363.596178) (xy 326.709979 -363.541741)
			(xy 326.729902 -363.48965) (xy 326.757198 -363.441015) (xy 326.791284 -363.396872) (xy 326.831433 -363.358163)
			(xy 326.876791 -363.325712) (xy 326.926391 -363.300211) (xy 326.979175 -363.282204) (xy 327.034018 -363.272074)
			(xy 327.089752 -363.270037) (xy 327.145189 -363.276137) (xy 327.199146 -363.290243) (xy 327.250475 -363.312055)
			(xy 327.298081 -363.341109) (xy 327.340949 -363.376784) (xy 327.378166 -363.418321) (xy 327.408939 -363.464834)
			(xy 327.432611 -363.515331) (xy 327.448679 -363.568738) (xy 327.456799 -363.623914) (xy 327.457308 -363.6518)
			(xy 327.709782 -363.6518) (xy 327.713853 -363.596178) (xy 327.725979 -363.541741) (xy 327.745902 -363.48965)
			(xy 327.773198 -363.441015) (xy 327.807284 -363.396872) (xy 327.847433 -363.358163) (xy 327.892791 -363.325712)
			(xy 327.942391 -363.300211) (xy 327.995175 -363.282204) (xy 328.050018 -363.272074) (xy 328.105752 -363.270037)
			(xy 328.161189 -363.276137) (xy 328.215146 -363.290243) (xy 328.266475 -363.312055) (xy 328.314081 -363.341109)
			(xy 328.356949 -363.376784) (xy 328.394166 -363.418321) (xy 328.424939 -363.464834) (xy 328.448611 -363.515331)
			(xy 328.464679 -363.568738) (xy 328.472799 -363.623914) (xy 328.473308 -363.6518) (xy 328.472799 -363.679686)
			(xy 328.464679 -363.734862) (xy 328.448611 -363.788269) (xy 328.424939 -363.838766) (xy 328.394166 -363.885279)
			(xy 328.356949 -363.926816) (xy 328.314081 -363.962491) (xy 328.266475 -363.991545) (xy 328.215146 -364.013357)
			(xy 328.161189 -364.027463) (xy 328.105752 -364.033563) (xy 328.050018 -364.031526) (xy 327.995175 -364.021396)
			(xy 327.942391 -364.003389) (xy 327.892791 -363.977888) (xy 327.847433 -363.945437) (xy 327.807284 -363.906728)
			(xy 327.773198 -363.862585) (xy 327.745902 -363.81395) (xy 327.725979 -363.761859) (xy 327.713853 -363.707422)
			(xy 327.709782 -363.6518) (xy 327.457308 -363.6518) (xy 327.456799 -363.679686) (xy 327.448679 -363.734862)
			(xy 327.432611 -363.788269) (xy 327.408939 -363.838766) (xy 327.378166 -363.885279) (xy 327.340949 -363.926816)
			(xy 327.298081 -363.962491) (xy 327.250475 -363.991545) (xy 327.199146 -364.013357) (xy 327.145189 -364.027463)
			(xy 327.089752 -364.033563) (xy 327.034018 -364.031526) (xy 326.979175 -364.021396) (xy 326.926391 -364.003389)
			(xy 326.876791 -363.977888) (xy 326.831433 -363.945437) (xy 326.791284 -363.906728) (xy 326.757198 -363.862585)
			(xy 326.729902 -363.81395) (xy 326.709979 -363.761859) (xy 326.697853 -363.707422) (xy 326.693782 -363.6518)
			(xy 325.373406 -363.6518) (xy 325.380445 -363.700745) (xy 325.380445 -363.755255) (xy 325.372686 -363.80921)
			(xy 325.357328 -363.861512) (xy 325.334682 -363.911096) (xy 325.305209 -363.956951) (xy 325.26951 -363.998145)
			(xy 325.228311 -364.033839) (xy 325.182452 -364.063306) (xy 325.132865 -364.085945) (xy 325.080562 -364.101297)
			(xy 325.026605 -364.109048) (xy 324.99935 -364.109508) (xy 324.970118 -364.108981) (xy 324.912341 -364.100041)
			(xy 324.856604 -364.082395) (xy 324.80421 -364.056454) (xy 324.756385 -364.022825) (xy 324.714249 -363.982296)
			(xy 324.696074 -363.959394) (xy 324.687663 -363.948953) (xy 324.666477 -363.932535) (xy 324.641745 -363.922206)
			(xy 324.615175 -363.918682) (xy 324.588605 -363.922206) (xy 324.563873 -363.932535) (xy 324.542687 -363.948953)
			(xy 324.534276 -363.959394) (xy 324.516077 -363.982276) (xy 324.473954 -364.022814) (xy 324.426136 -364.056447)
			(xy 324.373744 -364.082387) (xy 324.318007 -364.100025) (xy 324.260231 -364.108949) (xy 324.231 -364.109508)
			(xy 324.203749 -364.109022) (xy 324.149801 -364.101266) (xy 324.097506 -364.085911) (xy 324.047929 -364.063269)
			(xy 324.002079 -364.033803) (xy 323.960888 -363.998112) (xy 323.925197 -363.956921) (xy 323.895731 -363.911071)
			(xy 323.873089 -363.861494) (xy 323.857734 -363.809199) (xy 323.849978 -363.755251) (xy 317.805308 -363.755251)
			(xy 317.805308 -364.363) (xy 318.794382 -364.363) (xy 318.798453 -364.307378) (xy 318.810579 -364.252941)
			(xy 318.830502 -364.20085) (xy 318.857798 -364.152215) (xy 318.891884 -364.108072) (xy 318.932033 -364.069363)
			(xy 318.977391 -364.036912) (xy 319.026991 -364.011411) (xy 319.079775 -363.993404) (xy 319.134618 -363.983274)
			(xy 319.190352 -363.981237) (xy 319.245789 -363.987337) (xy 319.299746 -364.001443) (xy 319.351075 -364.023255)
			(xy 319.398681 -364.052309) (xy 319.441549 -364.087984) (xy 319.478766 -364.129521) (xy 319.509539 -364.176034)
			(xy 319.533211 -364.226531) (xy 319.549279 -364.279938) (xy 319.557399 -364.335114) (xy 319.557908 -364.363)
			(xy 319.557399 -364.390886) (xy 319.549279 -364.446062) (xy 319.533211 -364.499469) (xy 319.509539 -364.549966)
			(xy 319.478766 -364.596479) (xy 319.441549 -364.638016) (xy 319.398681 -364.673691) (xy 319.351075 -364.702745)
			(xy 319.299746 -364.724557) (xy 319.245789 -364.738663) (xy 319.190352 -364.744763) (xy 319.134618 -364.742726)
			(xy 319.079775 -364.732596) (xy 319.026991 -364.714589) (xy 318.977391 -364.689088) (xy 318.932033 -364.656637)
			(xy 318.891884 -364.617928) (xy 318.857798 -364.573785) (xy 318.830502 -364.52515) (xy 318.810579 -364.473059)
			(xy 318.798453 -364.418622) (xy 318.794382 -364.363) (xy 317.805308 -364.363) (xy 317.805308 -366.4204)
			(xy 317.804727 -366.450378) (xy 317.795336 -366.509594) (xy 317.776799 -366.566613) (xy 317.749574 -366.620031)
			(xy 317.71433 -366.668535) (xy 317.693548 -366.690148) (xy 313.731148 -370.652548) (xy 313.709539 -370.673338)
			(xy 313.661041 -370.708595) (xy 313.607623 -370.735828) (xy 313.550601 -370.754365) (xy 313.49138 -370.76375)
			(xy 313.4614 -370.764308) (xy 306.2732 -370.764308) (xy 306.243222 -370.763727) (xy 306.184006 -370.754336)
			(xy 306.126987 -370.735799) (xy 306.073569 -370.708574) (xy 306.025065 -370.67333) (xy 306.003452 -370.652548)
			(xy 304.225452 -368.874548) (xy 304.204662 -368.852939) (xy 304.169405 -368.804441) (xy 304.142172 -368.751023)
			(xy 304.123635 -368.694001) (xy 304.11425 -368.63478) (xy 304.113692 -368.6048) (xy 301.453296 -368.6048)
			(xy 300.14926 -369.908836) (xy 300.142563 -369.916314) (xy 300.134974 -369.934876) (xy 300.134528 -369.944904)
			(xy 300.134528 -369.987576) (xy 300.13656 -369.994688) (xy 300.143941 -370.021257) (xy 300.151843 -370.075829)
			(xy 300.152308 -370.1034) (xy 300.151822 -370.130651) (xy 300.144066 -370.184599) (xy 300.128711 -370.236894)
			(xy 300.106069 -370.286471) (xy 300.076603 -370.332321) (xy 300.040912 -370.373512) (xy 299.999721 -370.409203)
			(xy 299.953871 -370.438669) (xy 299.904294 -370.461311) (xy 299.851999 -370.476666) (xy 299.798051 -370.484422)
			(xy 299.7708 -370.484908) (xy 299.741626 -370.484344) (xy 299.683959 -370.47546) (xy 299.628318 -370.457897)
			(xy 299.575999 -370.432067) (xy 299.528224 -370.398572) (xy 299.486106 -370.358192) (xy 299.450628 -370.31187)
			(xy 299.422618 -370.260685) (xy 299.412152 -370.233448) (xy 299.40758 -370.221256) (xy 299.388276 -370.204238)
			(xy 299.291756 -370.182648) (xy 299.283349 -370.18109) (xy 299.266375 -370.183048) (xy 299.251012 -370.190525)
			(xy 299.244766 -370.196364) (xy 299.17517 -370.26596) (xy 299.172632 -370.268651) (xy 299.168296 -370.274645)
			(xy 299.166534 -370.277898) (xy 299.152116 -370.3034) (xy 299.116626 -370.350008) (xy 299.074433 -370.390649)
			(xy 299.026528 -370.424369) (xy 298.974035 -370.450377) (xy 298.918186 -370.468062) (xy 298.860291 -370.477009)
			(xy 298.831 -370.477542) (xy 298.80375 -370.477022) (xy 298.749806 -370.469267) (xy 298.697514 -370.453913)
			(xy 298.647939 -370.431275) (xy 298.60209 -370.401811) (xy 298.5609 -370.366124) (xy 298.525209 -370.324937)
			(xy 298.495742 -370.279091) (xy 298.473099 -370.229518) (xy 298.457741 -370.177228) (xy 298.44998 -370.123284)
			(xy 298.449492 -370.096034) (xy 297.756834 -370.096034) (xy 297.57878 -370.274088) (xy 297.57497 -370.278152)
			(xy 297.566133 -370.289913) (xy 297.554981 -370.317122) (xy 297.552032 -370.346379) (xy 297.55753 -370.375266)
			(xy 297.57102 -370.401394) (xy 297.591388 -370.422603) (xy 297.603926 -370.430298) (xy 297.625637 -370.443158)
			(xy 297.665777 -370.473736) (xy 297.683936 -370.491258) (xy 297.693796 -370.500464) (xy 297.717234 -370.5138)
			(xy 297.743345 -370.520539) (xy 297.770309 -370.520212) (xy 297.796249 -370.512842) (xy 297.819358 -370.498943)
			(xy 297.82897 -370.48948) (xy 297.847034 -370.471238) (xy 297.887207 -370.439272) (xy 297.931301 -370.412977)
			(xy 297.978521 -370.392827) (xy 298.028015 -370.379187) (xy 298.07889 -370.372303) (xy 298.10456 -370.371878)
			(xy 298.13183 -370.372339) (xy 298.185816 -370.380095) (xy 298.238148 -370.395457) (xy 298.287761 -370.418109)
			(xy 298.333644 -370.447593) (xy 298.374865 -370.483307) (xy 298.410583 -370.524523) (xy 298.440071 -370.570404)
			(xy 298.462729 -370.620015) (xy 298.478096 -370.672345) (xy 298.485858 -370.72633) (xy 298.485858 -370.78087)
			(xy 298.478096 -370.834855) (xy 298.462729 -370.887185) (xy 298.440071 -370.936796) (xy 298.410583 -370.982677)
			(xy 298.374865 -371.023893) (xy 298.333644 -371.059607) (xy 298.287761 -371.089091) (xy 298.238148 -371.111743)
			(xy 298.185816 -371.127105) (xy 298.13183 -371.134861) (xy 298.10456 -371.135402) (xy 298.074652 -371.134823)
			(xy 298.01557 -371.125493) (xy 297.958669 -371.107051) (xy 297.905345 -371.079951) (xy 297.856908 -371.044856)
			(xy 297.83532 -371.02415) (xy 297.825461 -371.014949) (xy 297.802026 -371.001624) (xy 297.775921 -370.994894)
			(xy 297.748964 -370.995229) (xy 297.723034 -371.002605) (xy 297.699937 -371.016508) (xy 297.690286 -371.025928)
			(xy 297.672222 -371.044173) (xy 297.632051 -371.076144) (xy 297.587958 -371.102445) (xy 297.540738 -371.122601)
			(xy 297.491243 -371.136247) (xy 297.440367 -371.14314) (xy 297.414696 -371.14353) (xy 297.385993 -371.143012)
			(xy 297.329234 -371.134416) (xy 297.274403 -371.117417) (xy 297.222735 -371.0924) (xy 297.175395 -371.059928)
			(xy 297.133452 -371.020733) (xy 297.097851 -370.9757) (xy 297.083226 -370.950998) (xy 297.075531 -370.938458)
			(xy 297.054319 -370.918089) (xy 297.028189 -370.904595) (xy 296.999299 -370.899092) (xy 296.970038 -370.902035)
			(xy 296.942823 -370.91318) (xy 296.93108 -370.922042) (xy 296.927016 -370.925852) (xy 296.160444 -371.692424)
			(xy 296.154681 -371.699585) (xy 296.148192 -371.716769) (xy 296.147744 -371.725952) (xy 296.147744 -372.910862)
			(xy 296.14818 -372.920926) (xy 296.155915 -372.93951) (xy 296.16273 -372.94693) (xy 296.683938 -373.468138)
			(xy 296.688764 -373.47271) (xy 296.68978 -373.473472) (xy 296.698948 -373.481488) (xy 296.71636 -373.49852)
			(xy 296.724578 -373.507508) (xy 296.73169 -373.515382) (xy 296.760392 -373.52859) (xy 296.765401 -373.530716)
			(xy 296.776034 -373.533017) (xy 296.781474 -373.533162) (xy 329.820524 -373.533162)
		)
		(stroke
			(width 0)
			(type solid)
		)
		(fill yes)
		(layer "In11.Cu")
		(net "GND")
	)
	(gr_poly
		(pts
			(xy 104.968548 -190.26886) (xy 104.975547 -190.268442) (xy 104.988944 -190.264327) (xy 104.994964 -190.260732)
			(xy 105.003854 -190.253366) (xy 105.0544 -190.201296) (xy 105.05784 -190.19754) (xy 105.063343 -190.188971)
			(xy 105.065322 -190.184278) (xy 105.068878 -190.17488) (xy 105.068624 -190.16472) (xy 105.068624 -190.155322)
			(xy 105.069086 -190.128069) (xy 105.07684 -190.074117) (xy 105.092195 -190.021819) (xy 105.114837 -189.972238)
			(xy 105.144305 -189.926384) (xy 105.179999 -189.885192) (xy 105.221192 -189.849499) (xy 105.267047 -189.820032)
			(xy 105.316628 -189.797391) (xy 105.368927 -189.782038) (xy 105.422879 -189.774285) (xy 105.450132 -189.773814)
			(xy 105.476175 -189.774279) (xy 105.527771 -189.781407) (xy 105.577919 -189.795485) (xy 105.625687 -189.816253)
			(xy 105.670186 -189.843322) (xy 105.69067 -189.859412) (xy 105.691686 -189.85992) (xy 105.69448 -189.862206)
			(xy 105.710482 -189.867794) (xy 105.751884 -189.867794) (xy 105.751884 -189.88024) (xy 105.801414 -189.88024)
			(xy 105.80624 -189.879986) (xy 105.81365 -189.879013) (xy 105.827462 -189.873325) (xy 105.833418 -189.86881)
			(xy 105.834434 -189.867794) (xy 105.854853 -189.850575) (xy 105.899609 -189.821425) (xy 105.947996 -189.798809)
			(xy 105.999067 -189.78317) (xy 106.051821 -189.774814) (xy 106.105226 -189.773906) (xy 106.158234 -189.780462)
			(xy 106.209807 -189.794354) (xy 106.258936 -189.815311) (xy 106.304658 -189.842922) (xy 106.32567 -189.859412)
			(xy 106.326686 -189.85992) (xy 106.32948 -189.862206) (xy 106.345482 -189.867794) (xy 106.386884 -189.867794)
			(xy 106.386884 -189.88024) (xy 106.436414 -189.88024) (xy 106.44124 -189.879986) (xy 106.44865 -189.879013)
			(xy 106.462462 -189.873325) (xy 106.468418 -189.86881) (xy 106.469434 -189.867794) (xy 106.490366 -189.850154)
			(xy 106.536334 -189.820433) (xy 106.586081 -189.797594) (xy 106.638584 -189.782109) (xy 106.692762 -189.774295)
			(xy 106.720132 -189.773814) (xy 106.747381 -189.774302) (xy 106.801324 -189.782063) (xy 106.853614 -189.797421)
			(xy 106.903185 -189.820064) (xy 106.94903 -189.849532) (xy 106.990215 -189.885223) (xy 107.025901 -189.926413)
			(xy 107.055362 -189.972262) (xy 107.077998 -190.021837) (xy 107.093349 -190.074129) (xy 107.101101 -190.128073)
			(xy 107.10164 -190.155322) (xy 107.10164 -190.16472) (xy 107.101386 -190.17488) (xy 107.104942 -190.184278)
			(xy 107.106875 -190.188996) (xy 107.112376 -190.197578) (xy 107.115864 -190.201296) (xy 107.16641 -190.253366)
			(xy 107.1753 -190.260732) (xy 107.181302 -190.264368) (xy 107.194708 -190.268495) (xy 107.201716 -190.26886)
			(xy 108.980478 -190.26886) (xy 108.981748 -190.26886) (xy 108.988747 -190.268442) (xy 109.002144 -190.264327)
			(xy 109.008164 -190.260732) (xy 109.017054 -190.253366) (xy 109.0676 -190.201296) (xy 109.07104 -190.19754)
			(xy 109.076543 -190.188971) (xy 109.078522 -190.184278) (xy 109.082078 -190.17488) (xy 109.081824 -190.16472)
			(xy 109.081824 -190.155322) (xy 109.082286 -190.128069) (xy 109.09004 -190.074117) (xy 109.105395 -190.021819)
			(xy 109.128037 -189.972238) (xy 109.157505 -189.926384) (xy 109.193199 -189.885192) (xy 109.234392 -189.849499)
			(xy 109.280247 -189.820032) (xy 109.329828 -189.797391) (xy 109.382127 -189.782038) (xy 109.436079 -189.774285)
			(xy 109.463332 -189.773814) (xy 109.489375 -189.774279) (xy 109.540971 -189.781407) (xy 109.591119 -189.795485)
			(xy 109.638887 -189.816253) (xy 109.683386 -189.843322) (xy 109.70387 -189.859412) (xy 109.704886 -189.85992)
			(xy 109.70768 -189.862206) (xy 109.723682 -189.867794) (xy 109.765084 -189.867794) (xy 109.765084 -189.88024)
			(xy 109.814614 -189.88024) (xy 109.81944 -189.879986) (xy 109.82685 -189.879013) (xy 109.840662 -189.873325)
			(xy 109.846618 -189.86881) (xy 109.847634 -189.867794) (xy 109.868566 -189.850154) (xy 109.914534 -189.820433)
			(xy 109.964281 -189.797594) (xy 110.016784 -189.782109) (xy 110.070962 -189.774295) (xy 110.098332 -189.773814)
			(xy 110.125581 -189.774302) (xy 110.179524 -189.782063) (xy 110.231814 -189.797421) (xy 110.281385 -189.820064)
			(xy 110.32723 -189.849532) (xy 110.368415 -189.885223) (xy 110.404101 -189.926413) (xy 110.433562 -189.972262)
			(xy 110.456198 -190.021837) (xy 110.471549 -190.074129) (xy 110.479301 -190.128073) (xy 110.47984 -190.155322)
			(xy 110.47984 -190.16472) (xy 110.479586 -190.17488) (xy 110.483142 -190.184278) (xy 110.485075 -190.188996)
			(xy 110.490576 -190.197578) (xy 110.494064 -190.201296) (xy 110.54461 -190.253366) (xy 110.5535 -190.260732)
			(xy 110.559502 -190.264368) (xy 110.572908 -190.268495) (xy 110.579916 -190.26886) (xy 112.973358 -190.26886)
			(xy 112.978184 -190.268606) (xy 112.98519 -190.267703) (xy 112.998333 -190.262538) (xy 113.004092 -190.258446)
			(xy 114.638074 -188.916056) (xy 114.644374 -188.910001) (xy 114.652791 -188.894703) (xy 114.655561 -188.877463)
			(xy 114.65433 -188.868812) (xy 114.638582 -188.78169) (xy 114.636593 -188.772836) (xy 114.627353 -188.757233)
			(xy 114.613281 -188.745795) (xy 114.6048 -188.742574) (xy 114.573184 -188.731026) (xy 114.514294 -188.698443)
			(xy 114.487706 -188.677804) (xy 114.487198 -188.677296) (xy 114.483896 -188.674756) (xy 114.467894 -188.669168)
			(xy 114.426492 -188.669168) (xy 114.426492 -188.656722) (xy 114.376962 -188.656722) (xy 114.372136 -188.656976)
			(xy 114.364721 -188.657937) (xy 114.350893 -188.663606) (xy 114.344958 -188.668152) (xy 114.343942 -188.669168)
			(xy 114.323522 -188.686382) (xy 114.278765 -188.715525) (xy 114.230378 -188.738134) (xy 114.179309 -188.753767)
			(xy 114.126558 -188.762119) (xy 114.073158 -188.763025) (xy 114.020153 -188.756467) (xy 113.968583 -188.742575)
			(xy 113.919458 -188.72162) (xy 113.873738 -188.694013) (xy 113.852706 -188.67755) (xy 113.85169 -188.677042)
			(xy 113.848896 -188.674756) (xy 113.832894 -188.669168) (xy 113.791492 -188.669168) (xy 113.791492 -188.656722)
			(xy 113.741962 -188.656722) (xy 113.737136 -188.656976) (xy 113.729721 -188.657937) (xy 113.715893 -188.663606)
			(xy 113.709958 -188.668152) (xy 113.708942 -188.669168) (xy 113.68801 -188.686808) (xy 113.642043 -188.71653)
			(xy 113.592296 -188.739367) (xy 113.539792 -188.754851) (xy 113.485614 -188.762662) (xy 113.458244 -188.763148)
			(xy 113.430988 -188.762688) (xy 113.37703 -188.754937) (xy 113.324725 -188.739585) (xy 113.275136 -188.716945)
			(xy 113.229275 -188.687479) (xy 113.188074 -188.651786) (xy 113.152371 -188.610593) (xy 113.122895 -188.564737)
			(xy 113.100245 -188.515154) (xy 113.084881 -188.462852) (xy 113.077118 -188.408896) (xy 113.076736 -188.38164)
			(xy 113.077203 -188.355598) (xy 113.084335 -188.304003) (xy 113.098417 -188.253858) (xy 113.119187 -188.206094)
			(xy 113.146261 -188.161598) (xy 113.162334 -188.141102) (xy 113.162842 -188.140086) (xy 113.165128 -188.137292)
			(xy 113.170716 -188.12129) (xy 113.170716 -188.079888) (xy 113.183162 -188.079888) (xy 113.183162 -188.030358)
			(xy 113.182908 -188.025532) (xy 113.181945 -188.018117) (xy 113.176274 -188.004292) (xy 113.171732 -187.998354)
			(xy 113.170716 -187.997338) (xy 113.153496 -187.976918) (xy 113.124341 -187.932159) (xy 113.10172 -187.883769)
			(xy 113.086075 -187.832694) (xy 113.077713 -187.779937) (xy 113.076796 -187.726528) (xy 113.083344 -187.673514)
			(xy 113.097228 -187.621933) (xy 113.118176 -187.572796) (xy 113.145778 -187.527063) (xy 113.162334 -187.506102)
			(xy 113.162842 -187.505086) (xy 113.165128 -187.502292) (xy 113.170716 -187.48629) (xy 113.170716 -187.444888)
			(xy 113.183162 -187.444888) (xy 113.183162 -187.395358) (xy 113.182908 -187.390532) (xy 113.181945 -187.383117)
			(xy 113.176274 -187.369292) (xy 113.171732 -187.363354) (xy 113.170716 -187.362338) (xy 113.153496 -187.341918)
			(xy 113.124341 -187.297159) (xy 113.10172 -187.248769) (xy 113.086075 -187.197694) (xy 113.077713 -187.144937)
			(xy 113.076796 -187.091528) (xy 113.083344 -187.038514) (xy 113.097228 -186.986933) (xy 113.118176 -186.937796)
			(xy 113.145778 -186.892063) (xy 113.162334 -186.871102) (xy 113.162842 -186.870086) (xy 113.165128 -186.867292)
			(xy 113.170716 -186.85129) (xy 113.170716 -186.809888) (xy 113.183162 -186.809888) (xy 113.183162 -186.760358)
			(xy 113.182908 -186.755532) (xy 113.181945 -186.748117) (xy 113.176274 -186.734292) (xy 113.171732 -186.728354)
			(xy 113.170716 -186.727338) (xy 113.153496 -186.706918) (xy 113.124341 -186.662159) (xy 113.10172 -186.613769)
			(xy 113.086075 -186.562694) (xy 113.077713 -186.509937) (xy 113.076796 -186.456528) (xy 113.083344 -186.403514)
			(xy 113.097228 -186.351933) (xy 113.118176 -186.302796) (xy 113.145778 -186.257063) (xy 113.162334 -186.236102)
			(xy 113.162842 -186.235086) (xy 113.165128 -186.232292) (xy 113.170716 -186.21629) (xy 113.170716 -186.174888)
			(xy 113.183162 -186.174888) (xy 113.183162 -186.125358) (xy 113.182908 -186.120532) (xy 113.181945 -186.113117)
			(xy 113.176274 -186.099292) (xy 113.171732 -186.093354) (xy 113.170716 -186.092338) (xy 113.153496 -186.071918)
			(xy 113.124341 -186.027159) (xy 113.10172 -185.978769) (xy 113.086075 -185.927694) (xy 113.077713 -185.874937)
			(xy 113.076796 -185.821528) (xy 113.083344 -185.768514) (xy 113.097228 -185.716933) (xy 113.118176 -185.667796)
			(xy 113.145778 -185.622063) (xy 113.162334 -185.601102) (xy 113.162842 -185.600086) (xy 113.165128 -185.597292)
			(xy 113.170716 -185.58129) (xy 113.170716 -185.539888) (xy 113.183162 -185.539888) (xy 113.183162 -185.490358)
			(xy 113.182908 -185.485532) (xy 113.181945 -185.478117) (xy 113.176274 -185.464292) (xy 113.171732 -185.458354)
			(xy 113.170716 -185.457338) (xy 113.153496 -185.436918) (xy 113.124341 -185.392159) (xy 113.10172 -185.343769)
			(xy 113.086075 -185.292694) (xy 113.077713 -185.239937) (xy 113.076796 -185.186528) (xy 113.083344 -185.133514)
			(xy 113.097228 -185.081933) (xy 113.118176 -185.032796) (xy 113.145778 -184.987063) (xy 113.162334 -184.966102)
			(xy 113.162842 -184.965086) (xy 113.165128 -184.962292) (xy 113.170716 -184.94629) (xy 113.170716 -184.904888)
			(xy 113.183162 -184.904888) (xy 113.183162 -184.855358) (xy 113.182908 -184.850532) (xy 113.181945 -184.843117)
			(xy 113.176274 -184.829292) (xy 113.171732 -184.823354) (xy 113.170716 -184.822338) (xy 113.153077 -184.801406)
			(xy 113.123357 -184.755438) (xy 113.100521 -184.705691) (xy 113.085039 -184.653188) (xy 113.077228 -184.599009)
			(xy 113.076736 -184.57164) (xy 113.077285 -184.542486) (xy 113.086148 -184.484855) (xy 113.103674 -184.429243)
			(xy 113.129455 -184.376943) (xy 113.16289 -184.329174) (xy 113.182654 -184.307734) (xy 113.19002 -184.300114)
			(xy 113.193322 -184.291478) (xy 113.194952 -184.287015) (xy 113.196749 -184.277685) (xy 113.196878 -184.272936)
			(xy 113.196878 -184.201816) (xy 113.196495 -184.193191) (xy 113.190646 -184.17696) (xy 113.185448 -184.170066)
			(xy 113.182654 -184.167018) (xy 113.162898 -184.145572) (xy 113.129465 -184.097802) (xy 113.103685 -184.045504)
			(xy 113.086157 -183.989894) (xy 113.077289 -183.932265) (xy 113.076736 -183.903112) (xy 113.077199 -183.87586)
			(xy 113.084954 -183.82191) (xy 113.10031 -183.769613) (xy 113.122952 -183.720034) (xy 113.152421 -183.674183)
			(xy 113.188115 -183.632992) (xy 113.229308 -183.597301) (xy 113.275162 -183.567837) (xy 113.324743 -183.545199)
			(xy 113.377041 -183.529848) (xy 113.430992 -183.522096) (xy 113.458244 -183.521604) (xy 113.484287 -183.52207)
			(xy 113.535882 -183.529199) (xy 113.58603 -183.543279) (xy 113.633796 -183.564046) (xy 113.678295 -183.591117)
			(xy 113.698782 -183.607202) (xy 113.699798 -183.60771) (xy 113.702592 -183.609996) (xy 113.718594 -183.615584)
			(xy 113.759996 -183.615584) (xy 113.759996 -183.62803) (xy 113.809526 -183.62803) (xy 113.814352 -183.627776)
			(xy 113.821761 -183.626801) (xy 113.83557 -183.62111) (xy 113.84153 -183.6166) (xy 113.842546 -183.615584)
			(xy 113.862965 -183.598367) (xy 113.907721 -183.569219) (xy 113.956108 -183.546605) (xy 114.007178 -183.530968)
			(xy 114.059931 -183.522614) (xy 114.113334 -183.521706) (xy 114.166341 -183.528263) (xy 114.217913 -183.542157)
			(xy 114.26704 -183.563114) (xy 114.31276 -183.590724) (xy 114.333782 -183.607202) (xy 114.334798 -183.60771)
			(xy 114.337592 -183.609996) (xy 114.353594 -183.615584) (xy 114.394996 -183.615584) (xy 114.394996 -183.62803)
			(xy 114.444526 -183.62803) (xy 114.449352 -183.627776) (xy 114.456761 -183.626801) (xy 114.47057 -183.62111)
			(xy 114.47653 -183.6166) (xy 114.477546 -183.615584) (xy 114.498479 -183.597945) (xy 114.544446 -183.568226)
			(xy 114.594194 -183.54539) (xy 114.646697 -183.529907) (xy 114.700875 -183.522095) (xy 114.728244 -183.521604)
			(xy 114.755493 -183.522093) (xy 114.809435 -183.529855) (xy 114.861724 -183.545214) (xy 114.911295 -183.567858)
			(xy 114.957139 -183.597325) (xy 114.998323 -183.633017) (xy 115.034008 -183.674206) (xy 115.063469 -183.720055)
			(xy 115.086106 -183.769629) (xy 115.101457 -183.82192) (xy 115.109211 -183.875863) (xy 115.109752 -183.903112)
			(xy 117.089936 -183.903112) (xy 117.090367 -183.875857) (xy 117.098123 -183.821903) (xy 117.11348 -183.769602)
			(xy 117.136124 -183.720019) (xy 117.165595 -183.674164) (xy 117.201292 -183.63297) (xy 117.242489 -183.597276)
			(xy 117.288347 -183.567809) (xy 117.337932 -183.545169) (xy 117.390234 -183.529816) (xy 117.444189 -183.522064)
			(xy 117.471444 -183.521604) (xy 117.498813 -183.522102) (xy 117.552991 -183.529912) (xy 117.605494 -183.545393)
			(xy 117.655241 -183.568228) (xy 117.701209 -183.597946) (xy 117.722142 -183.615584) (xy 117.722396 -183.615838)
			(xy 117.729476 -183.621433) (xy 117.746398 -183.627674) (xy 117.755416 -183.62803) (xy 117.822472 -183.62803)
			(xy 117.831487 -183.627653) (xy 117.848403 -183.621419) (xy 117.855492 -183.615838) (xy 117.855492 -183.615584)
			(xy 117.855746 -183.615584) (xy 117.876679 -183.597943) (xy 117.922647 -183.568219) (xy 117.972393 -183.545373)
			(xy 118.024895 -183.529877) (xy 118.079073 -183.522048) (xy 118.133815 -183.522048) (xy 118.187993 -183.529877)
			(xy 118.240495 -183.545373) (xy 118.290241 -183.568219) (xy 118.336209 -183.597943) (xy 118.357142 -183.615584)
			(xy 118.357396 -183.615838) (xy 118.364476 -183.621433) (xy 118.381398 -183.627674) (xy 118.390416 -183.62803)
			(xy 118.457472 -183.62803) (xy 118.466487 -183.627653) (xy 118.483403 -183.621419) (xy 118.490492 -183.615838)
			(xy 118.490492 -183.615584) (xy 118.490746 -183.615584) (xy 118.511686 -183.597954) (xy 118.557657 -183.568242)
			(xy 118.607402 -183.545404) (xy 118.659901 -183.529911) (xy 118.714075 -183.52208) (xy 118.741444 -183.521604)
			(xy 118.768697 -183.522037) (xy 118.822647 -183.5298) (xy 118.874944 -183.545161) (xy 118.924522 -183.567808)
			(xy 118.970373 -183.59728) (xy 119.011563 -183.632977) (xy 119.047253 -183.674172) (xy 119.076719 -183.720027)
			(xy 119.099359 -183.769609) (xy 119.114712 -183.821908) (xy 119.122467 -183.875859) (xy 119.122952 -183.903112)
			(xy 119.122414 -183.93223) (xy 119.113567 -183.989791) (xy 119.09608 -184.045341) (xy 119.070359 -184.09759)
			(xy 119.037002 -184.145327) (xy 119.017288 -184.166764) (xy 119.01043 -184.173876) (xy 119.003064 -184.192164)
			(xy 119.003318 -184.27192) (xy 119.003763 -184.28171) (xy 119.011066 -184.299872) (xy 119.017542 -184.307226)
			(xy 119.037386 -184.328688) (xy 119.070982 -184.376519) (xy 119.096891 -184.428914) (xy 119.114505 -184.484647)
			(xy 119.123413 -184.542415) (xy 119.123968 -184.57164) (xy 119.123559 -184.598894) (xy 119.115796 -184.652847)
			(xy 119.100434 -184.705145) (xy 119.077785 -184.754725) (xy 119.048311 -184.800577) (xy 119.012612 -184.841768)
			(xy 118.971413 -184.877459) (xy 118.925555 -184.906924) (xy 118.87597 -184.929562) (xy 118.823668 -184.944913)
			(xy 118.769714 -184.952665) (xy 118.74246 -184.953148) (xy 118.716175 -184.952671) (xy 118.664099 -184.945476)
			(xy 118.613504 -184.931202) (xy 118.565348 -184.910117) (xy 118.520541 -184.882622) (xy 118.479933 -184.849236)
			(xy 118.46179 -184.830212) (xy 118.454727 -184.82329) (xy 118.436833 -184.814918) (xy 118.426992 -184.813956)
			(xy 118.373906 -184.811162) (xy 118.366286 -184.818274) (xy 118.366286 -184.871614) (xy 118.366778 -184.881428)
			(xy 118.374219 -184.899592) (xy 118.380764 -184.90692) (xy 118.400949 -184.928409) (xy 118.435092 -184.976472)
			(xy 118.461436 -185.029214) (xy 118.479354 -185.08538) (xy 118.48842 -185.143634) (xy 118.488968 -185.173112)
			(xy 118.488556 -185.200367) (xy 118.480797 -185.254322) (xy 118.465437 -185.306623) (xy 118.44279 -185.356206)
			(xy 118.413317 -185.402061) (xy 118.377618 -185.443255) (xy 118.336419 -185.478948) (xy 118.29056 -185.508415)
			(xy 118.240974 -185.531055) (xy 118.188671 -185.546408) (xy 118.134715 -185.55416) (xy 118.10746 -185.55462)
			(xy 118.077984 -185.554037) (xy 118.019733 -185.544978) (xy 117.963569 -185.527065) (xy 117.910829 -185.500725)
			(xy 117.862769 -185.466586) (xy 117.841268 -185.446416) (xy 117.833937 -185.439877) (xy 117.815774 -185.432434)
			(xy 117.805962 -185.431938) (xy 117.752622 -185.431938) (xy 117.745764 -185.439304) (xy 117.73923 -185.446639)
			(xy 117.731786 -185.464799) (xy 117.731286 -185.47461) (xy 117.731286 -185.506614) (xy 117.731778 -185.516428)
			(xy 117.739219 -185.534592) (xy 117.745764 -185.54192) (xy 117.765949 -185.563409) (xy 117.800092 -185.611472)
			(xy 117.826436 -185.664214) (xy 117.844354 -185.72038) (xy 117.85342 -185.778634) (xy 117.853968 -185.808112)
			(xy 117.853482 -185.835363) (xy 117.845726 -185.889311) (xy 117.830371 -185.941606) (xy 117.807729 -185.991183)
			(xy 117.778263 -186.037033) (xy 117.742572 -186.078224) (xy 117.701381 -186.113915) (xy 117.655531 -186.143381)
			(xy 117.605954 -186.166023) (xy 117.553659 -186.181378) (xy 117.499711 -186.189134) (xy 117.445209 -186.189134)
			(xy 117.391261 -186.181378) (xy 117.338966 -186.166023) (xy 117.289389 -186.143381) (xy 117.243539 -186.113915)
			(xy 117.202348 -186.078224) (xy 117.166657 -186.037033) (xy 117.137191 -185.991183) (xy 117.114549 -185.941606)
			(xy 117.099194 -185.889311) (xy 117.091438 -185.835363) (xy 117.090952 -185.808112) (xy 117.091412 -185.780741)
			(xy 117.09923 -185.726562) (xy 117.114719 -185.674058) (xy 117.137563 -185.624311) (xy 117.167289 -185.578345)
			(xy 117.184932 -185.557414) (xy 117.185186 -185.55716) (xy 117.190752 -185.550059) (xy 117.197012 -185.533153)
			(xy 117.197378 -185.52414) (xy 117.197378 -185.457084) (xy 117.197033 -185.448066) (xy 117.190778 -185.431149)
			(xy 117.185186 -185.424064) (xy 117.184932 -185.424064) (xy 117.184932 -185.42381) (xy 117.167303 -185.402868)
			(xy 117.137577 -185.356902) (xy 117.114731 -185.307157) (xy 117.099233 -185.254656) (xy 117.091404 -185.200479)
			(xy 117.091402 -185.145739) (xy 117.09923 -185.091561) (xy 117.114724 -185.03906) (xy 117.137568 -184.989314)
			(xy 117.167292 -184.943347) (xy 117.184932 -184.922414) (xy 117.185186 -184.92216) (xy 117.190752 -184.915059)
			(xy 117.197012 -184.898153) (xy 117.197378 -184.88914) (xy 117.197378 -184.822084) (xy 117.197033 -184.813066)
			(xy 117.190778 -184.796149) (xy 117.185186 -184.789064) (xy 117.184932 -184.789064) (xy 117.184932 -184.78881)
			(xy 117.167289 -184.767881) (xy 117.137577 -184.721908) (xy 117.114741 -184.67216) (xy 117.099251 -184.619658)
			(xy 117.091425 -184.565481) (xy 117.090952 -184.538112) (xy 117.091455 -184.510814) (xy 117.099223 -184.456774)
			(xy 117.114618 -184.404394) (xy 117.137324 -184.354744) (xy 117.166878 -184.308839) (xy 117.184424 -184.287922)
			(xy 117.190273 -184.280736) (xy 117.196777 -184.2634) (xy 117.197124 -184.25414) (xy 117.19687 -184.178194)
			(xy 117.19052 -184.161176) (xy 117.184424 -184.154318) (xy 117.166722 -184.133347) (xy 117.136841 -184.087318)
			(xy 117.113872 -184.037479) (xy 117.098289 -183.98486) (xy 117.090415 -183.930551) (xy 117.089936 -183.903112)
			(xy 115.109752 -183.903112) (xy 115.109288 -183.930375) (xy 115.101524 -183.984345) (xy 115.086157 -184.03666)
			(xy 115.0635 -184.086255) (xy 115.034013 -184.13212) (xy 115.016534 -184.153048) (xy 115.01628 -184.153302)
			(xy 115.010773 -184.160027) (xy 115.004272 -184.176134) (xy 115.00358 -184.184798) (xy 115.003834 -184.237376)
			(xy 115.003834 -184.253632) (xy 115.003937 -184.258244) (xy 115.005601 -184.267316) (xy 115.007136 -184.271666)
			(xy 115.010184 -184.279794) (xy 115.01628 -184.286906) (xy 115.034001 -184.307861) (xy 115.063871 -184.353898)
			(xy 115.086834 -184.403742) (xy 115.102416 -184.456362) (xy 115.110294 -184.510673) (xy 115.110768 -184.538112)
			(xy 115.110304 -184.564155) (xy 115.103178 -184.615753) (xy 115.089102 -184.665902) (xy 115.068336 -184.713671)
			(xy 115.041266 -184.758171) (xy 115.02517 -184.77865) (xy 115.024662 -184.779666) (xy 115.022376 -184.78246)
			(xy 115.016788 -184.798462) (xy 115.016788 -184.839864) (xy 115.004342 -184.839864) (xy 115.004342 -184.889394)
			(xy 115.004596 -184.89422) (xy 115.005566 -184.901631) (xy 115.011248 -184.915448) (xy 115.015772 -184.921398)
			(xy 115.016788 -184.922414) (xy 115.03443 -184.943345) (xy 115.064155 -184.989312) (xy 115.086997 -185.039059)
			(xy 115.102486 -185.091562) (xy 115.110303 -185.145742) (xy 115.110768 -185.173112) (xy 115.110304 -185.199155)
			(xy 115.103178 -185.250753) (xy 115.089102 -185.300902) (xy 115.068336 -185.348671) (xy 115.041266 -185.393171)
			(xy 115.02517 -185.41365) (xy 115.024662 -185.414666) (xy 115.022376 -185.41746) (xy 115.016788 -185.433462)
			(xy 115.016788 -185.474864) (xy 115.004342 -185.474864) (xy 115.004342 -185.524394) (xy 115.004596 -185.52922)
			(xy 115.005566 -185.536631) (xy 115.011248 -185.550448) (xy 115.015772 -185.556398) (xy 115.016788 -185.557414)
			(xy 115.03443 -185.578345) (xy 115.064155 -185.624312) (xy 115.086997 -185.674059) (xy 115.102486 -185.726562)
			(xy 115.110303 -185.780742) (xy 115.110768 -185.808112) (xy 115.110304 -185.834155) (xy 115.103178 -185.885753)
			(xy 115.089102 -185.935902) (xy 115.068336 -185.983671) (xy 115.041266 -186.028171) (xy 115.02517 -186.04865)
			(xy 115.024662 -186.049666) (xy 115.022376 -186.05246) (xy 115.016788 -186.068462) (xy 115.016788 -186.109864)
			(xy 115.004342 -186.109864) (xy 115.004342 -186.159394) (xy 115.004596 -186.16422) (xy 115.005566 -186.171631)
			(xy 115.011248 -186.185448) (xy 115.015772 -186.191398) (xy 115.016788 -186.192414) (xy 115.03443 -186.213345)
			(xy 115.064155 -186.259312) (xy 115.086997 -186.309059) (xy 115.102486 -186.361562) (xy 115.110303 -186.415742)
			(xy 115.110768 -186.443112) (xy 115.110689 -186.45585) (xy 115.109035 -186.481271) (xy 115.107466 -186.493912)
			(xy 115.10307 -186.52268) (xy 115.086701 -186.578525) (xy 115.062053 -186.631241) (xy 115.029694 -186.679609)
			(xy 115.010438 -186.70143) (xy 115.004088 -186.708034) (xy 114.993674 -186.733688) (xy 114.991991 -186.738202)
			(xy 114.990206 -186.747667) (xy 114.990118 -186.752484) (xy 114.989864 -186.812682) (xy 114.990003 -186.817572)
			(xy 114.991925 -186.827163) (xy 114.993674 -186.831732) (xy 114.99723 -186.840876) (xy 115.004088 -186.847988)
			(xy 115.023799 -186.869426) (xy 115.05715 -186.917164) (xy 115.082863 -186.969414) (xy 115.100343 -187.024963)
			(xy 115.109182 -187.082523) (xy 115.109752 -187.11164) (xy 115.109286 -187.137683) (xy 115.102157 -187.189278)
			(xy 115.088076 -187.239425) (xy 115.067307 -187.28719) (xy 115.040235 -187.331688) (xy 115.024154 -187.352178)
			(xy 115.023646 -187.353194) (xy 115.02136 -187.355988) (xy 115.015772 -187.37199) (xy 115.015772 -187.413392)
			(xy 115.003326 -187.413392) (xy 115.003326 -187.462922) (xy 115.00358 -187.467748) (xy 115.004553 -187.475158)
			(xy 115.01024 -187.488971) (xy 115.014756 -187.494926) (xy 115.015772 -187.495942) (xy 115.033413 -187.516874)
			(xy 115.063136 -187.56284) (xy 115.085975 -187.612588) (xy 115.101461 -187.665091) (xy 115.109274 -187.71927)
			(xy 115.109752 -187.74664) (xy 115.109286 -187.772683) (xy 115.102157 -187.824278) (xy 115.088076 -187.874425)
			(xy 115.067307 -187.92219) (xy 115.040235 -187.966688) (xy 115.024154 -187.987178) (xy 115.023646 -187.988194)
			(xy 115.02136 -187.990988) (xy 115.015772 -188.00699) (xy 115.015772 -188.048392) (xy 115.003326 -188.048392)
			(xy 115.003326 -188.097668) (xy 115.003608 -188.105925) (xy 115.008799 -188.121598) (xy 115.013486 -188.128402)
			(xy 115.017296 -188.132466) (xy 115.01755 -188.13272) (xy 115.033315 -188.151694) (xy 115.060318 -188.192976)
			(xy 115.071398 -188.215016) (xy 115.084162 -188.242543) (xy 115.101768 -188.300607) (xy 115.10645 -188.330586)
			(xy 115.107212 -188.337444) (xy 115.112546 -188.350144) (xy 115.116864 -188.355478) (xy 115.121161 -188.360577)
			(xy 115.131832 -188.368567) (xy 115.137946 -188.371226) (xy 115.22075 -188.403738) (xy 115.229283 -188.406708)
			(xy 115.247336 -188.407065) (xy 115.264381 -188.401108) (xy 115.27155 -188.39561) (xy 122.838464 -182.17896)
			(xy 122.845064 -182.173064) (xy 122.85412 -182.157875) (xy 122.857478 -182.140512) (xy 122.856498 -182.131716)
			(xy 122.842782 -182.045102) (xy 122.842782 -182.044848) (xy 122.840148 -182.03293) (xy 122.825697 -182.013303)
			(xy 122.815096 -182.007256) (xy 122.811286 -182.005732) (xy 122.784121 -181.994429) (xy 122.73335 -181.964702)
			(xy 122.710194 -181.94655) (xy 122.709178 -181.946042) (xy 122.706384 -181.943756) (xy 122.690382 -181.938168)
			(xy 122.64898 -181.938168) (xy 122.64898 -181.925722) (xy 122.59945 -181.925722) (xy 122.594624 -181.925976)
			(xy 122.58721 -181.926939) (xy 122.573384 -181.93261) (xy 122.567446 -181.937152) (xy 122.56643 -181.938168)
			(xy 122.5455 -181.955813) (xy 122.499535 -181.985545) (xy 122.449788 -182.008394) (xy 122.397284 -182.02389)
			(xy 122.343104 -182.031713) (xy 122.315732 -182.032148) (xy 122.286687 -182.0316) (xy 122.229269 -182.022791)
			(xy 122.173847 -182.005387) (xy 122.121701 -181.979789) (xy 122.074034 -181.946588) (xy 122.052588 -181.926992)
			(xy 122.049286 -181.923944) (xy 122.023632 -181.913276) (xy 122.018946 -181.911476) (xy 122.009093 -181.909552)
			(xy 122.004074 -181.909466) (xy 121.992136 -181.909466) (xy 121.987246 -181.909604) (xy 121.977653 -181.911523)
			(xy 121.973086 -181.913276) (xy 121.962418 -181.917594) (xy 121.958017 -181.919525) (xy 121.949963 -181.924765)
			(xy 121.946416 -181.928008) (xy 121.939558 -181.934358) (xy 121.939558 -181.973982) (xy 121.939653 -181.979001)
			(xy 121.941577 -181.988851) (xy 121.943368 -181.99354) (xy 121.954036 -182.019194) (xy 121.957084 -182.022496)
			(xy 121.976715 -182.043914) (xy 122.009923 -182.091584) (xy 122.035523 -182.143736) (xy 122.052924 -182.199165)
			(xy 122.061723 -182.256592) (xy 122.06224 -182.28564) (xy 122.061754 -182.312891) (xy 122.053998 -182.366839)
			(xy 122.038643 -182.419134) (xy 122.016001 -182.468711) (xy 121.986535 -182.514561) (xy 121.950844 -182.555752)
			(xy 121.909653 -182.591443) (xy 121.863803 -182.620909) (xy 121.814226 -182.643551) (xy 121.761931 -182.658906)
			(xy 121.707983 -182.666662) (xy 121.653481 -182.666662) (xy 121.599533 -182.658906) (xy 121.547238 -182.643551)
			(xy 121.497661 -182.620909) (xy 121.451811 -182.591443) (xy 121.41062 -182.555752) (xy 121.374929 -182.514561)
			(xy 121.345463 -182.468711) (xy 121.322821 -182.419134) (xy 121.307466 -182.366839) (xy 121.29971 -182.312891)
			(xy 121.299224 -182.28564) (xy 121.299691 -182.259598) (xy 121.306823 -182.208003) (xy 121.320904 -182.157858)
			(xy 121.341674 -182.110093) (xy 121.368747 -182.065596) (xy 121.384822 -182.045102) (xy 121.38533 -182.044086)
			(xy 121.387616 -182.041292) (xy 121.393204 -182.02529) (xy 121.393204 -181.983888) (xy 121.40565 -181.983888)
			(xy 121.40565 -181.934612) (xy 121.405396 -181.930802) (xy 121.405024 -181.92648) (xy 121.402976 -181.918052)
			(xy 121.401332 -181.914038) (xy 121.381792 -181.892545) (xy 121.348757 -181.844767) (xy 121.3233 -181.792557)
			(xy 121.306002 -181.737107) (xy 121.297257 -181.679683) (xy 121.296684 -181.65064) (xy 121.297121 -181.624534)
			(xy 121.304193 -181.572804) (xy 121.318213 -181.522509) (xy 121.338921 -181.47458) (xy 121.365936 -181.4299)
			(xy 121.382028 -181.40934) (xy 121.387139 -181.402416) (xy 121.392844 -181.386189) (xy 121.393204 -181.37759)
			(xy 121.393204 -181.348888) (xy 121.40565 -181.348888) (xy 121.40565 -181.299358) (xy 121.405396 -181.294532)
			(xy 121.404433 -181.287118) (xy 121.398761 -181.273293) (xy 121.39422 -181.267354) (xy 121.393204 -181.266338)
			(xy 121.375984 -181.245917) (xy 121.346831 -181.201158) (xy 121.32421 -181.152768) (xy 121.308566 -181.101694)
			(xy 121.300204 -181.048936) (xy 121.299287 -180.995528) (xy 121.305835 -180.942515) (xy 121.319718 -180.890934)
			(xy 121.340665 -180.841796) (xy 121.368266 -180.796064) (xy 121.384822 -180.775102) (xy 121.38533 -180.774086)
			(xy 121.387616 -180.771292) (xy 121.393204 -180.75529) (xy 121.393204 -180.713888) (xy 121.40565 -180.713888)
			(xy 121.40565 -180.664358) (xy 121.405396 -180.659532) (xy 121.404433 -180.652118) (xy 121.398761 -180.638293)
			(xy 121.39422 -180.632354) (xy 121.393204 -180.631338) (xy 121.375984 -180.610917) (xy 121.346831 -180.566158)
			(xy 121.32421 -180.517768) (xy 121.308566 -180.466694) (xy 121.300204 -180.413936) (xy 121.299287 -180.360528)
			(xy 121.305835 -180.307515) (xy 121.319718 -180.255934) (xy 121.340665 -180.206796) (xy 121.368266 -180.161064)
			(xy 121.384822 -180.140102) (xy 121.38533 -180.139086) (xy 121.387616 -180.136292) (xy 121.393204 -180.12029)
			(xy 121.393204 -180.078888) (xy 121.40565 -180.078888) (xy 121.40565 -180.029358) (xy 121.405396 -180.024532)
			(xy 121.404433 -180.017118) (xy 121.398761 -180.003293) (xy 121.39422 -179.997354) (xy 121.393204 -179.996338)
			(xy 121.375984 -179.975917) (xy 121.346831 -179.931158) (xy 121.32421 -179.882768) (xy 121.308566 -179.831694)
			(xy 121.300204 -179.778936) (xy 121.299287 -179.725528) (xy 121.305835 -179.672515) (xy 121.319718 -179.620934)
			(xy 121.340665 -179.571796) (xy 121.368266 -179.526064) (xy 121.384822 -179.505102) (xy 121.38533 -179.504086)
			(xy 121.387616 -179.501292) (xy 121.393204 -179.48529) (xy 121.393204 -179.443888) (xy 121.40565 -179.443888)
			(xy 121.40565 -179.394358) (xy 121.405396 -179.389532) (xy 121.404433 -179.382118) (xy 121.398761 -179.368293)
			(xy 121.39422 -179.362354) (xy 121.393204 -179.361338) (xy 121.375984 -179.340917) (xy 121.346831 -179.296158)
			(xy 121.32421 -179.247768) (xy 121.308566 -179.196694) (xy 121.300204 -179.143936) (xy 121.299287 -179.090528)
			(xy 121.305835 -179.037515) (xy 121.319718 -178.985934) (xy 121.340665 -178.936796) (xy 121.368266 -178.891064)
			(xy 121.384822 -178.870102) (xy 121.38533 -178.869086) (xy 121.387616 -178.866292) (xy 121.393204 -178.85029)
			(xy 121.393204 -178.808888) (xy 121.40565 -178.808888) (xy 121.40565 -178.759358) (xy 121.405396 -178.754532)
			(xy 121.404433 -178.747118) (xy 121.398761 -178.733293) (xy 121.39422 -178.727354) (xy 121.393204 -178.726338)
			(xy 121.375984 -178.705917) (xy 121.346831 -178.661158) (xy 121.32421 -178.612768) (xy 121.308566 -178.561694)
			(xy 121.300204 -178.508936) (xy 121.299287 -178.455528) (xy 121.305835 -178.402515) (xy 121.319718 -178.350934)
			(xy 121.340665 -178.301796) (xy 121.368266 -178.256064) (xy 121.384822 -178.235102) (xy 121.38533 -178.234086)
			(xy 121.387616 -178.231292) (xy 121.393204 -178.21529) (xy 121.393204 -178.173888) (xy 121.40565 -178.173888)
			(xy 121.40565 -178.124358) (xy 121.405396 -178.119532) (xy 121.404433 -178.112118) (xy 121.398761 -178.098293)
			(xy 121.39422 -178.092354) (xy 121.393204 -178.091338) (xy 121.375565 -178.070406) (xy 121.345847 -178.024438)
			(xy 121.323011 -177.97469) (xy 121.307529 -177.922187) (xy 121.299719 -177.868009) (xy 121.299224 -177.84064)
			(xy 121.299773 -177.811486) (xy 121.308636 -177.753855) (xy 121.326161 -177.698242) (xy 121.351941 -177.645942)
			(xy 121.385376 -177.598172) (xy 121.405142 -177.576734) (xy 121.412508 -177.569114) (xy 121.41581 -177.560478)
			(xy 121.417441 -177.556015) (xy 121.419238 -177.546686) (xy 121.419366 -177.541936) (xy 121.419366 -177.470816)
			(xy 121.418982 -177.462191) (xy 121.413132 -177.445961) (xy 121.407936 -177.439066) (xy 121.405142 -177.436018)
			(xy 121.385387 -177.414571) (xy 121.351955 -177.366801) (xy 121.326175 -177.314504) (xy 121.308648 -177.258894)
			(xy 121.29978 -177.201265) (xy 121.299224 -177.172112) (xy 121.299687 -177.144859) (xy 121.307442 -177.090909)
			(xy 121.322798 -177.038611) (xy 121.34544 -176.989032) (xy 121.374908 -176.94318) (xy 121.410602 -176.901988)
			(xy 121.451796 -176.866296) (xy 121.497649 -176.83683) (xy 121.54723 -176.814191) (xy 121.599528 -176.798838)
			(xy 121.653479 -176.791085) (xy 121.680732 -176.790604) (xy 121.706775 -176.791069) (xy 121.758372 -176.798197)
			(xy 121.80852 -176.812275) (xy 121.856287 -176.833042) (xy 121.900788 -176.860111) (xy 121.92127 -176.876202)
			(xy 121.922286 -176.87671) (xy 121.92508 -176.878996) (xy 121.941082 -176.884584) (xy 121.982484 -176.884584)
			(xy 121.982484 -176.89703) (xy 122.032014 -176.89703) (xy 122.03684 -176.896776) (xy 122.04425 -176.895803)
			(xy 122.058061 -176.890114) (xy 122.064018 -176.8856) (xy 122.065034 -176.884584) (xy 122.085453 -176.867366)
			(xy 122.130209 -176.838216) (xy 122.178597 -176.815601) (xy 122.229668 -176.799962) (xy 122.282422 -176.791607)
			(xy 122.335826 -176.790698) (xy 122.388833 -176.797254) (xy 122.440407 -176.811146) (xy 122.489535 -176.832103)
			(xy 122.535257 -176.859713) (xy 122.55627 -176.876202) (xy 122.557286 -176.87671) (xy 122.56008 -176.878996)
			(xy 122.576082 -176.884584) (xy 122.617484 -176.884584) (xy 122.617484 -176.89703) (xy 122.667014 -176.89703)
			(xy 122.67184 -176.896776) (xy 122.67925 -176.895803) (xy 122.693061 -176.890114) (xy 122.699018 -176.8856)
			(xy 122.700034 -176.884584) (xy 122.720966 -176.866945) (xy 122.766934 -176.837224) (xy 122.816681 -176.814386)
			(xy 122.869184 -176.798901) (xy 122.923362 -176.791088) (xy 122.950732 -176.790604) (xy 122.977981 -176.791092)
			(xy 123.031925 -176.798853) (xy 123.084215 -176.814211) (xy 123.133787 -176.836854) (xy 123.179633 -176.866321)
			(xy 123.220818 -176.902013) (xy 123.256505 -176.943202) (xy 123.285967 -176.989051) (xy 123.308605 -177.038626)
			(xy 123.323957 -177.090918) (xy 123.331711 -177.144863) (xy 123.33224 -177.172112) (xy 123.331776 -177.199375)
			(xy 123.324012 -177.253345) (xy 123.308645 -177.30566) (xy 123.285987 -177.355254) (xy 123.256499 -177.401118)
			(xy 123.239022 -177.422048) (xy 123.238768 -177.422302) (xy 123.233263 -177.429028) (xy 123.226763 -177.445134)
			(xy 123.226068 -177.453798) (xy 123.226322 -177.506376) (xy 123.226322 -177.522632) (xy 123.226424 -177.527244)
			(xy 123.228089 -177.536316) (xy 123.229624 -177.540666) (xy 123.232672 -177.548794) (xy 123.238768 -177.555906)
			(xy 123.25649 -177.576861) (xy 123.286361 -177.622898) (xy 123.309324 -177.672742) (xy 123.324906 -177.725362)
			(xy 123.332785 -177.779673) (xy 123.333256 -177.807112) (xy 123.332792 -177.833155) (xy 123.325666 -177.884753)
			(xy 123.311589 -177.934901) (xy 123.290822 -177.98267) (xy 123.263752 -178.02717) (xy 123.247658 -178.04765)
			(xy 123.24715 -178.048666) (xy 123.244864 -178.05146) (xy 123.239276 -178.067462) (xy 123.239276 -178.108864)
			(xy 123.22683 -178.108864) (xy 123.22683 -178.158394) (xy 123.227084 -178.16322) (xy 123.228053 -178.170632)
			(xy 123.233734 -178.184449) (xy 123.23826 -178.190398) (xy 123.239276 -178.191414) (xy 123.256918 -178.212345)
			(xy 123.286644 -178.258311) (xy 123.309487 -178.308058) (xy 123.324977 -178.360562) (xy 123.332794 -178.414742)
			(xy 123.333256 -178.442112) (xy 123.332792 -178.468155) (xy 123.325666 -178.519753) (xy 123.311589 -178.569901)
			(xy 123.290822 -178.61767) (xy 123.263752 -178.66217) (xy 123.247658 -178.68265) (xy 123.24715 -178.683666)
			(xy 123.244864 -178.68646) (xy 123.239276 -178.702462) (xy 123.239276 -178.743864) (xy 123.22683 -178.743864)
			(xy 123.22683 -178.793394) (xy 123.227084 -178.79822) (xy 123.228053 -178.805632) (xy 123.233734 -178.819449)
			(xy 123.23826 -178.825398) (xy 123.239276 -178.826414) (xy 123.256918 -178.847345) (xy 123.286644 -178.893311)
			(xy 123.309487 -178.943058) (xy 123.324977 -178.995562) (xy 123.332794 -179.049742) (xy 123.333256 -179.077112)
			(xy 123.332792 -179.103155) (xy 123.325666 -179.154753) (xy 123.311589 -179.204901) (xy 123.290822 -179.25267)
			(xy 123.263752 -179.29717) (xy 123.247658 -179.31765) (xy 123.24715 -179.318666) (xy 123.244864 -179.32146)
			(xy 123.239276 -179.337462) (xy 123.239276 -179.378864) (xy 123.22683 -179.378864) (xy 123.22683 -179.428394)
			(xy 123.227084 -179.43322) (xy 123.228053 -179.440632) (xy 123.233734 -179.454449) (xy 123.23826 -179.460398)
			(xy 123.239276 -179.461414) (xy 123.256918 -179.482345) (xy 123.286644 -179.528311) (xy 123.309487 -179.578058)
			(xy 123.324977 -179.630562) (xy 123.332794 -179.684742) (xy 123.333256 -179.712112) (xy 123.333177 -179.72485)
			(xy 123.331523 -179.750271) (xy 123.329954 -179.762912) (xy 123.325558 -179.79168) (xy 123.309189 -179.847525)
			(xy 123.28454 -179.90024) (xy 123.25218 -179.948608) (xy 123.232926 -179.97043) (xy 123.226576 -179.977034)
			(xy 123.216162 -180.002688) (xy 123.214479 -180.007202) (xy 123.212695 -180.016667) (xy 123.212606 -180.021484)
			(xy 123.212352 -180.081682) (xy 123.212491 -180.086572) (xy 123.214413 -180.096163) (xy 123.216162 -180.100732)
			(xy 123.219718 -180.109876) (xy 123.226576 -180.116988) (xy 123.246287 -180.138426) (xy 123.279639 -180.186164)
			(xy 123.305354 -180.238414) (xy 123.322833 -180.293963) (xy 123.331673 -180.351523) (xy 123.33224 -180.38064)
			(xy 123.331774 -180.406682) (xy 123.324644 -180.458278) (xy 123.310564 -180.508424) (xy 123.289794 -180.55619)
			(xy 123.262721 -180.600686) (xy 123.246642 -180.621178) (xy 123.246134 -180.622194) (xy 123.243848 -180.624988)
			(xy 123.23826 -180.64099) (xy 123.23826 -180.682392) (xy 123.225814 -180.682392) (xy 123.225814 -180.731922)
			(xy 123.226068 -180.736748) (xy 123.22704 -180.744158) (xy 123.232726 -180.757972) (xy 123.237244 -180.763926)
			(xy 123.23826 -180.764942) (xy 123.255901 -180.785873) (xy 123.285625 -180.83184) (xy 123.308465 -180.881587)
			(xy 123.323952 -180.934091) (xy 123.331765 -180.98827) (xy 123.33224 -181.01564) (xy 123.331774 -181.041682)
			(xy 123.324644 -181.093278) (xy 123.310564 -181.143424) (xy 123.289794 -181.19119) (xy 123.262721 -181.235686)
			(xy 123.246642 -181.256178) (xy 123.246134 -181.257194) (xy 123.243848 -181.259988) (xy 123.23826 -181.27599)
			(xy 123.23826 -181.317392) (xy 123.225814 -181.317392) (xy 123.225814 -181.366922) (xy 123.226068 -181.371748)
			(xy 123.22704 -181.379158) (xy 123.232726 -181.392972) (xy 123.237244 -181.398926) (xy 123.23826 -181.399942)
			(xy 123.254821 -181.419575) (xy 123.283077 -181.462469) (xy 123.305327 -181.508763) (xy 123.321168 -181.557624)
			(xy 123.326144 -181.582822) (xy 123.32716 -181.589172) (xy 123.332748 -181.601364) (xy 123.337066 -181.60619)
			(xy 123.341453 -181.611132) (xy 123.352267 -181.618719) (xy 123.358402 -181.621176) (xy 123.441206 -181.651656)
			(xy 123.449294 -181.654198) (xy 123.466237 -181.654344) (xy 123.482295 -181.64894) (xy 123.489212 -181.644036)
			(xy 126.076964 -179.518056) (xy 126.08052 -179.514754) (xy 126.084838 -179.509928) (xy 126.089371 -179.503346)
			(xy 126.094433 -179.488195) (xy 126.094744 -179.48021) (xy 126.09576 -179.402994) (xy 126.095692 -179.397504)
			(xy 126.093511 -179.386744) (xy 126.091442 -179.381658) (xy 126.087124 -179.371752) (xy 126.078742 -179.364386)
			(xy 126.07036 -179.356766) (xy 126.063502 -179.350416) (xy 126.03734 -179.339748) (xy 126.032774 -179.337989)
			(xy 126.023181 -179.336062) (xy 126.01829 -179.335938) (xy 126.006606 -179.335938) (xy 126.001588 -179.336035)
			(xy 125.99174 -179.337964) (xy 125.987048 -179.339748) (xy 125.961394 -179.350416) (xy 125.958092 -179.353464)
			(xy 125.936674 -179.373095) (xy 125.889005 -179.406304) (xy 125.836853 -179.431904) (xy 125.781423 -179.449303)
			(xy 125.723996 -179.458101) (xy 125.694948 -179.45862) (xy 125.667693 -179.45816) (xy 125.613736 -179.450409)
			(xy 125.561431 -179.435057) (xy 125.511844 -179.412418) (xy 125.465984 -179.382951) (xy 125.424785 -179.347258)
			(xy 125.389085 -179.306064) (xy 125.359611 -179.260208) (xy 125.336964 -179.210625) (xy 125.321604 -179.158323)
			(xy 125.313844 -179.104367) (xy 125.31344 -179.077112) (xy 125.313902 -179.051068) (xy 125.321025 -178.999469)
			(xy 125.3351 -178.949319) (xy 125.355864 -178.901548) (xy 125.382932 -178.857045) (xy 125.399038 -178.836574)
			(xy 125.399546 -178.835558) (xy 125.401832 -178.832764) (xy 125.40742 -178.816762) (xy 125.40742 -178.77536)
			(xy 125.419866 -178.77536) (xy 125.419866 -178.72583) (xy 125.419612 -178.721004) (xy 125.418646 -178.713591)
			(xy 125.41297 -178.69977) (xy 125.408436 -178.693826) (xy 125.40742 -178.69281) (xy 125.390201 -178.67239)
			(xy 125.361051 -178.627631) (xy 125.338433 -178.579242) (xy 125.322791 -178.52817) (xy 125.314432 -178.475414)
			(xy 125.313519 -178.422007) (xy 125.32007 -178.368996) (xy 125.333956 -178.317419) (xy 125.354906 -178.268285)
			(xy 125.382509 -178.222556) (xy 125.399038 -178.201574) (xy 125.399546 -178.200558) (xy 125.401832 -178.197764)
			(xy 125.40742 -178.181762) (xy 125.40742 -178.14036) (xy 125.419866 -178.14036) (xy 125.419866 -178.09083)
			(xy 125.419612 -178.086004) (xy 125.418646 -178.078591) (xy 125.41297 -178.06477) (xy 125.408436 -178.058826)
			(xy 125.40742 -178.05781) (xy 125.389777 -178.036879) (xy 125.360048 -177.990913) (xy 125.337202 -177.941167)
			(xy 125.32171 -177.888663) (xy 125.313889 -177.834483) (xy 125.31344 -177.807112) (xy 125.313518 -177.794374)
			(xy 125.315171 -177.768953) (xy 125.316742 -177.756312) (xy 125.321252 -177.727079) (xy 125.338121 -177.670387)
			(xy 125.363534 -177.616977) (xy 125.379734 -177.592228) (xy 125.386019 -177.583131) (xy 125.399487 -177.565592)
			(xy 125.406658 -177.557176) (xy 125.406912 -177.556922) (xy 125.412409 -177.550193) (xy 125.418887 -177.534085)
			(xy 125.419612 -177.525426) (xy 125.419358 -177.472848) (xy 125.419358 -177.456592) (xy 125.419258 -177.45198)
			(xy 125.417597 -177.442906) (xy 125.416056 -177.438558) (xy 125.413008 -177.43043) (xy 125.406912 -177.423318)
			(xy 125.38919 -177.402363) (xy 125.359317 -177.356326) (xy 125.336352 -177.306483) (xy 125.320767 -177.253862)
			(xy 125.312886 -177.199552) (xy 125.312424 -177.172112) (xy 125.312887 -177.144859) (xy 125.320642 -177.090909)
			(xy 125.335998 -177.038611) (xy 125.35864 -176.989032) (xy 125.388108 -176.94318) (xy 125.423802 -176.901988)
			(xy 125.464996 -176.866296) (xy 125.510849 -176.83683) (xy 125.56043 -176.814191) (xy 125.612728 -176.798838)
			(xy 125.666679 -176.791085) (xy 125.693932 -176.790604) (xy 125.719975 -176.791069) (xy 125.771572 -176.798197)
			(xy 125.82172 -176.812275) (xy 125.869487 -176.833042) (xy 125.913988 -176.860111) (xy 125.93447 -176.876202)
			(xy 125.935486 -176.87671) (xy 125.93828 -176.878996) (xy 125.954282 -176.884584) (xy 125.995684 -176.884584)
			(xy 125.995684 -176.89703) (xy 126.045214 -176.89703) (xy 126.05004 -176.896776) (xy 126.05745 -176.895803)
			(xy 126.071261 -176.890114) (xy 126.077218 -176.8856) (xy 126.078234 -176.884584) (xy 126.098653 -176.867366)
			(xy 126.143409 -176.838216) (xy 126.191797 -176.815601) (xy 126.242868 -176.799962) (xy 126.295622 -176.791607)
			(xy 126.349026 -176.790698) (xy 126.402033 -176.797254) (xy 126.453607 -176.811146) (xy 126.502735 -176.832103)
			(xy 126.548457 -176.859713) (xy 126.56947 -176.876202) (xy 126.570486 -176.87671) (xy 126.57328 -176.878996)
			(xy 126.589282 -176.884584) (xy 126.630684 -176.884584) (xy 126.630684 -176.89703) (xy 126.680214 -176.89703)
			(xy 126.68504 -176.896776) (xy 126.69245 -176.895803) (xy 126.706261 -176.890114) (xy 126.712218 -176.8856)
			(xy 126.713234 -176.884584) (xy 126.734166 -176.866945) (xy 126.780134 -176.837224) (xy 126.829881 -176.814386)
			(xy 126.882384 -176.798901) (xy 126.936562 -176.791088) (xy 126.963932 -176.790604) (xy 126.991181 -176.791092)
			(xy 127.045125 -176.798853) (xy 127.097415 -176.814211) (xy 127.146987 -176.836854) (xy 127.192833 -176.866321)
			(xy 127.234018 -176.902013) (xy 127.269705 -176.943202) (xy 127.299167 -176.989051) (xy 127.321805 -177.038626)
			(xy 127.337157 -177.090918) (xy 127.344911 -177.144863) (xy 127.34544 -177.172112) (xy 127.34489 -177.201229)
			(xy 127.336043 -177.258788) (xy 127.318557 -177.314336) (xy 127.292836 -177.366583) (xy 127.259479 -177.414318)
			(xy 127.239776 -177.435764) (xy 127.232918 -177.442876) (xy 127.229362 -177.45202) (xy 127.227611 -177.456588)
			(xy 127.225699 -177.46618) (xy 127.225552 -177.47107) (xy 127.225806 -177.531014) (xy 127.225939 -177.535905)
			(xy 127.227851 -177.545501) (xy 127.229616 -177.550064) (xy 127.24003 -177.575972) (xy 127.243586 -177.580036)
			(xy 127.262814 -177.601353) (xy 127.295303 -177.648683) (xy 127.320333 -177.700346) (xy 127.337338 -177.755177)
			(xy 127.345934 -177.811936) (xy 127.346456 -177.84064) (xy 127.34599 -177.866683) (xy 127.338861 -177.918278)
			(xy 127.324781 -177.968425) (xy 127.304012 -178.016191) (xy 127.276939 -178.060688) (xy 127.260858 -178.081178)
			(xy 127.26035 -178.082194) (xy 127.258064 -178.084988) (xy 127.252476 -178.10099) (xy 127.252476 -178.142392)
			(xy 127.24003 -178.142392) (xy 127.24003 -178.191922) (xy 127.240284 -178.196748) (xy 127.241257 -178.204158)
			(xy 127.246944 -178.21797) (xy 127.25146 -178.223926) (xy 127.252476 -178.224942) (xy 127.272385 -178.248653)
			(xy 127.305054 -178.301241) (xy 127.3175 -178.32959) (xy 127.3199 -178.335016) (xy 127.326831 -178.344643)
			(xy 127.331216 -178.34864) (xy 127.335534 -178.35245) (xy 127.345948 -178.358038) (xy 127.431038 -178.379374)
			(xy 127.43434 -178.380136) (xy 127.445366 -178.381522) (xy 127.466826 -178.375849) (xy 127.475742 -178.369214)
			(xy 134.32536 -172.74159) (xy 134.333059 -172.734527) (xy 134.342486 -172.715906) (xy 134.343648 -172.705522)
			(xy 134.345172 -172.679106) (xy 134.348728 -172.620178) (xy 134.34822 -172.618654) (xy 134.333996 -172.603668)
			(xy 134.326548 -172.596439) (xy 134.307532 -172.588177) (xy 134.297166 -172.587666) (xy 134.28599 -172.587666)
			(xy 134.28097 -172.587754) (xy 134.271115 -172.589666) (xy 134.266432 -172.591476) (xy 134.240778 -172.602144)
			(xy 134.237476 -172.605192) (xy 134.216057 -172.624821) (xy 134.168387 -172.658025) (xy 134.116234 -172.683621)
			(xy 134.060805 -172.701017) (xy 134.00338 -172.709811) (xy 133.974332 -172.710348) (xy 133.947078 -172.709864)
			(xy 133.893125 -172.702112) (xy 133.840824 -172.68676) (xy 133.79124 -172.664121) (xy 133.745383 -172.634656)
			(xy 133.704186 -172.598965) (xy 133.668487 -172.557775) (xy 133.639013 -172.511923) (xy 133.616365 -172.462344)
			(xy 133.601003 -172.410046) (xy 133.593241 -172.356094) (xy 133.592824 -172.32884) (xy 133.593291 -172.302798)
			(xy 133.600423 -172.251203) (xy 133.614504 -172.201058) (xy 133.635274 -172.153293) (xy 133.662347 -172.108796)
			(xy 133.678422 -172.088302) (xy 133.67893 -172.087286) (xy 133.681216 -172.084492) (xy 133.686804 -172.06849)
			(xy 133.686804 -172.027088) (xy 133.69925 -172.027088) (xy 133.69925 -171.977558) (xy 133.698996 -171.972732)
			(xy 133.698033 -171.965318) (xy 133.692361 -171.951493) (xy 133.68782 -171.945554) (xy 133.686804 -171.944538)
			(xy 133.669165 -171.923606) (xy 133.639447 -171.877638) (xy 133.616611 -171.82789) (xy 133.601129 -171.775387)
			(xy 133.593319 -171.721209) (xy 133.592824 -171.69384) (xy 133.592901 -171.681102) (xy 133.594552 -171.65568)
			(xy 133.596126 -171.64304) (xy 133.600423 -171.614926) (xy 133.616267 -171.560307) (xy 133.640054 -171.508651)
			(xy 133.671257 -171.461105) (xy 133.689852 -171.439586) (xy 133.69417 -171.43476) (xy 133.696202 -171.432474)
			(xy 133.699504 -171.423838) (xy 133.701044 -171.41949) (xy 133.702698 -171.410416) (xy 133.702806 -171.405804)
			(xy 133.702806 -171.38904) (xy 133.70306 -171.3357) (xy 133.702498 -171.328026) (xy 133.697337 -171.313537)
			(xy 133.6929 -171.307252) (xy 133.690106 -171.304204) (xy 133.672063 -171.283166) (xy 133.641624 -171.236852)
			(xy 133.618218 -171.186615) (xy 133.602341 -171.133516) (xy 133.594327 -171.078677) (xy 133.59384 -171.050966)
			(xy 133.59384 -171.050712) (xy 133.594302 -171.024668) (xy 133.601425 -170.973069) (xy 133.6155 -170.922919)
			(xy 133.636264 -170.875148) (xy 133.663332 -170.830645) (xy 133.679438 -170.810174) (xy 133.679946 -170.809158)
			(xy 133.682232 -170.806364) (xy 133.68782 -170.790362) (xy 133.68782 -170.74896) (xy 133.700266 -170.74896)
			(xy 133.700266 -170.69943) (xy 133.700012 -170.694604) (xy 133.699046 -170.687191) (xy 133.69337 -170.67337)
			(xy 133.688836 -170.667426) (xy 133.68782 -170.66641) (xy 133.670601 -170.64599) (xy 133.641451 -170.601231)
			(xy 133.618833 -170.552842) (xy 133.603191 -170.50177) (xy 133.594832 -170.449014) (xy 133.593919 -170.395607)
			(xy 133.60047 -170.342596) (xy 133.614356 -170.291019) (xy 133.635306 -170.241885) (xy 133.662909 -170.196156)
			(xy 133.679438 -170.175174) (xy 133.679946 -170.174158) (xy 133.682232 -170.171364) (xy 133.68782 -170.155362)
			(xy 133.68782 -170.11396) (xy 133.700266 -170.11396) (xy 133.700266 -170.06443) (xy 133.700012 -170.059604)
			(xy 133.699046 -170.052191) (xy 133.69337 -170.03837) (xy 133.688836 -170.032426) (xy 133.68782 -170.03141)
			(xy 133.670601 -170.01099) (xy 133.641451 -169.966231) (xy 133.618833 -169.917842) (xy 133.603191 -169.86677)
			(xy 133.594832 -169.814014) (xy 133.593919 -169.760607) (xy 133.60047 -169.707596) (xy 133.614356 -169.656019)
			(xy 133.635306 -169.606885) (xy 133.662909 -169.561156) (xy 133.679438 -169.540174) (xy 133.679946 -169.539158)
			(xy 133.682232 -169.536364) (xy 133.68782 -169.520362) (xy 133.68782 -169.47896) (xy 133.700266 -169.47896)
			(xy 133.700266 -169.42943) (xy 133.700012 -169.424604) (xy 133.699046 -169.417191) (xy 133.69337 -169.40337)
			(xy 133.688836 -169.397426) (xy 133.68782 -169.39641) (xy 133.670177 -169.375479) (xy 133.640448 -169.329513)
			(xy 133.617602 -169.279767) (xy 133.60211 -169.227263) (xy 133.594289 -169.173083) (xy 133.59384 -169.145712)
			(xy 133.593918 -169.132974) (xy 133.595571 -169.107553) (xy 133.597142 -169.094912) (xy 133.601652 -169.065679)
			(xy 133.618521 -169.008987) (xy 133.643934 -168.955577) (xy 133.660134 -168.930828) (xy 133.666419 -168.921731)
			(xy 133.679887 -168.904192) (xy 133.687058 -168.895776) (xy 133.687312 -168.895522) (xy 133.692809 -168.888793)
			(xy 133.699287 -168.872685) (xy 133.700012 -168.864026) (xy 133.699758 -168.811448) (xy 133.699758 -168.795192)
			(xy 133.699658 -168.79058) (xy 133.697997 -168.781506) (xy 133.696456 -168.777158) (xy 133.693408 -168.76903)
			(xy 133.687312 -168.761918) (xy 133.66959 -168.740963) (xy 133.639717 -168.694926) (xy 133.616752 -168.645083)
			(xy 133.601167 -168.592462) (xy 133.593286 -168.538152) (xy 133.592824 -168.510712) (xy 133.593287 -168.483459)
			(xy 133.601042 -168.429509) (xy 133.616398 -168.377211) (xy 133.63904 -168.327632) (xy 133.668508 -168.28178)
			(xy 133.704202 -168.240588) (xy 133.745396 -168.204896) (xy 133.791249 -168.17543) (xy 133.84083 -168.152791)
			(xy 133.893128 -168.137438) (xy 133.947079 -168.129685) (xy 133.974332 -168.129204) (xy 134.000375 -168.129669)
			(xy 134.051972 -168.136797) (xy 134.10212 -168.150875) (xy 134.149887 -168.171642) (xy 134.194388 -168.198711)
			(xy 134.21487 -168.214802) (xy 134.215886 -168.21531) (xy 134.21868 -168.217596) (xy 134.234682 -168.223184)
			(xy 134.276084 -168.223184) (xy 134.276084 -168.23563) (xy 134.325614 -168.23563) (xy 134.33044 -168.235376)
			(xy 134.33785 -168.234403) (xy 134.351661 -168.228714) (xy 134.357618 -168.2242) (xy 134.358634 -168.223184)
			(xy 134.379566 -168.205545) (xy 134.425534 -168.175824) (xy 134.475281 -168.152986) (xy 134.527784 -168.137501)
			(xy 134.581962 -168.129688) (xy 134.609332 -168.129204) (xy 134.636395 -168.129678) (xy 134.689977 -168.137331)
			(xy 134.74194 -168.152478) (xy 134.791241 -168.174816) (xy 134.836891 -168.203896) (xy 134.857744 -168.221152)
			(xy 134.864348 -168.22674) (xy 134.888732 -168.236392) (xy 134.893021 -168.237909) (xy 134.901964 -168.239565)
			(xy 134.906512 -168.239694) (xy 134.964932 -168.24071) (xy 134.969206 -168.240653) (xy 134.977636 -168.239251)
			(xy 134.981696 -168.237916) (xy 134.99084 -168.234868) (xy 135.011936 -168.216629) (xy 135.058428 -168.185834)
			(xy 135.108907 -168.162134) (xy 135.162299 -168.146036) (xy 135.217465 -168.137881) (xy 135.245348 -168.137332)
			(xy 135.27139 -168.137798) (xy 135.322986 -168.144929) (xy 135.373132 -168.159009) (xy 135.420897 -168.179778)
			(xy 135.465395 -168.20685) (xy 135.485886 -168.22293) (xy 135.486902 -168.223438) (xy 135.489696 -168.225724)
			(xy 135.505698 -168.231312) (xy 135.5471 -168.231312) (xy 135.5471 -168.243758) (xy 135.59663 -168.243758)
			(xy 135.601456 -168.243504) (xy 135.608865 -168.242529) (xy 135.622675 -168.236839) (xy 135.628634 -168.232328)
			(xy 135.62965 -168.231312) (xy 135.650582 -168.213672) (xy 135.696549 -168.183951) (xy 135.746297 -168.161114)
			(xy 135.7988 -168.14563) (xy 135.852978 -168.137818) (xy 135.880348 -168.137332) (xy 135.907596 -168.137822)
			(xy 135.961536 -168.145584) (xy 136.013823 -168.160944) (xy 136.063391 -168.183588) (xy 136.109233 -168.213056)
			(xy 136.150414 -168.248748) (xy 136.186097 -168.289938) (xy 136.215554 -168.335786) (xy 136.238187 -168.38536)
			(xy 136.253535 -168.43765) (xy 136.261285 -168.491592) (xy 136.261856 -168.51884) (xy 136.26139 -168.544883)
			(xy 136.254261 -168.596478) (xy 136.240181 -168.646625) (xy 136.219412 -168.694391) (xy 136.192339 -168.738888)
			(xy 136.176258 -168.759378) (xy 136.17575 -168.760394) (xy 136.173464 -168.763188) (xy 136.167876 -168.77919)
			(xy 136.167876 -168.820592) (xy 136.15543 -168.820592) (xy 136.15543 -168.870122) (xy 136.155684 -168.874948)
			(xy 136.156657 -168.882358) (xy 136.162344 -168.89617) (xy 136.16686 -168.902126) (xy 136.167876 -168.903142)
			(xy 136.185517 -168.924074) (xy 136.215239 -168.970041) (xy 136.238079 -169.019788) (xy 136.253564 -169.072291)
			(xy 136.261377 -169.12647) (xy 136.261856 -169.15384) (xy 136.26139 -169.179883) (xy 136.254261 -169.231478)
			(xy 136.240181 -169.281625) (xy 136.219412 -169.329391) (xy 136.192339 -169.373888) (xy 136.176258 -169.394378)
			(xy 136.17575 -169.395394) (xy 136.173464 -169.398188) (xy 136.167876 -169.41419) (xy 136.167876 -169.455592)
			(xy 136.15543 -169.455592) (xy 136.15543 -169.505122) (xy 136.155684 -169.509948) (xy 136.156657 -169.517358)
			(xy 136.162344 -169.53117) (xy 136.16686 -169.537126) (xy 136.167876 -169.538142) (xy 136.185517 -169.559074)
			(xy 136.215239 -169.605041) (xy 136.238079 -169.654788) (xy 136.253564 -169.707291) (xy 136.261377 -169.76147)
			(xy 136.261856 -169.78884) (xy 136.26139 -169.814883) (xy 136.254261 -169.866478) (xy 136.240181 -169.916625)
			(xy 136.219412 -169.964391) (xy 136.192339 -170.008888) (xy 136.176258 -170.029378) (xy 136.17575 -170.030394)
			(xy 136.173464 -170.033188) (xy 136.167876 -170.04919) (xy 136.167876 -170.090592) (xy 136.15543 -170.090592)
			(xy 136.15543 -170.140122) (xy 136.155684 -170.144948) (xy 136.156657 -170.152358) (xy 136.162344 -170.16617)
			(xy 136.16686 -170.172126) (xy 136.167876 -170.173142) (xy 136.185517 -170.194074) (xy 136.215239 -170.240041)
			(xy 136.238079 -170.289788) (xy 136.253564 -170.342291) (xy 136.261377 -170.39647) (xy 136.261856 -170.42384)
			(xy 136.26139 -170.449883) (xy 136.254261 -170.501478) (xy 136.240181 -170.551625) (xy 136.219412 -170.599391)
			(xy 136.192339 -170.643888) (xy 136.176258 -170.664378) (xy 136.17575 -170.665394) (xy 136.173464 -170.668188)
			(xy 136.167876 -170.68419) (xy 136.167876 -170.725592) (xy 136.15543 -170.725592) (xy 136.15543 -170.775122)
			(xy 136.155684 -170.779948) (xy 136.156657 -170.787358) (xy 136.162344 -170.80117) (xy 136.16686 -170.807126)
			(xy 136.167876 -170.808142) (xy 136.187584 -170.83169) (xy 136.220005 -170.883832) (xy 136.243679 -170.940485)
			(xy 136.251442 -170.970194) (xy 136.25195 -170.972734) (xy 136.255838 -170.98356) (xy 136.271272 -171.000575)
			(xy 136.281668 -171.0055) (xy 136.36879 -171.034964) (xy 136.37396 -171.036243) (xy 136.384588 -171.036891)
			(xy 136.389872 -171.036234) (xy 136.39546 -171.035218) (xy 136.400179 -171.033824) (xy 136.409001 -171.029469)
			(xy 136.412986 -171.026582) (xy 136.868408 -170.65244) (xy 136.948672 -170.5864) (xy 136.948926 -170.586146)
			(xy 136.950196 -170.58513) (xy 136.952482 -170.583098) (xy 139.323572 -168.212008) (xy 139.32869 -168.206547)
			(xy 139.33578 -168.193375) (xy 139.337542 -168.1861) (xy 139.339066 -168.17848) (xy 139.337796 -168.164002)
			(xy 139.335002 -168.157144) (xy 139.326341 -168.134528) (xy 139.314151 -168.087659) (xy 139.30798 -168.039626)
			(xy 139.30757 -168.015412) (xy 139.308062 -167.987383) (xy 139.316257 -167.931927) (xy 139.332472 -167.878265)
			(xy 139.35636 -167.82755) (xy 139.387405 -167.780874) (xy 139.424942 -167.739238) (xy 139.446254 -167.721026)
			(xy 139.450572 -167.717724) (xy 139.45743 -167.709088) (xy 139.469114 -167.684958) (xy 139.47146 -167.679736)
			(xy 139.474029 -167.668582) (xy 139.474194 -167.66286) (xy 139.474194 -167.605964) (xy 139.474048 -167.600239)
			(xy 139.471486 -167.589079) (xy 139.469114 -167.583866) (xy 139.45743 -167.559736) (xy 139.450572 -167.5511)
			(xy 139.446254 -167.547798) (xy 139.424953 -167.529572) (xy 139.387407 -167.487943) (xy 139.356352 -167.441271)
			(xy 139.332456 -167.39056) (xy 139.316234 -167.336898) (xy 139.308034 -167.281442) (xy 139.30757 -167.253412)
			(xy 139.308055 -167.22616) (xy 139.31581 -167.172209) (xy 139.331164 -167.119912) (xy 139.353804 -167.070332)
			(xy 139.38327 -167.024478) (xy 139.418961 -166.983285) (xy 139.460151 -166.94759) (xy 139.506002 -166.91812)
			(xy 139.55558 -166.895476) (xy 139.607876 -166.880117) (xy 139.661826 -166.872357) (xy 139.689078 -166.871904)
			(xy 139.717774 -166.872427) (xy 139.774519 -166.881031) (xy 139.829335 -166.898035) (xy 139.880988 -166.923053)
			(xy 139.928314 -166.955523) (xy 139.970244 -166.994713) (xy 140.005834 -167.039738) (xy 140.034282 -167.089585)
			(xy 140.054946 -167.143128) (xy 140.067361 -167.199163) (xy 140.069824 -167.227758) (xy 140.070332 -167.235124)
			(xy 140.075158 -167.248332) (xy 140.07973 -167.254428) (xy 140.084233 -167.2602) (xy 140.095849 -167.269099)
			(xy 140.10259 -167.271954) (xy 140.18895 -167.304466) (xy 140.191744 -167.305482) (xy 140.200692 -167.307816)
			(xy 140.219133 -167.306641) (xy 140.235966 -167.299017) (xy 140.242798 -167.292782) (xy 142.692882 -164.842698)
			(xy 142.697874 -164.837201) (xy 142.704726 -164.824036) (xy 142.706344 -164.81679) (xy 142.70736 -164.807138)
			(xy 142.70736 -150.343362) (xy 142.707195 -150.337352) (xy 142.704377 -150.325667) (xy 142.701772 -150.320248)
			(xy 142.69993 -150.316776) (xy 142.695331 -150.310402) (xy 142.692628 -150.307548) (xy 137.39114 -145.00606)
			(xy 137.383709 -144.999265) (xy 137.365096 -144.991621) (xy 137.344975 -144.991686) (xy 137.335514 -144.995138)
			(xy 137.326494 -144.999402) (xy 137.312401 -145.013496) (xy 137.304769 -145.031909) (xy 137.304272 -145.041874)
			(xy 137.304272 -150.250906) (xy 137.304356 -150.255317) (xy 137.305884 -150.264006) (xy 137.30732 -150.268178)
			(xy 137.310722 -150.27652) (xy 137.322298 -150.290309) (xy 137.329926 -150.295102) (xy 137.415524 -150.339298)
			(xy 137.424668 -150.344124) (xy 137.438892 -150.343108) (xy 137.445698 -150.342367) (xy 137.458571 -150.337726)
			(xy 137.464292 -150.333964) (xy 137.4648 -150.33371) (xy 137.489136 -150.317057) (xy 137.541866 -150.290665)
			(xy 137.598034 -150.272715) (xy 137.656297 -150.263638) (xy 137.68578 -150.263098) (xy 137.691368 -150.263098)
			(xy 137.718371 -150.26394) (xy 137.771744 -150.272301) (xy 137.823403 -150.288109) (xy 137.872315 -150.311047)
			(xy 137.917502 -150.340657) (xy 137.958058 -150.376347) (xy 137.993173 -150.417402) (xy 138.022143 -150.463001)
			(xy 138.04439 -150.512232) (xy 138.059469 -150.564109) (xy 138.067076 -150.617594) (xy 138.067542 -150.644606)
			(xy 138.067056 -150.671858) (xy 138.059299 -150.725807) (xy 138.043944 -150.778103) (xy 138.021302 -150.827681)
			(xy 137.991837 -150.873533) (xy 137.956146 -150.914726) (xy 137.914956 -150.95042) (xy 137.869106 -150.979889)
			(xy 137.819529 -151.002534) (xy 137.767234 -151.017893) (xy 137.713286 -151.025654) (xy 137.686034 -151.026114)
			(xy 137.686034 -151.026368) (xy 137.66011 -151.02593) (xy 137.608739 -151.018908) (xy 137.55879 -151.005001)
			(xy 137.511182 -150.984465) (xy 137.466789 -150.957679) (xy 137.426427 -150.925133) (xy 137.390839 -150.887426)
			(xy 137.375392 -150.866602) (xy 137.372852 -150.863046) (xy 137.365382 -150.855098) (xy 137.345641 -150.845875)
			(xy 137.334752 -150.845266) (xy 137.261346 -150.847552) (xy 137.255089 -150.847895) (xy 137.243014 -150.851235)
			(xy 137.23747 -150.854156) (xy 137.212578 -150.868634) (xy 137.203942 -150.876762) (xy 137.20064 -150.881842)
			(xy 137.181065 -150.910852) (xy 137.136516 -150.964831) (xy 137.086306 -151.013587) (xy 137.031041 -151.056529)
			(xy 136.971392 -151.093138) (xy 136.908081 -151.12297) (xy 136.841875 -151.145664) (xy 136.773576 -151.160945)
			(xy 136.704012 -151.168627) (xy 136.669018 -151.169116) (xy 136.63338 -151.168618) (xy 136.562552 -151.160641)
			(xy 136.493062 -151.144786) (xy 136.425784 -151.121251) (xy 136.361563 -151.090333) (xy 136.301207 -151.052421)
			(xy 136.245475 -151.00799) (xy 136.195066 -150.9576) (xy 136.150615 -150.901884) (xy 136.11268 -150.841542)
			(xy 136.081738 -150.777332) (xy 136.058179 -150.710063) (xy 136.042298 -150.640579) (xy 136.034295 -150.569754)
			(xy 136.033764 -150.534116) (xy 136.033764 -143.669766) (xy 136.033598 -143.663756) (xy 136.030776 -143.652073)
			(xy 136.028176 -143.646652) (xy 136.026334 -143.64318) (xy 136.021736 -143.636805) (xy 136.019032 -143.633952)
			(xy 130.941572 -138.556492) (xy 130.938719 -138.553789) (xy 130.932337 -138.549203) (xy 130.928872 -138.547348)
			(xy 130.923446 -138.544761) (xy 130.911766 -138.541931) (xy 130.905758 -138.54176) (xy 110.411514 -138.54176)
			(xy 110.402232 -138.542161) (xy 110.384901 -138.548805) (xy 110.377732 -138.554714) (xy 105.283 -143.649446)
			(xy 112.505996 -143.649446) (xy 112.510067 -143.593824) (xy 112.522193 -143.539387) (xy 112.542116 -143.487296)
			(xy 112.569412 -143.438661) (xy 112.603498 -143.394518) (xy 112.643647 -143.355809) (xy 112.689005 -143.323358)
			(xy 112.738605 -143.297857) (xy 112.791389 -143.27985) (xy 112.846232 -143.26972) (xy 112.901966 -143.267683)
			(xy 112.957403 -143.273783) (xy 113.01136 -143.287889) (xy 113.062689 -143.309701) (xy 113.110295 -143.338755)
			(xy 113.153163 -143.37443) (xy 113.19038 -143.415967) (xy 113.221153 -143.46248) (xy 113.244825 -143.512977)
			(xy 113.260893 -143.566384) (xy 113.269013 -143.62156) (xy 113.269522 -143.649446) (xy 113.269013 -143.677332)
			(xy 113.260893 -143.732508) (xy 113.244825 -143.785915) (xy 113.221153 -143.836412) (xy 113.19038 -143.882925)
			(xy 113.153163 -143.924462) (xy 113.110295 -143.960137) (xy 113.062689 -143.989191) (xy 113.01136 -144.011003)
			(xy 112.957403 -144.025109) (xy 112.901966 -144.031209) (xy 112.846232 -144.029172) (xy 112.791389 -144.019042)
			(xy 112.738605 -144.001035) (xy 112.689005 -143.975534) (xy 112.643647 -143.943083) (xy 112.603498 -143.904374)
			(xy 112.569412 -143.860231) (xy 112.542116 -143.811596) (xy 112.522193 -143.759505) (xy 112.510067 -143.705068)
			(xy 112.505996 -143.649446) (xy 105.283 -143.649446) (xy 104.041702 -144.890744) (xy 104.034672 -144.898535)
			(xy 104.027066 -144.918067) (xy 104.027918 -144.939011) (xy 104.03205 -144.948656) (xy 104.073452 -145.035016)
			(xy 104.077196 -145.042046) (xy 104.088196 -145.05355) (xy 104.095042 -145.057622) (xy 104.102011 -145.061069)
			(xy 104.117262 -145.06405) (xy 104.125014 -145.063464) (xy 104.135771 -145.062292) (xy 104.157374 -145.061021)
			(xy 104.168194 -145.060924) (xy 104.195443 -145.06141) (xy 104.249385 -145.069165) (xy 104.301675 -145.084517)
			(xy 104.351248 -145.107155) (xy 104.397094 -145.136617) (xy 104.438281 -145.172304) (xy 104.47397 -145.213489)
			(xy 104.503435 -145.259334) (xy 104.526076 -145.308906) (xy 104.541431 -145.361195) (xy 104.549189 -145.415137)
			(xy 104.549191 -145.469634) (xy 104.541437 -145.523577) (xy 104.526086 -145.575867) (xy 104.503449 -145.62544)
			(xy 104.473988 -145.671287) (xy 104.438302 -145.712475) (xy 104.397118 -145.748165) (xy 104.351273 -145.777631)
			(xy 104.301702 -145.800273) (xy 104.249414 -145.815629) (xy 104.195472 -145.823388) (xy 104.140975 -145.823391)
			(xy 104.087032 -145.815639) (xy 104.034741 -145.800289) (xy 103.985168 -145.777653) (xy 103.93932 -145.748193)
			(xy 103.898131 -145.712508) (xy 103.86244 -145.671325) (xy 103.832973 -145.625481) (xy 103.81033 -145.575911)
			(xy 103.794973 -145.523622) (xy 103.787212 -145.46968) (xy 103.786686 -145.442432) (xy 103.786783 -145.431612)
			(xy 103.788055 -145.410009) (xy 103.789226 -145.399252) (xy 103.789845 -145.391498) (xy 103.786862 -145.376239)
			(xy 103.783384 -145.36928) (xy 103.779334 -145.362417) (xy 103.767822 -145.351414) (xy 103.760778 -145.34769)
			(xy 103.674418 -145.306288) (xy 103.664766 -145.302193) (xy 103.643838 -145.301361) (xy 103.624313 -145.30894)
			(xy 103.616506 -145.31594) (xy 103.362252 -145.570194) (xy 103.340676 -145.590931) (xy 103.29226 -145.626096)
			(xy 103.238941 -145.65326) (xy 103.182032 -145.671755) (xy 103.122931 -145.681127) (xy 103.093012 -145.6817)
			(xy 103.010462 -145.6817) (xy 103.004879 -145.681841) (xy 102.99398 -145.684269) (xy 102.988872 -145.686526)
			(xy 102.985577 -145.688162) (xy 102.979456 -145.692241) (xy 102.97668 -145.694654) (xy 102.728522 -145.942812)
			(xy 102.706907 -145.96359) (xy 102.658401 -145.998825) (xy 102.604982 -146.026041) (xy 102.547964 -146.044571)
			(xy 102.48875 -146.053957) (xy 102.458774 -146.054572) (xy 102.458266 -146.054572) (xy 102.448469 -146.054502)
			(xy 102.428902 -146.053483) (xy 102.41915 -146.05254) (xy 102.418388 -146.05254) (xy 102.390642 -146.049096)
			(xy 102.336508 -146.035126) (xy 102.284994 -146.013398) (xy 102.237207 -145.984378) (xy 102.194172 -145.948689)
			(xy 102.156811 -145.907097) (xy 102.125927 -145.860493) (xy 102.102182 -145.809878) (xy 102.086085 -145.756337)
			(xy 102.077981 -145.701019) (xy 102.07752 -145.673064) (xy 102.078094 -145.643097) (xy 102.087438 -145.583897)
			(xy 102.105923 -145.526886) (xy 102.133094 -145.473466) (xy 102.168282 -145.42495) (xy 102.189026 -145.403316)
			(xy 102.561644 -145.030698) (xy 102.58322 -145.009962) (xy 102.631637 -144.974797) (xy 102.684955 -144.947632)
			(xy 102.741864 -144.929137) (xy 102.800965 -144.919765) (xy 102.830884 -144.919192) (xy 102.913434 -144.919192)
			(xy 102.919017 -144.919051) (xy 102.929916 -144.916624) (xy 102.935024 -144.914366) (xy 102.938319 -144.91273)
			(xy 102.94444 -144.908651) (xy 102.947216 -144.906238) (xy 109.225334 -138.628374) (xy 109.232009 -138.620971)
			(xy 109.239597 -138.60256) (xy 109.239599 -138.582647) (xy 109.236256 -138.573256) (xy 109.23397 -138.567668)
			(xy 109.230414 -138.558778) (xy 109.21746 -138.550142) (xy 109.211131 -138.546277) (xy 109.196932 -138.542019)
			(xy 109.18952 -138.54176) (xy 105.616756 -138.54176) (xy 105.604247 -138.5424) (xy 105.58214 -138.554116)
			(xy 105.574592 -138.564112) (xy 105.559344 -138.586011) (xy 105.523702 -138.625725) (xy 105.482871 -138.660081)
			(xy 105.437648 -138.688407) (xy 105.388917 -138.710151) (xy 105.33763 -138.724888) (xy 105.284789 -138.732329)
			(xy 105.231427 -138.732329) (xy 105.178586 -138.724888) (xy 105.127299 -138.710151) (xy 105.078568 -138.688407)
			(xy 105.033345 -138.660081) (xy 104.992514 -138.625725) (xy 104.956872 -138.586011) (xy 104.941624 -138.564112)
			(xy 104.934095 -138.55409) (xy 104.911979 -138.542357) (xy 104.89946 -138.54176) (xy 102.927404 -138.54176)
			(xy 102.918173 -138.542159) (xy 102.900913 -138.548708) (xy 102.887098 -138.560955) (xy 102.882446 -138.568938)
			(xy 102.840536 -138.648186) (xy 102.837508 -138.654476) (xy 102.834662 -138.668136) (xy 102.834948 -138.67511)
			(xy 102.83571 -138.689334) (xy 102.843584 -138.700764) (xy 102.859358 -138.724701) (xy 102.884315 -138.776308)
			(xy 102.901272 -138.831068) (xy 102.909846 -138.887748) (xy 102.910386 -138.91641) (xy 102.9099 -138.943661)
			(xy 102.902144 -138.997609) (xy 102.886789 -139.049904) (xy 102.864147 -139.099481) (xy 102.834681 -139.145331)
			(xy 102.79899 -139.186522) (xy 102.757799 -139.222213) (xy 102.711949 -139.251679) (xy 102.662372 -139.274321)
			(xy 102.610077 -139.289676) (xy 102.556129 -139.297432) (xy 102.501627 -139.297432) (xy 102.447679 -139.289676)
			(xy 102.395384 -139.274321) (xy 102.345807 -139.251679) (xy 102.299957 -139.222213) (xy 102.258766 -139.186522)
			(xy 102.223075 -139.145331) (xy 102.193609 -139.099481) (xy 102.170967 -139.049904) (xy 102.155612 -138.997609)
			(xy 102.147856 -138.943661) (xy 102.14737 -138.91641) (xy 102.147885 -138.887746) (xy 102.156463 -138.831064)
			(xy 102.173426 -138.776304) (xy 102.198394 -138.7247) (xy 102.214172 -138.700764) (xy 102.217982 -138.695176)
			(xy 102.222554 -138.682222) (xy 102.222808 -138.67511) (xy 102.223086 -138.668135) (xy 102.220263 -138.654468)
			(xy 102.21722 -138.648186) (xy 102.17531 -138.568938) (xy 102.170663 -138.560952) (xy 102.156842 -138.548711)
			(xy 102.139583 -138.542156) (xy 102.130352 -138.54176) (xy 97.666048 -138.54176) (xy 97.653976 -138.542428)
			(xy 97.632487 -138.55343) (xy 97.6249 -138.562842) (xy 97.57664 -138.62939) (xy 97.573336 -138.634347)
			(xy 97.56885 -138.645379) (xy 97.56775 -138.651234) (xy 97.565718 -138.663426) (xy 97.569528 -138.67511)
			(xy 97.578422 -138.70402) (xy 97.587991 -138.763741) (xy 97.588578 -138.793982) (xy 97.588092 -138.821233)
			(xy 97.580336 -138.875181) (xy 97.564981 -138.927476) (xy 97.542339 -138.977053) (xy 97.512873 -139.022903)
			(xy 97.477182 -139.064094) (xy 97.435991 -139.099785) (xy 97.390141 -139.129251) (xy 97.340564 -139.151893)
			(xy 97.288269 -139.167248) (xy 97.234321 -139.175004) (xy 97.179819 -139.175004) (xy 97.125871 -139.167248)
			(xy 97.073576 -139.151893) (xy 97.023999 -139.129251) (xy 96.978149 -139.099785) (xy 96.936958 -139.064094)
			(xy 96.901267 -139.022903) (xy 96.871801 -138.977053) (xy 96.849159 -138.927476) (xy 96.833804 -138.875181)
			(xy 96.826048 -138.821233) (xy 96.825562 -138.793982) (xy 96.826161 -138.763742) (xy 96.83573 -138.704022)
			(xy 96.844612 -138.67511) (xy 96.846342 -138.669372) (xy 96.847376 -138.657436) (xy 96.846644 -138.651488)
			(xy 96.844612 -138.639296) (xy 96.78924 -138.562842) (xy 96.781628 -138.553462) (xy 96.760152 -138.542473)
			(xy 96.748092 -138.54176) (xy 96.679766 -138.54176) (xy 96.672814 -138.541995) (xy 96.659418 -138.545726)
			(xy 96.65335 -138.549126) (xy 96.647508 -138.552682) (xy 96.63811 -138.562842) (xy 96.634808 -138.569446)
			(xy 96.621657 -138.594132) (xy 96.589228 -138.639702) (xy 96.550493 -138.68005) (xy 96.506283 -138.714311)
			(xy 96.457545 -138.741751) (xy 96.405324 -138.761783) (xy 96.350738 -138.773976) (xy 96.294956 -138.778069)
			(xy 96.239174 -138.773976) (xy 96.184588 -138.761783) (xy 96.132367 -138.741751) (xy 96.083629 -138.714311)
			(xy 96.039419 -138.68005) (xy 96.000684 -138.639702) (xy 95.968255 -138.594132) (xy 95.955104 -138.569446)
			(xy 95.955104 -138.569192) (xy 95.951714 -138.563089) (xy 95.94218 -138.5529) (xy 95.936308 -138.549126)
			(xy 95.930466 -138.54557) (xy 95.917258 -138.54176) (xy 90.48877 -138.54176) (xy 90.481658 -138.542268)
			(xy 90.474726 -138.543499) (xy 90.461842 -138.549157) (xy 90.456258 -138.553444) (xy 90.434931 -138.572714)
			(xy 90.387568 -138.605279) (xy 90.335857 -138.63037) (xy 90.280966 -138.64742) (xy 90.224139 -138.656042)
			(xy 90.166661 -138.656042) (xy 90.109834 -138.64742) (xy 90.054943 -138.63037) (xy 90.003232 -138.605279)
			(xy 89.955869 -138.572714) (xy 89.934542 -138.553444) (xy 89.928984 -138.549112) (xy 89.916091 -138.543438)
			(xy 89.909142 -138.542268) (xy 89.90203 -138.54176) (xy 85.619082 -138.54176) (xy 85.613071 -138.541923)
			(xy 85.601385 -138.544738) (xy 85.595968 -138.547348) (xy 85.592496 -138.54919) (xy 85.586121 -138.553788)
			(xy 85.583268 -138.556492) (xy 85.082126 -139.057634) (xy 85.074727 -139.064476) (xy 85.056128 -139.072194)
			(xy 85.046058 -139.07262) (xy 73.542652 -139.07262) (xy 73.530666 -139.073254) (xy 73.509297 -139.084112)
			(xy 73.501758 -139.093448) (xy 73.453244 -139.159488) (xy 73.446734 -139.169453) (xy 73.442764 -139.192892)
			(xy 73.445624 -139.204446) (xy 73.445624 -139.2047) (xy 73.453789 -139.232503) (xy 73.462589 -139.289774)
			(xy 73.46315 -139.318746) (xy 73.462664 -139.345997) (xy 73.454908 -139.399945) (xy 73.439553 -139.45224)
			(xy 73.416911 -139.501817) (xy 73.387445 -139.547667) (xy 73.351754 -139.588858) (xy 73.310563 -139.624549)
			(xy 73.264713 -139.654015) (xy 73.215136 -139.676657) (xy 73.162841 -139.692012) (xy 73.108893 -139.699768)
			(xy 73.054391 -139.699768) (xy 73.000443 -139.692012) (xy 72.948148 -139.676657) (xy 72.898571 -139.654015)
			(xy 72.852721 -139.624549) (xy 72.81153 -139.588858) (xy 72.775839 -139.547667) (xy 72.746373 -139.501817)
			(xy 72.723731 -139.45224) (xy 72.708376 -139.399945) (xy 72.70062 -139.345997) (xy 72.700134 -139.318746)
			(xy 72.700692 -139.289774) (xy 72.709493 -139.232503) (xy 72.71766 -139.2047) (xy 72.71766 -139.204446)
			(xy 72.720568 -139.192894) (xy 72.716586 -139.169441) (xy 72.71004 -139.159488) (xy 72.661526 -139.093448)
			(xy 72.653922 -139.084184) (xy 72.632596 -139.073316) (xy 72.620632 -139.07262) (xy 59.335162 -139.07262)
			(xy 59.329152 -139.072786) (xy 59.317469 -139.075608) (xy 59.312048 -139.078208) (xy 59.308575 -139.08005)
			(xy 59.3022 -139.084647) (xy 59.299348 -139.087352) (xy 58.748422 -139.638278) (xy 58.741585 -139.64568)
			(xy 58.733876 -139.664278) (xy 58.733436 -139.674346) (xy 58.733436 -139.80541) (xy 88.81186 -139.80541)
			(xy 88.815931 -139.749788) (xy 88.828057 -139.695351) (xy 88.84798 -139.64326) (xy 88.875276 -139.594625)
			(xy 88.909362 -139.550482) (xy 88.949511 -139.511773) (xy 88.994869 -139.479322) (xy 89.044469 -139.453821)
			(xy 89.097253 -139.435814) (xy 89.152096 -139.425684) (xy 89.20783 -139.423647) (xy 89.263267 -139.429747)
			(xy 89.317224 -139.443853) (xy 89.368553 -139.465665) (xy 89.416159 -139.494719) (xy 89.459027 -139.530394)
			(xy 89.496244 -139.571931) (xy 89.527017 -139.618444) (xy 89.550689 -139.668941) (xy 89.566757 -139.722348)
			(xy 89.574877 -139.777524) (xy 89.575386 -139.80541) (xy 89.574877 -139.833296) (xy 89.566757 -139.888472)
			(xy 89.550689 -139.941879) (xy 89.540482 -139.963652) (xy 92.346016 -139.963652) (xy 92.350087 -139.90803)
			(xy 92.362213 -139.853593) (xy 92.382136 -139.801502) (xy 92.409432 -139.752867) (xy 92.443518 -139.708724)
			(xy 92.483667 -139.670015) (xy 92.529025 -139.637564) (xy 92.578625 -139.612063) (xy 92.631409 -139.594056)
			(xy 92.686252 -139.583926) (xy 92.741986 -139.581889) (xy 92.797423 -139.587989) (xy 92.85138 -139.602095)
			(xy 92.902709 -139.623907) (xy 92.950315 -139.652961) (xy 92.993183 -139.688636) (xy 93.0304 -139.730173)
			(xy 93.061173 -139.776686) (xy 93.084845 -139.827183) (xy 93.100913 -139.88059) (xy 93.109033 -139.935766)
			(xy 93.109542 -139.963652) (xy 93.109033 -139.991538) (xy 93.100913 -140.046714) (xy 93.084845 -140.100121)
			(xy 93.061173 -140.150618) (xy 93.0304 -140.197131) (xy 92.993183 -140.238668) (xy 92.950315 -140.274343)
			(xy 92.902709 -140.303397) (xy 92.85138 -140.325209) (xy 92.797423 -140.339315) (xy 92.741986 -140.345415)
			(xy 92.686252 -140.343378) (xy 92.631409 -140.333248) (xy 92.578625 -140.315241) (xy 92.529025 -140.28974)
			(xy 92.483667 -140.257289) (xy 92.443518 -140.21858) (xy 92.409432 -140.174437) (xy 92.382136 -140.125802)
			(xy 92.362213 -140.073711) (xy 92.350087 -140.019274) (xy 92.346016 -139.963652) (xy 89.540482 -139.963652)
			(xy 89.527017 -139.992376) (xy 89.496244 -140.038889) (xy 89.459027 -140.080426) (xy 89.416159 -140.116101)
			(xy 89.368553 -140.145155) (xy 89.317224 -140.166967) (xy 89.263267 -140.181073) (xy 89.20783 -140.187173)
			(xy 89.152096 -140.185136) (xy 89.097253 -140.175006) (xy 89.044469 -140.156999) (xy 88.994869 -140.131498)
			(xy 88.949511 -140.099047) (xy 88.909362 -140.060338) (xy 88.875276 -140.016195) (xy 88.84798 -139.96756)
			(xy 88.828057 -139.915469) (xy 88.815931 -139.861032) (xy 88.81186 -139.80541) (xy 58.733436 -139.80541)
			(xy 58.733436 -140.471652) (xy 93.184726 -140.471652) (xy 93.185197 -140.444014) (xy 93.193157 -140.389315)
			(xy 93.208932 -140.336339) (xy 93.232191 -140.286196) (xy 93.262446 -140.239937) (xy 93.299065 -140.198531)
			(xy 93.319854 -140.180314) (xy 93.326953 -140.173735) (xy 93.335955 -140.156615) (xy 93.33738 -140.14704)
			(xy 93.345 -140.076936) (xy 93.345591 -140.067316) (xy 93.340348 -140.04878) (xy 93.33484 -140.040868)
			(xy 93.334586 -140.040614) (xy 93.31952 -140.020498) (xy 93.294254 -139.977053) (xy 93.274912 -139.930666)
			(xy 93.261828 -139.88214) (xy 93.25523 -139.832317) (xy 93.25483 -139.807188) (xy 93.255316 -139.779937)
			(xy 93.263072 -139.725989) (xy 93.278427 -139.673694) (xy 93.301069 -139.624117) (xy 93.330535 -139.578267)
			(xy 93.366226 -139.537076) (xy 93.407417 -139.501385) (xy 93.453267 -139.471919) (xy 93.502844 -139.449277)
			(xy 93.555139 -139.433922) (xy 93.609087 -139.426166) (xy 93.663589 -139.426166) (xy 93.717537 -139.433922)
			(xy 93.769832 -139.449277) (xy 93.819409 -139.471919) (xy 93.865259 -139.501385) (xy 93.90645 -139.537076)
			(xy 93.942141 -139.578267) (xy 93.971607 -139.624117) (xy 93.994249 -139.673694) (xy 94.009604 -139.725989)
			(xy 94.01736 -139.779937) (xy 94.017846 -139.807188) (xy 94.017377 -139.834825) (xy 94.009413 -139.889523)
			(xy 93.993637 -139.942498) (xy 93.970377 -139.992641) (xy 93.940122 -140.0389) (xy 93.903506 -140.080307)
			(xy 93.882718 -140.098526) (xy 93.875637 -140.105122) (xy 93.866625 -140.12223) (xy 93.865192 -140.1318)
			(xy 93.857572 -140.201904) (xy 93.857017 -140.211524) (xy 93.862236 -140.230057) (xy 93.867732 -140.237972)
			(xy 93.867986 -140.238226) (xy 93.883066 -140.258332) (xy 93.908331 -140.30178) (xy 93.927671 -140.348169)
			(xy 93.940751 -140.396697) (xy 93.947345 -140.446522) (xy 93.947742 -140.471652) (xy 93.947234 -140.49121)
			(xy 93.947234 -140.491464) (xy 93.94724 -140.50176) (xy 93.954454 -140.521027) (xy 93.961204 -140.528802)
			(xy 94.02699 -140.598144) (xy 94.02826 -140.598144) (xy 94.038984 -140.597721) (xy 94.058588 -140.589039)
			(xy 94.066106 -140.58138) (xy 94.086934 -140.558012) (xy 94.093396 -140.550199) (xy 94.100064 -140.531067)
			(xy 94.099888 -140.520928) (xy 94.099126 -140.497052) (xy 94.099612 -140.469801) (xy 94.107368 -140.415853)
			(xy 94.122723 -140.363558) (xy 94.145365 -140.313981) (xy 94.174831 -140.268131) (xy 94.210522 -140.22694)
			(xy 94.251713 -140.191249) (xy 94.297563 -140.161783) (xy 94.34714 -140.139141) (xy 94.399435 -140.123786)
			(xy 94.453383 -140.11603) (xy 94.507885 -140.11603) (xy 94.561833 -140.123786) (xy 94.614128 -140.139141)
			(xy 94.663705 -140.161783) (xy 94.709555 -140.191249) (xy 94.750746 -140.22694) (xy 94.786437 -140.268131)
			(xy 94.815903 -140.313981) (xy 94.838545 -140.363558) (xy 94.8539 -140.415853) (xy 94.861656 -140.469801)
			(xy 94.862142 -140.497052) (xy 94.861593 -140.525011) (xy 94.853464 -140.580336) (xy 94.837342 -140.63388)
			(xy 94.813575 -140.684495) (xy 94.78267 -140.731098) (xy 94.745292 -140.772688) (xy 94.702242 -140.808374)
			(xy 94.654441 -140.83739) (xy 94.602916 -140.859116) (xy 94.548771 -140.873084) (xy 94.52102 -140.876528)
			(xy 94.511622 -140.877544) (xy 94.495112 -140.885926) (xy 94.443296 -140.943838) (xy 94.437382 -140.951003)
			(xy 94.430741 -140.968338) (xy 94.430342 -140.97762) (xy 94.430342 -140.979652) (xy 94.429856 -141.006903)
			(xy 94.4221 -141.060851) (xy 94.406745 -141.113146) (xy 94.384103 -141.162723) (xy 94.354637 -141.208573)
			(xy 94.318946 -141.249764) (xy 94.277755 -141.285455) (xy 94.231905 -141.314921) (xy 94.182328 -141.337563)
			(xy 94.130033 -141.352918) (xy 94.076085 -141.360674) (xy 94.021583 -141.360674) (xy 93.967635 -141.352918)
			(xy 93.91534 -141.337563) (xy 93.865763 -141.314921) (xy 93.819913 -141.285455) (xy 93.778722 -141.249764)
			(xy 93.743031 -141.208573) (xy 93.713565 -141.162723) (xy 93.690923 -141.113146) (xy 93.675568 -141.060851)
			(xy 93.667812 -141.006903) (xy 93.667326 -140.979652) (xy 93.667834 -140.960094) (xy 93.667834 -140.95984)
			(xy 93.667834 -140.949543) (xy 93.660617 -140.930276) (xy 93.653864 -140.922502) (xy 93.603064 -140.868908)
			(xy 93.595577 -140.861767) (xy 93.576569 -140.853642) (xy 93.566234 -140.85316) (xy 93.53898 -140.852713)
			(xy 93.485026 -140.844959) (xy 93.432725 -140.829605) (xy 93.383142 -140.806963) (xy 93.337286 -140.777494)
			(xy 93.296092 -140.741799) (xy 93.260397 -140.700603) (xy 93.23093 -140.654746) (xy 93.20829 -140.605162)
			(xy 93.192938 -140.552861) (xy 93.185186 -140.498906) (xy 93.184726 -140.471652) (xy 58.733436 -140.471652)
			(xy 58.733436 -141.261592) (xy 81.648552 -141.261592) (xy 81.652623 -141.20597) (xy 81.664749 -141.151533)
			(xy 81.684672 -141.099442) (xy 81.711968 -141.050807) (xy 81.746054 -141.006664) (xy 81.786203 -140.967955)
			(xy 81.831561 -140.935504) (xy 81.881161 -140.910003) (xy 81.933945 -140.891996) (xy 81.988788 -140.881866)
			(xy 82.044522 -140.879829) (xy 82.099959 -140.885929) (xy 82.153916 -140.900035) (xy 82.205245 -140.921847)
			(xy 82.252851 -140.950901) (xy 82.295719 -140.986576) (xy 82.332936 -141.028113) (xy 82.363709 -141.074626)
			(xy 82.387381 -141.125123) (xy 82.403449 -141.17853) (xy 82.411569 -141.233706) (xy 82.412078 -141.261592)
			(xy 82.411569 -141.289478) (xy 82.403449 -141.344654) (xy 82.387381 -141.398061) (xy 82.363709 -141.448558)
			(xy 82.332936 -141.495071) (xy 82.295719 -141.536608) (xy 82.252851 -141.572283) (xy 82.205245 -141.601337)
			(xy 82.153916 -141.623149) (xy 82.099959 -141.637255) (xy 82.044522 -141.643355) (xy 81.988788 -141.641318)
			(xy 81.933945 -141.631188) (xy 81.881161 -141.613181) (xy 81.831561 -141.58768) (xy 81.786203 -141.555229)
			(xy 81.746054 -141.51652) (xy 81.711968 -141.472377) (xy 81.684672 -141.423742) (xy 81.664749 -141.371651)
			(xy 81.652623 -141.317214) (xy 81.648552 -141.261592) (xy 58.733436 -141.261592) (xy 58.733436 -143.354552)
			(xy 87.380316 -143.354552) (xy 87.384387 -143.29893) (xy 87.396513 -143.244493) (xy 87.416436 -143.192402)
			(xy 87.443732 -143.143767) (xy 87.477818 -143.099624) (xy 87.517967 -143.060915) (xy 87.563325 -143.028464)
			(xy 87.612925 -143.002963) (xy 87.665709 -142.984956) (xy 87.720552 -142.974826) (xy 87.776286 -142.972789)
			(xy 87.831723 -142.978889) (xy 87.88568 -142.992995) (xy 87.937009 -143.014807) (xy 87.984615 -143.043861)
			(xy 88.027483 -143.079536) (xy 88.0647 -143.121073) (xy 88.095473 -143.167586) (xy 88.119145 -143.218083)
			(xy 88.135213 -143.27149) (xy 88.143333 -143.326666) (xy 88.143842 -143.354552) (xy 88.143333 -143.382438)
			(xy 88.135213 -143.437614) (xy 88.119145 -143.491021) (xy 88.095473 -143.541518) (xy 88.0647 -143.588031)
			(xy 88.027483 -143.629568) (xy 87.984615 -143.665243) (xy 87.937009 -143.694297) (xy 87.88568 -143.716109)
			(xy 87.831723 -143.730215) (xy 87.776286 -143.736315) (xy 87.720552 -143.734278) (xy 87.665709 -143.724148)
			(xy 87.612925 -143.706141) (xy 87.563325 -143.68064) (xy 87.517967 -143.648189) (xy 87.477818 -143.60948)
			(xy 87.443732 -143.565337) (xy 87.416436 -143.516702) (xy 87.396513 -143.464611) (xy 87.384387 -143.410174)
			(xy 87.380316 -143.354552) (xy 58.733436 -143.354552) (xy 58.733436 -143.785844) (xy 82.07832 -143.785844)
			(xy 82.082391 -143.730222) (xy 82.094517 -143.675785) (xy 82.11444 -143.623694) (xy 82.141736 -143.575059)
			(xy 82.175822 -143.530916) (xy 82.215971 -143.492207) (xy 82.261329 -143.459756) (xy 82.310929 -143.434255)
			(xy 82.363713 -143.416248) (xy 82.418556 -143.406118) (xy 82.47429 -143.404081) (xy 82.529727 -143.410181)
			(xy 82.583684 -143.424287) (xy 82.635013 -143.446099) (xy 82.682619 -143.475153) (xy 82.725487 -143.510828)
			(xy 82.762704 -143.552365) (xy 82.793477 -143.598878) (xy 82.817149 -143.649375) (xy 82.833217 -143.702782)
			(xy 82.841337 -143.757958) (xy 82.841846 -143.785844) (xy 82.841337 -143.81373) (xy 82.833217 -143.868906)
			(xy 82.817149 -143.922313) (xy 82.793477 -143.97281) (xy 82.762704 -144.019323) (xy 82.725487 -144.06086)
			(xy 82.682619 -144.096535) (xy 82.635013 -144.125589) (xy 82.583684 -144.147401) (xy 82.529727 -144.161507)
			(xy 82.47429 -144.167607) (xy 82.418556 -144.16557) (xy 82.363713 -144.15544) (xy 82.310929 -144.137433)
			(xy 82.261329 -144.111932) (xy 82.215971 -144.079481) (xy 82.175822 -144.040772) (xy 82.141736 -143.996629)
			(xy 82.11444 -143.947994) (xy 82.094517 -143.895903) (xy 82.082391 -143.841466) (xy 82.07832 -143.785844)
			(xy 58.733436 -143.785844) (xy 58.733436 -145.973292) (xy 69.238366 -145.973292) (xy 69.242437 -145.91767)
			(xy 69.254563 -145.863233) (xy 69.274486 -145.811142) (xy 69.301782 -145.762507) (xy 69.335868 -145.718364)
			(xy 69.376017 -145.679655) (xy 69.421375 -145.647204) (xy 69.470975 -145.621703) (xy 69.523759 -145.603696)
			(xy 69.578602 -145.593566) (xy 69.634336 -145.591529) (xy 69.689773 -145.597629) (xy 69.74373 -145.611735)
			(xy 69.795059 -145.633547) (xy 69.842665 -145.662601) (xy 69.885533 -145.698276) (xy 69.92275 -145.739813)
			(xy 69.953523 -145.786326) (xy 69.977195 -145.836823) (xy 69.993263 -145.89023) (xy 70.001383 -145.945406)
			(xy 70.001892 -145.973292) (xy 70.001383 -146.001178) (xy 69.993263 -146.056354) (xy 69.987686 -146.074892)
			(xy 73.130916 -146.074892) (xy 73.134987 -146.01927) (xy 73.147113 -145.964833) (xy 73.167036 -145.912742)
			(xy 73.194332 -145.864107) (xy 73.228418 -145.819964) (xy 73.268567 -145.781255) (xy 73.313925 -145.748804)
			(xy 73.363525 -145.723303) (xy 73.416309 -145.705296) (xy 73.471152 -145.695166) (xy 73.526886 -145.693129)
			(xy 73.582323 -145.699229) (xy 73.63628 -145.713335) (xy 73.687609 -145.735147) (xy 73.735215 -145.764201)
			(xy 73.778083 -145.799876) (xy 73.8153 -145.841413) (xy 73.846073 -145.887926) (xy 73.869745 -145.938423)
			(xy 73.885813 -145.99183) (xy 73.893933 -146.047006) (xy 73.894442 -146.074892) (xy 73.893933 -146.102778)
			(xy 73.885813 -146.157954) (xy 73.869745 -146.211361) (xy 73.846073 -146.261858) (xy 73.8153 -146.308371)
			(xy 73.778083 -146.349908) (xy 73.735215 -146.385583) (xy 73.687609 -146.414637) (xy 73.63628 -146.436449)
			(xy 73.582323 -146.450555) (xy 73.526886 -146.456655) (xy 73.471152 -146.454618) (xy 73.416309 -146.444488)
			(xy 73.363525 -146.426481) (xy 73.313925 -146.40098) (xy 73.268567 -146.368529) (xy 73.228418 -146.32982)
			(xy 73.194332 -146.285677) (xy 73.167036 -146.237042) (xy 73.147113 -146.184951) (xy 73.134987 -146.130514)
			(xy 73.130916 -146.074892) (xy 69.987686 -146.074892) (xy 69.977195 -146.109761) (xy 69.953523 -146.160258)
			(xy 69.92275 -146.206771) (xy 69.885533 -146.248308) (xy 69.842665 -146.283983) (xy 69.795059 -146.313037)
			(xy 69.74373 -146.334849) (xy 69.689773 -146.348955) (xy 69.634336 -146.355055) (xy 69.578602 -146.353018)
			(xy 69.523759 -146.342888) (xy 69.470975 -146.324881) (xy 69.421375 -146.29938) (xy 69.376017 -146.266929)
			(xy 69.335868 -146.22822) (xy 69.301782 -146.184077) (xy 69.274486 -146.135442) (xy 69.254563 -146.083351)
			(xy 69.242437 -146.028914) (xy 69.238366 -145.973292) (xy 58.733436 -145.973292) (xy 58.733436 -146.605752)
			(xy 74.369928 -146.605752) (xy 74.373999 -146.55013) (xy 74.386125 -146.495693) (xy 74.406048 -146.443602)
			(xy 74.433344 -146.394967) (xy 74.46743 -146.350824) (xy 74.507579 -146.312115) (xy 74.552937 -146.279664)
			(xy 74.602537 -146.254163) (xy 74.655321 -146.236156) (xy 74.710164 -146.226026) (xy 74.765898 -146.223989)
			(xy 74.821335 -146.230089) (xy 74.875292 -146.244195) (xy 74.926621 -146.266007) (xy 74.974227 -146.295061)
			(xy 75.017095 -146.330736) (xy 75.054312 -146.372273) (xy 75.085085 -146.418786) (xy 75.108757 -146.469283)
			(xy 75.124825 -146.52269) (xy 75.132945 -146.577866) (xy 75.133454 -146.605752) (xy 75.132945 -146.633638)
			(xy 75.124825 -146.688814) (xy 75.108757 -146.742221) (xy 75.085085 -146.792718) (xy 75.054312 -146.839231)
			(xy 75.017095 -146.880768) (xy 74.974227 -146.916443) (xy 74.926621 -146.945497) (xy 74.875292 -146.967309)
			(xy 74.821335 -146.981415) (xy 74.765898 -146.987515) (xy 74.710164 -146.985478) (xy 74.655321 -146.975348)
			(xy 74.602537 -146.957341) (xy 74.552937 -146.93184) (xy 74.507579 -146.899389) (xy 74.46743 -146.86068)
			(xy 74.433344 -146.816537) (xy 74.406048 -146.767902) (xy 74.386125 -146.715811) (xy 74.373999 -146.661374)
			(xy 74.369928 -146.605752) (xy 58.733436 -146.605752) (xy 58.733436 -147.444751) (xy 75.263991 -147.444751)
			(xy 75.263991 -147.390249) (xy 75.271748 -147.336303) (xy 75.287103 -147.284009) (xy 75.309744 -147.234433)
			(xy 75.33921 -147.188583) (xy 75.374901 -147.147394) (xy 75.416091 -147.111704) (xy 75.461942 -147.082239)
			(xy 75.511518 -147.059599) (xy 75.563812 -147.044246) (xy 75.617759 -147.036491) (xy 75.64501 -147.036028)
			(xy 75.677943 -147.03676) (xy 75.742822 -147.048126) (xy 75.774042 -147.058634) (xy 75.782424 -147.061428)
			(xy 80.62849 -147.061428) (xy 80.638561 -147.061016) (xy 80.65716 -147.053288) (xy 80.664558 -147.046442)
			(xy 83.103212 -144.608042) (xy 83.123358 -144.588622) (xy 83.168626 -144.55573) (xy 83.218477 -144.530315)
			(xy 83.271687 -144.513002) (xy 83.326949 -144.504216) (xy 83.354926 -144.503648) (xy 86.086696 -144.503648)
			(xy 86.09674 -144.503264) (xy 86.115337 -144.495686) (xy 86.122764 -144.488916) (xy 86.327234 -144.284446)
			(xy 86.347415 -144.265064) (xy 86.392673 -144.232167) (xy 86.442516 -144.206745) (xy 86.495718 -144.189423)
			(xy 86.550973 -144.180626) (xy 86.578948 -144.180052) (xy 88.285828 -144.180052) (xy 88.313808 -144.18061)
			(xy 88.369077 -144.189374) (xy 88.422293 -144.206681) (xy 88.472143 -144.232105) (xy 88.5174 -144.265018)
			(xy 88.537542 -144.284446) (xy 88.767666 -144.51457) (xy 88.775087 -144.521383) (xy 88.79367 -144.529119)
			(xy 88.803734 -144.529556) (xy 89.056464 -144.529556) (xy 89.064846 -144.526508) (xy 89.096058 -144.515972)
			(xy 89.160943 -144.504611) (xy 89.193878 -144.503902) (xy 89.222986 -144.504492) (xy 89.280514 -144.513425)
			(xy 89.308432 -144.521682) (xy 89.30894 -144.521682) (xy 89.332816 -144.529048) (xy 89.339928 -144.529048)
			(xy 89.443052 -144.425924) (xy 89.449397 -144.418964) (xy 89.456968 -144.401735) (xy 89.457804 -144.382935)
			(xy 89.451792 -144.365103) (xy 89.4461 -144.357598) (xy 89.439242 -144.349216) (xy 89.431269 -144.34065)
			(xy 89.409919 -144.331139) (xy 89.386563 -144.332002) (xy 89.375996 -144.337024) (xy 89.347879 -144.351594)
			(xy 89.287998 -144.372192) (xy 89.22554 -144.382632) (xy 89.193878 -144.383252) (xy 89.166628 -144.382743)
			(xy 89.112684 -144.374984) (xy 89.060392 -144.359629) (xy 89.010818 -144.336988) (xy 88.964969 -144.307524)
			(xy 88.923781 -144.271835) (xy 88.888089 -144.230648) (xy 88.858622 -144.184802) (xy 88.835979 -144.135229)
			(xy 88.82062 -144.082938) (xy 88.812859 -144.028994) (xy 88.81237 -144.001744) (xy 88.812875 -143.972379)
			(xy 88.821808 -143.914334) (xy 88.83015 -143.886174) (xy 88.83396 -143.874744) (xy 88.83015 -143.851122)
			(xy 88.776302 -143.775176) (xy 88.768972 -143.765925) (xy 88.748188 -143.754799) (xy 88.736424 -143.75384)
			(xy 88.73617 -143.75384) (xy 88.709422 -143.752733) (xy 88.656639 -143.743785) (xy 88.605625 -143.727542)
			(xy 88.557385 -143.704324) (xy 88.512866 -143.674588) (xy 88.472943 -143.638918) (xy 88.438402 -143.598015)
			(xy 88.40992 -143.552684) (xy 88.388058 -143.503814) (xy 88.373246 -143.452367) (xy 88.365774 -143.399354)
			(xy 88.36533 -143.372586) (xy 88.365816 -143.345335) (xy 88.373572 -143.291387) (xy 88.388927 -143.239092)
			(xy 88.411569 -143.189515) (xy 88.441035 -143.143665) (xy 88.476726 -143.102474) (xy 88.517917 -143.066783)
			(xy 88.563767 -143.037317) (xy 88.613344 -143.014675) (xy 88.665639 -142.99932) (xy 88.719587 -142.991564)
			(xy 88.774089 -142.991564) (xy 88.828037 -142.99932) (xy 88.880332 -143.014675) (xy 88.929909 -143.037317)
			(xy 88.975759 -143.066783) (xy 89.01695 -143.102474) (xy 89.052641 -143.143665) (xy 89.082107 -143.189515)
			(xy 89.104749 -143.239092) (xy 89.120104 -143.291387) (xy 89.12786 -143.345335) (xy 89.128346 -143.372586)
			(xy 89.127829 -143.40195) (xy 89.118904 -143.459996) (xy 89.110566 -143.488156) (xy 89.106756 -143.499586)
			(xy 89.110566 -143.523208) (xy 89.164414 -143.599154) (xy 89.171731 -143.608418) (xy 89.192525 -143.619535)
			(xy 89.204292 -143.62049) (xy 89.204546 -143.62049) (xy 89.231388 -143.621687) (xy 89.284361 -143.630675)
			(xy 89.335543 -143.647024) (xy 89.383917 -143.670411) (xy 89.406476 -143.685006) (xy 89.41816 -143.692626)
			(xy 89.445846 -143.69415) (xy 89.53754 -143.645128) (xy 89.54545 -143.640473) (xy 89.557598 -143.626741)
			(xy 89.56408 -143.609592) (xy 89.564464 -143.600424) (xy 89.564464 -141.838934) (xy 89.56403 -141.828866)
			(xy 89.556316 -141.810267) (xy 89.549478 -141.802866) (xy 89.067894 -141.321028) (xy 89.063438 -141.316758)
			(xy 89.052901 -141.310338) (xy 89.047066 -141.308328) (xy 89.046812 -141.308328) (xy 89.021133 -141.299964)
			(xy 88.972242 -141.277026) (xy 88.927075 -141.247421) (xy 88.886535 -141.211742) (xy 88.851433 -141.170701)
			(xy 88.82247 -141.125119) (xy 88.800227 -141.075908) (xy 88.785147 -141.024052) (xy 88.777532 -140.970586)
			(xy 88.777064 -140.943584) (xy 88.777563 -140.916334) (xy 88.785321 -140.862388) (xy 88.800677 -140.810095)
			(xy 88.823317 -140.76052) (xy 88.852783 -140.714671) (xy 88.888473 -140.673481) (xy 88.929661 -140.63779)
			(xy 88.975509 -140.608323) (xy 89.025084 -140.585681) (xy 89.077376 -140.570323) (xy 89.131322 -140.562564)
			(xy 89.158572 -140.562076) (xy 89.185186 -140.562494) (xy 89.237896 -140.569896) (xy 89.289064 -140.58456)
			(xy 89.337693 -140.6062) (xy 89.382839 -140.634395) (xy 89.423623 -140.668598) (xy 89.441782 -140.68806)
			(xy 89.443814 -140.690092) (xy 89.445592 -140.69187) (xy 90.172286 -141.418564) (xy 90.173994 -141.420342)
			(xy 92.08592 -141.420342) (xy 92.089991 -141.36472) (xy 92.102117 -141.310283) (xy 92.12204 -141.258192)
			(xy 92.149336 -141.209557) (xy 92.183422 -141.165414) (xy 92.223571 -141.126705) (xy 92.268929 -141.094254)
			(xy 92.318529 -141.068753) (xy 92.371313 -141.050746) (xy 92.426156 -141.040616) (xy 92.48189 -141.038579)
			(xy 92.537327 -141.044679) (xy 92.591284 -141.058785) (xy 92.642613 -141.080597) (xy 92.690219 -141.109651)
			(xy 92.733087 -141.145326) (xy 92.770304 -141.186863) (xy 92.801077 -141.233376) (xy 92.824749 -141.283873)
			(xy 92.840817 -141.33728) (xy 92.848937 -141.392456) (xy 92.849446 -141.420342) (xy 92.848937 -141.448228)
			(xy 92.840817 -141.503404) (xy 92.824749 -141.556811) (xy 92.801077 -141.607308) (xy 92.770304 -141.653821)
			(xy 92.733087 -141.695358) (xy 92.690219 -141.731033) (xy 92.642613 -141.760087) (xy 92.591284 -141.781899)
			(xy 92.537327 -141.796005) (xy 92.48189 -141.802105) (xy 92.426156 -141.800068) (xy 92.371313 -141.789938)
			(xy 92.318529 -141.771931) (xy 92.268929 -141.74643) (xy 92.223571 -141.713979) (xy 92.183422 -141.67527)
			(xy 92.149336 -141.631127) (xy 92.12204 -141.582492) (xy 92.102117 -141.530401) (xy 92.089991 -141.475964)
			(xy 92.08592 -141.420342) (xy 90.173994 -141.420342) (xy 90.191671 -141.438743) (xy 90.22457 -141.484)
			(xy 90.249993 -141.533843) (xy 90.267314 -141.587046) (xy 90.276108 -141.642303) (xy 90.27668 -141.670278)
			(xy 90.27668 -142.505176) (xy 91.124276 -142.505176) (xy 91.128347 -142.449554) (xy 91.140473 -142.395117)
			(xy 91.160396 -142.343026) (xy 91.187692 -142.294391) (xy 91.221778 -142.250248) (xy 91.261927 -142.211539)
			(xy 91.307285 -142.179088) (xy 91.356885 -142.153587) (xy 91.409669 -142.13558) (xy 91.464512 -142.12545)
			(xy 91.520246 -142.123413) (xy 91.575683 -142.129513) (xy 91.62964 -142.143619) (xy 91.680969 -142.165431)
			(xy 91.728575 -142.194485) (xy 91.771443 -142.23016) (xy 91.80866 -142.271697) (xy 91.839433 -142.31821)
			(xy 91.863105 -142.368707) (xy 91.879173 -142.422114) (xy 91.887293 -142.47729) (xy 91.887802 -142.505176)
			(xy 91.887293 -142.533062) (xy 91.879173 -142.588238) (xy 91.863105 -142.641645) (xy 91.839433 -142.692142)
			(xy 91.80866 -142.738655) (xy 91.771443 -142.780192) (xy 91.728575 -142.815867) (xy 91.680969 -142.844921)
			(xy 91.62964 -142.866733) (xy 91.575683 -142.880839) (xy 91.520246 -142.886939) (xy 91.464512 -142.884902)
			(xy 91.409669 -142.874772) (xy 91.356885 -142.856765) (xy 91.307285 -142.831264) (xy 91.261927 -142.798813)
			(xy 91.221778 -142.760104) (xy 91.187692 -142.715961) (xy 91.160396 -142.667326) (xy 91.140473 -142.615235)
			(xy 91.128347 -142.560798) (xy 91.124276 -142.505176) (xy 90.27668 -142.505176) (xy 90.27668 -144.042754)
			(xy 90.855738 -144.042754) (xy 90.855738 -143.988246) (xy 90.863495 -143.934293) (xy 90.878852 -143.881992)
			(xy 90.901495 -143.83241) (xy 90.930965 -143.786555) (xy 90.96666 -143.74536) (xy 91.007855 -143.709665)
			(xy 91.05371 -143.680195) (xy 91.103292 -143.657552) (xy 91.155593 -143.642195) (xy 91.209546 -143.634438)
			(xy 91.2368 -143.633952) (xy 91.26329 -143.634388) (xy 91.315759 -143.641738) (xy 91.366705 -143.65628)
			(xy 91.415147 -143.677737) (xy 91.460151 -143.705694) (xy 91.500851 -143.739612) (xy 91.518994 -143.75892)
			(xy 91.52822 -143.768469) (xy 91.550551 -143.782819) (xy 91.575827 -143.790926) (xy 91.602338 -143.792242)
			(xy 91.628293 -143.786678) (xy 91.651935 -143.77461) (xy 91.671666 -143.756854) (xy 91.679268 -143.745966)
			(xy 91.694495 -143.723592) (xy 91.730189 -143.682913) (xy 91.771271 -143.647684) (xy 91.816917 -143.618611)
			(xy 91.866212 -143.596277) (xy 91.918167 -143.581129) (xy 91.971741 -143.573471) (xy 91.9988 -143.572992)
			(xy 92.026051 -143.573478) (xy 92.079999 -143.581234) (xy 92.132294 -143.596589) (xy 92.181871 -143.619231)
			(xy 92.227721 -143.648697) (xy 92.268912 -143.684388) (xy 92.304603 -143.725579) (xy 92.334069 -143.771429)
			(xy 92.356711 -143.821006) (xy 92.372066 -143.873301) (xy 92.379822 -143.927249) (xy 92.379822 -143.981751)
			(xy 92.372066 -144.035699) (xy 92.356711 -144.087994) (xy 92.334069 -144.137571) (xy 92.304603 -144.183421)
			(xy 92.268912 -144.224612) (xy 92.227721 -144.260303) (xy 92.181871 -144.289769) (xy 92.132294 -144.312411)
			(xy 92.079999 -144.327766) (xy 92.026051 -144.335522) (xy 91.9988 -144.336008) (xy 91.972309 -144.335585)
			(xy 91.919839 -144.328235) (xy 91.868893 -144.31369) (xy 91.820451 -144.292231) (xy 91.775447 -144.264272)
			(xy 91.734748 -144.23035) (xy 91.716606 -144.21104) (xy 91.705788 -144.199934) (xy 91.679009 -144.184333)
			(xy 91.648787 -144.177468) (xy 91.617896 -144.179968) (xy 91.589172 -144.191605) (xy 91.565251 -144.21131)
			(xy 91.556332 -144.223994) (xy 91.541125 -144.246382) (xy 91.505425 -144.287057) (xy 91.464339 -144.322283)
			(xy 91.418689 -144.351353) (xy 91.369392 -144.373686) (xy 91.317435 -144.388832) (xy 91.26386 -144.396489)
			(xy 91.2368 -144.396968) (xy 91.209546 -144.396562) (xy 91.155593 -144.388805) (xy 91.103292 -144.373448)
			(xy 91.05371 -144.350805) (xy 91.007855 -144.321335) (xy 90.96666 -144.28564) (xy 90.930965 -144.244445)
			(xy 90.901495 -144.19859) (xy 90.878852 -144.149008) (xy 90.863495 -144.096707) (xy 90.855738 -144.042754)
			(xy 90.27668 -144.042754) (xy 90.27668 -144.451832) (xy 90.276115 -144.479811) (xy 90.267352 -144.53508)
			(xy 90.250046 -144.588295) (xy 90.224624 -144.638146) (xy 90.191712 -144.683403) (xy 90.172286 -144.703546)
			(xy 89.917524 -144.958308) (xy 90.97086 -144.958308) (xy 90.974931 -144.902686) (xy 90.987057 -144.848249)
			(xy 91.00698 -144.796158) (xy 91.034276 -144.747523) (xy 91.068362 -144.70338) (xy 91.108511 -144.664671)
			(xy 91.153869 -144.63222) (xy 91.203469 -144.606719) (xy 91.256253 -144.588712) (xy 91.311096 -144.578582)
			(xy 91.36683 -144.576545) (xy 91.422267 -144.582645) (xy 91.476224 -144.596751) (xy 91.527553 -144.618563)
			(xy 91.575159 -144.647617) (xy 91.618027 -144.683292) (xy 91.655244 -144.724829) (xy 91.686017 -144.771342)
			(xy 91.709689 -144.821839) (xy 91.725757 -144.875246) (xy 91.733877 -144.930422) (xy 91.734386 -144.958308)
			(xy 91.733877 -144.986194) (xy 91.725757 -145.04137) (xy 91.709689 -145.094777) (xy 91.686017 -145.145274)
			(xy 91.655244 -145.191787) (xy 91.618027 -145.233324) (xy 91.575159 -145.268999) (xy 91.527553 -145.298053)
			(xy 91.476224 -145.319865) (xy 91.422267 -145.333971) (xy 91.36683 -145.340071) (xy 91.311096 -145.338034)
			(xy 91.256253 -145.327904) (xy 91.203469 -145.309897) (xy 91.153869 -145.284396) (xy 91.108511 -145.251945)
			(xy 91.068362 -145.213236) (xy 91.034276 -145.169093) (xy 91.00698 -145.120458) (xy 90.987057 -145.068367)
			(xy 90.974931 -145.01393) (xy 90.97086 -144.958308) (xy 89.917524 -144.958308) (xy 89.749122 -145.12671)
			(xy 89.747852 -145.128234) (xy 89.727474 -145.149271) (xy 89.681092 -145.185027) (xy 89.629489 -145.212722)
			(xy 89.574054 -145.231609) (xy 89.516276 -145.241181) (xy 89.486994 -145.241772) (xy 89.330276 -145.241772)
			(xy 89.32291 -145.244312) (xy 89.291694 -145.254836) (xy 89.226813 -145.266204) (xy 89.193878 -145.266918)
			(xy 89.160945 -145.266187) (xy 89.096066 -145.25482) (xy 89.064846 -145.244312) (xy 89.056464 -145.241264)
			(xy 88.634824 -145.241264) (xy 88.606884 -145.240682) (xy 88.551692 -145.231927) (xy 88.498545 -145.214659)
			(xy 88.448748 -145.189303) (xy 88.403522 -145.15648) (xy 88.383364 -145.137124) (xy 88.15324 -144.907254)
			(xy 88.145787 -144.900491) (xy 88.127223 -144.892772) (xy 88.117172 -144.892268) (xy 86.747604 -144.892268)
			(xy 86.737559 -144.892647) (xy 86.718962 -144.900228) (xy 86.711536 -144.907) (xy 86.507066 -145.11147)
			(xy 86.486888 -145.130855) (xy 86.441628 -145.163751) (xy 86.391785 -145.189172) (xy 86.338583 -145.206493)
			(xy 86.283327 -145.21529) (xy 86.255352 -145.215864) (xy 83.523582 -145.215864) (xy 83.513509 -145.216263)
			(xy 83.494911 -145.224) (xy 83.487514 -145.23085) (xy 82.768039 -145.95025) (xy 85.577678 -145.95025)
			(xy 85.577678 -145.89575) (xy 85.585434 -145.841804) (xy 85.600788 -145.789511) (xy 85.623428 -145.739935)
			(xy 85.652892 -145.694085) (xy 85.688581 -145.652895) (xy 85.729769 -145.617204) (xy 85.775617 -145.587737)
			(xy 85.825192 -145.565095) (xy 85.877484 -145.549738) (xy 85.93143 -145.541979) (xy 85.95868 -145.541492)
			(xy 85.984408 -145.541906) (xy 86.035397 -145.548825) (xy 86.084992 -145.56254) (xy 86.132291 -145.582801)
			(xy 86.176435 -145.609241) (xy 86.216621 -145.641379) (xy 86.252119 -145.67863) (xy 86.267544 -145.699226)
			(xy 86.275964 -145.710071) (xy 86.297411 -145.727195) (xy 86.322644 -145.737991) (xy 86.34984 -145.741678)
			(xy 86.377036 -145.737991) (xy 86.402269 -145.727195) (xy 86.423716 -145.710071) (xy 86.432136 -145.699226)
			(xy 86.44755 -145.678622) (xy 86.483053 -145.641377) (xy 86.523243 -145.609244) (xy 86.567389 -145.582808)
			(xy 86.614689 -145.562548) (xy 86.664283 -145.548834) (xy 86.715272 -145.541914) (xy 86.741 -145.541492)
			(xy 86.768251 -145.541978) (xy 86.822199 -145.549734) (xy 86.874494 -145.565089) (xy 86.924071 -145.587731)
			(xy 86.969921 -145.617197) (xy 87.011112 -145.652888) (xy 87.046803 -145.694079) (xy 87.076269 -145.739929)
			(xy 87.098911 -145.789506) (xy 87.114266 -145.841801) (xy 87.122022 -145.895749) (xy 87.122022 -145.90141)
			(xy 90.84386 -145.90141) (xy 90.847931 -145.845788) (xy 90.860057 -145.791351) (xy 90.87998 -145.73926)
			(xy 90.907276 -145.690625) (xy 90.941362 -145.646482) (xy 90.981511 -145.607773) (xy 91.026869 -145.575322)
			(xy 91.076469 -145.549821) (xy 91.129253 -145.531814) (xy 91.184096 -145.521684) (xy 91.23983 -145.519647)
			(xy 91.295267 -145.525747) (xy 91.349224 -145.539853) (xy 91.400553 -145.561665) (xy 91.448159 -145.590719)
			(xy 91.491027 -145.626394) (xy 91.528244 -145.667931) (xy 91.559017 -145.714444) (xy 91.582689 -145.764941)
			(xy 91.598757 -145.818348) (xy 91.606877 -145.873524) (xy 91.607386 -145.90141) (xy 91.606877 -145.929296)
			(xy 91.598757 -145.984472) (xy 91.582689 -146.037879) (xy 91.559017 -146.088376) (xy 91.528244 -146.134889)
			(xy 91.491027 -146.176426) (xy 91.448159 -146.212101) (xy 91.400553 -146.241155) (xy 91.349224 -146.262967)
			(xy 91.295267 -146.277073) (xy 91.23983 -146.283173) (xy 91.184096 -146.281136) (xy 91.129253 -146.271006)
			(xy 91.076469 -146.252999) (xy 91.026869 -146.227498) (xy 90.981511 -146.195047) (xy 90.941362 -146.156338)
			(xy 90.907276 -146.112195) (xy 90.87998 -146.06356) (xy 90.860057 -146.011469) (xy 90.847931 -145.957032)
			(xy 90.84386 -145.90141) (xy 87.122022 -145.90141) (xy 87.122022 -145.950251) (xy 87.114266 -146.004199)
			(xy 87.098911 -146.056494) (xy 87.076269 -146.106071) (xy 87.046803 -146.151921) (xy 87.011112 -146.193112)
			(xy 86.969921 -146.228803) (xy 86.924071 -146.258269) (xy 86.874494 -146.280911) (xy 86.822199 -146.296266)
			(xy 86.768251 -146.304022) (xy 86.741 -146.304508) (xy 86.715271 -146.304109) (xy 86.664282 -146.297187)
			(xy 86.614686 -146.28347) (xy 86.567387 -146.263206) (xy 86.523243 -146.236764) (xy 86.483058 -146.204624)
			(xy 86.44756 -146.167371) (xy 86.432136 -146.146774) (xy 86.423716 -146.135929) (xy 86.402269 -146.118805)
			(xy 86.377036 -146.108009) (xy 86.34984 -146.104322) (xy 86.322644 -146.108009) (xy 86.297411 -146.118805)
			(xy 86.275964 -146.135929) (xy 86.267544 -146.146774) (xy 86.252142 -146.167387) (xy 86.216637 -146.204632)
			(xy 86.176445 -146.236765) (xy 86.132297 -146.2632) (xy 86.084995 -146.283457) (xy 86.035399 -146.297169)
			(xy 85.984409 -146.304087) (xy 85.95868 -146.304508) (xy 85.93143 -146.304021) (xy 85.877484 -146.296262)
			(xy 85.825192 -146.280905) (xy 85.775617 -146.258263) (xy 85.729769 -146.228796) (xy 85.688581 -146.193105)
			(xy 85.652892 -146.151915) (xy 85.623428 -146.106065) (xy 85.600788 -146.056489) (xy 85.585434 -146.004196)
			(xy 85.577678 -145.95025) (xy 82.768039 -145.95025) (xy 81.779186 -146.939) (xy 86.612982 -146.939)
			(xy 86.617053 -146.883378) (xy 86.629179 -146.828941) (xy 86.649102 -146.77685) (xy 86.676398 -146.728215)
			(xy 86.710484 -146.684072) (xy 86.750633 -146.645363) (xy 86.795991 -146.612912) (xy 86.845591 -146.587411)
			(xy 86.898375 -146.569404) (xy 86.953218 -146.559274) (xy 87.008952 -146.557237) (xy 87.064389 -146.563337)
			(xy 87.118346 -146.577443) (xy 87.169675 -146.599255) (xy 87.217281 -146.628309) (xy 87.260149 -146.663984)
			(xy 87.297366 -146.705521) (xy 87.328139 -146.752034) (xy 87.351811 -146.802531) (xy 87.367879 -146.855938)
			(xy 87.375999 -146.911114) (xy 87.376508 -146.939) (xy 87.375999 -146.966886) (xy 87.367879 -147.022062)
			(xy 87.351811 -147.075469) (xy 87.328139 -147.125966) (xy 87.297366 -147.172479) (xy 87.260149 -147.214016)
			(xy 87.217281 -147.249691) (xy 87.169675 -147.278745) (xy 87.118346 -147.300557) (xy 87.064389 -147.314663)
			(xy 87.008952 -147.320763) (xy 86.953218 -147.318726) (xy 86.898375 -147.308596) (xy 86.845591 -147.290589)
			(xy 86.795991 -147.265088) (xy 86.750633 -147.232637) (xy 86.710484 -147.193928) (xy 86.676398 -147.149785)
			(xy 86.649102 -147.10115) (xy 86.629179 -147.049059) (xy 86.617053 -146.994622) (xy 86.612982 -146.939)
			(xy 81.779186 -146.939) (xy 81.04886 -147.66925) (xy 81.028681 -147.688635) (xy 80.983422 -147.721531)
			(xy 80.933579 -147.746953) (xy 80.880377 -147.764274) (xy 80.825121 -147.77307) (xy 80.797146 -147.773644)
			(xy 75.782424 -147.773644) (xy 75.774042 -147.776438) (xy 75.742824 -147.786955) (xy 75.677944 -147.798328)
			(xy 75.64501 -147.799044) (xy 75.617759 -147.798509) (xy 75.563812 -147.790754) (xy 75.511518 -147.775401)
			(xy 75.461942 -147.752761) (xy 75.416091 -147.723296) (xy 75.374901 -147.687606) (xy 75.33921 -147.646417)
			(xy 75.309744 -147.600567) (xy 75.287103 -147.550991) (xy 75.271748 -147.498697) (xy 75.263991 -147.444751)
			(xy 58.733436 -147.444751) (xy 58.733436 -147.955) (xy 86.612982 -147.955) (xy 86.617053 -147.899378)
			(xy 86.629179 -147.844941) (xy 86.649102 -147.79285) (xy 86.676398 -147.744215) (xy 86.710484 -147.700072)
			(xy 86.750633 -147.661363) (xy 86.795991 -147.628912) (xy 86.845591 -147.603411) (xy 86.898375 -147.585404)
			(xy 86.953218 -147.575274) (xy 87.008952 -147.573237) (xy 87.064389 -147.579337) (xy 87.118346 -147.593443)
			(xy 87.169675 -147.615255) (xy 87.217281 -147.644309) (xy 87.260149 -147.679984) (xy 87.297366 -147.721521)
			(xy 87.328139 -147.768034) (xy 87.351811 -147.818531) (xy 87.367879 -147.871938) (xy 87.375999 -147.927114)
			(xy 87.376508 -147.955) (xy 87.375999 -147.982886) (xy 87.367879 -148.038062) (xy 87.351811 -148.091469)
			(xy 87.328139 -148.141966) (xy 87.297366 -148.188479) (xy 87.260149 -148.230016) (xy 87.217281 -148.265691)
			(xy 87.169675 -148.294745) (xy 87.118346 -148.316557) (xy 87.064389 -148.330663) (xy 87.008952 -148.336763)
			(xy 86.953218 -148.334726) (xy 86.898375 -148.324596) (xy 86.845591 -148.306589) (xy 86.795991 -148.281088)
			(xy 86.750633 -148.248637) (xy 86.710484 -148.209928) (xy 86.676398 -148.165785) (xy 86.649102 -148.11715)
			(xy 86.629179 -148.065059) (xy 86.617053 -148.010622) (xy 86.612982 -147.955) (xy 58.733436 -147.955)
			(xy 58.733436 -148.37664) (xy 76.359002 -148.37664) (xy 76.363073 -148.321018) (xy 76.375199 -148.266581)
			(xy 76.395122 -148.21449) (xy 76.422418 -148.165855) (xy 76.456504 -148.121712) (xy 76.496653 -148.083003)
			(xy 76.542011 -148.050552) (xy 76.591611 -148.025051) (xy 76.644395 -148.007044) (xy 76.699238 -147.996914)
			(xy 76.754972 -147.994877) (xy 76.810409 -148.000977) (xy 76.864366 -148.015083) (xy 76.915695 -148.036895)
			(xy 76.963301 -148.065949) (xy 77.006169 -148.101624) (xy 77.043386 -148.143161) (xy 77.074159 -148.189674)
			(xy 77.097831 -148.240171) (xy 77.113899 -148.293578) (xy 77.122019 -148.348754) (xy 77.122528 -148.37664)
			(xy 77.122019 -148.404526) (xy 77.113899 -148.459702) (xy 77.097831 -148.513109) (xy 77.074159 -148.563606)
			(xy 77.043386 -148.610119) (xy 77.006169 -148.651656) (xy 76.963301 -148.687331) (xy 76.915695 -148.716385)
			(xy 76.864366 -148.738197) (xy 76.810409 -148.752303) (xy 76.754972 -148.758403) (xy 76.699238 -148.756366)
			(xy 76.644395 -148.746236) (xy 76.591611 -148.728229) (xy 76.542011 -148.702728) (xy 76.496653 -148.670277)
			(xy 76.456504 -148.631568) (xy 76.422418 -148.587425) (xy 76.395122 -148.53879) (xy 76.375199 -148.486699)
			(xy 76.363073 -148.432262) (xy 76.359002 -148.37664) (xy 58.733436 -148.37664) (xy 58.733436 -148.94941)
			(xy 88.81186 -148.94941) (xy 88.815931 -148.893788) (xy 88.828057 -148.839351) (xy 88.84798 -148.78726)
			(xy 88.875276 -148.738625) (xy 88.909362 -148.694482) (xy 88.949511 -148.655773) (xy 88.994869 -148.623322)
			(xy 89.044469 -148.597821) (xy 89.097253 -148.579814) (xy 89.152096 -148.569684) (xy 89.20783 -148.567647)
			(xy 89.263267 -148.573747) (xy 89.317224 -148.587853) (xy 89.368553 -148.609665) (xy 89.416159 -148.638719)
			(xy 89.459027 -148.674394) (xy 89.496244 -148.715931) (xy 89.527017 -148.762444) (xy 89.550689 -148.812941)
			(xy 89.566757 -148.866348) (xy 89.574877 -148.921524) (xy 89.575386 -148.94941) (xy 89.574877 -148.977296)
			(xy 89.566757 -149.032472) (xy 89.550689 -149.085879) (xy 89.527017 -149.136376) (xy 89.496244 -149.182889)
			(xy 89.459027 -149.224426) (xy 89.416159 -149.260101) (xy 89.368553 -149.289155) (xy 89.317224 -149.310967)
			(xy 89.263267 -149.325073) (xy 89.20783 -149.331173) (xy 89.152096 -149.329136) (xy 89.097253 -149.319006)
			(xy 89.044469 -149.300999) (xy 88.994869 -149.275498) (xy 88.949511 -149.243047) (xy 88.909362 -149.204338)
			(xy 88.875276 -149.160195) (xy 88.84798 -149.11156) (xy 88.828057 -149.059469) (xy 88.815931 -149.005032)
			(xy 88.81186 -148.94941) (xy 58.733436 -148.94941) (xy 58.733436 -149.412198) (xy 69.012814 -149.412198)
			(xy 69.016885 -149.356576) (xy 69.029011 -149.302139) (xy 69.048934 -149.250048) (xy 69.07623 -149.201413)
			(xy 69.110316 -149.15727) (xy 69.150465 -149.118561) (xy 69.195823 -149.08611) (xy 69.245423 -149.060609)
			(xy 69.298207 -149.042602) (xy 69.35305 -149.032472) (xy 69.408784 -149.030435) (xy 69.464221 -149.036535)
			(xy 69.518178 -149.050641) (xy 69.569507 -149.072453) (xy 69.617113 -149.101507) (xy 69.659981 -149.137182)
			(xy 69.697198 -149.178719) (xy 69.727971 -149.225232) (xy 69.751643 -149.275729) (xy 69.767711 -149.329136)
			(xy 69.775831 -149.384312) (xy 69.77634 -149.412198) (xy 69.775831 -149.440084) (xy 69.767711 -149.49526)
			(xy 69.751643 -149.548667) (xy 69.727971 -149.599164) (xy 69.697198 -149.645677) (xy 69.659981 -149.687214)
			(xy 69.617113 -149.722889) (xy 69.569507 -149.751943) (xy 69.518178 -149.773755) (xy 69.464221 -149.787861)
			(xy 69.408784 -149.793961) (xy 69.35305 -149.791924) (xy 69.298207 -149.781794) (xy 69.245423 -149.763787)
			(xy 69.195823 -149.738286) (xy 69.150465 -149.705835) (xy 69.110316 -149.667126) (xy 69.07623 -149.622983)
			(xy 69.048934 -149.574348) (xy 69.029011 -149.522257) (xy 69.016885 -149.46782) (xy 69.012814 -149.412198)
			(xy 58.733436 -149.412198) (xy 58.733436 -149.96541) (xy 88.81186 -149.96541) (xy 88.815931 -149.909788)
			(xy 88.828057 -149.855351) (xy 88.84798 -149.80326) (xy 88.875276 -149.754625) (xy 88.909362 -149.710482)
			(xy 88.949511 -149.671773) (xy 88.994869 -149.639322) (xy 89.044469 -149.613821) (xy 89.097253 -149.595814)
			(xy 89.152096 -149.585684) (xy 89.20783 -149.583647) (xy 89.263267 -149.589747) (xy 89.317224 -149.603853)
			(xy 89.368553 -149.625665) (xy 89.416159 -149.654719) (xy 89.459027 -149.690394) (xy 89.496244 -149.731931)
			(xy 89.527017 -149.778444) (xy 89.550689 -149.828941) (xy 89.566757 -149.882348) (xy 89.574877 -149.937524)
			(xy 89.575386 -149.96541) (xy 89.574877 -149.993296) (xy 89.566757 -150.048472) (xy 89.550689 -150.101879)
			(xy 89.527017 -150.152376) (xy 89.496244 -150.198889) (xy 89.459027 -150.240426) (xy 89.416159 -150.276101)
			(xy 89.368553 -150.305155) (xy 89.317224 -150.326967) (xy 89.263267 -150.341073) (xy 89.20783 -150.347173)
			(xy 89.152096 -150.345136) (xy 89.097253 -150.335006) (xy 89.044469 -150.316999) (xy 88.994869 -150.291498)
			(xy 88.949511 -150.259047) (xy 88.909362 -150.220338) (xy 88.875276 -150.176195) (xy 88.84798 -150.12756)
			(xy 88.828057 -150.075469) (xy 88.815931 -150.021032) (xy 88.81186 -149.96541) (xy 58.733436 -149.96541)
			(xy 58.733436 -154.528012) (xy 67.588636 -154.528012) (xy 67.592707 -154.47239) (xy 67.604833 -154.417953)
			(xy 67.624756 -154.365862) (xy 67.652052 -154.317227) (xy 67.686138 -154.273084) (xy 67.726287 -154.234375)
			(xy 67.771645 -154.201924) (xy 67.821245 -154.176423) (xy 67.874029 -154.158416) (xy 67.928872 -154.148286)
			(xy 67.984606 -154.146249) (xy 68.040043 -154.152349) (xy 68.094 -154.166455) (xy 68.145329 -154.188267)
			(xy 68.192935 -154.217321) (xy 68.235803 -154.252996) (xy 68.27302 -154.294533) (xy 68.303793 -154.341046)
			(xy 68.327465 -154.391543) (xy 68.343533 -154.44495) (xy 68.351653 -154.500126) (xy 68.352162 -154.528012)
			(xy 68.351653 -154.555898) (xy 68.343533 -154.611074) (xy 68.327465 -154.664481) (xy 68.303793 -154.714978)
			(xy 68.27302 -154.761491) (xy 68.235803 -154.803028) (xy 68.192935 -154.838703) (xy 68.145329 -154.867757)
			(xy 68.094 -154.889569) (xy 68.040043 -154.903675) (xy 67.984606 -154.909775) (xy 67.928872 -154.907738)
			(xy 67.874029 -154.897608) (xy 67.821245 -154.879601) (xy 67.771645 -154.8541) (xy 67.726287 -154.821649)
			(xy 67.686138 -154.78294) (xy 67.652052 -154.738797) (xy 67.624756 -154.690162) (xy 67.604833 -154.638071)
			(xy 67.592707 -154.583634) (xy 67.588636 -154.528012) (xy 58.733436 -154.528012) (xy 58.733436 -156.334714)
			(xy 58.733862 -156.344782) (xy 58.741584 -156.36338) (xy 58.748422 -156.370782) (xy 59.410854 -157.033214)
			(xy 59.417703 -157.040611) (xy 59.42544 -157.05921) (xy 59.42584 -157.069282) (xy 59.42584 -164.588698)
			(xy 65.341246 -164.588698) (xy 65.341732 -164.561447) (xy 65.349488 -164.507499) (xy 65.364843 -164.455204)
			(xy 65.387485 -164.405627) (xy 65.416951 -164.359777) (xy 65.452642 -164.318586) (xy 65.493833 -164.282895)
			(xy 65.539683 -164.253429) (xy 65.58926 -164.230787) (xy 65.641555 -164.215432) (xy 65.695503 -164.207676)
			(xy 65.750005 -164.207676) (xy 65.803953 -164.215432) (xy 65.856248 -164.230787) (xy 65.905825 -164.253429)
			(xy 65.951675 -164.282895) (xy 65.992866 -164.318586) (xy 66.028557 -164.359777) (xy 66.058023 -164.405627)
			(xy 66.080665 -164.455204) (xy 66.09602 -164.507499) (xy 66.103776 -164.561447) (xy 66.104262 -164.588698)
			(xy 66.10363 -164.620262) (xy 66.093232 -164.682528) (xy 66.072735 -164.742237) (xy 66.058288 -164.770308)
			(xy 66.053462 -164.779198) (xy 66.05143 -164.798756) (xy 66.07429 -164.877242) (xy 66.077525 -164.886667)
			(xy 66.089946 -164.902225) (xy 66.09842 -164.907468) (xy 66.105786 -164.911532) (xy 66.115692 -164.917374)
			(xy 66.137536 -164.919406) (xy 66.232278 -164.885878) (xy 66.248026 -164.870384) (xy 66.25209 -164.85997)
			(xy 66.262762 -164.833183) (xy 66.291054 -164.782942) (xy 66.326587 -164.737533) (xy 66.368553 -164.697991)
			(xy 66.415994 -164.665219) (xy 66.467828 -164.639963) (xy 66.522874 -164.622799) (xy 66.579876 -164.614118)
			(xy 66.608706 -164.61359) (xy 66.635957 -164.61408) (xy 66.689904 -164.621837) (xy 66.742197 -164.637193)
			(xy 66.791774 -164.659834) (xy 66.837623 -164.689301) (xy 66.878812 -164.724992) (xy 66.914503 -164.766182)
			(xy 66.943969 -164.812032) (xy 66.966609 -164.861608) (xy 66.981964 -164.913902) (xy 66.98972 -164.967849)
			(xy 66.98972 -165.022351) (xy 66.981964 -165.076298) (xy 66.972618 -165.108128) (xy 67.231514 -165.108128)
			(xy 67.232013 -165.080654) (xy 67.239902 -165.026275) (xy 67.255519 -164.973592) (xy 67.27854 -164.923699)
			(xy 67.30849 -164.87763) (xy 67.326256 -164.856668) (xy 67.32651 -164.856414) (xy 67.332098 -164.849328)
			(xy 67.338344 -164.832411) (xy 67.338702 -164.823394) (xy 67.338702 -164.75583) (xy 67.33833 -164.746815)
			(xy 67.332093 -164.729898) (xy 67.32651 -164.72281) (xy 67.326002 -164.722302) (xy 67.308274 -164.701352)
			(xy 67.27839 -164.65532) (xy 67.255423 -164.605476) (xy 67.239847 -164.552852) (xy 67.231985 -164.498537)
			(xy 67.231514 -164.471096) (xy 67.232064 -164.442025) (xy 67.2409 -164.384558) (xy 67.258352 -164.329096)
			(xy 67.284015 -164.276924) (xy 67.317297 -164.229249) (xy 67.357425 -164.187175) (xy 67.403473 -164.151675)
			(xy 67.454372 -164.123572) (xy 67.508946 -164.103516) (xy 67.53733 -164.097208) (xy 67.537584 -164.097208)
			(xy 67.548894 -164.094293) (xy 67.567355 -164.080028) (xy 67.577643 -164.059089) (xy 67.578224 -164.047424)
			(xy 67.578224 -159.042862) (xy 67.578838 -159.017879) (xy 67.588582 -158.968871) (xy 67.607689 -158.922702)
			(xy 67.635426 -158.881141) (xy 67.652646 -158.86303) (xy 69.742304 -156.773372) (xy 69.7604 -156.756116)
			(xy 69.801945 -156.728307) (xy 69.848116 -156.709135) (xy 69.89714 -156.699334) (xy 69.922136 -156.698696)
			(xy 77.888592 -156.698696) (xy 77.898665 -156.698294) (xy 77.917264 -156.69056) (xy 77.92466 -156.68371)
			(xy 83.789266 -150.819358) (xy 83.807379 -150.802139) (xy 83.848937 -150.774397) (xy 83.895106 -150.755288)
			(xy 83.944114 -150.745547) (xy 83.969098 -150.744936) (xy 89.691464 -150.744936) (xy 89.701533 -150.744509)
			(xy 89.720132 -150.736791) (xy 89.727532 -150.72995) (xy 91.610434 -148.847048) (xy 91.618054 -148.827998)
			(xy 91.617546 -148.81733) (xy 91.616751 -148.807032) (xy 91.608102 -148.788295) (xy 91.600782 -148.781008)
			(xy 91.402154 -148.603208) (xy 91.4019 -148.603208) (xy 91.383141 -148.585718) (xy 91.351169 -148.545621)
			(xy 91.326364 -148.500737) (xy 91.309425 -148.452332) (xy 91.300831 -148.401774) (xy 91.3003 -148.376132)
			(xy 91.3003 -147.39493) (xy 91.300769 -147.371008) (xy 91.308301 -147.32376) (xy 91.323136 -147.278273)
			(xy 91.344909 -147.235669) (xy 91.373083 -147.196999) (xy 91.389708 -147.179792) (xy 91.58986 -146.97964)
			(xy 91.607099 -146.963055) (xy 91.645778 -146.934911) (xy 91.688376 -146.91315) (xy 91.733849 -146.898307)
			(xy 91.781082 -146.890746) (xy 91.804998 -146.890232) (xy 97.60712 -146.890232) (xy 97.617193 -146.889835)
			(xy 97.635792 -146.882097) (xy 97.643188 -146.875246) (xy 97.873058 -146.645376) (xy 97.879895 -146.637973)
			(xy 97.887618 -146.619376) (xy 97.888044 -146.609308) (xy 97.888044 -141.481302) (xy 97.887663 -141.471835)
			(xy 97.880738 -141.454214) (xy 97.874582 -141.447012) (xy 97.854262 -141.424914) (xy 97.847934 -141.418644)
			(xy 97.83207 -141.410568) (xy 97.823274 -141.409166) (xy 97.796953 -141.405365) (xy 97.745616 -141.391492)
			(xy 97.696706 -141.370618) (xy 97.651172 -141.343149) (xy 97.609899 -141.309616) (xy 97.573687 -141.270672)
			(xy 97.543241 -141.227072) (xy 97.51915 -141.179664) (xy 97.501883 -141.129367) (xy 97.496376 -141.10335)
			(xy 97.494007 -141.093564) (xy 97.4829 -141.076795) (xy 97.474786 -141.070838) (xy 97.414842 -141.030706)
			(xy 97.406155 -141.025472) (xy 97.386242 -141.02169) (xy 97.376234 -141.02334) (xy 97.357575 -141.02688)
			(xy 97.319786 -141.030698) (xy 97.300796 -141.03096) (xy 97.300034 -141.03096) (xy 97.273288 -141.030536)
			(xy 97.220321 -141.023048) (xy 97.168918 -141.008242) (xy 97.120084 -140.986407) (xy 97.074775 -140.957971)
			(xy 97.033877 -140.92349) (xy 96.998192 -140.88364) (xy 96.968417 -140.839199) (xy 96.956372 -140.815314)
			(xy 96.951292 -140.804646) (xy 96.933258 -140.790422) (xy 96.832674 -140.767816) (xy 96.810068 -140.77315)
			(xy 96.800924 -140.78077) (xy 96.780402 -140.796895) (xy 96.735811 -140.824015) (xy 96.68794 -140.844804)
			(xy 96.637681 -140.858872) (xy 96.585974 -140.865957) (xy 96.559878 -140.866368) (xy 96.530415 -140.865851)
			(xy 96.472187 -140.856813) (xy 96.416046 -140.838912) (xy 96.389444 -140.826236) (xy 96.379434 -140.821819)
			(xy 96.357587 -140.82104) (xy 96.34728 -140.824712) (xy 96.266 -140.858494) (xy 96.251014 -140.87475)
			(xy 96.247712 -140.885164) (xy 96.238928 -140.910191) (xy 96.215411 -140.957731) (xy 96.185537 -141.001556)
			(xy 96.14988 -141.040821) (xy 96.109128 -141.074768) (xy 96.064066 -141.102744) (xy 96.015565 -141.124208)
			(xy 95.964557 -141.138747) (xy 95.912028 -141.146081) (xy 95.885508 -141.14653) (xy 95.858258 -141.146015)
			(xy 95.804312 -141.13826) (xy 95.75202 -141.122907) (xy 95.702444 -141.100268) (xy 95.656594 -141.070805)
			(xy 95.615405 -141.035117) (xy 95.579713 -140.99393) (xy 95.550246 -140.948083) (xy 95.527604 -140.898509)
			(xy 95.512246 -140.846217) (xy 95.504487 -140.792272) (xy 95.504 -140.765022) (xy 95.504 -140.755624)
			(xy 95.504254 -140.744702) (xy 95.496126 -140.724636) (xy 95.423736 -140.657834) (xy 95.403162 -140.650976)
			(xy 95.392494 -140.651992) (xy 95.35414 -140.654024) (xy 95.326883 -140.653588) (xy 95.272924 -140.645835)
			(xy 95.220618 -140.630482) (xy 95.171029 -140.607841) (xy 95.125167 -140.578373) (xy 95.083966 -140.542678)
			(xy 95.048264 -140.501482) (xy 95.018788 -140.455625) (xy 94.996139 -140.40604) (xy 94.980778 -140.353736)
			(xy 94.973017 -140.299778) (xy 94.973013 -140.245265) (xy 94.980769 -140.191306) (xy 94.996124 -140.139)
			(xy 95.018768 -140.089412) (xy 95.048238 -140.043552) (xy 95.083935 -140.002352) (xy 95.125133 -139.966653)
			(xy 95.170991 -139.937179) (xy 95.220578 -139.914533) (xy 95.272883 -139.899174) (xy 95.326841 -139.891415)
			(xy 95.381354 -139.891415) (xy 95.435312 -139.899173) (xy 95.487617 -139.914531) (xy 95.537204 -139.937177)
			(xy 95.583063 -139.966649) (xy 95.624261 -140.002349) (xy 95.659959 -140.043548) (xy 95.68943 -140.089408)
			(xy 95.712074 -140.138995) (xy 95.72743 -140.191301) (xy 95.735186 -140.245259) (xy 95.735648 -140.272516)
			(xy 95.735648 -140.281914) (xy 95.735394 -140.292836) (xy 95.743522 -140.312902) (xy 95.815912 -140.379704)
			(xy 95.836486 -140.386562) (xy 95.847154 -140.385546) (xy 95.885508 -140.383514) (xy 95.885762 -140.383514)
			(xy 95.915182 -140.384055) (xy 95.973323 -140.393102) (xy 96.029379 -140.410988) (xy 96.055942 -140.423646)
			(xy 96.065955 -140.428055) (xy 96.087799 -140.42884) (xy 96.098106 -140.42517) (xy 96.179386 -140.391388)
			(xy 96.194372 -140.375132) (xy 96.197674 -140.364718) (xy 96.20646 -140.339692) (xy 96.229977 -140.292153)
			(xy 96.259852 -140.248328) (xy 96.29551 -140.209064) (xy 96.336261 -140.175118) (xy 96.381322 -140.147142)
			(xy 96.429823 -140.125678) (xy 96.48083 -140.111138) (xy 96.533359 -140.103802) (xy 96.559878 -140.103352)
			(xy 96.586625 -140.103759) (xy 96.639593 -140.111249) (xy 96.690996 -140.126058) (xy 96.739831 -140.147895)
			(xy 96.78514 -140.176333) (xy 96.826037 -140.210816) (xy 96.861722 -140.250669) (xy 96.891496 -140.295112)
			(xy 96.90354 -140.318998) (xy 96.90862 -140.329666) (xy 96.926654 -140.34389) (xy 97.027238 -140.366496)
			(xy 97.049844 -140.361162) (xy 97.058988 -140.353542) (xy 97.079478 -140.33746) (xy 97.123973 -140.310382)
			(xy 97.171738 -140.28961) (xy 97.221886 -140.275531) (xy 97.273483 -140.268406) (xy 97.299526 -140.267944)
			(xy 97.300034 -140.267944) (xy 97.326337 -140.268382) (xy 97.378441 -140.275627) (xy 97.429057 -140.289961)
			(xy 97.477223 -140.311112) (xy 97.522027 -140.33868) (xy 97.56262 -140.372141) (xy 97.598231 -140.410861)
			(xy 97.628185 -140.454106) (xy 97.651914 -140.501056) (xy 97.668969 -140.55082) (xy 97.67443 -140.576554)
			(xy 97.676796 -140.586341) (xy 97.687905 -140.60311) (xy 97.69602 -140.609066) (xy 97.755964 -140.649198)
			(xy 97.764675 -140.654383) (xy 97.784568 -140.658195) (xy 97.794572 -140.656564) (xy 97.813231 -140.653023)
			(xy 97.85102 -140.649205) (xy 97.87001 -140.648944) (xy 97.870772 -140.648944) (xy 97.897414 -140.649413)
			(xy 97.950184 -140.6568) (xy 97.975928 -140.663676) (xy 97.985082 -140.665901) (xy 98.003841 -140.664331)
			(xy 98.012504 -140.660628) (xy 98.040444 -140.646912) (xy 98.048551 -140.642519) (xy 98.06118 -140.629104)
			(xy 98.065082 -140.62075) (xy 98.077214 -140.593383) (xy 98.110478 -140.543623) (xy 98.131122 -140.521944)
			(xy 98.29546 -140.357606) (xy 98.312652 -140.340978) (xy 98.35134 -140.312857) (xy 98.393954 -140.29114)
			(xy 98.439443 -140.276363) (xy 98.486684 -140.26889) (xy 98.510598 -140.268452) (xy 100.991416 -140.268452)
			(xy 101.015323 -140.268962) (xy 101.062548 -140.276454) (xy 101.108021 -140.291234) (xy 101.150625 -140.312939)
			(xy 101.189313 -140.341037) (xy 101.206554 -140.357606) (xy 101.61143 -140.762482) (xy 101.628009 -140.779719)
			(xy 101.656139 -140.818394) (xy 101.677866 -140.860996) (xy 101.692655 -140.906475) (xy 101.70014 -140.953709)
			(xy 101.700584 -140.97762) (xy 101.700584 -141.6939) (xy 103.389682 -141.6939) (xy 103.393753 -141.638278)
			(xy 103.405879 -141.583841) (xy 103.425802 -141.53175) (xy 103.453098 -141.483115) (xy 103.487184 -141.438972)
			(xy 103.527333 -141.400263) (xy 103.572691 -141.367812) (xy 103.622291 -141.342311) (xy 103.675075 -141.324304)
			(xy 103.729918 -141.314174) (xy 103.785652 -141.312137) (xy 103.841089 -141.318237) (xy 103.895046 -141.332343)
			(xy 103.946375 -141.354155) (xy 103.993981 -141.383209) (xy 104.036849 -141.418884) (xy 104.074066 -141.460421)
			(xy 104.104839 -141.506934) (xy 104.128511 -141.557431) (xy 104.144579 -141.610838) (xy 104.152699 -141.666014)
			(xy 104.153208 -141.6939) (xy 104.152699 -141.721786) (xy 104.144579 -141.776962) (xy 104.128511 -141.830369)
			(xy 104.104839 -141.880866) (xy 104.074066 -141.927379) (xy 104.036849 -141.968916) (xy 103.993981 -142.004591)
			(xy 103.946375 -142.033645) (xy 103.895046 -142.055457) (xy 103.841089 -142.069563) (xy 103.785652 -142.075663)
			(xy 103.729918 -142.073626) (xy 103.675075 -142.063496) (xy 103.622291 -142.045489) (xy 103.572691 -142.019988)
			(xy 103.527333 -141.987537) (xy 103.487184 -141.948828) (xy 103.453098 -141.904685) (xy 103.425802 -141.85605)
			(xy 103.405879 -141.803959) (xy 103.393753 -141.749522) (xy 103.389682 -141.6939) (xy 101.700584 -141.6939)
			(xy 101.700584 -144.103852) (xy 102.455216 -144.103852) (xy 102.459287 -144.04823) (xy 102.471413 -143.993793)
			(xy 102.491336 -143.941702) (xy 102.518632 -143.893067) (xy 102.552718 -143.848924) (xy 102.592867 -143.810215)
			(xy 102.638225 -143.777764) (xy 102.687825 -143.752263) (xy 102.740609 -143.734256) (xy 102.795452 -143.724126)
			(xy 102.851186 -143.722089) (xy 102.906623 -143.728189) (xy 102.96058 -143.742295) (xy 103.011909 -143.764107)
			(xy 103.059515 -143.793161) (xy 103.102383 -143.828836) (xy 103.1396 -143.870373) (xy 103.170373 -143.916886)
			(xy 103.194045 -143.967383) (xy 103.210113 -144.02079) (xy 103.218233 -144.075966) (xy 103.218742 -144.103852)
			(xy 103.218233 -144.131738) (xy 103.210113 -144.186914) (xy 103.194045 -144.240321) (xy 103.170373 -144.290818)
			(xy 103.1396 -144.337331) (xy 103.102383 -144.378868) (xy 103.059515 -144.414543) (xy 103.011909 -144.443597)
			(xy 102.96058 -144.465409) (xy 102.906623 -144.479515) (xy 102.851186 -144.485615) (xy 102.795452 -144.483578)
			(xy 102.740609 -144.473448) (xy 102.687825 -144.455441) (xy 102.638225 -144.42994) (xy 102.592867 -144.397489)
			(xy 102.552718 -144.35878) (xy 102.518632 -144.314637) (xy 102.491336 -144.266002) (xy 102.471413 -144.213911)
			(xy 102.459287 -144.159474) (xy 102.455216 -144.103852) (xy 101.700584 -144.103852) (xy 101.700584 -147.44446)
			(xy 103.134414 -147.44446) (xy 103.134842 -147.418796) (xy 103.14171 -147.367929) (xy 103.155345 -147.318446)
			(xy 103.175498 -147.27124) (xy 103.201806 -147.227166) (xy 103.233791 -147.187023) (xy 103.270876 -147.151537)
			(xy 103.291386 -147.136104) (xy 103.302172 -147.127651) (xy 103.319255 -147.106243) (xy 103.330025 -147.081061)
			(xy 103.333708 -147.053921) (xy 103.330036 -147.026779) (xy 103.319276 -147.001593) (xy 103.302202 -146.980177)
			(xy 103.291386 -146.971766) (xy 103.267495 -146.953705) (xy 103.225182 -146.911322) (xy 103.190012 -146.862847)
			(xy 103.162849 -146.809472) (xy 103.14436 -146.752508) (xy 103.135 -146.693355) (xy 103.134414 -146.66341)
			(xy 103.1349 -146.636159) (xy 103.142656 -146.582211) (xy 103.158011 -146.529916) (xy 103.180653 -146.480339)
			(xy 103.210119 -146.434489) (xy 103.24581 -146.393298) (xy 103.287001 -146.357607) (xy 103.332851 -146.328141)
			(xy 103.382428 -146.305499) (xy 103.434723 -146.290144) (xy 103.488671 -146.282388) (xy 103.543173 -146.282388)
			(xy 103.597121 -146.290144) (xy 103.649416 -146.305499) (xy 103.698993 -146.328141) (xy 103.744843 -146.357607)
			(xy 103.786034 -146.393298) (xy 103.821725 -146.434489) (xy 103.84103 -146.464528) (xy 115.805966 -146.464528)
			(xy 115.806432 -146.437158) (xy 115.814248 -146.382978) (xy 115.829736 -146.330474) (xy 115.852578 -146.280727)
			(xy 115.882304 -146.234761) (xy 115.899946 -146.21383) (xy 115.9002 -146.213576) (xy 115.905803 -146.2065)
			(xy 115.91204 -146.189575) (xy 115.912392 -146.180556) (xy 115.912392 -146.1135) (xy 115.912037 -146.104483)
			(xy 115.905788 -146.087566) (xy 115.9002 -146.08048) (xy 115.899946 -146.08048) (xy 115.899946 -146.080226)
			(xy 115.882332 -146.059271) (xy 115.852605 -146.013308) (xy 115.829756 -145.963565) (xy 115.814257 -145.911066)
			(xy 115.806426 -145.856891) (xy 115.806422 -145.802152) (xy 115.814248 -145.747975) (xy 115.829742 -145.695474)
			(xy 115.852584 -145.645729) (xy 115.882307 -145.599762) (xy 115.899946 -145.57883) (xy 115.9002 -145.578576)
			(xy 115.905803 -145.5715) (xy 115.91204 -145.554575) (xy 115.912392 -145.545556) (xy 115.912392 -145.4785)
			(xy 115.912037 -145.469483) (xy 115.905788 -145.452566) (xy 115.9002 -145.44548) (xy 115.899946 -145.44548)
			(xy 115.899946 -145.445226) (xy 115.882332 -145.424271) (xy 115.852605 -145.378308) (xy 115.829756 -145.328565)
			(xy 115.814257 -145.276066) (xy 115.806426 -145.221891) (xy 115.806422 -145.167152) (xy 115.814248 -145.112975)
			(xy 115.829742 -145.060474) (xy 115.852584 -145.010729) (xy 115.882307 -144.964762) (xy 115.899946 -144.94383)
			(xy 115.9002 -144.943576) (xy 115.905803 -144.9365) (xy 115.91204 -144.919575) (xy 115.912392 -144.910556)
			(xy 115.912392 -144.8435) (xy 115.912037 -144.834483) (xy 115.905788 -144.817566) (xy 115.9002 -144.81048)
			(xy 115.899946 -144.81048) (xy 115.899946 -144.810226) (xy 115.882332 -144.789271) (xy 115.852605 -144.743308)
			(xy 115.829756 -144.693565) (xy 115.814257 -144.641066) (xy 115.806426 -144.586891) (xy 115.806422 -144.532152)
			(xy 115.814248 -144.477975) (xy 115.829742 -144.425474) (xy 115.852584 -144.375729) (xy 115.882307 -144.329762)
			(xy 115.899946 -144.30883) (xy 115.9002 -144.308576) (xy 115.905803 -144.3015) (xy 115.91204 -144.284575)
			(xy 115.912392 -144.275556) (xy 115.912392 -144.2085) (xy 115.912037 -144.199483) (xy 115.905788 -144.182566)
			(xy 115.9002 -144.17548) (xy 115.899946 -144.17548) (xy 115.899946 -144.175226) (xy 115.882313 -144.154289)
			(xy 115.852598 -144.108318) (xy 115.829761 -144.058572) (xy 115.814268 -144.006072) (xy 115.80644 -143.951897)
			(xy 115.805966 -143.924528) (xy 115.806481 -143.897277) (xy 115.814234 -143.843329) (xy 115.829585 -143.791034)
			(xy 115.852222 -143.741456) (xy 115.881685 -143.695604) (xy 115.917373 -143.654411) (xy 115.95856 -143.618717)
			(xy 116.004408 -143.589248) (xy 116.053983 -143.566604) (xy 116.106276 -143.551245) (xy 116.160223 -143.543485)
			(xy 116.187474 -143.54302) (xy 116.214844 -143.543496) (xy 116.269023 -143.551311) (xy 116.321526 -143.566797)
			(xy 116.371273 -143.589637) (xy 116.41724 -143.61936) (xy 116.438172 -143.637) (xy 116.438426 -143.637254)
			(xy 116.445525 -143.642822) (xy 116.462432 -143.649079) (xy 116.471446 -143.649446) (xy 116.538502 -143.649446)
			(xy 116.54752 -143.649101) (xy 116.564438 -143.642846) (xy 116.571522 -143.637254) (xy 116.571522 -143.637)
			(xy 116.571776 -143.637) (xy 116.592706 -143.619359) (xy 116.63868 -143.589647) (xy 116.688428 -143.566812)
			(xy 116.740929 -143.551321) (xy 116.795105 -143.543494) (xy 116.822474 -143.54302) (xy 116.850048 -143.543497)
			(xy 116.904621 -143.551446) (xy 116.957481 -143.567168) (xy 117.007527 -143.590336) (xy 117.053717 -143.620467)
			(xy 117.095088 -143.656933) (xy 117.113304 -143.67764) (xy 117.120851 -143.685724) (xy 117.140869 -143.695072)
			(xy 117.151912 -143.695674) (xy 117.229636 -143.695674) (xy 117.240682 -143.695079) (xy 117.260704 -143.685733)
			(xy 117.268244 -143.67764) (xy 117.28649 -143.656961) (xy 117.32785 -143.620486) (xy 117.374033 -143.590349)
			(xy 117.424074 -143.567177) (xy 117.476931 -143.551455) (xy 117.531501 -143.543509) (xy 117.559074 -143.54302)
			(xy 117.586444 -143.543496) (xy 117.640623 -143.551311) (xy 117.693126 -143.566797) (xy 117.742873 -143.589637)
			(xy 117.78884 -143.61936) (xy 117.809772 -143.637) (xy 117.810026 -143.637254) (xy 117.817125 -143.642822)
			(xy 117.834032 -143.649079) (xy 117.843046 -143.649446) (xy 117.910102 -143.649446) (xy 117.91912 -143.649101)
			(xy 117.936038 -143.642846) (xy 117.943122 -143.637254) (xy 117.943122 -143.637) (xy 117.943376 -143.637)
			(xy 117.964309 -143.619359) (xy 118.010277 -143.589635) (xy 118.060023 -143.566789) (xy 118.112525 -143.551293)
			(xy 118.166703 -143.543464) (xy 118.221445 -143.543464) (xy 118.275623 -143.551293) (xy 118.328125 -143.566789)
			(xy 118.377871 -143.589635) (xy 118.423839 -143.619359) (xy 118.444772 -143.637) (xy 118.445026 -143.637254)
			(xy 118.452125 -143.642822) (xy 118.469032 -143.649079) (xy 118.478046 -143.649446) (xy 118.545102 -143.649446)
			(xy 118.55412 -143.649101) (xy 118.571038 -143.642846) (xy 118.578122 -143.637254) (xy 118.578122 -143.637)
			(xy 118.578376 -143.637) (xy 118.599309 -143.619359) (xy 118.645277 -143.589635) (xy 118.695023 -143.566789)
			(xy 118.747525 -143.551293) (xy 118.801703 -143.543464) (xy 118.856445 -143.543464) (xy 118.910623 -143.551293)
			(xy 118.963125 -143.566789) (xy 119.012871 -143.589635) (xy 119.058839 -143.619359) (xy 119.079772 -143.637)
			(xy 119.080026 -143.637254) (xy 119.087125 -143.642822) (xy 119.104032 -143.649079) (xy 119.113046 -143.649446)
			(xy 119.180102 -143.649446) (xy 119.18912 -143.649101) (xy 119.206038 -143.642846) (xy 119.213122 -143.637254)
			(xy 119.213122 -143.637) (xy 119.213376 -143.637) (xy 119.234306 -143.619359) (xy 119.28028 -143.589647)
			(xy 119.330028 -143.566812) (xy 119.382529 -143.551321) (xy 119.436705 -143.543494) (xy 119.464074 -143.54302)
			(xy 119.491648 -143.543497) (xy 119.546221 -143.551446) (xy 119.599081 -143.567168) (xy 119.649127 -143.590336)
			(xy 119.695317 -143.620467) (xy 119.736688 -143.656933) (xy 119.754904 -143.67764) (xy 119.762451 -143.685724)
			(xy 119.782469 -143.695072) (xy 119.793512 -143.695674) (xy 119.871236 -143.695674) (xy 119.882282 -143.695079)
			(xy 119.902304 -143.685733) (xy 119.909844 -143.67764) (xy 119.92809 -143.656961) (xy 119.96945 -143.620486)
			(xy 120.015633 -143.590349) (xy 120.065674 -143.567177) (xy 120.118531 -143.551455) (xy 120.173101 -143.543509)
			(xy 120.200674 -143.54302) (xy 120.228044 -143.543496) (xy 120.282223 -143.551311) (xy 120.334726 -143.566797)
			(xy 120.384473 -143.589637) (xy 120.43044 -143.61936) (xy 120.451372 -143.637) (xy 120.451626 -143.637254)
			(xy 120.458725 -143.642822) (xy 120.475632 -143.649079) (xy 120.484646 -143.649446) (xy 120.551702 -143.649446)
			(xy 120.56072 -143.649101) (xy 120.577638 -143.642846) (xy 120.584722 -143.637254) (xy 120.584722 -143.637)
			(xy 120.584976 -143.637) (xy 120.605906 -143.619359) (xy 120.65188 -143.589647) (xy 120.701628 -143.566812)
			(xy 120.754129 -143.551321) (xy 120.808305 -143.543494) (xy 120.835674 -143.54302) (xy 120.862927 -143.54348)
			(xy 120.91688 -143.551234) (xy 120.96918 -143.566588) (xy 121.018762 -143.589229) (xy 121.064616 -143.618697)
			(xy 121.10581 -143.654392) (xy 121.141504 -143.695585) (xy 121.170972 -143.74144) (xy 121.193613 -143.791022)
			(xy 121.208967 -143.843322) (xy 121.216721 -143.897275) (xy 121.217182 -143.924528) (xy 121.216737 -143.951899)
			(xy 121.208915 -144.006079) (xy 121.193421 -144.058583) (xy 121.170574 -144.108329) (xy 121.140845 -144.154295)
			(xy 121.123202 -144.175226) (xy 121.122948 -144.17548) (xy 121.117357 -144.182564) (xy 121.111114 -144.199483)
			(xy 121.110756 -144.2085) (xy 121.110756 -144.275556) (xy 121.111122 -144.284572) (xy 121.117362 -144.30149)
			(xy 121.122948 -144.308576) (xy 121.123202 -144.308576) (xy 121.123202 -144.30883) (xy 121.140869 -144.329741)
			(xy 121.17059 -144.375713) (xy 121.193432 -144.425463) (xy 121.208925 -144.477968) (xy 121.216751 -144.532149)
			(xy 121.216747 -144.586893) (xy 121.208916 -144.641073) (xy 121.193417 -144.693576) (xy 121.17057 -144.743324)
			(xy 121.140843 -144.789293) (xy 121.123202 -144.810226) (xy 121.122948 -144.81048) (xy 121.117357 -144.817564)
			(xy 121.111114 -144.834483) (xy 121.110756 -144.8435) (xy 121.110756 -144.910556) (xy 121.111122 -144.919572)
			(xy 121.117362 -144.93649) (xy 121.122948 -144.943576) (xy 121.123202 -144.943576) (xy 121.123202 -144.94383)
			(xy 121.140869 -144.964741) (xy 121.17059 -145.010713) (xy 121.193432 -145.060463) (xy 121.208925 -145.112968)
			(xy 121.216751 -145.167149) (xy 121.216747 -145.221893) (xy 121.208916 -145.276073) (xy 121.193417 -145.328576)
			(xy 121.17057 -145.378324) (xy 121.140843 -145.424293) (xy 121.123202 -145.445226) (xy 121.122948 -145.44548)
			(xy 121.117357 -145.452564) (xy 121.111114 -145.469483) (xy 121.110756 -145.4785) (xy 121.110756 -145.545556)
			(xy 121.111122 -145.554572) (xy 121.117362 -145.57149) (xy 121.122948 -145.578576) (xy 121.123202 -145.578576)
			(xy 121.123202 -145.57883) (xy 121.140869 -145.599741) (xy 121.17059 -145.645713) (xy 121.193432 -145.695463)
			(xy 121.208925 -145.747968) (xy 121.216751 -145.802149) (xy 121.216747 -145.856893) (xy 121.208916 -145.911073)
			(xy 121.193417 -145.963576) (xy 121.17057 -146.013324) (xy 121.140843 -146.059293) (xy 121.123202 -146.080226)
			(xy 121.122948 -146.08048) (xy 121.117357 -146.087564) (xy 121.111114 -146.104483) (xy 121.110756 -146.1135)
			(xy 121.110756 -146.180556) (xy 121.111122 -146.189572) (xy 121.117362 -146.20649) (xy 121.122948 -146.213576)
			(xy 121.123202 -146.213576) (xy 121.123202 -146.21383) (xy 121.140822 -146.234777) (xy 121.170537 -146.280746)
			(xy 121.193376 -146.33049) (xy 121.208872 -146.382987) (xy 121.216705 -146.43716) (xy 121.217182 -146.464528)
			(xy 121.216748 -146.491781) (xy 121.208987 -146.545732) (xy 121.193627 -146.598029) (xy 121.170981 -146.647608)
			(xy 121.141509 -146.69346) (xy 121.105812 -146.734651) (xy 121.064617 -146.770342) (xy 121.018761 -146.799807)
			(xy 120.969179 -146.822446) (xy 120.916879 -146.837799) (xy 120.862927 -146.845552) (xy 120.835674 -146.846036)
			(xy 120.808302 -146.845601) (xy 120.754121 -146.837778) (xy 120.701617 -146.822282) (xy 120.651871 -146.799433)
			(xy 120.605906 -146.769701) (xy 120.584976 -146.752056) (xy 120.584722 -146.751802) (xy 120.577633 -146.746219)
			(xy 120.560718 -146.73997) (xy 120.551702 -146.73961) (xy 120.484646 -146.73961) (xy 120.475631 -146.739987)
			(xy 120.458714 -146.746221) (xy 120.451626 -146.751802) (xy 120.451626 -146.752056) (xy 120.451372 -146.752056)
			(xy 120.430418 -146.769668) (xy 120.384452 -146.799385) (xy 120.33471 -146.822227) (xy 120.282214 -146.837725)
			(xy 120.228042 -146.845559) (xy 120.200674 -146.846036) (xy 120.173354 -146.845559) (xy 120.119273 -146.83776)
			(xy 120.066857 -146.822326) (xy 120.01718 -146.799573) (xy 119.971256 -146.769965) (xy 119.930026 -146.734109)
			(xy 119.894333 -146.692738) (xy 119.864907 -146.646698) (xy 119.853202 -146.622008) (xy 119.847106 -146.608292)
			(xy 119.82196 -146.592036) (xy 119.770144 -146.592036) (xy 119.760076 -146.592475) (xy 119.741478 -146.600185)
			(xy 119.734076 -146.607022) (xy 119.714472 -146.626004) (xy 119.670814 -146.658738) (xy 119.622937 -146.684918)
			(xy 119.571819 -146.704009) (xy 119.518502 -146.715621) (xy 119.464074 -146.719519) (xy 119.409646 -146.715621)
			(xy 119.356329 -146.704009) (xy 119.305211 -146.684918) (xy 119.257334 -146.658738) (xy 119.213676 -146.626004)
			(xy 119.194072 -146.607022) (xy 119.186673 -146.60018) (xy 119.168073 -146.592461) (xy 119.158004 -146.592036)
			(xy 119.135144 -146.592036) (xy 119.125076 -146.592475) (xy 119.106478 -146.600185) (xy 119.099076 -146.607022)
			(xy 119.079472 -146.626004) (xy 119.035814 -146.658738) (xy 118.987937 -146.684918) (xy 118.936819 -146.704009)
			(xy 118.883502 -146.715621) (xy 118.829074 -146.719519) (xy 118.774646 -146.715621) (xy 118.721329 -146.704009)
			(xy 118.670211 -146.684918) (xy 118.622334 -146.658738) (xy 118.578676 -146.626004) (xy 118.559072 -146.607022)
			(xy 118.551673 -146.60018) (xy 118.533073 -146.592461) (xy 118.523004 -146.592036) (xy 118.500144 -146.592036)
			(xy 118.490076 -146.592475) (xy 118.471478 -146.600185) (xy 118.464076 -146.607022) (xy 118.444472 -146.626004)
			(xy 118.400814 -146.658738) (xy 118.352937 -146.684918) (xy 118.301819 -146.704009) (xy 118.248502 -146.715621)
			(xy 118.194074 -146.719519) (xy 118.139646 -146.715621) (xy 118.086329 -146.704009) (xy 118.035211 -146.684918)
			(xy 117.987334 -146.658738) (xy 117.943676 -146.626004) (xy 117.924072 -146.607022) (xy 117.916673 -146.60018)
			(xy 117.898073 -146.592461) (xy 117.888004 -146.592036) (xy 117.865144 -146.592036) (xy 117.855076 -146.592475)
			(xy 117.836478 -146.600185) (xy 117.829076 -146.607022) (xy 117.809472 -146.626004) (xy 117.765814 -146.658738)
			(xy 117.717937 -146.684918) (xy 117.666819 -146.704009) (xy 117.613502 -146.715621) (xy 117.559074 -146.719519)
			(xy 117.504646 -146.715621) (xy 117.451329 -146.704009) (xy 117.400211 -146.684918) (xy 117.352334 -146.658738)
			(xy 117.308676 -146.626004) (xy 117.289072 -146.607022) (xy 117.281673 -146.60018) (xy 117.263073 -146.592461)
			(xy 117.253004 -146.592036) (xy 117.201188 -146.592036) (xy 117.176042 -146.608292) (xy 117.169946 -146.622008)
			(xy 117.158242 -146.6467) (xy 117.128821 -146.692745) (xy 117.093131 -146.734122) (xy 117.051901 -146.769981)
			(xy 117.005977 -146.799591) (xy 116.956297 -146.822344) (xy 116.903879 -146.837776) (xy 116.849795 -146.845569)
			(xy 116.822474 -146.846036) (xy 116.795102 -146.845601) (xy 116.740921 -146.837778) (xy 116.688417 -146.822282)
			(xy 116.638671 -146.799433) (xy 116.592706 -146.769701) (xy 116.571776 -146.752056) (xy 116.571522 -146.751802)
			(xy 116.564433 -146.746219) (xy 116.547518 -146.73997) (xy 116.538502 -146.73961) (xy 116.471446 -146.73961)
			(xy 116.462431 -146.739987) (xy 116.445514 -146.746221) (xy 116.438426 -146.751802) (xy 116.438426 -146.752056)
			(xy 116.438172 -146.752056) (xy 116.417218 -146.769668) (xy 116.371252 -146.799385) (xy 116.32151 -146.822227)
			(xy 116.269014 -146.837725) (xy 116.214842 -146.845559) (xy 116.187474 -146.846036) (xy 116.160223 -146.845546)
			(xy 116.106277 -146.837787) (xy 116.053984 -146.82243) (xy 116.004409 -146.799788) (xy 115.95856 -146.770322)
			(xy 115.917371 -146.734631) (xy 115.88168 -146.693442) (xy 115.852213 -146.647593) (xy 115.829571 -146.598018)
			(xy 115.814213 -146.545725) (xy 115.806454 -146.491779) (xy 115.805966 -146.464528) (xy 103.84103 -146.464528)
			(xy 103.851191 -146.480339) (xy 103.873833 -146.529916) (xy 103.889188 -146.582211) (xy 103.896944 -146.636159)
			(xy 103.89743 -146.66341) (xy 103.897037 -146.689075) (xy 103.89016 -146.739942) (xy 103.876518 -146.789426)
			(xy 103.856359 -146.836632) (xy 103.830046 -146.880705) (xy 103.798057 -146.920847) (xy 103.760969 -146.956334)
			(xy 103.740458 -146.971766) (xy 103.729652 -146.980167) (xy 103.712661 -147.001617) (xy 103.701957 -147.026801)
			(xy 103.698306 -147.053921) (xy 103.701968 -147.081039) (xy 103.712682 -147.106219) (xy 103.729682 -147.127662)
			(xy 103.740458 -147.136104) (xy 103.764322 -147.154199) (xy 103.806639 -147.196573) (xy 103.841814 -147.24504)
			(xy 103.868982 -147.298409) (xy 103.887476 -147.355368) (xy 103.896841 -147.414517) (xy 103.89743 -147.44446)
			(xy 103.896944 -147.471711) (xy 103.889188 -147.525659) (xy 103.873833 -147.577954) (xy 103.851191 -147.627531)
			(xy 103.821725 -147.673381) (xy 103.786034 -147.714572) (xy 103.744843 -147.750263) (xy 103.698993 -147.779729)
			(xy 103.649416 -147.802371) (xy 103.597121 -147.817726) (xy 103.543173 -147.825482) (xy 103.488671 -147.825482)
			(xy 103.434723 -147.817726) (xy 103.382428 -147.802371) (xy 103.332851 -147.779729) (xy 103.287001 -147.750263)
			(xy 103.24581 -147.714572) (xy 103.210119 -147.673381) (xy 103.180653 -147.627531) (xy 103.158011 -147.577954)
			(xy 103.142656 -147.525659) (xy 103.1349 -147.471711) (xy 103.134414 -147.44446) (xy 101.700584 -147.44446)
			(xy 101.700584 -150.984134) (xy 109.251492 -150.984134) (xy 109.251492 -150.899438) (xy 109.259543 -150.815124)
			(xy 109.275572 -150.731958) (xy 109.299433 -150.650691) (xy 109.330912 -150.572061) (xy 109.369723 -150.49678)
			(xy 109.415513 -150.425528) (xy 109.467869 -150.358952) (xy 109.526317 -150.297654) (xy 109.590327 -150.242189)
			(xy 109.659319 -150.19306) (xy 109.732669 -150.150711) (xy 109.809712 -150.115527) (xy 109.889751 -150.087825)
			(xy 109.97206 -150.067857) (xy 110.055895 -150.055804) (xy 110.140496 -150.051774) (xy 110.225097 -150.055804)
			(xy 110.308932 -150.067857) (xy 110.391241 -150.087825) (xy 110.47128 -150.115527) (xy 110.548323 -150.150711)
			(xy 110.621673 -150.19306) (xy 110.690665 -150.242189) (xy 110.754675 -150.297654) (xy 110.813123 -150.358952)
			(xy 110.865479 -150.425528) (xy 110.911269 -150.49678) (xy 110.95008 -150.572061) (xy 110.981559 -150.650691)
			(xy 111.00542 -150.731958) (xy 111.021449 -150.815124) (xy 111.0295 -150.899438) (xy 111.030004 -150.941786)
			(xy 111.674409 -150.941786) (xy 111.678412 -150.853924) (xy 111.690388 -150.76679) (xy 111.710239 -150.681106)
			(xy 111.737798 -150.597582) (xy 111.772839 -150.51691) (xy 111.81507 -150.439759) (xy 111.864142 -150.366768)
			(xy 111.919649 -150.298542) (xy 111.981129 -150.235646) (xy 112.048074 -150.178601) (xy 112.119929 -150.12788)
			(xy 112.196099 -150.083903) (xy 112.275952 -150.047035) (xy 112.358827 -150.017582) (xy 112.444037 -149.995786)
			(xy 112.530876 -149.98183) (xy 112.618624 -149.975827) (xy 112.706554 -149.977829) (xy 112.793939 -149.987819)
			(xy 112.880052 -150.005714) (xy 112.964182 -150.031365) (xy 113.04563 -150.06456) (xy 113.123723 -150.105024)
			(xy 113.197812 -150.152422) (xy 113.267284 -150.206361) (xy 113.331563 -150.266394) (xy 113.390117 -150.332023)
			(xy 113.442461 -150.402705) (xy 113.48816 -150.477854) (xy 113.526836 -150.556847) (xy 113.558168 -150.63903)
			(xy 113.581898 -150.723722) (xy 113.597828 -150.810221) (xy 113.605826 -150.897809) (xy 113.606326 -150.941786)
			(xy 113.605826 -150.985763) (xy 113.597828 -151.073351) (xy 113.581898 -151.15985) (xy 113.558168 -151.244542)
			(xy 113.526836 -151.326725) (xy 113.48816 -151.405718) (xy 113.442461 -151.480867) (xy 113.390117 -151.551549)
			(xy 113.331563 -151.617178) (xy 113.267284 -151.677211) (xy 113.197812 -151.73115) (xy 113.123723 -151.778548)
			(xy 113.04563 -151.819012) (xy 112.964182 -151.852207) (xy 112.880052 -151.877858) (xy 112.793939 -151.895753)
			(xy 112.706554 -151.905743) (xy 112.618624 -151.907745) (xy 112.530876 -151.901742) (xy 112.444037 -151.887786)
			(xy 112.358827 -151.86599) (xy 112.275952 -151.836537) (xy 112.196099 -151.799669) (xy 112.119929 -151.755692)
			(xy 112.048074 -151.704971) (xy 111.981129 -151.647926) (xy 111.919649 -151.58503) (xy 111.864142 -151.516804)
			(xy 111.81507 -151.443813) (xy 111.772839 -151.366662) (xy 111.737798 -151.28599) (xy 111.710239 -151.202466)
			(xy 111.690388 -151.116782) (xy 111.678412 -151.029648) (xy 111.674409 -150.941786) (xy 111.030004 -150.941786)
			(xy 111.0295 -150.984134) (xy 111.021449 -151.068448) (xy 111.00542 -151.151614) (xy 110.981559 -151.232881)
			(xy 110.95008 -151.311511) (xy 110.911269 -151.386792) (xy 110.865479 -151.458044) (xy 110.813123 -151.52462)
			(xy 110.754675 -151.585918) (xy 110.690665 -151.641383) (xy 110.621673 -151.690512) (xy 110.548323 -151.732861)
			(xy 110.47128 -151.768045) (xy 110.391241 -151.795747) (xy 110.308932 -151.815715) (xy 110.225097 -151.827768)
			(xy 110.140496 -151.831799) (xy 110.055895 -151.827768) (xy 109.97206 -151.815715) (xy 109.889751 -151.795747)
			(xy 109.809712 -151.768045) (xy 109.732669 -151.732861) (xy 109.659319 -151.690512) (xy 109.590327 -151.641383)
			(xy 109.526317 -151.585918) (xy 109.467869 -151.52462) (xy 109.415513 -151.458044) (xy 109.369723 -151.386792)
			(xy 109.330912 -151.311511) (xy 109.299433 -151.232881) (xy 109.275572 -151.151614) (xy 109.259543 -151.068448)
			(xy 109.251492 -150.984134) (xy 101.700584 -150.984134) (xy 101.700584 -152.657556) (xy 115.877086 -152.657556)
			(xy 115.877588 -152.630187) (xy 115.885398 -152.57601) (xy 115.900879 -152.523507) (xy 115.923712 -152.47376)
			(xy 115.953429 -152.427791) (xy 115.971066 -152.406858) (xy 115.97132 -152.406604) (xy 115.976913 -152.399522)
			(xy 115.983155 -152.382602) (xy 115.983512 -152.373584) (xy 115.983512 -152.306528) (xy 115.983139 -152.297513)
			(xy 115.976902 -152.280596) (xy 115.97132 -152.273508) (xy 115.971066 -152.273508) (xy 115.971066 -152.273254)
			(xy 115.953433 -152.252317) (xy 115.923722 -152.206345) (xy 115.900885 -152.156599) (xy 115.885392 -152.104099)
			(xy 115.877562 -152.049925) (xy 115.877086 -152.022556) (xy 115.877537 -151.995304) (xy 115.885299 -151.941355)
			(xy 115.90066 -151.88906) (xy 115.923305 -151.839483) (xy 115.952776 -151.793633) (xy 115.988471 -151.752444)
			(xy 116.029664 -151.716753) (xy 116.075517 -151.687287) (xy 116.125096 -151.664646) (xy 116.177392 -151.649291)
			(xy 116.231342 -151.641534) (xy 116.258594 -151.641048) (xy 116.285965 -151.641506) (xy 116.340145 -151.649324)
			(xy 116.392648 -151.664814) (xy 116.442395 -151.687658) (xy 116.488361 -151.717385) (xy 116.509292 -151.735028)
			(xy 116.509546 -151.735282) (xy 116.516646 -151.74085) (xy 116.533552 -151.747108) (xy 116.542566 -151.747474)
			(xy 116.609622 -151.747474) (xy 116.618641 -151.747133) (xy 116.635558 -151.740875) (xy 116.642642 -151.735282)
			(xy 116.642642 -151.735028) (xy 116.642896 -151.735028) (xy 116.663822 -151.717382) (xy 116.709796 -151.68767)
			(xy 116.759545 -151.664835) (xy 116.812047 -151.649346) (xy 116.866224 -151.64152) (xy 116.893594 -151.641048)
			(xy 116.922607 -151.64157) (xy 116.979966 -151.65034) (xy 117.035335 -151.667693) (xy 117.087439 -151.69323)
			(xy 117.135076 -151.726361) (xy 117.156484 -151.74595) (xy 117.163342 -151.752808) (xy 117.181376 -151.75992)
			(xy 117.271292 -151.75992) (xy 117.289326 -151.752808) (xy 117.296184 -151.74595) (xy 117.317594 -151.726366)
			(xy 117.365238 -151.693251) (xy 117.417343 -151.667723) (xy 117.472709 -151.650369) (xy 117.530063 -151.64159)
			(xy 117.559074 -151.641048) (xy 117.586444 -151.641518) (xy 117.640624 -151.649333) (xy 117.693127 -151.66482)
			(xy 117.742874 -151.687662) (xy 117.788841 -151.717386) (xy 117.809772 -151.735028) (xy 117.810026 -151.735282)
			(xy 117.817131 -151.740841) (xy 117.834034 -151.747105) (xy 117.843046 -151.747474) (xy 117.910102 -151.747474)
			(xy 117.91912 -151.747124) (xy 117.936037 -151.740872) (xy 117.943122 -151.735282) (xy 117.943122 -151.735028)
			(xy 117.943376 -151.735028) (xy 117.964309 -151.717387) (xy 118.010277 -151.687663) (xy 118.060023 -151.664817)
			(xy 118.112525 -151.649321) (xy 118.166703 -151.641492) (xy 118.221445 -151.641492) (xy 118.275623 -151.649321)
			(xy 118.328125 -151.664817) (xy 118.377871 -151.687663) (xy 118.423839 -151.717387) (xy 118.444772 -151.735028)
			(xy 118.445026 -151.735282) (xy 118.452131 -151.740841) (xy 118.469034 -151.747105) (xy 118.478046 -151.747474)
			(xy 118.545102 -151.747474) (xy 118.55412 -151.747124) (xy 118.571037 -151.740872) (xy 118.578122 -151.735282)
			(xy 118.578122 -151.735028) (xy 118.578376 -151.735028) (xy 118.599309 -151.717387) (xy 118.645277 -151.687663)
			(xy 118.695023 -151.664817) (xy 118.747525 -151.649321) (xy 118.801703 -151.641492) (xy 118.856445 -151.641492)
			(xy 118.910623 -151.649321) (xy 118.963125 -151.664817) (xy 119.012871 -151.687663) (xy 119.058839 -151.717387)
			(xy 119.079772 -151.735028) (xy 119.080026 -151.735282) (xy 119.087131 -151.740841) (xy 119.104034 -151.747105)
			(xy 119.113046 -151.747474) (xy 119.180102 -151.747474) (xy 119.18912 -151.747124) (xy 119.206037 -151.740872)
			(xy 119.213122 -151.735282) (xy 119.213122 -151.735028) (xy 119.213376 -151.735028) (xy 119.23431 -151.717391)
			(xy 119.280282 -151.687678) (xy 119.330029 -151.664841) (xy 119.382529 -151.64935) (xy 119.436705 -151.641522)
			(xy 119.464074 -151.641048) (xy 119.491323 -151.641602) (xy 119.545266 -151.649354) (xy 119.597556 -151.664704)
			(xy 119.64713 -151.687339) (xy 119.692979 -151.716798) (xy 119.734168 -151.752482) (xy 119.76986 -151.793665)
			(xy 119.799328 -151.839508) (xy 119.821972 -151.889078) (xy 119.837331 -151.941366) (xy 119.845093 -151.995308)
			(xy 119.845582 -152.022556) (xy 119.845095 -152.049926) (xy 119.837283 -152.104104) (xy 119.821799 -152.156607)
			(xy 119.805913 -152.191212) (xy 132.117846 -152.191212) (xy 132.118332 -152.163961) (xy 132.126088 -152.110013)
			(xy 132.141443 -152.057718) (xy 132.164085 -152.008141) (xy 132.193551 -151.962291) (xy 132.229242 -151.9211)
			(xy 132.270433 -151.885409) (xy 132.316283 -151.855943) (xy 132.36586 -151.833301) (xy 132.418155 -151.817946)
			(xy 132.472103 -151.81019) (xy 132.526605 -151.81019) (xy 132.580553 -151.817946) (xy 132.632848 -151.833301)
			(xy 132.682425 -151.855943) (xy 132.728275 -151.885409) (xy 132.769466 -151.9211) (xy 132.805157 -151.962291)
			(xy 132.834623 -152.008141) (xy 132.857265 -152.057718) (xy 132.863423 -152.07869) (xy 134.023354 -152.07869)
			(xy 134.02384 -152.051439) (xy 134.031596 -151.997491) (xy 134.046951 -151.945196) (xy 134.069593 -151.895619)
			(xy 134.099059 -151.849769) (xy 134.13475 -151.808578) (xy 134.175941 -151.772887) (xy 134.221791 -151.743421)
			(xy 134.271368 -151.720779) (xy 134.323663 -151.705424) (xy 134.377611 -151.697668) (xy 134.432113 -151.697668)
			(xy 134.486061 -151.705424) (xy 134.538356 -151.720779) (xy 134.587933 -151.743421) (xy 134.633783 -151.772887)
			(xy 134.674974 -151.808578) (xy 134.710665 -151.849769) (xy 134.740131 -151.895619) (xy 134.762773 -151.945196)
			(xy 134.778128 -151.997491) (xy 134.785884 -152.051439) (xy 134.78637 -152.07869) (xy 134.785938 -152.104179)
			(xy 134.779161 -152.154704) (xy 134.765712 -152.203876) (xy 134.745833 -152.250818) (xy 134.719877 -152.294693)
			(xy 134.688307 -152.334719) (xy 134.670292 -152.352756) (xy 134.670038 -152.35301) (xy 134.662866 -152.36075)
			(xy 134.655 -152.380306) (xy 134.654798 -152.390856) (xy 134.65683 -152.465786) (xy 134.657714 -152.476292)
			(xy 134.666753 -152.495313) (xy 134.674356 -152.502616) (xy 134.67461 -152.50287) (xy 134.695019 -152.52108)
			(xy 134.730949 -152.562319) (xy 134.760621 -152.608266) (xy 134.783427 -152.65798) (xy 134.7989 -152.710441)
			(xy 134.804508 -152.74925) (xy 135.34593 -152.74925) (xy 135.350001 -152.693628) (xy 135.362127 -152.639191)
			(xy 135.38205 -152.5871) (xy 135.409346 -152.538465) (xy 135.443432 -152.494322) (xy 135.483581 -152.455613)
			(xy 135.528939 -152.423162) (xy 135.578539 -152.397661) (xy 135.631323 -152.379654) (xy 135.686166 -152.369524)
			(xy 135.7419 -152.367487) (xy 135.797337 -152.373587) (xy 135.851294 -152.387693) (xy 135.902623 -152.409505)
			(xy 135.950229 -152.438559) (xy 135.993097 -152.474234) (xy 136.030314 -152.515771) (xy 136.061087 -152.562284)
			(xy 136.084759 -152.612781) (xy 136.100827 -152.666188) (xy 136.108947 -152.721364) (xy 136.109456 -152.74925)
			(xy 136.108947 -152.777136) (xy 136.100827 -152.832312) (xy 136.084759 -152.885719) (xy 136.061087 -152.936216)
			(xy 136.030314 -152.982729) (xy 135.993097 -153.024266) (xy 135.950229 -153.059941) (xy 135.902623 -153.088995)
			(xy 135.851294 -153.110807) (xy 135.797337 -153.124913) (xy 135.7419 -153.131013) (xy 135.686166 -153.128976)
			(xy 135.631323 -153.118846) (xy 135.578539 -153.100839) (xy 135.528939 -153.075338) (xy 135.483581 -153.042887)
			(xy 135.443432 -153.004178) (xy 135.409346 -152.960035) (xy 135.38205 -152.9114) (xy 135.362127 -152.859309)
			(xy 135.350001 -152.804872) (xy 135.34593 -152.74925) (xy 134.804508 -152.74925) (xy 134.806722 -152.764574)
			(xy 134.807198 -152.791922) (xy 134.806712 -152.819173) (xy 134.798956 -152.873121) (xy 134.783601 -152.925416)
			(xy 134.760959 -152.974993) (xy 134.731493 -153.020843) (xy 134.695802 -153.062034) (xy 134.654611 -153.097725)
			(xy 134.608761 -153.127191) (xy 134.559184 -153.149833) (xy 134.506889 -153.165188) (xy 134.452941 -153.172944)
			(xy 134.398439 -153.172944) (xy 134.344491 -153.165188) (xy 134.292196 -153.149833) (xy 134.242619 -153.127191)
			(xy 134.196769 -153.097725) (xy 134.155578 -153.062034) (xy 134.119887 -153.020843) (xy 134.090421 -152.974993)
			(xy 134.067779 -152.925416) (xy 134.052424 -152.873121) (xy 134.044668 -152.819173) (xy 134.044182 -152.791922)
			(xy 134.044637 -152.766434) (xy 134.051411 -152.71591) (xy 134.064856 -152.666739) (xy 134.084731 -152.619797)
			(xy 134.110683 -152.575922) (xy 134.142248 -152.535894) (xy 134.16026 -152.517856) (xy 134.160514 -152.517602)
			(xy 134.167688 -152.509864) (xy 134.175551 -152.490307) (xy 134.175754 -152.479756) (xy 134.173722 -152.404826)
			(xy 134.172846 -152.394318) (xy 134.163803 -152.375297) (xy 134.156196 -152.367996) (xy 134.155942 -152.367742)
			(xy 134.135549 -152.349514) (xy 134.099616 -152.30828) (xy 134.06994 -152.262337) (xy 134.047131 -152.212627)
			(xy 134.031655 -152.160168) (xy 134.023831 -152.106037) (xy 134.023354 -152.07869) (xy 132.863423 -152.07869)
			(xy 132.87262 -152.110013) (xy 132.880376 -152.163961) (xy 132.880862 -152.191212) (xy 132.880196 -152.222775)
			(xy 132.869812 -152.28504) (xy 132.849329 -152.344749) (xy 132.834888 -152.372822) (xy 132.830062 -152.381712)
			(xy 132.82803 -152.40127) (xy 132.85089 -152.479756) (xy 132.85412 -152.489184) (xy 132.866544 -152.50474)
			(xy 132.87502 -152.509982) (xy 132.882386 -152.514046) (xy 132.892292 -152.519888) (xy 132.914136 -152.52192)
			(xy 133.008878 -152.488392) (xy 133.024626 -152.472898) (xy 133.02869 -152.462484) (xy 133.039369 -152.4357)
			(xy 133.067659 -152.385458) (xy 133.103192 -152.340049) (xy 133.145156 -152.300507) (xy 133.192596 -152.267734)
			(xy 133.244429 -152.242477) (xy 133.299474 -152.225313) (xy 133.356476 -152.216632) (xy 133.385306 -152.216104)
			(xy 133.412558 -152.216566) (xy 133.466507 -152.224324) (xy 133.518802 -152.23968) (xy 133.56838 -152.262322)
			(xy 133.614231 -152.291789) (xy 133.655422 -152.327482) (xy 133.691114 -152.368673) (xy 133.720581 -152.414525)
			(xy 133.743222 -152.464103) (xy 133.758578 -152.516399) (xy 133.766334 -152.570348) (xy 133.766334 -152.624852)
			(xy 133.758578 -152.678801) (xy 133.743222 -152.731097) (xy 133.720581 -152.780675) (xy 133.691114 -152.826527)
			(xy 133.655422 -152.867718) (xy 133.614231 -152.903411) (xy 133.56838 -152.932878) (xy 133.518802 -152.95552)
			(xy 133.466507 -152.970876) (xy 133.412558 -152.978634) (xy 133.385306 -152.97912) (xy 133.385052 -152.97912)
			(xy 133.359849 -152.978703) (xy 133.309881 -152.972069) (xy 133.261227 -152.958898) (xy 133.214736 -152.93942)
			(xy 133.192774 -152.92705) (xy 133.182868 -152.921208) (xy 133.161024 -152.919176) (xy 133.066282 -152.952704)
			(xy 133.050534 -152.968198) (xy 133.04647 -152.978612) (xy 133.035739 -153.005373) (xy 133.007455 -153.055613)
			(xy 132.97193 -153.101022) (xy 132.929973 -153.140565) (xy 132.882541 -153.17334) (xy 132.830715 -153.198601)
			(xy 132.775677 -153.215771) (xy 132.718681 -153.224459) (xy 132.689854 -153.224992) (xy 132.662601 -153.224565)
			(xy 132.60865 -153.216802) (xy 132.556353 -153.20144) (xy 132.506775 -153.178792) (xy 132.460924 -153.14932)
			(xy 132.419734 -153.113622) (xy 132.384043 -153.072426) (xy 132.354578 -153.026571) (xy 132.331938 -152.976988)
			(xy 132.316585 -152.924689) (xy 132.308831 -152.870737) (xy 132.308346 -152.843484) (xy 132.309009 -152.811921)
			(xy 132.319394 -152.749656) (xy 132.339879 -152.689947) (xy 132.35432 -152.661874) (xy 132.359146 -152.652984)
			(xy 132.361178 -152.633426) (xy 132.338318 -152.55494) (xy 132.335087 -152.545513) (xy 132.322663 -152.529957)
			(xy 132.314188 -152.524714) (xy 132.289062 -152.510206) (xy 132.24318 -152.474696) (xy 132.203207 -152.432645)
			(xy 132.170065 -152.385024) (xy 132.144518 -152.332933) (xy 132.127157 -152.277572) (xy 132.118382 -152.220221)
			(xy 132.117846 -152.191212) (xy 119.805913 -152.191212) (xy 119.798962 -152.206354) (xy 119.769241 -152.252322)
			(xy 119.751602 -152.273254) (xy 119.751348 -152.273508) (xy 119.745746 -152.280584) (xy 119.73951 -152.297509)
			(xy 119.739156 -152.306528) (xy 119.739156 -152.373584) (xy 119.739509 -152.382602) (xy 119.745758 -152.399519)
			(xy 119.751348 -152.406604) (xy 119.751602 -152.406604) (xy 119.751602 -152.406858) (xy 119.769235 -152.427795)
			(xy 119.798948 -152.473766) (xy 119.821785 -152.523513) (xy 119.837277 -152.576012) (xy 119.845107 -152.630187)
			(xy 119.845582 -152.657556) (xy 119.845104 -152.684809) (xy 119.837352 -152.738761) (xy 119.822 -152.79106)
			(xy 119.799361 -152.840642) (xy 119.769895 -152.886496) (xy 119.734203 -152.92769) (xy 119.693011 -152.963384)
			(xy 119.647157 -152.992852) (xy 119.597577 -153.015494) (xy 119.545278 -153.030848) (xy 119.491327 -153.038602)
			(xy 119.464074 -153.039064) (xy 119.436703 -153.038622) (xy 119.382522 -153.0308) (xy 119.330019 -153.015305)
			(xy 119.280272 -152.992458) (xy 119.234307 -152.962728) (xy 119.213376 -152.945084) (xy 119.213122 -152.94483)
			(xy 119.206039 -152.939238) (xy 119.189119 -152.932997) (xy 119.180102 -152.932638) (xy 119.113046 -152.932638)
			(xy 119.10403 -152.933009) (xy 119.087113 -152.939246) (xy 119.080026 -152.94483) (xy 119.079772 -152.945084)
			(xy 119.058839 -152.962725) (xy 119.012871 -152.992449) (xy 118.963125 -153.015295) (xy 118.910623 -153.030791)
			(xy 118.856445 -153.03862) (xy 118.801703 -153.03862) (xy 118.747525 -153.030791) (xy 118.695023 -153.015295)
			(xy 118.645277 -152.992449) (xy 118.599309 -152.962725) (xy 118.578376 -152.945084) (xy 118.578122 -152.94483)
			(xy 118.571039 -152.939238) (xy 118.554119 -152.932997) (xy 118.545102 -152.932638) (xy 118.478046 -152.932638)
			(xy 118.46903 -152.933009) (xy 118.452113 -152.939246) (xy 118.445026 -152.94483) (xy 118.445026 -152.945084)
			(xy 118.444772 -152.945084) (xy 118.423839 -152.962725) (xy 118.377871 -152.992449) (xy 118.328125 -153.015295)
			(xy 118.275623 -153.030791) (xy 118.221445 -153.03862) (xy 118.166703 -153.03862) (xy 118.112525 -153.030791)
			(xy 118.060023 -153.015295) (xy 118.010277 -152.992449) (xy 117.964309 -152.962725) (xy 117.943376 -152.945084)
			(xy 117.943122 -152.94483) (xy 117.936039 -152.939238) (xy 117.919119 -152.932997) (xy 117.910102 -152.932638)
			(xy 117.843046 -152.932638) (xy 117.83403 -152.933009) (xy 117.817113 -152.939246) (xy 117.810026 -152.94483)
			(xy 117.810026 -152.945084) (xy 117.809772 -152.945084) (xy 117.788822 -152.9627) (xy 117.742854 -152.992416)
			(xy 117.693111 -153.015257) (xy 117.640615 -153.030753) (xy 117.586442 -153.038587) (xy 117.559074 -153.039064)
			(xy 117.530061 -153.038558) (xy 117.472701 -153.029784) (xy 117.417332 -153.012427) (xy 117.365228 -152.986886)
			(xy 117.317592 -152.953752) (xy 117.296184 -152.934162) (xy 117.289326 -152.927304) (xy 117.271292 -152.920192)
			(xy 117.181376 -152.920192) (xy 117.163342 -152.927304) (xy 117.156484 -152.934162) (xy 117.135089 -152.953763)
			(xy 117.087441 -152.986876) (xy 117.035332 -153.0124) (xy 116.979963 -153.029749) (xy 116.922606 -153.038525)
			(xy 116.893594 -153.039064) (xy 116.866223 -153.03861) (xy 116.812043 -153.030791) (xy 116.75954 -153.015299)
			(xy 116.709793 -152.992455) (xy 116.663827 -152.962727) (xy 116.642896 -152.945084) (xy 116.642642 -152.94483)
			(xy 116.635554 -152.939247) (xy 116.618638 -152.933) (xy 116.609622 -152.932638) (xy 116.542566 -152.932638)
			(xy 116.533546 -152.93297) (xy 116.516629 -152.939234) (xy 116.509546 -152.94483) (xy 116.509546 -152.945084)
			(xy 116.509292 -152.945084) (xy 116.488372 -152.962738) (xy 116.442396 -152.992448) (xy 116.392645 -153.015281)
			(xy 116.340142 -153.030769) (xy 116.285964 -153.038593) (xy 116.258594 -153.039064) (xy 116.231339 -153.03865)
			(xy 116.177384 -153.030891) (xy 116.125083 -153.015532) (xy 116.075499 -152.992886) (xy 116.029644 -152.963413)
			(xy 115.988451 -152.927714) (xy 115.952757 -152.886516) (xy 115.92329 -152.840657) (xy 115.90065 -152.791071)
			(xy 115.885298 -152.738767) (xy 115.877546 -152.684811) (xy 115.877086 -152.657556) (xy 101.700584 -152.657556)
			(xy 101.700584 -152.788874) (xy 101.700128 -152.812784) (xy 101.692627 -152.860011) (xy 101.677835 -152.905486)
			(xy 101.656116 -152.948089) (xy 101.628005 -152.986774) (xy 101.61143 -153.004012) (xy 101.293422 -153.32202)
			(xy 101.276184 -153.338606) (xy 101.237506 -153.366752) (xy 101.194908 -153.388513) (xy 101.149434 -153.403356)
			(xy 101.1022 -153.410916) (xy 101.078284 -153.411428) (xy 97.258632 -153.411428) (xy 97.229168 -153.409904)
			(xy 97.2185 -153.408888) (xy 97.19818 -153.415492) (xy 97.134172 -153.47315) (xy 97.126623 -153.480743)
			(xy 97.117968 -153.500303) (xy 97.117408 -153.510996) (xy 97.117408 -154.465274) (xy 128.331722 -154.465274)
			(xy 128.332231 -154.437701) (xy 128.340174 -154.38313) (xy 128.35589 -154.33027) (xy 128.379051 -154.280224)
			(xy 128.409177 -154.234033) (xy 128.445638 -154.192661) (xy 128.466342 -154.174444) (xy 128.474405 -154.166878)
			(xy 128.483764 -154.146874) (xy 128.484376 -154.135836) (xy 128.484376 -154.058112) (xy 128.483809 -154.047062)
			(xy 128.474444 -154.027041) (xy 128.466342 -154.019504) (xy 128.445638 -154.001285) (xy 128.409165 -153.959919)
			(xy 128.379031 -153.913731) (xy 128.355864 -153.863684) (xy 128.340147 -153.810823) (xy 128.332207 -153.756248)
			(xy 128.331722 -153.728674) (xy 128.332231 -153.701101) (xy 128.340174 -153.64653) (xy 128.35589 -153.59367)
			(xy 128.379051 -153.543624) (xy 128.409177 -153.497433) (xy 128.445638 -153.456061) (xy 128.466342 -153.437844)
			(xy 128.474405 -153.430278) (xy 128.483764 -153.410274) (xy 128.484376 -153.399236) (xy 128.484376 -153.321512)
			(xy 128.483809 -153.310462) (xy 128.474444 -153.290441) (xy 128.466342 -153.282904) (xy 128.445638 -153.264685)
			(xy 128.409165 -153.223319) (xy 128.379031 -153.177131) (xy 128.355864 -153.127084) (xy 128.340147 -153.074223)
			(xy 128.332207 -153.019648) (xy 128.331722 -152.992074) (xy 128.332131 -152.964819) (xy 128.339892 -152.910865)
			(xy 128.355253 -152.858564) (xy 128.377901 -152.808982) (xy 128.407374 -152.763127) (xy 128.443074 -152.721934)
			(xy 128.484272 -152.686241) (xy 128.530131 -152.656774) (xy 128.579716 -152.634133) (xy 128.632019 -152.61878)
			(xy 128.685975 -152.611027) (xy 128.71323 -152.610566) (xy 128.741085 -152.611087) (xy 128.796199 -152.619214)
			(xy 128.849548 -152.635262) (xy 128.9 -152.65889) (xy 128.946483 -152.689597) (xy 128.988012 -152.726732)
			(xy 129.023706 -152.769506) (xy 129.052806 -152.817012) (xy 129.074696 -152.868242) (xy 129.082292 -152.895046)
			(xy 129.084578 -152.903936) (xy 129.095246 -152.919176) (xy 129.167128 -152.966928) (xy 129.185162 -152.970992)
			(xy 129.194306 -152.969722) (xy 129.207323 -152.968054) (xy 129.233507 -152.966273) (xy 129.24663 -152.966166)
			(xy 129.260779 -152.966257) (xy 129.289002 -152.968293) (xy 129.303018 -152.97023) (xy 129.312924 -152.971754)
			(xy 129.332736 -152.966928) (xy 129.407158 -152.911048) (xy 129.417318 -152.893522) (xy 129.418588 -152.883362)
			(xy 129.422677 -152.856208) (xy 129.437649 -152.803378) (xy 129.46004 -152.753239) (xy 129.489387 -152.706828)
			(xy 129.525085 -152.665104) (xy 129.566394 -152.628927) (xy 129.612463 -152.599046) (xy 129.66234 -152.576077)
			(xy 129.714994 -152.560496) (xy 129.769338 -152.552624) (xy 129.796794 -152.552146) (xy 129.824043 -152.552683)
			(xy 129.877987 -152.560438) (xy 129.930277 -152.57579) (xy 129.979852 -152.598427) (xy 130.0257 -152.627888)
			(xy 130.066889 -152.663574) (xy 130.102581 -152.704758) (xy 130.132048 -152.750603) (xy 130.154692 -152.800174)
			(xy 130.170051 -152.852463) (xy 130.177813 -152.906405) (xy 130.178302 -152.933654) (xy 130.177804 -152.961227)
			(xy 130.169858 -153.015799) (xy 130.154139 -153.068658) (xy 130.130975 -153.118704) (xy 130.100849 -153.164894)
			(xy 130.064387 -153.206267) (xy 130.043682 -153.224484) (xy 130.035611 -153.232043) (xy 130.026255 -153.252052)
			(xy 130.025648 -153.263092) (xy 130.025648 -153.340816) (xy 130.026248 -153.351862) (xy 130.035589 -153.371884)
			(xy 130.043682 -153.379424) (xy 130.064404 -153.397623) (xy 130.100875 -153.438994) (xy 130.131006 -153.485186)
			(xy 130.15417 -153.535237) (xy 130.169883 -153.588102) (xy 130.177819 -153.642678) (xy 130.177853 -153.6446)
			(xy 134.76681 -153.6446) (xy 134.770881 -153.588978) (xy 134.783007 -153.534541) (xy 134.80293 -153.48245)
			(xy 134.830226 -153.433815) (xy 134.864312 -153.389672) (xy 134.904461 -153.350963) (xy 134.949819 -153.318512)
			(xy 134.999419 -153.293011) (xy 135.052203 -153.275004) (xy 135.107046 -153.264874) (xy 135.16278 -153.262837)
			(xy 135.218217 -153.268937) (xy 135.272174 -153.283043) (xy 135.323503 -153.304855) (xy 135.371109 -153.333909)
			(xy 135.413977 -153.369584) (xy 135.451194 -153.411121) (xy 135.481967 -153.457634) (xy 135.505639 -153.508131)
			(xy 135.521707 -153.561538) (xy 135.529827 -153.616714) (xy 135.530336 -153.6446) (xy 135.529827 -153.672486)
			(xy 135.521707 -153.727662) (xy 135.505639 -153.781069) (xy 135.481967 -153.831566) (xy 135.451194 -153.878079)
			(xy 135.413977 -153.919616) (xy 135.371109 -153.955291) (xy 135.323503 -153.984345) (xy 135.272174 -154.006157)
			(xy 135.218217 -154.020263) (xy 135.16278 -154.026363) (xy 135.107046 -154.024326) (xy 135.052203 -154.014196)
			(xy 134.999419 -153.996189) (xy 134.949819 -153.970688) (xy 134.904461 -153.938237) (xy 134.864312 -153.899528)
			(xy 134.830226 -153.855385) (xy 134.80293 -153.80675) (xy 134.783007 -153.754659) (xy 134.770881 -153.700222)
			(xy 134.76681 -153.6446) (xy 130.177853 -153.6446) (xy 130.178302 -153.670254) (xy 130.177802 -153.697506)
			(xy 130.170051 -153.751456) (xy 130.154701 -153.803753) (xy 130.132063 -153.853334) (xy 130.102599 -153.899187)
			(xy 130.066909 -153.940381) (xy 130.02572 -153.976075) (xy 129.979869 -154.005544) (xy 129.930291 -154.028187)
			(xy 129.877995 -154.043543) (xy 129.824046 -154.051299) (xy 129.796794 -154.051762) (xy 129.796286 -154.051762)
			(xy 129.762504 -154.050238) (xy 129.752344 -154.049222) (xy 129.73304 -154.055318) (xy 129.670048 -154.10815)
			(xy 129.66275 -154.114866) (xy 129.653475 -154.132376) (xy 129.652014 -154.142186) (xy 129.652014 -154.142948)
			(xy 129.649063 -154.171109) (xy 129.635856 -154.22617) (xy 129.614653 -154.278673) (xy 129.58592 -154.327463)
			(xy 129.550289 -154.37147) (xy 129.508544 -154.409724) (xy 129.461601 -154.441386) (xy 129.410493 -154.46576)
			(xy 129.356343 -154.48231) (xy 129.300341 -154.490671) (xy 129.27203 -154.491182) (xy 129.254011 -154.490966)
			(xy 129.218136 -154.487528) (xy 129.200402 -154.484324) (xy 129.19075 -154.482546) (xy 129.1717 -154.486102)
			(xy 129.09677 -154.534108) (xy 129.08534 -154.549856) (xy 129.083054 -154.559254) (xy 129.075689 -154.586308)
			(xy 129.054056 -154.638036) (xy 129.025088 -154.686042) (xy 128.989409 -154.729294) (xy 128.947785 -154.766861)
			(xy 128.901113 -154.797934) (xy 128.850398 -154.821844) (xy 128.79673 -154.838078) (xy 128.741265 -154.846285)
			(xy 128.71323 -154.846782) (xy 128.685977 -154.846317) (xy 128.632024 -154.838563) (xy 128.579725 -154.82321)
			(xy 128.530143 -154.800569) (xy 128.484289 -154.771101) (xy 128.443095 -154.735408) (xy 128.407401 -154.694214)
			(xy 128.377933 -154.64836) (xy 128.355292 -154.598779) (xy 128.339938 -154.546479) (xy 128.332184 -154.492527)
			(xy 128.331722 -154.465274) (xy 97.117408 -154.465274) (xy 97.117408 -155.94076) (xy 129.92354 -155.94076)
			(xy 129.924033 -155.913186) (xy 129.931978 -155.858614) (xy 129.947697 -155.805754) (xy 129.970862 -155.755708)
			(xy 130.00099 -155.709517) (xy 130.037454 -155.668146) (xy 130.05816 -155.64993) (xy 130.066231 -155.642372)
			(xy 130.075585 -155.622362) (xy 130.076194 -155.611322) (xy 130.076194 -155.533598) (xy 130.075573 -155.522555)
			(xy 130.066245 -155.502534) (xy 130.05816 -155.49499) (xy 130.037433 -155.476797) (xy 130.000965 -155.435423)
			(xy 129.970836 -155.389229) (xy 129.947674 -155.339178) (xy 129.93196 -155.286313) (xy 129.924024 -155.231736)
			(xy 129.92354 -155.20416) (xy 129.923989 -155.177973) (xy 129.93117 -155.126093) (xy 129.945377 -155.075683)
			(xy 129.966344 -155.027688) (xy 129.993677 -154.983012) (xy 130.026862 -154.942493) (xy 130.065276 -154.906892)
			(xy 130.108198 -154.876878) (xy 130.131312 -154.864562) (xy 130.140139 -154.859448) (xy 130.153105 -154.843718)
			(xy 130.156458 -154.834082) (xy 130.180842 -154.754072) (xy 130.178556 -154.733752) (xy 130.173476 -154.724608)
			(xy 130.158654 -154.6967) (xy 130.137613 -154.63712) (xy 130.126918 -154.574845) (xy 130.126232 -154.543252)
			(xy 130.126232 -154.542744) (xy 130.126675 -154.516125) (xy 130.134247 -154.463428) (xy 130.149242 -154.412346)
			(xy 130.171355 -154.363918) (xy 130.200137 -154.31913) (xy 130.235 -154.278896) (xy 130.275235 -154.244033)
			(xy 130.320023 -154.215252) (xy 130.368451 -154.19314) (xy 130.419534 -154.178145) (xy 130.472231 -154.170575)
			(xy 130.49885 -154.170126) (xy 130.525272 -154.170572) (xy 130.577587 -154.178028) (xy 130.628325 -154.192796)
			(xy 130.676469 -154.214582) (xy 130.721054 -154.242948) (xy 130.74142 -154.259788) (xy 130.748278 -154.26563)
			(xy 130.765296 -154.27198) (xy 130.849624 -154.27198) (xy 130.866642 -154.26563) (xy 130.8735 -154.259788)
			(xy 130.893866 -154.242949) (xy 130.938452 -154.214584) (xy 130.986596 -154.192797) (xy 131.037333 -154.178026)
			(xy 131.089648 -154.170566) (xy 131.142492 -154.170566) (xy 131.194807 -154.178026) (xy 131.245544 -154.192797)
			(xy 131.293688 -154.214584) (xy 131.338274 -154.242949) (xy 131.35864 -154.259788) (xy 131.365498 -154.26563)
			(xy 131.382516 -154.27198) (xy 131.466844 -154.27198) (xy 131.483862 -154.26563) (xy 131.49072 -154.259788)
			(xy 131.511077 -154.242939) (xy 131.555669 -154.214586) (xy 131.603816 -154.192809) (xy 131.654554 -154.178044)
			(xy 131.706869 -154.170586) (xy 131.73329 -154.170126) (xy 131.761181 -154.170532) (xy 131.816339 -154.178845)
			(xy 131.869642 -154.195285) (xy 131.919899 -154.219487) (xy 131.965988 -154.250909) (xy 132.006879 -154.288849)
			(xy 132.041659 -154.33246) (xy 132.048975 -154.345132) (xy 136.69086 -154.345132) (xy 136.694931 -154.28951)
			(xy 136.707057 -154.235073) (xy 136.72698 -154.182982) (xy 136.754276 -154.134347) (xy 136.788362 -154.090204)
			(xy 136.828511 -154.051495) (xy 136.873869 -154.019044) (xy 136.923469 -153.993543) (xy 136.976253 -153.975536)
			(xy 137.031096 -153.965406) (xy 137.08683 -153.963369) (xy 137.142267 -153.969469) (xy 137.196224 -153.983575)
			(xy 137.247553 -154.005387) (xy 137.295159 -154.034441) (xy 137.338027 -154.070116) (xy 137.375244 -154.111653)
			(xy 137.406017 -154.158166) (xy 137.429689 -154.208663) (xy 137.445757 -154.26207) (xy 137.453877 -154.317246)
			(xy 137.454386 -154.345132) (xy 137.453877 -154.373018) (xy 137.445757 -154.428194) (xy 137.429689 -154.481601)
			(xy 137.406017 -154.532098) (xy 137.375244 -154.578611) (xy 137.338027 -154.620148) (xy 137.295159 -154.655823)
			(xy 137.247553 -154.684877) (xy 137.196224 -154.706689) (xy 137.142267 -154.720795) (xy 137.08683 -154.726895)
			(xy 137.031096 -154.724858) (xy 136.976253 -154.714728) (xy 136.923469 -154.696721) (xy 136.873869 -154.67122)
			(xy 136.828511 -154.638769) (xy 136.788362 -154.60006) (xy 136.754276 -154.555917) (xy 136.72698 -154.507282)
			(xy 136.707057 -154.455191) (xy 136.694931 -154.400754) (xy 136.69086 -154.345132) (xy 132.048975 -154.345132)
			(xy 132.06955 -154.380767) (xy 132.089929 -154.432692) (xy 132.102342 -154.487075) (xy 132.106511 -154.5427)
			(xy 132.102342 -154.598325) (xy 132.089929 -154.652708) (xy 132.06955 -154.704633) (xy 132.041659 -154.75294)
			(xy 132.006879 -154.796551) (xy 131.965988 -154.834491) (xy 131.919899 -154.865913) (xy 131.869642 -154.890115)
			(xy 131.816339 -154.906555) (xy 131.761181 -154.914868) (xy 131.73329 -154.915362) (xy 131.706869 -154.914895)
			(xy 131.654554 -154.907445) (xy 131.603816 -154.892682) (xy 131.555672 -154.8709) (xy 131.511086 -154.842538)
			(xy 131.49072 -154.8257) (xy 131.483862 -154.819858) (xy 131.466844 -154.813508) (xy 131.382516 -154.813508)
			(xy 131.365498 -154.819858) (xy 131.35864 -154.8257) (xy 131.338274 -154.842539) (xy 131.293688 -154.870904)
			(xy 131.245544 -154.892691) (xy 131.194807 -154.907462) (xy 131.142492 -154.914922) (xy 131.089648 -154.914922)
			(xy 131.037333 -154.907462) (xy 130.986596 -154.892691) (xy 130.938452 -154.870904) (xy 130.893866 -154.842539)
			(xy 130.8735 -154.8257) (xy 130.866642 -154.819858) (xy 130.849624 -154.813508) (xy 130.765296 -154.813508)
			(xy 130.748278 -154.819858) (xy 130.74142 -154.8257) (xy 130.725853 -154.838706) (xy 130.692378 -154.861619)
			(xy 130.674618 -154.87142) (xy 130.665474 -154.876246) (xy 130.65252 -154.892248) (xy 130.62966 -154.972512)
			(xy 130.627365 -154.9825) (xy 130.629979 -155.002807) (xy 130.63474 -155.011882) (xy 130.63474 -155.012136)
			(xy 130.647068 -155.034075) (xy 130.666446 -155.08052) (xy 130.679551 -155.129108) (xy 130.686158 -155.178997)
			(xy 130.686556 -155.20416) (xy 130.686078 -155.231734) (xy 130.67813 -155.286307) (xy 130.662409 -155.339168)
			(xy 130.639241 -155.389214) (xy 130.60911 -155.435404) (xy 130.572643 -155.476775) (xy 130.551936 -155.49499)
			(xy 130.543855 -155.502539) (xy 130.534924 -155.52166) (xy 135.725662 -155.52166) (xy 135.726138 -155.493749)
			(xy 135.734277 -155.438522) (xy 135.750377 -155.385072) (xy 135.774094 -155.334537) (xy 135.80492 -155.287998)
			(xy 135.823198 -155.266898) (xy 135.829095 -155.259721) (xy 135.835746 -155.242396) (xy 135.836152 -155.233116)
			(xy 135.836152 -155.155392) (xy 135.829548 -155.13812) (xy 135.823198 -155.131008) (xy 135.804902 -155.109923)
			(xy 135.774077 -155.063381) (xy 135.750365 -155.012842) (xy 135.734273 -154.959388) (xy 135.726144 -154.904158)
			(xy 135.725662 -154.876246) (xy 135.726148 -154.848995) (xy 135.733904 -154.795047) (xy 135.749259 -154.742752)
			(xy 135.771901 -154.693175) (xy 135.801367 -154.647325) (xy 135.837058 -154.606134) (xy 135.878249 -154.570443)
			(xy 135.924099 -154.540977) (xy 135.973676 -154.518335) (xy 136.025971 -154.50298) (xy 136.079919 -154.495224)
			(xy 136.134421 -154.495224) (xy 136.188369 -154.50298) (xy 136.240664 -154.518335) (xy 136.290241 -154.540977)
			(xy 136.336091 -154.570443) (xy 136.377282 -154.606134) (xy 136.412973 -154.647325) (xy 136.442439 -154.693175)
			(xy 136.465081 -154.742752) (xy 136.480436 -154.795047) (xy 136.488192 -154.848995) (xy 136.488678 -154.876246)
			(xy 136.488196 -154.904157) (xy 136.480056 -154.959383) (xy 136.463957 -155.012833) (xy 136.440243 -155.063367)
			(xy 136.409418 -155.109907) (xy 136.391142 -155.131008) (xy 136.385235 -155.138178) (xy 136.378592 -155.155509)
			(xy 136.378188 -155.16479) (xy 136.378188 -155.242514) (xy 136.384792 -155.259786) (xy 136.391142 -155.266898)
			(xy 136.4094 -155.288014) (xy 136.440229 -155.334549) (xy 136.463947 -155.385079) (xy 136.480049 -155.438527)
			(xy 136.488189 -155.49375) (xy 136.488678 -155.52166) (xy 136.488192 -155.548911) (xy 136.480436 -155.602859)
			(xy 136.465081 -155.655154) (xy 136.442439 -155.704731) (xy 136.412973 -155.750581) (xy 136.377282 -155.791772)
			(xy 136.336091 -155.827463) (xy 136.290241 -155.856929) (xy 136.240664 -155.879571) (xy 136.188369 -155.894926)
			(xy 136.134421 -155.902682) (xy 136.079919 -155.902682) (xy 136.025971 -155.894926) (xy 135.973676 -155.879571)
			(xy 135.924099 -155.856929) (xy 135.878249 -155.827463) (xy 135.837058 -155.791772) (xy 135.801367 -155.750581)
			(xy 135.771901 -155.704731) (xy 135.749259 -155.655154) (xy 135.733904 -155.602859) (xy 135.726148 -155.548911)
			(xy 135.725662 -155.52166) (xy 130.534924 -155.52166) (xy 130.534506 -155.522556) (xy 130.533902 -155.533598)
			(xy 130.533902 -155.611322) (xy 130.534513 -155.622366) (xy 130.543848 -155.642388) (xy 130.551936 -155.64993)
			(xy 130.572672 -155.668114) (xy 130.609139 -155.709489) (xy 130.639267 -155.755685) (xy 130.662428 -155.805738)
			(xy 130.67814 -155.858605) (xy 130.686074 -155.913184) (xy 130.686556 -155.94076) (xy 130.68607 -155.968011)
			(xy 130.678314 -156.021959) (xy 130.662959 -156.074254) (xy 130.640317 -156.123831) (xy 130.610851 -156.169681)
			(xy 130.57516 -156.210872) (xy 130.533969 -156.246563) (xy 130.488119 -156.276029) (xy 130.438542 -156.298671)
			(xy 130.386247 -156.314026) (xy 130.332299 -156.321782) (xy 130.277797 -156.321782) (xy 130.223849 -156.314026)
			(xy 130.171554 -156.298671) (xy 130.121977 -156.276029) (xy 130.076127 -156.246563) (xy 130.034936 -156.210872)
			(xy 129.999245 -156.169681) (xy 129.969779 -156.123831) (xy 129.947137 -156.074254) (xy 129.931782 -156.021959)
			(xy 129.924026 -155.968011) (xy 129.92354 -155.94076) (xy 97.117408 -155.94076) (xy 97.117408 -160.852612)
			(xy 123.659646 -160.852612) (xy 123.660132 -160.825361) (xy 123.667888 -160.771413) (xy 123.683243 -160.719118)
			(xy 123.705885 -160.669541) (xy 123.735351 -160.623691) (xy 123.771042 -160.5825) (xy 123.812233 -160.546809)
			(xy 123.858083 -160.517343) (xy 123.90766 -160.494701) (xy 123.959955 -160.479346) (xy 124.013903 -160.47159)
			(xy 124.068405 -160.47159) (xy 124.122353 -160.479346) (xy 124.174648 -160.494701) (xy 124.224225 -160.517343)
			(xy 124.270075 -160.546809) (xy 124.311266 -160.5825) (xy 124.346957 -160.623691) (xy 124.376423 -160.669541)
			(xy 124.399065 -160.719118) (xy 124.403731 -160.73501) (xy 125.549914 -160.73501) (xy 125.5504 -160.707759)
			(xy 125.558156 -160.653811) (xy 125.573511 -160.601516) (xy 125.596153 -160.551939) (xy 125.625619 -160.506089)
			(xy 125.66131 -160.464898) (xy 125.702501 -160.429207) (xy 125.748351 -160.399741) (xy 125.797928 -160.377099)
			(xy 125.850223 -160.361744) (xy 125.904171 -160.353988) (xy 125.958673 -160.353988) (xy 126.012621 -160.361744)
			(xy 126.064916 -160.377099) (xy 126.114493 -160.399741) (xy 126.160343 -160.429207) (xy 126.201534 -160.464898)
			(xy 126.237225 -160.506089) (xy 126.266691 -160.551939) (xy 126.289333 -160.601516) (xy 126.304688 -160.653811)
			(xy 126.312444 -160.707759) (xy 126.31293 -160.73501) (xy 126.312484 -160.761804) (xy 126.304979 -160.814864)
			(xy 126.290129 -160.866354) (xy 126.268229 -160.915263) (xy 126.239707 -160.960631) (xy 126.22276 -160.98139)
			(xy 126.216664 -160.988502) (xy 126.210822 -161.00552) (xy 126.212092 -161.081974) (xy 126.212641 -161.091144)
			(xy 126.219401 -161.108207) (xy 126.2253 -161.115248) (xy 126.243886 -161.136439) (xy 126.275271 -161.183257)
			(xy 126.299425 -161.234183) (xy 126.315825 -161.288108) (xy 126.324111 -161.34386) (xy 126.324614 -161.372042)
			(xy 126.324128 -161.399293) (xy 126.322495 -161.41065) (xy 126.88773 -161.41065) (xy 126.891801 -161.355028)
			(xy 126.903927 -161.300591) (xy 126.92385 -161.2485) (xy 126.951146 -161.199865) (xy 126.985232 -161.155722)
			(xy 127.025381 -161.117013) (xy 127.070739 -161.084562) (xy 127.120339 -161.059061) (xy 127.173123 -161.041054)
			(xy 127.227966 -161.030924) (xy 127.2837 -161.028887) (xy 127.339137 -161.034987) (xy 127.393094 -161.049093)
			(xy 127.444423 -161.070905) (xy 127.492029 -161.099959) (xy 127.534897 -161.135634) (xy 127.572114 -161.177171)
			(xy 127.602887 -161.223684) (xy 127.626559 -161.274181) (xy 127.642627 -161.327588) (xy 127.650747 -161.382764)
			(xy 127.651256 -161.41065) (xy 127.650747 -161.438536) (xy 127.642627 -161.493712) (xy 127.626559 -161.547119)
			(xy 127.602887 -161.597616) (xy 127.572114 -161.644129) (xy 127.534897 -161.685666) (xy 127.492029 -161.721341)
			(xy 127.444423 -161.750395) (xy 127.393094 -161.772207) (xy 127.339137 -161.786313) (xy 127.2837 -161.792413)
			(xy 127.227966 -161.790376) (xy 127.173123 -161.780246) (xy 127.120339 -161.762239) (xy 127.070739 -161.736738)
			(xy 127.025381 -161.704287) (xy 126.985232 -161.665578) (xy 126.951146 -161.621435) (xy 126.92385 -161.5728)
			(xy 126.903927 -161.520709) (xy 126.891801 -161.466272) (xy 126.88773 -161.41065) (xy 126.322495 -161.41065)
			(xy 126.316372 -161.453241) (xy 126.301017 -161.505536) (xy 126.278375 -161.555113) (xy 126.248909 -161.600963)
			(xy 126.213218 -161.642154) (xy 126.172027 -161.677845) (xy 126.126177 -161.707311) (xy 126.0766 -161.729953)
			(xy 126.024305 -161.745308) (xy 125.970357 -161.753064) (xy 125.915855 -161.753064) (xy 125.861907 -161.745308)
			(xy 125.809612 -161.729953) (xy 125.760035 -161.707311) (xy 125.714185 -161.677845) (xy 125.672994 -161.642154)
			(xy 125.637303 -161.600963) (xy 125.607837 -161.555113) (xy 125.585195 -161.505536) (xy 125.56984 -161.453241)
			(xy 125.562084 -161.399293) (xy 125.561598 -161.372042) (xy 125.562067 -161.345249) (xy 125.569567 -161.292189)
			(xy 125.58441 -161.240699) (xy 125.606306 -161.19179) (xy 125.634823 -161.146422) (xy 125.651768 -161.125662)
			(xy 125.657864 -161.11855) (xy 125.663706 -161.101532) (xy 125.662436 -161.025078) (xy 125.661904 -161.015906)
			(xy 125.655131 -160.998844) (xy 125.649228 -160.991804) (xy 125.630608 -160.970642) (xy 125.59923 -160.923815)
			(xy 125.575084 -160.872882) (xy 125.558692 -160.81895) (xy 125.550413 -160.763194) (xy 125.549914 -160.73501)
			(xy 124.403731 -160.73501) (xy 124.41442 -160.771413) (xy 124.422176 -160.825361) (xy 124.422662 -160.852612)
			(xy 124.421996 -160.884175) (xy 124.411612 -160.94644) (xy 124.391129 -161.006149) (xy 124.376688 -161.034222)
			(xy 124.371862 -161.043112) (xy 124.36983 -161.06267) (xy 124.39269 -161.141156) (xy 124.39592 -161.150584)
			(xy 124.408344 -161.16614) (xy 124.41682 -161.171382) (xy 124.424186 -161.175446) (xy 124.434092 -161.181288)
			(xy 124.455936 -161.18332) (xy 124.550678 -161.149792) (xy 124.566426 -161.134298) (xy 124.57049 -161.123884)
			(xy 124.581169 -161.0971) (xy 124.609459 -161.046858) (xy 124.644992 -161.001449) (xy 124.686956 -160.961907)
			(xy 124.734396 -160.929134) (xy 124.786229 -160.903877) (xy 124.841274 -160.886713) (xy 124.898276 -160.878032)
			(xy 124.927106 -160.877504) (xy 124.954358 -160.877966) (xy 125.008307 -160.885724) (xy 125.060602 -160.90108)
			(xy 125.11018 -160.923722) (xy 125.156031 -160.953189) (xy 125.197222 -160.988882) (xy 125.232914 -161.030073)
			(xy 125.262381 -161.075925) (xy 125.285022 -161.125503) (xy 125.300378 -161.177799) (xy 125.308134 -161.231748)
			(xy 125.308134 -161.286252) (xy 125.300378 -161.340201) (xy 125.285022 -161.392497) (xy 125.262381 -161.442075)
			(xy 125.232914 -161.487927) (xy 125.197222 -161.529118) (xy 125.156031 -161.564811) (xy 125.11018 -161.594278)
			(xy 125.060602 -161.61692) (xy 125.008307 -161.632276) (xy 124.954358 -161.640034) (xy 124.927106 -161.64052)
			(xy 124.926852 -161.64052) (xy 124.901649 -161.640103) (xy 124.851681 -161.633469) (xy 124.803027 -161.620298)
			(xy 124.756536 -161.60082) (xy 124.734574 -161.58845) (xy 124.724668 -161.582608) (xy 124.702824 -161.580576)
			(xy 124.608082 -161.614104) (xy 124.592334 -161.629598) (xy 124.58827 -161.640012) (xy 124.577539 -161.666773)
			(xy 124.549255 -161.717013) (xy 124.51373 -161.762422) (xy 124.471773 -161.801965) (xy 124.424341 -161.83474)
			(xy 124.372515 -161.860001) (xy 124.317477 -161.877171) (xy 124.260481 -161.885859) (xy 124.231654 -161.886392)
			(xy 124.204401 -161.885965) (xy 124.15045 -161.878202) (xy 124.098153 -161.86284) (xy 124.048575 -161.840192)
			(xy 124.002724 -161.81072) (xy 123.961534 -161.775022) (xy 123.925843 -161.733826) (xy 123.896378 -161.687971)
			(xy 123.873738 -161.638388) (xy 123.858385 -161.586089) (xy 123.850631 -161.532137) (xy 123.850146 -161.504884)
			(xy 123.850809 -161.473321) (xy 123.861194 -161.411056) (xy 123.881679 -161.351347) (xy 123.89612 -161.323274)
			(xy 123.900946 -161.314384) (xy 123.902978 -161.294826) (xy 123.880118 -161.21634) (xy 123.876887 -161.206913)
			(xy 123.864463 -161.191357) (xy 123.855988 -161.186114) (xy 123.830862 -161.171606) (xy 123.78498 -161.136096)
			(xy 123.745007 -161.094045) (xy 123.711865 -161.046424) (xy 123.686318 -160.994333) (xy 123.668957 -160.938972)
			(xy 123.660182 -160.881621) (xy 123.659646 -160.852612) (xy 97.117408 -160.852612) (xy 97.117408 -163.126674)
			(xy 119.873522 -163.126674) (xy 119.874031 -163.099101) (xy 119.881974 -163.04453) (xy 119.89769 -162.99167)
			(xy 119.920851 -162.941624) (xy 119.950977 -162.895433) (xy 119.987438 -162.854061) (xy 120.008142 -162.835844)
			(xy 120.016205 -162.828278) (xy 120.025564 -162.808274) (xy 120.026176 -162.797236) (xy 120.026176 -162.719512)
			(xy 120.025609 -162.708462) (xy 120.016244 -162.688441) (xy 120.008142 -162.680904) (xy 119.987438 -162.662685)
			(xy 119.950965 -162.621319) (xy 119.920831 -162.575131) (xy 119.897664 -162.525084) (xy 119.881947 -162.472223)
			(xy 119.874007 -162.417648) (xy 119.873522 -162.390074) (xy 119.874031 -162.362501) (xy 119.881974 -162.30793)
			(xy 119.89769 -162.25507) (xy 119.920851 -162.205024) (xy 119.950977 -162.158833) (xy 119.987438 -162.117461)
			(xy 120.008142 -162.099244) (xy 120.016205 -162.091678) (xy 120.025564 -162.071674) (xy 120.026176 -162.060636)
			(xy 120.026176 -161.982912) (xy 120.025609 -161.971862) (xy 120.016244 -161.951841) (xy 120.008142 -161.944304)
			(xy 119.987438 -161.926085) (xy 119.950965 -161.884719) (xy 119.920831 -161.838531) (xy 119.897664 -161.788484)
			(xy 119.881947 -161.735623) (xy 119.874007 -161.681048) (xy 119.873522 -161.653474) (xy 119.873931 -161.626219)
			(xy 119.881692 -161.572265) (xy 119.897053 -161.519964) (xy 119.919701 -161.470382) (xy 119.949174 -161.424527)
			(xy 119.984874 -161.383334) (xy 120.026072 -161.347641) (xy 120.071931 -161.318174) (xy 120.121516 -161.295533)
			(xy 120.173819 -161.28018) (xy 120.227775 -161.272427) (xy 120.25503 -161.271966) (xy 120.282885 -161.272487)
			(xy 120.337999 -161.280614) (xy 120.391348 -161.296662) (xy 120.4418 -161.32029) (xy 120.488283 -161.350997)
			(xy 120.529812 -161.388132) (xy 120.565506 -161.430906) (xy 120.594606 -161.478412) (xy 120.616496 -161.529642)
			(xy 120.624092 -161.556446) (xy 120.626378 -161.565336) (xy 120.637046 -161.580576) (xy 120.708928 -161.628328)
			(xy 120.726962 -161.632392) (xy 120.736106 -161.631122) (xy 120.749123 -161.629454) (xy 120.775307 -161.627673)
			(xy 120.78843 -161.627566) (xy 120.802579 -161.627657) (xy 120.830802 -161.629693) (xy 120.844818 -161.63163)
			(xy 120.854724 -161.633154) (xy 120.874536 -161.628328) (xy 120.948958 -161.572448) (xy 120.959118 -161.554922)
			(xy 120.960388 -161.544762) (xy 120.964477 -161.517608) (xy 120.979449 -161.464778) (xy 121.00184 -161.414639)
			(xy 121.031187 -161.368228) (xy 121.066885 -161.326504) (xy 121.108194 -161.290327) (xy 121.154263 -161.260446)
			(xy 121.20414 -161.237477) (xy 121.256794 -161.221896) (xy 121.311138 -161.214024) (xy 121.338594 -161.213546)
			(xy 121.365843 -161.214083) (xy 121.419787 -161.221838) (xy 121.472077 -161.23719) (xy 121.521652 -161.259827)
			(xy 121.5675 -161.289288) (xy 121.608689 -161.324974) (xy 121.644381 -161.366158) (xy 121.673848 -161.412003)
			(xy 121.696492 -161.461574) (xy 121.711851 -161.513863) (xy 121.719613 -161.567805) (xy 121.720102 -161.595054)
			(xy 121.719604 -161.622627) (xy 121.711658 -161.677199) (xy 121.695939 -161.730058) (xy 121.672775 -161.780104)
			(xy 121.642649 -161.826294) (xy 121.606187 -161.867667) (xy 121.585482 -161.885884) (xy 121.577411 -161.893443)
			(xy 121.568055 -161.913452) (xy 121.567448 -161.924492) (xy 121.567448 -162.002216) (xy 121.568048 -162.013262)
			(xy 121.577389 -162.033284) (xy 121.585482 -162.040824) (xy 121.606204 -162.059023) (xy 121.642675 -162.100394)
			(xy 121.672806 -162.146586) (xy 121.69597 -162.196637) (xy 121.711683 -162.249502) (xy 121.719619 -162.304078)
			(xy 121.719653 -162.306) (xy 126.30861 -162.306) (xy 126.312681 -162.250378) (xy 126.324807 -162.195941)
			(xy 126.34473 -162.14385) (xy 126.372026 -162.095215) (xy 126.406112 -162.051072) (xy 126.446261 -162.012363)
			(xy 126.491619 -161.979912) (xy 126.541219 -161.954411) (xy 126.594003 -161.936404) (xy 126.648846 -161.926274)
			(xy 126.70458 -161.924237) (xy 126.760017 -161.930337) (xy 126.813974 -161.944443) (xy 126.865303 -161.966255)
			(xy 126.912909 -161.995309) (xy 126.955777 -162.030984) (xy 126.992994 -162.072521) (xy 127.023767 -162.119034)
			(xy 127.047439 -162.169531) (xy 127.063507 -162.222938) (xy 127.071627 -162.278114) (xy 127.072136 -162.306)
			(xy 127.071627 -162.333886) (xy 127.063507 -162.389062) (xy 127.047439 -162.442469) (xy 127.023767 -162.492966)
			(xy 126.992994 -162.539479) (xy 126.955777 -162.581016) (xy 126.912909 -162.616691) (xy 126.865303 -162.645745)
			(xy 126.813974 -162.667557) (xy 126.760017 -162.681663) (xy 126.70458 -162.687763) (xy 126.648846 -162.685726)
			(xy 126.594003 -162.675596) (xy 126.541219 -162.657589) (xy 126.491619 -162.632088) (xy 126.446261 -162.599637)
			(xy 126.406112 -162.560928) (xy 126.372026 -162.516785) (xy 126.34473 -162.46815) (xy 126.324807 -162.416059)
			(xy 126.312681 -162.361622) (xy 126.30861 -162.306) (xy 121.719653 -162.306) (xy 121.720102 -162.331654)
			(xy 121.719602 -162.358906) (xy 121.711851 -162.412856) (xy 121.696501 -162.465153) (xy 121.673863 -162.514734)
			(xy 121.644399 -162.560587) (xy 121.608709 -162.601781) (xy 121.56752 -162.637475) (xy 121.521669 -162.666944)
			(xy 121.472091 -162.689587) (xy 121.419795 -162.704943) (xy 121.365846 -162.712699) (xy 121.338594 -162.713162)
			(xy 121.338086 -162.713162) (xy 121.304304 -162.711638) (xy 121.294144 -162.710622) (xy 121.27484 -162.716718)
			(xy 121.211848 -162.76955) (xy 121.20455 -162.776266) (xy 121.195275 -162.793776) (xy 121.193814 -162.803586)
			(xy 121.193814 -162.804348) (xy 121.190863 -162.832509) (xy 121.177656 -162.88757) (xy 121.156453 -162.940073)
			(xy 121.12772 -162.988863) (xy 121.092089 -163.03287) (xy 121.050344 -163.071124) (xy 121.003401 -163.102786)
			(xy 120.952293 -163.12716) (xy 120.898143 -163.14371) (xy 120.842141 -163.152071) (xy 120.81383 -163.152582)
			(xy 120.795811 -163.152366) (xy 120.759936 -163.148928) (xy 120.742202 -163.145724) (xy 120.73255 -163.143946)
			(xy 120.7135 -163.147502) (xy 120.63857 -163.195508) (xy 120.62714 -163.211256) (xy 120.624854 -163.220654)
			(xy 120.617489 -163.247708) (xy 120.595856 -163.299436) (xy 120.566888 -163.347442) (xy 120.531209 -163.390694)
			(xy 120.489585 -163.428261) (xy 120.442913 -163.459334) (xy 120.392198 -163.483244) (xy 120.33853 -163.499478)
			(xy 120.283065 -163.507685) (xy 120.25503 -163.508182) (xy 120.227777 -163.507717) (xy 120.173824 -163.499963)
			(xy 120.121525 -163.48461) (xy 120.071943 -163.461969) (xy 120.026089 -163.432501) (xy 119.984895 -163.396808)
			(xy 119.949201 -163.355614) (xy 119.919733 -163.30976) (xy 119.897092 -163.260179) (xy 119.881738 -163.207879)
			(xy 119.873984 -163.153927) (xy 119.873522 -163.126674) (xy 97.117408 -163.126674) (xy 97.117408 -164.62756)
			(xy 121.49074 -164.62756) (xy 121.491233 -164.599986) (xy 121.499178 -164.545414) (xy 121.514897 -164.492554)
			(xy 121.538062 -164.442508) (xy 121.56819 -164.396317) (xy 121.604654 -164.354946) (xy 121.62536 -164.33673)
			(xy 121.633431 -164.329172) (xy 121.642785 -164.309162) (xy 121.643394 -164.298122) (xy 121.643394 -164.220398)
			(xy 121.642773 -164.209355) (xy 121.633445 -164.189334) (xy 121.62536 -164.18179) (xy 121.604633 -164.163597)
			(xy 121.568165 -164.122223) (xy 121.538036 -164.076029) (xy 121.514874 -164.025978) (xy 121.49916 -163.973113)
			(xy 121.491224 -163.918536) (xy 121.49074 -163.89096) (xy 121.491336 -163.861514) (xy 121.500398 -163.803322)
			(xy 121.518285 -163.747211) (xy 121.544574 -163.694511) (xy 121.578641 -163.646472) (xy 121.619678 -163.604231)
			(xy 121.666714 -163.56879) (xy 121.692416 -163.55441) (xy 121.701814 -163.54933) (xy 121.715022 -163.532566)
			(xy 121.738898 -163.43884) (xy 121.735342 -163.418012) (xy 121.7295 -163.409122) (xy 121.714965 -163.386192)
			(xy 121.691987 -163.337005) (xy 121.676395 -163.285003) (xy 121.668519 -163.231289) (xy 121.668032 -163.204144)
			(xy 121.668475 -163.177525) (xy 121.676047 -163.124828) (xy 121.691042 -163.073746) (xy 121.713155 -163.025318)
			(xy 121.741937 -162.98053) (xy 121.7768 -162.940296) (xy 121.817035 -162.905433) (xy 121.861823 -162.876652)
			(xy 121.910251 -162.85454) (xy 121.961334 -162.839545) (xy 122.014031 -162.831975) (xy 122.04065 -162.831526)
			(xy 122.067072 -162.831972) (xy 122.119387 -162.839428) (xy 122.170125 -162.854196) (xy 122.218269 -162.875982)
			(xy 122.262854 -162.904348) (xy 122.28322 -162.921188) (xy 122.290078 -162.92703) (xy 122.307096 -162.93338)
			(xy 122.391424 -162.93338) (xy 122.408442 -162.92703) (xy 122.4153 -162.921188) (xy 122.435666 -162.904349)
			(xy 122.480252 -162.875984) (xy 122.528396 -162.854197) (xy 122.579133 -162.839426) (xy 122.631448 -162.831966)
			(xy 122.684292 -162.831966) (xy 122.736607 -162.839426) (xy 122.787344 -162.854197) (xy 122.835488 -162.875984)
			(xy 122.880074 -162.904349) (xy 122.90044 -162.921188) (xy 122.907298 -162.92703) (xy 122.924316 -162.93338)
			(xy 123.008644 -162.93338) (xy 123.025662 -162.92703) (xy 123.03252 -162.921188) (xy 123.052877 -162.904339)
			(xy 123.097469 -162.875986) (xy 123.145616 -162.854209) (xy 123.196354 -162.839444) (xy 123.248669 -162.831986)
			(xy 123.27509 -162.831526) (xy 123.302981 -162.831932) (xy 123.358139 -162.840245) (xy 123.411442 -162.856685)
			(xy 123.461699 -162.880887) (xy 123.507788 -162.912309) (xy 123.548679 -162.950249) (xy 123.583459 -162.99386)
			(xy 123.61135 -163.042167) (xy 123.631729 -163.094092) (xy 123.644142 -163.148475) (xy 123.648311 -163.2041)
			(xy 123.644142 -163.259725) (xy 123.631729 -163.314108) (xy 123.61135 -163.366033) (xy 123.583459 -163.41434)
			(xy 123.548679 -163.457951) (xy 123.507788 -163.495891) (xy 123.461699 -163.527313) (xy 123.411442 -163.551515)
			(xy 123.358139 -163.567955) (xy 123.302981 -163.576268) (xy 123.27509 -163.576762) (xy 123.248669 -163.576295)
			(xy 123.196354 -163.568845) (xy 123.145616 -163.554082) (xy 123.097472 -163.5323) (xy 123.052886 -163.503938)
			(xy 123.03252 -163.4871) (xy 123.025662 -163.481258) (xy 123.008644 -163.474908) (xy 122.924316 -163.474908)
			(xy 122.907298 -163.481258) (xy 122.90044 -163.4871) (xy 122.880074 -163.503939) (xy 122.835488 -163.532304)
			(xy 122.787344 -163.554091) (xy 122.736607 -163.568862) (xy 122.684292 -163.576322) (xy 122.631448 -163.576322)
			(xy 122.579133 -163.568862) (xy 122.528396 -163.554091) (xy 122.480252 -163.532304) (xy 122.435666 -163.503939)
			(xy 122.4153 -163.4871) (xy 122.408442 -163.481258) (xy 122.391424 -163.474908) (xy 122.307096 -163.474908)
			(xy 122.290078 -163.481258) (xy 122.28322 -163.4871) (xy 122.268829 -163.499111) (xy 122.238035 -163.520486)
			(xy 122.221752 -163.529772) (xy 122.212688 -163.535318) (xy 122.199934 -163.552292) (xy 122.197114 -163.562538)
			(xy 122.177302 -163.646104) (xy 122.181112 -163.666678) (xy 122.187208 -163.675568) (xy 122.187208 -163.676076)
			(xy 122.202908 -163.69994) (xy 122.227774 -163.751363) (xy 122.244676 -163.805925) (xy 122.253234 -163.8624)
			(xy 122.253756 -163.89096) (xy 122.253278 -163.918534) (xy 122.24533 -163.973107) (xy 122.229609 -164.025968)
			(xy 122.206441 -164.076014) (xy 122.17631 -164.122204) (xy 122.139843 -164.163575) (xy 122.119136 -164.18179)
			(xy 122.117776 -164.18306) (xy 127.267462 -164.18306) (xy 127.267938 -164.155149) (xy 127.276077 -164.099922)
			(xy 127.292177 -164.046472) (xy 127.315894 -163.995937) (xy 127.34672 -163.949398) (xy 127.364998 -163.928298)
			(xy 127.370895 -163.921121) (xy 127.377546 -163.903796) (xy 127.377952 -163.894516) (xy 127.377952 -163.816792)
			(xy 127.371348 -163.79952) (xy 127.364998 -163.792408) (xy 127.346702 -163.771323) (xy 127.315877 -163.724781)
			(xy 127.292165 -163.674242) (xy 127.276073 -163.620788) (xy 127.267944 -163.565558) (xy 127.267462 -163.537646)
			(xy 127.267948 -163.510395) (xy 127.275704 -163.456447) (xy 127.291059 -163.404152) (xy 127.313701 -163.354575)
			(xy 127.343167 -163.308725) (xy 127.378858 -163.267534) (xy 127.420049 -163.231843) (xy 127.465899 -163.202377)
			(xy 127.515476 -163.179735) (xy 127.567771 -163.16438) (xy 127.621719 -163.156624) (xy 127.676221 -163.156624)
			(xy 127.730169 -163.16438) (xy 127.782464 -163.179735) (xy 127.832041 -163.202377) (xy 127.877891 -163.231843)
			(xy 127.919082 -163.267534) (xy 127.954773 -163.308725) (xy 127.984239 -163.354575) (xy 128.006881 -163.404152)
			(xy 128.022236 -163.456447) (xy 128.029992 -163.510395) (xy 128.030478 -163.537646) (xy 128.029996 -163.565557)
			(xy 128.021856 -163.620783) (xy 128.005757 -163.674233) (xy 127.982043 -163.724767) (xy 127.951218 -163.771307)
			(xy 127.932942 -163.792408) (xy 127.927035 -163.799578) (xy 127.920392 -163.816909) (xy 127.919988 -163.82619)
			(xy 127.919988 -163.903914) (xy 127.926592 -163.921186) (xy 127.932942 -163.928298) (xy 127.9512 -163.949414)
			(xy 127.982029 -163.995949) (xy 128.005747 -164.046479) (xy 128.021849 -164.099927) (xy 128.029989 -164.15515)
			(xy 128.030478 -164.18306) (xy 128.029992 -164.210311) (xy 128.022236 -164.264259) (xy 128.006881 -164.316554)
			(xy 127.984239 -164.366131) (xy 127.954773 -164.411981) (xy 127.919082 -164.453172) (xy 127.877891 -164.488863)
			(xy 127.832041 -164.518329) (xy 127.782464 -164.540971) (xy 127.730169 -164.556326) (xy 127.676221 -164.564082)
			(xy 127.621719 -164.564082) (xy 127.567771 -164.556326) (xy 127.515476 -164.540971) (xy 127.465899 -164.518329)
			(xy 127.420049 -164.488863) (xy 127.378858 -164.453172) (xy 127.343167 -164.411981) (xy 127.313701 -164.366131)
			(xy 127.291059 -164.316554) (xy 127.275704 -164.264259) (xy 127.267948 -164.210311) (xy 127.267462 -164.18306)
			(xy 122.117776 -164.18306) (xy 122.111055 -164.189339) (xy 122.101706 -164.209356) (xy 122.101102 -164.220398)
			(xy 122.101102 -164.298122) (xy 122.101713 -164.309166) (xy 122.111048 -164.329188) (xy 122.119136 -164.33673)
			(xy 122.139872 -164.354914) (xy 122.176339 -164.396289) (xy 122.206467 -164.442485) (xy 122.229628 -164.492538)
			(xy 122.24534 -164.545405) (xy 122.253274 -164.599984) (xy 122.253756 -164.62756) (xy 122.25327 -164.654811)
			(xy 122.245514 -164.708759) (xy 122.230159 -164.761054) (xy 122.207517 -164.810631) (xy 122.178051 -164.856481)
			(xy 122.14236 -164.897672) (xy 122.101169 -164.933363) (xy 122.055319 -164.962829) (xy 122.005742 -164.985471)
			(xy 121.953447 -165.000826) (xy 121.899499 -165.008582) (xy 121.844997 -165.008582) (xy 121.791049 -165.000826)
			(xy 121.738754 -164.985471) (xy 121.689177 -164.962829) (xy 121.643327 -164.933363) (xy 121.602136 -164.897672)
			(xy 121.566445 -164.856481) (xy 121.536979 -164.810631) (xy 121.514337 -164.761054) (xy 121.498982 -164.708759)
			(xy 121.491226 -164.654811) (xy 121.49074 -164.62756) (xy 97.117408 -164.62756) (xy 97.117408 -167.583612)
			(xy 115.379246 -167.583612) (xy 115.379732 -167.556361) (xy 115.387488 -167.502413) (xy 115.402843 -167.450118)
			(xy 115.425485 -167.400541) (xy 115.454951 -167.354691) (xy 115.490642 -167.3135) (xy 115.531833 -167.277809)
			(xy 115.577683 -167.248343) (xy 115.62726 -167.225701) (xy 115.679555 -167.210346) (xy 115.733503 -167.20259)
			(xy 115.788005 -167.20259) (xy 115.841953 -167.210346) (xy 115.894248 -167.225701) (xy 115.943825 -167.248343)
			(xy 115.989675 -167.277809) (xy 116.030866 -167.3135) (xy 116.066557 -167.354691) (xy 116.096023 -167.400541)
			(xy 116.118665 -167.450118) (xy 116.13402 -167.502413) (xy 116.141776 -167.556361) (xy 116.142262 -167.583612)
			(xy 116.141596 -167.615175) (xy 116.131212 -167.67744) (xy 116.110729 -167.737149) (xy 116.096288 -167.765222)
			(xy 116.091462 -167.774112) (xy 116.08943 -167.79367) (xy 116.11229 -167.872156) (xy 116.11552 -167.881584)
			(xy 116.127944 -167.89714) (xy 116.13642 -167.902382) (xy 116.143786 -167.906446) (xy 116.153692 -167.912288)
			(xy 116.175536 -167.91432) (xy 116.270278 -167.880792) (xy 116.286026 -167.865298) (xy 116.29009 -167.854884)
			(xy 116.300769 -167.8281) (xy 116.329059 -167.777858) (xy 116.364592 -167.732449) (xy 116.406556 -167.692907)
			(xy 116.453996 -167.660134) (xy 116.505829 -167.634877) (xy 116.560874 -167.617713) (xy 116.617876 -167.609032)
			(xy 116.646706 -167.608504) (xy 116.673958 -167.608966) (xy 116.727907 -167.616724) (xy 116.780202 -167.63208)
			(xy 116.82978 -167.654722) (xy 116.875631 -167.684189) (xy 116.916822 -167.719882) (xy 116.952514 -167.761073)
			(xy 116.981981 -167.806925) (xy 117.004622 -167.856503) (xy 117.019978 -167.908799) (xy 117.027734 -167.962748)
			(xy 117.027734 -168.017252) (xy 117.019978 -168.071201) (xy 117.010628 -168.103042) (xy 117.269514 -168.103042)
			(xy 117.270022 -168.075568) (xy 117.277908 -168.021189) (xy 117.293523 -167.968507) (xy 117.316543 -167.918614)
			(xy 117.34649 -167.872544) (xy 117.364256 -167.851582) (xy 117.36451 -167.851328) (xy 117.370092 -167.844238)
			(xy 117.376341 -167.827324) (xy 117.376702 -167.818308) (xy 117.376702 -167.750744) (xy 117.376324 -167.741729)
			(xy 117.370091 -167.724812) (xy 117.36451 -167.717724) (xy 117.364002 -167.717216) (xy 117.34628 -167.69626)
			(xy 117.316396 -167.65023) (xy 117.293427 -167.600387) (xy 117.27785 -167.547764) (xy 117.269986 -167.49345)
			(xy 117.269514 -167.46601) (xy 117.27 -167.438759) (xy 117.277756 -167.384811) (xy 117.293111 -167.332516)
			(xy 117.315753 -167.282939) (xy 117.345219 -167.237089) (xy 117.38091 -167.195898) (xy 117.422101 -167.160207)
			(xy 117.467951 -167.130741) (xy 117.517528 -167.108099) (xy 117.569823 -167.092744) (xy 117.623771 -167.084988)
			(xy 117.678273 -167.084988) (xy 117.732221 -167.092744) (xy 117.784516 -167.108099) (xy 117.834093 -167.130741)
			(xy 117.879943 -167.160207) (xy 117.921134 -167.195898) (xy 117.956825 -167.237089) (xy 117.986291 -167.282939)
			(xy 118.008933 -167.332516) (xy 118.024288 -167.384811) (xy 118.032044 -167.438759) (xy 118.03253 -167.46601)
			(xy 118.032042 -167.493484) (xy 118.02415 -167.547864) (xy 118.008529 -167.600546) (xy 117.985505 -167.650439)
			(xy 117.955555 -167.696508) (xy 117.937788 -167.71747) (xy 117.937534 -167.717724) (xy 117.931923 -167.724794)
			(xy 117.925693 -167.741724) (xy 117.925342 -167.750744) (xy 117.925342 -167.818308) (xy 117.925686 -167.827326)
			(xy 117.931941 -167.844244) (xy 117.937534 -167.851328) (xy 117.938042 -167.851836) (xy 117.955779 -167.872779)
			(xy 117.985663 -167.918812) (xy 118.00863 -167.968658) (xy 118.024203 -168.021284) (xy 118.032061 -168.075601)
			(xy 118.03253 -168.103042) (xy 118.032044 -168.130293) (xy 118.030411 -168.14165) (xy 118.60733 -168.14165)
			(xy 118.611401 -168.086028) (xy 118.623527 -168.031591) (xy 118.64345 -167.9795) (xy 118.670746 -167.930865)
			(xy 118.704832 -167.886722) (xy 118.744981 -167.848013) (xy 118.790339 -167.815562) (xy 118.839939 -167.790061)
			(xy 118.892723 -167.772054) (xy 118.947566 -167.761924) (xy 119.0033 -167.759887) (xy 119.058737 -167.765987)
			(xy 119.112694 -167.780093) (xy 119.164023 -167.801905) (xy 119.211629 -167.830959) (xy 119.254497 -167.866634)
			(xy 119.291714 -167.908171) (xy 119.322487 -167.954684) (xy 119.346159 -168.005181) (xy 119.362227 -168.058588)
			(xy 119.370347 -168.113764) (xy 119.370856 -168.14165) (xy 119.370347 -168.169536) (xy 119.362227 -168.224712)
			(xy 119.346159 -168.278119) (xy 119.322487 -168.328616) (xy 119.291714 -168.375129) (xy 119.254497 -168.416666)
			(xy 119.211629 -168.452341) (xy 119.164023 -168.481395) (xy 119.112694 -168.503207) (xy 119.058737 -168.517313)
			(xy 119.0033 -168.523413) (xy 118.947566 -168.521376) (xy 118.892723 -168.511246) (xy 118.839939 -168.493239)
			(xy 118.790339 -168.467738) (xy 118.744981 -168.435287) (xy 118.704832 -168.396578) (xy 118.670746 -168.352435)
			(xy 118.64345 -168.3038) (xy 118.623527 -168.251709) (xy 118.611401 -168.197272) (xy 118.60733 -168.14165)
			(xy 118.030411 -168.14165) (xy 118.024288 -168.184241) (xy 118.008933 -168.236536) (xy 117.986291 -168.286113)
			(xy 117.956825 -168.331963) (xy 117.921134 -168.373154) (xy 117.879943 -168.408845) (xy 117.834093 -168.438311)
			(xy 117.784516 -168.460953) (xy 117.732221 -168.476308) (xy 117.678273 -168.484064) (xy 117.623771 -168.484064)
			(xy 117.569823 -168.476308) (xy 117.517528 -168.460953) (xy 117.467951 -168.438311) (xy 117.422101 -168.408845)
			(xy 117.38091 -168.373154) (xy 117.345219 -168.331963) (xy 117.315753 -168.286113) (xy 117.293111 -168.236536)
			(xy 117.277756 -168.184241) (xy 117.27 -168.130293) (xy 117.269514 -168.103042) (xy 117.010628 -168.103042)
			(xy 117.004622 -168.123497) (xy 116.981981 -168.173075) (xy 116.952514 -168.218927) (xy 116.916822 -168.260118)
			(xy 116.875631 -168.295811) (xy 116.82978 -168.325278) (xy 116.780202 -168.34792) (xy 116.727907 -168.363276)
			(xy 116.673958 -168.371034) (xy 116.646706 -168.37152) (xy 116.646452 -168.37152) (xy 116.621249 -168.371103)
			(xy 116.571281 -168.364469) (xy 116.522627 -168.351298) (xy 116.476136 -168.33182) (xy 116.454174 -168.31945)
			(xy 116.444268 -168.313608) (xy 116.422424 -168.311576) (xy 116.327682 -168.345104) (xy 116.311934 -168.360598)
			(xy 116.30787 -168.371012) (xy 116.297139 -168.397773) (xy 116.268855 -168.448013) (xy 116.23333 -168.493422)
			(xy 116.191373 -168.532965) (xy 116.143941 -168.56574) (xy 116.092115 -168.591001) (xy 116.037077 -168.608171)
			(xy 115.980081 -168.616859) (xy 115.951254 -168.617392) (xy 115.924001 -168.616965) (xy 115.87005 -168.609202)
			(xy 115.817753 -168.59384) (xy 115.768175 -168.571192) (xy 115.722324 -168.54172) (xy 115.681134 -168.506022)
			(xy 115.645443 -168.464826) (xy 115.615978 -168.418971) (xy 115.593338 -168.369388) (xy 115.577985 -168.317089)
			(xy 115.570231 -168.263137) (xy 115.569746 -168.235884) (xy 115.570409 -168.204321) (xy 115.580794 -168.142056)
			(xy 115.601279 -168.082347) (xy 115.61572 -168.054274) (xy 115.620546 -168.045384) (xy 115.622578 -168.025826)
			(xy 115.599718 -167.94734) (xy 115.596487 -167.937913) (xy 115.584063 -167.922357) (xy 115.575588 -167.917114)
			(xy 115.550462 -167.902606) (xy 115.50458 -167.867096) (xy 115.464607 -167.825045) (xy 115.431465 -167.777424)
			(xy 115.405918 -167.725333) (xy 115.388557 -167.669972) (xy 115.379782 -167.612621) (xy 115.379246 -167.583612)
			(xy 97.117408 -167.583612) (xy 97.117408 -169.435272) (xy 97.116834 -169.460258) (xy 97.107081 -169.509268)
			(xy 97.087963 -169.555438) (xy 97.060213 -169.596996) (xy 97.042986 -169.615104) (xy 96.800416 -169.857674)
			(xy 111.593122 -169.857674) (xy 111.593631 -169.830101) (xy 111.601574 -169.77553) (xy 111.61729 -169.72267)
			(xy 111.640451 -169.672624) (xy 111.670577 -169.626433) (xy 111.707038 -169.585061) (xy 111.727742 -169.566844)
			(xy 111.735805 -169.559278) (xy 111.745164 -169.539274) (xy 111.745776 -169.528236) (xy 111.745776 -169.450512)
			(xy 111.745209 -169.439462) (xy 111.735844 -169.419441) (xy 111.727742 -169.411904) (xy 111.707038 -169.393685)
			(xy 111.670565 -169.352319) (xy 111.640431 -169.306131) (xy 111.617264 -169.256084) (xy 111.601547 -169.203223)
			(xy 111.593607 -169.148648) (xy 111.593122 -169.121074) (xy 111.593631 -169.093501) (xy 111.601574 -169.03893)
			(xy 111.61729 -168.98607) (xy 111.640451 -168.936024) (xy 111.670577 -168.889833) (xy 111.707038 -168.848461)
			(xy 111.727742 -168.830244) (xy 111.735805 -168.822678) (xy 111.745164 -168.802674) (xy 111.745776 -168.791636)
			(xy 111.745776 -168.713912) (xy 111.745209 -168.702862) (xy 111.735844 -168.682841) (xy 111.727742 -168.675304)
			(xy 111.707038 -168.657085) (xy 111.670565 -168.615719) (xy 111.640431 -168.569531) (xy 111.617264 -168.519484)
			(xy 111.601547 -168.466623) (xy 111.593607 -168.412048) (xy 111.593122 -168.384474) (xy 111.593531 -168.357219)
			(xy 111.601292 -168.303265) (xy 111.616653 -168.250964) (xy 111.639301 -168.201382) (xy 111.668774 -168.155527)
			(xy 111.704474 -168.114334) (xy 111.745672 -168.078641) (xy 111.791531 -168.049174) (xy 111.841116 -168.026533)
			(xy 111.893419 -168.01118) (xy 111.947375 -168.003427) (xy 111.97463 -168.002966) (xy 112.002485 -168.003487)
			(xy 112.057599 -168.011614) (xy 112.110948 -168.027662) (xy 112.1614 -168.05129) (xy 112.207883 -168.081997)
			(xy 112.249412 -168.119132) (xy 112.285106 -168.161906) (xy 112.314206 -168.209412) (xy 112.336096 -168.260642)
			(xy 112.343692 -168.287446) (xy 112.345978 -168.296336) (xy 112.356646 -168.311576) (xy 112.428528 -168.359328)
			(xy 112.446562 -168.363392) (xy 112.455706 -168.362122) (xy 112.468723 -168.360454) (xy 112.494907 -168.358673)
			(xy 112.50803 -168.358566) (xy 112.522179 -168.358657) (xy 112.550402 -168.360693) (xy 112.564418 -168.36263)
			(xy 112.574324 -168.364154) (xy 112.594136 -168.359328) (xy 112.668558 -168.303448) (xy 112.678718 -168.285922)
			(xy 112.679988 -168.275762) (xy 112.684077 -168.248608) (xy 112.699049 -168.195778) (xy 112.72144 -168.145639)
			(xy 112.750787 -168.099228) (xy 112.786485 -168.057504) (xy 112.827794 -168.021327) (xy 112.873863 -167.991446)
			(xy 112.92374 -167.968477) (xy 112.976394 -167.952896) (xy 113.030738 -167.945024) (xy 113.058194 -167.944546)
			(xy 113.085443 -167.945083) (xy 113.139387 -167.952838) (xy 113.191677 -167.96819) (xy 113.241252 -167.990827)
			(xy 113.2871 -168.020288) (xy 113.328289 -168.055974) (xy 113.363981 -168.097158) (xy 113.393448 -168.143003)
			(xy 113.416092 -168.192574) (xy 113.431451 -168.244863) (xy 113.439213 -168.298805) (xy 113.439702 -168.326054)
			(xy 113.439204 -168.353627) (xy 113.431258 -168.408199) (xy 113.415539 -168.461058) (xy 113.392375 -168.511104)
			(xy 113.362249 -168.557294) (xy 113.325787 -168.598667) (xy 113.305082 -168.616884) (xy 113.297011 -168.624443)
			(xy 113.287655 -168.644452) (xy 113.287048 -168.655492) (xy 113.287048 -168.733216) (xy 113.287648 -168.744262)
			(xy 113.296989 -168.764284) (xy 113.305082 -168.771824) (xy 113.325804 -168.790023) (xy 113.362275 -168.831394)
			(xy 113.392406 -168.877586) (xy 113.41557 -168.927637) (xy 113.431283 -168.980502) (xy 113.439219 -169.035078)
			(xy 113.439253 -169.037) (xy 118.02821 -169.037) (xy 118.032281 -168.981378) (xy 118.044407 -168.926941)
			(xy 118.06433 -168.87485) (xy 118.091626 -168.826215) (xy 118.125712 -168.782072) (xy 118.165861 -168.743363)
			(xy 118.211219 -168.710912) (xy 118.260819 -168.685411) (xy 118.313603 -168.667404) (xy 118.368446 -168.657274)
			(xy 118.42418 -168.655237) (xy 118.479617 -168.661337) (xy 118.533574 -168.675443) (xy 118.584903 -168.697255)
			(xy 118.632509 -168.726309) (xy 118.675377 -168.761984) (xy 118.712594 -168.803521) (xy 118.743367 -168.850034)
			(xy 118.767039 -168.900531) (xy 118.783107 -168.953938) (xy 118.791227 -169.009114) (xy 118.791736 -169.037)
			(xy 118.791227 -169.064886) (xy 118.783107 -169.120062) (xy 118.767039 -169.173469) (xy 118.743367 -169.223966)
			(xy 118.712594 -169.270479) (xy 118.675377 -169.312016) (xy 118.632509 -169.347691) (xy 118.584903 -169.376745)
			(xy 118.533574 -169.398557) (xy 118.479617 -169.412663) (xy 118.42418 -169.418763) (xy 118.368446 -169.416726)
			(xy 118.313603 -169.406596) (xy 118.260819 -169.388589) (xy 118.211219 -169.363088) (xy 118.165861 -169.330637)
			(xy 118.125712 -169.291928) (xy 118.091626 -169.247785) (xy 118.06433 -169.19915) (xy 118.044407 -169.147059)
			(xy 118.032281 -169.092622) (xy 118.02821 -169.037) (xy 113.439253 -169.037) (xy 113.439702 -169.062654)
			(xy 113.439202 -169.089906) (xy 113.431451 -169.143856) (xy 113.416101 -169.196153) (xy 113.393463 -169.245734)
			(xy 113.363999 -169.291587) (xy 113.328309 -169.332781) (xy 113.28712 -169.368475) (xy 113.241269 -169.397944)
			(xy 113.191691 -169.420587) (xy 113.139395 -169.435943) (xy 113.085446 -169.443699) (xy 113.058194 -169.444162)
			(xy 113.057686 -169.444162) (xy 113.023904 -169.442638) (xy 113.013744 -169.441622) (xy 112.99444 -169.447718)
			(xy 112.931448 -169.50055) (xy 112.92415 -169.507266) (xy 112.914875 -169.524776) (xy 112.913414 -169.534586)
			(xy 112.913414 -169.535348) (xy 112.910463 -169.563509) (xy 112.897256 -169.61857) (xy 112.876053 -169.671073)
			(xy 112.84732 -169.719863) (xy 112.811689 -169.76387) (xy 112.769944 -169.802124) (xy 112.723001 -169.833786)
			(xy 112.671893 -169.85816) (xy 112.617743 -169.87471) (xy 112.561741 -169.883071) (xy 112.53343 -169.883582)
			(xy 112.515411 -169.883366) (xy 112.479536 -169.879928) (xy 112.461802 -169.876724) (xy 112.45215 -169.874946)
			(xy 112.4331 -169.878502) (xy 112.35817 -169.926508) (xy 112.34674 -169.942256) (xy 112.344454 -169.951654)
			(xy 112.337089 -169.978708) (xy 112.315456 -170.030436) (xy 112.286488 -170.078442) (xy 112.250809 -170.121694)
			(xy 112.209185 -170.159261) (xy 112.162513 -170.190334) (xy 112.111798 -170.214244) (xy 112.05813 -170.230478)
			(xy 112.002665 -170.238685) (xy 111.97463 -170.239182) (xy 111.947377 -170.238717) (xy 111.893424 -170.230963)
			(xy 111.841125 -170.21561) (xy 111.791543 -170.192969) (xy 111.745689 -170.163501) (xy 111.704495 -170.127808)
			(xy 111.668801 -170.086614) (xy 111.639333 -170.04076) (xy 111.616692 -169.991179) (xy 111.601338 -169.938879)
			(xy 111.593584 -169.884927) (xy 111.593122 -169.857674) (xy 96.800416 -169.857674) (xy 95.32493 -171.33316)
			(xy 113.21034 -171.33316) (xy 113.210833 -171.305586) (xy 113.218778 -171.251014) (xy 113.234497 -171.198154)
			(xy 113.257662 -171.148108) (xy 113.28779 -171.101917) (xy 113.324254 -171.060546) (xy 113.34496 -171.04233)
			(xy 113.353031 -171.034772) (xy 113.362385 -171.014762) (xy 113.362994 -171.003722) (xy 113.362994 -170.925998)
			(xy 113.362373 -170.914955) (xy 113.353045 -170.894934) (xy 113.34496 -170.88739) (xy 113.324233 -170.869197)
			(xy 113.287765 -170.827823) (xy 113.257636 -170.781629) (xy 113.234474 -170.731578) (xy 113.21876 -170.678713)
			(xy 113.210824 -170.624136) (xy 113.21034 -170.59656) (xy 113.210869 -170.567888) (xy 113.219469 -170.511192)
			(xy 113.236454 -170.456421) (xy 113.261442 -170.404807) (xy 113.293871 -170.357513) (xy 113.333011 -170.315602)
			(xy 113.37798 -170.280019) (xy 113.402618 -170.265344) (xy 113.402872 -170.265344) (xy 113.411379 -170.259887)
			(xy 113.423556 -170.243773) (xy 113.426494 -170.234102) (xy 113.44783 -170.154092) (xy 113.445036 -170.134026)
			(xy 113.439702 -170.125136) (xy 113.42735 -170.103476) (xy 113.407872 -170.057577) (xy 113.394688 -170.00949)
			(xy 113.388033 -169.960075) (xy 113.387632 -169.935144) (xy 113.388075 -169.908525) (xy 113.395647 -169.855828)
			(xy 113.410642 -169.804746) (xy 113.432755 -169.756318) (xy 113.461537 -169.71153) (xy 113.4964 -169.671296)
			(xy 113.536635 -169.636433) (xy 113.581423 -169.607652) (xy 113.629851 -169.58554) (xy 113.680934 -169.570545)
			(xy 113.733631 -169.562975) (xy 113.76025 -169.562526) (xy 113.786672 -169.562972) (xy 113.838987 -169.570428)
			(xy 113.889725 -169.585196) (xy 113.937869 -169.606982) (xy 113.982454 -169.635348) (xy 114.00282 -169.652188)
			(xy 114.009678 -169.65803) (xy 114.026696 -169.66438) (xy 114.111024 -169.66438) (xy 114.128042 -169.65803)
			(xy 114.1349 -169.652188) (xy 114.155266 -169.635349) (xy 114.199852 -169.606984) (xy 114.247996 -169.585197)
			(xy 114.298733 -169.570426) (xy 114.351048 -169.562966) (xy 114.403892 -169.562966) (xy 114.456207 -169.570426)
			(xy 114.506944 -169.585197) (xy 114.555088 -169.606984) (xy 114.599674 -169.635349) (xy 114.62004 -169.652188)
			(xy 114.626898 -169.65803) (xy 114.643916 -169.66438) (xy 114.728244 -169.66438) (xy 114.745262 -169.65803)
			(xy 114.75212 -169.652188) (xy 114.772477 -169.635339) (xy 114.817069 -169.606986) (xy 114.865216 -169.585209)
			(xy 114.915954 -169.570444) (xy 114.968269 -169.562986) (xy 114.99469 -169.562526) (xy 115.022581 -169.562932)
			(xy 115.077739 -169.571245) (xy 115.131042 -169.587685) (xy 115.181299 -169.611887) (xy 115.227388 -169.643309)
			(xy 115.268279 -169.681249) (xy 115.303059 -169.72486) (xy 115.33095 -169.773167) (xy 115.351329 -169.825092)
			(xy 115.363742 -169.879475) (xy 115.367911 -169.9351) (xy 115.363742 -169.990725) (xy 115.351329 -170.045108)
			(xy 115.33095 -170.097033) (xy 115.303059 -170.14534) (xy 115.268279 -170.188951) (xy 115.227388 -170.226891)
			(xy 115.181299 -170.258313) (xy 115.131042 -170.282515) (xy 115.077739 -170.298955) (xy 115.022581 -170.307268)
			(xy 114.99469 -170.307762) (xy 114.968269 -170.307295) (xy 114.915954 -170.299845) (xy 114.865216 -170.285082)
			(xy 114.817072 -170.2633) (xy 114.772486 -170.234938) (xy 114.75212 -170.2181) (xy 114.745262 -170.212258)
			(xy 114.728244 -170.205908) (xy 114.643916 -170.205908) (xy 114.626898 -170.212258) (xy 114.62004 -170.2181)
			(xy 114.599674 -170.234939) (xy 114.555088 -170.263304) (xy 114.506944 -170.285091) (xy 114.456207 -170.299862)
			(xy 114.403892 -170.307322) (xy 114.351048 -170.307322) (xy 114.298733 -170.299862) (xy 114.247996 -170.285091)
			(xy 114.199852 -170.263304) (xy 114.155266 -170.234939) (xy 114.1349 -170.2181) (xy 114.128042 -170.212258)
			(xy 114.111024 -170.205908) (xy 114.026696 -170.205908) (xy 114.009678 -170.212258) (xy 114.00282 -170.2181)
			(xy 113.990525 -170.228404) (xy 113.964455 -170.247101) (xy 113.95075 -170.255438) (xy 113.942114 -170.260518)
			(xy 113.929922 -170.277028) (xy 113.907824 -170.367198) (xy 113.911126 -170.387264) (xy 113.91646 -170.3959)
			(xy 113.929919 -170.418564) (xy 113.951182 -170.466795) (xy 113.965598 -170.517495) (xy 113.972893 -170.569697)
			(xy 113.973356 -170.596052) (xy 113.973356 -170.59656) (xy 113.972878 -170.624134) (xy 113.96493 -170.678707)
			(xy 113.949209 -170.731568) (xy 113.926041 -170.781614) (xy 113.89591 -170.827804) (xy 113.859443 -170.869175)
			(xy 113.838736 -170.88739) (xy 113.830655 -170.894939) (xy 113.821724 -170.91406) (xy 118.987062 -170.91406)
			(xy 118.987538 -170.886149) (xy 118.995677 -170.830922) (xy 119.011777 -170.777472) (xy 119.035494 -170.726937)
			(xy 119.06632 -170.680398) (xy 119.084598 -170.659298) (xy 119.090495 -170.652121) (xy 119.097146 -170.634796)
			(xy 119.097552 -170.625516) (xy 119.097552 -170.547792) (xy 119.090948 -170.53052) (xy 119.084598 -170.523408)
			(xy 119.066302 -170.502323) (xy 119.035477 -170.455781) (xy 119.011765 -170.405242) (xy 118.995673 -170.351788)
			(xy 118.987544 -170.296558) (xy 118.987062 -170.268646) (xy 118.987548 -170.241395) (xy 118.995304 -170.187447)
			(xy 119.010659 -170.135152) (xy 119.033301 -170.085575) (xy 119.062767 -170.039725) (xy 119.098458 -169.998534)
			(xy 119.139649 -169.962843) (xy 119.185499 -169.933377) (xy 119.235076 -169.910735) (xy 119.287371 -169.89538)
			(xy 119.341319 -169.887624) (xy 119.395821 -169.887624) (xy 119.449769 -169.89538) (xy 119.502064 -169.910735)
			(xy 119.551641 -169.933377) (xy 119.597491 -169.962843) (xy 119.638682 -169.998534) (xy 119.674373 -170.039725)
			(xy 119.703839 -170.085575) (xy 119.726481 -170.135152) (xy 119.741836 -170.187447) (xy 119.749592 -170.241395)
			(xy 119.750078 -170.268646) (xy 119.749596 -170.296557) (xy 119.741456 -170.351783) (xy 119.725357 -170.405233)
			(xy 119.701643 -170.455767) (xy 119.670818 -170.502307) (xy 119.652542 -170.523408) (xy 119.646635 -170.530578)
			(xy 119.639992 -170.547909) (xy 119.639588 -170.55719) (xy 119.639588 -170.634914) (xy 119.646192 -170.652186)
			(xy 119.652542 -170.659298) (xy 119.6708 -170.680414) (xy 119.701629 -170.726949) (xy 119.725347 -170.777479)
			(xy 119.741449 -170.830927) (xy 119.749589 -170.88615) (xy 119.750078 -170.91406) (xy 119.749592 -170.941311)
			(xy 119.741836 -170.995259) (xy 119.726481 -171.047554) (xy 119.703839 -171.097131) (xy 119.674373 -171.142981)
			(xy 119.638682 -171.184172) (xy 119.597491 -171.219863) (xy 119.551641 -171.249329) (xy 119.502064 -171.271971)
			(xy 119.449769 -171.287326) (xy 119.395821 -171.295082) (xy 119.341319 -171.295082) (xy 119.287371 -171.287326)
			(xy 119.235076 -171.271971) (xy 119.185499 -171.249329) (xy 119.139649 -171.219863) (xy 119.098458 -171.184172)
			(xy 119.062767 -171.142981) (xy 119.033301 -171.097131) (xy 119.010659 -171.047554) (xy 118.995304 -170.995259)
			(xy 118.987548 -170.941311) (xy 118.987062 -170.91406) (xy 113.821724 -170.91406) (xy 113.821306 -170.914956)
			(xy 113.820702 -170.925998) (xy 113.820702 -171.003722) (xy 113.821313 -171.014766) (xy 113.830648 -171.034788)
			(xy 113.838736 -171.04233) (xy 113.859472 -171.060514) (xy 113.895939 -171.101889) (xy 113.926067 -171.148085)
			(xy 113.949228 -171.198138) (xy 113.96494 -171.251005) (xy 113.972874 -171.305584) (xy 113.973356 -171.33316)
			(xy 113.97287 -171.360411) (xy 113.965114 -171.414359) (xy 113.949759 -171.466654) (xy 113.927117 -171.516231)
			(xy 113.897651 -171.562081) (xy 113.86196 -171.603272) (xy 113.820769 -171.638963) (xy 113.774919 -171.668429)
			(xy 113.725342 -171.691071) (xy 113.673047 -171.706426) (xy 113.619099 -171.714182) (xy 113.564597 -171.714182)
			(xy 113.510649 -171.706426) (xy 113.458354 -171.691071) (xy 113.408777 -171.668429) (xy 113.362927 -171.638963)
			(xy 113.321736 -171.603272) (xy 113.286045 -171.562081) (xy 113.256579 -171.516231) (xy 113.233937 -171.466654)
			(xy 113.218582 -171.414359) (xy 113.210826 -171.360411) (xy 113.21034 -171.33316) (xy 95.32493 -171.33316)
			(xy 94.967806 -171.690284) (xy 94.949699 -171.707528) (xy 94.908158 -171.735341) (xy 94.861991 -171.754517)
			(xy 94.812969 -171.764321) (xy 94.787974 -171.76496) (xy 77.261466 -171.76496) (xy 77.251393 -171.765352)
			(xy 77.232794 -171.773094) (xy 77.225398 -171.779946) (xy 76.796138 -172.208952) (xy 76.789332 -172.216379)
			(xy 76.781591 -172.234957) (xy 76.781152 -172.24502) (xy 76.781152 -173.322234) (xy 76.780542 -173.347218)
			(xy 76.770798 -173.396226) (xy 76.75169 -173.442395) (xy 76.723952 -173.483956) (xy 76.70673 -173.502066)
			(xy 76.364846 -173.84395) (xy 76.88275 -173.84395) (xy 76.886821 -173.788328) (xy 76.898947 -173.733891)
			(xy 76.91887 -173.6818) (xy 76.946166 -173.633165) (xy 76.980252 -173.589022) (xy 77.020401 -173.550313)
			(xy 77.065759 -173.517862) (xy 77.115359 -173.492361) (xy 77.168143 -173.474354) (xy 77.222986 -173.464224)
			(xy 77.27872 -173.462187) (xy 77.334157 -173.468287) (xy 77.388114 -173.482393) (xy 77.439443 -173.504205)
			(xy 77.487049 -173.533259) (xy 77.529917 -173.568934) (xy 77.567134 -173.610471) (xy 77.597907 -173.656984)
			(xy 77.621579 -173.707481) (xy 77.637647 -173.760888) (xy 77.645767 -173.816064) (xy 77.646058 -173.832012)
			(xy 107.149646 -173.832012) (xy 107.150132 -173.804761) (xy 107.157888 -173.750813) (xy 107.173243 -173.698518)
			(xy 107.195885 -173.648941) (xy 107.225351 -173.603091) (xy 107.261042 -173.5619) (xy 107.302233 -173.526209)
			(xy 107.348083 -173.496743) (xy 107.39766 -173.474101) (xy 107.449955 -173.458746) (xy 107.503903 -173.45099)
			(xy 107.558405 -173.45099) (xy 107.612353 -173.458746) (xy 107.664648 -173.474101) (xy 107.714225 -173.496743)
			(xy 107.760075 -173.526209) (xy 107.801266 -173.5619) (xy 107.836957 -173.603091) (xy 107.866423 -173.648941)
			(xy 107.889065 -173.698518) (xy 107.90442 -173.750813) (xy 107.912176 -173.804761) (xy 107.912662 -173.832012)
			(xy 107.911996 -173.863575) (xy 107.901612 -173.92584) (xy 107.881129 -173.985549) (xy 107.866688 -174.013622)
			(xy 107.861862 -174.022512) (xy 107.85983 -174.04207) (xy 107.88269 -174.120556) (xy 107.88592 -174.129984)
			(xy 107.898344 -174.14554) (xy 107.90682 -174.150782) (xy 107.914186 -174.154846) (xy 107.924092 -174.160688)
			(xy 107.945936 -174.16272) (xy 108.040678 -174.129192) (xy 108.056426 -174.113698) (xy 108.06049 -174.103284)
			(xy 108.071169 -174.0765) (xy 108.099459 -174.026258) (xy 108.134992 -173.980849) (xy 108.176956 -173.941307)
			(xy 108.224396 -173.908534) (xy 108.276229 -173.883277) (xy 108.331274 -173.866113) (xy 108.388276 -173.857432)
			(xy 108.417106 -173.856904) (xy 108.444358 -173.857366) (xy 108.498307 -173.865124) (xy 108.550602 -173.88048)
			(xy 108.60018 -173.903122) (xy 108.646031 -173.932589) (xy 108.687222 -173.968282) (xy 108.722914 -174.009473)
			(xy 108.752381 -174.055325) (xy 108.775022 -174.104903) (xy 108.790378 -174.157199) (xy 108.798134 -174.211148)
			(xy 108.798134 -174.265652) (xy 108.790378 -174.319601) (xy 108.781028 -174.351442) (xy 109.039914 -174.351442)
			(xy 109.040422 -174.323968) (xy 109.048308 -174.269589) (xy 109.063923 -174.216907) (xy 109.086943 -174.167014)
			(xy 109.11689 -174.120944) (xy 109.134656 -174.099982) (xy 109.13491 -174.099728) (xy 109.140492 -174.092638)
			(xy 109.146741 -174.075724) (xy 109.147102 -174.066708) (xy 109.147102 -173.999144) (xy 109.146724 -173.990129)
			(xy 109.140491 -173.973212) (xy 109.13491 -173.966124) (xy 109.134402 -173.965616) (xy 109.11668 -173.94466)
			(xy 109.086796 -173.89863) (xy 109.063827 -173.848787) (xy 109.04825 -173.796164) (xy 109.040386 -173.74185)
			(xy 109.039914 -173.71441) (xy 109.0404 -173.687159) (xy 109.048156 -173.633211) (xy 109.063511 -173.580916)
			(xy 109.086153 -173.531339) (xy 109.115619 -173.485489) (xy 109.15131 -173.444298) (xy 109.192501 -173.408607)
			(xy 109.238351 -173.379141) (xy 109.287928 -173.356499) (xy 109.340223 -173.341144) (xy 109.394171 -173.333388)
			(xy 109.448673 -173.333388) (xy 109.502621 -173.341144) (xy 109.554916 -173.356499) (xy 109.604493 -173.379141)
			(xy 109.650343 -173.408607) (xy 109.691534 -173.444298) (xy 109.727225 -173.485489) (xy 109.756691 -173.531339)
			(xy 109.779333 -173.580916) (xy 109.784596 -173.59884) (xy 130.214624 -173.59884) (xy 130.215108 -173.57147)
			(xy 130.22292 -173.517292) (xy 130.238405 -173.464789) (xy 130.261243 -173.415041) (xy 130.290964 -173.369074)
			(xy 130.308604 -173.348142) (xy 130.308858 -173.347888) (xy 130.314463 -173.340814) (xy 130.320697 -173.323887)
			(xy 130.32105 -173.314868) (xy 130.32105 -173.247812) (xy 130.320698 -173.238794) (xy 130.314448 -173.221877)
			(xy 130.308858 -173.214792) (xy 130.308604 -173.214792) (xy 130.308604 -173.214538) (xy 130.291003 -173.193573)
			(xy 130.261279 -173.14761) (xy 130.238432 -173.097869) (xy 130.222934 -173.045372) (xy 130.215102 -172.991199)
			(xy 130.215098 -172.936462) (xy 130.222921 -172.882287) (xy 130.238411 -172.829787) (xy 130.26125 -172.780043)
			(xy 130.290967 -172.734075) (xy 130.308604 -172.713142) (xy 130.308858 -172.712888) (xy 130.314463 -172.705814)
			(xy 130.320697 -172.688887) (xy 130.32105 -172.679868) (xy 130.32105 -172.612812) (xy 130.320698 -172.603794)
			(xy 130.314448 -172.586877) (xy 130.308858 -172.579792) (xy 130.308604 -172.579792) (xy 130.308604 -172.579538)
			(xy 130.291003 -172.558573) (xy 130.261279 -172.51261) (xy 130.238432 -172.462869) (xy 130.222934 -172.410372)
			(xy 130.215102 -172.356199) (xy 130.215098 -172.301462) (xy 130.222921 -172.247287) (xy 130.238411 -172.194787)
			(xy 130.26125 -172.145043) (xy 130.290967 -172.099075) (xy 130.308604 -172.078142) (xy 130.308858 -172.077888)
			(xy 130.314463 -172.070814) (xy 130.320697 -172.053887) (xy 130.32105 -172.044868) (xy 130.32105 -171.977812)
			(xy 130.320698 -171.968794) (xy 130.314448 -171.951877) (xy 130.308858 -171.944792) (xy 130.308604 -171.944792)
			(xy 130.308604 -171.944538) (xy 130.29097 -171.923602) (xy 130.261257 -171.87763) (xy 130.23842 -171.827884)
			(xy 130.222928 -171.775384) (xy 130.215099 -171.721209) (xy 130.214624 -171.69384) (xy 130.215109 -171.665965)
			(xy 130.22322 -171.610807) (xy 130.239275 -171.557418) (xy 130.262932 -171.506936) (xy 130.293686 -171.460435)
			(xy 130.311906 -171.439332) (xy 130.318002 -171.432474) (xy 130.324606 -171.415202) (xy 130.32486 -171.328588)
			(xy 130.318256 -171.311316) (xy 130.31216 -171.304458) (xy 130.31216 -171.304204) (xy 130.294099 -171.283136)
			(xy 130.263576 -171.236796) (xy 130.240103 -171.186515) (xy 130.224177 -171.13336) (xy 130.216135 -171.078457)
			(xy 130.21564 -171.050712) (xy 130.216103 -171.023342) (xy 130.22392 -170.969162) (xy 130.23941 -170.916658)
			(xy 130.262252 -170.866912) (xy 130.291978 -170.820945) (xy 130.30962 -170.800014) (xy 130.309874 -170.79976)
			(xy 130.31545 -170.792667) (xy 130.321701 -170.775755) (xy 130.322066 -170.76674) (xy 130.322066 -170.699684)
			(xy 130.321724 -170.690665) (xy 130.315467 -170.673748) (xy 130.309874 -170.666664) (xy 130.30962 -170.666664)
			(xy 130.30962 -170.66641) (xy 130.291991 -170.645468) (xy 130.262267 -170.599501) (xy 130.239421 -170.549757)
			(xy 130.223924 -170.497256) (xy 130.216095 -170.443079) (xy 130.216093 -170.388339) (xy 130.22392 -170.334162)
			(xy 130.239415 -170.28166) (xy 130.262258 -170.231915) (xy 130.29198 -170.185947) (xy 130.30962 -170.165014)
			(xy 130.309874 -170.16476) (xy 130.31545 -170.157667) (xy 130.321701 -170.140755) (xy 130.322066 -170.13174)
			(xy 130.322066 -170.064684) (xy 130.321724 -170.055665) (xy 130.315467 -170.038748) (xy 130.309874 -170.031664)
			(xy 130.30962 -170.031664) (xy 130.30962 -170.03141) (xy 130.291991 -170.010468) (xy 130.262267 -169.964501)
			(xy 130.239421 -169.914757) (xy 130.223924 -169.862256) (xy 130.216095 -169.808079) (xy 130.216093 -169.753339)
			(xy 130.22392 -169.699162) (xy 130.239415 -169.64666) (xy 130.262258 -169.596915) (xy 130.29198 -169.550947)
			(xy 130.30962 -169.530014) (xy 130.309874 -169.52976) (xy 130.31545 -169.522667) (xy 130.321701 -169.505755)
			(xy 130.322066 -169.49674) (xy 130.322066 -169.429684) (xy 130.321724 -169.420665) (xy 130.315467 -169.403748)
			(xy 130.309874 -169.396664) (xy 130.30962 -169.396664) (xy 130.30962 -169.39641) (xy 130.291975 -169.375482)
			(xy 130.262264 -169.329509) (xy 130.239428 -169.27976) (xy 130.223939 -169.227258) (xy 130.216113 -169.173082)
			(xy 130.21564 -169.145712) (xy 130.216121 -169.118413) (xy 130.223892 -169.064371) (xy 130.23929 -169.01199)
			(xy 130.262002 -168.96234) (xy 130.291562 -168.916437) (xy 130.309112 -168.895522) (xy 130.31496 -168.888335)
			(xy 130.321465 -168.871) (xy 130.321812 -168.86174) (xy 130.321558 -168.785794) (xy 130.315208 -168.768776)
			(xy 130.309112 -168.761918) (xy 130.291409 -168.740948) (xy 130.261528 -168.694919) (xy 130.238559 -168.645079)
			(xy 130.222977 -168.592461) (xy 130.215103 -168.538151) (xy 130.214624 -168.510712) (xy 130.215067 -168.483458)
			(xy 130.222823 -168.429505) (xy 130.238179 -168.377204) (xy 130.260822 -168.327622) (xy 130.290292 -168.281768)
			(xy 130.325988 -168.240574) (xy 130.367184 -168.20488) (xy 130.41304 -168.175413) (xy 130.462623 -168.152772)
			(xy 130.514924 -168.137418) (xy 130.568878 -168.129665) (xy 130.596132 -168.129204) (xy 130.623503 -168.12965)
			(xy 130.677683 -168.137473) (xy 130.730186 -168.152966) (xy 130.779933 -168.175813) (xy 130.825899 -168.205541)
			(xy 130.84683 -168.223184) (xy 130.847084 -168.223438) (xy 130.854168 -168.229028) (xy 130.871087 -168.235272)
			(xy 130.880104 -168.23563) (xy 130.94716 -168.23563) (xy 130.956174 -168.235247) (xy 130.973091 -168.229017)
			(xy 130.98018 -168.223438) (xy 130.98018 -168.223184) (xy 130.980434 -168.223184) (xy 131.001378 -168.20556)
			(xy 131.047348 -168.175846) (xy 131.097092 -168.153008) (xy 131.14959 -168.137513) (xy 131.203764 -168.129681)
			(xy 131.231132 -168.129204) (xy 131.258385 -168.129648) (xy 131.312334 -168.137409) (xy 131.364631 -168.152769)
			(xy 131.414209 -168.175415) (xy 131.46006 -168.204886) (xy 131.50125 -168.240581) (xy 131.536941 -168.281776)
			(xy 131.566406 -168.32763) (xy 131.589046 -168.377211) (xy 131.6044 -168.429509) (xy 131.612155 -168.483459)
			(xy 131.61264 -168.510712) (xy 131.612153 -168.538011) (xy 131.604381 -168.592051) (xy 131.588983 -168.644432)
			(xy 131.566273 -168.694081) (xy 131.536716 -168.739986) (xy 131.519168 -168.760902) (xy 131.51335 -168.76811)
			(xy 131.506828 -168.785429) (xy 131.506468 -168.794684) (xy 131.506722 -168.87063) (xy 131.513072 -168.887648)
			(xy 131.519168 -168.894506) (xy 131.53688 -168.915469) (xy 131.56676 -168.9615) (xy 131.589727 -169.011341)
			(xy 131.605308 -169.063962) (xy 131.613178 -169.118273) (xy 131.613656 -169.145712) (xy 131.613208 -169.173083)
			(xy 131.605387 -169.227263) (xy 131.589895 -169.279767) (xy 131.567049 -169.329514) (xy 131.53732 -169.375479)
			(xy 131.519676 -169.39641) (xy 131.519422 -169.396664) (xy 131.513835 -169.40375) (xy 131.507591 -169.420668)
			(xy 131.50723 -169.429684) (xy 131.50723 -169.49674) (xy 131.507561 -169.50576) (xy 131.513826 -169.522677)
			(xy 131.519422 -169.52976) (xy 131.519676 -169.52976) (xy 131.519676 -169.530014) (xy 131.537328 -169.550937)
			(xy 131.567052 -169.596907) (xy 131.589897 -169.646655) (xy 131.605392 -169.699158) (xy 131.61322 -169.753338)
			(xy 131.613218 -169.80808) (xy 131.605388 -169.86226) (xy 131.589891 -169.914762) (xy 131.567044 -169.964509)
			(xy 131.537317 -170.010477) (xy 131.519676 -170.03141) (xy 131.519422 -170.031664) (xy 131.513835 -170.03875)
			(xy 131.507591 -170.055668) (xy 131.50723 -170.064684) (xy 131.50723 -170.13174) (xy 131.507561 -170.14076)
			(xy 131.513826 -170.157677) (xy 131.519422 -170.16476) (xy 131.519676 -170.16476) (xy 131.519676 -170.165014)
			(xy 131.537328 -170.185937) (xy 131.567052 -170.231907) (xy 131.589897 -170.281655) (xy 131.605392 -170.334158)
			(xy 131.61322 -170.388338) (xy 131.613218 -170.44308) (xy 131.605388 -170.49726) (xy 131.589891 -170.549762)
			(xy 131.567044 -170.599509) (xy 131.537317 -170.645477) (xy 131.519676 -170.66641) (xy 131.519422 -170.666664)
			(xy 131.513835 -170.67375) (xy 131.507591 -170.690668) (xy 131.50723 -170.699684) (xy 131.50723 -170.76674)
			(xy 131.507561 -170.77576) (xy 131.513826 -170.792677) (xy 131.519422 -170.79976) (xy 131.519676 -170.79976)
			(xy 131.519676 -170.800014) (xy 131.537285 -170.820971) (xy 131.567002 -170.866936) (xy 131.589844 -170.916678)
			(xy 131.605342 -170.969173) (xy 131.613178 -171.023344) (xy 131.613656 -171.050712) (xy 131.613122 -171.078585)
			(xy 131.60502 -171.13374) (xy 131.588975 -171.187128) (xy 131.56533 -171.237611) (xy 131.534587 -171.284114)
			(xy 131.516374 -171.30522) (xy 131.510278 -171.312078) (xy 131.503674 -171.32935) (xy 131.50342 -171.415964)
			(xy 131.510024 -171.433236) (xy 131.51612 -171.440094) (xy 131.51612 -171.440348) (xy 131.534202 -171.461398)
			(xy 131.564723 -171.507743) (xy 131.588192 -171.558028) (xy 131.604113 -171.611187) (xy 131.612148 -171.666094)
			(xy 131.61264 -171.69384) (xy 131.612153 -171.72121) (xy 131.604343 -171.775388) (xy 131.588859 -171.827892)
			(xy 131.566022 -171.877639) (xy 131.5363 -171.923606) (xy 131.51866 -171.944538) (xy 131.518406 -171.944792)
			(xy 131.512817 -171.951877) (xy 131.506572 -171.968795) (xy 131.506214 -171.977812) (xy 131.506214 -172.044868)
			(xy 131.506584 -172.053884) (xy 131.512822 -172.070801) (xy 131.518406 -172.077888) (xy 131.51866 -172.077888)
			(xy 131.51866 -172.078142) (xy 131.53634 -172.099043) (xy 131.566065 -172.145016) (xy 131.588908 -172.194767)
			(xy 131.604402 -172.247274) (xy 131.612227 -172.301457) (xy 131.612223 -172.356203) (xy 131.604389 -172.410385)
			(xy 131.588887 -172.462889) (xy 131.566036 -172.512637) (xy 131.536304 -172.558605) (xy 131.51866 -172.579538)
			(xy 131.518406 -172.579792) (xy 131.512817 -172.586877) (xy 131.506572 -172.603795) (xy 131.506214 -172.612812)
			(xy 131.506214 -172.679868) (xy 131.506584 -172.688884) (xy 131.512822 -172.705801) (xy 131.518406 -172.712888)
			(xy 131.51866 -172.712888) (xy 131.51866 -172.713142) (xy 131.53634 -172.734043) (xy 131.566065 -172.780016)
			(xy 131.588908 -172.829767) (xy 131.604402 -172.882274) (xy 131.612227 -172.936457) (xy 131.612223 -172.991203)
			(xy 131.604389 -173.045385) (xy 131.588887 -173.097889) (xy 131.566036 -173.147637) (xy 131.536304 -173.193605)
			(xy 131.51866 -173.214538) (xy 131.518406 -173.214792) (xy 131.512817 -173.221877) (xy 131.506572 -173.238795)
			(xy 131.506214 -173.247812) (xy 131.506214 -173.314868) (xy 131.506584 -173.323884) (xy 131.512822 -173.340801)
			(xy 131.518406 -173.347888) (xy 131.51866 -173.347888) (xy 131.51866 -173.348142) (xy 131.536279 -173.36909)
			(xy 131.565995 -173.415058) (xy 131.588836 -173.464801) (xy 131.604331 -173.517299) (xy 131.612164 -173.571472)
			(xy 131.61264 -173.59884) (xy 131.612159 -173.626091) (xy 131.604398 -173.680037) (xy 131.58904 -173.73233)
			(xy 131.566396 -173.781905) (xy 131.536929 -173.827754) (xy 131.501237 -173.868943) (xy 131.460047 -173.904634)
			(xy 131.414198 -173.9341) (xy 131.364622 -173.956743) (xy 131.312329 -173.9721) (xy 131.258383 -173.97986)
			(xy 131.231132 -173.980348) (xy 131.203762 -173.979876) (xy 131.149583 -173.972061) (xy 131.097079 -173.956574)
			(xy 131.047332 -173.933734) (xy 131.001365 -173.904009) (xy 130.980434 -173.886368) (xy 130.98018 -173.886114)
			(xy 130.973102 -173.880514) (xy 130.956179 -173.874275) (xy 130.94716 -173.873922) (xy 130.880104 -173.873922)
			(xy 130.871087 -173.874276) (xy 130.854169 -173.880525) (xy 130.847084 -173.886114) (xy 130.847084 -173.886368)
			(xy 130.84683 -173.886368) (xy 130.825893 -173.904002) (xy 130.779922 -173.933715) (xy 130.730176 -173.956553)
			(xy 130.677676 -173.972045) (xy 130.623501 -173.979874) (xy 130.596132 -173.980348) (xy 130.568883 -173.979792)
			(xy 130.51494 -173.972041) (xy 130.462649 -173.956692) (xy 130.413075 -173.934057) (xy 130.367226 -173.904598)
			(xy 130.326037 -173.868914) (xy 130.290345 -173.827731) (xy 130.260877 -173.781888) (xy 130.238233 -173.732318)
			(xy 130.222874 -173.68003) (xy 130.215113 -173.626089) (xy 130.214624 -173.59884) (xy 109.784596 -173.59884)
			(xy 109.794688 -173.633211) (xy 109.802444 -173.687159) (xy 109.80293 -173.71441) (xy 109.802442 -173.741884)
			(xy 109.79455 -173.796264) (xy 109.778929 -173.848946) (xy 109.755905 -173.898839) (xy 109.725955 -173.944908)
			(xy 109.708188 -173.96587) (xy 109.707934 -173.966124) (xy 109.702323 -173.973194) (xy 109.696093 -173.990124)
			(xy 109.695742 -173.999144) (xy 109.695742 -174.066708) (xy 109.696086 -174.075726) (xy 109.702341 -174.092644)
			(xy 109.707934 -174.099728) (xy 109.708442 -174.100236) (xy 109.726179 -174.121179) (xy 109.756063 -174.167212)
			(xy 109.77903 -174.217058) (xy 109.794603 -174.269684) (xy 109.802461 -174.324001) (xy 109.80293 -174.351442)
			(xy 109.802444 -174.378693) (xy 109.800811 -174.39005) (xy 110.37773 -174.39005) (xy 110.381801 -174.334428)
			(xy 110.393927 -174.279991) (xy 110.41385 -174.2279) (xy 110.441146 -174.179265) (xy 110.475232 -174.135122)
			(xy 110.515381 -174.096413) (xy 110.560739 -174.063962) (xy 110.610339 -174.038461) (xy 110.663123 -174.020454)
			(xy 110.717966 -174.010324) (xy 110.7737 -174.008287) (xy 110.829137 -174.014387) (xy 110.883094 -174.028493)
			(xy 110.934423 -174.050305) (xy 110.982029 -174.079359) (xy 111.024897 -174.115034) (xy 111.062114 -174.156571)
			(xy 111.092887 -174.203084) (xy 111.116559 -174.253581) (xy 111.132627 -174.306988) (xy 111.140747 -174.362164)
			(xy 111.141256 -174.39005) (xy 111.140747 -174.417936) (xy 111.132627 -174.473112) (xy 111.116559 -174.526519)
			(xy 111.092887 -174.577016) (xy 111.062114 -174.623529) (xy 111.024897 -174.665066) (xy 110.982029 -174.700741)
			(xy 110.934423 -174.729795) (xy 110.883094 -174.751607) (xy 110.829137 -174.765713) (xy 110.7737 -174.771813)
			(xy 110.717966 -174.769776) (xy 110.663123 -174.759646) (xy 110.610339 -174.741639) (xy 110.560739 -174.716138)
			(xy 110.515381 -174.683687) (xy 110.475232 -174.644978) (xy 110.441146 -174.600835) (xy 110.41385 -174.5522)
			(xy 110.393927 -174.500109) (xy 110.381801 -174.445672) (xy 110.37773 -174.39005) (xy 109.800811 -174.39005)
			(xy 109.794688 -174.432641) (xy 109.779333 -174.484936) (xy 109.756691 -174.534513) (xy 109.727225 -174.580363)
			(xy 109.691534 -174.621554) (xy 109.650343 -174.657245) (xy 109.604493 -174.686711) (xy 109.554916 -174.709353)
			(xy 109.502621 -174.724708) (xy 109.448673 -174.732464) (xy 109.394171 -174.732464) (xy 109.340223 -174.724708)
			(xy 109.287928 -174.709353) (xy 109.238351 -174.686711) (xy 109.192501 -174.657245) (xy 109.15131 -174.621554)
			(xy 109.115619 -174.580363) (xy 109.086153 -174.534513) (xy 109.063511 -174.484936) (xy 109.048156 -174.432641)
			(xy 109.0404 -174.378693) (xy 109.039914 -174.351442) (xy 108.781028 -174.351442) (xy 108.775022 -174.371897)
			(xy 108.752381 -174.421475) (xy 108.722914 -174.467327) (xy 108.687222 -174.508518) (xy 108.646031 -174.544211)
			(xy 108.60018 -174.573678) (xy 108.550602 -174.59632) (xy 108.498307 -174.611676) (xy 108.444358 -174.619434)
			(xy 108.417106 -174.61992) (xy 108.416852 -174.61992) (xy 108.391649 -174.619503) (xy 108.341681 -174.612869)
			(xy 108.293027 -174.599698) (xy 108.246536 -174.58022) (xy 108.224574 -174.56785) (xy 108.214668 -174.562008)
			(xy 108.192824 -174.559976) (xy 108.098082 -174.593504) (xy 108.082334 -174.608998) (xy 108.07827 -174.619412)
			(xy 108.067539 -174.646173) (xy 108.039255 -174.696413) (xy 108.00373 -174.741822) (xy 107.961773 -174.781365)
			(xy 107.914341 -174.81414) (xy 107.862515 -174.839401) (xy 107.807477 -174.856571) (xy 107.750481 -174.865259)
			(xy 107.721654 -174.865792) (xy 107.694401 -174.865365) (xy 107.64045 -174.857602) (xy 107.588153 -174.84224)
			(xy 107.538575 -174.819592) (xy 107.492724 -174.79012) (xy 107.451534 -174.754422) (xy 107.415843 -174.713226)
			(xy 107.386378 -174.667371) (xy 107.363738 -174.617788) (xy 107.348385 -174.565489) (xy 107.340631 -174.511537)
			(xy 107.340146 -174.484284) (xy 107.340809 -174.452721) (xy 107.351194 -174.390456) (xy 107.371679 -174.330747)
			(xy 107.38612 -174.302674) (xy 107.390946 -174.293784) (xy 107.392978 -174.274226) (xy 107.370118 -174.19574)
			(xy 107.366887 -174.186313) (xy 107.354463 -174.170757) (xy 107.345988 -174.165514) (xy 107.320862 -174.151006)
			(xy 107.27498 -174.115496) (xy 107.235007 -174.073445) (xy 107.201865 -174.025824) (xy 107.176318 -173.973733)
			(xy 107.158957 -173.918372) (xy 107.150182 -173.861021) (xy 107.149646 -173.832012) (xy 77.646058 -173.832012)
			(xy 77.646276 -173.84395) (xy 77.645767 -173.871836) (xy 77.637647 -173.927012) (xy 77.621579 -173.980419)
			(xy 77.597907 -174.030916) (xy 77.567134 -174.077429) (xy 77.529917 -174.118966) (xy 77.487049 -174.154641)
			(xy 77.439443 -174.183695) (xy 77.388114 -174.205507) (xy 77.334157 -174.219613) (xy 77.27872 -174.225713)
			(xy 77.222986 -174.223676) (xy 77.168143 -174.213546) (xy 77.115359 -174.195539) (xy 77.065759 -174.170038)
			(xy 77.020401 -174.137587) (xy 76.980252 -174.098878) (xy 76.946166 -174.054735) (xy 76.91887 -174.0061)
			(xy 76.898947 -173.954009) (xy 76.886821 -173.899572) (xy 76.88275 -173.84395) (xy 76.364846 -173.84395)
			(xy 76.291186 -173.91761) (xy 76.287376 -173.928786) (xy 76.278445 -173.953547) (xy 76.254738 -174.000545)
			(xy 76.224794 -174.043836) (xy 76.189179 -174.082597) (xy 76.148573 -174.116091) (xy 76.103745 -174.143682)
			(xy 76.055549 -174.164846) (xy 76.0049 -174.17918) (xy 75.952761 -174.186411) (xy 75.926442 -174.18685)
			(xy 75.899194 -174.186283) (xy 75.845251 -174.178533) (xy 75.792961 -174.163185) (xy 75.743386 -174.140552)
			(xy 75.697538 -174.111094) (xy 75.656348 -174.075411) (xy 75.620656 -174.03423) (xy 75.591188 -173.988387)
			(xy 75.568544 -173.938818) (xy 75.553185 -173.886531) (xy 75.545423 -173.83259) (xy 75.544934 -173.805342)
			(xy 75.545437 -173.777868) (xy 75.553323 -173.723489) (xy 75.568939 -173.670806) (xy 75.59196 -173.620913)
			(xy 75.621909 -173.574844) (xy 75.639676 -173.553882) (xy 75.63993 -173.553628) (xy 75.645514 -173.54654)
			(xy 75.651761 -173.529624) (xy 75.652122 -173.520608) (xy 75.652122 -173.453044) (xy 75.651739 -173.44403)
			(xy 75.645509 -173.427113) (xy 75.63993 -173.420024) (xy 75.639422 -173.419516) (xy 75.621703 -173.398558)
			(xy 75.591818 -173.352528) (xy 75.568848 -173.302687) (xy 75.55327 -173.250064) (xy 75.545406 -173.19575)
			(xy 75.544934 -173.16831) (xy 75.54548 -173.139238) (xy 75.554315 -173.08177) (xy 75.571766 -173.026308)
			(xy 75.59743 -172.974135) (xy 75.630711 -172.926459) (xy 75.670841 -172.884384) (xy 75.716889 -172.848885)
			(xy 75.76779 -172.820783) (xy 75.822365 -172.800728) (xy 75.85075 -172.794422) (xy 75.851004 -172.794422)
			(xy 75.862314 -172.791507) (xy 75.880772 -172.77724) (xy 75.891061 -172.756302) (xy 75.891644 -172.744638)
			(xy 75.891644 -171.96054) (xy 75.892239 -171.935556) (xy 75.901988 -171.886547) (xy 75.9211 -171.840378)
			(xy 75.948843 -171.798818) (xy 75.966066 -171.780708) (xy 76.797154 -170.94962) (xy 76.815236 -170.932349)
			(xy 76.856785 -170.90454) (xy 76.902961 -170.885371) (xy 76.951988 -170.875577) (xy 76.976986 -170.874944)
			(xy 94.473522 -170.874944) (xy 94.483595 -170.874545) (xy 94.502193 -170.866807) (xy 94.50959 -170.859958)
			(xy 96.212914 -169.156888) (xy 96.219754 -169.149488) (xy 96.227473 -169.130889) (xy 96.2279 -169.12082)
			(xy 96.2279 -153.462228) (xy 96.227457 -153.452209) (xy 96.219797 -153.433692) (xy 96.205631 -153.419519)
			(xy 96.187119 -153.411848) (xy 96.1771 -153.411428) (xy 92.304362 -153.411428) (xy 92.298433 -153.411283)
			(xy 92.286887 -153.408581) (xy 92.281502 -153.406094) (xy 92.155518 -153.342594) (xy 92.150354 -153.339794)
			(xy 92.141376 -153.332221) (xy 92.137738 -153.327608) (xy 92.109036 -153.289254) (xy 92.088386 -153.262565)
			(xy 92.041187 -153.214338) (xy 91.988022 -153.172779) (xy 91.929825 -153.138621) (xy 91.867621 -153.112463)
			(xy 91.802502 -153.094766) (xy 91.735614 -153.085841) (xy 91.701874 -153.085292) (xy 91.70162 -153.085292)
			(xy 91.676728 -153.0858) (xy 91.675204 -153.0858) (xy 91.624912 -153.08961) (xy 91.61948 -153.089872)
			(xy 91.608718 -153.088332) (xy 91.603576 -153.086562) (xy 91.5035 -153.049478) (xy 91.498677 -153.047612)
			(xy 91.489847 -153.042236) (xy 91.485974 -153.03881) (xy 91.39555 -152.952958) (xy 91.377921 -152.935612)
			(xy 91.34796 -152.896265) (xy 91.32475 -152.852596) (xy 91.308899 -152.80575) (xy 91.300825 -152.756959)
			(xy 91.3003 -152.732232) (xy 91.3003 -150.671784) (xy 91.283282 -150.646384) (xy 91.269058 -150.640542)
			(xy 91.259617 -150.637132) (xy 91.239561 -150.637176) (xy 91.221053 -150.644902) (xy 91.213686 -150.651718)
			(xy 90.222578 -151.642572) (xy 90.204481 -151.659827) (xy 90.162937 -151.687638) (xy 90.116766 -151.706812)
			(xy 90.067742 -151.716611) (xy 90.042746 -151.717248) (xy 84.350606 -151.717248) (xy 84.340535 -151.717664)
			(xy 84.321937 -151.72539) (xy 84.314538 -151.732234) (xy 82.152396 -153.894282) (xy 83.466178 -153.894282)
			(xy 83.466726 -153.865366) (xy 83.475445 -153.808195) (xy 83.492695 -153.752995) (xy 83.518081 -153.701033)
			(xy 83.551021 -153.653498) (xy 83.590759 -153.611482) (xy 83.613244 -153.593292) (xy 83.622052 -153.585686)
			(xy 83.632233 -153.564784) (xy 83.632802 -153.55316) (xy 83.632802 -153.473404) (xy 83.632246 -153.461774)
			(xy 83.622069 -153.440865) (xy 83.613244 -153.433272) (xy 83.590756 -153.415086) (xy 83.551019 -153.373066)
			(xy 83.51808 -153.325531) (xy 83.492691 -153.273568) (xy 83.475437 -153.218369) (xy 83.466711 -153.161199)
			(xy 83.466178 -153.132282) (xy 83.466661 -153.105031) (xy 83.47442 -153.051084) (xy 83.489776 -152.99879)
			(xy 83.512419 -152.949214) (xy 83.541885 -152.903364) (xy 83.577577 -152.862174) (xy 83.618767 -152.826483)
			(xy 83.664617 -152.797017) (xy 83.714194 -152.774375) (xy 83.766488 -152.759019) (xy 83.820435 -152.751261)
			(xy 83.847686 -152.750774) (xy 83.874961 -152.751244) (xy 83.928959 -152.758987) (xy 83.981303 -152.774346)
			(xy 84.030923 -152.797008) (xy 84.076808 -152.82651) (xy 84.11802 -152.86225) (xy 84.153718 -152.903497)
			(xy 84.183174 -152.949411) (xy 84.194904 -152.97404) (xy 84.201 -152.987248) (xy 84.224622 -153.00325)
			(xy 84.344256 -153.007822) (xy 84.369148 -152.993852) (xy 84.376006 -152.981406) (xy 84.388811 -152.959294)
			(xy 84.419408 -152.918369) (xy 84.455175 -152.881876) (xy 84.475066 -152.865836) (xy 84.483858 -152.858215)
			(xy 84.494047 -152.837324) (xy 84.494624 -152.825704) (xy 84.494624 -152.745948) (xy 84.494127 -152.73431)
			(xy 84.483911 -152.713399) (xy 84.475066 -152.705816) (xy 84.452583 -152.687625) (xy 84.412849 -152.645604)
			(xy 84.379911 -152.598069) (xy 84.354523 -152.546108) (xy 84.337266 -152.490911) (xy 84.328536 -152.433742)
			(xy 84.328 -152.404826) (xy 84.328486 -152.377575) (xy 84.336242 -152.323627) (xy 84.351597 -152.271332)
			(xy 84.374239 -152.221755) (xy 84.403705 -152.175905) (xy 84.439396 -152.134714) (xy 84.480587 -152.099023)
			(xy 84.526437 -152.069557) (xy 84.576014 -152.046915) (xy 84.628309 -152.03156) (xy 84.682257 -152.023804)
			(xy 84.736759 -152.023804) (xy 84.790707 -152.03156) (xy 84.843002 -152.046915) (xy 84.892579 -152.069557)
			(xy 84.938429 -152.099023) (xy 84.97962 -152.134714) (xy 85.015311 -152.175905) (xy 85.044777 -152.221755)
			(xy 85.067419 -152.271332) (xy 85.082774 -152.323627) (xy 85.09053 -152.377575) (xy 85.091016 -152.404826)
			(xy 85.090476 -152.433743) (xy 85.081756 -152.490914) (xy 85.064505 -152.546114) (xy 85.039117 -152.598076)
			(xy 85.006176 -152.645611) (xy 84.966435 -152.687626) (xy 84.94395 -152.705816) (xy 84.935137 -152.713417)
			(xy 84.924958 -152.734323) (xy 84.924392 -152.745948) (xy 84.924392 -152.825704) (xy 84.924946 -152.837334)
			(xy 84.935125 -152.858243) (xy 84.94395 -152.865836) (xy 84.966461 -152.883994) (xy 85.006192 -152.926022)
			(xy 85.039127 -152.973564) (xy 85.06451 -153.025532) (xy 85.081761 -153.080735) (xy 85.090484 -153.137908)
			(xy 85.091016 -153.166826) (xy 85.090546 -153.194078) (xy 85.082787 -153.248025) (xy 85.067429 -153.30032)
			(xy 85.044785 -153.349897) (xy 85.015317 -153.395747) (xy 84.979624 -153.436936) (xy 84.938432 -153.472628)
			(xy 84.892581 -153.502094) (xy 84.843003 -153.524735) (xy 84.790708 -153.54009) (xy 84.73676 -153.547848)
			(xy 84.709508 -153.548334) (xy 84.682233 -153.547865) (xy 84.628235 -153.540121) (xy 84.575892 -153.524761)
			(xy 84.526271 -153.502099) (xy 84.480387 -153.472597) (xy 84.439175 -153.436857) (xy 84.403476 -153.39561)
			(xy 84.37402 -153.349696) (xy 84.36229 -153.325068) (xy 84.356194 -153.31186) (xy 84.332572 -153.295858)
			(xy 84.212938 -153.291286) (xy 84.188046 -153.305256) (xy 84.181188 -153.317702) (xy 84.168386 -153.339816)
			(xy 84.137788 -153.38074) (xy 84.102019 -153.417232) (xy 84.082128 -153.433272) (xy 84.073332 -153.440889)
			(xy 84.063145 -153.461783) (xy 84.06257 -153.473404) (xy 84.06257 -153.55316) (xy 84.063064 -153.564798)
			(xy 84.073282 -153.585709) (xy 84.082128 -153.593292) (xy 84.104613 -153.61148) (xy 84.144347 -153.653502)
			(xy 84.177285 -153.701037) (xy 84.202673 -153.752999) (xy 84.219929 -153.808197) (xy 84.228659 -153.865366)
			(xy 84.229194 -153.894282) (xy 84.228708 -153.921533) (xy 84.220952 -153.975481) (xy 84.205597 -154.027776)
			(xy 84.182955 -154.077353) (xy 84.153489 -154.123203) (xy 84.117798 -154.164394) (xy 84.076607 -154.200085)
			(xy 84.030757 -154.229551) (xy 83.98118 -154.252193) (xy 83.928885 -154.267548) (xy 83.874937 -154.275304)
			(xy 83.820435 -154.275304) (xy 83.766487 -154.267548) (xy 83.714192 -154.252193) (xy 83.664615 -154.229551)
			(xy 83.618765 -154.200085) (xy 83.577574 -154.164394) (xy 83.541883 -154.123203) (xy 83.512417 -154.077353)
			(xy 83.489775 -154.027776) (xy 83.47442 -153.975481) (xy 83.466664 -153.921533) (xy 83.466178 -153.894282)
			(xy 82.152396 -153.894282) (xy 80.218099 -155.828495) (xy 83.791294 -155.828495) (xy 83.795025 -155.775242)
			(xy 83.806143 -155.72303) (xy 83.824431 -155.672877) (xy 83.849532 -155.625763) (xy 83.880955 -155.582608)
			(xy 83.918088 -155.544255) (xy 83.938872 -155.527502) (xy 83.94768 -155.519896) (xy 83.95786 -155.498994)
			(xy 83.95843 -155.48737) (xy 83.95843 -155.407614) (xy 83.957893 -155.395981) (xy 83.947705 -155.37507)
			(xy 83.938872 -155.367482) (xy 83.916374 -155.349308) (xy 83.876641 -155.307284) (xy 83.843705 -155.259745)
			(xy 83.818319 -155.207781) (xy 83.801066 -155.152581) (xy 83.79234 -155.095409) (xy 83.791806 -155.066492)
			(xy 83.792248 -155.039238) (xy 83.800006 -154.985286) (xy 83.815364 -154.932987) (xy 83.838009 -154.883406)
			(xy 83.867479 -154.837552) (xy 83.903175 -154.796359) (xy 83.94437 -154.760666) (xy 83.990225 -154.731198)
			(xy 84.039807 -154.708556) (xy 84.092107 -154.693202) (xy 84.14606 -154.685446) (xy 84.173314 -154.684984)
			(xy 84.202588 -154.685536) (xy 84.260445 -154.694503) (xy 84.316252 -154.712208) (xy 84.368696 -154.738236)
			(xy 84.416546 -154.771974) (xy 84.437982 -154.791918) (xy 84.438236 -154.792172) (xy 84.445552 -154.798555)
			(xy 84.463586 -154.805721) (xy 84.473288 -154.806142) (xy 84.5439 -154.806142) (xy 84.553602 -154.805721)
			(xy 84.571629 -154.798549) (xy 84.578952 -154.792172) (xy 84.57946 -154.791664) (xy 84.600916 -154.771799)
			(xy 84.648736 -154.738156) (xy 84.701126 -154.712197) (xy 84.756862 -154.69453) (xy 84.81464 -154.685566)
			(xy 84.843874 -154.684984) (xy 84.872792 -154.685489) (xy 84.929965 -154.694216) (xy 84.985166 -154.711475)
			(xy 85.037128 -154.736869) (xy 85.084661 -154.769816) (xy 85.126676 -154.809562) (xy 85.144864 -154.83205)
			(xy 85.152488 -154.840839) (xy 85.173376 -154.851031) (xy 85.184996 -154.851608) (xy 85.264752 -154.851608)
			(xy 85.276385 -154.851082) (xy 85.297294 -154.840883) (xy 85.304884 -154.83205) (xy 85.319664 -154.813652)
			(xy 85.353034 -154.780281) (xy 85.371432 -154.765502) (xy 85.380234 -154.75789) (xy 85.390419 -154.736993)
			(xy 85.39099 -154.72537) (xy 85.39099 -154.645614) (xy 85.390432 -154.633984) (xy 85.380257 -154.613075)
			(xy 85.371432 -154.605482) (xy 85.348947 -154.587293) (xy 85.30921 -154.545274) (xy 85.27627 -154.497739)
			(xy 85.250882 -154.445777) (xy 85.233627 -154.390579) (xy 85.2249 -154.333408) (xy 85.224366 -154.304492)
			(xy 85.22487 -154.277242) (xy 85.232627 -154.223296) (xy 85.247982 -154.171003) (xy 85.270622 -154.121428)
			(xy 85.300087 -154.075579) (xy 85.335776 -154.034389) (xy 85.376964 -153.998698) (xy 85.422812 -153.969231)
			(xy 85.472386 -153.946588) (xy 85.524678 -153.931231) (xy 85.578624 -153.923472) (xy 85.605874 -153.922984)
			(xy 85.634792 -153.923489) (xy 85.691965 -153.932216) (xy 85.747166 -153.949475) (xy 85.799128 -153.974869)
			(xy 85.846661 -154.007816) (xy 85.888676 -154.047562) (xy 85.906864 -154.07005) (xy 85.914488 -154.078839)
			(xy 85.935376 -154.089031) (xy 85.946996 -154.089608) (xy 86.026752 -154.089608) (xy 86.038385 -154.089082)
			(xy 86.059294 -154.078883) (xy 86.066884 -154.07005) (xy 86.081664 -154.051652) (xy 86.115034 -154.018281)
			(xy 86.133432 -154.003502) (xy 86.142234 -153.99589) (xy 86.152419 -153.974993) (xy 86.15299 -153.96337)
			(xy 86.15299 -153.883614) (xy 86.152432 -153.871984) (xy 86.142257 -153.851075) (xy 86.133432 -153.843482)
			(xy 86.110947 -153.825293) (xy 86.07121 -153.783274) (xy 86.03827 -153.735739) (xy 86.012882 -153.683777)
			(xy 85.995627 -153.628579) (xy 85.9869 -153.571408) (xy 85.986366 -153.542492) (xy 85.98687 -153.515242)
			(xy 85.994627 -153.461296) (xy 86.009982 -153.409003) (xy 86.032622 -153.359428) (xy 86.062087 -153.313579)
			(xy 86.097776 -153.272389) (xy 86.138964 -153.236698) (xy 86.184812 -153.207231) (xy 86.234386 -153.184588)
			(xy 86.286678 -153.169231) (xy 86.340624 -153.161472) (xy 86.367874 -153.160984) (xy 86.396792 -153.161489)
			(xy 86.453965 -153.170216) (xy 86.509166 -153.187475) (xy 86.561128 -153.212869) (xy 86.608661 -153.245816)
			(xy 86.650676 -153.285562) (xy 86.668864 -153.30805) (xy 86.676488 -153.316839) (xy 86.697376 -153.327031)
			(xy 86.708996 -153.327608) (xy 86.788752 -153.327608) (xy 86.800385 -153.327082) (xy 86.821294 -153.316883)
			(xy 86.828884 -153.30805) (xy 86.845637 -153.287267) (xy 86.883991 -153.250137) (xy 86.927145 -153.218715)
			(xy 86.974259 -153.193616) (xy 87.024411 -153.17533) (xy 87.076622 -153.164213) (xy 87.129874 -153.160483)
			(xy 87.183126 -153.164213) (xy 87.235337 -153.17533) (xy 87.285489 -153.193616) (xy 87.332603 -153.218715)
			(xy 87.375757 -153.250137) (xy 87.414111 -153.287267) (xy 87.430864 -153.30805) (xy 87.438488 -153.316839)
			(xy 87.459376 -153.327031) (xy 87.470996 -153.327608) (xy 87.550752 -153.327608) (xy 87.562385 -153.327082)
			(xy 87.583294 -153.316883) (xy 87.590884 -153.30805) (xy 87.607637 -153.287267) (xy 87.645991 -153.250137)
			(xy 87.689145 -153.218715) (xy 87.736259 -153.193616) (xy 87.786411 -153.17533) (xy 87.838622 -153.164213)
			(xy 87.891874 -153.160483) (xy 87.945126 -153.164213) (xy 87.997337 -153.17533) (xy 88.047489 -153.193616)
			(xy 88.094603 -153.218715) (xy 88.137757 -153.250137) (xy 88.176111 -153.287267) (xy 88.192864 -153.30805)
			(xy 88.200488 -153.316839) (xy 88.221376 -153.327031) (xy 88.232996 -153.327608) (xy 88.312752 -153.327608)
			(xy 88.324385 -153.327082) (xy 88.345294 -153.316883) (xy 88.352884 -153.30805) (xy 88.369637 -153.287267)
			(xy 88.407991 -153.250137) (xy 88.451145 -153.218715) (xy 88.498259 -153.193616) (xy 88.548411 -153.17533)
			(xy 88.600622 -153.164213) (xy 88.653874 -153.160483) (xy 88.707126 -153.164213) (xy 88.759337 -153.17533)
			(xy 88.809489 -153.193616) (xy 88.856603 -153.218715) (xy 88.899757 -153.250137) (xy 88.938111 -153.287267)
			(xy 88.954864 -153.30805) (xy 88.962488 -153.316839) (xy 88.983376 -153.327031) (xy 88.994996 -153.327608)
			(xy 89.074752 -153.327608) (xy 89.086385 -153.327082) (xy 89.107294 -153.316883) (xy 89.114884 -153.30805)
			(xy 89.131637 -153.287267) (xy 89.169991 -153.250137) (xy 89.213145 -153.218715) (xy 89.260259 -153.193616)
			(xy 89.310411 -153.17533) (xy 89.362622 -153.164213) (xy 89.415874 -153.160483) (xy 89.469126 -153.164213)
			(xy 89.521337 -153.17533) (xy 89.571489 -153.193616) (xy 89.618603 -153.218715) (xy 89.661757 -153.250137)
			(xy 89.700111 -153.287267) (xy 89.716864 -153.30805) (xy 89.724488 -153.316839) (xy 89.745376 -153.327031)
			(xy 89.756996 -153.327608) (xy 89.836752 -153.327608) (xy 89.848385 -153.327082) (xy 89.869294 -153.316883)
			(xy 89.876884 -153.30805) (xy 89.893637 -153.287267) (xy 89.931991 -153.250137) (xy 89.975145 -153.218715)
			(xy 90.022259 -153.193616) (xy 90.072411 -153.17533) (xy 90.124622 -153.164213) (xy 90.177874 -153.160483)
			(xy 90.231126 -153.164213) (xy 90.283337 -153.17533) (xy 90.333489 -153.193616) (xy 90.380603 -153.218715)
			(xy 90.423757 -153.250137) (xy 90.462111 -153.287267) (xy 90.478864 -153.30805) (xy 90.486488 -153.316839)
			(xy 90.507376 -153.327031) (xy 90.518996 -153.327608) (xy 90.598752 -153.327608) (xy 90.610385 -153.327082)
			(xy 90.631294 -153.316883) (xy 90.638884 -153.30805) (xy 90.657071 -153.285564) (xy 90.699093 -153.245831)
			(xy 90.74663 -153.212894) (xy 90.798591 -153.187506) (xy 90.853789 -153.17025) (xy 90.910958 -153.16152)
			(xy 90.939874 -153.160984) (xy 90.967126 -153.161479) (xy 91.021075 -153.169233) (xy 91.073372 -153.184585)
			(xy 91.122951 -153.207224) (xy 91.168804 -153.236688) (xy 91.209997 -153.272379) (xy 91.245691 -153.313568)
			(xy 91.27516 -153.359419) (xy 91.297803 -153.408996) (xy 91.31316 -153.461292) (xy 91.320918 -153.51524)
			(xy 91.321382 -153.542492) (xy 91.320865 -153.571409) (xy 91.312136 -153.628581) (xy 91.294879 -153.68378)
			(xy 91.269487 -153.735741) (xy 91.236543 -153.783275) (xy 91.196802 -153.825292) (xy 91.174316 -153.843482)
			(xy 91.165513 -153.851092) (xy 91.15533 -153.871991) (xy 91.154758 -153.883614) (xy 91.154758 -153.96337)
			(xy 91.155308 -153.975001) (xy 91.165487 -153.995912) (xy 91.174316 -154.003502) (xy 91.192712 -154.018284)
			(xy 91.226085 -154.051652) (xy 91.240864 -154.07005) (xy 91.248488 -154.078839) (xy 91.269376 -154.089031)
			(xy 91.280996 -154.089608) (xy 91.360752 -154.089608) (xy 91.372385 -154.089082) (xy 91.393294 -154.078883)
			(xy 91.400884 -154.07005) (xy 91.419071 -154.047564) (xy 91.461093 -154.007831) (xy 91.50863 -153.974894)
			(xy 91.560591 -153.949506) (xy 91.615789 -153.93225) (xy 91.672958 -153.92352) (xy 91.701874 -153.922984)
			(xy 91.729126 -153.923479) (xy 91.783075 -153.931233) (xy 91.835372 -153.946585) (xy 91.884951 -153.969224)
			(xy 91.930804 -153.998688) (xy 91.971997 -154.034379) (xy 92.007691 -154.075568) (xy 92.03716 -154.121419)
			(xy 92.059803 -154.170996) (xy 92.07516 -154.223292) (xy 92.082918 -154.27724) (xy 92.083382 -154.304492)
			(xy 92.082865 -154.333409) (xy 92.074136 -154.390581) (xy 92.056879 -154.44578) (xy 92.031487 -154.497741)
			(xy 91.998543 -154.545275) (xy 91.958802 -154.587292) (xy 91.936316 -154.605482) (xy 91.927513 -154.613092)
			(xy 91.91733 -154.633991) (xy 91.916758 -154.645614) (xy 91.916758 -154.72537) (xy 91.917308 -154.737001)
			(xy 91.927487 -154.757912) (xy 91.936316 -154.765502) (xy 91.957092 -154.782264) (xy 91.994224 -154.820615)
			(xy 92.025648 -154.863768) (xy 92.050749 -154.910881) (xy 92.069037 -154.961032) (xy 92.080155 -155.013244)
			(xy 92.083885 -155.066495) (xy 92.080156 -155.119747) (xy 92.06904 -155.171958) (xy 92.050753 -155.22211)
			(xy 92.025653 -155.269223) (xy 91.994231 -155.312377) (xy 91.957099 -155.350729) (xy 91.936316 -155.367482)
			(xy 91.927513 -155.375092) (xy 91.91733 -155.395991) (xy 91.916758 -155.407614) (xy 91.916758 -155.48737)
			(xy 91.917308 -155.499001) (xy 91.927487 -155.519912) (xy 91.936316 -155.527502) (xy 91.957092 -155.544264)
			(xy 91.994224 -155.582615) (xy 92.025648 -155.625768) (xy 92.050749 -155.672881) (xy 92.069037 -155.723032)
			(xy 92.080155 -155.775244) (xy 92.083885 -155.828495) (xy 92.080156 -155.881747) (xy 92.06904 -155.933958)
			(xy 92.050753 -155.98411) (xy 92.025653 -156.031223) (xy 91.994231 -156.074377) (xy 91.957099 -156.112729)
			(xy 91.936316 -156.129482) (xy 91.927513 -156.137092) (xy 91.91733 -156.157991) (xy 91.916758 -156.169614)
			(xy 91.916758 -156.24937) (xy 91.917308 -156.261001) (xy 91.927487 -156.281912) (xy 91.936316 -156.289502)
			(xy 91.958804 -156.307688) (xy 91.998538 -156.349709) (xy 92.031476 -156.397245) (xy 92.056863 -156.449207)
			(xy 92.074119 -156.504406) (xy 92.082847 -156.561576) (xy 92.083382 -156.590492) (xy 92.082917 -156.618067)
			(xy 92.074965 -156.67264) (xy 92.059241 -156.7255) (xy 92.03607 -156.775546) (xy 92.005937 -156.821736)
			(xy 91.969469 -156.863106) (xy 91.948762 -156.881322) (xy 91.940671 -156.888862) (xy 91.931327 -156.908885)
			(xy 91.930728 -156.91993) (xy 91.930728 -156.997654) (xy 91.931313 -157.008701) (xy 91.940665 -157.028723)
			(xy 91.948762 -157.036262) (xy 91.96945 -157.054498) (xy 92.005924 -157.095861) (xy 92.03606 -157.142045)
			(xy 92.05923 -157.192088) (xy 92.074951 -157.244947) (xy 92.082895 -157.299519) (xy 92.083382 -157.327092)
			(xy 92.082937 -157.354346) (xy 92.075181 -157.408299) (xy 92.059824 -157.460599) (xy 92.037181 -157.51018)
			(xy 92.007711 -157.556035) (xy 91.972015 -157.597228) (xy 91.93082 -157.632922) (xy 91.884965 -157.662389)
			(xy 91.835382 -157.685031) (xy 91.783081 -157.700384) (xy 91.729128 -157.708138) (xy 91.701874 -157.7086)
			(xy 91.672959 -157.708029) (xy 91.61579 -157.699311) (xy 91.560593 -157.682063) (xy 91.508631 -157.656682)
			(xy 91.461095 -157.623747) (xy 91.419076 -157.584015) (xy 91.400884 -157.561534) (xy 91.393285 -157.552719)
			(xy 91.372378 -157.542542) (xy 91.360752 -157.541976) (xy 91.280996 -157.541976) (xy 91.269362 -157.542501)
			(xy 91.248451 -157.552697) (xy 91.240864 -157.561534) (xy 91.224111 -157.582317) (xy 91.185757 -157.619447)
			(xy 91.142603 -157.650869) (xy 91.095489 -157.675968) (xy 91.045337 -157.694254) (xy 90.993126 -157.705371)
			(xy 90.939874 -157.709101) (xy 90.886622 -157.705371) (xy 90.834411 -157.694254) (xy 90.784259 -157.675968)
			(xy 90.737145 -157.650869) (xy 90.693991 -157.619447) (xy 90.655637 -157.582317) (xy 90.638884 -157.561534)
			(xy 90.631285 -157.552719) (xy 90.610378 -157.542542) (xy 90.598752 -157.541976) (xy 90.518996 -157.541976)
			(xy 90.507362 -157.542501) (xy 90.486451 -157.552697) (xy 90.478864 -157.561534) (xy 90.460702 -157.584042)
			(xy 90.418675 -157.623774) (xy 90.371134 -157.656709) (xy 90.319167 -157.682093) (xy 90.263965 -157.699344)
			(xy 90.206792 -157.708068) (xy 90.177874 -157.7086) (xy 90.15153 -157.708154) (xy 90.099341 -157.700917)
			(xy 90.048644 -157.686571) (xy 90.000402 -157.665389) (xy 89.955532 -157.637772) (xy 89.914886 -157.604247)
			(xy 89.879239 -157.565449) (xy 89.849266 -157.522118) (xy 89.837006 -157.498796) (xy 89.830656 -157.485842)
			(xy 89.806272 -157.470856) (xy 86.739476 -157.470856) (xy 86.715092 -157.485842) (xy 86.708742 -157.498796)
			(xy 86.696496 -157.522125) (xy 86.666517 -157.565453) (xy 86.630865 -157.604247) (xy 86.590217 -157.63777)
			(xy 86.545346 -157.665386) (xy 86.497103 -157.686569) (xy 86.446407 -157.700918) (xy 86.394218 -157.708159)
			(xy 86.367874 -157.7086) (xy 86.338959 -157.708029) (xy 86.28179 -157.699311) (xy 86.226593 -157.682063)
			(xy 86.174631 -157.656682) (xy 86.127095 -157.623747) (xy 86.085076 -157.584015) (xy 86.066884 -157.561534)
			(xy 86.059285 -157.552719) (xy 86.038378 -157.542542) (xy 86.026752 -157.541976) (xy 85.946996 -157.541976)
			(xy 85.935362 -157.542501) (xy 85.914451 -157.552697) (xy 85.906864 -157.561534) (xy 85.890111 -157.582317)
			(xy 85.851757 -157.619447) (xy 85.808603 -157.650869) (xy 85.761489 -157.675968) (xy 85.711337 -157.694254)
			(xy 85.659126 -157.705371) (xy 85.605874 -157.709101) (xy 85.552622 -157.705371) (xy 85.500411 -157.694254)
			(xy 85.450259 -157.675968) (xy 85.403145 -157.650869) (xy 85.359991 -157.619447) (xy 85.321637 -157.582317)
			(xy 85.304884 -157.561534) (xy 85.297285 -157.552719) (xy 85.276378 -157.542542) (xy 85.264752 -157.541976)
			(xy 85.184996 -157.541976) (xy 85.173362 -157.542501) (xy 85.152451 -157.552697) (xy 85.144864 -157.561534)
			(xy 85.126702 -157.584042) (xy 85.084675 -157.623774) (xy 85.037134 -157.656709) (xy 84.985167 -157.682093)
			(xy 84.929965 -157.699344) (xy 84.872792 -157.708068) (xy 84.843874 -157.7086) (xy 84.8146 -157.70806)
			(xy 84.756742 -157.699091) (xy 84.700935 -157.681383) (xy 84.64849 -157.655352) (xy 84.600641 -157.621611)
			(xy 84.579206 -157.601666) (xy 84.578952 -157.601412) (xy 84.571598 -157.595078) (xy 84.553594 -157.587881)
			(xy 84.5439 -157.587442) (xy 84.473288 -157.587442) (xy 84.463586 -157.587861) (xy 84.445559 -157.595035)
			(xy 84.438236 -157.601412) (xy 84.437728 -157.60192) (xy 84.416275 -157.621788) (xy 84.368454 -157.655431)
			(xy 84.316063 -157.68139) (xy 84.260327 -157.699056) (xy 84.202548 -157.708019) (xy 84.173314 -157.7086)
			(xy 84.146061 -157.708132) (xy 84.09211 -157.700376) (xy 84.039812 -157.685022) (xy 83.990231 -157.66238)
			(xy 83.944378 -157.632913) (xy 83.903185 -157.59722) (xy 83.867491 -157.556027) (xy 83.838023 -157.510174)
			(xy 83.81538 -157.460594) (xy 83.800025 -157.408296) (xy 83.792269 -157.354345) (xy 83.791806 -157.327092)
			(xy 83.792333 -157.29952) (xy 83.800273 -157.244949) (xy 83.815985 -157.192091) (xy 83.839144 -157.142044)
			(xy 83.869266 -157.095853) (xy 83.905723 -157.054479) (xy 83.926426 -157.036262) (xy 83.934523 -157.028726)
			(xy 83.943864 -157.0087) (xy 83.94446 -156.997654) (xy 83.94446 -156.91993) (xy 83.943888 -156.908881)
			(xy 83.934527 -156.888859) (xy 83.926426 -156.881322) (xy 83.905727 -156.863097) (xy 83.869255 -156.821732)
			(xy 83.839121 -156.775545) (xy 83.815953 -156.7255) (xy 83.800234 -156.672639) (xy 83.792292 -156.618066)
			(xy 83.791806 -156.590492) (xy 83.792388 -156.561577) (xy 83.801103 -156.504409) (xy 83.818349 -156.449211)
			(xy 83.843728 -156.397249) (xy 83.876661 -156.349714) (xy 83.916391 -156.307694) (xy 83.938872 -156.289502)
			(xy 83.94768 -156.281896) (xy 83.95786 -156.260994) (xy 83.95843 -156.24937) (xy 83.95843 -156.169614)
			(xy 83.957893 -156.157981) (xy 83.947705 -156.13707) (xy 83.938872 -156.129482) (xy 83.91808 -156.112738)
			(xy 83.880949 -156.074385) (xy 83.849526 -156.031229) (xy 83.824427 -155.984115) (xy 83.80614 -155.933961)
			(xy 83.795023 -155.881748) (xy 83.791294 -155.828495) (xy 80.218099 -155.828495) (xy 78.473554 -157.572964)
			(xy 78.455466 -157.590229) (xy 78.413919 -157.618039) (xy 78.367746 -157.63721) (xy 78.318719 -157.647006)
			(xy 78.293722 -157.64764) (xy 70.327266 -157.64764) (xy 70.317193 -157.648037) (xy 70.298595 -157.655777)
			(xy 70.291198 -157.662626) (xy 68.609718 -159.343852) (xy 68.602909 -159.351277) (xy 68.59517 -159.369857)
			(xy 68.594732 -159.37992) (xy 68.594732 -164.097716) (xy 86.637622 -164.097716) (xy 86.638123 -164.068308)
			(xy 86.647149 -164.010189) (xy 86.66499 -163.954145) (xy 86.691223 -163.901503) (xy 86.725225 -163.853512)
			(xy 86.745318 -163.832032) (xy 86.751922 -163.825428) (xy 86.759288 -163.807902) (xy 86.761828 -163.730178)
			(xy 86.761678 -163.720682) (xy 86.755299 -163.702808) (xy 86.749382 -163.69538) (xy 86.732199 -163.674557)
			(xy 86.703277 -163.62897) (xy 86.681067 -163.579764) (xy 86.66601 -163.527919) (xy 86.658407 -163.47447)
			(xy 86.657942 -163.447476) (xy 86.658384 -163.420105) (xy 86.666206 -163.365924) (xy 86.6817 -163.31342)
			(xy 86.704547 -163.263674) (xy 86.734278 -163.217709) (xy 86.751922 -163.196778) (xy 86.752176 -163.196524)
			(xy 86.757768 -163.189441) (xy 86.764009 -163.172521) (xy 86.764368 -163.163504) (xy 86.764368 -163.096448)
			(xy 86.763995 -163.087433) (xy 86.757759 -163.070515) (xy 86.752176 -163.063428) (xy 86.751922 -163.063428)
			(xy 86.751922 -163.063174) (xy 86.734308 -163.042222) (xy 86.704591 -162.996255) (xy 86.68175 -162.946513)
			(xy 86.666253 -162.894016) (xy 86.658419 -162.839844) (xy 86.657942 -162.812476) (xy 86.658333 -162.78522)
			(xy 86.666094 -162.731264) (xy 86.681456 -162.678962) (xy 86.704105 -162.629378) (xy 86.73358 -162.583523)
			(xy 86.769281 -162.542329) (xy 86.810482 -162.506636) (xy 86.856343 -162.477169) (xy 86.905931 -162.45453)
			(xy 86.958236 -162.439178) (xy 87.012194 -162.431427) (xy 87.03945 -162.430968) (xy 87.06682 -162.431447)
			(xy 87.120999 -162.439259) (xy 87.173503 -162.454744) (xy 87.22325 -162.477584) (xy 87.269217 -162.507307)
			(xy 87.290148 -162.524948) (xy 87.290402 -162.525202) (xy 87.297484 -162.530796) (xy 87.314404 -162.537038)
			(xy 87.323422 -162.537394) (xy 87.390478 -162.537394) (xy 87.399494 -162.537028) (xy 87.416411 -162.530787)
			(xy 87.423498 -162.525202) (xy 87.423498 -162.524948) (xy 87.423752 -162.524948) (xy 87.444685 -162.507307)
			(xy 87.490653 -162.477583) (xy 87.540399 -162.454737) (xy 87.592901 -162.439241) (xy 87.647079 -162.431412)
			(xy 87.701821 -162.431412) (xy 87.755999 -162.439241) (xy 87.808501 -162.454737) (xy 87.858247 -162.477583)
			(xy 87.904215 -162.507307) (xy 87.925148 -162.524948) (xy 87.925402 -162.525202) (xy 87.932484 -162.530796)
			(xy 87.949404 -162.537038) (xy 87.958422 -162.537394) (xy 88.025478 -162.537394) (xy 88.034494 -162.537028)
			(xy 88.051411 -162.530787) (xy 88.058498 -162.525202) (xy 88.058498 -162.524948) (xy 88.058752 -162.524948)
			(xy 88.079685 -162.507307) (xy 88.125653 -162.477583) (xy 88.175399 -162.454737) (xy 88.227901 -162.439241)
			(xy 88.282079 -162.431412) (xy 88.336821 -162.431412) (xy 88.390999 -162.439241) (xy 88.443501 -162.454737)
			(xy 88.493247 -162.477583) (xy 88.539215 -162.507307) (xy 88.560148 -162.524948) (xy 88.560402 -162.525202)
			(xy 88.567484 -162.530796) (xy 88.584404 -162.537038) (xy 88.593422 -162.537394) (xy 88.660478 -162.537394)
			(xy 88.669494 -162.537028) (xy 88.686411 -162.530787) (xy 88.693498 -162.525202) (xy 88.693498 -162.524948)
			(xy 88.693752 -162.524948) (xy 88.714685 -162.507307) (xy 88.760653 -162.477583) (xy 88.810399 -162.454737)
			(xy 88.862901 -162.439241) (xy 88.917079 -162.431412) (xy 88.971821 -162.431412) (xy 89.025999 -162.439241)
			(xy 89.078501 -162.454737) (xy 89.128247 -162.477583) (xy 89.174215 -162.507307) (xy 89.195148 -162.524948)
			(xy 89.195402 -162.525202) (xy 89.202484 -162.530796) (xy 89.219404 -162.537038) (xy 89.228422 -162.537394)
			(xy 89.295478 -162.537394) (xy 89.304494 -162.537028) (xy 89.321411 -162.530787) (xy 89.328498 -162.525202)
			(xy 89.328498 -162.524948) (xy 89.328752 -162.524948) (xy 89.349698 -162.507325) (xy 89.395666 -162.477609)
			(xy 89.44541 -162.45477) (xy 89.497908 -162.439275) (xy 89.552082 -162.431443) (xy 89.57945 -162.430968)
			(xy 89.60876 -162.431511) (xy 89.666686 -162.440505) (xy 89.722554 -162.458257) (xy 89.775046 -162.48435)
			(xy 89.822928 -162.518168) (xy 89.844372 -162.538156) (xy 89.851569 -162.544521) (xy 89.869324 -162.551829)
			(xy 89.878916 -162.55238) (xy 89.958164 -162.553396) (xy 89.976198 -162.546538) (xy 89.98331 -162.540188)
			(xy 90.004476 -162.521627) (xy 90.051268 -162.490328) (xy 90.102149 -162.466241) (xy 90.156017 -162.449889)
			(xy 90.211702 -162.441627) (xy 90.23985 -162.441128) (xy 90.267103 -162.441602) (xy 90.321056 -162.449353)
			(xy 90.373356 -162.464705) (xy 90.422938 -162.487344) (xy 90.468793 -162.51681) (xy 90.509987 -162.552503)
			(xy 90.545682 -162.593696) (xy 90.575149 -162.63955) (xy 90.597791 -162.689131) (xy 90.613144 -162.741431)
			(xy 90.620897 -162.795383) (xy 90.621358 -162.822636) (xy 90.620923 -162.850007) (xy 90.613099 -162.904188)
			(xy 90.597604 -162.956692) (xy 90.574755 -163.006439) (xy 90.545023 -163.052404) (xy 90.527378 -163.073334)
			(xy 90.527124 -163.073588) (xy 90.521527 -163.080667) (xy 90.515289 -163.09759) (xy 90.514932 -163.106608)
			(xy 90.514932 -163.173664) (xy 90.515299 -163.18268) (xy 90.521539 -163.199597) (xy 90.527124 -163.206684)
			(xy 90.527378 -163.206684) (xy 90.527378 -163.206938) (xy 90.544998 -163.227885) (xy 90.574714 -163.273854)
			(xy 90.597553 -163.323597) (xy 90.613049 -163.376095) (xy 90.620882 -163.430268) (xy 90.621358 -163.457636)
			(xy 90.620806 -163.487042) (xy 90.611789 -163.545157) (xy 90.593959 -163.601201) (xy 90.567738 -163.653843)
			(xy 90.533749 -163.701837) (xy 90.513662 -163.72332) (xy 90.507058 -163.729924) (xy 90.499692 -163.74745)
			(xy 90.497152 -163.825174) (xy 90.497338 -163.834663) (xy 90.503725 -163.852516) (xy 90.509598 -163.859972)
			(xy 90.526755 -163.880815) (xy 90.555682 -163.926396) (xy 90.577898 -163.975598) (xy 90.592961 -164.027438)
			(xy 90.60057 -164.080884) (xy 90.601038 -164.107876) (xy 90.6005 -164.135125) (xy 90.592747 -164.189069)
			(xy 90.577396 -164.241361) (xy 90.55476 -164.290936) (xy 90.525299 -164.336785) (xy 90.489613 -164.377975)
			(xy 90.448429 -164.413667) (xy 90.402584 -164.443134) (xy 90.353012 -164.465778) (xy 90.300722 -164.481136)
			(xy 90.246779 -164.488896) (xy 90.21953 -164.489384) (xy 90.19022 -164.488839) (xy 90.132295 -164.479843)
			(xy 90.076428 -164.462091) (xy 90.023935 -164.435999) (xy 89.976053 -164.402183) (xy 89.954608 -164.382196)
			(xy 89.947422 -164.375816) (xy 89.929659 -164.368518) (xy 89.920064 -164.367972) (xy 89.840816 -164.366956)
			(xy 89.822782 -164.373814) (xy 89.81567 -164.380164) (xy 89.794479 -164.398695) (xy 89.747694 -164.429997)
			(xy 89.696818 -164.454089) (xy 89.642956 -164.470448) (xy 89.587276 -164.478719) (xy 89.55913 -164.479224)
			(xy 89.53176 -164.478759) (xy 89.47758 -164.470944) (xy 89.425076 -164.455455) (xy 89.375329 -164.432613)
			(xy 89.329363 -164.402887) (xy 89.308432 -164.385244) (xy 89.308178 -164.38499) (xy 89.301103 -164.379387)
			(xy 89.284177 -164.37315) (xy 89.275158 -164.372798) (xy 89.208102 -164.372798) (xy 89.199085 -164.373156)
			(xy 89.182168 -164.379403) (xy 89.175082 -164.38499) (xy 89.175082 -164.385244) (xy 89.174828 -164.385244)
			(xy 89.153895 -164.402885) (xy 89.107927 -164.432609) (xy 89.058181 -164.455455) (xy 89.005679 -164.470951)
			(xy 88.951501 -164.47878) (xy 88.896759 -164.47878) (xy 88.842581 -164.470951) (xy 88.790079 -164.455455)
			(xy 88.740333 -164.432609) (xy 88.694365 -164.402885) (xy 88.673432 -164.385244) (xy 88.673178 -164.38499)
			(xy 88.666103 -164.379387) (xy 88.649177 -164.37315) (xy 88.640158 -164.372798) (xy 88.573102 -164.372798)
			(xy 88.564085 -164.373156) (xy 88.547168 -164.379403) (xy 88.540082 -164.38499) (xy 88.540082 -164.385244)
			(xy 88.539828 -164.385244) (xy 88.518895 -164.402885) (xy 88.472927 -164.432609) (xy 88.423181 -164.455455)
			(xy 88.370679 -164.470951) (xy 88.316501 -164.47878) (xy 88.261759 -164.47878) (xy 88.207581 -164.470951)
			(xy 88.155079 -164.455455) (xy 88.105333 -164.432609) (xy 88.059365 -164.402885) (xy 88.038432 -164.385244)
			(xy 88.038178 -164.38499) (xy 88.031103 -164.379387) (xy 88.014177 -164.37315) (xy 88.005158 -164.372798)
			(xy 87.938102 -164.372798) (xy 87.929085 -164.373156) (xy 87.912168 -164.379403) (xy 87.905082 -164.38499)
			(xy 87.905082 -164.385244) (xy 87.904828 -164.385244) (xy 87.883895 -164.402885) (xy 87.837927 -164.432609)
			(xy 87.788181 -164.455455) (xy 87.735679 -164.470951) (xy 87.681501 -164.47878) (xy 87.626759 -164.47878)
			(xy 87.572581 -164.470951) (xy 87.520079 -164.455455) (xy 87.470333 -164.432609) (xy 87.424365 -164.402885)
			(xy 87.403432 -164.385244) (xy 87.403178 -164.38499) (xy 87.396103 -164.379387) (xy 87.379177 -164.37315)
			(xy 87.370158 -164.372798) (xy 87.303102 -164.372798) (xy 87.294085 -164.373156) (xy 87.277168 -164.379403)
			(xy 87.270082 -164.38499) (xy 87.270082 -164.385244) (xy 87.269828 -164.385244) (xy 87.248902 -164.402891)
			(xy 87.202927 -164.4326) (xy 87.153178 -164.455434) (xy 87.100676 -164.470923) (xy 87.046499 -164.478751)
			(xy 87.01913 -164.479224) (xy 86.991879 -164.478717) (xy 86.93793 -164.470964) (xy 86.885634 -164.455613)
			(xy 86.836055 -164.432975) (xy 86.790203 -164.403512) (xy 86.74901 -164.367823) (xy 86.713316 -164.326634)
			(xy 86.683847 -164.280785) (xy 86.661203 -164.231209) (xy 86.645845 -164.178915) (xy 86.638086 -164.124967)
			(xy 86.637622 -164.097716) (xy 68.594732 -164.097716) (xy 68.594732 -164.462206) (xy 68.594111 -164.487189)
			(xy 68.584371 -164.536197) (xy 68.565267 -164.582367) (xy 68.537531 -164.623928) (xy 68.52031 -164.642038)
			(xy 68.517262 -164.645086) (xy 68.51043 -164.652492) (xy 68.502707 -164.671087) (xy 68.502276 -164.681154)
			(xy 68.502276 -164.73424) (xy 68.501663 -164.759223) (xy 68.491919 -164.808231) (xy 68.472812 -164.8544)
			(xy 68.445075 -164.895961) (xy 68.427854 -164.914072) (xy 68.19519 -165.146736) (xy 68.56933 -165.146736)
			(xy 68.573401 -165.091114) (xy 68.585527 -165.036677) (xy 68.60545 -164.984586) (xy 68.632746 -164.935951)
			(xy 68.666832 -164.891808) (xy 68.706981 -164.853099) (xy 68.752339 -164.820648) (xy 68.801939 -164.795147)
			(xy 68.854723 -164.77714) (xy 68.909566 -164.76701) (xy 68.9653 -164.764973) (xy 69.020737 -164.771073)
			(xy 69.074694 -164.785179) (xy 69.126023 -164.806991) (xy 69.173629 -164.836045) (xy 69.216497 -164.87172)
			(xy 69.253714 -164.913257) (xy 69.284487 -164.95977) (xy 69.308159 -165.010267) (xy 69.324227 -165.063674)
			(xy 69.332347 -165.11885) (xy 69.332856 -165.146736) (xy 69.332347 -165.174622) (xy 69.324227 -165.229798)
			(xy 69.308159 -165.283205) (xy 69.284487 -165.333702) (xy 69.253714 -165.380215) (xy 69.216497 -165.421752)
			(xy 69.173629 -165.457427) (xy 69.126023 -165.486481) (xy 69.074694 -165.508293) (xy 69.020737 -165.522399)
			(xy 68.9653 -165.528499) (xy 68.909566 -165.526462) (xy 68.854723 -165.516332) (xy 68.801939 -165.498325)
			(xy 68.752339 -165.472824) (xy 68.706981 -165.440373) (xy 68.666832 -165.401664) (xy 68.632746 -165.357521)
			(xy 68.60545 -165.308886) (xy 68.585527 -165.256795) (xy 68.573401 -165.202358) (xy 68.56933 -165.146736)
			(xy 68.19519 -165.146736) (xy 68.055998 -165.285928) (xy 68.041697 -165.299752) (xy 68.009556 -165.32318)
			(xy 67.974161 -165.341322) (xy 67.936374 -165.353733) (xy 67.916806 -165.357302) (xy 67.90877 -165.358955)
			(xy 67.89426 -165.36659) (xy 67.888358 -165.372288) (xy 67.870293 -165.390491) (xy 67.830163 -165.422423)
			(xy 67.786112 -165.448682) (xy 67.738937 -165.468793) (xy 67.689489 -165.482393) (xy 67.638664 -165.489237)
			(xy 67.613022 -165.489636) (xy 67.585773 -165.489101) (xy 67.531828 -165.481349) (xy 67.479536 -165.465998)
			(xy 67.429961 -165.443361) (xy 67.384112 -165.4139) (xy 67.342922 -165.378213) (xy 67.30723 -165.337028)
			(xy 67.277763 -165.291183) (xy 67.25512 -165.241611) (xy 67.239762 -165.189321) (xy 67.232002 -165.135377)
			(xy 67.231514 -165.108128) (xy 66.972618 -165.108128) (xy 66.966609 -165.128592) (xy 66.943969 -165.178168)
			(xy 66.914503 -165.224018) (xy 66.878812 -165.265208) (xy 66.837623 -165.300899) (xy 66.791774 -165.330366)
			(xy 66.742197 -165.353007) (xy 66.689904 -165.368363) (xy 66.635957 -165.37612) (xy 66.608706 -165.376606)
			(xy 66.608452 -165.376606) (xy 66.583249 -165.376191) (xy 66.533281 -165.369557) (xy 66.484626 -165.356385)
			(xy 66.438136 -165.336906) (xy 66.416174 -165.324536) (xy 66.406268 -165.318694) (xy 66.384424 -165.316662)
			(xy 66.289682 -165.35019) (xy 66.273934 -165.365684) (xy 66.26987 -165.376098) (xy 66.259131 -165.402856)
			(xy 66.230849 -165.453096) (xy 66.195325 -165.498506) (xy 66.15337 -165.538049) (xy 66.105939 -165.570825)
			(xy 66.054114 -165.596086) (xy 65.999076 -165.613257) (xy 65.942081 -165.621945) (xy 65.913254 -165.622478)
			(xy 65.886 -165.622065) (xy 65.832048 -165.614301) (xy 65.77975 -165.598939) (xy 65.730171 -165.57629)
			(xy 65.684319 -165.546816) (xy 65.643129 -165.511117) (xy 65.607438 -165.46992) (xy 65.577973 -165.424062)
			(xy 65.555335 -165.374478) (xy 65.539982 -165.322177) (xy 65.53223 -165.268224) (xy 65.531746 -165.24097)
			(xy 65.532404 -165.209407) (xy 65.542791 -165.147142) (xy 65.563278 -165.087432) (xy 65.57772 -165.05936)
			(xy 65.582546 -165.05047) (xy 65.584578 -165.030912) (xy 65.561718 -164.952426) (xy 65.558453 -164.943013)
			(xy 65.546054 -164.927448) (xy 65.537588 -164.9222) (xy 65.5125 -164.907631) (xy 65.466618 -164.87213)
			(xy 65.426643 -164.830089) (xy 65.393497 -164.782479) (xy 65.367944 -164.730398) (xy 65.350574 -164.675047)
			(xy 65.341788 -164.617704) (xy 65.341246 -164.588698) (xy 59.42584 -164.588698) (xy 59.42584 -166.86276)
			(xy 61.555122 -166.86276) (xy 61.555621 -166.835187) (xy 61.563566 -166.780615) (xy 61.579284 -166.727755)
			(xy 61.602447 -166.677709) (xy 61.632574 -166.631519) (xy 61.669037 -166.590146) (xy 61.689742 -166.57193)
			(xy 61.697811 -166.564369) (xy 61.707167 -166.544362) (xy 61.707776 -166.533322) (xy 61.707776 -166.455598)
			(xy 61.707161 -166.444554) (xy 61.697829 -166.424532) (xy 61.689742 -166.41699) (xy 61.669031 -166.398778)
			(xy 61.632559 -166.357411) (xy 61.602426 -166.311221) (xy 61.57926 -166.261173) (xy 61.563544 -166.20831)
			(xy 61.555606 -166.153735) (xy 61.555122 -166.12616) (xy 61.555621 -166.098587) (xy 61.563566 -166.044015)
			(xy 61.579284 -165.991155) (xy 61.602447 -165.941109) (xy 61.632574 -165.894919) (xy 61.669037 -165.853546)
			(xy 61.689742 -165.83533) (xy 61.697811 -165.827769) (xy 61.707167 -165.807762) (xy 61.707776 -165.796722)
			(xy 61.707776 -165.718998) (xy 61.707161 -165.707954) (xy 61.697829 -165.687932) (xy 61.689742 -165.68039)
			(xy 61.669031 -165.662178) (xy 61.632559 -165.620811) (xy 61.602426 -165.574621) (xy 61.57926 -165.524573)
			(xy 61.563544 -165.47171) (xy 61.555606 -165.417135) (xy 61.555122 -165.38956) (xy 61.555541 -165.362306)
			(xy 61.563303 -165.308355) (xy 61.578665 -165.256057) (xy 61.601313 -165.206478) (xy 61.630786 -165.160626)
			(xy 61.666485 -165.119435) (xy 61.707682 -165.083744) (xy 61.753539 -165.05428) (xy 61.803123 -165.031641)
			(xy 61.855423 -165.016289) (xy 61.909376 -165.008536) (xy 61.93663 -165.008052) (xy 61.964488 -165.008509)
			(xy 62.019608 -165.016639) (xy 62.072962 -165.032691) (xy 62.123417 -165.056325) (xy 62.169903 -165.08704)
			(xy 62.211432 -165.124184) (xy 62.247123 -165.166968) (xy 62.276219 -165.214484) (xy 62.298101 -165.265723)
			(xy 62.305692 -165.292532) (xy 62.307978 -165.301422) (xy 62.318646 -165.316662) (xy 62.390528 -165.364414)
			(xy 62.408562 -165.368478) (xy 62.417706 -165.367208) (xy 62.430723 -165.36554) (xy 62.456907 -165.363759)
			(xy 62.47003 -165.363652) (xy 62.484179 -165.363743) (xy 62.512402 -165.365779) (xy 62.526418 -165.367716)
			(xy 62.536324 -165.36924) (xy 62.556136 -165.364414) (xy 62.630558 -165.308534) (xy 62.640718 -165.291008)
			(xy 62.641988 -165.280848) (xy 62.646066 -165.253693) (xy 62.66104 -165.200862) (xy 62.683433 -165.150723)
			(xy 62.712781 -165.104313) (xy 62.74848 -165.062588) (xy 62.789791 -165.026412) (xy 62.835861 -164.996531)
			(xy 62.885739 -164.973563) (xy 62.938393 -164.957982) (xy 62.992738 -164.95011) (xy 63.020194 -164.949632)
			(xy 63.047449 -164.950061) (xy 63.101403 -164.957818) (xy 63.153704 -164.973176) (xy 63.203286 -164.99582)
			(xy 63.249142 -165.025291) (xy 63.290335 -165.060989) (xy 63.326029 -165.102186) (xy 63.355496 -165.148043)
			(xy 63.378136 -165.197628) (xy 63.393489 -165.249931) (xy 63.401241 -165.303885) (xy 63.401702 -165.33114)
			(xy 63.401194 -165.358713) (xy 63.39325 -165.413284) (xy 63.377533 -165.466143) (xy 63.354371 -165.516189)
			(xy 63.324246 -165.56238) (xy 63.287786 -165.603753) (xy 63.267082 -165.62197) (xy 63.259017 -165.629535)
			(xy 63.249658 -165.649539) (xy 63.249048 -165.660578) (xy 63.249048 -165.738302) (xy 63.249655 -165.749347)
			(xy 63.258991 -165.769369) (xy 63.267082 -165.77691) (xy 63.287798 -165.795116) (xy 63.324268 -165.836486)
			(xy 63.3544 -165.882676) (xy 63.377566 -165.932725) (xy 63.393281 -165.985589) (xy 63.401218 -166.040165)
			(xy 63.401252 -166.042086) (xy 67.99021 -166.042086) (xy 67.994281 -165.986464) (xy 68.006407 -165.932027)
			(xy 68.02633 -165.879936) (xy 68.053626 -165.831301) (xy 68.087712 -165.787158) (xy 68.127861 -165.748449)
			(xy 68.173219 -165.715998) (xy 68.222819 -165.690497) (xy 68.275603 -165.67249) (xy 68.330446 -165.66236)
			(xy 68.38618 -165.660323) (xy 68.441617 -165.666423) (xy 68.495574 -165.680529) (xy 68.546903 -165.702341)
			(xy 68.594509 -165.731395) (xy 68.637377 -165.76707) (xy 68.674594 -165.808607) (xy 68.705367 -165.85512)
			(xy 68.729039 -165.905617) (xy 68.745107 -165.959024) (xy 68.751788 -166.004424) (xy 82.10067 -166.004424)
			(xy 82.10067 -165.919728) (xy 82.108721 -165.835414) (xy 82.12475 -165.752248) (xy 82.148611 -165.670981)
			(xy 82.18009 -165.592351) (xy 82.218901 -165.51707) (xy 82.264691 -165.445818) (xy 82.317047 -165.379242)
			(xy 82.375495 -165.317944) (xy 82.439505 -165.262479) (xy 82.508497 -165.21335) (xy 82.581847 -165.171001)
			(xy 82.65889 -165.135817) (xy 82.738929 -165.108115) (xy 82.821238 -165.088147) (xy 82.905073 -165.076094)
			(xy 82.989674 -165.072064) (xy 83.074275 -165.076094) (xy 83.15811 -165.088147) (xy 83.240419 -165.108115)
			(xy 83.320458 -165.135817) (xy 83.397501 -165.171001) (xy 83.470851 -165.21335) (xy 83.539843 -165.262479)
			(xy 83.603853 -165.317944) (xy 83.662301 -165.379242) (xy 83.714657 -165.445818) (xy 83.760447 -165.51707)
			(xy 83.799258 -165.592351) (xy 83.830737 -165.670981) (xy 83.854598 -165.752248) (xy 83.870627 -165.835414)
			(xy 83.878678 -165.919728) (xy 83.879182 -165.962076) (xy 83.878678 -166.004424) (xy 91.49867 -166.004424)
			(xy 91.49867 -165.919728) (xy 91.506721 -165.835414) (xy 91.52275 -165.752248) (xy 91.546611 -165.670981)
			(xy 91.57809 -165.592351) (xy 91.616901 -165.51707) (xy 91.662691 -165.445818) (xy 91.715047 -165.379242)
			(xy 91.773495 -165.317944) (xy 91.837505 -165.262479) (xy 91.906497 -165.21335) (xy 91.979847 -165.171001)
			(xy 92.05689 -165.135817) (xy 92.136929 -165.108115) (xy 92.219238 -165.088147) (xy 92.303073 -165.076094)
			(xy 92.387674 -165.072064) (xy 92.472275 -165.076094) (xy 92.55611 -165.088147) (xy 92.638419 -165.108115)
			(xy 92.718458 -165.135817) (xy 92.795501 -165.171001) (xy 92.868851 -165.21335) (xy 92.937843 -165.262479)
			(xy 93.001853 -165.317944) (xy 93.060301 -165.379242) (xy 93.112657 -165.445818) (xy 93.158447 -165.51707)
			(xy 93.197258 -165.592351) (xy 93.228737 -165.670981) (xy 93.252598 -165.752248) (xy 93.268627 -165.835414)
			(xy 93.276678 -165.919728) (xy 93.277182 -165.962076) (xy 93.276678 -166.004424) (xy 93.268627 -166.088738)
			(xy 93.252598 -166.171904) (xy 93.228737 -166.253171) (xy 93.197258 -166.331801) (xy 93.158447 -166.407082)
			(xy 93.112657 -166.478334) (xy 93.060301 -166.54491) (xy 93.001853 -166.606208) (xy 92.937843 -166.661673)
			(xy 92.868851 -166.710802) (xy 92.795501 -166.753151) (xy 92.718458 -166.788335) (xy 92.638419 -166.816037)
			(xy 92.55611 -166.836005) (xy 92.472275 -166.848058) (xy 92.387674 -166.852089) (xy 92.303073 -166.848058)
			(xy 92.219238 -166.836005) (xy 92.136929 -166.816037) (xy 92.05689 -166.788335) (xy 91.979847 -166.753151)
			(xy 91.906497 -166.710802) (xy 91.837505 -166.661673) (xy 91.773495 -166.606208) (xy 91.715047 -166.54491)
			(xy 91.662691 -166.478334) (xy 91.616901 -166.407082) (xy 91.57809 -166.331801) (xy 91.546611 -166.253171)
			(xy 91.52275 -166.171904) (xy 91.506721 -166.088738) (xy 91.49867 -166.004424) (xy 83.878678 -166.004424)
			(xy 83.870627 -166.088738) (xy 83.854598 -166.171904) (xy 83.830737 -166.253171) (xy 83.799258 -166.331801)
			(xy 83.760447 -166.407082) (xy 83.714657 -166.478334) (xy 83.662301 -166.54491) (xy 83.603853 -166.606208)
			(xy 83.539843 -166.661673) (xy 83.470851 -166.710802) (xy 83.397501 -166.753151) (xy 83.320458 -166.788335)
			(xy 83.240419 -166.816037) (xy 83.15811 -166.836005) (xy 83.074275 -166.848058) (xy 82.989674 -166.852089)
			(xy 82.905073 -166.848058) (xy 82.821238 -166.836005) (xy 82.738929 -166.816037) (xy 82.65889 -166.788335)
			(xy 82.581847 -166.753151) (xy 82.508497 -166.710802) (xy 82.439505 -166.661673) (xy 82.375495 -166.606208)
			(xy 82.317047 -166.54491) (xy 82.264691 -166.478334) (xy 82.218901 -166.407082) (xy 82.18009 -166.331801)
			(xy 82.148611 -166.253171) (xy 82.12475 -166.171904) (xy 82.108721 -166.088738) (xy 82.10067 -166.004424)
			(xy 68.751788 -166.004424) (xy 68.753227 -166.0142) (xy 68.753736 -166.042086) (xy 68.753227 -166.069972)
			(xy 68.745107 -166.125148) (xy 68.729039 -166.178555) (xy 68.705367 -166.229052) (xy 68.674594 -166.275565)
			(xy 68.637377 -166.317102) (xy 68.594509 -166.352777) (xy 68.546903 -166.381831) (xy 68.495574 -166.403643)
			(xy 68.441617 -166.417749) (xy 68.38618 -166.423849) (xy 68.330446 -166.421812) (xy 68.275603 -166.411682)
			(xy 68.222819 -166.393675) (xy 68.173219 -166.368174) (xy 68.127861 -166.335723) (xy 68.087712 -166.297014)
			(xy 68.053626 -166.252871) (xy 68.02633 -166.204236) (xy 68.006407 -166.152145) (xy 67.994281 -166.097708)
			(xy 67.99021 -166.042086) (xy 63.401252 -166.042086) (xy 63.401702 -166.06774) (xy 63.401259 -166.094993)
			(xy 63.393497 -166.148942) (xy 63.378137 -166.201238) (xy 63.355491 -166.250816) (xy 63.32602 -166.296666)
			(xy 63.290324 -166.337856) (xy 63.249129 -166.373547) (xy 63.203275 -166.403013) (xy 63.153695 -166.425653)
			(xy 63.101397 -166.441007) (xy 63.047447 -166.448763) (xy 63.020194 -166.449248) (xy 63.019686 -166.449248)
			(xy 62.985904 -166.447724) (xy 62.975744 -166.446708) (xy 62.95644 -166.452804) (xy 62.893448 -166.505636)
			(xy 62.886156 -166.512357) (xy 62.876877 -166.529864) (xy 62.875414 -166.539672) (xy 62.875414 -166.540434)
			(xy 62.872452 -166.568594) (xy 62.859246 -166.623654) (xy 62.838045 -166.676157) (xy 62.809314 -166.724948)
			(xy 62.773684 -166.768954) (xy 62.73194 -166.807209) (xy 62.684998 -166.838872) (xy 62.633891 -166.863246)
			(xy 62.579742 -166.879795) (xy 62.523741 -166.888157) (xy 62.49543 -166.888668) (xy 62.477411 -166.888452)
			(xy 62.441536 -166.885014) (xy 62.423802 -166.88181) (xy 62.41415 -166.880032) (xy 62.3951 -166.883588)
			(xy 62.32017 -166.931594) (xy 62.30874 -166.947342) (xy 62.306454 -166.95674) (xy 62.29908 -166.983791)
			(xy 62.277449 -167.03552) (xy 62.248482 -167.083526) (xy 62.212804 -167.126779) (xy 62.171182 -167.164346)
			(xy 62.124511 -167.195419) (xy 62.073796 -167.21933) (xy 62.020129 -167.235564) (xy 61.964664 -167.243771)
			(xy 61.93663 -167.244268) (xy 61.909376 -167.243817) (xy 61.855423 -167.236063) (xy 61.803122 -167.220708)
			(xy 61.753539 -167.198067) (xy 61.707684 -167.168598) (xy 61.66649 -167.132903) (xy 61.630796 -167.091708)
			(xy 61.601329 -167.045852) (xy 61.578688 -166.996269) (xy 61.563335 -166.943968) (xy 61.555583 -166.890014)
			(xy 61.555122 -166.86276) (xy 59.42584 -166.86276) (xy 59.42584 -168.42232) (xy 63.19774 -168.42232)
			(xy 63.198205 -168.394745) (xy 63.206156 -168.340172) (xy 63.22188 -168.287311) (xy 63.24505 -168.237265)
			(xy 63.275183 -168.191076) (xy 63.311652 -168.149705) (xy 63.33236 -168.13149) (xy 63.340449 -168.123948)
			(xy 63.349793 -168.103926) (xy 63.350394 -168.092882) (xy 63.350394 -168.015158) (xy 63.349795 -168.004112)
			(xy 63.340452 -167.984091) (xy 63.33236 -167.97655) (xy 63.311662 -167.958325) (xy 63.275192 -167.916958)
			(xy 63.245059 -167.870771) (xy 63.221892 -167.820726) (xy 63.206172 -167.767866) (xy 63.198228 -167.713294)
			(xy 63.19774 -167.68572) (xy 63.198161 -167.659185) (xy 63.205502 -167.606625) (xy 63.22006 -167.555591)
			(xy 63.241552 -167.507068) (xy 63.269564 -167.461993) (xy 63.303555 -167.421238) (xy 63.342869 -167.385588)
			(xy 63.386745 -167.355734) (xy 63.410338 -167.343582) (xy 63.420752 -167.338502) (xy 63.43523 -167.319706)
			(xy 63.455804 -167.217344) (xy 63.449708 -167.194484) (xy 63.441834 -167.185594) (xy 63.424552 -167.165109)
			(xy 63.395397 -167.12014) (xy 63.372986 -167.071458) (xy 63.357783 -167.020066) (xy 63.350099 -166.967027)
			(xy 63.349632 -166.94023) (xy 63.350062 -166.913611) (xy 63.357636 -166.860913) (xy 63.372633 -166.809831)
			(xy 63.394748 -166.761403) (xy 63.423531 -166.716615) (xy 63.458395 -166.676381) (xy 63.498631 -166.641519)
			(xy 63.54342 -166.612738) (xy 63.591849 -166.590626) (xy 63.642933 -166.575631) (xy 63.695631 -166.568061)
			(xy 63.72225 -166.567612) (xy 63.748673 -166.568038) (xy 63.80099 -166.575495) (xy 63.851729 -166.590267)
			(xy 63.899873 -166.612058) (xy 63.944456 -166.640431) (xy 63.96482 -166.657274) (xy 63.971678 -166.663116)
			(xy 63.988696 -166.669466) (xy 64.073024 -166.669466) (xy 64.090042 -166.663116) (xy 64.0969 -166.657274)
			(xy 64.117266 -166.640435) (xy 64.161852 -166.61207) (xy 64.209996 -166.590283) (xy 64.260733 -166.575512)
			(xy 64.313048 -166.568052) (xy 64.365892 -166.568052) (xy 64.418207 -166.575512) (xy 64.468944 -166.590283)
			(xy 64.517088 -166.61207) (xy 64.561674 -166.640435) (xy 64.58204 -166.657274) (xy 64.588898 -166.663116)
			(xy 64.605916 -166.669466) (xy 64.690244 -166.669466) (xy 64.707262 -166.663116) (xy 64.71412 -166.657274)
			(xy 64.734487 -166.640438) (xy 64.779076 -166.61208) (xy 64.82722 -166.590299) (xy 64.877956 -166.575531)
			(xy 64.930269 -166.568072) (xy 64.95669 -166.567612) (xy 64.984579 -166.568046) (xy 65.039736 -166.576358)
			(xy 65.093037 -166.592798) (xy 65.143292 -166.616999) (xy 65.18938 -166.64842) (xy 65.230269 -166.686358)
			(xy 65.265047 -166.729968) (xy 65.292937 -166.778274) (xy 65.313316 -166.830197) (xy 65.325728 -166.884577)
			(xy 65.329897 -166.9402) (xy 65.325728 -166.995823) (xy 65.313316 -167.050203) (xy 65.292937 -167.102126)
			(xy 65.265047 -167.150432) (xy 65.230269 -167.194042) (xy 65.18938 -167.23198) (xy 65.143292 -167.263401)
			(xy 65.093037 -167.287602) (xy 65.039736 -167.304042) (xy 64.984579 -167.312354) (xy 64.95669 -167.312848)
			(xy 64.930269 -167.312385) (xy 64.877954 -167.304934) (xy 64.827216 -167.29017) (xy 64.779071 -167.268388)
			(xy 64.734486 -167.240024) (xy 64.71412 -167.223186) (xy 64.707262 -167.217344) (xy 64.690244 -167.210994)
			(xy 64.605916 -167.210994) (xy 64.588898 -167.217344) (xy 64.58204 -167.223186) (xy 64.561674 -167.240025)
			(xy 64.517088 -167.26839) (xy 64.468944 -167.290177) (xy 64.418207 -167.304948) (xy 64.365892 -167.312408)
			(xy 64.313048 -167.312408) (xy 64.260733 -167.304948) (xy 64.209996 -167.290177) (xy 64.161852 -167.26839)
			(xy 64.117266 -167.240025) (xy 64.0969 -167.223186) (xy 64.090042 -167.217344) (xy 64.073024 -167.210994)
			(xy 63.988696 -167.210994) (xy 63.971678 -167.217344) (xy 63.96482 -167.223186) (xy 63.947904 -167.23723)
			(xy 63.911358 -167.261676) (xy 63.891922 -167.271954) (xy 63.881729 -167.277794) (xy 63.867686 -167.296588)
			(xy 63.864998 -167.308022) (xy 63.848234 -167.398954) (xy 63.854838 -167.421814) (xy 63.862712 -167.43045)
			(xy 63.881107 -167.451542) (xy 63.912082 -167.498155) (xy 63.935914 -167.548794) (xy 63.952091 -167.602371)
			(xy 63.960266 -167.657737) (xy 63.960756 -167.68572) (xy 63.960251 -167.713293) (xy 63.952308 -167.767865)
			(xy 63.936592 -167.820725) (xy 63.91343 -167.870771) (xy 63.883303 -167.916962) (xy 63.881378 -167.919146)
			(xy 68.949062 -167.919146) (xy 68.949529 -167.891234) (xy 68.957671 -167.836008) (xy 68.973773 -167.782557)
			(xy 68.997491 -167.732023) (xy 69.028319 -167.685484) (xy 69.046598 -167.664384) (xy 69.052501 -167.657211)
			(xy 69.059148 -167.639883) (xy 69.059552 -167.630602) (xy 69.059552 -167.552878) (xy 69.052948 -167.535606)
			(xy 69.046598 -167.528494) (xy 69.028343 -167.507376) (xy 68.997512 -167.460842) (xy 68.973792 -167.410313)
			(xy 68.957691 -167.356865) (xy 68.94955 -167.301642) (xy 68.949062 -167.273732) (xy 68.949548 -167.246481)
			(xy 68.957304 -167.192533) (xy 68.972659 -167.140238) (xy 68.995301 -167.090661) (xy 69.024767 -167.044811)
			(xy 69.060458 -167.00362) (xy 69.101649 -166.967929) (xy 69.147499 -166.938463) (xy 69.197076 -166.915821)
			(xy 69.249371 -166.900466) (xy 69.303319 -166.89271) (xy 69.357821 -166.89271) (xy 69.411769 -166.900466)
			(xy 69.464064 -166.915821) (xy 69.513641 -166.938463) (xy 69.559491 -166.967929) (xy 69.600682 -167.00362)
			(xy 69.636373 -167.044811) (xy 69.665839 -167.090661) (xy 69.688481 -167.140238) (xy 69.703836 -167.192533)
			(xy 69.711592 -167.246481) (xy 69.712078 -167.273732) (xy 69.711587 -167.301643) (xy 69.70345 -167.356868)
			(xy 69.687353 -167.410318) (xy 69.66364 -167.460853) (xy 69.632818 -167.507393) (xy 69.614542 -167.528494)
			(xy 69.608641 -167.535668) (xy 69.601994 -167.552996) (xy 69.601588 -167.562276) (xy 69.601588 -167.64)
			(xy 69.608192 -167.657272) (xy 69.614542 -167.664384) (xy 69.63284 -167.685466) (xy 69.663664 -167.73201)
			(xy 69.687374 -167.782549) (xy 69.703466 -167.836004) (xy 69.711595 -167.891234) (xy 69.712078 -167.919146)
			(xy 69.711592 -167.946397) (xy 69.703836 -168.000345) (xy 69.688481 -168.05264) (xy 69.665839 -168.102217)
			(xy 69.636373 -168.148067) (xy 69.600682 -168.189258) (xy 69.559491 -168.224949) (xy 69.513641 -168.254415)
			(xy 69.464064 -168.277057) (xy 69.411769 -168.292412) (xy 69.357821 -168.300168) (xy 69.303319 -168.300168)
			(xy 69.249371 -168.292412) (xy 69.197076 -168.277057) (xy 69.147499 -168.254415) (xy 69.101649 -168.224949)
			(xy 69.060458 -168.189258) (xy 69.024767 -168.148067) (xy 68.995301 -168.102217) (xy 68.972659 -168.05264)
			(xy 68.957304 -168.000345) (xy 68.949548 -167.946397) (xy 68.949062 -167.919146) (xy 63.881378 -167.919146)
			(xy 63.846841 -167.958334) (xy 63.826136 -167.97655) (xy 63.818028 -167.984075) (xy 63.808694 -168.00411)
			(xy 63.808102 -168.015158) (xy 63.808102 -168.092882) (xy 63.80868 -168.10393) (xy 63.818038 -168.123951)
			(xy 63.826136 -168.13149) (xy 63.846853 -168.149695) (xy 63.883321 -168.191066) (xy 63.913452 -168.237257)
			(xy 63.936616 -168.287306) (xy 63.952332 -168.34017) (xy 63.960271 -168.394745) (xy 63.960756 -168.42232)
			(xy 63.96027 -168.449571) (xy 63.958455 -168.462198) (xy 82.023465 -168.462198) (xy 82.027468 -168.374336)
			(xy 82.039444 -168.287202) (xy 82.059295 -168.201518) (xy 82.086854 -168.117994) (xy 82.121895 -168.037322)
			(xy 82.164126 -167.960171) (xy 82.213198 -167.88718) (xy 82.268705 -167.818954) (xy 82.330185 -167.756058)
			(xy 82.39713 -167.699013) (xy 82.468985 -167.648292) (xy 82.545155 -167.604315) (xy 82.625008 -167.567447)
			(xy 82.707883 -167.537994) (xy 82.793093 -167.516198) (xy 82.879932 -167.502242) (xy 82.96768 -167.496239)
			(xy 83.05561 -167.498241) (xy 83.142995 -167.508231) (xy 83.229108 -167.526126) (xy 83.313238 -167.551777)
			(xy 83.394686 -167.584972) (xy 83.472779 -167.625436) (xy 83.546868 -167.672834) (xy 83.61634 -167.726773)
			(xy 83.680619 -167.786806) (xy 83.739173 -167.852435) (xy 83.791517 -167.923117) (xy 83.837216 -167.998266)
			(xy 83.875892 -168.077259) (xy 83.907224 -168.159442) (xy 83.930954 -168.244134) (xy 83.946884 -168.330633)
			(xy 83.954882 -168.418221) (xy 83.955382 -168.462198) (xy 91.421465 -168.462198) (xy 91.425468 -168.374336)
			(xy 91.437444 -168.287202) (xy 91.457295 -168.201518) (xy 91.484854 -168.117994) (xy 91.519895 -168.037322)
			(xy 91.562126 -167.960171) (xy 91.611198 -167.88718) (xy 91.666705 -167.818954) (xy 91.728185 -167.756058)
			(xy 91.79513 -167.699013) (xy 91.866985 -167.648292) (xy 91.943155 -167.604315) (xy 92.023008 -167.567447)
			(xy 92.105883 -167.537994) (xy 92.191093 -167.516198) (xy 92.277932 -167.502242) (xy 92.36568 -167.496239)
			(xy 92.45361 -167.498241) (xy 92.540995 -167.508231) (xy 92.627108 -167.526126) (xy 92.711238 -167.551777)
			(xy 92.792686 -167.584972) (xy 92.870779 -167.625436) (xy 92.944868 -167.672834) (xy 93.01434 -167.726773)
			(xy 93.078619 -167.786806) (xy 93.137173 -167.852435) (xy 93.189517 -167.923117) (xy 93.235216 -167.998266)
			(xy 93.273892 -168.077259) (xy 93.305224 -168.159442) (xy 93.328954 -168.244134) (xy 93.344884 -168.330633)
			(xy 93.352882 -168.418221) (xy 93.353382 -168.462198) (xy 93.352882 -168.506175) (xy 93.344884 -168.593763)
			(xy 93.328954 -168.680262) (xy 93.305224 -168.764954) (xy 93.273892 -168.847137) (xy 93.235216 -168.92613)
			(xy 93.189517 -169.001279) (xy 93.137173 -169.071961) (xy 93.078619 -169.13759) (xy 93.01434 -169.197623)
			(xy 92.944868 -169.251562) (xy 92.870779 -169.29896) (xy 92.792686 -169.339424) (xy 92.711238 -169.372619)
			(xy 92.627108 -169.39827) (xy 92.540995 -169.416165) (xy 92.45361 -169.426155) (xy 92.36568 -169.428157)
			(xy 92.277932 -169.422154) (xy 92.191093 -169.408198) (xy 92.105883 -169.386402) (xy 92.023008 -169.356949)
			(xy 91.943155 -169.320081) (xy 91.866985 -169.276104) (xy 91.79513 -169.225383) (xy 91.728185 -169.168338)
			(xy 91.666705 -169.105442) (xy 91.611198 -169.037216) (xy 91.562126 -168.964225) (xy 91.519895 -168.887074)
			(xy 91.484854 -168.806402) (xy 91.457295 -168.722878) (xy 91.437444 -168.637194) (xy 91.425468 -168.55006)
			(xy 91.421465 -168.462198) (xy 83.955382 -168.462198) (xy 83.954882 -168.506175) (xy 83.946884 -168.593763)
			(xy 83.930954 -168.680262) (xy 83.907224 -168.764954) (xy 83.875892 -168.847137) (xy 83.837216 -168.92613)
			(xy 83.791517 -169.001279) (xy 83.739173 -169.071961) (xy 83.680619 -169.13759) (xy 83.61634 -169.197623)
			(xy 83.546868 -169.251562) (xy 83.472779 -169.29896) (xy 83.394686 -169.339424) (xy 83.313238 -169.372619)
			(xy 83.229108 -169.39827) (xy 83.142995 -169.416165) (xy 83.05561 -169.426155) (xy 82.96768 -169.428157)
			(xy 82.879932 -169.422154) (xy 82.793093 -169.408198) (xy 82.707883 -169.386402) (xy 82.625008 -169.356949)
			(xy 82.545155 -169.320081) (xy 82.468985 -169.276104) (xy 82.39713 -169.225383) (xy 82.330185 -169.168338)
			(xy 82.268705 -169.105442) (xy 82.213198 -169.037216) (xy 82.164126 -168.964225) (xy 82.121895 -168.887074)
			(xy 82.086854 -168.806402) (xy 82.059295 -168.722878) (xy 82.039444 -168.637194) (xy 82.027468 -168.55006)
			(xy 82.023465 -168.462198) (xy 63.958455 -168.462198) (xy 63.952514 -168.503519) (xy 63.937159 -168.555814)
			(xy 63.914517 -168.605391) (xy 63.885051 -168.651241) (xy 63.84936 -168.692432) (xy 63.808169 -168.728123)
			(xy 63.762319 -168.757589) (xy 63.712742 -168.780231) (xy 63.660447 -168.795586) (xy 63.606499 -168.803342)
			(xy 63.551997 -168.803342) (xy 63.498049 -168.795586) (xy 63.445754 -168.780231) (xy 63.396177 -168.757589)
			(xy 63.350327 -168.728123) (xy 63.309136 -168.692432) (xy 63.273445 -168.651241) (xy 63.243979 -168.605391)
			(xy 63.221337 -168.555814) (xy 63.205982 -168.503519) (xy 63.198226 -168.449571) (xy 63.19774 -168.42232)
			(xy 59.42584 -168.42232) (xy 59.42584 -170.877738) (xy 59.426856 -170.88739) (xy 59.428489 -170.894631)
			(xy 59.43534 -170.907791) (xy 59.440318 -170.913298) (xy 61.812932 -173.285912) (xy 73.654666 -173.285912)
			(xy 73.655152 -173.258661) (xy 73.662908 -173.204713) (xy 73.678263 -173.152418) (xy 73.700905 -173.102841)
			(xy 73.730371 -173.056991) (xy 73.766062 -173.0158) (xy 73.807253 -172.980109) (xy 73.853103 -172.950643)
			(xy 73.90268 -172.928001) (xy 73.954975 -172.912646) (xy 74.008923 -172.90489) (xy 74.063425 -172.90489)
			(xy 74.117373 -172.912646) (xy 74.169668 -172.928001) (xy 74.219245 -172.950643) (xy 74.265095 -172.980109)
			(xy 74.306286 -173.0158) (xy 74.341977 -173.056991) (xy 74.371443 -173.102841) (xy 74.394085 -173.152418)
			(xy 74.40944 -173.204713) (xy 74.417196 -173.258661) (xy 74.417682 -173.285912) (xy 74.417014 -173.317474)
			(xy 74.40663 -173.379739) (xy 74.386148 -173.439449) (xy 74.371708 -173.467522) (xy 74.366882 -173.476412)
			(xy 74.36485 -173.49597) (xy 74.38771 -173.574456) (xy 74.390933 -173.583887) (xy 74.403362 -173.599442)
			(xy 74.41184 -173.604682) (xy 74.419206 -173.608746) (xy 74.429112 -173.614588) (xy 74.450956 -173.61662)
			(xy 74.545698 -173.583092) (xy 74.561446 -173.567598) (xy 74.56551 -173.557184) (xy 74.576173 -173.530393)
			(xy 74.604465 -173.480151) (xy 74.639999 -173.43474) (xy 74.681966 -173.395199) (xy 74.729408 -173.362426)
			(xy 74.781244 -173.337171) (xy 74.836291 -173.320009) (xy 74.893296 -173.311331) (xy 74.922126 -173.310804)
			(xy 74.949377 -173.311268) (xy 75.003324 -173.319027) (xy 75.055617 -173.334385) (xy 75.105192 -173.357029)
			(xy 75.151041 -173.386496) (xy 75.192229 -173.422189) (xy 75.227919 -173.46338) (xy 75.257384 -173.509231)
			(xy 75.280024 -173.558808) (xy 75.295378 -173.611102) (xy 75.303134 -173.665049) (xy 75.303134 -173.719551)
			(xy 75.295378 -173.773498) (xy 75.280024 -173.825792) (xy 75.257384 -173.875369) (xy 75.227919 -173.92122)
			(xy 75.192229 -173.962411) (xy 75.151041 -173.998104) (xy 75.105192 -174.027571) (xy 75.055617 -174.050215)
			(xy 75.003324 -174.065573) (xy 74.949377 -174.073332) (xy 74.922126 -174.07382) (xy 74.921872 -174.07382)
			(xy 74.896668 -174.073438) (xy 74.846699 -174.066794) (xy 74.798044 -174.053613) (xy 74.751555 -174.034124)
			(xy 74.729594 -174.02175) (xy 74.719688 -174.015908) (xy 74.697844 -174.013876) (xy 74.603102 -174.047404)
			(xy 74.587354 -174.062898) (xy 74.58329 -174.073312) (xy 74.572625 -174.100102) (xy 74.544334 -174.150345)
			(xy 74.5088 -174.195755) (xy 74.466833 -174.235297) (xy 74.419391 -174.268069) (xy 74.367556 -174.293325)
			(xy 74.312508 -174.310487) (xy 74.255504 -174.319165) (xy 74.226674 -174.319692) (xy 74.199421 -174.319246)
			(xy 74.145471 -174.311486) (xy 74.093175 -174.296127) (xy 74.043597 -174.273481) (xy 73.997745 -174.244011)
			(xy 73.956555 -174.208315) (xy 73.920864 -174.167121) (xy 73.891399 -174.121267) (xy 73.868759 -174.071686)
			(xy 73.853405 -174.019388) (xy 73.845651 -173.965437) (xy 73.845166 -173.938184) (xy 73.845839 -173.906622)
			(xy 73.856221 -173.844357) (xy 73.876701 -173.784648) (xy 73.89114 -173.756574) (xy 73.895966 -173.747684)
			(xy 73.897998 -173.728126) (xy 73.875138 -173.64964) (xy 73.871936 -173.6402) (xy 73.859493 -173.624649)
			(xy 73.851008 -173.619414) (xy 73.825887 -173.604898) (xy 73.780004 -173.56939) (xy 73.74003 -173.527341)
			(xy 73.706886 -173.479721) (xy 73.681339 -173.427631) (xy 73.663977 -173.372272) (xy 73.655202 -173.314921)
			(xy 73.654666 -173.285912) (xy 61.812932 -173.285912) (xy 64.086994 -175.559974) (xy 69.868542 -175.559974)
			(xy 69.869044 -175.532401) (xy 69.876987 -175.477829) (xy 69.892704 -175.424969) (xy 69.915867 -175.374922)
			(xy 69.945994 -175.328732) (xy 69.982457 -175.28736) (xy 70.003162 -175.269144) (xy 70.011228 -175.26158)
			(xy 70.020585 -175.241575) (xy 70.021196 -175.230536) (xy 70.021196 -175.152812) (xy 70.020622 -175.141763)
			(xy 70.011261 -175.121742) (xy 70.003162 -175.114204) (xy 69.982442 -175.096003) (xy 69.945974 -175.054631)
			(xy 69.915844 -175.008439) (xy 69.89268 -174.958389) (xy 69.876965 -174.905525) (xy 69.869027 -174.850949)
			(xy 69.868542 -174.823374) (xy 69.869044 -174.795801) (xy 69.876987 -174.741229) (xy 69.892704 -174.688369)
			(xy 69.915867 -174.638322) (xy 69.945994 -174.592132) (xy 69.982457 -174.55076) (xy 70.003162 -174.532544)
			(xy 70.011228 -174.52498) (xy 70.020585 -174.504975) (xy 70.021196 -174.493936) (xy 70.021196 -174.416212)
			(xy 70.020622 -174.405163) (xy 70.011261 -174.385142) (xy 70.003162 -174.377604) (xy 69.982442 -174.359403)
			(xy 69.945974 -174.318031) (xy 69.915844 -174.271839) (xy 69.89268 -174.221789) (xy 69.876965 -174.168925)
			(xy 69.869027 -174.114349) (xy 69.868542 -174.086774) (xy 69.868931 -174.059518) (xy 69.876693 -174.005562)
			(xy 69.892055 -173.95326) (xy 69.914704 -173.903676) (xy 69.944179 -173.857821) (xy 69.979881 -173.816627)
			(xy 70.021081 -173.780934) (xy 70.066943 -173.751467) (xy 70.116531 -173.728828) (xy 70.168836 -173.713476)
			(xy 70.222794 -173.705725) (xy 70.25005 -173.705266) (xy 70.277905 -173.705769) (xy 70.333021 -173.713899)
			(xy 70.38637 -173.72995) (xy 70.436822 -173.75358) (xy 70.483305 -173.78429) (xy 70.524834 -173.821426)
			(xy 70.560527 -173.864202) (xy 70.589627 -173.91171) (xy 70.611517 -173.962941) (xy 70.619112 -173.989746)
			(xy 70.621398 -173.998636) (xy 70.632066 -174.013876) (xy 70.703948 -174.061628) (xy 70.721982 -174.065692)
			(xy 70.731126 -174.064422) (xy 70.744142 -174.062752) (xy 70.770327 -174.060973) (xy 70.78345 -174.060866)
			(xy 70.797599 -174.060965) (xy 70.825822 -174.062996) (xy 70.839838 -174.06493) (xy 70.849744 -174.066454)
			(xy 70.869556 -174.061628) (xy 70.943978 -174.005748) (xy 70.954138 -173.988222) (xy 70.955408 -173.978062)
			(xy 70.959477 -173.950905) (xy 70.974451 -173.898073) (xy 70.996843 -173.847933) (xy 71.026193 -173.801521)
			(xy 71.061892 -173.759796) (xy 71.103204 -173.72362) (xy 71.149276 -173.693739) (xy 71.199155 -173.670772)
			(xy 71.251811 -173.655192) (xy 71.306158 -173.647322) (xy 71.333614 -173.646846) (xy 71.360864 -173.647365)
			(xy 71.414808 -173.655122) (xy 71.467099 -173.670476) (xy 71.516673 -173.693116) (xy 71.562521 -173.722579)
			(xy 71.60371 -173.758267) (xy 71.639401 -173.799453) (xy 71.668869 -173.845299) (xy 71.691512 -173.894871)
			(xy 71.706871 -173.947161) (xy 71.714633 -174.001105) (xy 71.715122 -174.028354) (xy 71.714617 -174.055927)
			(xy 71.706671 -174.110498) (xy 71.690954 -174.163357) (xy 71.667791 -174.213403) (xy 71.637666 -174.259593)
			(xy 71.601206 -174.300967) (xy 71.580502 -174.319184) (xy 71.572434 -174.326746) (xy 71.563076 -174.346752)
			(xy 71.562468 -174.357792) (xy 71.562468 -174.435516) (xy 71.563061 -174.446563) (xy 71.572406 -174.466586)
			(xy 71.580502 -174.474124) (xy 71.601228 -174.492319) (xy 71.637697 -174.533691) (xy 71.667828 -174.579884)
			(xy 71.690991 -174.629936) (xy 71.706704 -174.682801) (xy 71.714639 -174.737378) (xy 71.714673 -174.7393)
			(xy 76.30363 -174.7393) (xy 76.307701 -174.683678) (xy 76.319827 -174.629241) (xy 76.33975 -174.57715)
			(xy 76.367046 -174.528515) (xy 76.401132 -174.484372) (xy 76.441281 -174.445663) (xy 76.486639 -174.413212)
			(xy 76.536239 -174.387711) (xy 76.589023 -174.369704) (xy 76.643866 -174.359574) (xy 76.6996 -174.357537)
			(xy 76.755037 -174.363637) (xy 76.808994 -174.377743) (xy 76.860323 -174.399555) (xy 76.907929 -174.428609)
			(xy 76.950797 -174.464284) (xy 76.988014 -174.505821) (xy 77.018787 -174.552334) (xy 77.042459 -174.602831)
			(xy 77.058527 -174.656238) (xy 77.066647 -174.711414) (xy 77.067156 -174.7393) (xy 77.066647 -174.767186)
			(xy 77.058527 -174.822362) (xy 77.042459 -174.875769) (xy 77.018787 -174.926266) (xy 76.988014 -174.972779)
			(xy 76.950797 -175.014316) (xy 76.907929 -175.049991) (xy 76.860323 -175.079045) (xy 76.808994 -175.100857)
			(xy 76.755037 -175.114963) (xy 76.6996 -175.121063) (xy 76.643866 -175.119026) (xy 76.589023 -175.108896)
			(xy 76.536239 -175.090889) (xy 76.486639 -175.065388) (xy 76.441281 -175.032937) (xy 76.401132 -174.994228)
			(xy 76.367046 -174.950085) (xy 76.33975 -174.90145) (xy 76.319827 -174.849359) (xy 76.307701 -174.794922)
			(xy 76.30363 -174.7393) (xy 71.714673 -174.7393) (xy 71.715122 -174.764954) (xy 71.714602 -174.792205)
			(xy 71.706852 -174.846153) (xy 71.691502 -174.898449) (xy 71.668866 -174.948028) (xy 71.639404 -174.993881)
			(xy 71.603716 -175.035074) (xy 71.562529 -175.070768) (xy 71.516681 -175.100237) (xy 71.467105 -175.122881)
			(xy 71.414812 -175.138239) (xy 71.360865 -175.145998) (xy 71.333614 -175.146462) (xy 71.333106 -175.146462)
			(xy 71.299324 -175.144938) (xy 71.289164 -175.143922) (xy 71.26986 -175.150018) (xy 71.206868 -175.20285)
			(xy 71.199574 -175.209569) (xy 71.190295 -175.227077) (xy 71.188834 -175.236886) (xy 71.188834 -175.237648)
			(xy 71.185864 -175.265807) (xy 71.172657 -175.320866) (xy 71.151455 -175.373367) (xy 71.122725 -175.422157)
			(xy 71.087096 -175.466162) (xy 71.045353 -175.504417) (xy 70.998413 -175.53608) (xy 70.947307 -175.560454)
			(xy 70.89316 -175.577006) (xy 70.83716 -175.585369) (xy 70.80885 -175.585882) (xy 70.790831 -175.585663)
			(xy 70.754956 -175.582227) (xy 70.737222 -175.579024) (xy 70.72757 -175.577246) (xy 70.70852 -175.580802)
			(xy 70.63359 -175.628808) (xy 70.62216 -175.644556) (xy 70.619874 -175.653954) (xy 70.612491 -175.681002)
			(xy 70.59086 -175.732729) (xy 70.561894 -175.780735) (xy 70.526216 -175.823987) (xy 70.484595 -175.861553)
			(xy 70.437926 -175.892627) (xy 70.387213 -175.916539) (xy 70.333547 -175.932774) (xy 70.278084 -175.940984)
			(xy 70.25005 -175.941482) (xy 70.222797 -175.940998) (xy 70.168846 -175.933247) (xy 70.116547 -175.917896)
			(xy 70.066965 -175.895258) (xy 70.02111 -175.865792) (xy 69.979916 -175.830101) (xy 69.944222 -175.788909)
			(xy 69.914754 -175.743056) (xy 69.892112 -175.693476) (xy 69.876758 -175.641178) (xy 69.869004 -175.587227)
			(xy 69.868542 -175.559974) (xy 64.086994 -175.559974) (xy 65.63614 -177.10912) (xy 71.51116 -177.10912)
			(xy 71.511618 -177.081545) (xy 71.51957 -177.026971) (xy 71.535295 -176.97411) (xy 71.558466 -176.924064)
			(xy 71.588601 -176.877874) (xy 71.625071 -176.836505) (xy 71.64578 -176.81829) (xy 71.653873 -176.810751)
			(xy 71.663214 -176.790727) (xy 71.663814 -176.779682) (xy 71.663814 -176.701958) (xy 71.663241 -176.690909)
			(xy 71.653882 -176.670886) (xy 71.64578 -176.66335) (xy 71.625086 -176.645121) (xy 71.588615 -176.603755)
			(xy 71.558481 -176.557569) (xy 71.535313 -176.507525) (xy 71.519592 -176.454666) (xy 71.511648 -176.400094)
			(xy 71.51116 -176.37252) (xy 71.51163 -176.346404) (xy 71.518765 -176.294662) (xy 71.53289 -176.244376)
			(xy 71.553741 -176.196487) (xy 71.58093 -176.151889) (xy 71.613946 -176.111416) (xy 71.652175 -176.075824)
			(xy 71.6949 -176.045779) (xy 71.717916 -176.03343) (xy 71.727929 -176.027709) (xy 71.741808 -176.009317)
			(xy 71.744586 -175.998124) (xy 71.76262 -175.90897) (xy 71.757032 -175.886872) (xy 71.749666 -175.877982)
			(xy 71.733387 -175.857795) (xy 71.705983 -175.81377) (xy 71.684951 -175.766368) (xy 71.670699 -175.716507)
			(xy 71.663502 -175.665151) (xy 71.663052 -175.639222) (xy 71.663577 -175.612608) (xy 71.671149 -175.55992)
			(xy 71.686142 -175.508847) (xy 71.708251 -175.460427) (xy 71.737025 -175.415647) (xy 71.77188 -175.375417)
			(xy 71.812105 -175.340557) (xy 71.856881 -175.311776) (xy 71.905298 -175.28966) (xy 71.95637 -175.27466)
			(xy 72.009056 -175.267081) (xy 72.03567 -175.266604) (xy 72.062091 -175.267078) (xy 72.114406 -175.274524)
			(xy 72.165144 -175.289285) (xy 72.213289 -175.311065) (xy 72.257874 -175.339428) (xy 72.27824 -175.356266)
			(xy 72.285098 -175.362108) (xy 72.302116 -175.368458) (xy 72.386444 -175.368458) (xy 72.403462 -175.362108)
			(xy 72.41032 -175.356266) (xy 72.430686 -175.339427) (xy 72.475272 -175.311062) (xy 72.523416 -175.289275)
			(xy 72.574153 -175.274504) (xy 72.626468 -175.267044) (xy 72.679312 -175.267044) (xy 72.731627 -175.274504)
			(xy 72.782364 -175.289275) (xy 72.830508 -175.311062) (xy 72.875094 -175.339427) (xy 72.89546 -175.356266)
			(xy 72.902318 -175.362108) (xy 72.919336 -175.368458) (xy 73.003664 -175.368458) (xy 73.020682 -175.362108)
			(xy 73.02754 -175.356266) (xy 73.047899 -175.339419) (xy 73.09249 -175.311063) (xy 73.140636 -175.289285)
			(xy 73.191374 -175.274519) (xy 73.243688 -175.267063) (xy 73.27011 -175.266604) (xy 73.297996 -175.267082)
			(xy 73.353145 -175.275395) (xy 73.406439 -175.291836) (xy 73.456687 -175.316035) (xy 73.502767 -175.347453)
			(xy 73.543651 -175.385389) (xy 73.578423 -175.428993) (xy 73.606309 -175.477293) (xy 73.626684 -175.52921)
			(xy 73.639095 -175.583584) (xy 73.643263 -175.6392) (xy 73.639095 -175.694816) (xy 73.626684 -175.74919)
			(xy 73.606309 -175.801107) (xy 73.578423 -175.849407) (xy 73.543651 -175.893011) (xy 73.502767 -175.930947)
			(xy 73.456687 -175.962365) (xy 73.406439 -175.986564) (xy 73.353145 -176.003005) (xy 73.297996 -176.011318)
			(xy 73.27011 -176.01184) (xy 73.243689 -176.011367) (xy 73.191374 -176.003919) (xy 73.140636 -175.989157)
			(xy 73.092492 -175.967377) (xy 73.047906 -175.939016) (xy 73.02754 -175.922178) (xy 73.020682 -175.916336)
			(xy 73.003664 -175.909986) (xy 72.919336 -175.909986) (xy 72.902318 -175.916336) (xy 72.89546 -175.922178)
			(xy 72.875094 -175.939017) (xy 72.830508 -175.967382) (xy 72.782364 -175.989169) (xy 72.731627 -176.00394)
			(xy 72.679312 -176.0114) (xy 72.626468 -176.0114) (xy 72.574153 -176.00394) (xy 72.523416 -175.989169)
			(xy 72.475272 -175.967382) (xy 72.430686 -175.939017) (xy 72.41032 -175.922178) (xy 72.403462 -175.916336)
			(xy 72.386444 -175.909986) (xy 72.302116 -175.909986) (xy 72.285098 -175.916336) (xy 72.27824 -175.922178)
			(xy 72.262606 -175.935184) (xy 72.229003 -175.958095) (xy 72.211184 -175.967898) (xy 72.20077 -175.973486)
			(xy 72.187308 -175.991774) (xy 72.170544 -176.081182) (xy 72.16891 -176.092584) (xy 72.174845 -176.11481)
			(xy 72.181974 -176.123854) (xy 72.199282 -176.14471) (xy 72.228443 -176.190393) (xy 72.250844 -176.239745)
			(xy 72.266032 -176.29177) (xy 72.273702 -176.345421) (xy 72.274176 -176.37252) (xy 72.273664 -176.400093)
			(xy 72.265722 -176.454664) (xy 72.250007 -176.507523) (xy 72.226845 -176.55757) (xy 72.196721 -176.603761)
			(xy 72.185618 -176.61636) (xy 77.262482 -176.61636) (xy 77.262953 -176.588448) (xy 77.271093 -176.533222)
			(xy 77.287194 -176.479771) (xy 77.310911 -176.429236) (xy 77.341739 -176.382697) (xy 77.360018 -176.361598)
			(xy 77.365918 -176.354423) (xy 77.372567 -176.337096) (xy 77.372972 -176.327816) (xy 77.372972 -176.250092)
			(xy 77.366368 -176.23282) (xy 77.360018 -176.225708) (xy 77.341725 -176.204621) (xy 77.310899 -176.158079)
			(xy 77.287187 -176.107542) (xy 77.271094 -176.054087) (xy 77.262964 -175.998858) (xy 77.262482 -175.970946)
			(xy 77.262968 -175.943695) (xy 77.270724 -175.889747) (xy 77.286079 -175.837452) (xy 77.308721 -175.787875)
			(xy 77.338187 -175.742025) (xy 77.373878 -175.700834) (xy 77.415069 -175.665143) (xy 77.460919 -175.635677)
			(xy 77.510496 -175.613035) (xy 77.562791 -175.59768) (xy 77.616739 -175.589924) (xy 77.671241 -175.589924)
			(xy 77.725189 -175.59768) (xy 77.777484 -175.613035) (xy 77.827061 -175.635677) (xy 77.872911 -175.665143)
			(xy 77.914102 -175.700834) (xy 77.949793 -175.742025) (xy 77.979259 -175.787875) (xy 78.001901 -175.837452)
			(xy 78.017256 -175.889747) (xy 78.025012 -175.943695) (xy 78.025498 -175.970946) (xy 78.025011 -175.998857)
			(xy 78.016871 -176.054082) (xy 78.001212 -176.106074) (xy 103.363522 -176.106074) (xy 103.364031 -176.078501)
			(xy 103.371974 -176.02393) (xy 103.38769 -175.97107) (xy 103.410851 -175.921024) (xy 103.440977 -175.874833)
			(xy 103.477438 -175.833461) (xy 103.498142 -175.815244) (xy 103.506205 -175.807678) (xy 103.515564 -175.787674)
			(xy 103.516176 -175.776636) (xy 103.516176 -175.698912) (xy 103.515609 -175.687862) (xy 103.506244 -175.667841)
			(xy 103.498142 -175.660304) (xy 103.477438 -175.642085) (xy 103.440965 -175.600719) (xy 103.410831 -175.554531)
			(xy 103.387664 -175.504484) (xy 103.371947 -175.451623) (xy 103.364007 -175.397048) (xy 103.363522 -175.369474)
			(xy 103.364031 -175.341901) (xy 103.371974 -175.28733) (xy 103.38769 -175.23447) (xy 103.410851 -175.184424)
			(xy 103.440977 -175.138233) (xy 103.477438 -175.096861) (xy 103.498142 -175.078644) (xy 103.506205 -175.071078)
			(xy 103.515564 -175.051074) (xy 103.516176 -175.040036) (xy 103.516176 -174.962312) (xy 103.515609 -174.951262)
			(xy 103.506244 -174.931241) (xy 103.498142 -174.923704) (xy 103.477438 -174.905485) (xy 103.440965 -174.864119)
			(xy 103.410831 -174.817931) (xy 103.387664 -174.767884) (xy 103.371947 -174.715023) (xy 103.364007 -174.660448)
			(xy 103.363522 -174.632874) (xy 103.363931 -174.605619) (xy 103.371692 -174.551665) (xy 103.387053 -174.499364)
			(xy 103.409701 -174.449782) (xy 103.439174 -174.403927) (xy 103.474874 -174.362734) (xy 103.516072 -174.327041)
			(xy 103.561931 -174.297574) (xy 103.611516 -174.274933) (xy 103.663819 -174.25958) (xy 103.717775 -174.251827)
			(xy 103.74503 -174.251366) (xy 103.772885 -174.251887) (xy 103.827999 -174.260014) (xy 103.881348 -174.276062)
			(xy 103.9318 -174.29969) (xy 103.978283 -174.330397) (xy 104.019812 -174.367532) (xy 104.055506 -174.410306)
			(xy 104.084606 -174.457812) (xy 104.106496 -174.509042) (xy 104.114092 -174.535846) (xy 104.116378 -174.544736)
			(xy 104.127046 -174.559976) (xy 104.198928 -174.607728) (xy 104.216962 -174.611792) (xy 104.226106 -174.610522)
			(xy 104.239123 -174.608854) (xy 104.265307 -174.607073) (xy 104.27843 -174.606966) (xy 104.292579 -174.607057)
			(xy 104.320802 -174.609093) (xy 104.334818 -174.61103) (xy 104.344724 -174.612554) (xy 104.364536 -174.607728)
			(xy 104.438958 -174.551848) (xy 104.449118 -174.534322) (xy 104.450388 -174.524162) (xy 104.454477 -174.497008)
			(xy 104.469449 -174.444178) (xy 104.49184 -174.394039) (xy 104.521187 -174.347628) (xy 104.556885 -174.305904)
			(xy 104.598194 -174.269727) (xy 104.644263 -174.239846) (xy 104.69414 -174.216877) (xy 104.746794 -174.201296)
			(xy 104.801138 -174.193424) (xy 104.828594 -174.192946) (xy 104.855843 -174.193483) (xy 104.909787 -174.201238)
			(xy 104.962077 -174.21659) (xy 105.011652 -174.239227) (xy 105.0575 -174.268688) (xy 105.098689 -174.304374)
			(xy 105.134381 -174.345558) (xy 105.163848 -174.391403) (xy 105.186492 -174.440974) (xy 105.201851 -174.493263)
			(xy 105.209613 -174.547205) (xy 105.210102 -174.574454) (xy 105.209604 -174.602027) (xy 105.201658 -174.656599)
			(xy 105.185939 -174.709458) (xy 105.162775 -174.759504) (xy 105.132649 -174.805694) (xy 105.096187 -174.847067)
			(xy 105.075482 -174.865284) (xy 105.067411 -174.872843) (xy 105.058055 -174.892852) (xy 105.057448 -174.903892)
			(xy 105.057448 -174.981616) (xy 105.058048 -174.992662) (xy 105.067389 -175.012684) (xy 105.075482 -175.020224)
			(xy 105.096204 -175.038423) (xy 105.132675 -175.079794) (xy 105.162806 -175.125986) (xy 105.18597 -175.176037)
			(xy 105.201683 -175.228902) (xy 105.209619 -175.283478) (xy 105.209653 -175.2854) (xy 109.79861 -175.2854)
			(xy 109.802681 -175.229778) (xy 109.814807 -175.175341) (xy 109.83473 -175.12325) (xy 109.862026 -175.074615)
			(xy 109.896112 -175.030472) (xy 109.936261 -174.991763) (xy 109.981619 -174.959312) (xy 110.031219 -174.933811)
			(xy 110.084003 -174.915804) (xy 110.138846 -174.905674) (xy 110.19458 -174.903637) (xy 110.250017 -174.909737)
			(xy 110.303974 -174.923843) (xy 110.355303 -174.945655) (xy 110.402909 -174.974709) (xy 110.445777 -175.010384)
			(xy 110.482994 -175.051921) (xy 110.513767 -175.098434) (xy 110.537439 -175.148931) (xy 110.553507 -175.202338)
			(xy 110.561627 -175.257514) (xy 110.562136 -175.2854) (xy 110.561627 -175.313286) (xy 110.553507 -175.368462)
			(xy 110.537439 -175.421869) (xy 110.513767 -175.472366) (xy 110.482994 -175.518879) (xy 110.445777 -175.560416)
			(xy 110.402909 -175.596091) (xy 110.355303 -175.625145) (xy 110.303974 -175.646957) (xy 110.250017 -175.661063)
			(xy 110.19458 -175.667163) (xy 110.138846 -175.665126) (xy 110.084003 -175.654996) (xy 110.031219 -175.636989)
			(xy 109.981619 -175.611488) (xy 109.936261 -175.579037) (xy 109.896112 -175.540328) (xy 109.862026 -175.496185)
			(xy 109.83473 -175.44755) (xy 109.814807 -175.395459) (xy 109.802681 -175.341022) (xy 109.79861 -175.2854)
			(xy 105.209653 -175.2854) (xy 105.210102 -175.311054) (xy 105.209602 -175.338306) (xy 105.201851 -175.392256)
			(xy 105.186501 -175.444553) (xy 105.163863 -175.494134) (xy 105.134399 -175.539987) (xy 105.098709 -175.581181)
			(xy 105.05752 -175.616875) (xy 105.011669 -175.646344) (xy 104.962091 -175.668987) (xy 104.909795 -175.684343)
			(xy 104.855846 -175.692099) (xy 104.828594 -175.692562) (xy 104.828086 -175.692562) (xy 104.794304 -175.691038)
			(xy 104.784144 -175.690022) (xy 104.76484 -175.696118) (xy 104.701848 -175.74895) (xy 104.69455 -175.755666)
			(xy 104.685275 -175.773176) (xy 104.683814 -175.782986) (xy 104.683814 -175.783748) (xy 104.680863 -175.811909)
			(xy 104.667656 -175.86697) (xy 104.646453 -175.919473) (xy 104.61772 -175.968263) (xy 104.582089 -176.01227)
			(xy 104.540344 -176.050524) (xy 104.493401 -176.082186) (xy 104.442293 -176.10656) (xy 104.388143 -176.12311)
			(xy 104.332141 -176.131471) (xy 104.30383 -176.131982) (xy 104.285811 -176.131766) (xy 104.249936 -176.128328)
			(xy 104.232202 -176.125124) (xy 104.22255 -176.123346) (xy 104.2035 -176.126902) (xy 104.12857 -176.174908)
			(xy 104.11714 -176.190656) (xy 104.114854 -176.200054) (xy 104.107489 -176.227108) (xy 104.085856 -176.278836)
			(xy 104.056888 -176.326842) (xy 104.021209 -176.370094) (xy 103.979585 -176.407661) (xy 103.932913 -176.438734)
			(xy 103.882198 -176.462644) (xy 103.82853 -176.478878) (xy 103.773065 -176.487085) (xy 103.74503 -176.487582)
			(xy 103.717777 -176.487117) (xy 103.663824 -176.479363) (xy 103.611525 -176.46401) (xy 103.561943 -176.441369)
			(xy 103.516089 -176.411901) (xy 103.474895 -176.376208) (xy 103.439201 -176.335014) (xy 103.409733 -176.28916)
			(xy 103.387092 -176.239579) (xy 103.371738 -176.187279) (xy 103.363984 -176.133327) (xy 103.363522 -176.106074)
			(xy 78.001212 -176.106074) (xy 78.000773 -176.107532) (xy 77.97706 -176.158066) (xy 77.946238 -176.204607)
			(xy 77.927962 -176.225708) (xy 77.922057 -176.232879) (xy 77.915412 -176.250209) (xy 77.915008 -176.25949)
			(xy 77.915008 -176.337214) (xy 77.921612 -176.354486) (xy 77.927962 -176.361598) (xy 77.946223 -176.382711)
			(xy 77.977051 -176.429247) (xy 78.000768 -176.479778) (xy 78.016869 -176.533226) (xy 78.025009 -176.58845)
			(xy 78.025498 -176.61636) (xy 78.025012 -176.643611) (xy 78.017256 -176.697559) (xy 78.001901 -176.749854)
			(xy 77.979259 -176.799431) (xy 77.949793 -176.845281) (xy 77.914102 -176.886472) (xy 77.872911 -176.922163)
			(xy 77.827061 -176.951629) (xy 77.777484 -176.974271) (xy 77.725189 -176.989626) (xy 77.671241 -176.997382)
			(xy 77.616739 -176.997382) (xy 77.562791 -176.989626) (xy 77.510496 -176.974271) (xy 77.460919 -176.951629)
			(xy 77.415069 -176.922163) (xy 77.373878 -176.886472) (xy 77.338187 -176.845281) (xy 77.308721 -176.799431)
			(xy 77.286079 -176.749854) (xy 77.270724 -176.697559) (xy 77.262968 -176.643611) (xy 77.262482 -176.61636)
			(xy 72.185618 -176.61636) (xy 72.16026 -176.645133) (xy 72.139556 -176.66335) (xy 72.131451 -176.670878)
			(xy 72.122115 -176.69091) (xy 72.121522 -176.701958) (xy 72.121522 -176.779682) (xy 72.122093 -176.790731)
			(xy 72.131456 -176.810753) (xy 72.139556 -176.81829) (xy 72.160257 -176.836513) (xy 72.19673 -176.877878)
			(xy 72.226864 -176.924065) (xy 72.250032 -176.974111) (xy 72.26575 -177.026972) (xy 72.273691 -177.081546)
			(xy 72.274176 -177.10912) (xy 72.27369 -177.136371) (xy 72.265934 -177.190319) (xy 72.250579 -177.242614)
			(xy 72.227937 -177.292191) (xy 72.198471 -177.338041) (xy 72.16278 -177.379232) (xy 72.121589 -177.414923)
			(xy 72.075739 -177.444389) (xy 72.026162 -177.467031) (xy 71.973867 -177.482386) (xy 71.919919 -177.490142)
			(xy 71.865417 -177.490142) (xy 71.811469 -177.482386) (xy 71.759174 -177.467031) (xy 71.709597 -177.444389)
			(xy 71.663747 -177.414923) (xy 71.622556 -177.379232) (xy 71.586865 -177.338041) (xy 71.557399 -177.292191)
			(xy 71.534757 -177.242614) (xy 71.519402 -177.190319) (xy 71.511646 -177.136371) (xy 71.51116 -177.10912)
			(xy 65.63614 -177.10912) (xy 67.325494 -178.798474) (xy 78.471522 -178.798474) (xy 78.472085 -178.769559)
			(xy 78.480804 -178.712389) (xy 78.498052 -178.657191) (xy 78.523435 -178.605229) (xy 78.556371 -178.557694)
			(xy 78.596106 -178.515675) (xy 78.618588 -178.497484) (xy 78.627391 -178.489872) (xy 78.637577 -178.468975)
			(xy 78.638146 -178.457352) (xy 78.638146 -178.377596) (xy 78.637614 -178.365963) (xy 78.627422 -178.345052)
			(xy 78.618588 -178.337464) (xy 78.596085 -178.319296) (xy 78.556351 -178.277271) (xy 78.523415 -178.229732)
			(xy 78.49803 -178.177766) (xy 78.480778 -178.122564) (xy 78.472054 -178.065391) (xy 78.471522 -178.036474)
			(xy 78.471931 -178.009219) (xy 78.479692 -177.955265) (xy 78.495053 -177.902964) (xy 78.517701 -177.853382)
			(xy 78.547174 -177.807527) (xy 78.582874 -177.766334) (xy 78.624072 -177.730641) (xy 78.669931 -177.701174)
			(xy 78.719516 -177.678533) (xy 78.771819 -177.66318) (xy 78.825775 -177.655427) (xy 78.85303 -177.654966)
			(xy 78.880667 -177.655461) (xy 78.896382 -177.65776) (xy 104.95534 -177.65776) (xy 104.955833 -177.630186)
			(xy 104.963778 -177.575614) (xy 104.979497 -177.522754) (xy 105.002662 -177.472708) (xy 105.03279 -177.426517)
			(xy 105.069254 -177.385146) (xy 105.08996 -177.36693) (xy 105.098031 -177.359372) (xy 105.107385 -177.339362)
			(xy 105.107994 -177.328322) (xy 105.107994 -177.250598) (xy 105.107373 -177.239555) (xy 105.098045 -177.219534)
			(xy 105.08996 -177.21199) (xy 105.069233 -177.193797) (xy 105.032765 -177.152423) (xy 105.002636 -177.106229)
			(xy 104.979474 -177.056178) (xy 104.96376 -177.003313) (xy 104.955824 -176.948736) (xy 104.95534 -176.92116)
			(xy 104.955873 -176.892873) (xy 104.964232 -176.836919) (xy 104.980763 -176.782814) (xy 105.005102 -176.731742)
			(xy 105.036715 -176.684824) (xy 105.07491 -176.643089) (xy 105.118849 -176.607451) (xy 105.167569 -176.578693)
			(xy 105.193592 -176.567592) (xy 105.204768 -176.56302) (xy 105.220516 -176.545494) (xy 105.247694 -176.443894)
			(xy 105.243122 -176.42078) (xy 105.235756 -176.411382) (xy 105.217491 -176.38675) (xy 105.188467 -176.332735)
			(xy 105.168676 -176.274697) (xy 105.158649 -176.214204) (xy 105.158032 -176.183544) (xy 105.158475 -176.156925)
			(xy 105.166047 -176.104228) (xy 105.181042 -176.053146) (xy 105.203155 -176.004718) (xy 105.231937 -175.95993)
			(xy 105.2668 -175.919696) (xy 105.307035 -175.884833) (xy 105.351823 -175.856052) (xy 105.400251 -175.83394)
			(xy 105.451334 -175.818945) (xy 105.504031 -175.811375) (xy 105.53065 -175.810926) (xy 105.557072 -175.811372)
			(xy 105.609387 -175.818828) (xy 105.660125 -175.833596) (xy 105.708269 -175.855382) (xy 105.752854 -175.883748)
			(xy 105.77322 -175.900588) (xy 105.780078 -175.90643) (xy 105.797096 -175.91278) (xy 105.881424 -175.91278)
			(xy 105.898442 -175.90643) (xy 105.9053 -175.900588) (xy 105.925666 -175.883749) (xy 105.970252 -175.855384)
			(xy 106.018396 -175.833597) (xy 106.069133 -175.818826) (xy 106.121448 -175.811366) (xy 106.174292 -175.811366)
			(xy 106.226607 -175.818826) (xy 106.277344 -175.833597) (xy 106.325488 -175.855384) (xy 106.370074 -175.883749)
			(xy 106.39044 -175.900588) (xy 106.397298 -175.90643) (xy 106.414316 -175.91278) (xy 106.498644 -175.91278)
			(xy 106.515662 -175.90643) (xy 106.52252 -175.900588) (xy 106.542877 -175.883739) (xy 106.587469 -175.855386)
			(xy 106.635616 -175.833609) (xy 106.686354 -175.818844) (xy 106.738669 -175.811386) (xy 106.76509 -175.810926)
			(xy 106.792981 -175.811332) (xy 106.848139 -175.819645) (xy 106.901442 -175.836085) (xy 106.951699 -175.860287)
			(xy 106.997788 -175.891709) (xy 107.038679 -175.929649) (xy 107.073459 -175.97326) (xy 107.10135 -176.021567)
			(xy 107.121729 -176.073492) (xy 107.134142 -176.127875) (xy 107.138311 -176.1835) (xy 107.134142 -176.239125)
			(xy 107.121729 -176.293508) (xy 107.10135 -176.345433) (xy 107.073459 -176.39374) (xy 107.038679 -176.437351)
			(xy 106.997788 -176.475291) (xy 106.951699 -176.506713) (xy 106.901442 -176.530915) (xy 106.848139 -176.547355)
			(xy 106.792981 -176.555668) (xy 106.76509 -176.556162) (xy 106.738669 -176.555695) (xy 106.686354 -176.548245)
			(xy 106.635616 -176.533482) (xy 106.587472 -176.5117) (xy 106.542886 -176.483338) (xy 106.52252 -176.4665)
			(xy 106.515662 -176.460658) (xy 106.498644 -176.454308) (xy 106.414316 -176.454308) (xy 106.397298 -176.460658)
			(xy 106.39044 -176.4665) (xy 106.370074 -176.483339) (xy 106.325488 -176.511704) (xy 106.277344 -176.533491)
			(xy 106.226607 -176.548262) (xy 106.174292 -176.555722) (xy 106.121448 -176.555722) (xy 106.069133 -176.548262)
			(xy 106.018396 -176.533491) (xy 105.970252 -176.511704) (xy 105.925666 -176.483339) (xy 105.9053 -176.4665)
			(xy 105.898442 -176.460658) (xy 105.881424 -176.454308) (xy 105.797096 -176.454308) (xy 105.780078 -176.460658)
			(xy 105.77322 -176.4665) (xy 105.750945 -176.484878) (xy 105.701825 -176.515237) (xy 105.67543 -176.526952)
			(xy 105.664508 -176.531524) (xy 105.649014 -176.549304) (xy 105.626154 -176.639474) (xy 105.623809 -176.651027)
			(xy 105.628721 -176.67406) (xy 105.635552 -176.68367) (xy 105.651188 -176.703966) (xy 105.677413 -176.747981)
			(xy 105.697503 -176.795114) (xy 105.711096 -176.844513) (xy 105.717947 -176.895288) (xy 105.718356 -176.920906)
			(xy 105.718356 -176.92116) (xy 105.717878 -176.948734) (xy 105.70993 -177.003307) (xy 105.694209 -177.056168)
			(xy 105.671041 -177.106214) (xy 105.64091 -177.152404) (xy 105.632046 -177.16246) (xy 110.757462 -177.16246)
			(xy 110.757938 -177.134549) (xy 110.766077 -177.079322) (xy 110.782177 -177.025872) (xy 110.805894 -176.975337)
			(xy 110.83672 -176.928798) (xy 110.854998 -176.907698) (xy 110.860895 -176.900521) (xy 110.867546 -176.883196)
			(xy 110.867952 -176.873916) (xy 110.867952 -176.796192) (xy 110.861348 -176.77892) (xy 110.854998 -176.771808)
			(xy 110.836702 -176.750723) (xy 110.805877 -176.704181) (xy 110.782165 -176.653642) (xy 110.766073 -176.600188)
			(xy 110.757944 -176.544958) (xy 110.757462 -176.517046) (xy 110.757948 -176.489795) (xy 110.765704 -176.435847)
			(xy 110.781059 -176.383552) (xy 110.803701 -176.333975) (xy 110.833167 -176.288125) (xy 110.868858 -176.246934)
			(xy 110.910049 -176.211243) (xy 110.955899 -176.181777) (xy 111.005476 -176.159135) (xy 111.057771 -176.14378)
			(xy 111.111719 -176.136024) (xy 111.166221 -176.136024) (xy 111.220169 -176.14378) (xy 111.272464 -176.159135)
			(xy 111.322041 -176.181777) (xy 111.367891 -176.211243) (xy 111.409082 -176.246934) (xy 111.444773 -176.288125)
			(xy 111.474239 -176.333975) (xy 111.496881 -176.383552) (xy 111.512236 -176.435847) (xy 111.519992 -176.489795)
			(xy 111.520478 -176.517046) (xy 111.519996 -176.544957) (xy 111.511856 -176.600183) (xy 111.495757 -176.653633)
			(xy 111.472043 -176.704167) (xy 111.441218 -176.750707) (xy 111.422942 -176.771808) (xy 111.417035 -176.778978)
			(xy 111.410392 -176.796309) (xy 111.409988 -176.80559) (xy 111.409988 -176.883314) (xy 111.416592 -176.900586)
			(xy 111.422942 -176.907698) (xy 111.4412 -176.928814) (xy 111.472029 -176.975349) (xy 111.495747 -177.025879)
			(xy 111.511849 -177.079327) (xy 111.519989 -177.13455) (xy 111.520478 -177.16246) (xy 111.519992 -177.189711)
			(xy 111.512236 -177.243659) (xy 111.496881 -177.295954) (xy 111.474239 -177.345531) (xy 111.444773 -177.391381)
			(xy 111.409082 -177.432572) (xy 111.367891 -177.468263) (xy 111.322041 -177.497729) (xy 111.272464 -177.520371)
			(xy 111.220169 -177.535726) (xy 111.166221 -177.543482) (xy 111.111719 -177.543482) (xy 111.057771 -177.535726)
			(xy 111.005476 -177.520371) (xy 110.955899 -177.497729) (xy 110.910049 -177.468263) (xy 110.868858 -177.432572)
			(xy 110.833167 -177.391381) (xy 110.803701 -177.345531) (xy 110.781059 -177.295954) (xy 110.765704 -177.243659)
			(xy 110.757948 -177.189711) (xy 110.757462 -177.16246) (xy 105.632046 -177.16246) (xy 105.604443 -177.193775)
			(xy 105.583736 -177.21199) (xy 105.575655 -177.219539) (xy 105.566306 -177.239556) (xy 105.565702 -177.250598)
			(xy 105.565702 -177.328322) (xy 105.566313 -177.339366) (xy 105.575648 -177.359388) (xy 105.583736 -177.36693)
			(xy 105.604472 -177.385114) (xy 105.640939 -177.426489) (xy 105.671067 -177.472685) (xy 105.694228 -177.522738)
			(xy 105.70994 -177.575605) (xy 105.717874 -177.630184) (xy 105.718356 -177.65776) (xy 105.71787 -177.685011)
			(xy 105.710114 -177.738959) (xy 105.694759 -177.791254) (xy 105.672117 -177.840831) (xy 105.642651 -177.886681)
			(xy 105.60696 -177.927872) (xy 105.565769 -177.963563) (xy 105.519919 -177.993029) (xy 105.470342 -178.015671)
			(xy 105.418047 -178.031026) (xy 105.364099 -178.038782) (xy 105.309597 -178.038782) (xy 105.255649 -178.031026)
			(xy 105.203354 -178.015671) (xy 105.153777 -177.993029) (xy 105.107927 -177.963563) (xy 105.066736 -177.927872)
			(xy 105.031045 -177.886681) (xy 105.001579 -177.840831) (xy 104.978937 -177.791254) (xy 104.963582 -177.738959)
			(xy 104.955826 -177.685011) (xy 104.95534 -177.65776) (xy 78.896382 -177.65776) (xy 78.935359 -177.663462)
			(xy 78.988327 -177.679262) (xy 79.038464 -177.702533) (xy 79.084723 -177.732788) (xy 79.126137 -177.769395)
			(xy 79.161843 -177.81159) (xy 79.191093 -177.85849) (xy 79.213277 -177.909117) (xy 79.221076 -177.935636)
			(xy 79.223616 -177.94478) (xy 79.234792 -177.96002) (xy 79.308706 -178.00701) (xy 79.327248 -178.010566)
			(xy 79.336646 -178.008788) (xy 79.353146 -178.006047) (xy 79.386469 -178.003125) (xy 79.403194 -178.002946)
			(xy 79.430443 -178.003483) (xy 79.484387 -178.011238) (xy 79.536677 -178.02659) (xy 79.586252 -178.049227)
			(xy 79.6321 -178.078688) (xy 79.673289 -178.114374) (xy 79.708981 -178.155558) (xy 79.738448 -178.201403)
			(xy 79.761092 -178.250974) (xy 79.776451 -178.303263) (xy 79.784213 -178.357205) (xy 79.784702 -178.384454)
			(xy 79.784702 -178.384708) (xy 79.784361 -178.404012) (xy 81.978246 -178.404012) (xy 81.978732 -178.376761)
			(xy 81.986488 -178.322813) (xy 82.001843 -178.270518) (xy 82.024485 -178.220941) (xy 82.053951 -178.175091)
			(xy 82.089642 -178.1339) (xy 82.130833 -178.098209) (xy 82.176683 -178.068743) (xy 82.22626 -178.046101)
			(xy 82.278555 -178.030746) (xy 82.332503 -178.02299) (xy 82.387005 -178.02299) (xy 82.440953 -178.030746)
			(xy 82.493248 -178.046101) (xy 82.542825 -178.068743) (xy 82.588675 -178.098209) (xy 82.629866 -178.1339)
			(xy 82.665557 -178.175091) (xy 82.695023 -178.220941) (xy 82.717665 -178.270518) (xy 82.73302 -178.322813)
			(xy 82.740776 -178.376761) (xy 82.741262 -178.404012) (xy 82.740596 -178.435575) (xy 82.730212 -178.49784)
			(xy 82.709729 -178.557549) (xy 82.695288 -178.585622) (xy 82.690462 -178.594512) (xy 82.68843 -178.61407)
			(xy 82.71129 -178.692556) (xy 82.71452 -178.701984) (xy 82.726944 -178.71754) (xy 82.73542 -178.722782)
			(xy 82.742786 -178.726846) (xy 82.752692 -178.732688) (xy 82.774536 -178.73472) (xy 82.869278 -178.701192)
			(xy 82.885026 -178.685698) (xy 82.88909 -178.675284) (xy 82.899769 -178.6485) (xy 82.928059 -178.598258)
			(xy 82.963592 -178.552849) (xy 83.005556 -178.513307) (xy 83.052996 -178.480534) (xy 83.104829 -178.455277)
			(xy 83.159874 -178.438113) (xy 83.216876 -178.429432) (xy 83.245706 -178.428904) (xy 83.272958 -178.429366)
			(xy 83.326907 -178.437124) (xy 83.379202 -178.45248) (xy 83.42878 -178.475122) (xy 83.474631 -178.504589)
			(xy 83.515822 -178.540282) (xy 83.551514 -178.581473) (xy 83.580981 -178.627325) (xy 83.603622 -178.676903)
			(xy 83.618978 -178.729199) (xy 83.626734 -178.783148) (xy 83.626734 -178.837652) (xy 83.618978 -178.891601)
			(xy 83.609628 -178.923442) (xy 83.868514 -178.923442) (xy 83.869022 -178.895968) (xy 83.876908 -178.841589)
			(xy 83.892523 -178.788907) (xy 83.915543 -178.739014) (xy 83.94549 -178.692944) (xy 83.963256 -178.671982)
			(xy 83.96351 -178.671728) (xy 83.969092 -178.664638) (xy 83.975341 -178.647724) (xy 83.975702 -178.638708)
			(xy 83.975702 -178.571144) (xy 83.975324 -178.562129) (xy 83.969091 -178.545212) (xy 83.96351 -178.538124)
			(xy 83.963002 -178.537616) (xy 83.94528 -178.51666) (xy 83.915396 -178.47063) (xy 83.892427 -178.420787)
			(xy 83.87685 -178.368164) (xy 83.868986 -178.31385) (xy 83.868514 -178.28641) (xy 83.869 -178.259159)
			(xy 83.876756 -178.205211) (xy 83.892111 -178.152916) (xy 83.914753 -178.103339) (xy 83.944219 -178.057489)
			(xy 83.97991 -178.016298) (xy 84.021101 -177.980607) (xy 84.066951 -177.951141) (xy 84.116528 -177.928499)
			(xy 84.168823 -177.913144) (xy 84.222771 -177.905388) (xy 84.277273 -177.905388) (xy 84.331221 -177.913144)
			(xy 84.383516 -177.928499) (xy 84.433093 -177.951141) (xy 84.478943 -177.980607) (xy 84.520134 -178.016298)
			(xy 84.555825 -178.057489) (xy 84.585291 -178.103339) (xy 84.607933 -178.152916) (xy 84.623288 -178.205211)
			(xy 84.631044 -178.259159) (xy 84.63153 -178.28641) (xy 84.631042 -178.313884) (xy 84.627841 -178.33594)
			(xy 90.375486 -178.33594) (xy 90.375972 -178.308689) (xy 90.383728 -178.254741) (xy 90.399083 -178.202446)
			(xy 90.421725 -178.152869) (xy 90.451191 -178.107019) (xy 90.486882 -178.065828) (xy 90.528073 -178.030137)
			(xy 90.573923 -178.000671) (xy 90.6235 -177.978029) (xy 90.675795 -177.962674) (xy 90.729743 -177.954918)
			(xy 90.784245 -177.954918) (xy 90.838193 -177.962674) (xy 90.890488 -177.978029) (xy 90.940065 -178.000671)
			(xy 90.985915 -178.030137) (xy 91.027106 -178.065828) (xy 91.062797 -178.107019) (xy 91.092263 -178.152869)
			(xy 91.114905 -178.202446) (xy 91.13026 -178.254741) (xy 91.138016 -178.308689) (xy 91.138502 -178.33594)
			(xy 91.137843 -178.367503) (xy 91.127455 -178.429768) (xy 91.106969 -178.489477) (xy 91.092528 -178.51755)
			(xy 91.087702 -178.52644) (xy 91.08567 -178.545998) (xy 91.10853 -178.624484) (xy 91.111774 -178.633906)
			(xy 91.124187 -178.649467) (xy 91.13266 -178.65471) (xy 91.140026 -178.658774) (xy 91.149932 -178.664616)
			(xy 91.171776 -178.666648) (xy 91.266518 -178.63312) (xy 91.282266 -178.617626) (xy 91.28633 -178.607212)
			(xy 91.297074 -178.580456) (xy 91.325355 -178.530215) (xy 91.360878 -178.484806) (xy 91.402832 -178.445262)
			(xy 91.450263 -178.412485) (xy 91.502087 -178.387224) (xy 91.557124 -178.370053) (xy 91.614119 -178.361365)
			(xy 91.642946 -178.360832) (xy 91.670198 -178.361241) (xy 91.724146 -178.369004) (xy 91.776441 -178.384364)
			(xy 91.826018 -178.407011) (xy 91.871867 -178.436481) (xy 91.913056 -178.472176) (xy 91.948746 -178.51337)
			(xy 91.978212 -178.559223) (xy 92.000852 -178.608802) (xy 92.016206 -178.661099) (xy 92.023962 -178.715048)
			(xy 92.023962 -178.769552) (xy 92.016206 -178.823501) (xy 92.00685 -178.85537) (xy 92.265754 -178.85537)
			(xy 92.266209 -178.827894) (xy 92.274107 -178.773513) (xy 92.289733 -178.720829) (xy 92.312765 -178.670937)
			(xy 92.342725 -178.62487) (xy 92.360496 -178.60391) (xy 92.36075 -178.603656) (xy 92.366325 -178.596562)
			(xy 92.372578 -178.579651) (xy 92.372942 -178.570636) (xy 92.372942 -178.503072) (xy 92.372611 -178.494052)
			(xy 92.366347 -178.477135) (xy 92.36075 -178.470052) (xy 92.360242 -178.469544) (xy 92.342493 -178.44861)
			(xy 92.312611 -178.402575) (xy 92.289647 -178.352727) (xy 92.274076 -178.300098) (xy 92.266221 -178.24578)
			(xy 92.265754 -178.218338) (xy 92.26624 -178.191087) (xy 92.273996 -178.137139) (xy 92.289351 -178.084844)
			(xy 92.311993 -178.035267) (xy 92.341459 -177.989417) (xy 92.37715 -177.948226) (xy 92.418341 -177.912535)
			(xy 92.464191 -177.883069) (xy 92.513768 -177.860427) (xy 92.566063 -177.845072) (xy 92.620011 -177.837316)
			(xy 92.674513 -177.837316) (xy 92.728461 -177.845072) (xy 92.780756 -177.860427) (xy 92.830333 -177.883069)
			(xy 92.876183 -177.912535) (xy 92.917374 -177.948226) (xy 92.953065 -177.989417) (xy 92.982531 -178.035267)
			(xy 93.005173 -178.084844) (xy 93.020528 -178.137139) (xy 93.028284 -178.191087) (xy 93.02877 -178.218338)
			(xy 93.028313 -178.245814) (xy 93.020415 -178.300195) (xy 93.004789 -178.352878) (xy 93.004635 -178.353212)
			(xy 98.767646 -178.353212) (xy 98.768132 -178.325961) (xy 98.775888 -178.272013) (xy 98.791243 -178.219718)
			(xy 98.813885 -178.170141) (xy 98.843351 -178.124291) (xy 98.879042 -178.0831) (xy 98.920233 -178.047409)
			(xy 98.966083 -178.017943) (xy 99.01566 -177.995301) (xy 99.067955 -177.979946) (xy 99.121903 -177.97219)
			(xy 99.176405 -177.97219) (xy 99.230353 -177.979946) (xy 99.282648 -177.995301) (xy 99.332225 -178.017943)
			(xy 99.378075 -178.047409) (xy 99.419266 -178.0831) (xy 99.454957 -178.124291) (xy 99.484423 -178.170141)
			(xy 99.507065 -178.219718) (xy 99.52242 -178.272013) (xy 99.530176 -178.325961) (xy 99.530662 -178.353212)
			(xy 99.529996 -178.384775) (xy 99.519612 -178.44704) (xy 99.499129 -178.506749) (xy 99.484688 -178.534822)
			(xy 99.479862 -178.543712) (xy 99.47783 -178.56327) (xy 99.50069 -178.641756) (xy 99.50392 -178.651184)
			(xy 99.516344 -178.66674) (xy 99.52482 -178.671982) (xy 99.532186 -178.676046) (xy 99.542092 -178.681888)
			(xy 99.563936 -178.68392) (xy 99.658678 -178.650392) (xy 99.674426 -178.634898) (xy 99.67849 -178.624484)
			(xy 99.689169 -178.5977) (xy 99.717459 -178.547458) (xy 99.752992 -178.502049) (xy 99.794956 -178.462507)
			(xy 99.842396 -178.429734) (xy 99.894229 -178.404477) (xy 99.949274 -178.387313) (xy 100.006276 -178.378632)
			(xy 100.035106 -178.378104) (xy 100.062358 -178.378566) (xy 100.116307 -178.386324) (xy 100.168602 -178.40168)
			(xy 100.21818 -178.424322) (xy 100.264031 -178.453789) (xy 100.305222 -178.489482) (xy 100.340914 -178.530673)
			(xy 100.370381 -178.576525) (xy 100.393022 -178.626103) (xy 100.408378 -178.678399) (xy 100.416134 -178.732348)
			(xy 100.416134 -178.786852) (xy 100.408378 -178.840801) (xy 100.399028 -178.872642) (xy 100.657914 -178.872642)
			(xy 100.658422 -178.845168) (xy 100.666308 -178.790789) (xy 100.681923 -178.738107) (xy 100.704943 -178.688214)
			(xy 100.73489 -178.642144) (xy 100.752656 -178.621182) (xy 100.75291 -178.620928) (xy 100.758492 -178.613838)
			(xy 100.764741 -178.596924) (xy 100.765102 -178.587908) (xy 100.765102 -178.520344) (xy 100.764724 -178.511329)
			(xy 100.758491 -178.494412) (xy 100.75291 -178.487324) (xy 100.752402 -178.486816) (xy 100.73468 -178.46586)
			(xy 100.704796 -178.41983) (xy 100.681827 -178.369987) (xy 100.66625 -178.317364) (xy 100.658386 -178.26305)
			(xy 100.657914 -178.23561) (xy 100.6584 -178.208359) (xy 100.666156 -178.154411) (xy 100.681511 -178.102116)
			(xy 100.704153 -178.052539) (xy 100.733619 -178.006689) (xy 100.76931 -177.965498) (xy 100.810501 -177.929807)
			(xy 100.856351 -177.900341) (xy 100.905928 -177.877699) (xy 100.958223 -177.862344) (xy 101.012171 -177.854588)
			(xy 101.066673 -177.854588) (xy 101.120621 -177.862344) (xy 101.172916 -177.877699) (xy 101.222493 -177.900341)
			(xy 101.268343 -177.929807) (xy 101.309534 -177.965498) (xy 101.345225 -178.006689) (xy 101.374691 -178.052539)
			(xy 101.397333 -178.102116) (xy 101.412688 -178.154411) (xy 101.420444 -178.208359) (xy 101.42093 -178.23561)
			(xy 101.420442 -178.263084) (xy 101.41255 -178.317464) (xy 101.396929 -178.370146) (xy 101.373905 -178.420039)
			(xy 101.343955 -178.466108) (xy 101.326188 -178.48707) (xy 101.325934 -178.487324) (xy 101.320323 -178.494394)
			(xy 101.314093 -178.511324) (xy 101.313742 -178.520344) (xy 101.313742 -178.587908) (xy 101.314086 -178.596926)
			(xy 101.320341 -178.613844) (xy 101.325934 -178.620928) (xy 101.326442 -178.621436) (xy 101.344179 -178.642379)
			(xy 101.374063 -178.688412) (xy 101.39703 -178.738258) (xy 101.412603 -178.790884) (xy 101.420461 -178.845201)
			(xy 101.42093 -178.872642) (xy 101.420444 -178.899893) (xy 101.418811 -178.91125) (xy 101.99573 -178.91125)
			(xy 101.999801 -178.855628) (xy 102.011927 -178.801191) (xy 102.03185 -178.7491) (xy 102.059146 -178.700465)
			(xy 102.093232 -178.656322) (xy 102.133381 -178.617613) (xy 102.178739 -178.585162) (xy 102.228339 -178.559661)
			(xy 102.281123 -178.541654) (xy 102.335966 -178.531524) (xy 102.3917 -178.529487) (xy 102.447137 -178.535587)
			(xy 102.501094 -178.549693) (xy 102.552423 -178.571505) (xy 102.600029 -178.600559) (xy 102.642897 -178.636234)
			(xy 102.680114 -178.677771) (xy 102.710887 -178.724284) (xy 102.734559 -178.774781) (xy 102.750627 -178.828188)
			(xy 102.758747 -178.883364) (xy 102.759256 -178.91125) (xy 102.758747 -178.939136) (xy 102.750627 -178.994312)
			(xy 102.734559 -179.047719) (xy 102.710887 -179.098216) (xy 102.680114 -179.144729) (xy 102.642897 -179.186266)
			(xy 102.600029 -179.221941) (xy 102.552423 -179.250995) (xy 102.501094 -179.272807) (xy 102.447137 -179.286913)
			(xy 102.3917 -179.293013) (xy 102.335966 -179.290976) (xy 102.281123 -179.280846) (xy 102.228339 -179.262839)
			(xy 102.178739 -179.237338) (xy 102.133381 -179.204887) (xy 102.093232 -179.166178) (xy 102.059146 -179.122035)
			(xy 102.03185 -179.0734) (xy 102.011927 -179.021309) (xy 101.999801 -178.966872) (xy 101.99573 -178.91125)
			(xy 101.418811 -178.91125) (xy 101.412688 -178.953841) (xy 101.397333 -179.006136) (xy 101.374691 -179.055713)
			(xy 101.345225 -179.101563) (xy 101.309534 -179.142754) (xy 101.268343 -179.178445) (xy 101.222493 -179.207911)
			(xy 101.172916 -179.230553) (xy 101.120621 -179.245908) (xy 101.066673 -179.253664) (xy 101.012171 -179.253664)
			(xy 100.958223 -179.245908) (xy 100.905928 -179.230553) (xy 100.856351 -179.207911) (xy 100.810501 -179.178445)
			(xy 100.76931 -179.142754) (xy 100.733619 -179.101563) (xy 100.704153 -179.055713) (xy 100.681511 -179.006136)
			(xy 100.666156 -178.953841) (xy 100.6584 -178.899893) (xy 100.657914 -178.872642) (xy 100.399028 -178.872642)
			(xy 100.393022 -178.893097) (xy 100.370381 -178.942675) (xy 100.340914 -178.988527) (xy 100.305222 -179.029718)
			(xy 100.264031 -179.065411) (xy 100.21818 -179.094878) (xy 100.168602 -179.11752) (xy 100.116307 -179.132876)
			(xy 100.062358 -179.140634) (xy 100.035106 -179.14112) (xy 100.034852 -179.14112) (xy 100.009649 -179.140703)
			(xy 99.959681 -179.134069) (xy 99.911027 -179.120898) (xy 99.864536 -179.10142) (xy 99.842574 -179.08905)
			(xy 99.832668 -179.083208) (xy 99.810824 -179.081176) (xy 99.716082 -179.114704) (xy 99.700334 -179.130198)
			(xy 99.69627 -179.140612) (xy 99.685539 -179.167373) (xy 99.657255 -179.217613) (xy 99.62173 -179.263022)
			(xy 99.579773 -179.302565) (xy 99.532341 -179.33534) (xy 99.480515 -179.360601) (xy 99.425477 -179.377771)
			(xy 99.368481 -179.386459) (xy 99.339654 -179.386992) (xy 99.312401 -179.386565) (xy 99.25845 -179.378802)
			(xy 99.206153 -179.36344) (xy 99.156575 -179.340792) (xy 99.110724 -179.31132) (xy 99.069534 -179.275622)
			(xy 99.033843 -179.234426) (xy 99.004378 -179.188571) (xy 98.981738 -179.138988) (xy 98.966385 -179.086689)
			(xy 98.958631 -179.032737) (xy 98.958146 -179.005484) (xy 98.958809 -178.973921) (xy 98.969194 -178.911656)
			(xy 98.989679 -178.851947) (xy 99.00412 -178.823874) (xy 99.008946 -178.814984) (xy 99.010978 -178.795426)
			(xy 98.988118 -178.71694) (xy 98.984887 -178.707513) (xy 98.972463 -178.691957) (xy 98.963988 -178.686714)
			(xy 98.938862 -178.672206) (xy 98.89298 -178.636696) (xy 98.853007 -178.594645) (xy 98.819865 -178.547024)
			(xy 98.794318 -178.494933) (xy 98.776957 -178.439572) (xy 98.768182 -178.382221) (xy 98.767646 -178.353212)
			(xy 93.004635 -178.353212) (xy 92.981757 -178.40277) (xy 92.951799 -178.448837) (xy 92.934028 -178.469798)
			(xy 92.933774 -178.470052) (xy 92.928198 -178.477146) (xy 92.921946 -178.494057) (xy 92.921582 -178.503072)
			(xy 92.921582 -178.570636) (xy 92.921926 -178.579654) (xy 92.928183 -178.596571) (xy 92.933774 -178.603656)
			(xy 92.934282 -178.604164) (xy 92.951992 -178.625129) (xy 92.981878 -178.671157) (xy 93.00485 -178.720997)
			(xy 93.02043 -178.773618) (xy 93.028296 -178.82793) (xy 93.02877 -178.85537) (xy 93.028284 -178.882621)
			(xy 93.026651 -178.893978) (xy 93.60357 -178.893978) (xy 93.607641 -178.838356) (xy 93.619767 -178.783919)
			(xy 93.63969 -178.731828) (xy 93.666986 -178.683193) (xy 93.701072 -178.63905) (xy 93.741221 -178.600341)
			(xy 93.786579 -178.56789) (xy 93.836179 -178.542389) (xy 93.888963 -178.524382) (xy 93.943806 -178.514252)
			(xy 93.99954 -178.512215) (xy 94.054977 -178.518315) (xy 94.108934 -178.532421) (xy 94.160263 -178.554233)
			(xy 94.207869 -178.583287) (xy 94.250737 -178.618962) (xy 94.287954 -178.660499) (xy 94.318727 -178.707012)
			(xy 94.342399 -178.757509) (xy 94.358467 -178.810916) (xy 94.366587 -178.866092) (xy 94.367096 -178.893978)
			(xy 94.366587 -178.921864) (xy 94.358467 -178.97704) (xy 94.342399 -179.030447) (xy 94.318727 -179.080944)
			(xy 94.287954 -179.127457) (xy 94.250737 -179.168994) (xy 94.207869 -179.204669) (xy 94.160263 -179.233723)
			(xy 94.108934 -179.255535) (xy 94.054977 -179.269641) (xy 93.99954 -179.275741) (xy 93.943806 -179.273704)
			(xy 93.888963 -179.263574) (xy 93.836179 -179.245567) (xy 93.786579 -179.220066) (xy 93.741221 -179.187615)
			(xy 93.701072 -179.148906) (xy 93.666986 -179.104763) (xy 93.63969 -179.056128) (xy 93.619767 -179.004037)
			(xy 93.607641 -178.9496) (xy 93.60357 -178.893978) (xy 93.026651 -178.893978) (xy 93.020528 -178.936569)
			(xy 93.005173 -178.988864) (xy 92.982531 -179.038441) (xy 92.953065 -179.084291) (xy 92.917374 -179.125482)
			(xy 92.876183 -179.161173) (xy 92.830333 -179.190639) (xy 92.780756 -179.213281) (xy 92.728461 -179.228636)
			(xy 92.674513 -179.236392) (xy 92.620011 -179.236392) (xy 92.566063 -179.228636) (xy 92.513768 -179.213281)
			(xy 92.464191 -179.190639) (xy 92.418341 -179.161173) (xy 92.37715 -179.125482) (xy 92.341459 -179.084291)
			(xy 92.311993 -179.038441) (xy 92.289351 -178.988864) (xy 92.273996 -178.936569) (xy 92.26624 -178.882621)
			(xy 92.265754 -178.85537) (xy 92.00685 -178.85537) (xy 92.000852 -178.875798) (xy 91.978212 -178.925377)
			(xy 91.948746 -178.97123) (xy 91.913056 -179.012424) (xy 91.871867 -179.048119) (xy 91.826018 -179.077589)
			(xy 91.776441 -179.100236) (xy 91.724146 -179.115596) (xy 91.670198 -179.123359) (xy 91.642946 -179.123848)
			(xy 91.642692 -179.123848) (xy 91.617488 -179.123454) (xy 91.56752 -179.116813) (xy 91.518865 -179.103635)
			(xy 91.472376 -179.08415) (xy 91.450414 -179.071778) (xy 91.440508 -179.065936) (xy 91.418664 -179.063904)
			(xy 91.323922 -179.097432) (xy 91.308174 -179.112926) (xy 91.30411 -179.12334) (xy 91.293443 -179.150129)
			(xy 91.26515 -179.20037) (xy 91.229616 -179.245779) (xy 91.187649 -179.28532) (xy 91.140208 -179.318092)
			(xy 91.088373 -179.343348) (xy 91.033327 -179.360511) (xy 90.976324 -179.369192) (xy 90.947494 -179.36972)
			(xy 90.920243 -179.369228) (xy 90.866296 -179.361471) (xy 90.814002 -179.346116) (xy 90.764426 -179.323475)
			(xy 90.718576 -179.294009) (xy 90.677386 -179.258318) (xy 90.641695 -179.217129) (xy 90.612228 -179.171279)
			(xy 90.589587 -179.121703) (xy 90.57423 -179.06941) (xy 90.566473 -179.015463) (xy 90.565986 -178.988212)
			(xy 90.566628 -178.956648) (xy 90.577023 -178.894383) (xy 90.597515 -178.834674) (xy 90.61196 -178.806602)
			(xy 90.616786 -178.797712) (xy 90.618818 -178.778154) (xy 90.595958 -178.699668) (xy 90.592738 -178.690236)
			(xy 90.580308 -178.674681) (xy 90.571828 -178.669442) (xy 90.546724 -178.654899) (xy 90.50084 -178.619396)
			(xy 90.460864 -178.577351) (xy 90.427719 -178.529737) (xy 90.402168 -178.477651) (xy 90.384803 -178.422295)
			(xy 90.376024 -178.364948) (xy 90.375486 -178.33594) (xy 84.627841 -178.33594) (xy 84.62315 -178.368264)
			(xy 84.607529 -178.420946) (xy 84.584505 -178.470839) (xy 84.554555 -178.516908) (xy 84.536788 -178.53787)
			(xy 84.536534 -178.538124) (xy 84.530923 -178.545194) (xy 84.524693 -178.562124) (xy 84.524342 -178.571144)
			(xy 84.524342 -178.638708) (xy 84.524686 -178.647726) (xy 84.530941 -178.664644) (xy 84.536534 -178.671728)
			(xy 84.537042 -178.672236) (xy 84.554779 -178.693179) (xy 84.584663 -178.739212) (xy 84.60763 -178.789058)
			(xy 84.623203 -178.841684) (xy 84.631061 -178.896001) (xy 84.63153 -178.923442) (xy 84.631044 -178.950693)
			(xy 84.629411 -178.96205) (xy 85.20633 -178.96205) (xy 85.210401 -178.906428) (xy 85.222527 -178.851991)
			(xy 85.24245 -178.7999) (xy 85.269746 -178.751265) (xy 85.303832 -178.707122) (xy 85.343981 -178.668413)
			(xy 85.389339 -178.635962) (xy 85.438939 -178.610461) (xy 85.491723 -178.592454) (xy 85.546566 -178.582324)
			(xy 85.6023 -178.580287) (xy 85.657737 -178.586387) (xy 85.711694 -178.600493) (xy 85.763023 -178.622305)
			(xy 85.810629 -178.651359) (xy 85.853497 -178.687034) (xy 85.890714 -178.728571) (xy 85.921487 -178.775084)
			(xy 85.945159 -178.825581) (xy 85.961227 -178.878988) (xy 85.969347 -178.934164) (xy 85.969856 -178.96205)
			(xy 85.969347 -178.989936) (xy 85.961227 -179.045112) (xy 85.945159 -179.098519) (xy 85.921487 -179.149016)
			(xy 85.890714 -179.195529) (xy 85.853497 -179.237066) (xy 85.810629 -179.272741) (xy 85.763023 -179.301795)
			(xy 85.711694 -179.323607) (xy 85.657737 -179.337713) (xy 85.6023 -179.343813) (xy 85.546566 -179.341776)
			(xy 85.491723 -179.331646) (xy 85.438939 -179.313639) (xy 85.389339 -179.288138) (xy 85.343981 -179.255687)
			(xy 85.303832 -179.216978) (xy 85.269746 -179.172835) (xy 85.24245 -179.1242) (xy 85.222527 -179.072109)
			(xy 85.210401 -179.017672) (xy 85.20633 -178.96205) (xy 84.629411 -178.96205) (xy 84.623288 -179.004641)
			(xy 84.607933 -179.056936) (xy 84.585291 -179.106513) (xy 84.555825 -179.152363) (xy 84.520134 -179.193554)
			(xy 84.478943 -179.229245) (xy 84.433093 -179.258711) (xy 84.383516 -179.281353) (xy 84.331221 -179.296708)
			(xy 84.277273 -179.304464) (xy 84.222771 -179.304464) (xy 84.168823 -179.296708) (xy 84.116528 -179.281353)
			(xy 84.066951 -179.258711) (xy 84.021101 -179.229245) (xy 83.97991 -179.193554) (xy 83.944219 -179.152363)
			(xy 83.914753 -179.106513) (xy 83.892111 -179.056936) (xy 83.876756 -179.004641) (xy 83.869 -178.950693)
			(xy 83.868514 -178.923442) (xy 83.609628 -178.923442) (xy 83.603622 -178.943897) (xy 83.580981 -178.993475)
			(xy 83.551514 -179.039327) (xy 83.515822 -179.080518) (xy 83.474631 -179.116211) (xy 83.42878 -179.145678)
			(xy 83.379202 -179.16832) (xy 83.326907 -179.183676) (xy 83.272958 -179.191434) (xy 83.245706 -179.19192)
			(xy 83.245452 -179.19192) (xy 83.220249 -179.191503) (xy 83.170281 -179.184869) (xy 83.121627 -179.171698)
			(xy 83.075136 -179.15222) (xy 83.053174 -179.13985) (xy 83.043268 -179.134008) (xy 83.021424 -179.131976)
			(xy 82.926682 -179.165504) (xy 82.910934 -179.180998) (xy 82.90687 -179.191412) (xy 82.896139 -179.218173)
			(xy 82.867855 -179.268413) (xy 82.83233 -179.313822) (xy 82.790373 -179.353365) (xy 82.742941 -179.38614)
			(xy 82.691115 -179.411401) (xy 82.636077 -179.428571) (xy 82.579081 -179.437259) (xy 82.550254 -179.437792)
			(xy 82.523001 -179.437365) (xy 82.46905 -179.429602) (xy 82.416753 -179.41424) (xy 82.367175 -179.391592)
			(xy 82.321324 -179.36212) (xy 82.280134 -179.326422) (xy 82.244443 -179.285226) (xy 82.214978 -179.239371)
			(xy 82.192338 -179.189788) (xy 82.176985 -179.137489) (xy 82.169231 -179.083537) (xy 82.168746 -179.056284)
			(xy 82.169409 -179.024721) (xy 82.179794 -178.962456) (xy 82.200279 -178.902747) (xy 82.21472 -178.874674)
			(xy 82.219546 -178.865784) (xy 82.221578 -178.846226) (xy 82.198718 -178.76774) (xy 82.195487 -178.758313)
			(xy 82.183063 -178.742757) (xy 82.174588 -178.737514) (xy 82.149462 -178.723006) (xy 82.10358 -178.687496)
			(xy 82.063607 -178.645445) (xy 82.030465 -178.597824) (xy 82.004918 -178.545733) (xy 81.987557 -178.490372)
			(xy 81.978782 -178.433021) (xy 81.978246 -178.404012) (xy 79.784361 -178.404012) (xy 79.784257 -178.409868)
			(xy 79.777623 -178.45975) (xy 79.764495 -178.508329) (xy 79.745103 -178.554764) (xy 79.719781 -178.59825)
			(xy 79.704692 -178.618388) (xy 79.696818 -178.628294) (xy 79.6925 -178.65344) (xy 79.727298 -178.757834)
			(xy 79.745586 -178.775106) (xy 79.758032 -178.778408) (xy 79.784565 -178.786174) (xy 79.835211 -178.808337)
			(xy 79.882129 -178.837577) (xy 79.924337 -178.87328) (xy 79.960951 -178.914701) (xy 79.991205 -178.960971)
			(xy 80.014465 -179.011123) (xy 80.030246 -179.064106) (xy 80.038215 -179.118812) (xy 80.038702 -179.146454)
			(xy 80.038204 -179.174027) (xy 80.030258 -179.228599) (xy 80.014539 -179.281458) (xy 79.991375 -179.331504)
			(xy 79.961249 -179.377694) (xy 79.924787 -179.419067) (xy 79.904082 -179.437284) (xy 79.896011 -179.444843)
			(xy 79.886655 -179.464852) (xy 79.886048 -179.475892) (xy 79.886048 -179.553616) (xy 79.886648 -179.564662)
			(xy 79.895989 -179.584684) (xy 79.904082 -179.592224) (xy 79.924804 -179.610423) (xy 79.961275 -179.651794)
			(xy 79.991406 -179.697986) (xy 80.01457 -179.748037) (xy 80.030283 -179.800902) (xy 80.038219 -179.855478)
			(xy 80.038253 -179.8574) (xy 84.62721 -179.8574) (xy 84.631281 -179.801778) (xy 84.643407 -179.747341)
			(xy 84.66333 -179.69525) (xy 84.690626 -179.646615) (xy 84.724712 -179.602472) (xy 84.764861 -179.563763)
			(xy 84.810219 -179.531312) (xy 84.859819 -179.505811) (xy 84.912603 -179.487804) (xy 84.967446 -179.477674)
			(xy 85.02318 -179.475637) (xy 85.078617 -179.481737) (xy 85.132574 -179.495843) (xy 85.183903 -179.517655)
			(xy 85.231509 -179.546709) (xy 85.274377 -179.582384) (xy 85.311594 -179.623921) (xy 85.342367 -179.670434)
			(xy 85.366039 -179.720931) (xy 85.382107 -179.774338) (xy 85.390227 -179.829514) (xy 85.390736 -179.8574)
			(xy 85.390227 -179.885286) (xy 85.382107 -179.940462) (xy 85.366039 -179.993869) (xy 85.342367 -180.044366)
			(xy 85.311594 -180.090879) (xy 85.274377 -180.132416) (xy 85.231509 -180.168091) (xy 85.183903 -180.197145)
			(xy 85.132574 -180.218957) (xy 85.078617 -180.233063) (xy 85.02318 -180.239163) (xy 84.967446 -180.237126)
			(xy 84.912603 -180.226996) (xy 84.859819 -180.208989) (xy 84.810219 -180.183488) (xy 84.764861 -180.151037)
			(xy 84.724712 -180.112328) (xy 84.690626 -180.068185) (xy 84.66333 -180.01955) (xy 84.643407 -179.967459)
			(xy 84.631281 -179.913022) (xy 84.62721 -179.8574) (xy 80.038253 -179.8574) (xy 80.038702 -179.883054)
			(xy 80.038202 -179.910306) (xy 80.030451 -179.964256) (xy 80.015101 -180.016553) (xy 79.992463 -180.066134)
			(xy 79.962999 -180.111987) (xy 79.927309 -180.153181) (xy 79.88612 -180.188875) (xy 79.840269 -180.218344)
			(xy 79.790691 -180.240987) (xy 79.738395 -180.256343) (xy 79.684446 -180.264099) (xy 79.657194 -180.264562)
			(xy 79.656686 -180.264562) (xy 79.622904 -180.263038) (xy 79.612744 -180.262022) (xy 79.59344 -180.268118)
			(xy 79.530448 -180.32095) (xy 79.52315 -180.327666) (xy 79.513875 -180.345176) (xy 79.512414 -180.354986)
			(xy 79.512414 -180.355748) (xy 79.509463 -180.383909) (xy 79.496256 -180.43897) (xy 79.475053 -180.491473)
			(xy 79.44632 -180.540263) (xy 79.410689 -180.58427) (xy 79.368944 -180.622524) (xy 79.322001 -180.654186)
			(xy 79.270893 -180.67856) (xy 79.216743 -180.69511) (xy 79.160741 -180.703471) (xy 79.13243 -180.703982)
			(xy 79.105177 -180.703517) (xy 79.051224 -180.695763) (xy 78.998925 -180.68041) (xy 78.949343 -180.657769)
			(xy 78.903489 -180.628301) (xy 78.862295 -180.592608) (xy 78.826601 -180.551414) (xy 78.797133 -180.50556)
			(xy 78.774492 -180.455979) (xy 78.759138 -180.403679) (xy 78.751384 -180.349727) (xy 78.750922 -180.322474)
			(xy 78.751409 -180.294612) (xy 78.759514 -180.23948) (xy 78.775547 -180.186112) (xy 78.799167 -180.135641)
			(xy 78.829874 -180.089141) (xy 78.867014 -180.047598) (xy 78.888082 -180.029358) (xy 78.897226 -180.021738)
			(xy 78.906624 -180.000656) (xy 78.903576 -179.908454) (xy 78.902683 -179.896967) (xy 78.891947 -179.876602)
			(xy 78.883002 -179.869338) (xy 78.882748 -179.869084) (xy 78.862203 -179.853655) (xy 78.825069 -179.818144)
			(xy 78.793037 -179.777969) (xy 78.766688 -179.733859) (xy 78.746498 -179.686611) (xy 78.732833 -179.637081)
			(xy 78.72594 -179.586164) (xy 78.725522 -179.560474) (xy 78.725522 -179.56022) (xy 78.725922 -179.535058)
			(xy 78.732567 -179.485174) (xy 78.745704 -179.436595) (xy 78.765107 -179.390161) (xy 78.790438 -179.346676)
			(xy 78.805532 -179.32654) (xy 78.813406 -179.316634) (xy 78.817724 -179.291488) (xy 78.782926 -179.187094)
			(xy 78.764638 -179.169822) (xy 78.752192 -179.16652) (xy 78.725672 -179.158714) (xy 78.675027 -179.136556)
			(xy 78.628109 -179.107322) (xy 78.585901 -179.071623) (xy 78.549286 -179.030208) (xy 78.51903 -178.983943)
			(xy 78.495767 -178.933795) (xy 78.479984 -178.880816) (xy 78.472011 -178.826114) (xy 78.471522 -178.798474)
			(xy 67.325494 -178.798474) (xy 70.74662 -182.2196) (xy 79.86014 -182.2196) (xy 79.860592 -182.192025)
			(xy 79.868545 -182.137451) (xy 79.884272 -182.08459) (xy 79.907445 -182.034544) (xy 79.93758 -181.988355)
			(xy 79.974051 -181.946985) (xy 79.99476 -181.92877) (xy 80.002858 -181.921236) (xy 80.012197 -181.901208)
			(xy 80.012794 -181.890162) (xy 80.012794 -181.812438) (xy 80.012207 -181.801391) (xy 80.002855 -181.78137)
			(xy 79.99476 -181.77383) (xy 79.974052 -181.755616) (xy 79.937583 -181.714246) (xy 79.907452 -181.668057)
			(xy 79.884286 -181.61801) (xy 79.868568 -181.565148) (xy 79.860627 -181.510574) (xy 79.86014 -181.483)
			(xy 79.86071 -181.454477) (xy 79.869217 -181.398068) (xy 79.886025 -181.343553) (xy 79.910762 -181.292148)
			(xy 79.942875 -181.244998) (xy 79.981648 -181.203154) (xy 80.026219 -181.167547) (xy 80.05064 -181.1528)
			(xy 80.060546 -181.147212) (xy 80.073246 -181.12867) (xy 80.090264 -181.028848) (xy 80.084168 -181.007258)
			(xy 80.076802 -180.998622) (xy 80.059877 -180.978237) (xy 80.031365 -180.933582) (xy 80.009461 -180.885339)
			(xy 79.994606 -180.834483) (xy 79.9871 -180.782035) (xy 79.986632 -180.755544) (xy 79.987075 -180.728925)
			(xy 79.994647 -180.676228) (xy 80.009642 -180.625146) (xy 80.031755 -180.576718) (xy 80.060537 -180.53193)
			(xy 80.0954 -180.491696) (xy 80.135635 -180.456833) (xy 80.180423 -180.428052) (xy 80.228851 -180.40594)
			(xy 80.279934 -180.390945) (xy 80.332631 -180.383375) (xy 80.35925 -180.382926) (xy 80.385672 -180.383372)
			(xy 80.437987 -180.390828) (xy 80.488725 -180.405596) (xy 80.536869 -180.427382) (xy 80.581454 -180.455748)
			(xy 80.60182 -180.472588) (xy 80.608678 -180.47843) (xy 80.625696 -180.48478) (xy 80.710024 -180.48478)
			(xy 80.727042 -180.47843) (xy 80.7339 -180.472588) (xy 80.754266 -180.455749) (xy 80.798852 -180.427384)
			(xy 80.846996 -180.405597) (xy 80.897733 -180.390826) (xy 80.950048 -180.383366) (xy 81.002892 -180.383366)
			(xy 81.055207 -180.390826) (xy 81.105944 -180.405597) (xy 81.154088 -180.427384) (xy 81.198674 -180.455749)
			(xy 81.21904 -180.472588) (xy 81.225898 -180.47843) (xy 81.242916 -180.48478) (xy 81.327244 -180.48478)
			(xy 81.344262 -180.47843) (xy 81.35112 -180.472588) (xy 81.371477 -180.455739) (xy 81.416069 -180.427386)
			(xy 81.464216 -180.405609) (xy 81.514954 -180.390844) (xy 81.567269 -180.383386) (xy 81.59369 -180.382926)
			(xy 81.621581 -180.383332) (xy 81.676739 -180.391645) (xy 81.730042 -180.408085) (xy 81.780299 -180.432287)
			(xy 81.826388 -180.463709) (xy 81.867279 -180.501649) (xy 81.902059 -180.54526) (xy 81.92995 -180.593567)
			(xy 81.9364 -180.610002) (xy 86.589362 -180.610002) (xy 86.589807 -180.582426) (xy 86.597761 -180.527852)
			(xy 86.613489 -180.474991) (xy 86.636662 -180.424944) (xy 86.6668 -180.378755) (xy 86.703272 -180.337386)
			(xy 86.723982 -180.319172) (xy 86.732067 -180.311625) (xy 86.741416 -180.291608) (xy 86.742016 -180.280564)
			(xy 86.742016 -180.20284) (xy 86.741452 -180.191789) (xy 86.732087 -180.171767) (xy 86.723982 -180.164232)
			(xy 86.70328 -180.146012) (xy 86.666809 -180.104644) (xy 86.636677 -180.058456) (xy 86.613509 -180.00841)
			(xy 86.597791 -179.955549) (xy 86.589849 -179.900976) (xy 86.589362 -179.873402) (xy 86.589807 -179.845826)
			(xy 86.597761 -179.791252) (xy 86.613489 -179.738391) (xy 86.636662 -179.688344) (xy 86.6668 -179.642155)
			(xy 86.703272 -179.600786) (xy 86.723982 -179.582572) (xy 86.732067 -179.575025) (xy 86.741416 -179.555008)
			(xy 86.742016 -179.543964) (xy 86.742016 -179.46624) (xy 86.741452 -179.455189) (xy 86.732087 -179.435167)
			(xy 86.723982 -179.427632) (xy 86.70328 -179.409412) (xy 86.666809 -179.368044) (xy 86.636677 -179.321856)
			(xy 86.613509 -179.27181) (xy 86.597791 -179.218949) (xy 86.589849 -179.164376) (xy 86.589362 -179.136802)
			(xy 86.58988 -179.109552) (xy 86.597635 -179.055607) (xy 86.612988 -179.003315) (xy 86.635627 -178.95374)
			(xy 86.66509 -178.907891) (xy 86.700778 -178.866701) (xy 86.741965 -178.83101) (xy 86.787811 -178.801542)
			(xy 86.837385 -178.7789) (xy 86.889676 -178.763542) (xy 86.94362 -178.755782) (xy 86.97087 -178.755294)
			(xy 86.998724 -178.755849) (xy 87.053838 -178.763968) (xy 87.107187 -178.780009) (xy 87.15764 -178.803632)
			(xy 87.204124 -178.834335) (xy 87.245654 -178.871466) (xy 87.281348 -178.914238) (xy 87.310448 -178.961742)
			(xy 87.332337 -179.01297) (xy 87.339932 -179.039774) (xy 87.342218 -179.048664) (xy 87.352886 -179.063904)
			(xy 87.424768 -179.111656) (xy 87.442802 -179.11572) (xy 87.451946 -179.11445) (xy 87.464962 -179.112778)
			(xy 87.491147 -179.111) (xy 87.50427 -179.110894) (xy 87.518419 -179.110991) (xy 87.546642 -179.113023)
			(xy 87.560658 -179.114958) (xy 87.570564 -179.116482) (xy 87.590376 -179.111656) (xy 87.664798 -179.055776)
			(xy 87.674958 -179.03825) (xy 87.676228 -179.02809) (xy 87.680396 -179.00095) (xy 87.695362 -178.948124)
			(xy 87.717745 -178.897989) (xy 87.747084 -178.851581) (xy 87.782772 -178.809856) (xy 87.824072 -178.773679)
			(xy 87.870132 -178.743795) (xy 87.92 -178.720823) (xy 87.972645 -178.705236) (xy 88.026982 -178.697356)
			(xy 88.054434 -178.696874) (xy 88.081685 -178.697346) (xy 88.135633 -178.705107) (xy 88.187926 -178.720465)
			(xy 88.237503 -178.743109) (xy 88.283352 -178.772577) (xy 88.324541 -178.80827) (xy 88.360232 -178.849461)
			(xy 88.389699 -178.895311) (xy 88.41234 -178.944889) (xy 88.427697 -178.997183) (xy 88.435455 -179.051131)
			(xy 88.435942 -179.078382) (xy 88.435484 -179.105957) (xy 88.427533 -179.160531) (xy 88.411808 -179.213392)
			(xy 88.388636 -179.263438) (xy 88.358501 -179.309628) (xy 88.322031 -179.350997) (xy 88.301322 -179.369212)
			(xy 88.293229 -179.37675) (xy 88.283888 -179.396775) (xy 88.283288 -179.40782) (xy 88.283288 -179.485544)
			(xy 88.283891 -179.496589) (xy 88.293232 -179.51661) (xy 88.301322 -179.524152) (xy 88.322018 -179.54238)
			(xy 88.358488 -179.583746) (xy 88.388622 -179.629932) (xy 88.41179 -179.679977) (xy 88.42751 -179.732836)
			(xy 88.435454 -179.787408) (xy 88.435488 -179.789328) (xy 93.02445 -179.789328) (xy 93.028521 -179.733706)
			(xy 93.040647 -179.679269) (xy 93.06057 -179.627178) (xy 93.087866 -179.578543) (xy 93.121952 -179.5344)
			(xy 93.162101 -179.495691) (xy 93.207459 -179.46324) (xy 93.257059 -179.437739) (xy 93.309843 -179.419732)
			(xy 93.364686 -179.409602) (xy 93.42042 -179.407565) (xy 93.475857 -179.413665) (xy 93.529814 -179.427771)
			(xy 93.581143 -179.449583) (xy 93.628749 -179.478637) (xy 93.671617 -179.514312) (xy 93.708834 -179.555849)
			(xy 93.739607 -179.602362) (xy 93.763279 -179.652859) (xy 93.779347 -179.706266) (xy 93.787467 -179.761442)
			(xy 93.787976 -179.789328) (xy 93.787467 -179.817214) (xy 93.779347 -179.87239) (xy 93.763279 -179.925797)
			(xy 93.739607 -179.976294) (xy 93.708834 -180.022807) (xy 93.671617 -180.064344) (xy 93.628749 -180.100019)
			(xy 93.581143 -180.129073) (xy 93.529814 -180.150885) (xy 93.475857 -180.164991) (xy 93.42042 -180.171091)
			(xy 93.364686 -180.169054) (xy 93.309843 -180.158924) (xy 93.257059 -180.140917) (xy 93.207459 -180.115416)
			(xy 93.162101 -180.082965) (xy 93.121952 -180.044256) (xy 93.087866 -180.000113) (xy 93.06057 -179.951478)
			(xy 93.040647 -179.899387) (xy 93.028521 -179.84495) (xy 93.02445 -179.789328) (xy 88.435488 -179.789328)
			(xy 88.435942 -179.814982) (xy 88.435405 -179.842231) (xy 88.427652 -179.896175) (xy 88.412301 -179.948467)
			(xy 88.389664 -179.998042) (xy 88.360203 -180.043891) (xy 88.324517 -180.08508) (xy 88.283332 -180.120772)
			(xy 88.237487 -180.150239) (xy 88.187916 -180.172883) (xy 88.135626 -180.188241) (xy 88.081683 -180.196001)
			(xy 88.054434 -180.19649) (xy 88.053926 -180.19649) (xy 88.020144 -180.194966) (xy 88.009984 -180.19395)
			(xy 87.99068 -180.200046) (xy 87.927688 -180.252878) (xy 87.920386 -180.259591) (xy 87.911112 -180.277103)
			(xy 87.909654 -180.286914) (xy 87.909654 -180.287676) (xy 87.906688 -180.315835) (xy 87.893478 -180.370892)
			(xy 87.872274 -180.423392) (xy 87.843542 -180.472181) (xy 87.807913 -180.516185) (xy 87.76617 -180.554439)
			(xy 87.71923 -180.586102) (xy 87.668125 -180.610478) (xy 87.613979 -180.62703) (xy 87.55798 -180.635396)
			(xy 87.52967 -180.63591) (xy 87.511651 -180.635689) (xy 87.475776 -180.632255) (xy 87.458042 -180.629052)
			(xy 87.44839 -180.627274) (xy 87.42934 -180.63083) (xy 87.35441 -180.678836) (xy 87.34298 -180.694584)
			(xy 87.340694 -180.703982) (xy 87.333311 -180.73103) (xy 87.311678 -180.782756) (xy 87.28271 -180.83076)
			(xy 87.247032 -180.87401) (xy 87.205411 -180.911576) (xy 87.158743 -180.94265) (xy 87.10803 -180.966562)
			(xy 87.054366 -180.982799) (xy 86.998903 -180.99101) (xy 86.97087 -180.99151) (xy 86.943618 -180.99105)
			(xy 86.88967 -180.98329) (xy 86.837374 -180.967931) (xy 86.787797 -180.945286) (xy 86.741947 -180.915817)
			(xy 86.700757 -180.880123) (xy 86.665066 -180.83893) (xy 86.6356 -180.793078) (xy 86.612959 -180.743499)
			(xy 86.597604 -180.691203) (xy 86.589848 -180.637254) (xy 86.589362 -180.610002) (xy 81.9364 -180.610002)
			(xy 81.950329 -180.645492) (xy 81.962742 -180.699875) (xy 81.966911 -180.7555) (xy 81.962742 -180.811125)
			(xy 81.950329 -180.865508) (xy 81.92995 -180.917433) (xy 81.902059 -180.96574) (xy 81.867279 -181.009351)
			(xy 81.826388 -181.047291) (xy 81.780299 -181.078713) (xy 81.730042 -181.102915) (xy 81.676739 -181.119355)
			(xy 81.621581 -181.127668) (xy 81.59369 -181.128162) (xy 81.567269 -181.127695) (xy 81.514954 -181.120245)
			(xy 81.464216 -181.105482) (xy 81.416072 -181.0837) (xy 81.371486 -181.055338) (xy 81.35112 -181.0385)
			(xy 81.344262 -181.032658) (xy 81.327244 -181.026308) (xy 81.242916 -181.026308) (xy 81.225898 -181.032658)
			(xy 81.21904 -181.0385) (xy 81.198674 -181.055339) (xy 81.154088 -181.083704) (xy 81.105944 -181.105491)
			(xy 81.055207 -181.120262) (xy 81.002892 -181.127722) (xy 80.950048 -181.127722) (xy 80.897733 -181.120262)
			(xy 80.846996 -181.105491) (xy 80.798852 -181.083704) (xy 80.754266 -181.055339) (xy 80.7339 -181.0385)
			(xy 80.727042 -181.032658) (xy 80.710024 -181.026308) (xy 80.625696 -181.026308) (xy 80.608678 -181.032658)
			(xy 80.60182 -181.0385) (xy 80.589745 -181.04857) (xy 80.564186 -181.066884) (xy 80.550766 -181.075076)
			(xy 80.550512 -181.07533) (xy 80.541324 -181.08159) (xy 80.528931 -181.100014) (xy 80.526636 -181.11089)
			(xy 80.51292 -181.19979) (xy 80.51927 -181.22138) (xy 80.52689 -181.229762) (xy 80.544916 -181.250813)
			(xy 80.575348 -181.297128) (xy 80.598751 -181.347362) (xy 80.614633 -181.400456) (xy 80.622659 -181.455291)
			(xy 80.623156 -181.483) (xy 80.622706 -181.510575) (xy 80.614752 -181.56515) (xy 80.599025 -181.61801)
			(xy 80.575852 -181.668057) (xy 80.545716 -181.714246) (xy 80.527895 -181.73446) (xy 85.586062 -181.73446)
			(xy 85.586538 -181.706549) (xy 85.594677 -181.651322) (xy 85.610777 -181.597872) (xy 85.634494 -181.547337)
			(xy 85.66532 -181.500798) (xy 85.683598 -181.479698) (xy 85.689495 -181.472521) (xy 85.696146 -181.455196)
			(xy 85.696552 -181.445916) (xy 85.696552 -181.368192) (xy 85.689948 -181.35092) (xy 85.683598 -181.343808)
			(xy 85.665302 -181.322723) (xy 85.634477 -181.276181) (xy 85.610765 -181.225642) (xy 85.594673 -181.172188)
			(xy 85.586544 -181.116958) (xy 85.586062 -181.089046) (xy 85.586548 -181.061795) (xy 85.594304 -181.007847)
			(xy 85.609659 -180.955552) (xy 85.632301 -180.905975) (xy 85.661767 -180.860125) (xy 85.697458 -180.818934)
			(xy 85.738649 -180.783243) (xy 85.784499 -180.753777) (xy 85.834076 -180.731135) (xy 85.886371 -180.71578)
			(xy 85.940319 -180.708024) (xy 85.994821 -180.708024) (xy 86.048769 -180.71578) (xy 86.101064 -180.731135)
			(xy 86.150641 -180.753777) (xy 86.196491 -180.783243) (xy 86.237682 -180.818934) (xy 86.273373 -180.860125)
			(xy 86.302839 -180.905975) (xy 86.325481 -180.955552) (xy 86.340836 -181.007847) (xy 86.348592 -181.061795)
			(xy 86.349078 -181.089046) (xy 86.348596 -181.116957) (xy 86.340456 -181.172183) (xy 86.324357 -181.225633)
			(xy 86.300643 -181.276167) (xy 86.269818 -181.322707) (xy 86.251542 -181.343808) (xy 86.245635 -181.350978)
			(xy 86.238992 -181.368309) (xy 86.238588 -181.37759) (xy 86.238588 -181.455314) (xy 86.245192 -181.472586)
			(xy 86.251542 -181.479698) (xy 86.2698 -181.500814) (xy 86.300629 -181.547349) (xy 86.324347 -181.597879)
			(xy 86.340449 -181.651327) (xy 86.348589 -181.70655) (xy 86.349078 -181.73446) (xy 86.348592 -181.761711)
			(xy 86.340836 -181.815659) (xy 86.325481 -181.867954) (xy 86.302839 -181.917531) (xy 86.273373 -181.963381)
			(xy 86.237682 -182.004572) (xy 86.196491 -182.040263) (xy 86.150641 -182.069729) (xy 86.101064 -182.092371)
			(xy 86.048769 -182.107726) (xy 85.994821 -182.115482) (xy 85.940319 -182.115482) (xy 85.886371 -182.107726)
			(xy 85.834076 -182.092371) (xy 85.784499 -182.069729) (xy 85.738649 -182.040263) (xy 85.697458 -182.004572)
			(xy 85.661767 -181.963381) (xy 85.632301 -181.917531) (xy 85.609659 -181.867954) (xy 85.594304 -181.815659)
			(xy 85.586548 -181.761711) (xy 85.586062 -181.73446) (xy 80.527895 -181.73446) (xy 80.509245 -181.755615)
			(xy 80.488536 -181.77383) (xy 80.480437 -181.781363) (xy 80.471098 -181.801392) (xy 80.470502 -181.812438)
			(xy 80.470502 -181.890162) (xy 80.471091 -181.901209) (xy 80.480441 -181.92123) (xy 80.488536 -181.92877)
			(xy 80.509243 -181.946985) (xy 80.545712 -181.988354) (xy 80.575844 -182.034543) (xy 80.59901 -182.08459)
			(xy 80.613476 -182.13324) (xy 88.110822 -182.13324) (xy 88.111308 -182.105666) (xy 88.119255 -182.051094)
			(xy 88.134976 -181.998234) (xy 88.158142 -181.948188) (xy 88.188271 -181.901998) (xy 88.224736 -181.860626)
			(xy 88.245442 -181.84241) (xy 88.25352 -181.834857) (xy 88.262871 -181.814844) (xy 88.263476 -181.803802)
			(xy 88.263476 -181.726078) (xy 88.262872 -181.715033) (xy 88.253533 -181.695011) (xy 88.245442 -181.68747)
			(xy 88.224722 -181.669269) (xy 88.18825 -181.627899) (xy 88.158118 -181.581707) (xy 88.134954 -181.531657)
			(xy 88.11924 -181.478792) (xy 88.111305 -181.424215) (xy 88.110822 -181.39664) (xy 88.111224 -181.36959)
			(xy 88.118875 -181.316034) (xy 88.134013 -181.264095) (xy 88.156336 -181.214816) (xy 88.185396 -181.169184)
			(xy 88.220611 -181.128114) (xy 88.261273 -181.09243) (xy 88.306569 -181.062848) (xy 88.355588 -181.03996)
			(xy 88.381332 -181.031642) (xy 88.392508 -181.02834) (xy 88.40978 -181.012084) (xy 88.442546 -180.925978)
			(xy 88.446162 -180.914913) (xy 88.444043 -180.891755) (xy 88.438482 -180.881528) (xy 88.425555 -180.859512)
			(xy 88.405154 -180.812712) (xy 88.391321 -180.763568) (xy 88.384314 -180.712998) (xy 88.383872 -180.687472)
			(xy 88.384331 -180.660856) (xy 88.39191 -180.608165) (xy 88.40691 -180.557089) (xy 88.429026 -180.508668)
			(xy 88.457808 -180.463886) (xy 88.492669 -180.423657) (xy 88.532901 -180.388797) (xy 88.577683 -180.360018)
			(xy 88.626106 -180.337904) (xy 88.677183 -180.322906) (xy 88.729874 -180.315329) (xy 88.75649 -180.314854)
			(xy 88.782911 -180.315328) (xy 88.835225 -180.322776) (xy 88.885963 -180.337538) (xy 88.934108 -180.359318)
			(xy 88.978694 -180.387679) (xy 88.99906 -180.404516) (xy 89.005918 -180.410358) (xy 89.022936 -180.416708)
			(xy 89.107264 -180.416708) (xy 89.124282 -180.410358) (xy 89.13114 -180.404516) (xy 89.151506 -180.387677)
			(xy 89.196092 -180.359312) (xy 89.244236 -180.337525) (xy 89.294973 -180.322754) (xy 89.347288 -180.315294)
			(xy 89.400132 -180.315294) (xy 89.452447 -180.322754) (xy 89.503184 -180.337525) (xy 89.551328 -180.359312)
			(xy 89.595914 -180.387677) (xy 89.61628 -180.404516) (xy 89.623138 -180.410358) (xy 89.640156 -180.416708)
			(xy 89.724484 -180.416708) (xy 89.741502 -180.410358) (xy 89.74836 -180.404516) (xy 89.768742 -180.387699)
			(xy 89.813327 -180.35934) (xy 89.861468 -180.337557) (xy 89.912201 -180.322784) (xy 89.96451 -180.315318)
			(xy 89.99093 -180.314854) (xy 90.018811 -180.315433) (xy 90.07395 -180.323748) (xy 90.127235 -180.340188)
			(xy 90.177474 -180.364385) (xy 90.223545 -180.3958) (xy 90.264421 -180.43373) (xy 90.299186 -180.477328)
			(xy 90.327066 -180.52562) (xy 90.347438 -180.577529) (xy 90.358792 -180.627274) (xy 94.981522 -180.627274)
			(xy 94.982031 -180.599701) (xy 94.989974 -180.54513) (xy 95.00569 -180.49227) (xy 95.028851 -180.442224)
			(xy 95.058977 -180.396033) (xy 95.095438 -180.354661) (xy 95.116142 -180.336444) (xy 95.124205 -180.328878)
			(xy 95.133564 -180.308874) (xy 95.134176 -180.297836) (xy 95.134176 -180.220112) (xy 95.133609 -180.209062)
			(xy 95.124244 -180.189041) (xy 95.116142 -180.181504) (xy 95.095438 -180.163285) (xy 95.058965 -180.121919)
			(xy 95.028831 -180.075731) (xy 95.005664 -180.025684) (xy 94.989947 -179.972823) (xy 94.982007 -179.918248)
			(xy 94.981522 -179.890674) (xy 94.982031 -179.863101) (xy 94.989974 -179.80853) (xy 95.00569 -179.75567)
			(xy 95.028851 -179.705624) (xy 95.058977 -179.659433) (xy 95.095438 -179.618061) (xy 95.116142 -179.599844)
			(xy 95.124205 -179.592278) (xy 95.133564 -179.572274) (xy 95.134176 -179.561236) (xy 95.134176 -179.483512)
			(xy 95.133609 -179.472462) (xy 95.124244 -179.452441) (xy 95.116142 -179.444904) (xy 95.095438 -179.426685)
			(xy 95.058965 -179.385319) (xy 95.028831 -179.339131) (xy 95.005664 -179.289084) (xy 94.989947 -179.236223)
			(xy 94.982007 -179.181648) (xy 94.981522 -179.154074) (xy 94.981931 -179.126819) (xy 94.989692 -179.072865)
			(xy 95.005053 -179.020564) (xy 95.027701 -178.970982) (xy 95.057174 -178.925127) (xy 95.092874 -178.883934)
			(xy 95.134072 -178.848241) (xy 95.179931 -178.818774) (xy 95.229516 -178.796133) (xy 95.281819 -178.78078)
			(xy 95.335775 -178.773027) (xy 95.36303 -178.772566) (xy 95.390885 -178.773087) (xy 95.445999 -178.781214)
			(xy 95.499348 -178.797262) (xy 95.5498 -178.82089) (xy 95.596283 -178.851597) (xy 95.637812 -178.888732)
			(xy 95.673506 -178.931506) (xy 95.702606 -178.979012) (xy 95.724496 -179.030242) (xy 95.732092 -179.057046)
			(xy 95.734378 -179.065936) (xy 95.745046 -179.081176) (xy 95.816928 -179.128928) (xy 95.834962 -179.132992)
			(xy 95.844106 -179.131722) (xy 95.857123 -179.130054) (xy 95.883307 -179.128273) (xy 95.89643 -179.128166)
			(xy 95.910579 -179.128257) (xy 95.938802 -179.130293) (xy 95.952818 -179.13223) (xy 95.962724 -179.133754)
			(xy 95.982536 -179.128928) (xy 96.056958 -179.073048) (xy 96.067118 -179.055522) (xy 96.068388 -179.045362)
			(xy 96.072477 -179.018208) (xy 96.087449 -178.965378) (xy 96.10984 -178.915239) (xy 96.139187 -178.868828)
			(xy 96.174885 -178.827104) (xy 96.216194 -178.790927) (xy 96.262263 -178.761046) (xy 96.31214 -178.738077)
			(xy 96.364794 -178.722496) (xy 96.419138 -178.714624) (xy 96.446594 -178.714146) (xy 96.473843 -178.714683)
			(xy 96.527787 -178.722438) (xy 96.580077 -178.73779) (xy 96.629652 -178.760427) (xy 96.6755 -178.789888)
			(xy 96.716689 -178.825574) (xy 96.752381 -178.866758) (xy 96.781848 -178.912603) (xy 96.804492 -178.962174)
			(xy 96.819851 -179.014463) (xy 96.827613 -179.068405) (xy 96.828102 -179.095654) (xy 96.827604 -179.123227)
			(xy 96.819658 -179.177799) (xy 96.803939 -179.230658) (xy 96.780775 -179.280704) (xy 96.750649 -179.326894)
			(xy 96.714187 -179.368267) (xy 96.693482 -179.386484) (xy 96.685411 -179.394043) (xy 96.676055 -179.414052)
			(xy 96.675448 -179.425092) (xy 96.675448 -179.502816) (xy 96.676048 -179.513862) (xy 96.685389 -179.533884)
			(xy 96.693482 -179.541424) (xy 96.714204 -179.559623) (xy 96.750675 -179.600994) (xy 96.780806 -179.647186)
			(xy 96.80397 -179.697237) (xy 96.819683 -179.750102) (xy 96.827619 -179.804678) (xy 96.827653 -179.8066)
			(xy 101.41661 -179.8066) (xy 101.420681 -179.750978) (xy 101.432807 -179.696541) (xy 101.45273 -179.64445)
			(xy 101.480026 -179.595815) (xy 101.514112 -179.551672) (xy 101.554261 -179.512963) (xy 101.599619 -179.480512)
			(xy 101.649219 -179.455011) (xy 101.702003 -179.437004) (xy 101.756846 -179.426874) (xy 101.81258 -179.424837)
			(xy 101.868017 -179.430937) (xy 101.921974 -179.445043) (xy 101.973303 -179.466855) (xy 102.020909 -179.495909)
			(xy 102.063777 -179.531584) (xy 102.100994 -179.573121) (xy 102.131767 -179.619634) (xy 102.155439 -179.670131)
			(xy 102.171507 -179.723538) (xy 102.179627 -179.778714) (xy 102.180136 -179.8066) (xy 102.179627 -179.834486)
			(xy 102.171507 -179.889662) (xy 102.155439 -179.943069) (xy 102.131767 -179.993566) (xy 102.100994 -180.040079)
			(xy 102.063777 -180.081616) (xy 102.020909 -180.117291) (xy 101.973303 -180.146345) (xy 101.921974 -180.168157)
			(xy 101.868017 -180.182263) (xy 101.81258 -180.188363) (xy 101.756846 -180.186326) (xy 101.702003 -180.176196)
			(xy 101.649219 -180.158189) (xy 101.599619 -180.132688) (xy 101.554261 -180.100237) (xy 101.514112 -180.061528)
			(xy 101.480026 -180.017385) (xy 101.45273 -179.96875) (xy 101.432807 -179.916659) (xy 101.420681 -179.862222)
			(xy 101.41661 -179.8066) (xy 96.827653 -179.8066) (xy 96.828102 -179.832254) (xy 96.827602 -179.859506)
			(xy 96.819851 -179.913456) (xy 96.804501 -179.965753) (xy 96.781863 -180.015334) (xy 96.752399 -180.061187)
			(xy 96.716709 -180.102381) (xy 96.67552 -180.138075) (xy 96.629669 -180.167544) (xy 96.580091 -180.190187)
			(xy 96.527795 -180.205543) (xy 96.473846 -180.213299) (xy 96.446594 -180.213762) (xy 96.446086 -180.213762)
			(xy 96.412304 -180.212238) (xy 96.402144 -180.211222) (xy 96.38284 -180.217318) (xy 96.319848 -180.27015)
			(xy 96.31255 -180.276866) (xy 96.303275 -180.294376) (xy 96.301814 -180.304186) (xy 96.301814 -180.304948)
			(xy 96.298863 -180.333109) (xy 96.285656 -180.38817) (xy 96.264453 -180.440673) (xy 96.23572 -180.489463)
			(xy 96.200089 -180.53347) (xy 96.158344 -180.571724) (xy 96.111401 -180.603386) (xy 96.060293 -180.62776)
			(xy 96.006143 -180.64431) (xy 95.950141 -180.652671) (xy 95.92183 -180.653182) (xy 95.903811 -180.652966)
			(xy 95.867936 -180.649528) (xy 95.850202 -180.646324) (xy 95.84055 -180.644546) (xy 95.8215 -180.648102)
			(xy 95.74657 -180.696108) (xy 95.73514 -180.711856) (xy 95.732854 -180.721254) (xy 95.725489 -180.748308)
			(xy 95.703856 -180.800036) (xy 95.674888 -180.848042) (xy 95.639209 -180.891294) (xy 95.597585 -180.928861)
			(xy 95.550913 -180.959934) (xy 95.500198 -180.983844) (xy 95.44653 -181.000078) (xy 95.391065 -181.008285)
			(xy 95.36303 -181.008782) (xy 95.335777 -181.008317) (xy 95.281824 -181.000563) (xy 95.229525 -180.98521)
			(xy 95.179943 -180.962569) (xy 95.134089 -180.933101) (xy 95.092895 -180.897408) (xy 95.057201 -180.856214)
			(xy 95.027733 -180.81036) (xy 95.005092 -180.760779) (xy 94.989738 -180.708479) (xy 94.981984 -180.654527)
			(xy 94.981522 -180.627274) (xy 90.358792 -180.627274) (xy 90.359846 -180.631893) (xy 90.364013 -180.6875)
			(xy 90.359846 -180.743107) (xy 90.347438 -180.797471) (xy 90.327066 -180.84938) (xy 90.299186 -180.897672)
			(xy 90.264421 -180.94127) (xy 90.223545 -180.9792) (xy 90.177474 -181.010615) (xy 90.127235 -181.034812)
			(xy 90.07395 -181.051252) (xy 90.018811 -181.059567) (xy 89.99093 -181.06009) (xy 89.964509 -181.059617)
			(xy 89.912194 -181.052171) (xy 89.861455 -181.03741) (xy 89.813311 -181.015629) (xy 89.768725 -180.987266)
			(xy 89.74836 -180.970428) (xy 89.741502 -180.964586) (xy 89.724484 -180.958236) (xy 89.640156 -180.958236)
			(xy 89.623138 -180.964586) (xy 89.61628 -180.970428) (xy 89.595914 -180.987267) (xy 89.551328 -181.015632)
			(xy 89.503184 -181.037419) (xy 89.452447 -181.05219) (xy 89.400132 -181.05965) (xy 89.347288 -181.05965)
			(xy 89.294973 -181.05219) (xy 89.244236 -181.037419) (xy 89.196092 -181.015632) (xy 89.151506 -180.987267)
			(xy 89.13114 -180.970428) (xy 89.124282 -180.964586) (xy 89.107264 -180.958236) (xy 89.022936 -180.958236)
			(xy 89.005918 -180.964586) (xy 88.99906 -180.970428) (xy 88.979951 -180.986226) (xy 88.938339 -181.013183)
			(xy 88.893521 -181.034385) (xy 88.870028 -181.04231) (xy 88.858852 -181.045866) (xy 88.842088 -181.062122)
			(xy 88.810338 -181.148736) (xy 88.806937 -181.159888) (xy 88.809429 -181.183038) (xy 88.815164 -181.193186)
			(xy 88.829074 -181.2161) (xy 88.851016 -181.265008) (xy 88.865885 -181.316508) (xy 88.873388 -181.369584)
			(xy 88.873838 -181.396386) (xy 88.873838 -181.39664) (xy 88.873353 -181.424214) (xy 88.865407 -181.478787)
			(xy 88.849688 -181.531647) (xy 88.826521 -181.581694) (xy 88.796391 -181.627884) (xy 88.762452 -181.666388)
			(xy 93.983302 -181.666388) (xy 93.98381 -181.638478) (xy 93.991944 -181.583254) (xy 94.008037 -181.529804)
			(xy 94.031746 -181.479269) (xy 94.062564 -181.432728) (xy 94.080838 -181.411626) (xy 94.086728 -181.404444)
			(xy 94.093382 -181.387122) (xy 94.093792 -181.377844) (xy 94.093792 -181.30012) (xy 94.087188 -181.282848)
			(xy 94.080838 -181.275736) (xy 94.062546 -181.254648) (xy 94.031722 -181.208106) (xy 94.008011 -181.157568)
			(xy 93.991918 -181.104114) (xy 93.983786 -181.048886) (xy 93.983302 -181.020974) (xy 93.983788 -180.993723)
			(xy 93.991544 -180.939775) (xy 94.006899 -180.88748) (xy 94.029541 -180.837903) (xy 94.059007 -180.792053)
			(xy 94.094698 -180.750862) (xy 94.135889 -180.715171) (xy 94.181739 -180.685705) (xy 94.231316 -180.663063)
			(xy 94.283611 -180.647708) (xy 94.337559 -180.639952) (xy 94.392061 -180.639952) (xy 94.446009 -180.647708)
			(xy 94.498304 -180.663063) (xy 94.547881 -180.685705) (xy 94.593731 -180.715171) (xy 94.634922 -180.750862)
			(xy 94.670613 -180.792053) (xy 94.700079 -180.837903) (xy 94.722721 -180.88748) (xy 94.738076 -180.939775)
			(xy 94.745832 -180.993723) (xy 94.746318 -181.020974) (xy 94.745868 -181.048886) (xy 94.737722 -181.104114)
			(xy 94.721617 -181.157565) (xy 94.697895 -181.208099) (xy 94.667063 -181.254637) (xy 94.648782 -181.275736)
			(xy 94.642868 -181.282901) (xy 94.636227 -181.300235) (xy 94.635828 -181.309518) (xy 94.635828 -181.387242)
			(xy 94.642432 -181.404514) (xy 94.648782 -181.411626) (xy 94.667044 -181.432739) (xy 94.697874 -181.479274)
			(xy 94.721593 -181.529805) (xy 94.737693 -181.583253) (xy 94.745831 -181.638478) (xy 94.746318 -181.666388)
			(xy 94.745832 -181.693639) (xy 94.738076 -181.747587) (xy 94.722721 -181.799882) (xy 94.700079 -181.849459)
			(xy 94.670613 -181.895309) (xy 94.634922 -181.9365) (xy 94.593731 -181.972191) (xy 94.547881 -182.001657)
			(xy 94.498304 -182.024299) (xy 94.446009 -182.039654) (xy 94.392061 -182.04741) (xy 94.337559 -182.04741)
			(xy 94.283611 -182.039654) (xy 94.231316 -182.024299) (xy 94.181739 -182.001657) (xy 94.135889 -181.972191)
			(xy 94.094698 -181.9365) (xy 94.059007 -181.895309) (xy 94.029541 -181.849459) (xy 94.006899 -181.799882)
			(xy 93.991544 -181.747587) (xy 93.983788 -181.693639) (xy 93.983302 -181.666388) (xy 88.762452 -181.666388)
			(xy 88.759925 -181.669255) (xy 88.739218 -181.68747) (xy 88.731159 -181.69504) (xy 88.721795 -181.71504)
			(xy 88.721184 -181.726078) (xy 88.721184 -181.803802) (xy 88.72178 -181.814849) (xy 88.731123 -181.834872)
			(xy 88.739218 -181.84241) (xy 88.759941 -181.860608) (xy 88.796409 -181.90198) (xy 88.82654 -181.948173)
			(xy 88.849703 -181.998223) (xy 88.865417 -182.051088) (xy 88.873354 -182.105665) (xy 88.873838 -182.13324)
			(xy 96.59874 -182.13324) (xy 96.599219 -182.105666) (xy 96.607167 -182.051093) (xy 96.622888 -181.998233)
			(xy 96.646056 -181.948186) (xy 96.676187 -181.901997) (xy 96.712653 -181.860626) (xy 96.73336 -181.84241)
			(xy 96.74144 -181.83486) (xy 96.750789 -181.814844) (xy 96.751394 -181.803802) (xy 96.751394 -181.726078)
			(xy 96.750784 -181.715034) (xy 96.741449 -181.695012) (xy 96.73336 -181.68747) (xy 96.712623 -181.669287)
			(xy 96.676157 -181.627911) (xy 96.646029 -181.581715) (xy 96.622868 -181.531662) (xy 96.607156 -181.478795)
			(xy 96.599222 -181.424216) (xy 96.59874 -181.39664) (xy 96.599286 -181.367028) (xy 96.608433 -181.308514)
			(xy 96.626512 -181.252118) (xy 96.653091 -181.199192) (xy 96.68753 -181.151011) (xy 96.729001 -181.10873)
			(xy 96.776508 -181.073367) (xy 96.802448 -181.059074) (xy 96.811846 -181.054248) (xy 96.825308 -181.036976)
			(xy 96.849184 -180.942742) (xy 96.845374 -180.92166) (xy 96.839278 -180.912516) (xy 96.824345 -180.889347)
			(xy 96.800704 -180.839554) (xy 96.784649 -180.786823) (xy 96.77653 -180.732304) (xy 96.776032 -180.704744)
			(xy 96.776475 -180.678125) (xy 96.784047 -180.625428) (xy 96.799042 -180.574346) (xy 96.821155 -180.525918)
			(xy 96.849937 -180.48113) (xy 96.8848 -180.440896) (xy 96.925035 -180.406033) (xy 96.969823 -180.377252)
			(xy 97.018251 -180.35514) (xy 97.069334 -180.340145) (xy 97.122031 -180.332575) (xy 97.14865 -180.332126)
			(xy 97.175072 -180.332572) (xy 97.227387 -180.340028) (xy 97.278125 -180.354796) (xy 97.326269 -180.376582)
			(xy 97.370854 -180.404948) (xy 97.39122 -180.421788) (xy 97.398078 -180.42763) (xy 97.415096 -180.43398)
			(xy 97.499424 -180.43398) (xy 97.516442 -180.42763) (xy 97.5233 -180.421788) (xy 97.543666 -180.404949)
			(xy 97.588252 -180.376584) (xy 97.636396 -180.354797) (xy 97.687133 -180.340026) (xy 97.739448 -180.332566)
			(xy 97.792292 -180.332566) (xy 97.844607 -180.340026) (xy 97.895344 -180.354797) (xy 97.943488 -180.376584)
			(xy 97.988074 -180.404949) (xy 98.00844 -180.421788) (xy 98.015298 -180.42763) (xy 98.032316 -180.43398)
			(xy 98.116644 -180.43398) (xy 98.133662 -180.42763) (xy 98.14052 -180.421788) (xy 98.160877 -180.404939)
			(xy 98.205469 -180.376586) (xy 98.253616 -180.354809) (xy 98.304354 -180.340044) (xy 98.356669 -180.332586)
			(xy 98.38309 -180.332126) (xy 98.410981 -180.332532) (xy 98.466139 -180.340845) (xy 98.519442 -180.357285)
			(xy 98.569699 -180.381487) (xy 98.615788 -180.412909) (xy 98.656679 -180.450849) (xy 98.691459 -180.49446)
			(xy 98.71935 -180.542767) (xy 98.739729 -180.594692) (xy 98.752142 -180.649075) (xy 98.756311 -180.7047)
			(xy 98.752142 -180.760325) (xy 98.739729 -180.814708) (xy 98.71935 -180.866633) (xy 98.691459 -180.91494)
			(xy 98.656679 -180.958551) (xy 98.615788 -180.996491) (xy 98.569699 -181.027913) (xy 98.519442 -181.052115)
			(xy 98.466139 -181.068555) (xy 98.410981 -181.076868) (xy 98.38309 -181.077362) (xy 98.356669 -181.076895)
			(xy 98.304354 -181.069445) (xy 98.253616 -181.054682) (xy 98.205472 -181.0329) (xy 98.160886 -181.004538)
			(xy 98.14052 -180.9877) (xy 98.133662 -180.981858) (xy 98.116644 -180.975508) (xy 98.032316 -180.975508)
			(xy 98.015298 -180.981858) (xy 98.00844 -180.9877) (xy 97.988074 -181.004539) (xy 97.943488 -181.032904)
			(xy 97.895344 -181.054691) (xy 97.844607 -181.069462) (xy 97.792292 -181.076922) (xy 97.739448 -181.076922)
			(xy 97.687133 -181.069462) (xy 97.636396 -181.054691) (xy 97.588252 -181.032904) (xy 97.543666 -181.004539)
			(xy 97.5233 -180.9877) (xy 97.516442 -180.981858) (xy 97.499424 -180.975508) (xy 97.415096 -180.975508)
			(xy 97.398078 -180.981858) (xy 97.39122 -180.9877) (xy 97.376369 -181.000042) (xy 97.344556 -181.021932)
			(xy 97.32772 -181.031388) (xy 97.318579 -181.036981) (xy 97.305692 -181.054081) (xy 97.302828 -181.064408)
			(xy 97.285556 -181.138068) (xy 97.283673 -181.148528) (xy 97.287623 -181.16939) (xy 97.293176 -181.178454)
			(xy 97.29343 -181.178708) (xy 97.309557 -181.202826) (xy 97.33509 -181.254922) (xy 97.352443 -181.310283)
			(xy 97.361218 -181.367632) (xy 97.361756 -181.39664) (xy 97.361264 -181.424214) (xy 97.353319 -181.478786)
			(xy 97.3376 -181.531646) (xy 97.314435 -181.581693) (xy 97.284307 -181.627883) (xy 97.247842 -181.669254)
			(xy 97.231467 -181.68366) (xy 102.375462 -181.68366) (xy 102.375938 -181.655749) (xy 102.384077 -181.600522)
			(xy 102.400177 -181.547072) (xy 102.423894 -181.496537) (xy 102.45472 -181.449998) (xy 102.472998 -181.428898)
			(xy 102.478895 -181.421721) (xy 102.485546 -181.404396) (xy 102.485952 -181.395116) (xy 102.485952 -181.317392)
			(xy 102.479348 -181.30012) (xy 102.472998 -181.293008) (xy 102.454702 -181.271923) (xy 102.423877 -181.225381)
			(xy 102.400165 -181.174842) (xy 102.384073 -181.121388) (xy 102.375944 -181.066158) (xy 102.375462 -181.038246)
			(xy 102.375948 -181.010995) (xy 102.383704 -180.957047) (xy 102.399059 -180.904752) (xy 102.421701 -180.855175)
			(xy 102.451167 -180.809325) (xy 102.486858 -180.768134) (xy 102.528049 -180.732443) (xy 102.573899 -180.702977)
			(xy 102.623476 -180.680335) (xy 102.675771 -180.66498) (xy 102.729719 -180.657224) (xy 102.784221 -180.657224)
			(xy 102.838169 -180.66498) (xy 102.890464 -180.680335) (xy 102.940041 -180.702977) (xy 102.985891 -180.732443)
			(xy 103.027082 -180.768134) (xy 103.062773 -180.809325) (xy 103.092239 -180.855175) (xy 103.114881 -180.904752)
			(xy 103.130236 -180.957047) (xy 103.137992 -181.010995) (xy 103.138478 -181.038246) (xy 103.137996 -181.066157)
			(xy 103.129856 -181.121383) (xy 103.113757 -181.174833) (xy 103.090043 -181.225367) (xy 103.059218 -181.271907)
			(xy 103.040942 -181.293008) (xy 103.035035 -181.300178) (xy 103.028392 -181.317509) (xy 103.027988 -181.32679)
			(xy 103.027988 -181.404514) (xy 103.034592 -181.421786) (xy 103.040942 -181.428898) (xy 103.0592 -181.450014)
			(xy 103.090029 -181.496549) (xy 103.113747 -181.547079) (xy 103.129849 -181.600527) (xy 103.137989 -181.65575)
			(xy 103.138478 -181.68366) (xy 103.137992 -181.710911) (xy 103.130236 -181.764859) (xy 103.114881 -181.817154)
			(xy 103.092239 -181.866731) (xy 103.062773 -181.912581) (xy 103.027082 -181.953772) (xy 102.985891 -181.989463)
			(xy 102.940041 -182.018929) (xy 102.890464 -182.041571) (xy 102.838169 -182.056926) (xy 102.784221 -182.064682)
			(xy 102.729719 -182.064682) (xy 102.675771 -182.056926) (xy 102.623476 -182.041571) (xy 102.573899 -182.018929)
			(xy 102.528049 -181.989463) (xy 102.486858 -181.953772) (xy 102.451167 -181.912581) (xy 102.421701 -181.866731)
			(xy 102.399059 -181.817154) (xy 102.383704 -181.764859) (xy 102.375948 -181.710911) (xy 102.375462 -181.68366)
			(xy 97.231467 -181.68366) (xy 97.227136 -181.68747) (xy 97.219064 -181.695027) (xy 97.20971 -181.715037)
			(xy 97.209102 -181.726078) (xy 97.209102 -181.803802) (xy 97.209724 -181.814845) (xy 97.219051 -181.834866)
			(xy 97.227136 -181.84241) (xy 97.247862 -181.860604) (xy 97.28433 -181.901978) (xy 97.314459 -181.948171)
			(xy 97.337622 -181.998222) (xy 97.353336 -182.051088) (xy 97.361272 -182.105664) (xy 97.361756 -182.13324)
			(xy 97.36127 -182.160491) (xy 97.353514 -182.214439) (xy 97.338159 -182.266734) (xy 97.315517 -182.316311)
			(xy 97.286051 -182.362161) (xy 97.25036 -182.403352) (xy 97.209169 -182.439043) (xy 97.163319 -182.468509)
			(xy 97.113742 -182.491151) (xy 97.061447 -182.506506) (xy 97.007499 -182.514262) (xy 96.952997 -182.514262)
			(xy 96.899049 -182.506506) (xy 96.846754 -182.491151) (xy 96.797177 -182.468509) (xy 96.751327 -182.439043)
			(xy 96.710136 -182.403352) (xy 96.674445 -182.362161) (xy 96.644979 -182.316311) (xy 96.622337 -182.266734)
			(xy 96.606982 -182.214439) (xy 96.599226 -182.160491) (xy 96.59874 -182.13324) (xy 88.873838 -182.13324)
			(xy 88.873352 -182.160491) (xy 88.865596 -182.214439) (xy 88.850241 -182.266734) (xy 88.827599 -182.316311)
			(xy 88.798133 -182.362161) (xy 88.762442 -182.403352) (xy 88.721251 -182.439043) (xy 88.675401 -182.468509)
			(xy 88.625824 -182.491151) (xy 88.573529 -182.506506) (xy 88.519581 -182.514262) (xy 88.465079 -182.514262)
			(xy 88.411131 -182.506506) (xy 88.358836 -182.491151) (xy 88.309259 -182.468509) (xy 88.263409 -182.439043)
			(xy 88.222218 -182.403352) (xy 88.186527 -182.362161) (xy 88.157061 -182.316311) (xy 88.134419 -182.266734)
			(xy 88.119064 -182.214439) (xy 88.111308 -182.160491) (xy 88.110822 -182.13324) (xy 80.613476 -182.13324)
			(xy 80.614728 -182.137452) (xy 80.622669 -182.192026) (xy 80.623156 -182.2196) (xy 80.62267 -182.246851)
			(xy 80.614914 -182.300799) (xy 80.599559 -182.353094) (xy 80.576917 -182.402671) (xy 80.547451 -182.448521)
			(xy 80.51176 -182.489712) (xy 80.470569 -182.525403) (xy 80.424719 -182.554869) (xy 80.375142 -182.577511)
			(xy 80.322847 -182.592866) (xy 80.268899 -182.600622) (xy 80.214397 -182.600622) (xy 80.160449 -182.592866)
			(xy 80.108154 -182.577511) (xy 80.058577 -182.554869) (xy 80.012727 -182.525403) (xy 79.971536 -182.489712)
			(xy 79.935845 -182.448521) (xy 79.906379 -182.402671) (xy 79.883737 -182.353094) (xy 79.868382 -182.300799)
			(xy 79.860626 -182.246851) (xy 79.86014 -182.2196) (xy 70.74662 -182.2196) (xy 78.781402 -190.254382)
			(xy 78.786899 -190.259374) (xy 78.800064 -190.266226) (xy 78.80731 -190.267844) (xy 78.816962 -190.26886)
			(xy 104.967278 -190.26886)
		)
		(stroke
			(width 0)
			(type solid)
		)
		(fill yes)
		(layer "In11.Cu")
		(net "GND")
	)
	(gr_poly
		(pts
			(xy 396.124176 -202.197462) (xy 396.134239 -202.197024) (xy 396.15282 -202.189286) (xy 396.160244 -202.182476)
			(xy 409.206954 -189.135766) (xy 409.214352 -189.128921) (xy 409.232951 -189.121196) (xy 409.243022 -189.12078)
			(xy 414.550098 -189.12078) (xy 414.560168 -189.120357) (xy 414.578771 -189.112641) (xy 414.586166 -189.105794)
			(xy 428.184564 -175.507396) (xy 428.185072 -175.506888) (xy 428.191659 -175.499508) (xy 428.199121 -175.481209)
			(xy 428.19955 -175.471328) (xy 428.19955 -159.189166) (xy 428.199119 -159.1791) (xy 428.191391 -159.160509)
			(xy 428.184564 -159.153098) (xy 427.348396 -158.31693) (xy 427.341052 -158.310117) (xy 427.322589 -158.302381)
			(xy 427.312582 -158.301944) (xy 418.03447 -158.301944) (xy 417.908232 -158.301944) (xy 417.898169 -158.301507)
			(xy 417.879587 -158.293769) (xy 417.872164 -158.286958) (xy 417.79063 -158.205424) (xy 417.790122 -158.204916)
			(xy 417.782756 -158.197804) (xy 416.48126 -156.896308) (xy 416.473849 -156.889629) (xy 416.455412 -156.88206)
			(xy 416.445446 -156.881576) (xy 402.58238 -156.881576) (xy 402.57349 -156.881322) (xy 402.456142 -156.881322)
			(xy 402.446076 -156.880889) (xy 402.427485 -156.873162) (xy 402.420074 -156.866336) (xy 402.338794 -156.785056)
			(xy 402.338286 -156.784548) (xy 402.330666 -156.777182) (xy 399.281142 -153.727658) (xy 399.273743 -153.720814)
			(xy 399.255144 -153.713092) (xy 399.245074 -153.712672) (xy 399.01114 -153.712672) (xy 399.001075 -153.712237)
			(xy 398.982489 -153.704504) (xy 398.975072 -153.697686) (xy 394.59408 -149.316948) (xy 394.587233 -149.309551)
			(xy 394.579505 -149.290951) (xy 394.579094 -149.28088) (xy 394.579094 -146.941286) (xy 394.578668 -146.931217)
			(xy 394.570949 -146.912617) (xy 394.564108 -146.905218) (xy 393.320524 -145.661634) (xy 393.313412 -145.654268)
			(xy 393.294616 -145.646648) (xy 390.944862 -145.646648) (xy 390.934796 -145.646216) (xy 390.916207 -145.638487)
			(xy 390.908794 -145.631662) (xy 388.645654 -143.368268) (xy 388.638807 -143.36087) (xy 388.631076 -143.342272)
			(xy 388.630668 -143.3322) (xy 388.630668 -135.901938) (xy 388.630233 -135.891873) (xy 388.622499 -135.873288)
			(xy 388.615682 -135.86587) (xy 387.074918 -134.325106) (xy 387.067806 -134.31774) (xy 387.04901 -134.31012)
			(xy 375.019824 -134.31012) (xy 375.009381 -134.31061) (xy 374.990226 -134.318925) (xy 374.976003 -134.334216)
			(xy 374.972072 -134.343902) (xy 374.940068 -134.434072) (xy 374.93712 -134.444039) (xy 374.9386 -134.464752)
			(xy 374.948136 -134.483199) (xy 374.955816 -134.490206) (xy 374.95607 -134.49046) (xy 374.977692 -134.508677)
			(xy 375.015841 -134.550405) (xy 375.04741 -134.597307) (xy 375.071708 -134.648357) (xy 375.088203 -134.702435)
			(xy 375.096532 -134.758355) (xy 375.09704 -134.786624) (xy 375.096554 -134.813893) (xy 375.088792 -134.867877)
			(xy 375.073427 -134.920207) (xy 375.05077 -134.969817) (xy 375.021284 -135.015698) (xy 374.985569 -135.056915)
			(xy 374.944352 -135.09263) (xy 374.898471 -135.122116) (xy 374.848861 -135.144773) (xy 374.796531 -135.160138)
			(xy 374.742547 -135.1679) (xy 374.688009 -135.1679) (xy 374.634025 -135.160138) (xy 374.581695 -135.144773)
			(xy 374.532085 -135.122116) (xy 374.486204 -135.09263) (xy 374.444987 -135.056915) (xy 374.409272 -135.015698)
			(xy 374.379786 -134.969817) (xy 374.357129 -134.920207) (xy 374.341764 -134.867877) (xy 374.334002 -134.813893)
			(xy 374.333516 -134.786624) (xy 374.334033 -134.758358) (xy 374.342383 -134.702446) (xy 374.358888 -134.648377)
			(xy 374.383188 -134.597334) (xy 374.414751 -134.550433) (xy 374.452887 -134.508701) (xy 374.474486 -134.49046)
			(xy 374.47474 -134.490206) (xy 374.482473 -134.483242) (xy 374.492029 -134.464778) (xy 374.49348 -134.444039)
			(xy 374.490488 -134.434072) (xy 374.458484 -134.343902) (xy 374.454499 -134.334255) (xy 374.440263 -134.319019)
			(xy 374.421155 -134.310671) (xy 374.410732 -134.31012) (xy 372.625874 -134.31012) (xy 372.615437 -134.310619)
			(xy 372.596299 -134.318945) (xy 372.582092 -134.334235) (xy 372.578122 -134.343902) (xy 372.546118 -134.434072)
			(xy 372.543172 -134.44404) (xy 372.544651 -134.464754) (xy 372.55418 -134.483206) (xy 372.561866 -134.490206)
			(xy 372.56212 -134.49046) (xy 372.58374 -134.508679) (xy 372.621883 -134.550408) (xy 372.653448 -134.597311)
			(xy 372.677743 -134.648361) (xy 372.694236 -134.702437) (xy 372.702564 -134.758356) (xy 372.70309 -134.786624)
			(xy 372.702604 -134.813893) (xy 372.694842 -134.867877) (xy 372.679477 -134.920207) (xy 372.65682 -134.969817)
			(xy 372.627334 -135.015698) (xy 372.591619 -135.056915) (xy 372.550402 -135.09263) (xy 372.504521 -135.122116)
			(xy 372.454911 -135.144773) (xy 372.402581 -135.160138) (xy 372.348597 -135.1679) (xy 372.294059 -135.1679)
			(xy 372.240075 -135.160138) (xy 372.187745 -135.144773) (xy 372.138135 -135.122116) (xy 372.092254 -135.09263)
			(xy 372.051037 -135.056915) (xy 372.015322 -135.015698) (xy 371.985836 -134.969817) (xy 371.963179 -134.920207)
			(xy 371.947814 -134.867877) (xy 371.940052 -134.813893) (xy 371.939566 -134.786624) (xy 371.940024 -134.760038)
			(xy 371.9474 -134.707381) (xy 371.962012 -134.656257) (xy 371.983579 -134.607656) (xy 372.011681 -134.562517)
			(xy 372.045776 -134.521716) (xy 372.085203 -134.486042) (xy 372.1292 -134.456184) (xy 372.176915 -134.432722)
			(xy 372.227424 -134.416108) (xy 372.25351 -134.410958) (xy 372.253764 -134.410958) (xy 372.248684 -134.356348)
			(xy 372.247391 -134.347013) (xy 372.23901 -134.330152) (xy 372.225105 -134.317457) (xy 372.207552 -134.310642)
			(xy 372.198138 -134.31012) (xy 372.132098 -134.31012) (xy 372.122111 -134.310658) (xy 372.103681 -134.318374)
			(xy 372.096284 -134.325106) (xy 370.653818 -135.767572) (xy 370.647017 -135.77492) (xy 370.639308 -135.793383)
			(xy 370.638832 -135.803386) (xy 370.638832 -136.519158) (xy 384.87426 -136.519158) (xy 384.878331 -136.463536)
			(xy 384.890457 -136.409099) (xy 384.91038 -136.357008) (xy 384.937676 -136.308373) (xy 384.971762 -136.26423)
			(xy 385.011911 -136.225521) (xy 385.057269 -136.19307) (xy 385.106869 -136.167569) (xy 385.159653 -136.149562)
			(xy 385.214496 -136.139432) (xy 385.27023 -136.137395) (xy 385.325667 -136.143495) (xy 385.379624 -136.157601)
			(xy 385.430953 -136.179413) (xy 385.478559 -136.208467) (xy 385.521427 -136.244142) (xy 385.558644 -136.285679)
			(xy 385.589417 -136.332192) (xy 385.613089 -136.382689) (xy 385.629157 -136.436096) (xy 385.637277 -136.491272)
			(xy 385.637786 -136.519158) (xy 385.637277 -136.547044) (xy 385.629157 -136.60222) (xy 385.613089 -136.655627)
			(xy 385.589417 -136.706124) (xy 385.558644 -136.752637) (xy 385.521427 -136.794174) (xy 385.478559 -136.829849)
			(xy 385.430953 -136.858903) (xy 385.379624 -136.880715) (xy 385.325667 -136.894821) (xy 385.27023 -136.900921)
			(xy 385.214496 -136.898884) (xy 385.159653 -136.888754) (xy 385.106869 -136.870747) (xy 385.057269 -136.845246)
			(xy 385.011911 -136.812795) (xy 384.971762 -136.774086) (xy 384.937676 -136.729943) (xy 384.91038 -136.681308)
			(xy 384.890457 -136.629217) (xy 384.878331 -136.57478) (xy 384.87426 -136.519158) (xy 370.638832 -136.519158)
			(xy 370.638832 -137.027412) (xy 373.67032 -137.027412) (xy 373.674391 -136.97179) (xy 373.686517 -136.917353)
			(xy 373.70644 -136.865262) (xy 373.733736 -136.816627) (xy 373.767822 -136.772484) (xy 373.807971 -136.733775)
			(xy 373.853329 -136.701324) (xy 373.902929 -136.675823) (xy 373.955713 -136.657816) (xy 374.010556 -136.647686)
			(xy 374.06629 -136.645649) (xy 374.121727 -136.651749) (xy 374.175684 -136.665855) (xy 374.227013 -136.687667)
			(xy 374.274619 -136.716721) (xy 374.317487 -136.752396) (xy 374.354704 -136.793933) (xy 374.385477 -136.840446)
			(xy 374.409149 -136.890943) (xy 374.425217 -136.94435) (xy 374.433337 -136.999526) (xy 374.433846 -137.027412)
			(xy 374.433337 -137.055298) (xy 374.42674 -137.100125) (xy 378.717621 -137.100125) (xy 378.717624 -137.045631)
			(xy 378.725382 -136.991692) (xy 378.740737 -136.939406) (xy 378.763377 -136.889837) (xy 378.79284 -136.843995)
			(xy 378.828528 -136.802812) (xy 378.869713 -136.767127) (xy 378.915557 -136.737666) (xy 378.965126 -136.715029)
			(xy 379.017413 -136.699677) (xy 379.071353 -136.691922) (xy 379.125847 -136.691922) (xy 379.179787 -136.699677)
			(xy 379.232074 -136.715029) (xy 379.281643 -136.737666) (xy 379.327487 -136.767127) (xy 379.368672 -136.802812)
			(xy 379.40436 -136.843995) (xy 379.433823 -136.889837) (xy 379.456463 -136.939406) (xy 379.471818 -136.991692)
			(xy 379.479576 -137.045631) (xy 379.480064 -137.072878) (xy 379.47975 -137.094988) (xy 379.474658 -137.138913)
			(xy 379.469904 -137.160508) (xy 379.466602 -137.17397) (xy 379.47473 -137.200386) (xy 379.560836 -137.278872)
			(xy 379.58776 -137.28446) (xy 379.600968 -137.280142) (xy 379.630296 -137.271031) (xy 379.690914 -137.261202)
			(xy 379.721618 -137.260584) (xy 379.748869 -137.261061) (xy 379.802817 -137.26882) (xy 379.855111 -137.284177)
			(xy 379.904688 -137.306819) (xy 379.950538 -137.336287) (xy 379.991728 -137.371979) (xy 380.027419 -137.41317)
			(xy 380.056885 -137.459021) (xy 380.079527 -137.508598) (xy 380.094882 -137.560893) (xy 380.10264 -137.614841)
			(xy 380.103126 -137.642092) (xy 380.103028 -137.652912) (xy 380.101757 -137.674515) (xy 380.100586 -137.685272)
			(xy 380.099316 -137.697718) (xy 380.108206 -137.720832) (xy 380.189486 -137.79246) (xy 380.213616 -137.798302)
			(xy 380.225808 -137.795254) (xy 380.24819 -137.79013) (xy 380.293781 -137.784658) (xy 380.31674 -137.784332)
			(xy 380.343987 -137.784821) (xy 380.397926 -137.792582) (xy 380.450211 -137.807939) (xy 380.499779 -137.830581)
			(xy 380.54562 -137.860047) (xy 380.586802 -137.895736) (xy 380.622485 -137.936922) (xy 380.651944 -137.982768)
			(xy 380.674579 -138.032339) (xy 380.68993 -138.084626) (xy 380.697683 -138.138566) (xy 380.697681 -138.19306)
			(xy 380.689924 -138.247) (xy 380.67457 -138.299286) (xy 380.651932 -138.348856) (xy 380.622469 -138.394699)
			(xy 380.586783 -138.435883) (xy 380.545599 -138.471569) (xy 380.499756 -138.501032) (xy 380.450186 -138.52367)
			(xy 380.3979 -138.539024) (xy 380.34396 -138.546781) (xy 380.289466 -138.546783) (xy 380.235526 -138.53903)
			(xy 380.183239 -138.523679) (xy 380.133668 -138.501044) (xy 380.087822 -138.471585) (xy 380.046636 -138.435902)
			(xy 380.010947 -138.39472) (xy 379.981481 -138.348879) (xy 379.958839 -138.299311) (xy 379.943482 -138.247026)
			(xy 379.935721 -138.193087) (xy 379.935232 -138.16584) (xy 379.935333 -138.15502) (xy 379.936601 -138.133417)
			(xy 379.937772 -138.12266) (xy 379.939042 -138.110214) (xy 379.930152 -138.0871) (xy 379.848872 -138.015472)
			(xy 379.824742 -138.00963) (xy 379.81255 -138.012678) (xy 379.790166 -138.017793) (xy 379.744577 -138.023271)
			(xy 379.721618 -138.0236) (xy 379.694365 -138.023128) (xy 379.640414 -138.015373) (xy 379.588116 -138.000019)
			(xy 379.538535 -137.977378) (xy 379.492682 -137.947911) (xy 379.451489 -137.912218) (xy 379.415795 -137.871026)
			(xy 379.386327 -137.825173) (xy 379.363684 -137.775593) (xy 379.348329 -137.723296) (xy 379.340573 -137.669345)
			(xy 379.34011 -137.642092) (xy 379.34042 -137.619982) (xy 379.345515 -137.576057) (xy 379.35027 -137.554462)
			(xy 379.353572 -137.541) (xy 379.345444 -137.514584) (xy 379.259338 -137.436098) (xy 379.232414 -137.43051)
			(xy 379.219206 -137.434828) (xy 379.189879 -137.443945) (xy 379.129261 -137.45377) (xy 379.098556 -137.454386)
			(xy 379.071309 -137.453875) (xy 379.01737 -137.446113) (xy 378.965085 -137.430755) (xy 378.915518 -137.408113)
			(xy 378.869677 -137.378647) (xy 378.828496 -137.342957) (xy 378.792814 -137.30177) (xy 378.763356 -137.255924)
			(xy 378.740722 -137.206353) (xy 378.725372 -137.154065) (xy 378.717621 -137.100125) (xy 374.42674 -137.100125)
			(xy 374.425217 -137.110474) (xy 374.409149 -137.163881) (xy 374.385477 -137.214378) (xy 374.354704 -137.260891)
			(xy 374.317487 -137.302428) (xy 374.274619 -137.338103) (xy 374.227013 -137.367157) (xy 374.175684 -137.388969)
			(xy 374.121727 -137.403075) (xy 374.06629 -137.409175) (xy 374.010556 -137.407138) (xy 373.955713 -137.397008)
			(xy 373.902929 -137.379001) (xy 373.853329 -137.3535) (xy 373.807971 -137.321049) (xy 373.767822 -137.28234)
			(xy 373.733736 -137.238197) (xy 373.70644 -137.189562) (xy 373.686517 -137.137471) (xy 373.674391 -137.083034)
			(xy 373.67032 -137.027412) (xy 370.638832 -137.027412) (xy 370.638832 -138.424158) (xy 371.38432 -138.424158)
			(xy 371.388391 -138.368536) (xy 371.400517 -138.314099) (xy 371.42044 -138.262008) (xy 371.447736 -138.213373)
			(xy 371.481822 -138.16923) (xy 371.521971 -138.130521) (xy 371.567329 -138.09807) (xy 371.616929 -138.072569)
			(xy 371.669713 -138.054562) (xy 371.724556 -138.044432) (xy 371.78029 -138.042395) (xy 371.835727 -138.048495)
			(xy 371.889684 -138.062601) (xy 371.941013 -138.084413) (xy 371.988619 -138.113467) (xy 372.031487 -138.149142)
			(xy 372.068704 -138.190679) (xy 372.073186 -138.197453) (xy 375.096236 -138.197453) (xy 375.096236 -138.142947)
			(xy 375.103993 -138.088995) (xy 375.119348 -138.036696) (xy 375.14199 -137.987115) (xy 375.171458 -137.941261)
			(xy 375.207151 -137.900066) (xy 375.248343 -137.864371) (xy 375.294196 -137.834901) (xy 375.343776 -137.812256)
			(xy 375.396073 -137.796897) (xy 375.450025 -137.789137) (xy 375.477278 -137.78865) (xy 375.504916 -137.78913)
			(xy 375.559612 -137.797126) (xy 375.612583 -137.812924) (xy 375.662724 -137.836194) (xy 375.708985 -137.866451)
			(xy 375.7504 -137.903061) (xy 375.786104 -137.94526) (xy 375.815351 -137.992166) (xy 375.837529 -138.042799)
			(xy 375.845324 -138.06932) (xy 375.848626 -138.081766) (xy 375.865898 -138.100054) (xy 375.970546 -138.134852)
			(xy 375.995184 -138.130534) (xy 376.005344 -138.12266) (xy 376.016336 -138.114309) (xy 376.039348 -138.099056)
			(xy 376.051318 -138.09218) (xy 376.059954 -138.087354) (xy 376.071892 -138.072622) (xy 376.098816 -137.988294)
			(xy 376.097546 -137.969498) (xy 376.093482 -137.960608) (xy 376.08218 -137.935237) (xy 376.066223 -137.88204)
			(xy 376.058166 -137.827088) (xy 376.057668 -137.799318) (xy 376.058195 -137.772068) (xy 376.065948 -137.718123)
			(xy 376.0813 -137.665831) (xy 376.103937 -137.616255) (xy 376.133399 -137.570406) (xy 376.169087 -137.529216)
			(xy 376.210272 -137.493525) (xy 376.256118 -137.464057) (xy 376.305691 -137.441415) (xy 376.357982 -137.426057)
			(xy 376.411926 -137.418298) (xy 376.439176 -137.41781) (xy 376.463206 -137.418166) (xy 376.510884 -137.424213)
			(xy 376.557425 -137.436202) (xy 376.579892 -137.444734) (xy 376.588528 -137.448036) (xy 376.60707 -137.448544)
			(xy 376.688096 -137.41908) (xy 376.702066 -137.407142) (xy 376.706638 -137.39876) (xy 376.721075 -137.373331)
			(xy 376.756523 -137.326828) (xy 376.798656 -137.286283) (xy 376.846485 -137.252645) (xy 376.898888 -137.226704)
			(xy 376.954638 -137.209068) (xy 377.012427 -137.20015) (xy 377.041664 -137.199624) (xy 377.068921 -137.20002)
			(xy 377.12288 -137.207774) (xy 377.175187 -137.223128) (xy 377.224776 -137.245771) (xy 377.270637 -137.27524)
			(xy 377.311838 -137.310937) (xy 377.347538 -137.352134) (xy 377.377012 -137.397993) (xy 377.399659 -137.447579)
			(xy 377.415018 -137.499885) (xy 377.422777 -137.553843) (xy 377.422777 -137.608357) (xy 377.415018 -137.662315)
			(xy 377.399659 -137.714621) (xy 377.377012 -137.764207) (xy 377.347538 -137.810066) (xy 377.314594 -137.848083)
			(xy 377.700412 -137.848083) (xy 377.708165 -137.794125) (xy 377.723517 -137.74182) (xy 377.746157 -137.692232)
			(xy 377.775624 -137.646371) (xy 377.811317 -137.605171) (xy 377.852511 -137.569469) (xy 377.898366 -137.539993)
			(xy 377.947949 -137.517344) (xy 378.000251 -137.501981) (xy 378.054207 -137.494218) (xy 378.108719 -137.494212)
			(xy 378.162676 -137.501965) (xy 378.214981 -137.517317) (xy 378.264569 -137.539958) (xy 378.31043 -137.569424)
			(xy 378.35163 -137.605118) (xy 378.387332 -137.646312) (xy 378.416807 -137.692167) (xy 378.439457 -137.74175)
			(xy 378.45482 -137.794052) (xy 378.462582 -137.848008) (xy 378.463048 -137.875264) (xy 378.463048 -137.884662)
			(xy 378.46254 -137.895584) (xy 378.471176 -137.91565) (xy 378.543058 -137.982452) (xy 378.563632 -137.98931)
			(xy 378.574554 -137.988294) (xy 378.612908 -137.986262) (xy 378.640161 -137.986764) (xy 378.694111 -137.994522)
			(xy 378.746408 -138.009879) (xy 378.795987 -138.032523) (xy 378.841839 -138.061992) (xy 378.88303 -138.097686)
			(xy 378.918722 -138.13888) (xy 378.948188 -138.184734) (xy 378.970829 -138.234314) (xy 378.986183 -138.286612)
			(xy 378.993938 -138.340563) (xy 378.993936 -138.395068) (xy 378.986176 -138.449018) (xy 378.970818 -138.501315)
			(xy 378.948174 -138.550893) (xy 378.918704 -138.596745) (xy 378.883008 -138.637935) (xy 378.841814 -138.673627)
			(xy 378.79596 -138.703092) (xy 378.746379 -138.725732) (xy 378.694081 -138.741084) (xy 378.64013 -138.748838)
			(xy 378.585625 -138.748835) (xy 378.531675 -138.741075) (xy 378.479378 -138.725716) (xy 378.4298 -138.70307)
			(xy 378.383949 -138.673599) (xy 378.342759 -138.637903) (xy 378.307069 -138.596708) (xy 378.277605 -138.550854)
			(xy 378.254966 -138.501272) (xy 378.239614 -138.448974) (xy 378.231861 -138.395023) (xy 378.2314 -138.36777)
			(xy 378.2314 -138.358372) (xy 378.231908 -138.34745) (xy 378.223272 -138.327384) (xy 378.15139 -138.260582)
			(xy 378.130816 -138.253724) (xy 378.119894 -138.25474) (xy 378.08154 -138.256772) (xy 378.054284 -138.256388)
			(xy 378.000327 -138.248636) (xy 377.948021 -138.233283) (xy 377.898434 -138.210644) (xy 377.852573 -138.181177)
			(xy 377.811372 -138.145484) (xy 377.77567 -138.104291) (xy 377.746194 -138.058436) (xy 377.723544 -138.008852)
			(xy 377.708181 -137.95655) (xy 377.700418 -137.902594) (xy 377.700412 -137.848083) (xy 377.314594 -137.848083)
			(xy 377.311838 -137.851263) (xy 377.270637 -137.88696) (xy 377.224776 -137.916429) (xy 377.175187 -137.939072)
			(xy 377.12288 -137.954426) (xy 377.068921 -137.96218) (xy 377.041664 -137.96264) (xy 377.017634 -137.962275)
			(xy 376.969956 -137.956232) (xy 376.923416 -137.944246) (xy 376.900948 -137.935716) (xy 376.892312 -137.932414)
			(xy 376.87377 -137.931906) (xy 376.792744 -137.96137) (xy 376.778774 -137.973308) (xy 376.774202 -137.98169)
			(xy 376.761122 -138.004831) (xy 376.729486 -138.047549) (xy 376.692218 -138.085453) (xy 376.650041 -138.117807)
			(xy 376.627136 -138.131296) (xy 376.6185 -138.136122) (xy 376.606562 -138.150854) (xy 376.579638 -138.235182)
			(xy 376.580908 -138.253978) (xy 376.584972 -138.262868) (xy 376.596264 -138.288243) (xy 376.612225 -138.341439)
			(xy 376.620286 -138.396389) (xy 376.620786 -138.424158) (xy 376.620306 -138.451411) (xy 376.612554 -138.505362)
			(xy 376.597202 -138.557661) (xy 376.574563 -138.607243) (xy 376.545097 -138.653097) (xy 376.509405 -138.694291)
			(xy 376.468213 -138.729985) (xy 376.42236 -138.759453) (xy 376.37278 -138.782095) (xy 376.320482 -138.797449)
			(xy 376.266531 -138.805204) (xy 376.239278 -138.805666) (xy 376.211639 -138.805214) (xy 376.156943 -138.797212)
			(xy 376.103971 -138.781409) (xy 376.053831 -138.758135) (xy 376.007571 -138.727875) (xy 375.966156 -138.691261)
			(xy 375.930452 -138.64906) (xy 375.901206 -138.602152) (xy 375.879027 -138.551518) (xy 375.871232 -138.524996)
			(xy 375.86793 -138.51255) (xy 375.850658 -138.494262) (xy 375.74601 -138.459464) (xy 375.721372 -138.463782)
			(xy 375.711212 -138.471656) (xy 375.691054 -138.486766) (xy 375.647534 -138.512142) (xy 375.60105 -138.531561)
			(xy 375.552411 -138.544683) (xy 375.502467 -138.551281) (xy 375.477278 -138.551666) (xy 375.450025 -138.551263)
			(xy 375.396073 -138.543503) (xy 375.343776 -138.528144) (xy 375.294196 -138.505499) (xy 375.248343 -138.476029)
			(xy 375.207151 -138.440334) (xy 375.171458 -138.399139) (xy 375.14199 -138.353285) (xy 375.119348 -138.303704)
			(xy 375.103993 -138.251405) (xy 375.096236 -138.197453) (xy 372.073186 -138.197453) (xy 372.099477 -138.237192)
			(xy 372.123149 -138.287689) (xy 372.139217 -138.341096) (xy 372.147337 -138.396272) (xy 372.147846 -138.424158)
			(xy 372.147337 -138.452044) (xy 372.139217 -138.50722) (xy 372.123149 -138.560627) (xy 372.099477 -138.611124)
			(xy 372.068704 -138.657637) (xy 372.031487 -138.699174) (xy 371.988619 -138.734849) (xy 371.941013 -138.763903)
			(xy 371.889684 -138.785715) (xy 371.835727 -138.799821) (xy 371.78029 -138.805921) (xy 371.724556 -138.803884)
			(xy 371.669713 -138.793754) (xy 371.616929 -138.775747) (xy 371.567329 -138.750246) (xy 371.521971 -138.717795)
			(xy 371.481822 -138.679086) (xy 371.447736 -138.634943) (xy 371.42044 -138.586308) (xy 371.400517 -138.534217)
			(xy 371.388391 -138.47978) (xy 371.38432 -138.424158) (xy 370.638832 -138.424158) (xy 370.638832 -139.178792)
			(xy 373.863614 -139.178792) (xy 373.867685 -139.12317) (xy 373.879811 -139.068733) (xy 373.899734 -139.016642)
			(xy 373.92703 -138.968007) (xy 373.961116 -138.923864) (xy 374.001265 -138.885155) (xy 374.046623 -138.852704)
			(xy 374.096223 -138.827203) (xy 374.149007 -138.809196) (xy 374.20385 -138.799066) (xy 374.259584 -138.797029)
			(xy 374.315021 -138.803129) (xy 374.368978 -138.817235) (xy 374.420307 -138.839047) (xy 374.467913 -138.868101)
			(xy 374.510781 -138.903776) (xy 374.547998 -138.945313) (xy 374.578771 -138.991826) (xy 374.602443 -139.042323)
			(xy 374.618511 -139.09573) (xy 374.622511 -139.122912) (xy 375.06732 -139.122912) (xy 375.071391 -139.06729)
			(xy 375.083517 -139.012853) (xy 375.10344 -138.960762) (xy 375.130736 -138.912127) (xy 375.164822 -138.867984)
			(xy 375.204971 -138.829275) (xy 375.250329 -138.796824) (xy 375.299929 -138.771323) (xy 375.352713 -138.753316)
			(xy 375.407556 -138.743186) (xy 375.46329 -138.741149) (xy 375.518727 -138.747249) (xy 375.572684 -138.761355)
			(xy 375.624013 -138.783167) (xy 375.671619 -138.812221) (xy 375.714487 -138.847896) (xy 375.751704 -138.889433)
			(xy 375.782477 -138.935946) (xy 375.806149 -138.986443) (xy 375.822217 -139.03985) (xy 375.830337 -139.095026)
			(xy 375.830846 -139.122912) (xy 375.830337 -139.150798) (xy 375.822217 -139.205974) (xy 375.806149 -139.259381)
			(xy 375.782477 -139.309878) (xy 375.751704 -139.356391) (xy 375.714487 -139.397928) (xy 375.671619 -139.433603)
			(xy 375.624013 -139.462657) (xy 375.572684 -139.484469) (xy 375.518727 -139.498575) (xy 375.46329 -139.504675)
			(xy 375.407556 -139.502638) (xy 375.352713 -139.492508) (xy 375.299929 -139.474501) (xy 375.250329 -139.449)
			(xy 375.204971 -139.416549) (xy 375.164822 -139.37784) (xy 375.130736 -139.333697) (xy 375.10344 -139.285062)
			(xy 375.083517 -139.232971) (xy 375.071391 -139.178534) (xy 375.06732 -139.122912) (xy 374.622511 -139.122912)
			(xy 374.626631 -139.150906) (xy 374.62714 -139.178792) (xy 374.626631 -139.206678) (xy 374.618511 -139.261854)
			(xy 374.602443 -139.315261) (xy 374.578771 -139.365758) (xy 374.547998 -139.412271) (xy 374.510781 -139.453808)
			(xy 374.467913 -139.489483) (xy 374.420307 -139.518537) (xy 374.368978 -139.540349) (xy 374.315021 -139.554455)
			(xy 374.259584 -139.560555) (xy 374.20385 -139.558518) (xy 374.149007 -139.548388) (xy 374.096223 -139.530381)
			(xy 374.046623 -139.50488) (xy 374.001265 -139.472429) (xy 373.961116 -139.43372) (xy 373.92703 -139.389577)
			(xy 373.899734 -139.340942) (xy 373.879811 -139.288851) (xy 373.867685 -139.234414) (xy 373.863614 -139.178792)
			(xy 370.638832 -139.178792) (xy 370.638832 -139.676632) (xy 370.639376 -139.686616) (xy 370.647101 -139.705037)
			(xy 370.653818 -139.712446) (xy 370.956586 -140.015214) (xy 373.57126 -140.015214) (xy 373.575331 -139.959592)
			(xy 373.587457 -139.905155) (xy 373.60738 -139.853064) (xy 373.634676 -139.804429) (xy 373.668762 -139.760286)
			(xy 373.708911 -139.721577) (xy 373.754269 -139.689126) (xy 373.803869 -139.663625) (xy 373.856653 -139.645618)
			(xy 373.911496 -139.635488) (xy 373.96723 -139.633451) (xy 374.022667 -139.639551) (xy 374.076624 -139.653657)
			(xy 374.127953 -139.675469) (xy 374.175559 -139.704523) (xy 374.218427 -139.740198) (xy 374.255644 -139.781735)
			(xy 374.286417 -139.828248) (xy 374.310089 -139.878745) (xy 374.326157 -139.932152) (xy 374.334277 -139.987328)
			(xy 374.334786 -140.015214) (xy 374.334277 -140.0431) (xy 374.326157 -140.098276) (xy 374.310089 -140.151683)
			(xy 374.286417 -140.20218) (xy 374.255644 -140.248693) (xy 374.218427 -140.29023) (xy 374.175559 -140.325905)
			(xy 374.127953 -140.354959) (xy 374.076624 -140.376771) (xy 374.022667 -140.390877) (xy 373.96723 -140.396977)
			(xy 373.911496 -140.39494) (xy 373.856653 -140.38481) (xy 373.803869 -140.366803) (xy 373.754269 -140.341302)
			(xy 373.708911 -140.308851) (xy 373.668762 -140.270142) (xy 373.634676 -140.225999) (xy 373.60738 -140.177364)
			(xy 373.587457 -140.125273) (xy 373.575331 -140.070836) (xy 373.57126 -140.015214) (xy 370.956586 -140.015214)
			(xy 371.534944 -140.593572) (xy 371.547644 -140.60043) (xy 371.55501 -140.601954) (xy 371.583066 -140.608573)
			(xy 371.636926 -140.629113) (xy 371.687087 -140.657513) (xy 371.732411 -140.693129) (xy 371.771867 -140.735151)
			(xy 371.80456 -140.782626) (xy 371.829748 -140.834475) (xy 371.846857 -140.889521) (xy 371.8555 -140.946512)
			(xy 371.856 -140.975334) (xy 371.855443 -141.004709) (xy 371.846385 -141.062756) (xy 371.837966 -141.090904)
			(xy 371.834926 -141.102405) (xy 371.838622 -141.125872) (xy 371.845078 -141.135862) (xy 371.890798 -141.19987)
			(xy 371.896183 -141.20681) (xy 371.910607 -141.216811) (xy 371.918992 -141.219428) (xy 371.931946 -141.222984)
			(xy 371.937534 -141.223238) (xy 371.964019 -141.224803) (xy 372.016207 -141.234345) (xy 372.066569 -141.251028)
			(xy 372.114133 -141.27453) (xy 372.157981 -141.304397) (xy 372.197265 -141.340054) (xy 372.231229 -141.380811)
			(xy 372.259216 -141.425882) (xy 372.280686 -141.474397) (xy 372.295225 -141.52542) (xy 372.302551 -141.577965)
			(xy 372.30304 -141.604492) (xy 372.302554 -141.631761) (xy 372.294792 -141.685745) (xy 372.279427 -141.738075)
			(xy 372.25677 -141.787685) (xy 372.227284 -141.833566) (xy 372.191569 -141.874783) (xy 372.150352 -141.910498)
			(xy 372.104471 -141.939984) (xy 372.054861 -141.962641) (xy 372.002531 -141.978006) (xy 371.948547 -141.985768)
			(xy 371.894009 -141.985768) (xy 371.840025 -141.978006) (xy 371.787695 -141.962641) (xy 371.738085 -141.939984)
			(xy 371.692204 -141.910498) (xy 371.650987 -141.874783) (xy 371.615272 -141.833566) (xy 371.585786 -141.787685)
			(xy 371.563129 -141.738075) (xy 371.547764 -141.685745) (xy 371.540002 -141.631761) (xy 371.539516 -141.604492)
			(xy 371.539516 -141.60373) (xy 371.540139 -141.574423) (xy 371.549193 -141.516511) (xy 371.55755 -141.488414)
			(xy 371.55882 -141.48054) (xy 371.559894 -141.470884) (xy 371.555575 -141.451957) (xy 371.550438 -141.44371)
			(xy 371.54993 -141.442948) (xy 371.504718 -141.379956) (xy 371.499336 -141.373012) (xy 371.484914 -141.363002)
			(xy 371.476524 -141.360398) (xy 371.46357 -141.356842) (xy 371.457982 -141.356588) (xy 371.430136 -141.354883)
			(xy 371.375343 -141.344405) (xy 371.322656 -141.326069) (xy 371.273196 -141.300266) (xy 371.228015 -141.267544)
			(xy 371.188073 -141.228598) (xy 371.15422 -141.184258) (xy 371.127176 -141.135465) (xy 371.107515 -141.083259)
			(xy 371.101112 -141.056106) (xy 371.099588 -141.048994) (xy 371.092476 -141.03604) (xy 370.104924 -140.048488)
			(xy 370.098828 -140.042138) (xy 370.09832 -140.04163) (xy 370.02847 -139.971526) (xy 370.021664 -139.96418)
			(xy 370.013947 -139.945717) (xy 370.013484 -139.935712) (xy 370.013484 -139.835636) (xy 370.013484 -136.12495)
			(xy 370.01323 -136.121394) (xy 370.011658 -136.106937) (xy 370.001468 -136.079716) (xy 369.984028 -136.056463)
			(xy 369.960749 -136.039059) (xy 369.933513 -136.02891) (xy 369.904521 -136.026836) (xy 369.876117 -136.033007)
			(xy 369.850599 -136.046922) (xy 369.840002 -136.056878) (xy 369.31346 -136.583166) (xy 369.306681 -136.590591)
			(xy 369.299082 -136.609187) (xy 369.298728 -136.619234) (xy 369.298728 -136.740392) (xy 369.298181 -136.768969)
			(xy 369.289208 -136.825414) (xy 369.271513 -136.87976) (xy 369.245531 -136.930667) (xy 369.211904 -136.976881)
			(xy 369.192048 -136.99744) (xy 366.369092 -139.820396) (xy 366.3485 -139.840212) (xy 366.302286 -139.873824)
			(xy 366.251385 -139.899798) (xy 366.19705 -139.917496) (xy 366.140616 -139.926482) (xy 366.112044 -139.927076)
			(xy 365.708184 -139.927076) (xy 365.698217 -139.927552) (xy 365.679778 -139.935125) (xy 365.67237 -139.941808)
			(xy 363.238288 -142.37589) (xy 365.645444 -142.37589) (xy 365.649515 -142.320268) (xy 365.661641 -142.265831)
			(xy 365.681564 -142.21374) (xy 365.70886 -142.165105) (xy 365.742946 -142.120962) (xy 365.783095 -142.082253)
			(xy 365.828453 -142.049802) (xy 365.878053 -142.024301) (xy 365.930837 -142.006294) (xy 365.98568 -141.996164)
			(xy 366.041414 -141.994127) (xy 366.096851 -142.000227) (xy 366.150808 -142.014333) (xy 366.202137 -142.036145)
			(xy 366.249743 -142.065199) (xy 366.292611 -142.100874) (xy 366.329828 -142.142411) (xy 366.360601 -142.188924)
			(xy 366.384273 -142.239421) (xy 366.400341 -142.292828) (xy 366.408461 -142.348004) (xy 366.40897 -142.37589)
			(xy 366.408461 -142.403776) (xy 366.400341 -142.458952) (xy 366.391554 -142.488158) (xy 371.53926 -142.488158)
			(xy 371.543331 -142.432536) (xy 371.555457 -142.378099) (xy 371.57538 -142.326008) (xy 371.602676 -142.277373)
			(xy 371.636762 -142.23323) (xy 371.676911 -142.194521) (xy 371.722269 -142.16207) (xy 371.771869 -142.136569)
			(xy 371.824653 -142.118562) (xy 371.879496 -142.108432) (xy 371.93523 -142.106395) (xy 371.990667 -142.112495)
			(xy 372.044624 -142.126601) (xy 372.095953 -142.148413) (xy 372.143559 -142.177467) (xy 372.186427 -142.213142)
			(xy 372.223644 -142.254679) (xy 372.254417 -142.301192) (xy 372.278089 -142.351689) (xy 372.294157 -142.405096)
			(xy 372.302277 -142.460272) (xy 372.302786 -142.488158) (xy 372.302277 -142.516044) (xy 372.295653 -142.561056)
			(xy 373.69877 -142.561056) (xy 373.699236 -142.534988) (xy 373.706348 -142.483339) (xy 373.72042 -142.433137)
			(xy 373.74119 -142.385316) (xy 373.768273 -142.340766) (xy 373.801165 -142.300314) (xy 373.839253 -142.264712)
			(xy 373.881831 -142.234623) (xy 373.904764 -142.22222) (xy 373.915178 -142.216886) (xy 373.928894 -142.199106)
			(xy 373.949722 -142.099284) (xy 373.944388 -142.077186) (xy 373.937276 -142.068296) (xy 373.921311 -142.047845)
			(xy 373.894452 -142.003457) (xy 373.87386 -141.955836) (xy 373.859917 -141.905863) (xy 373.852878 -141.854461)
			(xy 373.85244 -141.82852) (xy 373.852894 -141.800916) (xy 373.860837 -141.746283) (xy 373.876574 -141.693366)
			(xy 373.899777 -141.643271) (xy 373.929959 -141.597044) (xy 373.966492 -141.555653) (xy 374.008611 -141.519962)
			(xy 374.031764 -141.504924) (xy 374.042686 -141.498066) (xy 374.055386 -141.475968) (xy 374.05818 -141.365732)
			(xy 374.04675 -141.342872) (xy 374.036082 -141.335506) (xy 374.014869 -141.320146) (xy 373.976466 -141.284535)
			(xy 373.943296 -141.244005) (xy 373.91598 -141.199319) (xy 373.895034 -141.151317) (xy 373.88085 -141.100901)
			(xy 373.873696 -141.049019) (xy 373.873268 -141.022832) (xy 373.873754 -140.995581) (xy 373.88151 -140.941633)
			(xy 373.896865 -140.889338) (xy 373.919507 -140.839761) (xy 373.948973 -140.793911) (xy 373.984664 -140.75272)
			(xy 374.025855 -140.717029) (xy 374.071705 -140.687563) (xy 374.121282 -140.664921) (xy 374.173577 -140.649566)
			(xy 374.227525 -140.64181) (xy 374.282027 -140.64181) (xy 374.335975 -140.649566) (xy 374.38827 -140.664921)
			(xy 374.437847 -140.687563) (xy 374.483697 -140.717029) (xy 374.524888 -140.75272) (xy 374.560579 -140.793911)
			(xy 374.590045 -140.839761) (xy 374.612687 -140.889338) (xy 374.628042 -140.941633) (xy 374.635798 -140.995581)
			(xy 374.636284 -141.022832) (xy 374.635828 -141.050436) (xy 374.62789 -141.105071) (xy 374.612156 -141.15799)
			(xy 374.588955 -141.208086) (xy 374.558771 -141.254313) (xy 374.522237 -141.295703) (xy 374.480115 -141.331392)
			(xy 374.45696 -141.346428) (xy 374.446038 -141.353286) (xy 374.433338 -141.375384) (xy 374.430544 -141.48562)
			(xy 374.441974 -141.50848) (xy 374.452642 -141.515846) (xy 374.473838 -141.531228) (xy 374.51224 -141.566837)
			(xy 374.545411 -141.607363) (xy 374.572728 -141.652045) (xy 374.593677 -141.700043) (xy 374.607865 -141.750456)
			(xy 374.615025 -141.802335) (xy 374.615456 -141.82852) (xy 374.61501 -141.854589) (xy 374.6079 -141.906241)
			(xy 374.593828 -141.956445) (xy 374.573056 -142.004267) (xy 374.54597 -142.048819) (xy 374.513074 -142.089271)
			(xy 374.474981 -142.12487) (xy 374.432398 -142.154956) (xy 374.409462 -142.167356) (xy 374.399048 -142.17269)
			(xy 374.385332 -142.19047) (xy 374.364504 -142.290292) (xy 374.369838 -142.31239) (xy 374.37695 -142.32128)
			(xy 374.392908 -142.341737) (xy 374.419767 -142.386124) (xy 374.44036 -142.433743) (xy 374.454305 -142.483714)
			(xy 374.461346 -142.535116) (xy 374.461786 -142.561056) (xy 374.4613 -142.588307) (xy 374.453544 -142.642255)
			(xy 374.438189 -142.69455) (xy 374.415547 -142.744127) (xy 374.386081 -142.789977) (xy 374.35039 -142.831168)
			(xy 374.309199 -142.866859) (xy 374.263349 -142.896325) (xy 374.213772 -142.918967) (xy 374.161477 -142.934322)
			(xy 374.107529 -142.942078) (xy 374.053027 -142.942078) (xy 373.999079 -142.934322) (xy 373.946784 -142.918967)
			(xy 373.897207 -142.896325) (xy 373.851357 -142.866859) (xy 373.810166 -142.831168) (xy 373.774475 -142.789977)
			(xy 373.745009 -142.744127) (xy 373.722367 -142.69455) (xy 373.707012 -142.642255) (xy 373.699256 -142.588307)
			(xy 373.69877 -142.561056) (xy 372.295653 -142.561056) (xy 372.294157 -142.57122) (xy 372.278089 -142.624627)
			(xy 372.254417 -142.675124) (xy 372.223644 -142.721637) (xy 372.186427 -142.763174) (xy 372.143559 -142.798849)
			(xy 372.095953 -142.827903) (xy 372.044624 -142.849715) (xy 371.990667 -142.863821) (xy 371.93523 -142.869921)
			(xy 371.879496 -142.867884) (xy 371.824653 -142.857754) (xy 371.771869 -142.839747) (xy 371.722269 -142.814246)
			(xy 371.676911 -142.781795) (xy 371.636762 -142.743086) (xy 371.602676 -142.698943) (xy 371.57538 -142.650308)
			(xy 371.555457 -142.598217) (xy 371.543331 -142.54378) (xy 371.53926 -142.488158) (xy 366.391554 -142.488158)
			(xy 366.384273 -142.512359) (xy 366.360601 -142.562856) (xy 366.329828 -142.609369) (xy 366.292611 -142.650906)
			(xy 366.249743 -142.686581) (xy 366.202137 -142.715635) (xy 366.150808 -142.737447) (xy 366.096851 -142.751553)
			(xy 366.041414 -142.757653) (xy 365.98568 -142.755616) (xy 365.930837 -142.745486) (xy 365.878053 -142.727479)
			(xy 365.828453 -142.701978) (xy 365.783095 -142.669527) (xy 365.742946 -142.630818) (xy 365.70886 -142.586675)
			(xy 365.681564 -142.53804) (xy 365.661641 -142.485949) (xy 365.649515 -142.431512) (xy 365.645444 -142.37589)
			(xy 363.238288 -142.37589) (xy 362.11002 -143.504158) (xy 373.57126 -143.504158) (xy 373.575331 -143.448536)
			(xy 373.587457 -143.394099) (xy 373.60738 -143.342008) (xy 373.634676 -143.293373) (xy 373.668762 -143.24923)
			(xy 373.708911 -143.210521) (xy 373.754269 -143.17807) (xy 373.803869 -143.152569) (xy 373.856653 -143.134562)
			(xy 373.911496 -143.124432) (xy 373.96723 -143.122395) (xy 374.022667 -143.128495) (xy 374.076624 -143.142601)
			(xy 374.127953 -143.164413) (xy 374.175559 -143.193467) (xy 374.218427 -143.229142) (xy 374.255644 -143.270679)
			(xy 374.286417 -143.317192) (xy 374.310089 -143.367689) (xy 374.326157 -143.421096) (xy 374.334277 -143.476272)
			(xy 374.334786 -143.504158) (xy 374.334277 -143.532044) (xy 374.326157 -143.58722) (xy 374.310089 -143.640627)
			(xy 374.286417 -143.691124) (xy 374.255644 -143.737637) (xy 374.218427 -143.779174) (xy 374.175559 -143.814849)
			(xy 374.127953 -143.843903) (xy 374.076624 -143.865715) (xy 374.022667 -143.879821) (xy 373.96723 -143.885921)
			(xy 373.911496 -143.883884) (xy 373.856653 -143.873754) (xy 373.803869 -143.855747) (xy 373.754269 -143.830246)
			(xy 373.708911 -143.797795) (xy 373.668762 -143.759086) (xy 373.634676 -143.714943) (xy 373.60738 -143.666308)
			(xy 373.587457 -143.614217) (xy 373.575331 -143.55978) (xy 373.57126 -143.504158) (xy 362.11002 -143.504158)
			(xy 361.09402 -144.520158) (xy 371.53926 -144.520158) (xy 371.543331 -144.464536) (xy 371.555457 -144.410099)
			(xy 371.57538 -144.358008) (xy 371.602676 -144.309373) (xy 371.636762 -144.26523) (xy 371.676911 -144.226521)
			(xy 371.722269 -144.19407) (xy 371.771869 -144.168569) (xy 371.824653 -144.150562) (xy 371.879496 -144.140432)
			(xy 371.93523 -144.138395) (xy 371.990667 -144.144495) (xy 372.044624 -144.158601) (xy 372.095953 -144.180413)
			(xy 372.143559 -144.209467) (xy 372.186427 -144.245142) (xy 372.223644 -144.286679) (xy 372.254417 -144.333192)
			(xy 372.278089 -144.383689) (xy 372.294157 -144.437096) (xy 372.302277 -144.492272) (xy 372.302786 -144.520158)
			(xy 372.302277 -144.548044) (xy 372.294157 -144.60322) (xy 372.278089 -144.656627) (xy 372.254417 -144.707124)
			(xy 372.223644 -144.753637) (xy 372.186427 -144.795174) (xy 372.143559 -144.830849) (xy 372.095953 -144.859903)
			(xy 372.044624 -144.881715) (xy 371.990667 -144.895821) (xy 371.93523 -144.901921) (xy 371.879496 -144.899884)
			(xy 371.824653 -144.889754) (xy 371.771869 -144.871747) (xy 371.722269 -144.846246) (xy 371.676911 -144.813795)
			(xy 371.636762 -144.775086) (xy 371.602676 -144.730943) (xy 371.57538 -144.682308) (xy 371.555457 -144.630217)
			(xy 371.543331 -144.57578) (xy 371.53926 -144.520158) (xy 361.09402 -144.520158) (xy 360.07802 -145.536158)
			(xy 371.53926 -145.536158) (xy 371.543331 -145.480536) (xy 371.555457 -145.426099) (xy 371.57538 -145.374008)
			(xy 371.602676 -145.325373) (xy 371.636762 -145.28123) (xy 371.676911 -145.242521) (xy 371.722269 -145.21007)
			(xy 371.771869 -145.184569) (xy 371.824653 -145.166562) (xy 371.879496 -145.156432) (xy 371.93523 -145.154395)
			(xy 371.990667 -145.160495) (xy 372.044624 -145.174601) (xy 372.095953 -145.196413) (xy 372.143559 -145.225467)
			(xy 372.186427 -145.261142) (xy 372.223644 -145.302679) (xy 372.254417 -145.349192) (xy 372.278089 -145.399689)
			(xy 372.294157 -145.453096) (xy 372.302277 -145.508272) (xy 372.302786 -145.536158) (xy 372.302277 -145.564044)
			(xy 372.294157 -145.61922) (xy 372.278089 -145.672627) (xy 372.254417 -145.723124) (xy 372.223644 -145.769637)
			(xy 372.186427 -145.811174) (xy 372.143559 -145.846849) (xy 372.095953 -145.875903) (xy 372.044624 -145.897715)
			(xy 371.990667 -145.911821) (xy 371.93523 -145.917921) (xy 371.879496 -145.915884) (xy 371.824653 -145.905754)
			(xy 371.771869 -145.887747) (xy 371.722269 -145.862246) (xy 371.676911 -145.829795) (xy 371.636762 -145.791086)
			(xy 371.602676 -145.746943) (xy 371.57538 -145.698308) (xy 371.555457 -145.646217) (xy 371.543331 -145.59178)
			(xy 371.53926 -145.536158) (xy 360.07802 -145.536158) (xy 359.25633 -146.357848) (xy 359.24892 -146.364532)
			(xy 359.230484 -146.372117) (xy 359.220516 -146.37258) (xy 357.457502 -146.37258) (xy 357.452334 -146.372393)
			(xy 357.442225 -146.370215) (xy 357.437436 -146.368262) (xy 357.432864 -146.36623) (xy 357.412036 -146.352768)
			(xy 357.39705 -146.342862) (xy 357.361236 -146.346672) (xy 357.212138 -146.49577) (xy 365.860074 -146.49577)
			(xy 365.864145 -146.440148) (xy 365.876271 -146.385711) (xy 365.896194 -146.33362) (xy 365.92349 -146.284985)
			(xy 365.957576 -146.240842) (xy 365.997725 -146.202133) (xy 366.043083 -146.169682) (xy 366.092683 -146.144181)
			(xy 366.145467 -146.126174) (xy 366.20031 -146.116044) (xy 366.256044 -146.114007) (xy 366.311481 -146.120107)
			(xy 366.365438 -146.134213) (xy 366.416767 -146.156025) (xy 366.464373 -146.185079) (xy 366.507241 -146.220754)
			(xy 366.544458 -146.262291) (xy 366.575231 -146.308804) (xy 366.598903 -146.359301) (xy 366.614971 -146.412708)
			(xy 366.623091 -146.467884) (xy 366.6236 -146.49577) (xy 366.623091 -146.523656) (xy 366.614971 -146.578832)
			(xy 366.598903 -146.632239) (xy 366.575231 -146.682736) (xy 366.544458 -146.729249) (xy 366.507241 -146.770786)
			(xy 366.464373 -146.806461) (xy 366.416767 -146.835515) (xy 366.365438 -146.857327) (xy 366.311481 -146.871433)
			(xy 366.256044 -146.877533) (xy 366.20031 -146.875496) (xy 366.145467 -146.865366) (xy 366.092683 -146.847359)
			(xy 366.043083 -146.821858) (xy 365.997725 -146.789407) (xy 365.957576 -146.750698) (xy 365.92349 -146.706555)
			(xy 365.896194 -146.65792) (xy 365.876271 -146.605829) (xy 365.864145 -146.551392) (xy 365.860074 -146.49577)
			(xy 357.212138 -146.49577) (xy 348.35465 -155.353258) (xy 348.347251 -155.360101) (xy 348.328652 -155.367824)
			(xy 348.318582 -155.368244) (xy 341.085678 -155.368244) (xy 341.066882 -155.375864) (xy 341.05977 -155.38323)
			(xy 339.643466 -156.799534) (xy 347.421454 -156.799534) (xy 347.42194 -156.772283) (xy 347.429696 -156.718335)
			(xy 347.445051 -156.66604) (xy 347.467693 -156.616463) (xy 347.497159 -156.570613) (xy 347.53285 -156.529422)
			(xy 347.574041 -156.493731) (xy 347.619891 -156.464265) (xy 347.669468 -156.441623) (xy 347.721763 -156.426268)
			(xy 347.775711 -156.418512) (xy 347.830213 -156.418512) (xy 347.884161 -156.426268) (xy 347.936456 -156.441623)
			(xy 347.986033 -156.464265) (xy 348.031883 -156.493731) (xy 348.073074 -156.529422) (xy 348.108765 -156.570613)
			(xy 348.138231 -156.616463) (xy 348.160873 -156.66604) (xy 348.165539 -156.681932) (xy 349.311722 -156.681932)
			(xy 349.312245 -156.654077) (xy 349.320329 -156.598958) (xy 349.336345 -156.545601) (xy 349.359953 -156.495141)
			(xy 349.390649 -156.448652) (xy 349.427781 -156.407122) (xy 349.470558 -156.371436) (xy 349.518072 -156.342351)
			(xy 349.569312 -156.320487) (xy 349.623186 -156.306309) (xy 349.650812 -156.30271) (xy 349.670116 -156.300678)
			(xy 349.696024 -156.271722) (xy 349.696024 -154.552142) (xy 349.696626 -154.527158) (xy 349.706374 -154.47815)
			(xy 349.725484 -154.431981) (xy 349.753224 -154.39042) (xy 349.770446 -154.37231) (xy 355.929438 -148.213318)
			(xy 355.947556 -148.196106) (xy 355.989114 -148.168364) (xy 356.035281 -148.149254) (xy 356.084287 -148.13951)
			(xy 356.10927 -148.138896) (xy 371.957346 -148.138896) (xy 371.967416 -148.13847) (xy 371.986015 -148.130753)
			(xy 371.993414 -148.12391) (xy 371.994176 -148.123148) (xy 372.000954 -148.115754) (xy 372.008603 -148.097229)
			(xy 372.008567 -148.077187) (xy 372.005098 -148.067776) (xy 371.963188 -147.966684) (xy 371.937534 -147.949666)
			(xy 371.92204 -147.949666) (xy 371.894749 -147.949317) (xy 371.840711 -147.941644) (xy 371.788318 -147.926349)
			(xy 371.738639 -147.903744) (xy 371.692689 -147.874291) (xy 371.651404 -147.83859) (xy 371.615628 -147.797371)
			(xy 371.58609 -147.751474) (xy 371.563395 -147.701837) (xy 371.548004 -147.649472) (xy 371.540232 -147.595448)
			(xy 371.53977 -147.568158) (xy 371.540239 -147.540907) (xy 371.548 -147.48696) (xy 371.56336 -147.434666)
			(xy 371.586004 -147.38509) (xy 371.615473 -147.339241) (xy 371.651166 -147.298052) (xy 371.692357 -147.262361)
			(xy 371.738207 -147.232894) (xy 371.787785 -147.210253) (xy 371.840079 -147.194896) (xy 371.894027 -147.187137)
			(xy 371.921278 -147.18665) (xy 371.948002 -147.18711) (xy 372.000928 -147.194559) (xy 372.052299 -147.209314)
			(xy 372.101111 -147.231086) (xy 372.146411 -147.259452) (xy 372.16715 -147.276312) (xy 372.17858 -147.285964)
			(xy 372.20779 -147.289774) (xy 372.304818 -147.244816) (xy 372.313398 -147.240351) (xy 372.326614 -147.226249)
			(xy 372.333665 -147.208254) (xy 372.334028 -147.198588) (xy 372.334028 -146.921728) (xy 372.33365 -146.912067)
			(xy 372.326589 -146.894085) (xy 372.313382 -146.879988) (xy 372.304818 -146.8755) (xy 372.20779 -146.830542)
			(xy 372.17858 -146.834352) (xy 372.16715 -146.844004) (xy 372.146409 -146.860867) (xy 372.101125 -146.889266)
			(xy 372.052315 -146.911057) (xy 372.000939 -146.92581) (xy 371.948005 -146.933238) (xy 371.921278 -146.933666)
			(xy 371.894025 -146.933263) (xy 371.840073 -146.925503) (xy 371.787776 -146.910144) (xy 371.738196 -146.887499)
			(xy 371.692343 -146.858029) (xy 371.651151 -146.822334) (xy 371.615458 -146.781139) (xy 371.58599 -146.735285)
			(xy 371.563348 -146.685704) (xy 371.547993 -146.633405) (xy 371.540236 -146.579453) (xy 371.540236 -146.524947)
			(xy 371.547993 -146.470995) (xy 371.563348 -146.418696) (xy 371.58599 -146.369115) (xy 371.615458 -146.323261)
			(xy 371.651151 -146.282066) (xy 371.692343 -146.246371) (xy 371.738196 -146.216901) (xy 371.787776 -146.194256)
			(xy 371.840073 -146.178897) (xy 371.894025 -146.171137) (xy 371.921278 -146.17065) (xy 371.948469 -146.171192)
			(xy 372.002301 -146.178912) (xy 372.054491 -146.194198) (xy 372.103981 -146.216741) (xy 372.149768 -146.246084)
			(xy 372.190925 -146.281631) (xy 372.226616 -146.322663) (xy 372.256118 -146.368347) (xy 372.278834 -146.417758)
			(xy 372.294302 -146.469894) (xy 372.30221 -146.523699) (xy 372.302786 -146.550888) (xy 372.303324 -146.561283)
			(xy 372.311636 -146.580344) (xy 372.326823 -146.594548) (xy 372.346395 -146.60157) (xy 372.367148 -146.60026)
			(xy 372.385681 -146.590831) (xy 372.392702 -146.583146) (xy 372.408704 -146.56562) (xy 374.0277 -144.94637)
			(xy 374.034558 -144.934432) (xy 374.036082 -144.927574) (xy 374.0432 -144.900419) (xy 374.06594 -144.849103)
			(xy 374.097706 -144.802828) (xy 374.117108 -144.78254) (xy 374.31726 -144.582388) (xy 374.334507 -144.565812)
			(xy 374.373183 -144.537664) (xy 374.415778 -144.515901) (xy 374.46125 -144.501056) (xy 374.508482 -144.493494)
			(xy 374.532398 -144.49298) (xy 380.33452 -144.49298) (xy 380.344564 -144.492601) (xy 380.363161 -144.485019)
			(xy 380.370588 -144.478248) (xy 380.600712 -144.248124) (xy 380.607423 -144.240656) (xy 380.615004 -144.222087)
			(xy 380.615444 -144.212056) (xy 380.615444 -138.807952) (xy 380.615662 -138.801866) (xy 380.618614 -138.790056)
			(xy 380.621286 -138.784584) (xy 380.688088 -138.655806) (xy 380.691018 -138.650508) (xy 380.698988 -138.641399)
			(xy 380.703836 -138.637772) (xy 380.744476 -138.60907) (xy 380.764019 -138.594587) (xy 380.797737 -138.559541)
			(xy 380.82417 -138.518718) (xy 380.842351 -138.473611) (xy 380.851616 -138.425869) (xy 380.852172 -138.401552)
			(xy 380.852172 -138.401044) (xy 380.851989 -138.386435) (xy 380.848684 -138.357406) (xy 380.845568 -138.343132)
			(xy 380.845568 -138.342878) (xy 380.830074 -138.27887) (xy 380.828795 -138.272503) (xy 380.829044 -138.259525)
			(xy 380.830582 -138.253216) (xy 380.86665 -138.125708) (xy 380.868589 -138.119517) (xy 380.875152 -138.10833)
			(xy 380.879604 -138.10361) (xy 381.02286 -137.960354) (xy 381.04006 -137.943735) (xy 381.078745 -137.915611)
			(xy 381.121357 -137.893891) (xy 381.166844 -137.879112) (xy 381.214084 -137.871638) (xy 381.237998 -137.8712)
			(xy 383.718816 -137.8712) (xy 383.742724 -137.871697) (xy 383.78995 -137.879189) (xy 383.835423 -137.893972)
			(xy 383.878027 -137.915681) (xy 383.916714 -137.943783) (xy 383.933954 -137.960354) (xy 384.33883 -138.36523)
			(xy 384.355432 -138.382446) (xy 384.383559 -138.421126) (xy 384.405282 -138.463734) (xy 384.420065 -138.509218)
			(xy 384.427543 -138.556455) (xy 384.427984 -138.580368) (xy 384.427984 -139.186158) (xy 384.74726 -139.186158)
			(xy 384.751331 -139.130536) (xy 384.763457 -139.076099) (xy 384.78338 -139.024008) (xy 384.810676 -138.975373)
			(xy 384.844762 -138.93123) (xy 384.884911 -138.892521) (xy 384.930269 -138.86007) (xy 384.979869 -138.834569)
			(xy 385.032653 -138.816562) (xy 385.087496 -138.806432) (xy 385.14323 -138.804395) (xy 385.198667 -138.810495)
			(xy 385.252624 -138.824601) (xy 385.303953 -138.846413) (xy 385.351559 -138.875467) (xy 385.394427 -138.911142)
			(xy 385.431644 -138.952679) (xy 385.462417 -138.999192) (xy 385.486089 -139.049689) (xy 385.502157 -139.103096)
			(xy 385.510277 -139.158272) (xy 385.510786 -139.186158) (xy 385.510277 -139.214044) (xy 385.502157 -139.26922)
			(xy 385.486089 -139.322627) (xy 385.462417 -139.373124) (xy 385.431644 -139.419637) (xy 385.394427 -139.461174)
			(xy 385.351559 -139.496849) (xy 385.303953 -139.525903) (xy 385.252624 -139.547715) (xy 385.198667 -139.561821)
			(xy 385.14323 -139.567921) (xy 385.087496 -139.565884) (xy 385.032653 -139.555754) (xy 384.979869 -139.537747)
			(xy 384.930269 -139.512246) (xy 384.884911 -139.479795) (xy 384.844762 -139.441086) (xy 384.810676 -139.396943)
			(xy 384.78338 -139.348308) (xy 384.763457 -139.296217) (xy 384.751331 -139.24178) (xy 384.74726 -139.186158)
			(xy 384.427984 -139.186158) (xy 384.427984 -140.202158) (xy 384.767326 -140.202158) (xy 384.771397 -140.146536)
			(xy 384.783523 -140.092099) (xy 384.803446 -140.040008) (xy 384.830742 -139.991373) (xy 384.864828 -139.94723)
			(xy 384.904977 -139.908521) (xy 384.950335 -139.87607) (xy 384.999935 -139.850569) (xy 385.052719 -139.832562)
			(xy 385.107562 -139.822432) (xy 385.163296 -139.820395) (xy 385.218733 -139.826495) (xy 385.27269 -139.840601)
			(xy 385.324019 -139.862413) (xy 385.371625 -139.891467) (xy 385.414493 -139.927142) (xy 385.45171 -139.968679)
			(xy 385.482483 -140.015192) (xy 385.506155 -140.065689) (xy 385.522223 -140.119096) (xy 385.530343 -140.174272)
			(xy 385.530852 -140.202158) (xy 385.530343 -140.230044) (xy 385.522223 -140.28522) (xy 385.506155 -140.338627)
			(xy 385.482483 -140.389124) (xy 385.45171 -140.435637) (xy 385.414493 -140.477174) (xy 385.371625 -140.512849)
			(xy 385.324019 -140.541903) (xy 385.27269 -140.563715) (xy 385.218733 -140.577821) (xy 385.163296 -140.583921)
			(xy 385.107562 -140.581884) (xy 385.052719 -140.571754) (xy 384.999935 -140.553747) (xy 384.950335 -140.528246)
			(xy 384.904977 -140.495795) (xy 384.864828 -140.457086) (xy 384.830742 -140.412943) (xy 384.803446 -140.364308)
			(xy 384.783523 -140.312217) (xy 384.771397 -140.25778) (xy 384.767326 -140.202158) (xy 384.427984 -140.202158)
			(xy 384.427984 -141.309852) (xy 385.56006 -141.309852) (xy 385.564131 -141.25423) (xy 385.576257 -141.199793)
			(xy 385.59618 -141.147702) (xy 385.623476 -141.099067) (xy 385.657562 -141.054924) (xy 385.697711 -141.016215)
			(xy 385.743069 -140.983764) (xy 385.792669 -140.958263) (xy 385.845453 -140.940256) (xy 385.900296 -140.930126)
			(xy 385.95603 -140.928089) (xy 386.011467 -140.934189) (xy 386.065424 -140.948295) (xy 386.116753 -140.970107)
			(xy 386.164359 -140.999161) (xy 386.207227 -141.034836) (xy 386.244444 -141.076373) (xy 386.275217 -141.122886)
			(xy 386.298889 -141.173383) (xy 386.314957 -141.22679) (xy 386.323077 -141.281966) (xy 386.323586 -141.309852)
			(xy 386.323077 -141.337738) (xy 386.314957 -141.392914) (xy 386.298889 -141.446321) (xy 386.275217 -141.496818)
			(xy 386.244444 -141.543331) (xy 386.207227 -141.584868) (xy 386.164359 -141.620543) (xy 386.116753 -141.649597)
			(xy 386.065424 -141.671409) (xy 386.011467 -141.685515) (xy 385.95603 -141.691615) (xy 385.900296 -141.689578)
			(xy 385.845453 -141.679448) (xy 385.792669 -141.661441) (xy 385.743069 -141.63594) (xy 385.697711 -141.603489)
			(xy 385.657562 -141.56478) (xy 385.623476 -141.520637) (xy 385.59618 -141.472002) (xy 385.576257 -141.419911)
			(xy 385.564131 -141.365474) (xy 385.56006 -141.309852) (xy 384.427984 -141.309852) (xy 384.427984 -142.307056)
			(xy 387.692644 -142.307056) (xy 387.696715 -142.251434) (xy 387.708841 -142.196997) (xy 387.728764 -142.144906)
			(xy 387.75606 -142.096271) (xy 387.790146 -142.052128) (xy 387.830295 -142.013419) (xy 387.875653 -141.980968)
			(xy 387.925253 -141.955467) (xy 387.978037 -141.93746) (xy 388.03288 -141.92733) (xy 388.088614 -141.925293)
			(xy 388.144051 -141.931393) (xy 388.198008 -141.945499) (xy 388.249337 -141.967311) (xy 388.296943 -141.996365)
			(xy 388.339811 -142.03204) (xy 388.377028 -142.073577) (xy 388.407801 -142.12009) (xy 388.431473 -142.170587)
			(xy 388.447541 -142.223994) (xy 388.455661 -142.27917) (xy 388.45617 -142.307056) (xy 388.455661 -142.334942)
			(xy 388.447541 -142.390118) (xy 388.431473 -142.443525) (xy 388.407801 -142.494022) (xy 388.377028 -142.540535)
			(xy 388.339811 -142.582072) (xy 388.296943 -142.617747) (xy 388.249337 -142.646801) (xy 388.198008 -142.668613)
			(xy 388.144051 -142.682719) (xy 388.088614 -142.688819) (xy 388.03288 -142.686782) (xy 387.978037 -142.676652)
			(xy 387.925253 -142.658645) (xy 387.875653 -142.633144) (xy 387.830295 -142.600693) (xy 387.790146 -142.561984)
			(xy 387.75606 -142.517841) (xy 387.728764 -142.469206) (xy 387.708841 -142.417115) (xy 387.696715 -142.362678)
			(xy 387.692644 -142.307056) (xy 384.427984 -142.307056) (xy 384.427984 -142.742158) (xy 385.5245 -142.742158)
			(xy 385.528571 -142.686536) (xy 385.540697 -142.632099) (xy 385.56062 -142.580008) (xy 385.587916 -142.531373)
			(xy 385.622002 -142.48723) (xy 385.662151 -142.448521) (xy 385.707509 -142.41607) (xy 385.757109 -142.390569)
			(xy 385.809893 -142.372562) (xy 385.864736 -142.362432) (xy 385.92047 -142.360395) (xy 385.975907 -142.366495)
			(xy 386.029864 -142.380601) (xy 386.081193 -142.402413) (xy 386.128799 -142.431467) (xy 386.171667 -142.467142)
			(xy 386.208884 -142.508679) (xy 386.239657 -142.555192) (xy 386.263329 -142.605689) (xy 386.279397 -142.659096)
			(xy 386.287517 -142.714272) (xy 386.288026 -142.742158) (xy 386.287517 -142.770044) (xy 386.279397 -142.82522)
			(xy 386.263329 -142.878627) (xy 386.239657 -142.929124) (xy 386.208884 -142.975637) (xy 386.171667 -143.017174)
			(xy 386.128799 -143.052849) (xy 386.081193 -143.081903) (xy 386.029864 -143.103715) (xy 385.975907 -143.117821)
			(xy 385.92047 -143.123921) (xy 385.864736 -143.121884) (xy 385.809893 -143.111754) (xy 385.757109 -143.093747)
			(xy 385.707509 -143.068246) (xy 385.662151 -143.035795) (xy 385.622002 -142.997086) (xy 385.587916 -142.952943)
			(xy 385.56062 -142.904308) (xy 385.540697 -142.852217) (xy 385.528571 -142.79778) (xy 385.5245 -142.742158)
			(xy 384.427984 -142.742158) (xy 384.427984 -146.557746) (xy 384.427873 -146.571987) (xy 384.425331 -146.600355)
			(xy 384.422904 -146.614388) (xy 384.420618 -146.625564) (xy 384.426206 -146.647408) (xy 384.48361 -146.716496)
			(xy 384.491231 -146.724722) (xy 384.511527 -146.734201) (xy 384.522726 -146.734784) (xy 385.066794 -146.734784)
			(xy 385.091791 -146.735406) (xy 385.140815 -146.745212) (xy 385.186986 -146.764389) (xy 385.228531 -146.792202)
			(xy 385.246626 -146.80946) (xy 386.100828 -147.663662) (xy 387.813054 -147.663662) (xy 387.81702 -147.579131)
			(xy 387.828885 -147.495344) (xy 387.848543 -147.413035) (xy 387.875823 -147.332929) (xy 387.910484 -147.25573)
			(xy 387.952222 -147.182115) (xy 388.000669 -147.112732) (xy 388.055401 -147.048191) (xy 388.115937 -146.989059)
			(xy 388.181743 -146.935855) (xy 388.252243 -146.889047) (xy 388.326815 -146.849046) (xy 388.404806 -146.816204)
			(xy 388.48553 -146.79081) (xy 388.568277 -146.773087) (xy 388.652319 -146.763189) (xy 388.73692 -146.761206)
			(xy 388.821334 -146.767153) (xy 388.904821 -146.780978) (xy 388.986646 -146.802561) (xy 389.06609 -146.831711)
			(xy 389.142456 -146.868172) (xy 389.215072 -146.911624) (xy 389.2833 -146.961685) (xy 389.34654 -147.017915)
			(xy 389.404237 -147.07982) (xy 389.455884 -147.146856) (xy 389.501026 -147.218433) (xy 389.539268 -147.293923)
			(xy 389.570272 -147.372662) (xy 389.593767 -147.453959) (xy 389.609546 -147.537098) (xy 389.61747 -147.62135)
			(xy 389.617966 -147.663662) (xy 390.353054 -147.663662) (xy 390.35702 -147.579131) (xy 390.368885 -147.495344)
			(xy 390.388543 -147.413035) (xy 390.415823 -147.332929) (xy 390.450484 -147.25573) (xy 390.492222 -147.182115)
			(xy 390.540669 -147.112732) (xy 390.595401 -147.048191) (xy 390.655937 -146.989059) (xy 390.721743 -146.935855)
			(xy 390.792243 -146.889047) (xy 390.866815 -146.849046) (xy 390.944806 -146.816204) (xy 391.02553 -146.79081)
			(xy 391.108277 -146.773087) (xy 391.192319 -146.763189) (xy 391.27692 -146.761206) (xy 391.361334 -146.767153)
			(xy 391.444821 -146.780978) (xy 391.526646 -146.802561) (xy 391.60609 -146.831711) (xy 391.682456 -146.868172)
			(xy 391.755072 -146.911624) (xy 391.8233 -146.961685) (xy 391.88654 -147.017915) (xy 391.944237 -147.07982)
			(xy 391.995884 -147.146856) (xy 392.041026 -147.218433) (xy 392.079268 -147.293923) (xy 392.110272 -147.372662)
			(xy 392.133767 -147.453959) (xy 392.149546 -147.537098) (xy 392.15747 -147.62135) (xy 392.157966 -147.663662)
			(xy 392.15747 -147.705974) (xy 392.149546 -147.790226) (xy 392.133767 -147.873365) (xy 392.110272 -147.954662)
			(xy 392.079268 -148.033401) (xy 392.041026 -148.108891) (xy 391.995884 -148.180468) (xy 391.944237 -148.247504)
			(xy 391.88654 -148.309409) (xy 391.8233 -148.365639) (xy 391.755072 -148.4157) (xy 391.682456 -148.459152)
			(xy 391.60609 -148.495613) (xy 391.526646 -148.524763) (xy 391.444821 -148.546346) (xy 391.361334 -148.560171)
			(xy 391.27692 -148.566118) (xy 391.192319 -148.564135) (xy 391.108277 -148.554237) (xy 391.02553 -148.536514)
			(xy 390.944806 -148.51112) (xy 390.866815 -148.478278) (xy 390.792243 -148.438277) (xy 390.721743 -148.391469)
			(xy 390.655937 -148.338265) (xy 390.595401 -148.279133) (xy 390.540669 -148.214592) (xy 390.492222 -148.145209)
			(xy 390.450484 -148.071594) (xy 390.415823 -147.994395) (xy 390.388543 -147.914289) (xy 390.368885 -147.83198)
			(xy 390.35702 -147.748193) (xy 390.353054 -147.663662) (xy 389.617966 -147.663662) (xy 389.61747 -147.705974)
			(xy 389.609546 -147.790226) (xy 389.593767 -147.873365) (xy 389.570272 -147.954662) (xy 389.539268 -148.033401)
			(xy 389.501026 -148.108891) (xy 389.455884 -148.180468) (xy 389.404237 -148.247504) (xy 389.34654 -148.309409)
			(xy 389.2833 -148.365639) (xy 389.215072 -148.4157) (xy 389.142456 -148.459152) (xy 389.06609 -148.495613)
			(xy 388.986646 -148.524763) (xy 388.904821 -148.546346) (xy 388.821334 -148.560171) (xy 388.73692 -148.566118)
			(xy 388.652319 -148.564135) (xy 388.568277 -148.554237) (xy 388.48553 -148.536514) (xy 388.404806 -148.51112)
			(xy 388.326815 -148.478278) (xy 388.252243 -148.438277) (xy 388.181743 -148.391469) (xy 388.115937 -148.338265)
			(xy 388.055401 -148.279133) (xy 388.000669 -148.214592) (xy 387.952222 -148.145209) (xy 387.910484 -148.071594)
			(xy 387.875823 -147.994395) (xy 387.848543 -147.914289) (xy 387.828885 -147.83198) (xy 387.81702 -147.748193)
			(xy 387.813054 -147.663662) (xy 386.100828 -147.663662) (xy 395.853158 -157.415992) (xy 395.860623 -157.422706)
			(xy 395.879195 -157.430283) (xy 395.889226 -157.430724) (xy 416.105848 -157.430724) (xy 416.130842 -157.431391)
			(xy 416.179864 -157.441186) (xy 416.226034 -157.46035) (xy 416.267582 -157.488149) (xy 416.28568 -157.5054)
			(xy 417.21659 -158.43631) (xy 417.233821 -158.454412) (xy 417.261563 -158.495973) (xy 417.280669 -158.542145)
			(xy 417.290405 -158.591157) (xy 417.291012 -158.616142) (xy 417.291012 -159.554672) (xy 417.290437 -159.579658)
			(xy 417.280684 -159.628668) (xy 417.261566 -159.674838) (xy 417.233817 -159.716396) (xy 417.21659 -159.734504)
			(xy 416.96513 -159.985964) (xy 417.451538 -159.985964) (xy 417.455609 -159.930342) (xy 417.467735 -159.875905)
			(xy 417.487658 -159.823814) (xy 417.514954 -159.775179) (xy 417.54904 -159.731036) (xy 417.589189 -159.692327)
			(xy 417.634547 -159.659876) (xy 417.684147 -159.634375) (xy 417.736931 -159.616368) (xy 417.791774 -159.606238)
			(xy 417.847508 -159.604201) (xy 417.902945 -159.610301) (xy 417.956902 -159.624407) (xy 418.008231 -159.646219)
			(xy 418.055837 -159.675273) (xy 418.098705 -159.710948) (xy 418.135922 -159.752485) (xy 418.166695 -159.798998)
			(xy 418.190367 -159.849495) (xy 418.206435 -159.902902) (xy 418.214555 -159.958078) (xy 418.215064 -159.985964)
			(xy 418.214555 -160.01385) (xy 418.206435 -160.069026) (xy 418.190367 -160.122433) (xy 418.166695 -160.17293)
			(xy 418.135922 -160.219443) (xy 418.098705 -160.26098) (xy 418.055837 -160.296655) (xy 418.008231 -160.325709)
			(xy 417.956902 -160.347521) (xy 417.902945 -160.361627) (xy 417.847508 -160.367727) (xy 417.791774 -160.36569)
			(xy 417.736931 -160.35556) (xy 417.684147 -160.337553) (xy 417.634547 -160.312052) (xy 417.589189 -160.279601)
			(xy 417.54904 -160.240892) (xy 417.514954 -160.196749) (xy 417.487658 -160.148114) (xy 417.467735 -160.096023)
			(xy 417.455609 -160.041586) (xy 417.451538 -159.985964) (xy 416.96513 -159.985964) (xy 416.839654 -160.11144)
			(xy 416.836098 -160.118806) (xy 416.82386 -160.142151) (xy 416.793907 -160.185522) (xy 416.758271 -160.224359)
			(xy 416.717629 -160.257923) (xy 416.672755 -160.285575) (xy 416.624504 -160.306789) (xy 416.573792 -160.321161)
			(xy 416.521585 -160.328418) (xy 416.49523 -160.328864) (xy 416.467976 -160.328417) (xy 416.414022 -160.320663)
			(xy 416.361721 -160.305308) (xy 416.312138 -160.282666) (xy 416.266283 -160.253197) (xy 416.225089 -160.217501)
			(xy 416.189395 -160.176306) (xy 416.159927 -160.130449) (xy 416.137287 -160.080866) (xy 416.121934 -160.028564)
			(xy 416.114182 -159.97461) (xy 416.113722 -159.947356) (xy 416.114177 -159.91988) (xy 416.122076 -159.865499)
			(xy 416.137703 -159.812816) (xy 416.160735 -159.762924) (xy 416.190693 -159.716857) (xy 416.208464 -159.695896)
			(xy 416.21456 -159.688784) (xy 416.22091 -159.671766) (xy 416.22091 -159.585914) (xy 416.21456 -159.568896)
			(xy 416.208464 -159.561784) (xy 416.190706 -159.540817) (xy 416.160781 -159.494736) (xy 416.137768 -159.444843)
			(xy 416.122141 -159.392167) (xy 416.114222 -159.337796) (xy 416.113722 -159.310324) (xy 416.114312 -159.280274)
			(xy 416.123744 -159.220917) (xy 416.142362 -159.163772) (xy 416.169706 -159.110252) (xy 416.205101 -159.061679)
			(xy 416.22599 -159.040068) (xy 416.232742 -159.032687) (xy 416.240446 -159.014245) (xy 416.240976 -159.004254)
			(xy 416.240976 -158.740094) (xy 416.24056 -158.730024) (xy 416.232833 -158.711426) (xy 416.22599 -158.704026)
			(xy 415.876232 -158.354268) (xy 415.868764 -158.347558) (xy 415.850195 -158.339977) (xy 415.840164 -158.339536)
			(xy 395.61008 -158.339536) (xy 395.585083 -158.338924) (xy 395.536058 -158.329114) (xy 395.489887 -158.309934)
			(xy 395.448343 -158.282119) (xy 395.430248 -158.26486) (xy 384.819398 -147.65401) (xy 384.811992 -147.647178)
			(xy 384.793397 -147.639453) (xy 384.78333 -147.639024) (xy 384.478784 -147.639024) (xy 384.468797 -147.639604)
			(xy 384.450353 -147.647283) (xy 384.436217 -147.661402) (xy 384.428516 -147.679837) (xy 384.427984 -147.689824)
			(xy 384.427984 -150.391622) (xy 384.427495 -150.41553) (xy 384.420001 -150.462756) (xy 384.405217 -150.50823)
			(xy 384.383506 -150.550834) (xy 384.355402 -150.58952) (xy 384.33883 -150.60676) (xy 384.020822 -150.924768)
			(xy 384.003592 -150.941363) (xy 383.964911 -150.969506) (xy 383.92231 -150.991264) (xy 383.876835 -151.006105)
			(xy 383.829601 -151.013664) (xy 383.805684 -151.014176) (xy 381.412496 -151.014176) (xy 381.402494 -151.013693)
			(xy 381.384031 -151.005989) (xy 381.376682 -150.99919) (xy 381.042164 -150.664672) (xy 381.034684 -150.657977)
			(xy 381.016124 -150.650387) (xy 381.006096 -150.64994) (xy 376.7074 -150.64994) (xy 376.697374 -150.65032)
			(xy 376.678849 -150.657998) (xy 376.664675 -150.672183) (xy 376.657013 -150.690713) (xy 376.6566 -150.70074)
			(xy 376.6566 -155.640532) (xy 378.748036 -155.640532) (xy 378.748512 -155.613162) (xy 378.756326 -155.558983)
			(xy 378.771812 -155.50648) (xy 378.794652 -155.456733) (xy 378.824375 -155.410766) (xy 378.842016 -155.389834)
			(xy 378.848112 -155.382722) (xy 378.854462 -155.365704) (xy 378.854462 -155.28036) (xy 378.848112 -155.263342)
			(xy 378.842016 -155.25623) (xy 378.824407 -155.235272) (xy 378.794682 -155.189308) (xy 378.771835 -155.139566)
			(xy 378.756337 -155.087068) (xy 378.748506 -155.032893) (xy 378.748502 -154.978155) (xy 378.756327 -154.923979)
			(xy 378.771818 -154.871479) (xy 378.794659 -154.821734) (xy 378.824378 -154.775767) (xy 378.842016 -154.754834)
			(xy 378.848112 -154.747722) (xy 378.854462 -154.730704) (xy 378.854462 -154.64536) (xy 378.848112 -154.628342)
			(xy 378.842016 -154.62123) (xy 378.824407 -154.600272) (xy 378.794682 -154.554308) (xy 378.771835 -154.504566)
			(xy 378.756337 -154.452068) (xy 378.748506 -154.397893) (xy 378.748502 -154.343155) (xy 378.756327 -154.288979)
			(xy 378.771818 -154.236479) (xy 378.794659 -154.186734) (xy 378.824378 -154.140767) (xy 378.842016 -154.119834)
			(xy 378.848112 -154.112722) (xy 378.854462 -154.095704) (xy 378.854462 -154.01036) (xy 378.848112 -153.993342)
			(xy 378.842016 -153.98623) (xy 378.82438 -153.965295) (xy 378.794667 -153.919324) (xy 378.77183 -153.869577)
			(xy 378.756339 -153.817076) (xy 378.74851 -153.762901) (xy 378.748036 -153.735532) (xy 378.748485 -153.708278)
			(xy 378.756239 -153.654324) (xy 378.771593 -153.602023) (xy 378.794235 -153.55244) (xy 378.823704 -153.506585)
			(xy 378.859399 -153.465391) (xy 378.900595 -153.429697) (xy 378.946451 -153.400229) (xy 378.996035 -153.377589)
			(xy 379.048336 -153.362236) (xy 379.10229 -153.354484) (xy 379.129544 -153.354024) (xy 379.15945 -153.35459)
			(xy 379.218528 -153.363942) (xy 379.275423 -153.382394) (xy 379.328744 -153.409495) (xy 379.377186 -153.444582)
			(xy 379.398784 -153.465276) (xy 379.405896 -153.472388) (xy 379.423168 -153.479754) (xy 379.512576 -153.482548)
			(xy 379.530356 -153.476198) (xy 379.537722 -153.469594) (xy 379.545539 -153.462796) (xy 379.561805 -153.449962)
			(xy 379.570234 -153.44394) (xy 379.579632 -153.437336) (xy 379.590808 -153.418032) (xy 379.599444 -153.317956)
			(xy 379.591824 -153.297128) (xy 379.583696 -153.289) (xy 379.562873 -153.267422) (xy 379.527622 -153.218915)
			(xy 379.500396 -153.165488) (xy 379.481867 -153.10846) (xy 379.47249 -153.049234) (xy 379.471936 -153.019252)
			(xy 379.472424 -152.991882) (xy 379.480235 -152.937704) (xy 379.495719 -152.885201) (xy 379.518556 -152.835453)
			(xy 379.548276 -152.789486) (xy 379.565916 -152.768554) (xy 379.572012 -152.761442) (xy 379.578362 -152.744424)
			(xy 379.578362 -152.65908) (xy 379.572012 -152.642062) (xy 379.565916 -152.63495) (xy 379.548289 -152.614008)
			(xy 379.518575 -152.568038) (xy 379.495737 -152.518293) (xy 379.480243 -152.465795) (xy 379.472411 -152.411621)
			(xy 379.471936 -152.384252) (xy 379.472333 -152.356998) (xy 379.480097 -152.303044) (xy 379.495461 -152.250745)
			(xy 379.518111 -152.201165) (xy 379.547586 -152.155313) (xy 379.583287 -152.114122) (xy 379.624486 -152.078431)
			(xy 379.670346 -152.048967) (xy 379.719932 -152.026329) (xy 379.772234 -152.010978) (xy 379.826189 -152.003227)
			(xy 379.853444 -152.002744) (xy 379.880814 -152.003232) (xy 379.934992 -152.011043) (xy 379.987495 -152.026526)
			(xy 380.037243 -152.049363) (xy 380.08321 -152.079084) (xy 380.104142 -152.096724) (xy 380.111254 -152.10282)
			(xy 380.128272 -152.10917) (xy 380.213616 -152.10917) (xy 380.230634 -152.10282) (xy 380.237746 -152.096724)
			(xy 380.258679 -152.079083) (xy 380.304647 -152.049359) (xy 380.354393 -152.026513) (xy 380.406895 -152.011017)
			(xy 380.461073 -152.003188) (xy 380.515815 -152.003188) (xy 380.569993 -152.011017) (xy 380.622495 -152.026513)
			(xy 380.672241 -152.049359) (xy 380.718209 -152.079083) (xy 380.739142 -152.096724) (xy 380.746254 -152.10282)
			(xy 380.763272 -152.10917) (xy 380.848616 -152.10917) (xy 380.865634 -152.10282) (xy 380.872746 -152.096724)
			(xy 380.893679 -152.079083) (xy 380.939647 -152.049359) (xy 380.989393 -152.026513) (xy 381.041895 -152.011017)
			(xy 381.096073 -152.003188) (xy 381.150815 -152.003188) (xy 381.204993 -152.011017) (xy 381.257495 -152.026513)
			(xy 381.307241 -152.049359) (xy 381.353209 -152.079083) (xy 381.374142 -152.096724) (xy 381.381254 -152.10282)
			(xy 381.398272 -152.10917) (xy 381.483616 -152.10917) (xy 381.500634 -152.10282) (xy 381.507746 -152.096724)
			(xy 381.528691 -152.0791) (xy 381.57466 -152.049385) (xy 381.624404 -152.026546) (xy 381.676902 -152.011052)
			(xy 381.731076 -152.00322) (xy 381.758444 -152.002744) (xy 381.785694 -152.003237) (xy 381.839639 -152.010998)
			(xy 381.891931 -152.026356) (xy 381.941505 -152.048999) (xy 381.987353 -152.078465) (xy 382.028541 -152.114156)
			(xy 382.064232 -152.155344) (xy 382.093699 -152.201191) (xy 382.116342 -152.250765) (xy 382.131701 -152.303057)
			(xy 382.139463 -152.357002) (xy 382.139952 -152.384252) (xy 382.139469 -152.411622) (xy 382.131657 -152.465801)
			(xy 382.116173 -152.518304) (xy 382.093334 -152.568051) (xy 382.063612 -152.614018) (xy 382.045972 -152.63495)
			(xy 382.039876 -152.642062) (xy 382.033526 -152.65908) (xy 382.033526 -152.744424) (xy 382.039876 -152.761442)
			(xy 382.045972 -152.768554) (xy 382.063599 -152.789496) (xy 382.093313 -152.835466) (xy 382.116152 -152.885211)
			(xy 382.131646 -152.937709) (xy 382.139477 -152.991883) (xy 382.139952 -153.019252) (xy 382.139434 -153.048033)
			(xy 382.13078 -153.104939) (xy 382.113677 -153.159901) (xy 382.088512 -153.21167) (xy 382.055856 -153.259071)
			(xy 382.016451 -153.30103) (xy 381.97119 -153.336593) (xy 381.946404 -153.35123) (xy 381.936498 -153.356818)
			(xy 381.923544 -153.37536) (xy 381.906272 -153.47569) (xy 381.912114 -153.49728) (xy 381.919734 -153.50617)
			(xy 381.937187 -153.527084) (xy 381.96664 -153.572906) (xy 381.989282 -153.622449) (xy 382.004654 -153.674706)
			(xy 382.012443 -153.728617) (xy 382.012952 -153.755852) (xy 382.012469 -153.783222) (xy 382.004657 -153.837401)
			(xy 381.989173 -153.889904) (xy 381.966334 -153.939651) (xy 381.936612 -153.985618) (xy 381.918972 -154.00655)
			(xy 381.912876 -154.013662) (xy 381.906526 -154.03068) (xy 381.906526 -154.116024) (xy 381.912876 -154.133042)
			(xy 381.918972 -154.140154) (xy 381.936566 -154.161125) (xy 381.966293 -154.207086) (xy 381.989141 -154.256826)
			(xy 382.004641 -154.309322) (xy 382.012474 -154.363496) (xy 382.012479 -154.418232) (xy 382.004656 -154.472407)
			(xy 381.989166 -154.524906) (xy 381.966327 -154.574651) (xy 381.936609 -154.620617) (xy 381.918972 -154.64155)
			(xy 381.912876 -154.648662) (xy 381.906526 -154.66568) (xy 381.906526 -154.751024) (xy 381.912876 -154.768042)
			(xy 381.918972 -154.775154) (xy 381.936566 -154.796125) (xy 381.966293 -154.842086) (xy 381.989141 -154.891826)
			(xy 382.004641 -154.944322) (xy 382.012474 -154.998496) (xy 382.012479 -155.053232) (xy 382.004656 -155.107407)
			(xy 381.989166 -155.159906) (xy 381.966327 -155.209651) (xy 381.936609 -155.255617) (xy 381.918972 -155.27655)
			(xy 381.912876 -155.283662) (xy 381.906526 -155.30068) (xy 381.906526 -155.386024) (xy 381.912876 -155.403042)
			(xy 381.918972 -155.410154) (xy 381.936599 -155.431096) (xy 381.966313 -155.477066) (xy 381.989152 -155.526811)
			(xy 382.004646 -155.579309) (xy 382.012477 -155.633483) (xy 382.012952 -155.660852) (xy 382.012435 -155.688653)
			(xy 382.004382 -155.743668) (xy 381.988424 -155.79693) (xy 381.9649 -155.84731) (xy 381.934309 -155.89374)
			(xy 381.897299 -155.935234) (xy 381.8763 -155.95346) (xy 381.86815 -155.961065) (xy 381.858649 -155.981196)
			(xy 381.858012 -155.992322) (xy 381.858012 -156.071824) (xy 381.8763 -156.097732) (xy 381.891286 -156.10332)
			(xy 381.918266 -156.113936) (xy 381.968932 -156.142116) (xy 382.014751 -156.177637) (xy 382.054669 -156.21968)
			(xy 382.087768 -156.267279) (xy 382.113284 -156.319338) (xy 382.130631 -156.374657) (xy 382.139409 -156.431964)
			(xy 382.139952 -156.460952) (xy 382.139469 -156.488322) (xy 382.131657 -156.542501) (xy 382.116173 -156.595004)
			(xy 382.093334 -156.644751) (xy 382.063612 -156.690718) (xy 382.045972 -156.71165) (xy 382.039876 -156.718762)
			(xy 382.033526 -156.73578) (xy 382.033526 -156.821124) (xy 382.039876 -156.838142) (xy 382.045972 -156.845254)
			(xy 382.063599 -156.866196) (xy 382.093313 -156.912166) (xy 382.116152 -156.961911) (xy 382.127975 -157.001972)
			(xy 386.91185 -157.001972) (xy 386.912287 -156.974601) (xy 386.92011 -156.92042) (xy 386.935605 -156.867916)
			(xy 386.958454 -156.818169) (xy 386.988185 -156.772204) (xy 387.00583 -156.751274) (xy 387.011926 -156.744162)
			(xy 387.018276 -156.727144) (xy 387.018276 -156.6418) (xy 387.011926 -156.624782) (xy 387.00583 -156.61767)
			(xy 386.988215 -156.596718) (xy 386.958498 -156.550752) (xy 386.935657 -156.501009) (xy 386.920161 -156.448512)
			(xy 386.912327 -156.39434) (xy 386.91185 -156.366972) (xy 386.912354 -156.339204) (xy 386.920393 -156.284252)
			(xy 386.936312 -156.231046) (xy 386.959775 -156.180709) (xy 386.990286 -156.134304) (xy 387.00837 -156.113226)
			(xy 387.01472 -156.106114) (xy 387.021324 -156.088842) (xy 387.021324 -156.002482) (xy 387.01472 -155.98521)
			(xy 387.00837 -155.978098) (xy 386.990305 -155.957004) (xy 386.959797 -155.910601) (xy 386.936331 -155.860268)
			(xy 386.920405 -155.807066) (xy 386.912353 -155.752119) (xy 386.91185 -155.724352) (xy 386.912334 -155.696982)
			(xy 386.920146 -155.642803) (xy 386.93563 -155.5903) (xy 386.958468 -155.540553) (xy 386.98819 -155.494586)
			(xy 387.00583 -155.473654) (xy 387.011926 -155.466542) (xy 387.018276 -155.449524) (xy 387.018276 -155.36418)
			(xy 387.011926 -155.347162) (xy 387.00583 -155.34005) (xy 386.988206 -155.319106) (xy 386.95849 -155.273137)
			(xy 386.935651 -155.223393) (xy 386.920157 -155.170894) (xy 386.912326 -155.11672) (xy 386.91185 -155.089352)
			(xy 386.912358 -155.060613) (xy 386.920986 -155.003785) (xy 386.938041 -154.948895) (xy 386.963136 -154.897183)
			(xy 386.995703 -154.849821) (xy 387.014974 -154.828494) (xy 387.021578 -154.821382) (xy 387.02869 -154.803856)
			(xy 387.02869 -154.714448) (xy 387.021578 -154.696922) (xy 387.014974 -154.68981) (xy 386.995686 -154.668497)
			(xy 386.963121 -154.621132) (xy 386.938031 -154.569417) (xy 386.920985 -154.514523) (xy 386.912368 -154.457692)
			(xy 386.91185 -154.428952) (xy 386.912334 -154.401582) (xy 386.920146 -154.347403) (xy 386.93563 -154.2949)
			(xy 386.958468 -154.245153) (xy 386.98819 -154.199186) (xy 387.00583 -154.178254) (xy 387.011926 -154.171142)
			(xy 387.018276 -154.154124) (xy 387.018276 -154.06878) (xy 387.011926 -154.051762) (xy 387.00583 -154.04465)
			(xy 386.988206 -154.023706) (xy 386.95849 -153.977737) (xy 386.935651 -153.927993) (xy 386.920157 -153.875494)
			(xy 386.912326 -153.82132) (xy 386.91185 -153.793952) (xy 386.912333 -153.766701) (xy 386.920095 -153.712756)
			(xy 386.935454 -153.660464) (xy 386.958098 -153.610889) (xy 386.987565 -153.565041) (xy 387.023257 -153.523852)
			(xy 387.064446 -153.488162) (xy 387.110294 -153.458695) (xy 387.159869 -153.436052) (xy 387.212162 -153.420694)
			(xy 387.266107 -153.412933) (xy 387.293358 -153.412444) (xy 387.320728 -153.412924) (xy 387.374907 -153.420737)
			(xy 387.42741 -153.436222) (xy 387.477157 -153.459061) (xy 387.523124 -153.488783) (xy 387.544056 -153.506424)
			(xy 387.551168 -153.51252) (xy 387.568186 -153.51887) (xy 387.65353 -153.51887) (xy 387.670548 -153.51252)
			(xy 387.67766 -153.506424) (xy 387.698599 -153.488794) (xy 387.74457 -153.45908) (xy 387.794315 -153.436242)
			(xy 387.846815 -153.420749) (xy 387.900989 -153.412919) (xy 387.928358 -153.412444) (xy 387.955606 -153.413017)
			(xy 388.009548 -153.420767) (xy 388.061838 -153.436114) (xy 388.111412 -153.458747) (xy 388.15726 -153.488204)
			(xy 388.19845 -153.523887) (xy 388.234142 -153.565068) (xy 388.26361 -153.610909) (xy 388.286254 -153.660477)
			(xy 388.301614 -153.712764) (xy 388.309376 -153.766704) (xy 388.309866 -153.793952) (xy 388.30938 -153.821322)
			(xy 388.301568 -153.8755) (xy 388.286084 -153.928003) (xy 388.263247 -153.977751) (xy 388.233526 -154.023718)
			(xy 388.215886 -154.04465) (xy 388.20979 -154.051762) (xy 388.20344 -154.06878) (xy 388.20344 -154.154124)
			(xy 388.20979 -154.171142) (xy 388.215886 -154.178254) (xy 388.233515 -154.199194) (xy 388.263229 -154.245165)
			(xy 388.286067 -154.29491) (xy 388.30156 -154.347409) (xy 388.309391 -154.401583) (xy 388.309866 -154.428952)
			(xy 388.309356 -154.457691) (xy 388.300728 -154.514518) (xy 388.283673 -154.569409) (xy 388.258579 -154.62112)
			(xy 388.226013 -154.668483) (xy 388.206742 -154.68981) (xy 388.200138 -154.696922) (xy 388.193026 -154.714448)
			(xy 388.193026 -154.803856) (xy 388.200138 -154.821382) (xy 388.206742 -154.828494) (xy 388.226034 -154.849803)
			(xy 388.258598 -154.897169) (xy 388.283687 -154.948886) (xy 388.300732 -155.003781) (xy 388.309349 -155.060612)
			(xy 388.309866 -155.089352) (xy 388.30938 -155.116722) (xy 388.301568 -155.1709) (xy 388.286084 -155.223403)
			(xy 388.263247 -155.273151) (xy 388.233526 -155.319118) (xy 388.215886 -155.34005) (xy 388.20979 -155.347162)
			(xy 388.20344 -155.36418) (xy 388.20344 -155.449524) (xy 388.20979 -155.466542) (xy 388.215886 -155.473654)
			(xy 388.233515 -155.494594) (xy 388.263229 -155.540565) (xy 388.286067 -155.59031) (xy 388.30156 -155.642809)
			(xy 388.309391 -155.696983) (xy 388.309866 -155.724352) (xy 388.309372 -155.752121) (xy 388.30133 -155.807073)
			(xy 388.285408 -155.860279) (xy 388.261943 -155.910615) (xy 388.231431 -155.95702) (xy 388.213346 -155.978098)
			(xy 388.206996 -155.98521) (xy 388.200392 -156.002482) (xy 388.200392 -156.088842) (xy 388.206996 -156.106114)
			(xy 388.213346 -156.113226) (xy 388.231425 -156.134308) (xy 388.261931 -156.180715) (xy 388.285393 -156.231051)
			(xy 388.301316 -156.284255) (xy 388.309365 -156.339204) (xy 388.309866 -156.366972) (xy 388.309392 -156.394342)
			(xy 388.301577 -156.448521) (xy 388.28609 -156.501024) (xy 388.26325 -156.550771) (xy 388.233527 -156.596738)
			(xy 388.215886 -156.61767) (xy 388.20979 -156.624782) (xy 388.20344 -156.6418) (xy 388.20344 -156.727144)
			(xy 388.20979 -156.744162) (xy 388.215886 -156.751274) (xy 388.233524 -156.772207) (xy 388.263237 -156.818179)
			(xy 388.286073 -156.867926) (xy 388.301564 -156.920427) (xy 388.309392 -156.974603) (xy 388.309866 -157.001972)
			(xy 388.309419 -157.029226) (xy 388.301664 -157.08318) (xy 388.28631 -157.13548) (xy 388.263667 -157.185063)
			(xy 388.234198 -157.230919) (xy 388.198503 -157.272113) (xy 388.157307 -157.307807) (xy 388.111451 -157.337274)
			(xy 388.061867 -157.359915) (xy 388.009566 -157.375267) (xy 387.955612 -157.38302) (xy 387.928358 -157.38348)
			(xy 387.900989 -157.382985) (xy 387.846811 -157.375175) (xy 387.794308 -157.359693) (xy 387.74456 -157.336857)
			(xy 387.698592 -157.307139) (xy 387.67766 -157.2895) (xy 387.670548 -157.283404) (xy 387.65353 -157.277054)
			(xy 387.568186 -157.277054) (xy 387.551168 -157.283404) (xy 387.544056 -157.2895) (xy 387.523114 -157.307126)
			(xy 387.477144 -157.33684) (xy 387.427399 -157.359678) (xy 387.3749 -157.375173) (xy 387.320726 -157.383004)
			(xy 387.293358 -157.38348) (xy 387.266104 -157.383061) (xy 387.212153 -157.375298) (xy 387.159855 -157.359936)
			(xy 387.110276 -157.337288) (xy 387.064424 -157.307815) (xy 387.023234 -157.272117) (xy 386.987543 -157.23092)
			(xy 386.958078 -157.185063) (xy 386.935439 -157.135479) (xy 386.920087 -157.083179) (xy 386.912334 -157.029226)
			(xy 386.91185 -157.001972) (xy 382.127975 -157.001972) (xy 382.131646 -157.014409) (xy 382.139477 -157.068583)
			(xy 382.139952 -157.095952) (xy 382.1394 -157.123202) (xy 382.131651 -157.177147) (xy 382.116303 -157.229441)
			(xy 382.093669 -157.279018) (xy 382.064211 -157.324869) (xy 382.028526 -157.366061) (xy 381.987343 -157.401755)
			(xy 381.941499 -157.431225) (xy 381.891927 -157.453871) (xy 381.839637 -157.469231) (xy 381.785694 -157.476994)
			(xy 381.758444 -157.47746) (xy 381.731074 -157.476978) (xy 381.676895 -157.469165) (xy 381.624392 -157.453681)
			(xy 381.574645 -157.430842) (xy 381.528678 -157.40112) (xy 381.507746 -157.38348) (xy 381.500634 -157.377384)
			(xy 381.483616 -157.371034) (xy 381.398272 -157.371034) (xy 381.381254 -157.377384) (xy 381.374142 -157.38348)
			(xy 381.353209 -157.401121) (xy 381.307241 -157.430845) (xy 381.257495 -157.453691) (xy 381.204993 -157.469187)
			(xy 381.150815 -157.477016) (xy 381.096073 -157.477016) (xy 381.041895 -157.469187) (xy 380.989393 -157.453691)
			(xy 380.939647 -157.430845) (xy 380.893679 -157.401121) (xy 380.872746 -157.38348) (xy 380.865634 -157.377384)
			(xy 380.848616 -157.371034) (xy 380.763272 -157.371034) (xy 380.746254 -157.377384) (xy 380.739142 -157.38348)
			(xy 380.718209 -157.401121) (xy 380.672241 -157.430845) (xy 380.622495 -157.453691) (xy 380.569993 -157.469187)
			(xy 380.515815 -157.477016) (xy 380.461073 -157.477016) (xy 380.406895 -157.469187) (xy 380.354393 -157.453691)
			(xy 380.304647 -157.430845) (xy 380.258679 -157.401121) (xy 380.237746 -157.38348) (xy 380.230634 -157.377384)
			(xy 380.213616 -157.371034) (xy 380.128272 -157.371034) (xy 380.111254 -157.377384) (xy 380.104142 -157.38348)
			(xy 380.083202 -157.40111) (xy 380.037232 -157.430824) (xy 379.987486 -157.453662) (xy 379.934987 -157.469155)
			(xy 379.880813 -157.476985) (xy 379.853444 -157.47746) (xy 379.82354 -157.476843) (xy 379.764464 -157.467504)
			(xy 379.707569 -157.449064) (xy 379.654247 -157.421974) (xy 379.605804 -157.386898) (xy 379.584204 -157.366208)
			(xy 379.577092 -157.359096) (xy 379.55982 -157.35173) (xy 379.470412 -157.348936) (xy 379.452632 -157.355286)
			(xy 379.445266 -157.36189) (xy 379.424251 -157.37974) (xy 379.378064 -157.409851) (xy 379.328024 -157.433002)
			(xy 379.275173 -157.448711) (xy 379.220612 -157.456652) (xy 379.193044 -157.45714) (xy 379.165794 -157.456604)
			(xy 379.111847 -157.448854) (xy 379.059552 -157.433505) (xy 379.009975 -157.41087) (xy 378.964123 -157.381409)
			(xy 378.92293 -157.345723) (xy 378.887236 -157.304538) (xy 378.857767 -157.258692) (xy 378.835122 -157.209119)
			(xy 378.819762 -157.156827) (xy 378.812002 -157.102882) (xy 378.811536 -157.075632) (xy 378.812012 -157.048262)
			(xy 378.819826 -156.994083) (xy 378.835312 -156.94158) (xy 378.858152 -156.891833) (xy 378.887875 -156.845866)
			(xy 378.905516 -156.824934) (xy 378.911612 -156.817822) (xy 378.917962 -156.800804) (xy 378.917962 -156.71546)
			(xy 378.911612 -156.698442) (xy 378.905516 -156.69133) (xy 378.88788 -156.670395) (xy 378.858167 -156.624424)
			(xy 378.83533 -156.574677) (xy 378.819839 -156.522176) (xy 378.81201 -156.468001) (xy 378.811536 -156.440632)
			(xy 378.812066 -156.411956) (xy 378.820635 -156.355248) (xy 378.837599 -156.300463) (xy 378.862576 -156.248836)
			(xy 378.895002 -156.201531) (xy 378.934147 -156.159616) (xy 378.956316 -156.14142) (xy 378.966222 -156.133546)
			(xy 378.976382 -156.110432) (xy 378.967746 -156.000704) (xy 378.95403 -155.979622) (xy 378.942854 -155.973272)
			(xy 378.917936 -155.958648) (xy 378.872393 -155.923103) (xy 378.832729 -155.881098) (xy 378.79985 -155.833593)
			(xy 378.774509 -155.781675) (xy 378.757285 -155.72653) (xy 378.74857 -155.669418) (xy 378.748036 -155.640532)
			(xy 376.6566 -155.640532) (xy 376.6566 -159.427926) (xy 414.223454 -159.427926) (xy 414.22394 -159.400675)
			(xy 414.231696 -159.346727) (xy 414.247051 -159.294432) (xy 414.269693 -159.244855) (xy 414.299159 -159.199005)
			(xy 414.33485 -159.157814) (xy 414.376041 -159.122123) (xy 414.421891 -159.092657) (xy 414.471468 -159.070015)
			(xy 414.523763 -159.05466) (xy 414.577711 -159.046904) (xy 414.632213 -159.046904) (xy 414.686161 -159.05466)
			(xy 414.738456 -159.070015) (xy 414.788033 -159.092657) (xy 414.833883 -159.122123) (xy 414.875074 -159.157814)
			(xy 414.910765 -159.199005) (xy 414.940231 -159.244855) (xy 414.962873 -159.294432) (xy 414.978228 -159.346727)
			(xy 414.985984 -159.400675) (xy 414.98647 -159.427926) (xy 414.985809 -159.459489) (xy 414.975423 -159.521754)
			(xy 414.954937 -159.581463) (xy 414.940496 -159.609536) (xy 414.93567 -159.618426) (xy 414.933638 -159.637984)
			(xy 414.959292 -159.726122) (xy 414.971738 -159.741616) (xy 414.980628 -159.746696) (xy 414.987994 -159.75076)
			(xy 414.997646 -159.756602) (xy 415.019744 -159.758634) (xy 415.114232 -159.725106) (xy 415.130234 -159.709612)
			(xy 415.134298 -159.699198) (xy 415.144978 -159.672415) (xy 415.173267 -159.622172) (xy 415.208799 -159.576762)
			(xy 415.250763 -159.537219) (xy 415.298203 -159.504446) (xy 415.350036 -159.479189) (xy 415.405082 -159.462026)
			(xy 415.462084 -159.453346) (xy 415.490914 -159.452818) (xy 415.518166 -159.453253) (xy 415.572116 -159.461011)
			(xy 415.624413 -159.476369) (xy 415.673992 -159.499012) (xy 415.719844 -159.528481) (xy 415.761035 -159.564175)
			(xy 415.796727 -159.605368) (xy 415.826194 -159.65122) (xy 415.848836 -159.7008) (xy 415.864192 -159.753097)
			(xy 415.871948 -159.807048) (xy 415.871948 -159.861552) (xy 415.864192 -159.915503) (xy 415.848836 -159.9678)
			(xy 415.826194 -160.01738) (xy 415.796727 -160.063232) (xy 415.761035 -160.104425) (xy 415.719844 -160.140119)
			(xy 415.673992 -160.169588) (xy 415.624413 -160.192231) (xy 415.572116 -160.207589) (xy 415.518166 -160.215347)
			(xy 415.490914 -160.215834) (xy 415.465679 -160.215426) (xy 415.415646 -160.208811) (xy 415.366925 -160.195641)
			(xy 415.320373 -160.176147) (xy 415.298382 -160.163764) (xy 415.28873 -160.157922) (xy 415.266632 -160.15589)
			(xy 415.172144 -160.189418) (xy 415.156142 -160.204912) (xy 415.152078 -160.215326) (xy 415.141347 -160.242087)
			(xy 415.113063 -160.292327) (xy 415.077537 -160.337735) (xy 415.03558 -160.377277) (xy 414.988148 -160.410052)
			(xy 414.936322 -160.435313) (xy 414.881285 -160.452484) (xy 414.824289 -160.461173) (xy 414.795462 -160.461706)
			(xy 414.76821 -160.461258) (xy 414.714261 -160.453496) (xy 414.661965 -160.438136) (xy 414.612388 -160.41549)
			(xy 414.566537 -160.38602) (xy 414.525347 -160.350324) (xy 414.489656 -160.309131) (xy 414.460191 -160.263277)
			(xy 414.43755 -160.213697) (xy 414.422196 -160.1614) (xy 414.41444 -160.10745) (xy 414.413954 -160.080198)
			(xy 414.414622 -160.048636) (xy 414.425005 -159.98637) (xy 414.445487 -159.926661) (xy 414.459928 -159.898588)
			(xy 414.464754 -159.889698) (xy 414.466786 -159.87014) (xy 414.441132 -159.782002) (xy 414.428686 -159.766508)
			(xy 414.419796 -159.761428) (xy 414.394678 -159.746907) (xy 414.348796 -159.711399) (xy 414.308822 -159.66935)
			(xy 414.275679 -159.621732) (xy 414.250131 -159.569642) (xy 414.232768 -159.514284) (xy 414.223991 -159.456935)
			(xy 414.223454 -159.427926) (xy 376.6566 -159.427926) (xy 376.6566 -161.701988) (xy 410.43733 -161.701988)
			(xy 410.437846 -161.674415) (xy 410.445787 -161.619844) (xy 410.461501 -161.566985) (xy 410.484662 -161.516938)
			(xy 410.514786 -161.470747) (xy 410.551246 -161.429375) (xy 410.57195 -161.411158) (xy 410.580091 -161.403576)
			(xy 410.589431 -161.383409) (xy 410.589984 -161.372296) (xy 410.589984 -161.29508) (xy 410.589448 -161.283966)
			(xy 410.580088 -161.263807) (xy 410.57195 -161.256218) (xy 410.55123 -161.238017) (xy 410.514762 -161.196645)
			(xy 410.484632 -161.150454) (xy 410.461467 -161.100405) (xy 410.44575 -161.047542) (xy 410.43781 -160.992967)
			(xy 410.437811 -160.937817) (xy 410.445754 -160.883243) (xy 410.461472 -160.83038) (xy 410.484639 -160.780332)
			(xy 410.514772 -160.734142) (xy 410.551241 -160.692772) (xy 410.57195 -160.674558) (xy 410.580091 -160.666976)
			(xy 410.589431 -160.646809) (xy 410.589984 -160.635696) (xy 410.589984 -160.55848) (xy 410.589448 -160.547366)
			(xy 410.580088 -160.527207) (xy 410.57195 -160.519618) (xy 410.551234 -160.501412) (xy 410.514767 -160.460041)
			(xy 410.484636 -160.413849) (xy 410.461472 -160.363801) (xy 410.445756 -160.310938) (xy 410.437816 -160.256363)
			(xy 410.43733 -160.228788) (xy 410.437744 -160.201533) (xy 410.445503 -160.147578) (xy 410.460863 -160.095277)
			(xy 410.48351 -160.045694) (xy 410.512982 -159.99984) (xy 410.548681 -159.958646) (xy 410.58988 -159.922952)
			(xy 410.635738 -159.893486) (xy 410.685324 -159.870845) (xy 410.737627 -159.855493) (xy 410.791583 -159.84774)
			(xy 410.818838 -159.84728) (xy 410.846694 -159.847784) (xy 410.901809 -159.855912) (xy 410.955159 -159.871962)
			(xy 411.005611 -159.895592) (xy 411.052095 -159.926301) (xy 411.093624 -159.963438) (xy 411.129317 -160.006215)
			(xy 411.158417 -160.053723) (xy 411.180305 -160.104955) (xy 411.1879 -160.13176) (xy 411.190186 -160.14065)
			(xy 411.200854 -160.15589) (xy 411.272736 -160.203642) (xy 411.29077 -160.207706) (xy 411.299914 -160.206436)
			(xy 411.312931 -160.204767) (xy 411.339115 -160.202987) (xy 411.352238 -160.20288) (xy 411.366387 -160.20297)
			(xy 411.39461 -160.205007) (xy 411.408626 -160.206944) (xy 411.418786 -160.208468) (xy 411.438344 -160.203642)
			(xy 411.512766 -160.147762) (xy 411.522926 -160.130236) (xy 411.524196 -160.120076) (xy 411.528288 -160.092923)
			(xy 411.543259 -160.040092) (xy 411.565649 -159.989953) (xy 411.594995 -159.943541) (xy 411.630692 -159.901816)
			(xy 411.672002 -159.865639) (xy 411.718071 -159.835758) (xy 411.767948 -159.81279) (xy 411.820602 -159.797209)
			(xy 411.874946 -159.789337) (xy 411.902402 -159.78886) (xy 411.929652 -159.789376) (xy 411.983597 -159.797132)
			(xy 412.035889 -159.812486) (xy 412.085464 -159.835125) (xy 412.131313 -159.864588) (xy 412.172502 -159.900276)
			(xy 412.208194 -159.941463) (xy 412.237661 -159.987309) (xy 412.260304 -160.036883) (xy 412.275662 -160.089174)
			(xy 412.283422 -160.143118) (xy 412.28391 -160.170368) (xy 412.283419 -160.197942) (xy 412.275471 -160.252513)
			(xy 412.259751 -160.305372) (xy 412.236585 -160.355418) (xy 412.206458 -160.401609) (xy 412.169995 -160.442981)
			(xy 412.14929 -160.461198) (xy 412.141175 -160.468804) (xy 412.131819 -160.488953) (xy 412.131256 -160.50006)
			(xy 412.131256 -160.577276) (xy 412.131804 -160.588389) (xy 412.141155 -160.608548) (xy 412.14929 -160.616138)
			(xy 412.170021 -160.634328) (xy 412.20649 -160.675701) (xy 412.23662 -160.721895) (xy 412.259782 -160.771947)
			(xy 412.275494 -160.824814) (xy 412.283428 -160.879392) (xy 412.283462 -160.881314) (xy 416.872418 -160.881314)
			(xy 416.876489 -160.825692) (xy 416.888615 -160.771255) (xy 416.908538 -160.719164) (xy 416.935834 -160.670529)
			(xy 416.96992 -160.626386) (xy 417.010069 -160.587677) (xy 417.055427 -160.555226) (xy 417.105027 -160.529725)
			(xy 417.157811 -160.511718) (xy 417.212654 -160.501588) (xy 417.268388 -160.499551) (xy 417.323825 -160.505651)
			(xy 417.377782 -160.519757) (xy 417.429111 -160.541569) (xy 417.476717 -160.570623) (xy 417.519585 -160.606298)
			(xy 417.556802 -160.647835) (xy 417.587575 -160.694348) (xy 417.611247 -160.744845) (xy 417.627315 -160.798252)
			(xy 417.635435 -160.853428) (xy 417.635944 -160.881314) (xy 417.635435 -160.9092) (xy 417.627315 -160.964376)
			(xy 417.611247 -161.017783) (xy 417.587575 -161.06828) (xy 417.556802 -161.114793) (xy 417.519585 -161.15633)
			(xy 417.476717 -161.192005) (xy 417.429111 -161.221059) (xy 417.377782 -161.242871) (xy 417.323825 -161.256977)
			(xy 417.268388 -161.263077) (xy 417.212654 -161.26104) (xy 417.157811 -161.25091) (xy 417.105027 -161.232903)
			(xy 417.055427 -161.207402) (xy 417.010069 -161.174951) (xy 416.96992 -161.136242) (xy 416.935834 -161.092099)
			(xy 416.908538 -161.043464) (xy 416.888615 -160.991373) (xy 416.876489 -160.936936) (xy 416.872418 -160.881314)
			(xy 412.283462 -160.881314) (xy 412.28391 -160.906968) (xy 412.283415 -160.93422) (xy 412.275662 -160.98817)
			(xy 412.26031 -161.040467) (xy 412.237672 -161.090047) (xy 412.208207 -161.1359) (xy 412.172517 -161.177093)
			(xy 412.131327 -161.212787) (xy 412.085477 -161.242256) (xy 412.035899 -161.264899) (xy 411.983603 -161.280255)
			(xy 411.929654 -161.288013) (xy 411.902402 -161.288476) (xy 411.868112 -161.286952) (xy 411.857952 -161.285936)
			(xy 411.838648 -161.292032) (xy 411.768036 -161.351214) (xy 411.758638 -161.369248) (xy 411.757622 -161.379408)
			(xy 411.75463 -161.407576) (xy 411.741462 -161.462667) (xy 411.720289 -161.515204) (xy 411.691577 -161.56403)
			(xy 411.655957 -161.608072) (xy 411.614214 -161.646359) (xy 411.567266 -161.67805) (xy 411.516147 -161.702447)
			(xy 411.46198 -161.719013) (xy 411.405959 -161.727383) (xy 411.377638 -161.727896) (xy 411.359619 -161.72768)
			(xy 411.323744 -161.724243) (xy 411.30601 -161.721038) (xy 411.296612 -161.71926) (xy 411.277562 -161.72307)
			(xy 411.202378 -161.770822) (xy 411.190948 -161.78657) (xy 411.188662 -161.795968) (xy 411.181299 -161.823022)
			(xy 411.159665 -161.87475) (xy 411.130696 -161.922756) (xy 411.095016 -161.966007) (xy 411.053392 -162.003573)
			(xy 411.006721 -162.034646) (xy 410.956005 -162.058557) (xy 410.902338 -162.074791) (xy 410.846873 -162.082999)
			(xy 410.818838 -162.083496) (xy 410.791586 -162.083009) (xy 410.737635 -162.075257) (xy 410.685337 -162.059905)
			(xy 410.635756 -162.037266) (xy 410.589902 -162.007801) (xy 410.548709 -161.97211) (xy 410.513014 -161.930919)
			(xy 410.483546 -161.885067) (xy 410.460904 -161.835488) (xy 410.445548 -161.783191) (xy 410.437793 -161.72924)
			(xy 410.43733 -161.701988) (xy 376.6566 -161.701988) (xy 376.6566 -162.104578) (xy 376.655972 -162.129575)
			(xy 376.646169 -162.178599) (xy 376.626993 -162.22477) (xy 376.599181 -162.266315) (xy 376.581924 -162.28441)
			(xy 376.227156 -162.639178) (xy 376.980954 -162.639178) (xy 376.980954 -162.554482) (xy 376.989005 -162.470168)
			(xy 377.005034 -162.387002) (xy 377.028895 -162.305735) (xy 377.060374 -162.227105) (xy 377.099185 -162.151824)
			(xy 377.144975 -162.080572) (xy 377.197331 -162.013996) (xy 377.255779 -161.952698) (xy 377.319789 -161.897233)
			(xy 377.388781 -161.848104) (xy 377.462131 -161.805755) (xy 377.539174 -161.770571) (xy 377.619213 -161.742869)
			(xy 377.701522 -161.722901) (xy 377.785357 -161.710848) (xy 377.869958 -161.706818) (xy 377.954559 -161.710848)
			(xy 378.038394 -161.722901) (xy 378.120703 -161.742869) (xy 378.200742 -161.770571) (xy 378.277785 -161.805755)
			(xy 378.351135 -161.848104) (xy 378.420127 -161.897233) (xy 378.484137 -161.952698) (xy 378.542585 -162.013996)
			(xy 378.594941 -162.080572) (xy 378.640731 -162.151824) (xy 378.679542 -162.227105) (xy 378.711021 -162.305735)
			(xy 378.734882 -162.387002) (xy 378.750911 -162.470168) (xy 378.758962 -162.554482) (xy 378.759466 -162.59683)
			(xy 378.758962 -162.639178) (xy 378.753626 -162.695058) (xy 386.317994 -162.695058) (xy 386.317994 -162.610362)
			(xy 386.326045 -162.526048) (xy 386.342074 -162.442882) (xy 386.365935 -162.361615) (xy 386.397414 -162.282985)
			(xy 386.436225 -162.207704) (xy 386.482015 -162.136452) (xy 386.534371 -162.069876) (xy 386.592819 -162.008578)
			(xy 386.656829 -161.953113) (xy 386.725821 -161.903984) (xy 386.799171 -161.861635) (xy 386.876214 -161.826451)
			(xy 386.956253 -161.798749) (xy 387.038562 -161.778781) (xy 387.122397 -161.766728) (xy 387.206998 -161.762698)
			(xy 387.291599 -161.766728) (xy 387.375434 -161.778781) (xy 387.457743 -161.798749) (xy 387.537782 -161.826451)
			(xy 387.614825 -161.861635) (xy 387.688175 -161.903984) (xy 387.757167 -161.953113) (xy 387.821177 -162.008578)
			(xy 387.879625 -162.069876) (xy 387.931981 -162.136452) (xy 387.977771 -162.207704) (xy 388.016582 -162.282985)
			(xy 388.048061 -162.361615) (xy 388.071922 -162.442882) (xy 388.087951 -162.526048) (xy 388.096002 -162.610362)
			(xy 388.096506 -162.65271) (xy 388.096002 -162.695058) (xy 388.087951 -162.779372) (xy 388.071922 -162.862538)
			(xy 388.048061 -162.943805) (xy 388.016582 -163.022435) (xy 387.977771 -163.097716) (xy 387.931981 -163.168968)
			(xy 387.879625 -163.235544) (xy 387.859916 -163.256214) (xy 412.105348 -163.256214) (xy 412.105858 -163.227297)
			(xy 412.114586 -163.170124) (xy 412.131845 -163.114924) (xy 412.157238 -163.062962) (xy 412.190184 -163.015429)
			(xy 412.229927 -162.973413) (xy 412.252414 -162.955224) (xy 412.261163 -162.94765) (xy 412.271353 -162.9269)
			(xy 412.271972 -162.915346) (xy 412.271972 -162.835082) (xy 412.271422 -162.823511) (xy 412.261214 -162.80274)
			(xy 412.252414 -162.795204) (xy 412.229935 -162.777007) (xy 412.190199 -162.734989) (xy 412.157259 -162.687456)
			(xy 412.13187 -162.635495) (xy 412.114613 -162.580299) (xy 412.105883 -162.52313) (xy 412.105348 -162.494214)
			(xy 412.105894 -162.466154) (xy 412.114126 -162.410641) (xy 412.1304 -162.356932) (xy 412.154364 -162.306186)
			(xy 412.185502 -162.259497) (xy 412.223142 -162.217872) (xy 412.266473 -162.182208) (xy 412.29026 -162.167316)
			(xy 412.299912 -162.161474) (xy 412.312104 -162.14344) (xy 412.329122 -162.04565) (xy 412.323534 -162.024568)
			(xy 412.316422 -162.015678) (xy 412.300531 -161.995603) (xy 412.273783 -161.951945) (xy 412.253257 -161.905041)
			(xy 412.239338 -161.855769) (xy 412.232287 -161.805057) (xy 412.23184 -161.779458) (xy 412.232317 -161.752843)
			(xy 412.239898 -161.700154) (xy 412.254898 -161.649081) (xy 412.277014 -161.600662) (xy 412.305794 -161.555882)
			(xy 412.340653 -161.515653) (xy 412.380882 -161.480794) (xy 412.425662 -161.452014) (xy 412.474081 -161.429898)
			(xy 412.525154 -161.414898) (xy 412.577843 -161.407317) (xy 412.604458 -161.40684) (xy 412.63088 -161.407278)
			(xy 412.683196 -161.414735) (xy 412.733934 -161.429505) (xy 412.782078 -161.451293) (xy 412.826663 -161.479661)
			(xy 412.847028 -161.496502) (xy 412.853886 -161.502598) (xy 412.870904 -161.508694) (xy 412.955232 -161.508694)
			(xy 412.97225 -161.502598) (xy 412.979108 -161.496502) (xy 412.999474 -161.479663) (xy 413.04406 -161.451298)
			(xy 413.092204 -161.429511) (xy 413.142941 -161.41474) (xy 413.195256 -161.40728) (xy 413.2481 -161.40728)
			(xy 413.300415 -161.41474) (xy 413.351152 -161.429511) (xy 413.399296 -161.451298) (xy 413.443882 -161.479663)
			(xy 413.464248 -161.496502) (xy 413.471106 -161.502598) (xy 413.488124 -161.508694) (xy 413.572452 -161.508694)
			(xy 413.58947 -161.502598) (xy 413.596328 -161.496502) (xy 413.616683 -161.479651) (xy 413.661276 -161.451298)
			(xy 413.709423 -161.429521) (xy 413.760162 -161.414756) (xy 413.812476 -161.407299) (xy 413.838898 -161.40684)
			(xy 413.866782 -161.407419) (xy 413.921926 -161.415731) (xy 413.975216 -161.432168) (xy 414.025461 -161.456364)
			(xy 414.071538 -161.487779) (xy 414.112419 -161.525711) (xy 414.147189 -161.569311) (xy 414.175073 -161.617607)
			(xy 414.195447 -161.669519) (xy 414.207856 -161.723889) (xy 414.212024 -161.7795) (xy 414.207856 -161.835111)
			(xy 414.195447 -161.889481) (xy 414.175073 -161.941393) (xy 414.147189 -161.989689) (xy 414.112419 -162.033289)
			(xy 414.071538 -162.071221) (xy 414.025461 -162.102636) (xy 413.975216 -162.126832) (xy 413.921926 -162.143269)
			(xy 413.866782 -162.151581) (xy 413.838898 -162.152076) (xy 413.812477 -162.151601) (xy 413.760163 -162.144153)
			(xy 413.709425 -162.129391) (xy 413.661281 -162.107611) (xy 413.616695 -162.079251) (xy 413.596328 -162.062414)
			(xy 413.58947 -162.056318) (xy 413.572452 -162.050222) (xy 413.488124 -162.050222) (xy 413.471106 -162.056318)
			(xy 413.464248 -162.062414) (xy 413.443882 -162.079253) (xy 413.399296 -162.107618) (xy 413.351152 -162.129405)
			(xy 413.300415 -162.144176) (xy 413.2481 -162.151636) (xy 413.195256 -162.151636) (xy 413.142941 -162.144176)
			(xy 413.092204 -162.129405) (xy 413.04406 -162.107618) (xy 412.999474 -162.079253) (xy 412.979108 -162.062414)
			(xy 412.97225 -162.056318) (xy 412.955232 -162.050222) (xy 412.870904 -162.050222) (xy 412.853886 -162.056318)
			(xy 412.847028 -162.062414) (xy 412.836226 -162.071478) (xy 412.813466 -162.088129) (xy 412.801562 -162.095688)
			(xy 412.79191 -162.10153) (xy 412.779972 -162.119818) (xy 412.764732 -162.218116) (xy 412.770574 -162.238944)
			(xy 412.77794 -162.24758) (xy 412.794941 -162.268341) (xy 412.823546 -162.31374) (xy 412.845507 -162.3627)
			(xy 412.860393 -162.414253) (xy 412.867909 -162.467384) (xy 412.868364 -162.494214) (xy 412.867797 -162.523129)
			(xy 412.85908 -162.580299) (xy 412.841833 -162.635497) (xy 412.81645 -162.687459) (xy 412.783514 -162.734994)
			(xy 412.761405 -162.758374) (xy 417.83127 -162.758374) (xy 417.831752 -162.730463) (xy 417.83989 -162.675237)
			(xy 417.855988 -162.621786) (xy 417.879703 -162.571252) (xy 417.910529 -162.524712) (xy 417.928806 -162.503612)
			(xy 417.935156 -162.4965) (xy 417.94176 -162.479228) (xy 417.94176 -162.392106) (xy 417.935156 -162.374834)
			(xy 417.928806 -162.367722) (xy 417.910518 -162.346631) (xy 417.879692 -162.30009) (xy 417.855978 -162.249554)
			(xy 417.839884 -162.1961) (xy 417.831753 -162.140872) (xy 417.83127 -162.11296) (xy 417.831756 -162.085709)
			(xy 417.839512 -162.031761) (xy 417.854867 -161.979466) (xy 417.877509 -161.929889) (xy 417.906975 -161.884039)
			(xy 417.942666 -161.842848) (xy 417.983857 -161.807157) (xy 418.029707 -161.777691) (xy 418.079284 -161.755049)
			(xy 418.131579 -161.739694) (xy 418.185527 -161.731938) (xy 418.240029 -161.731938) (xy 418.293977 -161.739694)
			(xy 418.346272 -161.755049) (xy 418.395849 -161.777691) (xy 418.441699 -161.807157) (xy 418.48289 -161.842848)
			(xy 418.518581 -161.884039) (xy 418.548047 -161.929889) (xy 418.570689 -161.979466) (xy 418.586044 -162.031761)
			(xy 418.5938 -162.085709) (xy 418.594286 -162.11296) (xy 418.59381 -162.140871) (xy 418.585669 -162.196097)
			(xy 418.569568 -162.249547) (xy 418.545852 -162.300082) (xy 418.515027 -162.346621) (xy 418.49675 -162.367722)
			(xy 418.4904 -162.374834) (xy 418.483796 -162.392106) (xy 418.483796 -162.479228) (xy 418.4904 -162.4965)
			(xy 418.49675 -162.503612) (xy 418.515016 -162.524721) (xy 418.545843 -162.571258) (xy 418.56956 -162.62179)
			(xy 418.58566 -162.675239) (xy 418.593798 -162.730464) (xy 418.594286 -162.758374) (xy 418.5938 -162.785625)
			(xy 418.586044 -162.839573) (xy 418.570689 -162.891868) (xy 418.548047 -162.941445) (xy 418.518581 -162.987295)
			(xy 418.48289 -163.028486) (xy 418.441699 -163.064177) (xy 418.395849 -163.093643) (xy 418.346272 -163.116285)
			(xy 418.293977 -163.13164) (xy 418.240029 -163.139396) (xy 418.185527 -163.139396) (xy 418.131579 -163.13164)
			(xy 418.079284 -163.116285) (xy 418.029707 -163.093643) (xy 417.983857 -163.064177) (xy 417.942666 -163.028486)
			(xy 417.906975 -162.987295) (xy 417.877509 -162.941445) (xy 417.854867 -162.891868) (xy 417.839512 -162.839573)
			(xy 417.831756 -162.785625) (xy 417.83127 -162.758374) (xy 412.761405 -162.758374) (xy 412.74378 -162.777013)
			(xy 412.721298 -162.795204) (xy 412.712538 -162.802768) (xy 412.702354 -162.823525) (xy 412.70174 -162.835082)
			(xy 412.70174 -162.915346) (xy 412.702327 -162.926912) (xy 412.712509 -162.947684) (xy 412.721298 -162.955224)
			(xy 412.743793 -162.973402) (xy 412.783527 -163.015424) (xy 412.816465 -163.062962) (xy 412.841851 -163.114926)
			(xy 412.859105 -163.170126) (xy 412.867831 -163.227297) (xy 412.868364 -163.256214) (xy 412.867878 -163.283465)
			(xy 412.860122 -163.337413) (xy 412.844767 -163.389708) (xy 412.822125 -163.439285) (xy 412.792659 -163.485135)
			(xy 412.756968 -163.526326) (xy 412.715777 -163.562017) (xy 412.669927 -163.591483) (xy 412.62035 -163.614125)
			(xy 412.568055 -163.62948) (xy 412.514107 -163.637236) (xy 412.459605 -163.637236) (xy 412.405657 -163.62948)
			(xy 412.353362 -163.614125) (xy 412.303785 -163.591483) (xy 412.257935 -163.562017) (xy 412.216744 -163.526326)
			(xy 412.181053 -163.485135) (xy 412.151587 -163.439285) (xy 412.128945 -163.389708) (xy 412.11359 -163.337413)
			(xy 412.105834 -163.283465) (xy 412.105348 -163.256214) (xy 387.859916 -163.256214) (xy 387.821177 -163.296842)
			(xy 387.757167 -163.352307) (xy 387.688175 -163.401436) (xy 387.614825 -163.443785) (xy 387.537782 -163.478969)
			(xy 387.457743 -163.506671) (xy 387.375434 -163.526639) (xy 387.291599 -163.538692) (xy 387.206998 -163.542723)
			(xy 387.122397 -163.538692) (xy 387.038562 -163.526639) (xy 386.956253 -163.506671) (xy 386.876214 -163.478969)
			(xy 386.799171 -163.443785) (xy 386.725821 -163.401436) (xy 386.656829 -163.352307) (xy 386.592819 -163.296842)
			(xy 386.534371 -163.235544) (xy 386.482015 -163.168968) (xy 386.436225 -163.097716) (xy 386.397414 -163.022435)
			(xy 386.365935 -162.943805) (xy 386.342074 -162.862538) (xy 386.326045 -162.779372) (xy 386.317994 -162.695058)
			(xy 378.753626 -162.695058) (xy 378.750911 -162.723492) (xy 378.734882 -162.806658) (xy 378.711021 -162.887925)
			(xy 378.679542 -162.966555) (xy 378.640731 -163.041836) (xy 378.594941 -163.113088) (xy 378.542585 -163.179664)
			(xy 378.484137 -163.240962) (xy 378.420127 -163.296427) (xy 378.351135 -163.345556) (xy 378.277785 -163.387905)
			(xy 378.200742 -163.423089) (xy 378.120703 -163.450791) (xy 378.038394 -163.470759) (xy 377.954559 -163.482812)
			(xy 377.869958 -163.486843) (xy 377.785357 -163.482812) (xy 377.701522 -163.470759) (xy 377.619213 -163.450791)
			(xy 377.539174 -163.423089) (xy 377.462131 -163.387905) (xy 377.388781 -163.345556) (xy 377.319789 -163.296427)
			(xy 377.255779 -163.240962) (xy 377.197331 -163.179664) (xy 377.144975 -163.113088) (xy 377.099185 -163.041836)
			(xy 377.060374 -162.966555) (xy 377.028895 -162.887925) (xy 377.005034 -162.806658) (xy 376.989005 -162.723492)
			(xy 376.980954 -162.639178) (xy 376.227156 -162.639178) (xy 373.769382 -165.096952) (xy 376.903749 -165.096952)
			(xy 376.907752 -165.00909) (xy 376.919728 -164.921956) (xy 376.939579 -164.836272) (xy 376.967138 -164.752748)
			(xy 377.002179 -164.672076) (xy 377.04441 -164.594925) (xy 377.093482 -164.521934) (xy 377.148989 -164.453708)
			(xy 377.210469 -164.390812) (xy 377.277414 -164.333767) (xy 377.349269 -164.283046) (xy 377.425439 -164.239069)
			(xy 377.505292 -164.202201) (xy 377.588167 -164.172748) (xy 377.673377 -164.150952) (xy 377.760216 -164.136996)
			(xy 377.847964 -164.130993) (xy 377.935894 -164.132995) (xy 378.023279 -164.142985) (xy 378.109392 -164.16088)
			(xy 378.193522 -164.186531) (xy 378.27497 -164.219726) (xy 378.353063 -164.26019) (xy 378.427152 -164.307588)
			(xy 378.496624 -164.361527) (xy 378.560903 -164.42156) (xy 378.619457 -164.487189) (xy 378.671801 -164.557871)
			(xy 378.7175 -164.63302) (xy 378.756176 -164.712013) (xy 378.787508 -164.794196) (xy 378.811238 -164.878888)
			(xy 378.827168 -164.965387) (xy 378.835166 -165.052975) (xy 378.835666 -165.096952) (xy 378.835166 -165.140929)
			(xy 378.834079 -165.152832) (xy 386.240789 -165.152832) (xy 386.244792 -165.06497) (xy 386.256768 -164.977836)
			(xy 386.276619 -164.892152) (xy 386.304178 -164.808628) (xy 386.339219 -164.727956) (xy 386.38145 -164.650805)
			(xy 386.430522 -164.577814) (xy 386.486029 -164.509588) (xy 386.547509 -164.446692) (xy 386.614454 -164.389647)
			(xy 386.686309 -164.338926) (xy 386.762479 -164.294949) (xy 386.842332 -164.258081) (xy 386.925207 -164.228628)
			(xy 387.010417 -164.206832) (xy 387.097256 -164.192876) (xy 387.185004 -164.186873) (xy 387.272934 -164.188875)
			(xy 387.360319 -164.198865) (xy 387.446432 -164.21676) (xy 387.530562 -164.242411) (xy 387.558815 -164.253926)
			(xy 405.841454 -164.253926) (xy 405.84194 -164.226675) (xy 405.849696 -164.172727) (xy 405.865051 -164.120432)
			(xy 405.887693 -164.070855) (xy 405.917159 -164.025005) (xy 405.95285 -163.983814) (xy 405.994041 -163.948123)
			(xy 406.039891 -163.918657) (xy 406.089468 -163.896015) (xy 406.141763 -163.88066) (xy 406.195711 -163.872904)
			(xy 406.250213 -163.872904) (xy 406.304161 -163.88066) (xy 406.356456 -163.896015) (xy 406.406033 -163.918657)
			(xy 406.451883 -163.948123) (xy 406.493074 -163.983814) (xy 406.528765 -164.025005) (xy 406.558231 -164.070855)
			(xy 406.580873 -164.120432) (xy 406.596228 -164.172727) (xy 406.603984 -164.226675) (xy 406.60447 -164.253926)
			(xy 406.603809 -164.285489) (xy 406.593423 -164.347754) (xy 406.572937 -164.407463) (xy 406.558496 -164.435536)
			(xy 406.55367 -164.444426) (xy 406.551638 -164.463984) (xy 406.577292 -164.552122) (xy 406.589738 -164.567616)
			(xy 406.598628 -164.572696) (xy 406.605994 -164.57676) (xy 406.615646 -164.582602) (xy 406.637744 -164.584634)
			(xy 406.732232 -164.551106) (xy 406.748234 -164.535612) (xy 406.752298 -164.525198) (xy 406.762978 -164.498415)
			(xy 406.791267 -164.448172) (xy 406.826799 -164.402762) (xy 406.868763 -164.363219) (xy 406.916203 -164.330446)
			(xy 406.968036 -164.305189) (xy 407.023082 -164.288026) (xy 407.080084 -164.279346) (xy 407.108914 -164.278818)
			(xy 407.136166 -164.279253) (xy 407.190116 -164.287011) (xy 407.242413 -164.302369) (xy 407.291992 -164.325012)
			(xy 407.337844 -164.354481) (xy 407.379035 -164.390175) (xy 407.414727 -164.431368) (xy 407.444194 -164.47722)
			(xy 407.466836 -164.5268) (xy 407.482192 -164.579097) (xy 407.489948 -164.633048) (xy 407.489948 -164.687552)
			(xy 407.482192 -164.741503) (xy 407.472839 -164.773356) (xy 407.731722 -164.773356) (xy 407.732177 -164.74588)
			(xy 407.740076 -164.691499) (xy 407.755703 -164.638816) (xy 407.778735 -164.588924) (xy 407.808693 -164.542857)
			(xy 407.826464 -164.521896) (xy 407.83256 -164.514784) (xy 407.83891 -164.497766) (xy 407.83891 -164.411914)
			(xy 407.83256 -164.394896) (xy 407.826464 -164.387784) (xy 407.808706 -164.366817) (xy 407.778781 -164.320736)
			(xy 407.755768 -164.270843) (xy 407.740141 -164.218167) (xy 407.732222 -164.163796) (xy 407.731722 -164.136324)
			(xy 407.732208 -164.109073) (xy 407.739964 -164.055125) (xy 407.755319 -164.00283) (xy 407.777961 -163.953253)
			(xy 407.807427 -163.907403) (xy 407.843118 -163.866212) (xy 407.884309 -163.830521) (xy 407.930159 -163.801055)
			(xy 407.979736 -163.778413) (xy 408.032031 -163.763058) (xy 408.085979 -163.755302) (xy 408.140481 -163.755302)
			(xy 408.194429 -163.763058) (xy 408.246724 -163.778413) (xy 408.296301 -163.801055) (xy 408.342151 -163.830521)
			(xy 408.383342 -163.866212) (xy 408.419033 -163.907403) (xy 408.448499 -163.953253) (xy 408.471141 -164.00283)
			(xy 408.486496 -164.055125) (xy 408.494252 -164.109073) (xy 408.494738 -164.136324) (xy 408.494256 -164.163799)
			(xy 408.486362 -164.218178) (xy 408.47074 -164.27086) (xy 408.447715 -164.320753) (xy 408.417763 -164.366822)
			(xy 408.399996 -164.387784) (xy 408.3939 -164.394896) (xy 408.38755 -164.411914) (xy 408.38755 -164.497766)
			(xy 408.3939 -164.514784) (xy 408.399996 -164.521896) (xy 408.417738 -164.542876) (xy 408.447667 -164.588952)
			(xy 408.470684 -164.638842) (xy 408.486314 -164.691515) (xy 408.494236 -164.745885) (xy 408.494738 -164.773356)
			(xy 408.494252 -164.800607) (xy 408.492619 -164.811964) (xy 409.069538 -164.811964) (xy 409.073609 -164.756342)
			(xy 409.085735 -164.701905) (xy 409.105658 -164.649814) (xy 409.132954 -164.601179) (xy 409.16704 -164.557036)
			(xy 409.207189 -164.518327) (xy 409.252547 -164.485876) (xy 409.302147 -164.460375) (xy 409.354931 -164.442368)
			(xy 409.409774 -164.432238) (xy 409.465508 -164.430201) (xy 409.520945 -164.436301) (xy 409.574902 -164.450407)
			(xy 409.626231 -164.472219) (xy 409.673837 -164.501273) (xy 409.716705 -164.536948) (xy 409.753922 -164.578485)
			(xy 409.784695 -164.624998) (xy 409.808367 -164.675495) (xy 409.824435 -164.728902) (xy 409.832555 -164.784078)
			(xy 409.833064 -164.811964) (xy 409.832555 -164.83985) (xy 409.824435 -164.895026) (xy 409.808367 -164.948433)
			(xy 409.784695 -164.99893) (xy 409.753922 -165.045443) (xy 409.716705 -165.08698) (xy 409.673837 -165.122655)
			(xy 409.626231 -165.151709) (xy 409.574902 -165.173521) (xy 409.520945 -165.187627) (xy 409.465508 -165.193727)
			(xy 409.409774 -165.19169) (xy 409.354931 -165.18156) (xy 409.302147 -165.163553) (xy 409.252547 -165.138052)
			(xy 409.207189 -165.105601) (xy 409.16704 -165.066892) (xy 409.132954 -165.022749) (xy 409.105658 -164.974114)
			(xy 409.085735 -164.922023) (xy 409.073609 -164.867586) (xy 409.069538 -164.811964) (xy 408.492619 -164.811964)
			(xy 408.486496 -164.854555) (xy 408.471141 -164.90685) (xy 408.448499 -164.956427) (xy 408.419033 -165.002277)
			(xy 408.383342 -165.043468) (xy 408.342151 -165.079159) (xy 408.296301 -165.108625) (xy 408.246724 -165.131267)
			(xy 408.194429 -165.146622) (xy 408.140481 -165.154378) (xy 408.085979 -165.154378) (xy 408.032031 -165.146622)
			(xy 407.979736 -165.131267) (xy 407.930159 -165.108625) (xy 407.884309 -165.079159) (xy 407.843118 -165.043468)
			(xy 407.807427 -165.002277) (xy 407.777961 -164.956427) (xy 407.755319 -164.90685) (xy 407.739964 -164.854555)
			(xy 407.732208 -164.800607) (xy 407.731722 -164.773356) (xy 407.472839 -164.773356) (xy 407.466836 -164.7938)
			(xy 407.444194 -164.84338) (xy 407.414727 -164.889232) (xy 407.379035 -164.930425) (xy 407.337844 -164.966119)
			(xy 407.291992 -164.995588) (xy 407.242413 -165.018231) (xy 407.190116 -165.033589) (xy 407.136166 -165.041347)
			(xy 407.108914 -165.041834) (xy 407.083679 -165.041426) (xy 407.033646 -165.034811) (xy 406.984925 -165.021641)
			(xy 406.938373 -165.002147) (xy 406.916382 -164.989764) (xy 406.90673 -164.983922) (xy 406.884632 -164.98189)
			(xy 406.790144 -165.015418) (xy 406.774142 -165.030912) (xy 406.770078 -165.041326) (xy 406.759347 -165.068087)
			(xy 406.731063 -165.118327) (xy 406.695537 -165.163735) (xy 406.65358 -165.203277) (xy 406.606148 -165.236052)
			(xy 406.554322 -165.261313) (xy 406.499285 -165.278484) (xy 406.442289 -165.287173) (xy 406.413462 -165.287706)
			(xy 406.38621 -165.287258) (xy 406.332261 -165.279496) (xy 406.279965 -165.264136) (xy 406.230388 -165.24149)
			(xy 406.184537 -165.21202) (xy 406.143347 -165.176324) (xy 406.107656 -165.135131) (xy 406.078191 -165.089277)
			(xy 406.05555 -165.039697) (xy 406.040196 -164.9874) (xy 406.03244 -164.93345) (xy 406.031954 -164.906198)
			(xy 406.032622 -164.874636) (xy 406.043005 -164.81237) (xy 406.063487 -164.752661) (xy 406.077928 -164.724588)
			(xy 406.082754 -164.715698) (xy 406.084786 -164.69614) (xy 406.059132 -164.608002) (xy 406.046686 -164.592508)
			(xy 406.037796 -164.587428) (xy 406.012678 -164.572907) (xy 405.966796 -164.537399) (xy 405.926822 -164.49535)
			(xy 405.893679 -164.447732) (xy 405.868131 -164.395642) (xy 405.850768 -164.340284) (xy 405.841991 -164.282935)
			(xy 405.841454 -164.253926) (xy 387.558815 -164.253926) (xy 387.61201 -164.275606) (xy 387.690103 -164.31607)
			(xy 387.764192 -164.363468) (xy 387.833664 -164.417407) (xy 387.897943 -164.47744) (xy 387.956497 -164.543069)
			(xy 388.008841 -164.613751) (xy 388.05454 -164.6889) (xy 388.093216 -164.767893) (xy 388.124548 -164.850076)
			(xy 388.148278 -164.934768) (xy 388.164208 -165.021267) (xy 388.172206 -165.108855) (xy 388.172706 -165.152832)
			(xy 388.172206 -165.196809) (xy 388.164208 -165.284397) (xy 388.148278 -165.370896) (xy 388.124548 -165.455588)
			(xy 388.093216 -165.537771) (xy 388.05454 -165.616764) (xy 388.008841 -165.691913) (xy 387.956497 -165.762595)
			(xy 387.897943 -165.828224) (xy 387.833664 -165.888257) (xy 387.764192 -165.942196) (xy 387.690103 -165.989594)
			(xy 387.61201 -166.030058) (xy 387.530562 -166.063253) (xy 387.446432 -166.088904) (xy 387.360319 -166.106799)
			(xy 387.272934 -166.116789) (xy 387.185004 -166.118791) (xy 387.097256 -166.112788) (xy 387.010417 -166.098832)
			(xy 386.925207 -166.077036) (xy 386.842332 -166.047583) (xy 386.762479 -166.010715) (xy 386.686309 -165.966738)
			(xy 386.614454 -165.916017) (xy 386.547509 -165.858972) (xy 386.486029 -165.796076) (xy 386.430522 -165.72785)
			(xy 386.38145 -165.654859) (xy 386.339219 -165.577708) (xy 386.304178 -165.497036) (xy 386.276619 -165.413512)
			(xy 386.256768 -165.327828) (xy 386.244792 -165.240694) (xy 386.240789 -165.152832) (xy 378.834079 -165.152832)
			(xy 378.827168 -165.228517) (xy 378.811238 -165.315016) (xy 378.787508 -165.399708) (xy 378.756176 -165.481891)
			(xy 378.7175 -165.560884) (xy 378.671801 -165.636033) (xy 378.619457 -165.706715) (xy 378.560903 -165.772344)
			(xy 378.496624 -165.832377) (xy 378.427152 -165.886316) (xy 378.353063 -165.933714) (xy 378.27497 -165.974178)
			(xy 378.193522 -166.007373) (xy 378.109392 -166.033024) (xy 378.023279 -166.050919) (xy 377.935894 -166.060909)
			(xy 377.847964 -166.062911) (xy 377.760216 -166.056908) (xy 377.673377 -166.042952) (xy 377.588167 -166.021156)
			(xy 377.505292 -165.991703) (xy 377.425439 -165.954835) (xy 377.349269 -165.910858) (xy 377.277414 -165.860137)
			(xy 377.210469 -165.803092) (xy 377.148989 -165.740196) (xy 377.093482 -165.67197) (xy 377.04441 -165.598979)
			(xy 377.002179 -165.521828) (xy 376.967138 -165.441156) (xy 376.939579 -165.357632) (xy 376.919728 -165.271948)
			(xy 376.907752 -165.184814) (xy 376.903749 -165.096952) (xy 373.769382 -165.096952) (xy 372.338346 -166.527988)
			(xy 402.05533 -166.527988) (xy 402.055846 -166.500415) (xy 402.063787 -166.445844) (xy 402.079501 -166.392985)
			(xy 402.102662 -166.342938) (xy 402.132786 -166.296747) (xy 402.169246 -166.255375) (xy 402.18995 -166.237158)
			(xy 402.198091 -166.229576) (xy 402.207431 -166.209409) (xy 402.207984 -166.198296) (xy 402.207984 -166.12108)
			(xy 402.207448 -166.109966) (xy 402.198088 -166.089807) (xy 402.18995 -166.082218) (xy 402.16923 -166.064017)
			(xy 402.132762 -166.022645) (xy 402.102632 -165.976454) (xy 402.079467 -165.926405) (xy 402.06375 -165.873542)
			(xy 402.05581 -165.818967) (xy 402.055811 -165.763817) (xy 402.063754 -165.709243) (xy 402.079472 -165.65638)
			(xy 402.102639 -165.606332) (xy 402.132772 -165.560142) (xy 402.169241 -165.518772) (xy 402.18995 -165.500558)
			(xy 402.198091 -165.492976) (xy 402.207431 -165.472809) (xy 402.207984 -165.461696) (xy 402.207984 -165.38448)
			(xy 402.207448 -165.373366) (xy 402.198088 -165.353207) (xy 402.18995 -165.345618) (xy 402.169234 -165.327412)
			(xy 402.132767 -165.286041) (xy 402.102636 -165.239849) (xy 402.079472 -165.189801) (xy 402.063756 -165.136938)
			(xy 402.055816 -165.082363) (xy 402.05533 -165.054788) (xy 402.055744 -165.027533) (xy 402.063503 -164.973578)
			(xy 402.078863 -164.921277) (xy 402.10151 -164.871694) (xy 402.130982 -164.82584) (xy 402.166681 -164.784646)
			(xy 402.20788 -164.748952) (xy 402.253738 -164.719486) (xy 402.303324 -164.696845) (xy 402.355627 -164.681493)
			(xy 402.409583 -164.67374) (xy 402.436838 -164.67328) (xy 402.464694 -164.673784) (xy 402.519809 -164.681912)
			(xy 402.573159 -164.697962) (xy 402.623611 -164.721592) (xy 402.670095 -164.752301) (xy 402.711624 -164.789438)
			(xy 402.747317 -164.832215) (xy 402.776417 -164.879723) (xy 402.798305 -164.930955) (xy 402.8059 -164.95776)
			(xy 402.808186 -164.96665) (xy 402.818854 -164.98189) (xy 402.890736 -165.029642) (xy 402.90877 -165.033706)
			(xy 402.917914 -165.032436) (xy 402.930931 -165.030767) (xy 402.957115 -165.028987) (xy 402.970238 -165.02888)
			(xy 402.984387 -165.02897) (xy 403.01261 -165.031007) (xy 403.026626 -165.032944) (xy 403.036786 -165.034468)
			(xy 403.056344 -165.029642) (xy 403.130766 -164.973762) (xy 403.140926 -164.956236) (xy 403.142196 -164.946076)
			(xy 403.146288 -164.918923) (xy 403.161259 -164.866092) (xy 403.183649 -164.815953) (xy 403.212995 -164.769541)
			(xy 403.248692 -164.727816) (xy 403.290002 -164.691639) (xy 403.336071 -164.661758) (xy 403.385948 -164.63879)
			(xy 403.438602 -164.623209) (xy 403.492946 -164.615337) (xy 403.520402 -164.61486) (xy 403.547652 -164.615376)
			(xy 403.601597 -164.623132) (xy 403.653889 -164.638486) (xy 403.703464 -164.661125) (xy 403.749313 -164.690588)
			(xy 403.790502 -164.726276) (xy 403.826194 -164.767463) (xy 403.855661 -164.813309) (xy 403.878304 -164.862883)
			(xy 403.893662 -164.915174) (xy 403.901422 -164.969118) (xy 403.90191 -164.996368) (xy 403.901419 -165.023942)
			(xy 403.893471 -165.078513) (xy 403.877751 -165.131372) (xy 403.854585 -165.181418) (xy 403.824458 -165.227609)
			(xy 403.787995 -165.268981) (xy 403.76729 -165.287198) (xy 403.759175 -165.294804) (xy 403.749819 -165.314953)
			(xy 403.749256 -165.32606) (xy 403.749256 -165.403276) (xy 403.749804 -165.414389) (xy 403.759155 -165.434548)
			(xy 403.76729 -165.442138) (xy 403.788021 -165.460328) (xy 403.82449 -165.501701) (xy 403.85462 -165.547895)
			(xy 403.877782 -165.597947) (xy 403.893494 -165.650814) (xy 403.901428 -165.705392) (xy 403.901462 -165.707314)
			(xy 408.490418 -165.707314) (xy 408.494489 -165.651692) (xy 408.506615 -165.597255) (xy 408.526538 -165.545164)
			(xy 408.553834 -165.496529) (xy 408.58792 -165.452386) (xy 408.628069 -165.413677) (xy 408.673427 -165.381226)
			(xy 408.723027 -165.355725) (xy 408.775811 -165.337718) (xy 408.830654 -165.327588) (xy 408.886388 -165.325551)
			(xy 408.941825 -165.331651) (xy 408.995782 -165.345757) (xy 409.047111 -165.367569) (xy 409.094717 -165.396623)
			(xy 409.137585 -165.432298) (xy 409.174802 -165.473835) (xy 409.205575 -165.520348) (xy 409.229247 -165.570845)
			(xy 409.245315 -165.624252) (xy 409.253435 -165.679428) (xy 409.253944 -165.707314) (xy 409.253435 -165.7352)
			(xy 409.245315 -165.790376) (xy 409.229247 -165.843783) (xy 409.205575 -165.89428) (xy 409.174802 -165.940793)
			(xy 409.137585 -165.98233) (xy 409.094717 -166.018005) (xy 409.047111 -166.047059) (xy 408.995782 -166.068871)
			(xy 408.941825 -166.082977) (xy 408.886388 -166.089077) (xy 408.830654 -166.08704) (xy 408.775811 -166.07691)
			(xy 408.723027 -166.058903) (xy 408.673427 -166.033402) (xy 408.628069 -166.000951) (xy 408.58792 -165.962242)
			(xy 408.553834 -165.918099) (xy 408.526538 -165.869464) (xy 408.506615 -165.817373) (xy 408.494489 -165.762936)
			(xy 408.490418 -165.707314) (xy 403.901462 -165.707314) (xy 403.90191 -165.732968) (xy 403.901415 -165.76022)
			(xy 403.893662 -165.81417) (xy 403.87831 -165.866467) (xy 403.855672 -165.916047) (xy 403.826207 -165.9619)
			(xy 403.790517 -166.003093) (xy 403.749327 -166.038787) (xy 403.703477 -166.068256) (xy 403.653899 -166.090899)
			(xy 403.601603 -166.106255) (xy 403.547654 -166.114013) (xy 403.520402 -166.114476) (xy 403.486112 -166.112952)
			(xy 403.475952 -166.111936) (xy 403.456648 -166.118032) (xy 403.386036 -166.177214) (xy 403.376638 -166.195248)
			(xy 403.375622 -166.205408) (xy 403.37263 -166.233576) (xy 403.359462 -166.288667) (xy 403.338289 -166.341204)
			(xy 403.309577 -166.39003) (xy 403.273957 -166.434072) (xy 403.232214 -166.472359) (xy 403.185266 -166.50405)
			(xy 403.134147 -166.528447) (xy 403.07998 -166.545013) (xy 403.023959 -166.553383) (xy 402.995638 -166.553896)
			(xy 402.977619 -166.55368) (xy 402.941744 -166.550243) (xy 402.92401 -166.547038) (xy 402.914612 -166.54526)
			(xy 402.895562 -166.54907) (xy 402.820378 -166.596822) (xy 402.808948 -166.61257) (xy 402.806662 -166.621968)
			(xy 402.799299 -166.649022) (xy 402.777665 -166.70075) (xy 402.748696 -166.748756) (xy 402.713016 -166.792007)
			(xy 402.671392 -166.829573) (xy 402.624721 -166.860646) (xy 402.574005 -166.884557) (xy 402.520338 -166.900791)
			(xy 402.464873 -166.908999) (xy 402.436838 -166.909496) (xy 402.409586 -166.909009) (xy 402.355635 -166.901257)
			(xy 402.303337 -166.885905) (xy 402.253756 -166.863266) (xy 402.207902 -166.833801) (xy 402.166709 -166.79811)
			(xy 402.131014 -166.756919) (xy 402.101546 -166.711067) (xy 402.078904 -166.661488) (xy 402.063548 -166.609191)
			(xy 402.055793 -166.55524) (xy 402.05533 -166.527988) (xy 372.338346 -166.527988) (xy 370.78412 -168.082214)
			(xy 403.723348 -168.082214) (xy 403.723858 -168.053297) (xy 403.732586 -167.996124) (xy 403.749845 -167.940924)
			(xy 403.775238 -167.888962) (xy 403.808184 -167.841429) (xy 403.847927 -167.799413) (xy 403.870414 -167.781224)
			(xy 403.879163 -167.77365) (xy 403.889353 -167.7529) (xy 403.889972 -167.741346) (xy 403.889972 -167.661082)
			(xy 403.889422 -167.649511) (xy 403.879214 -167.62874) (xy 403.870414 -167.621204) (xy 403.847935 -167.603007)
			(xy 403.808199 -167.560989) (xy 403.775259 -167.513456) (xy 403.74987 -167.461495) (xy 403.732613 -167.406299)
			(xy 403.723883 -167.34913) (xy 403.723348 -167.320214) (xy 403.723894 -167.292154) (xy 403.732126 -167.236641)
			(xy 403.7484 -167.182932) (xy 403.772364 -167.132186) (xy 403.803502 -167.085497) (xy 403.841142 -167.043872)
			(xy 403.884473 -167.008208) (xy 403.90826 -166.993316) (xy 403.917912 -166.987474) (xy 403.930104 -166.96944)
			(xy 403.947122 -166.87165) (xy 403.941534 -166.850568) (xy 403.934422 -166.841678) (xy 403.918531 -166.821603)
			(xy 403.891783 -166.777945) (xy 403.871257 -166.731041) (xy 403.857338 -166.681769) (xy 403.850287 -166.631057)
			(xy 403.84984 -166.605458) (xy 403.850317 -166.578843) (xy 403.857898 -166.526154) (xy 403.872898 -166.475081)
			(xy 403.895014 -166.426662) (xy 403.923794 -166.381882) (xy 403.958653 -166.341653) (xy 403.998882 -166.306794)
			(xy 404.043662 -166.278014) (xy 404.092081 -166.255898) (xy 404.143154 -166.240898) (xy 404.195843 -166.233317)
			(xy 404.222458 -166.23284) (xy 404.24888 -166.233278) (xy 404.301196 -166.240735) (xy 404.351934 -166.255505)
			(xy 404.400078 -166.277293) (xy 404.444663 -166.305661) (xy 404.465028 -166.322502) (xy 404.471886 -166.328598)
			(xy 404.488904 -166.334694) (xy 404.573232 -166.334694) (xy 404.59025 -166.328598) (xy 404.597108 -166.322502)
			(xy 404.617474 -166.305663) (xy 404.66206 -166.277298) (xy 404.710204 -166.255511) (xy 404.760941 -166.24074)
			(xy 404.813256 -166.23328) (xy 404.8661 -166.23328) (xy 404.918415 -166.24074) (xy 404.969152 -166.255511)
			(xy 405.017296 -166.277298) (xy 405.061882 -166.305663) (xy 405.082248 -166.322502) (xy 405.089106 -166.328598)
			(xy 405.106124 -166.334694) (xy 405.190452 -166.334694) (xy 405.20747 -166.328598) (xy 405.214328 -166.322502)
			(xy 405.234683 -166.305651) (xy 405.279276 -166.277298) (xy 405.327423 -166.255521) (xy 405.378162 -166.240756)
			(xy 405.430476 -166.233299) (xy 405.456898 -166.23284) (xy 405.484782 -166.233419) (xy 405.539926 -166.241731)
			(xy 405.593216 -166.258168) (xy 405.643461 -166.282364) (xy 405.689538 -166.313779) (xy 405.730419 -166.351711)
			(xy 405.765189 -166.395311) (xy 405.793073 -166.443607) (xy 405.813447 -166.495519) (xy 405.825856 -166.549889)
			(xy 405.830024 -166.6055) (xy 405.825856 -166.661111) (xy 405.813447 -166.715481) (xy 405.793073 -166.767393)
			(xy 405.765189 -166.815689) (xy 405.730419 -166.859289) (xy 405.689538 -166.897221) (xy 405.643461 -166.928636)
			(xy 405.593216 -166.952832) (xy 405.539926 -166.969269) (xy 405.484782 -166.977581) (xy 405.456898 -166.978076)
			(xy 405.430477 -166.977601) (xy 405.378163 -166.970153) (xy 405.327425 -166.955391) (xy 405.279281 -166.933611)
			(xy 405.234695 -166.905251) (xy 405.214328 -166.888414) (xy 405.20747 -166.882318) (xy 405.190452 -166.876222)
			(xy 405.106124 -166.876222) (xy 405.089106 -166.882318) (xy 405.082248 -166.888414) (xy 405.061882 -166.905253)
			(xy 405.017296 -166.933618) (xy 404.969152 -166.955405) (xy 404.918415 -166.970176) (xy 404.8661 -166.977636)
			(xy 404.813256 -166.977636) (xy 404.760941 -166.970176) (xy 404.710204 -166.955405) (xy 404.66206 -166.933618)
			(xy 404.617474 -166.905253) (xy 404.597108 -166.888414) (xy 404.59025 -166.882318) (xy 404.573232 -166.876222)
			(xy 404.488904 -166.876222) (xy 404.471886 -166.882318) (xy 404.465028 -166.888414) (xy 404.454226 -166.897478)
			(xy 404.431466 -166.914129) (xy 404.419562 -166.921688) (xy 404.40991 -166.92753) (xy 404.397972 -166.945818)
			(xy 404.382732 -167.044116) (xy 404.388574 -167.064944) (xy 404.39594 -167.07358) (xy 404.412941 -167.094341)
			(xy 404.441546 -167.13974) (xy 404.463507 -167.1887) (xy 404.478393 -167.240253) (xy 404.485909 -167.293384)
			(xy 404.486364 -167.320214) (xy 404.485797 -167.349129) (xy 404.47708 -167.406299) (xy 404.459833 -167.461497)
			(xy 404.43445 -167.513459) (xy 404.401514 -167.560994) (xy 404.379405 -167.584374) (xy 409.44927 -167.584374)
			(xy 409.449752 -167.556463) (xy 409.45789 -167.501237) (xy 409.473988 -167.447786) (xy 409.497703 -167.397252)
			(xy 409.528529 -167.350712) (xy 409.546806 -167.329612) (xy 409.553156 -167.3225) (xy 409.55976 -167.305228)
			(xy 409.55976 -167.218106) (xy 409.553156 -167.200834) (xy 409.546806 -167.193722) (xy 409.528518 -167.172631)
			(xy 409.497692 -167.12609) (xy 409.473978 -167.075554) (xy 409.457884 -167.0221) (xy 409.449753 -166.966872)
			(xy 409.44927 -166.93896) (xy 409.449756 -166.911709) (xy 409.457512 -166.857761) (xy 409.472867 -166.805466)
			(xy 409.495509 -166.755889) (xy 409.524975 -166.710039) (xy 409.560666 -166.668848) (xy 409.601857 -166.633157)
			(xy 409.647707 -166.603691) (xy 409.697284 -166.581049) (xy 409.749579 -166.565694) (xy 409.803527 -166.557938)
			(xy 409.858029 -166.557938) (xy 409.911977 -166.565694) (xy 409.964272 -166.581049) (xy 410.013849 -166.603691)
			(xy 410.059699 -166.633157) (xy 410.10089 -166.668848) (xy 410.136581 -166.710039) (xy 410.166047 -166.755889)
			(xy 410.188689 -166.805466) (xy 410.204044 -166.857761) (xy 410.2118 -166.911709) (xy 410.212286 -166.93896)
			(xy 410.21181 -166.966871) (xy 410.203669 -167.022097) (xy 410.187568 -167.075547) (xy 410.163852 -167.126082)
			(xy 410.133027 -167.172621) (xy 410.11475 -167.193722) (xy 410.1084 -167.200834) (xy 410.101796 -167.218106)
			(xy 410.101796 -167.305228) (xy 410.1084 -167.3225) (xy 410.11475 -167.329612) (xy 410.133016 -167.350721)
			(xy 410.163843 -167.397258) (xy 410.18756 -167.44779) (xy 410.20366 -167.501239) (xy 410.211798 -167.556464)
			(xy 410.212286 -167.584374) (xy 410.2118 -167.611625) (xy 410.204044 -167.665573) (xy 410.188689 -167.717868)
			(xy 410.166047 -167.767445) (xy 410.136581 -167.813295) (xy 410.10089 -167.854486) (xy 410.059699 -167.890177)
			(xy 410.013849 -167.919643) (xy 409.964272 -167.942285) (xy 409.911977 -167.95764) (xy 409.858029 -167.965396)
			(xy 409.803527 -167.965396) (xy 409.749579 -167.95764) (xy 409.697284 -167.942285) (xy 409.647707 -167.919643)
			(xy 409.601857 -167.890177) (xy 409.560666 -167.854486) (xy 409.524975 -167.813295) (xy 409.495509 -167.767445)
			(xy 409.472867 -167.717868) (xy 409.457512 -167.665573) (xy 409.449756 -167.611625) (xy 409.44927 -167.584374)
			(xy 404.379405 -167.584374) (xy 404.36178 -167.603013) (xy 404.339298 -167.621204) (xy 404.330538 -167.628768)
			(xy 404.320354 -167.649525) (xy 404.31974 -167.661082) (xy 404.31974 -167.741346) (xy 404.320327 -167.752912)
			(xy 404.330509 -167.773684) (xy 404.339298 -167.781224) (xy 404.361793 -167.799402) (xy 404.401527 -167.841424)
			(xy 404.434465 -167.888962) (xy 404.459851 -167.940926) (xy 404.477105 -167.996126) (xy 404.485831 -168.053297)
			(xy 404.486364 -168.082214) (xy 404.485878 -168.109465) (xy 404.478122 -168.163413) (xy 404.462767 -168.215708)
			(xy 404.440125 -168.265285) (xy 404.410659 -168.311135) (xy 404.374968 -168.352326) (xy 404.333777 -168.388017)
			(xy 404.287927 -168.417483) (xy 404.23835 -168.440125) (xy 404.186055 -168.45548) (xy 404.132107 -168.463236)
			(xy 404.077605 -168.463236) (xy 404.023657 -168.45548) (xy 403.971362 -168.440125) (xy 403.921785 -168.417483)
			(xy 403.875935 -168.388017) (xy 403.834744 -168.352326) (xy 403.799053 -168.311135) (xy 403.769587 -168.265285)
			(xy 403.746945 -168.215708) (xy 403.73159 -168.163413) (xy 403.723834 -168.109465) (xy 403.723348 -168.082214)
			(xy 370.78412 -168.082214) (xy 367.151158 -171.715176) (xy 367.14433 -171.722585) (xy 367.136605 -171.741178)
			(xy 367.136172 -171.751244) (xy 367.136172 -173.21911) (xy 394.24737 -173.21911) (xy 394.247869 -173.190192)
			(xy 394.256598 -173.133019) (xy 394.273858 -173.077818) (xy 394.299253 -173.025856) (xy 394.332202 -172.978323)
			(xy 394.371948 -172.936308) (xy 394.394436 -172.91812) (xy 394.40319 -172.910551) (xy 394.413376 -172.889797)
			(xy 394.413994 -172.878242) (xy 394.413994 -172.797978) (xy 394.413381 -172.786416) (xy 394.403217 -172.765644)
			(xy 394.394436 -172.7581) (xy 394.37196 -172.7399) (xy 394.332223 -172.697883) (xy 394.299282 -172.65035)
			(xy 394.273892 -172.598391) (xy 394.256634 -172.543194) (xy 394.247905 -172.486026) (xy 394.24737 -172.45711)
			(xy 394.247888 -172.42986) (xy 394.255642 -172.375915) (xy 394.270995 -172.323622) (xy 394.293633 -172.274046)
			(xy 394.323096 -172.228197) (xy 394.358784 -172.187007) (xy 394.399971 -172.151316) (xy 394.445818 -172.121849)
			(xy 394.495392 -172.099206) (xy 394.547683 -172.083849) (xy 394.601628 -172.07609) (xy 394.628878 -172.075602)
			(xy 394.657633 -172.07612) (xy 394.714492 -172.08474) (xy 394.769411 -172.101804) (xy 394.821143 -172.126924)
			(xy 394.868516 -172.15953) (xy 394.910453 -172.198882) (xy 394.946002 -172.244087) (xy 394.974358 -172.294119)
			(xy 394.994877 -172.347843) (xy 395.001496 -172.37583) (xy 395.003782 -172.386244) (xy 395.015974 -172.402754)
			(xy 395.097508 -172.45203) (xy 395.117828 -172.454824) (xy 395.128242 -172.451776) (xy 395.153392 -172.445244)
			(xy 395.204877 -172.438231) (xy 395.230858 -172.437806) (xy 395.25811 -172.438294) (xy 395.312061 -172.446046)
			(xy 395.364359 -172.461397) (xy 395.41394 -172.484036) (xy 395.459794 -172.513501) (xy 395.500988 -172.549192)
			(xy 395.536682 -172.590383) (xy 395.56615 -172.636235) (xy 395.588793 -172.685814) (xy 395.604148 -172.738111)
			(xy 395.611904 -172.792062) (xy 395.612366 -172.819314) (xy 395.612162 -172.831252) (xy 397.517874 -172.831252)
			(xy 397.51836 -172.804001) (xy 397.526116 -172.750053) (xy 397.541471 -172.697758) (xy 397.564113 -172.648181)
			(xy 397.593579 -172.602331) (xy 397.62927 -172.56114) (xy 397.670461 -172.525449) (xy 397.716311 -172.495983)
			(xy 397.765888 -172.473341) (xy 397.818183 -172.457986) (xy 397.872131 -172.45023) (xy 397.926633 -172.45023)
			(xy 397.980581 -172.457986) (xy 398.032876 -172.473341) (xy 398.082453 -172.495983) (xy 398.128303 -172.525449)
			(xy 398.169494 -172.56114) (xy 398.205185 -172.602331) (xy 398.234651 -172.648181) (xy 398.257293 -172.697758)
			(xy 398.272648 -172.750053) (xy 398.280404 -172.804001) (xy 398.28089 -172.831252) (xy 398.280237 -172.862815)
			(xy 398.269847 -172.925081) (xy 398.249359 -172.98479) (xy 398.234916 -173.012862) (xy 398.23009 -173.021752)
			(xy 398.228058 -173.04131) (xy 398.253712 -173.129448) (xy 398.266158 -173.144942) (xy 398.275048 -173.150022)
			(xy 398.282414 -173.154086) (xy 398.292066 -173.159928) (xy 398.314164 -173.16196) (xy 398.408652 -173.128432)
			(xy 398.424654 -173.112938) (xy 398.428718 -173.102524) (xy 398.439395 -173.075739) (xy 398.467683 -173.025495)
			(xy 398.503214 -172.980083) (xy 398.545179 -172.94054) (xy 398.592619 -172.907766) (xy 398.644454 -172.88251)
			(xy 398.6995 -172.865348) (xy 398.756504 -172.85667) (xy 398.785334 -172.856144) (xy 398.81258 -172.856728)
			(xy 398.866517 -172.864488) (xy 398.918801 -172.879844) (xy 398.968368 -172.902484) (xy 399.014208 -172.931948)
			(xy 399.055389 -172.967635) (xy 399.091073 -173.008819) (xy 399.120532 -173.054662) (xy 399.143168 -173.10423)
			(xy 399.158519 -173.156516) (xy 399.166274 -173.210454) (xy 399.166274 -173.264946) (xy 399.158519 -173.318884)
			(xy 399.149183 -173.350682) (xy 399.408142 -173.350682) (xy 399.408607 -173.323206) (xy 399.416503 -173.268826)
			(xy 399.432127 -173.216143) (xy 399.455157 -173.16625) (xy 399.485114 -173.120183) (xy 399.502884 -173.099222)
			(xy 399.50898 -173.09211) (xy 399.51533 -173.075092) (xy 399.51533 -172.98924) (xy 399.50898 -172.972222)
			(xy 399.502884 -172.96511) (xy 399.485141 -172.944131) (xy 399.455214 -172.898053) (xy 399.432197 -172.848164)
			(xy 399.416566 -172.79549) (xy 399.408644 -172.741121) (xy 399.408142 -172.71365) (xy 399.408628 -172.686399)
			(xy 399.416384 -172.632451) (xy 399.431739 -172.580156) (xy 399.454381 -172.530579) (xy 399.483847 -172.484729)
			(xy 399.519538 -172.443538) (xy 399.560729 -172.407847) (xy 399.606579 -172.378381) (xy 399.656156 -172.355739)
			(xy 399.708451 -172.340384) (xy 399.762399 -172.332628) (xy 399.816901 -172.332628) (xy 399.870849 -172.340384)
			(xy 399.923144 -172.355739) (xy 399.972721 -172.378381) (xy 400.018571 -172.407847) (xy 400.059762 -172.443538)
			(xy 400.095453 -172.484729) (xy 400.124919 -172.530579) (xy 400.147561 -172.580156) (xy 400.162916 -172.632451)
			(xy 400.170672 -172.686399) (xy 400.171158 -172.71365) (xy 400.170711 -172.741126) (xy 400.162811 -172.795508)
			(xy 400.147183 -172.848191) (xy 400.124149 -172.898083) (xy 400.094188 -172.94415) (xy 400.076416 -172.96511)
			(xy 400.07032 -172.972222) (xy 400.06397 -172.98924) (xy 400.06397 -173.075092) (xy 400.07032 -173.09211)
			(xy 400.076416 -173.099222) (xy 400.094174 -173.120189) (xy 400.124099 -173.16627) (xy 400.147113 -173.216163)
			(xy 400.16274 -173.268839) (xy 400.170658 -173.32321) (xy 400.171158 -173.350682) (xy 400.170672 -173.377933)
			(xy 400.169039 -173.38929) (xy 400.745958 -173.38929) (xy 400.750029 -173.333668) (xy 400.762155 -173.279231)
			(xy 400.782078 -173.22714) (xy 400.809374 -173.178505) (xy 400.84346 -173.134362) (xy 400.883609 -173.095653)
			(xy 400.928967 -173.063202) (xy 400.978567 -173.037701) (xy 401.031351 -173.019694) (xy 401.086194 -173.009564)
			(xy 401.141928 -173.007527) (xy 401.197365 -173.013627) (xy 401.251322 -173.027733) (xy 401.302651 -173.049545)
			(xy 401.350257 -173.078599) (xy 401.393125 -173.114274) (xy 401.430342 -173.155811) (xy 401.461115 -173.202324)
			(xy 401.484787 -173.252821) (xy 401.500855 -173.306228) (xy 401.508975 -173.361404) (xy 401.509484 -173.38929)
			(xy 401.508975 -173.417176) (xy 401.500855 -173.472352) (xy 401.484787 -173.525759) (xy 401.461115 -173.576256)
			(xy 401.430342 -173.622769) (xy 401.393125 -173.664306) (xy 401.350257 -173.699981) (xy 401.302651 -173.729035)
			(xy 401.251322 -173.750847) (xy 401.197365 -173.764953) (xy 401.141928 -173.771053) (xy 401.086194 -173.769016)
			(xy 401.031351 -173.758886) (xy 400.978567 -173.740879) (xy 400.928967 -173.715378) (xy 400.883609 -173.682927)
			(xy 400.84346 -173.644218) (xy 400.809374 -173.600075) (xy 400.782078 -173.55144) (xy 400.762155 -173.499349)
			(xy 400.750029 -173.444912) (xy 400.745958 -173.38929) (xy 400.169039 -173.38929) (xy 400.162916 -173.431881)
			(xy 400.147561 -173.484176) (xy 400.124919 -173.533753) (xy 400.095453 -173.579603) (xy 400.059762 -173.620794)
			(xy 400.018571 -173.656485) (xy 399.972721 -173.685951) (xy 399.923144 -173.708593) (xy 399.870849 -173.723948)
			(xy 399.816901 -173.731704) (xy 399.762399 -173.731704) (xy 399.708451 -173.723948) (xy 399.656156 -173.708593)
			(xy 399.606579 -173.685951) (xy 399.560729 -173.656485) (xy 399.519538 -173.620794) (xy 399.483847 -173.579603)
			(xy 399.454381 -173.533753) (xy 399.431739 -173.484176) (xy 399.416384 -173.431881) (xy 399.408628 -173.377933)
			(xy 399.408142 -173.350682) (xy 399.149183 -173.350682) (xy 399.143168 -173.37117) (xy 399.120532 -173.420738)
			(xy 399.091073 -173.466581) (xy 399.055389 -173.507765) (xy 399.014208 -173.543452) (xy 398.968368 -173.572916)
			(xy 398.918801 -173.595556) (xy 398.866517 -173.610912) (xy 398.81258 -173.618672) (xy 398.785334 -173.61916)
			(xy 398.760098 -173.618784) (xy 398.710064 -173.612158) (xy 398.661343 -173.598979) (xy 398.614792 -173.579477)
			(xy 398.592802 -173.56709) (xy 398.58315 -173.561248) (xy 398.561052 -173.559216) (xy 398.466564 -173.592744)
			(xy 398.450562 -173.608238) (xy 398.446498 -173.618652) (xy 398.435848 -173.645448) (xy 398.407552 -173.695689)
			(xy 398.372015 -173.741098) (xy 398.330046 -173.780638) (xy 398.282602 -173.813409) (xy 398.230765 -173.838664)
			(xy 398.175717 -173.855826) (xy 398.118713 -173.864505) (xy 398.089882 -173.865032) (xy 398.062631 -173.864539)
			(xy 398.008685 -173.856781) (xy 397.956392 -173.841424) (xy 397.906816 -173.818783) (xy 397.860967 -173.789317)
			(xy 397.819778 -173.753626) (xy 397.784087 -173.712438) (xy 397.75462 -173.666589) (xy 397.731978 -173.617014)
			(xy 397.716621 -173.564721) (xy 397.708861 -173.510775) (xy 397.708374 -173.483524) (xy 397.709022 -173.451961)
			(xy 397.719415 -173.389695) (xy 397.739905 -173.329986) (xy 397.754348 -173.301914) (xy 397.759174 -173.293024)
			(xy 397.761206 -173.273466) (xy 397.735552 -173.185328) (xy 397.723106 -173.169834) (xy 397.714216 -173.164754)
			(xy 397.689114 -173.150207) (xy 397.643231 -173.114704) (xy 397.603256 -173.07266) (xy 397.57011 -173.025046)
			(xy 397.544559 -172.972961) (xy 397.527193 -172.917606) (xy 397.518413 -172.860259) (xy 397.517874 -172.831252)
			(xy 395.612162 -172.831252) (xy 395.611926 -172.845003) (xy 395.60503 -172.895915) (xy 395.591363 -172.945442)
			(xy 395.571175 -172.992687) (xy 395.544828 -173.036795) (xy 395.512801 -173.076968) (xy 395.475673 -173.112481)
			(xy 395.45514 -173.127924) (xy 395.445742 -173.134782) (xy 395.43482 -173.154848) (xy 395.430248 -173.257718)
			(xy 395.439138 -173.2788) (xy 395.448028 -173.286674) (xy 395.4681 -173.304875) (xy 395.503432 -173.345953)
			(xy 395.532592 -173.39162) (xy 395.554992 -173.440956) (xy 395.570182 -173.492966) (xy 395.577854 -173.546603)
			(xy 395.57833 -173.573694) (xy 395.57785 -173.601268) (xy 395.569899 -173.65584) (xy 395.554176 -173.708699)
			(xy 395.531008 -173.758745) (xy 395.500879 -173.804935) (xy 395.464415 -173.846307) (xy 395.44371 -173.864524)
			(xy 395.435587 -173.872122) (xy 395.426235 -173.892277) (xy 395.425676 -173.903386) (xy 395.425676 -173.980602)
			(xy 395.426203 -173.991717) (xy 395.435568 -174.011877) (xy 395.44371 -174.019464) (xy 395.464409 -174.037688)
			(xy 395.50088 -174.079055) (xy 395.531013 -174.125242) (xy 395.554181 -174.175287) (xy 395.5699 -174.228147)
			(xy 395.577843 -174.28272) (xy 395.577877 -174.28464) (xy 400.166838 -174.28464) (xy 400.170909 -174.229018)
			(xy 400.183035 -174.174581) (xy 400.202958 -174.12249) (xy 400.230254 -174.073855) (xy 400.26434 -174.029712)
			(xy 400.304489 -173.991003) (xy 400.349847 -173.958552) (xy 400.399447 -173.933051) (xy 400.452231 -173.915044)
			(xy 400.507074 -173.904914) (xy 400.562808 -173.902877) (xy 400.618245 -173.908977) (xy 400.672202 -173.923083)
			(xy 400.723531 -173.944895) (xy 400.771137 -173.973949) (xy 400.814005 -174.009624) (xy 400.851222 -174.051161)
			(xy 400.881995 -174.097674) (xy 400.905667 -174.148171) (xy 400.921735 -174.201578) (xy 400.929855 -174.256754)
			(xy 400.930364 -174.28464) (xy 400.929855 -174.312526) (xy 400.921735 -174.367702) (xy 400.905667 -174.421109)
			(xy 400.881995 -174.471606) (xy 400.851222 -174.518119) (xy 400.814005 -174.559656) (xy 400.771137 -174.595331)
			(xy 400.723531 -174.624385) (xy 400.672202 -174.646197) (xy 400.618245 -174.660303) (xy 400.562808 -174.666403)
			(xy 400.507074 -174.664366) (xy 400.452231 -174.654236) (xy 400.399447 -174.636229) (xy 400.349847 -174.610728)
			(xy 400.304489 -174.578277) (xy 400.26434 -174.539568) (xy 400.230254 -174.495425) (xy 400.202958 -174.44679)
			(xy 400.183035 -174.394699) (xy 400.170909 -174.340262) (xy 400.166838 -174.28464) (xy 395.577877 -174.28464)
			(xy 395.57833 -174.310294) (xy 395.577817 -174.337544) (xy 395.570062 -174.39149) (xy 395.554708 -174.443783)
			(xy 395.532069 -174.493358) (xy 395.502606 -174.539208) (xy 395.466917 -174.580397) (xy 395.42573 -174.616089)
			(xy 395.379883 -174.645556) (xy 395.330309 -174.668199) (xy 395.278017 -174.683556) (xy 395.224072 -174.691315)
			(xy 395.196822 -174.691802) (xy 395.162532 -174.690278) (xy 395.152372 -174.689262) (xy 395.133068 -174.695358)
			(xy 395.062456 -174.75454) (xy 395.053058 -174.772574) (xy 395.052042 -174.782734) (xy 395.049052 -174.810902)
			(xy 395.035882 -174.865992) (xy 395.014706 -174.918527) (xy 394.985993 -174.967352) (xy 394.950373 -175.011393)
			(xy 394.90863 -175.04968) (xy 394.861683 -175.08137) (xy 394.810564 -175.105768) (xy 394.756399 -175.122335)
			(xy 394.700379 -175.130708) (xy 394.672058 -175.131222) (xy 394.644806 -175.130761) (xy 394.590858 -175.122999)
			(xy 394.538564 -175.10764) (xy 394.488988 -175.084995) (xy 394.443138 -175.055525) (xy 394.401949 -175.019831)
			(xy 394.366258 -174.978639) (xy 394.336792 -174.932788) (xy 394.314151 -174.88321) (xy 394.298795 -174.830914)
			(xy 394.291037 -174.776966) (xy 394.29055 -174.749714) (xy 394.291055 -174.721852) (xy 394.299155 -174.666721)
			(xy 394.315183 -174.613353) (xy 394.3388 -174.562882) (xy 394.369504 -174.516381) (xy 394.406643 -174.474838)
			(xy 394.42771 -174.456598) (xy 394.436854 -174.448978) (xy 394.446506 -174.427896) (xy 394.44295 -174.32401)
			(xy 394.432028 -174.303436) (xy 394.422376 -174.296324) (xy 394.401856 -174.280863) (xy 394.36472 -174.245358)
			(xy 394.332685 -174.20519) (xy 394.306333 -174.161085) (xy 394.286139 -174.113842) (xy 394.272469 -174.064316)
			(xy 394.26557 -174.013403) (xy 394.26515 -173.987714) (xy 394.265721 -173.959177) (xy 394.274209 -173.902738)
			(xy 394.291013 -173.848194) (xy 394.315757 -173.796762) (xy 394.347888 -173.749593) (xy 394.38669 -173.707738)
			(xy 394.40866 -173.689518) (xy 394.418058 -173.682152) (xy 394.427964 -173.660562) (xy 394.425678 -173.555914)
			(xy 394.414502 -173.535086) (xy 394.40485 -173.527974) (xy 394.384266 -173.512553) (xy 394.347079 -173.47702)
			(xy 394.315 -173.436815) (xy 394.28861 -173.392667) (xy 394.268388 -173.345375) (xy 394.254699 -173.295795)
			(xy 394.247791 -173.244827) (xy 394.24737 -173.21911) (xy 367.136172 -173.21911) (xy 367.136172 -173.465744)
			(xy 367.135563 -173.490728) (xy 367.125818 -173.539735) (xy 367.106709 -173.585905) (xy 367.078971 -173.627466)
			(xy 367.06175 -173.645576) (xy 366.717834 -173.989492) (xy 367.235738 -173.989492) (xy 367.239809 -173.93387)
			(xy 367.251935 -173.879433) (xy 367.271858 -173.827342) (xy 367.299154 -173.778707) (xy 367.33324 -173.734564)
			(xy 367.373389 -173.695855) (xy 367.418747 -173.663404) (xy 367.468347 -173.637903) (xy 367.521131 -173.619896)
			(xy 367.575974 -173.609766) (xy 367.631708 -173.607729) (xy 367.687145 -173.613829) (xy 367.741102 -173.627935)
			(xy 367.792431 -173.649747) (xy 367.840037 -173.678801) (xy 367.882905 -173.714476) (xy 367.920122 -173.756013)
			(xy 367.950895 -173.802526) (xy 367.974567 -173.853023) (xy 367.990635 -173.90643) (xy 367.998755 -173.961606)
			(xy 367.999264 -173.989492) (xy 367.998755 -174.017378) (xy 367.990635 -174.072554) (xy 367.974567 -174.125961)
			(xy 367.950895 -174.176458) (xy 367.920122 -174.222971) (xy 367.882905 -174.264508) (xy 367.840037 -174.300183)
			(xy 367.792431 -174.329237) (xy 367.741102 -174.351049) (xy 367.687145 -174.365155) (xy 367.631708 -174.371255)
			(xy 367.575974 -174.369218) (xy 367.521131 -174.359088) (xy 367.468347 -174.341081) (xy 367.418747 -174.31558)
			(xy 367.373389 -174.283129) (xy 367.33324 -174.24442) (xy 367.299154 -174.200277) (xy 367.271858 -174.151642)
			(xy 367.251935 -174.099551) (xy 367.239809 -174.045114) (xy 367.235738 -173.989492) (xy 366.717834 -173.989492)
			(xy 366.665002 -174.042324) (xy 366.658906 -174.052992) (xy 366.656874 -174.059088) (xy 366.64871 -174.085046)
			(xy 366.626036 -174.134513) (xy 366.596559 -174.180253) (xy 366.560879 -174.221338) (xy 366.51972 -174.256933)
			(xy 366.473919 -174.286315) (xy 366.424406 -174.308887) (xy 366.372186 -174.32419) (xy 366.318322 -174.331914)
			(xy 366.291114 -174.332392) (xy 366.263861 -174.331932) (xy 366.209909 -174.324176) (xy 366.15761 -174.308821)
			(xy 366.108029 -174.286179) (xy 366.062175 -174.256711) (xy 366.020982 -174.221017) (xy 365.985288 -174.179823)
			(xy 365.95582 -174.133969) (xy 365.933178 -174.084388) (xy 365.917823 -174.032089) (xy 365.910068 -173.978137)
			(xy 365.909606 -173.950884) (xy 365.91004 -173.924089) (xy 365.917547 -173.871028) (xy 365.932399 -173.819538)
			(xy 365.954302 -173.770629) (xy 365.982828 -173.725262) (xy 365.999776 -173.704504) (xy 366.005872 -173.697392)
			(xy 366.011968 -173.680374) (xy 366.010444 -173.594522) (xy 366.003586 -173.577758) (xy 365.997236 -173.570646)
			(xy 365.978637 -173.549467) (xy 365.947256 -173.502644) (xy 365.923105 -173.451715) (xy 365.906709 -173.397788)
			(xy 365.898424 -173.342035) (xy 365.897922 -173.313852) (xy 365.898516 -173.284782) (xy 365.907344 -173.227316)
			(xy 365.924789 -173.171855) (xy 365.950446 -173.119683) (xy 365.983722 -173.072008) (xy 366.023845 -173.029932)
			(xy 366.069888 -172.994432) (xy 366.120785 -172.966328) (xy 366.175355 -172.946272) (xy 366.203738 -172.939964)
			(xy 366.221518 -172.936408) (xy 366.244632 -172.908214) (xy 366.244632 -171.468796) (xy 366.245265 -171.443814)
			(xy 366.255002 -171.394807) (xy 366.274103 -171.348637) (xy 366.301836 -171.307075) (xy 366.319054 -171.288964)
			(xy 375.703338 -161.90468) (xy 375.710185 -161.897285) (xy 375.717899 -161.878682) (xy 375.718324 -161.868612)
			(xy 375.718324 -151.064976) (xy 375.717832 -151.05497) (xy 375.710169 -151.036482) (xy 375.696018 -151.022331)
			(xy 375.67753 -151.014668) (xy 375.667524 -151.014176) (xy 374.573292 -151.014176) (xy 374.549369 -151.013738)
			(xy 374.502119 -151.006199) (xy 374.456631 -150.991357) (xy 374.414028 -150.969577) (xy 374.37536 -150.941397)
			(xy 374.358154 -150.924768) (xy 374.117108 -150.683722) (xy 374.100509 -150.666496) (xy 374.072368 -150.627813)
			(xy 374.05061 -150.585212) (xy 374.03577 -150.539736) (xy 374.028212 -150.492501) (xy 374.0277 -150.468584)
			(xy 374.0277 -149.421596) (xy 374.010936 -149.396196) (xy 373.996458 -149.390354) (xy 373.987031 -149.386977)
			(xy 373.967027 -149.386965) (xy 373.948527 -149.394575) (xy 373.941086 -149.401276) (xy 372.391178 -150.951184)
			(xy 372.373083 -150.968441) (xy 372.331538 -150.996252) (xy 372.285367 -151.015425) (xy 372.236342 -151.025224)
			(xy 372.211346 -151.02586) (xy 365.50219 -151.02586) (xy 365.492145 -151.026234) (xy 365.473548 -151.033819)
			(xy 365.466122 -151.040592) (xy 364.265972 -152.240742) (xy 364.259274 -152.24822) (xy 364.251686 -152.266782)
			(xy 364.25124 -152.27681) (xy 364.25124 -157.46831) (xy 365.557825 -157.46831) (xy 365.561553 -157.415059)
			(xy 365.572669 -157.362848) (xy 365.590955 -157.312696) (xy 365.616054 -157.265584) (xy 365.647476 -157.22243)
			(xy 365.684607 -157.184079) (xy 365.70539 -157.167326) (xy 365.714134 -157.159747) (xy 365.724328 -157.139001)
			(xy 365.724948 -157.127448) (xy 365.724948 -157.047184) (xy 365.724405 -157.035612) (xy 365.714193 -157.01484)
			(xy 365.70539 -157.007306) (xy 365.684622 -156.990534) (xy 365.647489 -156.952185) (xy 365.616065 -156.909033)
			(xy 365.590963 -156.861922) (xy 365.572675 -156.811771) (xy 365.561556 -156.75956) (xy 365.557825 -156.70631)
			(xy 365.561553 -156.653059) (xy 365.572669 -156.600848) (xy 365.590955 -156.550696) (xy 365.616054 -156.503584)
			(xy 365.647476 -156.46043) (xy 365.684607 -156.422079) (xy 365.70539 -156.405326) (xy 365.714134 -156.397747)
			(xy 365.724328 -156.377001) (xy 365.724948 -156.365448) (xy 365.724948 -156.285184) (xy 365.724405 -156.273612)
			(xy 365.714193 -156.25284) (xy 365.70539 -156.245306) (xy 365.684622 -156.228534) (xy 365.647489 -156.190185)
			(xy 365.616065 -156.147033) (xy 365.590963 -156.099922) (xy 365.572675 -156.049771) (xy 365.561556 -155.99756)
			(xy 365.557825 -155.94431) (xy 365.561553 -155.891059) (xy 365.572669 -155.838848) (xy 365.590955 -155.788696)
			(xy 365.616054 -155.741584) (xy 365.647476 -155.69843) (xy 365.684607 -155.660079) (xy 365.70539 -155.643326)
			(xy 365.714134 -155.635747) (xy 365.724328 -155.615001) (xy 365.724948 -155.603448) (xy 365.724948 -155.523184)
			(xy 365.724405 -155.511612) (xy 365.714193 -155.49084) (xy 365.70539 -155.483306) (xy 365.684622 -155.466534)
			(xy 365.647489 -155.428185) (xy 365.616065 -155.385033) (xy 365.590963 -155.337922) (xy 365.572675 -155.287771)
			(xy 365.561556 -155.23556) (xy 365.557825 -155.18231) (xy 365.561553 -155.129059) (xy 365.572669 -155.076848)
			(xy 365.590955 -155.026696) (xy 365.616054 -154.979584) (xy 365.647476 -154.93643) (xy 365.684607 -154.898079)
			(xy 365.70539 -154.881326) (xy 365.714134 -154.873747) (xy 365.724328 -154.853001) (xy 365.724948 -154.841448)
			(xy 365.724948 -154.761184) (xy 365.724405 -154.749612) (xy 365.714193 -154.72884) (xy 365.70539 -154.721306)
			(xy 365.682907 -154.703114) (xy 365.643173 -154.661094) (xy 365.610234 -154.613559) (xy 365.584845 -154.561598)
			(xy 365.567589 -154.506401) (xy 365.558859 -154.449232) (xy 365.558324 -154.420316) (xy 365.55877 -154.393062)
			(xy 365.566526 -154.339109) (xy 365.581882 -154.286809) (xy 365.604525 -154.237227) (xy 365.633994 -154.191372)
			(xy 365.669689 -154.150178) (xy 365.710885 -154.114484) (xy 365.756741 -154.085017) (xy 365.806324 -154.062376)
			(xy 365.858625 -154.047023) (xy 365.912578 -154.039269) (xy 365.939832 -154.038808) (xy 365.968747 -154.039372)
			(xy 366.025916 -154.048091) (xy 366.081115 -154.06534) (xy 366.133077 -154.090723) (xy 366.180612 -154.123658)
			(xy 366.222631 -154.163392) (xy 366.240822 -154.185874) (xy 366.248366 -154.194654) (xy 366.269139 -154.204824)
			(xy 366.2807 -154.205432) (xy 366.360964 -154.205432) (xy 366.372533 -154.204865) (xy 366.393305 -154.19467)
			(xy 366.400842 -154.185874) (xy 366.417595 -154.165091) (xy 366.455949 -154.127961) (xy 366.499103 -154.096539)
			(xy 366.546217 -154.07144) (xy 366.596369 -154.053154) (xy 366.64858 -154.042037) (xy 366.701832 -154.038307)
			(xy 366.755084 -154.042037) (xy 366.807295 -154.053154) (xy 366.857447 -154.07144) (xy 366.904561 -154.096539)
			(xy 366.947715 -154.127961) (xy 366.986069 -154.165091) (xy 367.002822 -154.185874) (xy 367.010366 -154.194654)
			(xy 367.031139 -154.204824) (xy 367.0427 -154.205432) (xy 367.122964 -154.205432) (xy 367.134533 -154.204865)
			(xy 367.155305 -154.19467) (xy 367.162842 -154.185874) (xy 367.179595 -154.165091) (xy 367.217949 -154.127961)
			(xy 367.261103 -154.096539) (xy 367.308217 -154.07144) (xy 367.358369 -154.053154) (xy 367.41058 -154.042037)
			(xy 367.463832 -154.038307) (xy 367.517084 -154.042037) (xy 367.569295 -154.053154) (xy 367.619447 -154.07144)
			(xy 367.666561 -154.096539) (xy 367.709715 -154.127961) (xy 367.748069 -154.165091) (xy 367.764822 -154.185874)
			(xy 367.772366 -154.194654) (xy 367.793139 -154.204824) (xy 367.8047 -154.205432) (xy 367.884964 -154.205432)
			(xy 367.896533 -154.204865) (xy 367.917305 -154.19467) (xy 367.924842 -154.185874) (xy 367.941595 -154.165091)
			(xy 367.979949 -154.127961) (xy 368.023103 -154.096539) (xy 368.070217 -154.07144) (xy 368.120369 -154.053154)
			(xy 368.17258 -154.042037) (xy 368.225832 -154.038307) (xy 368.279084 -154.042037) (xy 368.331295 -154.053154)
			(xy 368.381447 -154.07144) (xy 368.428561 -154.096539) (xy 368.471715 -154.127961) (xy 368.510069 -154.165091)
			(xy 368.526822 -154.185874) (xy 368.534366 -154.194654) (xy 368.555139 -154.204824) (xy 368.5667 -154.205432)
			(xy 368.646964 -154.205432) (xy 368.658533 -154.204865) (xy 368.679305 -154.19467) (xy 368.686842 -154.185874)
			(xy 368.703595 -154.165091) (xy 368.741949 -154.127961) (xy 368.785103 -154.096539) (xy 368.832217 -154.07144)
			(xy 368.882369 -154.053154) (xy 368.93458 -154.042037) (xy 368.987832 -154.038307) (xy 369.041084 -154.042037)
			(xy 369.093295 -154.053154) (xy 369.143447 -154.07144) (xy 369.190561 -154.096539) (xy 369.233715 -154.127961)
			(xy 369.272069 -154.165091) (xy 369.288822 -154.185874) (xy 369.296366 -154.194654) (xy 369.317139 -154.204824)
			(xy 369.3287 -154.205432) (xy 369.408964 -154.205432) (xy 369.420533 -154.204865) (xy 369.441305 -154.19467)
			(xy 369.448842 -154.185874) (xy 369.465595 -154.165091) (xy 369.503949 -154.127961) (xy 369.547103 -154.096539)
			(xy 369.594217 -154.07144) (xy 369.644369 -154.053154) (xy 369.69658 -154.042037) (xy 369.749832 -154.038307)
			(xy 369.803084 -154.042037) (xy 369.855295 -154.053154) (xy 369.905447 -154.07144) (xy 369.952561 -154.096539)
			(xy 369.995715 -154.127961) (xy 370.034069 -154.165091) (xy 370.050822 -154.185874) (xy 370.058366 -154.194654)
			(xy 370.079139 -154.204824) (xy 370.0907 -154.205432) (xy 370.170964 -154.205432) (xy 370.182533 -154.204865)
			(xy 370.203305 -154.19467) (xy 370.210842 -154.185874) (xy 370.227595 -154.165091) (xy 370.265949 -154.127961)
			(xy 370.309103 -154.096539) (xy 370.356217 -154.07144) (xy 370.406369 -154.053154) (xy 370.45858 -154.042037)
			(xy 370.511832 -154.038307) (xy 370.565084 -154.042037) (xy 370.617295 -154.053154) (xy 370.667447 -154.07144)
			(xy 370.714561 -154.096539) (xy 370.757715 -154.127961) (xy 370.796069 -154.165091) (xy 370.812822 -154.185874)
			(xy 370.820366 -154.194654) (xy 370.841139 -154.204824) (xy 370.8527 -154.205432) (xy 370.932964 -154.205432)
			(xy 370.944533 -154.204865) (xy 370.965305 -154.19467) (xy 370.972842 -154.185874) (xy 370.989595 -154.165091)
			(xy 371.027949 -154.127961) (xy 371.071103 -154.096539) (xy 371.118217 -154.07144) (xy 371.168369 -154.053154)
			(xy 371.22058 -154.042037) (xy 371.273832 -154.038307) (xy 371.327084 -154.042037) (xy 371.379295 -154.053154)
			(xy 371.429447 -154.07144) (xy 371.476561 -154.096539) (xy 371.519715 -154.127961) (xy 371.558069 -154.165091)
			(xy 371.574822 -154.185874) (xy 371.582366 -154.194654) (xy 371.603139 -154.204824) (xy 371.6147 -154.205432)
			(xy 371.694964 -154.205432) (xy 371.706533 -154.204865) (xy 371.727305 -154.19467) (xy 371.734842 -154.185874)
			(xy 371.751595 -154.165091) (xy 371.789949 -154.127961) (xy 371.833103 -154.096539) (xy 371.880217 -154.07144)
			(xy 371.930369 -154.053154) (xy 371.98258 -154.042037) (xy 372.035832 -154.038307) (xy 372.089084 -154.042037)
			(xy 372.141295 -154.053154) (xy 372.191447 -154.07144) (xy 372.238561 -154.096539) (xy 372.281715 -154.127961)
			(xy 372.320069 -154.165091) (xy 372.336822 -154.185874) (xy 372.344366 -154.194654) (xy 372.365139 -154.204824)
			(xy 372.3767 -154.205432) (xy 372.456964 -154.205432) (xy 372.468533 -154.204865) (xy 372.489305 -154.19467)
			(xy 372.496842 -154.185874) (xy 372.515003 -154.163365) (xy 372.55703 -154.123633) (xy 372.604571 -154.090697)
			(xy 372.656538 -154.065314) (xy 372.711741 -154.048063) (xy 372.768914 -154.03934) (xy 372.797832 -154.038808)
			(xy 372.825085 -154.039248) (xy 372.879035 -154.047009) (xy 372.931332 -154.062369) (xy 372.98091 -154.085015)
			(xy 373.026761 -154.114487) (xy 373.067951 -154.150183) (xy 373.103642 -154.191378) (xy 373.133108 -154.237232)
			(xy 373.155747 -154.286813) (xy 373.171101 -154.339112) (xy 373.178855 -154.393063) (xy 373.17934 -154.420316)
			(xy 373.178784 -154.449232) (xy 373.170066 -154.506402) (xy 373.152817 -154.561601) (xy 373.127432 -154.613564)
			(xy 373.094494 -154.661098) (xy 373.054758 -154.703116) (xy 373.032274 -154.721306) (xy 373.023509 -154.728865)
			(xy 373.013328 -154.749626) (xy 373.012716 -154.761184) (xy 373.012716 -154.841448) (xy 373.013311 -154.853013)
			(xy 373.023488 -154.873784) (xy 373.032274 -154.881326) (xy 373.053071 -154.898062) (xy 373.090199 -154.936418)
			(xy 373.121617 -154.979576) (xy 373.146714 -155.026691) (xy 373.164998 -155.076845) (xy 373.176112 -155.129058)
			(xy 373.17984 -155.18231) (xy 373.17611 -155.235562) (xy 373.164992 -155.287774) (xy 373.146706 -155.337927)
			(xy 373.121607 -155.385041) (xy 373.090186 -155.428197) (xy 373.053057 -155.466552) (xy 373.032274 -155.483306)
			(xy 373.023509 -155.490865) (xy 373.013328 -155.511626) (xy 373.012716 -155.523184) (xy 373.012716 -155.603448)
			(xy 373.013311 -155.615013) (xy 373.023488 -155.635784) (xy 373.032274 -155.643326) (xy 373.053071 -155.660062)
			(xy 373.090199 -155.698418) (xy 373.121617 -155.741576) (xy 373.146714 -155.788691) (xy 373.164998 -155.838845)
			(xy 373.176112 -155.891058) (xy 373.17984 -155.94431) (xy 373.17611 -155.997562) (xy 373.164992 -156.049774)
			(xy 373.146706 -156.099927) (xy 373.121607 -156.147041) (xy 373.090186 -156.190197) (xy 373.053057 -156.228552)
			(xy 373.032274 -156.245306) (xy 373.023509 -156.252865) (xy 373.013328 -156.273626) (xy 373.012716 -156.285184)
			(xy 373.012716 -156.365448) (xy 373.013311 -156.377013) (xy 373.023488 -156.397784) (xy 373.032274 -156.405326)
			(xy 373.053071 -156.422062) (xy 373.090199 -156.460418) (xy 373.121617 -156.503576) (xy 373.146714 -156.550691)
			(xy 373.164998 -156.600845) (xy 373.176112 -156.653058) (xy 373.17984 -156.70631) (xy 373.17611 -156.759562)
			(xy 373.164992 -156.811774) (xy 373.146706 -156.861927) (xy 373.121607 -156.909041) (xy 373.090186 -156.952197)
			(xy 373.053057 -156.990552) (xy 373.032274 -157.007306) (xy 373.023509 -157.014865) (xy 373.013328 -157.035626)
			(xy 373.012716 -157.047184) (xy 373.012716 -157.127448) (xy 373.013311 -157.139013) (xy 373.023488 -157.159784)
			(xy 373.032274 -157.167326) (xy 373.053071 -157.184062) (xy 373.090199 -157.222418) (xy 373.121617 -157.265576)
			(xy 373.146714 -157.312691) (xy 373.164998 -157.362845) (xy 373.176112 -157.415058) (xy 373.17984 -157.46831)
			(xy 373.17611 -157.521562) (xy 373.164992 -157.573774) (xy 373.146706 -157.623927) (xy 373.121607 -157.671041)
			(xy 373.090186 -157.714197) (xy 373.053057 -157.752552) (xy 373.032274 -157.769306) (xy 373.023509 -157.776865)
			(xy 373.013328 -157.797626) (xy 373.012716 -157.809184) (xy 373.012716 -157.889448) (xy 373.013311 -157.901013)
			(xy 373.023488 -157.921784) (xy 373.032274 -157.929326) (xy 373.054765 -157.947509) (xy 373.0945 -157.98953)
			(xy 373.127439 -158.037066) (xy 373.152827 -158.089029) (xy 373.170081 -158.144228) (xy 373.178807 -158.201399)
			(xy 373.17934 -158.230316) (xy 373.178837 -158.257566) (xy 373.171079 -158.311512) (xy 373.155724 -158.363804)
			(xy 373.133083 -158.413379) (xy 373.103618 -158.459228) (xy 373.067929 -158.500417) (xy 373.026741 -158.536109)
			(xy 372.980893 -158.565575) (xy 372.931319 -158.588218) (xy 372.879027 -158.603576) (xy 372.825082 -158.611336)
			(xy 372.797832 -158.611824) (xy 372.768915 -158.611312) (xy 372.711742 -158.602585) (xy 372.656542 -158.585328)
			(xy 372.604579 -158.559936) (xy 372.557046 -158.52699) (xy 372.515031 -158.487245) (xy 372.496842 -158.464758)
			(xy 372.489265 -158.456013) (xy 372.468517 -158.445822) (xy 372.456964 -158.4452) (xy 372.3767 -158.4452)
			(xy 372.365132 -158.44577) (xy 372.344361 -158.455965) (xy 372.336822 -158.464758) (xy 372.320069 -158.485541)
			(xy 372.281715 -158.522671) (xy 372.238561 -158.554093) (xy 372.191447 -158.579192) (xy 372.141295 -158.597478)
			(xy 372.089084 -158.608595) (xy 372.035832 -158.612325) (xy 371.98258 -158.608595) (xy 371.930369 -158.597478)
			(xy 371.880217 -158.579192) (xy 371.833103 -158.554093) (xy 371.789949 -158.522671) (xy 371.751595 -158.485541)
			(xy 371.734842 -158.464758) (xy 371.727265 -158.456013) (xy 371.706517 -158.445822) (xy 371.694964 -158.4452)
			(xy 371.6147 -158.4452) (xy 371.603132 -158.44577) (xy 371.582361 -158.455965) (xy 371.574822 -158.464758)
			(xy 371.556608 -158.487222) (xy 371.514594 -158.526961) (xy 371.467065 -158.559903) (xy 371.415108 -158.585295)
			(xy 371.359914 -158.602555) (xy 371.302747 -158.611287) (xy 371.273832 -158.611824) (xy 371.246985 -158.611383)
			(xy 371.19382 -158.603872) (xy 371.142233 -158.588978) (xy 371.093246 -158.566998) (xy 371.047824 -158.538364)
			(xy 371.006867 -158.503644) (xy 370.971184 -158.463523) (xy 370.941481 -158.418794) (xy 370.918343 -158.370342)
			(xy 370.90985 -158.34487) (xy 370.90477 -158.328868) (xy 370.8781 -158.309056) (xy 370.430298 -158.309056)
			(xy 370.422678 -158.311596) (xy 370.394291 -158.320136) (xy 370.335731 -158.329324) (xy 370.306092 -158.329884)
			(xy 370.276456 -158.329298) (xy 370.217897 -158.320116) (xy 370.189506 -158.311596) (xy 370.181886 -158.309056)
			(xy 369.795298 -158.309056) (xy 369.787678 -158.311596) (xy 369.759291 -158.320136) (xy 369.700731 -158.329324)
			(xy 369.671092 -158.329884) (xy 369.641456 -158.329298) (xy 369.582897 -158.320116) (xy 369.554506 -158.311596)
			(xy 369.546886 -158.309056) (xy 369.160298 -158.309056) (xy 369.152678 -158.311596) (xy 369.124291 -158.320136)
			(xy 369.065731 -158.329324) (xy 369.036092 -158.329884) (xy 369.006456 -158.329298) (xy 368.947897 -158.320116)
			(xy 368.919506 -158.311596) (xy 368.911886 -158.309056) (xy 368.525298 -158.309056) (xy 368.517678 -158.311596)
			(xy 368.489291 -158.320136) (xy 368.430731 -158.329324) (xy 368.401092 -158.329884) (xy 368.371456 -158.329298)
			(xy 368.312897 -158.320116) (xy 368.284506 -158.311596) (xy 368.276886 -158.309056) (xy 367.859564 -158.309056)
			(xy 367.832894 -158.328868) (xy 367.827814 -158.34487) (xy 367.81935 -158.370349) (xy 367.79619 -158.418787)
			(xy 367.766471 -158.463501) (xy 367.730779 -158.50361) (xy 367.689819 -158.538322) (xy 367.6444 -158.566952)
			(xy 367.595417 -158.588935) (xy 367.543837 -158.603838) (xy 367.490677 -158.611365) (xy 367.463832 -158.611824)
			(xy 367.434915 -158.611312) (xy 367.377742 -158.602585) (xy 367.322542 -158.585328) (xy 367.270579 -158.559936)
			(xy 367.223046 -158.52699) (xy 367.181031 -158.487245) (xy 367.162842 -158.464758) (xy 367.155265 -158.456013)
			(xy 367.134517 -158.445822) (xy 367.122964 -158.4452) (xy 367.0427 -158.4452) (xy 367.031132 -158.44577)
			(xy 367.010361 -158.455965) (xy 367.002822 -158.464758) (xy 366.986069 -158.485541) (xy 366.947715 -158.522671)
			(xy 366.904561 -158.554093) (xy 366.857447 -158.579192) (xy 366.807295 -158.597478) (xy 366.755084 -158.608595)
			(xy 366.701832 -158.612325) (xy 366.64858 -158.608595) (xy 366.596369 -158.597478) (xy 366.546217 -158.579192)
			(xy 366.499103 -158.554093) (xy 366.455949 -158.522671) (xy 366.417595 -158.485541) (xy 366.400842 -158.464758)
			(xy 366.393265 -158.456013) (xy 366.372517 -158.445822) (xy 366.360964 -158.4452) (xy 366.2807 -158.4452)
			(xy 366.269132 -158.44577) (xy 366.248361 -158.455965) (xy 366.240822 -158.464758) (xy 366.222608 -158.487222)
			(xy 366.180594 -158.526961) (xy 366.133065 -158.559903) (xy 366.081108 -158.585295) (xy 366.025914 -158.602555)
			(xy 365.968747 -158.611287) (xy 365.939832 -158.611824) (xy 365.912581 -158.611315) (xy 365.858632 -158.603563)
			(xy 365.806336 -158.588212) (xy 365.756757 -158.565574) (xy 365.710905 -158.536111) (xy 365.669712 -158.500422)
			(xy 365.634018 -158.459234) (xy 365.604549 -158.413385) (xy 365.581905 -158.363809) (xy 365.566547 -158.311515)
			(xy 365.558788 -158.257567) (xy 365.558324 -158.230316) (xy 365.558845 -158.201399) (xy 365.567572 -158.144228)
			(xy 365.584829 -158.089028) (xy 365.61022 -158.037067) (xy 365.643164 -157.989533) (xy 365.682904 -157.947516)
			(xy 365.70539 -157.929326) (xy 365.714134 -157.921747) (xy 365.724328 -157.901001) (xy 365.724948 -157.889448)
			(xy 365.724948 -157.809184) (xy 365.724405 -157.797612) (xy 365.714193 -157.77684) (xy 365.70539 -157.769306)
			(xy 365.684622 -157.752534) (xy 365.647489 -157.714185) (xy 365.616065 -157.671033) (xy 365.590963 -157.623922)
			(xy 365.572675 -157.573771) (xy 365.561556 -157.52156) (xy 365.557825 -157.46831) (xy 364.25124 -157.46831)
			(xy 364.25124 -158.322772) (xy 364.250598 -158.347768) (xy 364.240797 -158.396791) (xy 364.221625 -158.442962)
			(xy 364.193819 -158.484508) (xy 364.176564 -158.502604) (xy 358.855518 -163.82365) (xy 358.84871 -163.831075)
			(xy 358.840971 -163.849655) (xy 358.840532 -163.859718) (xy 358.840532 -164.53358) (xy 366.362996 -164.53358)
			(xy 366.363451 -164.506209) (xy 366.371272 -164.45203) (xy 366.386764 -164.399527) (xy 366.409608 -164.34978)
			(xy 366.439334 -164.303814) (xy 366.456976 -164.282882) (xy 366.463072 -164.27577) (xy 366.469422 -164.258752)
			(xy 366.469422 -164.173408) (xy 366.463072 -164.15639) (xy 366.456976 -164.149278) (xy 366.439356 -164.12833)
			(xy 366.409642 -164.082361) (xy 366.386803 -164.032618) (xy 366.371307 -163.980121) (xy 366.363473 -163.925948)
			(xy 366.362996 -163.89858) (xy 366.363459 -163.871328) (xy 366.371219 -163.817379) (xy 366.386576 -163.765084)
			(xy 366.40922 -163.715506) (xy 366.438689 -163.669656) (xy 366.474383 -163.628466) (xy 366.515575 -163.592775)
			(xy 366.561427 -163.563309) (xy 366.611006 -163.540668) (xy 366.663303 -163.525313) (xy 366.717252 -163.517557)
			(xy 366.744504 -163.517072) (xy 366.771875 -163.517518) (xy 366.826056 -163.525338) (xy 366.87856 -163.540831)
			(xy 366.928306 -163.563677) (xy 366.974272 -163.593408) (xy 366.995202 -163.611052) (xy 367.002314 -163.617148)
			(xy 367.019332 -163.623498) (xy 367.104676 -163.623498) (xy 367.121694 -163.617148) (xy 367.128806 -163.611052)
			(xy 367.149732 -163.593405) (xy 367.195705 -163.563692) (xy 367.245454 -163.540857) (xy 367.297957 -163.525368)
			(xy 367.352134 -163.517544) (xy 367.379504 -163.517072) (xy 367.408516 -163.517609) (xy 367.465873 -163.526378)
			(xy 367.521242 -163.543729) (xy 367.573346 -163.569262) (xy 367.620984 -163.602388) (xy 367.642394 -163.621974)
			(xy 367.649506 -163.628832) (xy 367.667286 -163.635944) (xy 367.757202 -163.635944) (xy 367.774982 -163.628832)
			(xy 367.782094 -163.621974) (xy 367.803503 -163.602389) (xy 367.851147 -163.569273) (xy 367.903252 -163.543745)
			(xy 367.958618 -163.526392) (xy 368.015973 -163.517613) (xy 368.044984 -163.517072) (xy 368.072355 -163.51753)
			(xy 368.126535 -163.525347) (xy 368.179039 -163.540837) (xy 368.228786 -163.563681) (xy 368.274751 -163.593409)
			(xy 368.295682 -163.611052) (xy 368.302794 -163.617148) (xy 368.319812 -163.623498) (xy 368.405156 -163.623498)
			(xy 368.422174 -163.617148) (xy 368.429286 -163.611052) (xy 368.450219 -163.593411) (xy 368.496187 -163.563687)
			(xy 368.545933 -163.540841) (xy 368.598435 -163.525345) (xy 368.652613 -163.517516) (xy 368.707355 -163.517516)
			(xy 368.761533 -163.525345) (xy 368.814035 -163.540841) (xy 368.863781 -163.563687) (xy 368.909749 -163.593411)
			(xy 368.930682 -163.611052) (xy 368.937794 -163.617148) (xy 368.954812 -163.623498) (xy 369.040156 -163.623498)
			(xy 369.057174 -163.617148) (xy 369.064286 -163.611052) (xy 369.085219 -163.593411) (xy 369.131187 -163.563687)
			(xy 369.180933 -163.540841) (xy 369.233435 -163.525345) (xy 369.287613 -163.517516) (xy 369.342355 -163.517516)
			(xy 369.396533 -163.525345) (xy 369.449035 -163.540841) (xy 369.498781 -163.563687) (xy 369.544749 -163.593411)
			(xy 369.565682 -163.611052) (xy 369.572794 -163.617148) (xy 369.589812 -163.623498) (xy 369.675156 -163.623498)
			(xy 369.692174 -163.617148) (xy 369.699286 -163.611052) (xy 369.720219 -163.593414) (xy 369.766191 -163.5637)
			(xy 369.815938 -163.540863) (xy 369.868439 -163.525372) (xy 369.922615 -163.517545) (xy 369.949984 -163.517072)
			(xy 369.977558 -163.517558) (xy 370.032129 -163.525508) (xy 370.084988 -163.54123) (xy 370.135034 -163.564396)
			(xy 370.181224 -163.594524) (xy 370.222597 -163.630987) (xy 370.240814 -163.651692) (xy 370.248416 -163.659811)
			(xy 370.268568 -163.669165) (xy 370.279676 -163.669726) (xy 370.356892 -163.669726) (xy 370.368007 -163.669193)
			(xy 370.388167 -163.659832) (xy 370.395754 -163.651692) (xy 370.413984 -163.630998) (xy 370.455349 -163.594527)
			(xy 370.501535 -163.564393) (xy 370.551579 -163.541224) (xy 370.604438 -163.525504) (xy 370.65901 -163.51756)
			(xy 370.686584 -163.517072) (xy 370.713834 -163.517593) (xy 370.767779 -163.525347) (xy 370.820072 -163.540699)
			(xy 370.869648 -163.563337) (xy 370.915497 -163.592799) (xy 370.956687 -163.628487) (xy 370.992379 -163.669674)
			(xy 371.021846 -163.71552) (xy 371.044488 -163.765094) (xy 371.059845 -163.817385) (xy 371.067604 -163.87133)
			(xy 371.068092 -163.89858) (xy 371.067616 -163.92595) (xy 371.059801 -163.980129) (xy 371.044314 -164.032632)
			(xy 371.021475 -164.082379) (xy 370.991752 -164.128346) (xy 370.974112 -164.149278) (xy 370.968016 -164.15639)
			(xy 370.961666 -164.173408) (xy 370.961666 -164.258752) (xy 370.968016 -164.27577) (xy 370.974112 -164.282882)
			(xy 370.991758 -164.303808) (xy 371.021468 -164.349783) (xy 371.044303 -164.399532) (xy 371.059792 -164.452034)
			(xy 371.067619 -164.50621) (xy 371.068092 -164.53358) (xy 371.067581 -164.561585) (xy 371.059415 -164.616996)
			(xy 371.04324 -164.670619) (xy 371.019404 -164.721303) (xy 370.988418 -164.76796) (xy 370.970048 -164.789104)
			(xy 370.963444 -164.79647) (xy 370.95684 -164.813996) (xy 370.958364 -164.903404) (xy 370.96573 -164.920676)
			(xy 370.972588 -164.927788) (xy 370.992762 -164.949287) (xy 371.026905 -164.997347) (xy 371.053251 -165.050087)
			(xy 371.071172 -165.106251) (xy 371.080242 -165.164503) (xy 371.080792 -165.19398) (xy 371.080326 -165.221233)
			(xy 371.072571 -165.275185) (xy 371.057217 -165.327484) (xy 371.034576 -165.377065) (xy 371.005108 -165.422919)
			(xy 370.969415 -165.464112) (xy 370.928222 -165.499806) (xy 370.882368 -165.529274) (xy 370.832787 -165.551916)
			(xy 370.780489 -165.567271) (xy 370.726537 -165.575026) (xy 370.699284 -165.575488) (xy 370.671711 -165.574969)
			(xy 370.617141 -165.567028) (xy 370.564282 -165.551314) (xy 370.514235 -165.528154) (xy 370.468044 -165.49803)
			(xy 370.426671 -165.461571) (xy 370.408454 -165.440868) (xy 370.400871 -165.432728) (xy 370.380705 -165.423387)
			(xy 370.369592 -165.422834) (xy 370.292376 -165.422834) (xy 370.281261 -165.423362) (xy 370.261102 -165.432727)
			(xy 370.253514 -165.440868) (xy 370.235292 -165.461569) (xy 370.193926 -165.498042) (xy 370.147739 -165.528176)
			(xy 370.097693 -165.551344) (xy 370.044832 -165.567062) (xy 369.990258 -165.575002) (xy 369.962684 -165.575488)
			(xy 369.935313 -165.575034) (xy 369.881134 -165.567214) (xy 369.82863 -165.551722) (xy 369.778884 -165.528878)
			(xy 369.732917 -165.49915) (xy 369.711986 -165.481508) (xy 369.704874 -165.475412) (xy 369.687856 -165.469062)
			(xy 369.602512 -165.469062) (xy 369.585494 -165.475412) (xy 369.578382 -165.481508) (xy 369.557449 -165.499149)
			(xy 369.511481 -165.528873) (xy 369.461735 -165.551719) (xy 369.409233 -165.567215) (xy 369.355055 -165.575044)
			(xy 369.300313 -165.575044) (xy 369.246135 -165.567215) (xy 369.193633 -165.551719) (xy 369.143887 -165.528873)
			(xy 369.097919 -165.499149) (xy 369.076986 -165.481508) (xy 369.069874 -165.475412) (xy 369.052856 -165.469062)
			(xy 368.967512 -165.469062) (xy 368.950494 -165.475412) (xy 368.943382 -165.481508) (xy 368.922449 -165.499149)
			(xy 368.876481 -165.528873) (xy 368.826735 -165.551719) (xy 368.774233 -165.567215) (xy 368.720055 -165.575044)
			(xy 368.665313 -165.575044) (xy 368.611135 -165.567215) (xy 368.558633 -165.551719) (xy 368.508887 -165.528873)
			(xy 368.462919 -165.499149) (xy 368.441986 -165.481508) (xy 368.434874 -165.475412) (xy 368.417856 -165.469062)
			(xy 368.332512 -165.469062) (xy 368.315494 -165.475412) (xy 368.308382 -165.481508) (xy 368.287431 -165.499123)
			(xy 368.241463 -165.528838) (xy 368.19172 -165.551679) (xy 368.139224 -165.567176) (xy 368.085052 -165.57501)
			(xy 368.057684 -165.575488) (xy 368.028671 -165.57497) (xy 367.971313 -165.566198) (xy 367.915943 -165.548843)
			(xy 367.86384 -165.523305) (xy 367.816203 -165.490174) (xy 367.794794 -165.470586) (xy 367.787682 -165.463728)
			(xy 367.769902 -165.456616) (xy 367.679986 -165.456616) (xy 367.662206 -165.463728) (xy 367.655094 -165.470586)
			(xy 367.633699 -165.490187) (xy 367.58605 -165.523298) (xy 367.533941 -165.548822) (xy 367.478572 -165.566172)
			(xy 367.421216 -165.574948) (xy 367.392204 -165.575488) (xy 367.364834 -165.575023) (xy 367.310654 -165.567205)
			(xy 367.258151 -165.551716) (xy 367.208404 -165.528874) (xy 367.162438 -165.499149) (xy 367.141506 -165.481508)
			(xy 367.134394 -165.475412) (xy 367.117376 -165.469062) (xy 367.032032 -165.469062) (xy 367.015014 -165.475412)
			(xy 367.007902 -165.481508) (xy 366.986981 -165.499161) (xy 366.941005 -165.52887) (xy 366.891255 -165.551704)
			(xy 366.838752 -165.567191) (xy 366.784574 -165.575016) (xy 366.757204 -165.575488) (xy 366.72995 -165.575041)
			(xy 366.675998 -165.567284) (xy 366.623698 -165.551927) (xy 366.574117 -165.529284) (xy 366.528263 -165.499814)
			(xy 366.48707 -165.464119) (xy 366.451376 -165.422924) (xy 366.421908 -165.377069) (xy 366.399267 -165.327487)
			(xy 366.383913 -165.275187) (xy 366.376158 -165.221234) (xy 366.375696 -165.19398) (xy 366.376186 -165.165974)
			(xy 366.384357 -165.110563) (xy 366.400537 -165.05694) (xy 366.424378 -165.006256) (xy 366.455368 -164.959599)
			(xy 366.47374 -164.938456) (xy 366.480344 -164.93109) (xy 366.486948 -164.913564) (xy 366.485424 -164.824156)
			(xy 366.478058 -164.806884) (xy 366.4712 -164.799772) (xy 366.451022 -164.778276) (xy 366.416876 -164.730217)
			(xy 366.390529 -164.677477) (xy 366.372609 -164.621311) (xy 366.363543 -164.563057) (xy 366.362996 -164.53358)
			(xy 358.840532 -164.53358) (xy 358.840532 -165.29431) (xy 358.839913 -165.319293) (xy 358.830173 -165.368301)
			(xy 358.811068 -165.414471) (xy 358.783331 -165.456032) (xy 358.76611 -165.474142) (xy 358.384856 -165.855396)
			(xy 358.375832 -165.864032) (xy 358.955338 -165.864032) (xy 358.959409 -165.80841) (xy 358.971535 -165.753973)
			(xy 358.991458 -165.701882) (xy 359.018754 -165.653247) (xy 359.05284 -165.609104) (xy 359.092989 -165.570395)
			(xy 359.138347 -165.537944) (xy 359.187947 -165.512443) (xy 359.240731 -165.494436) (xy 359.295574 -165.484306)
			(xy 359.351308 -165.482269) (xy 359.406745 -165.488369) (xy 359.460702 -165.502475) (xy 359.512031 -165.524287)
			(xy 359.559637 -165.553341) (xy 359.602505 -165.589016) (xy 359.639722 -165.630553) (xy 359.670495 -165.677066)
			(xy 359.694167 -165.727563) (xy 359.710235 -165.78097) (xy 359.718355 -165.836146) (xy 359.718864 -165.864032)
			(xy 359.718355 -165.891918) (xy 359.710235 -165.947094) (xy 359.694167 -166.000501) (xy 359.670495 -166.050998)
			(xy 359.639722 -166.097511) (xy 359.602505 -166.139048) (xy 359.559637 -166.174723) (xy 359.512031 -166.203777)
			(xy 359.460702 -166.225589) (xy 359.406745 -166.239695) (xy 359.351308 -166.245795) (xy 359.295574 -166.243758)
			(xy 359.240731 -166.233628) (xy 359.187947 -166.215621) (xy 359.138347 -166.19012) (xy 359.092989 -166.157669)
			(xy 359.05284 -166.11896) (xy 359.018754 -166.074817) (xy 358.991458 -166.026182) (xy 358.971535 -165.974091)
			(xy 358.959409 -165.919654) (xy 358.955338 -165.864032) (xy 358.375832 -165.864032) (xy 358.368089 -165.871442)
			(xy 358.329879 -165.897774) (xy 358.30891 -165.90772) (xy 358.30378 -165.910247) (xy 358.294674 -165.917161)
			(xy 358.290876 -165.921436) (xy 358.272642 -165.942289) (xy 358.231181 -165.979023) (xy 358.184849 -166.009381)
			(xy 358.134616 -166.032726) (xy 358.081537 -166.048568) (xy 358.026726 -166.056576) (xy 357.99903 -166.057072)
			(xy 357.971776 -166.056617) (xy 357.917823 -166.048863) (xy 357.865523 -166.033509) (xy 357.815941 -166.010867)
			(xy 357.770086 -165.981399) (xy 357.728892 -165.945704) (xy 357.693197 -165.90451) (xy 357.66373 -165.858654)
			(xy 357.641089 -165.809071) (xy 357.625736 -165.756771) (xy 357.617983 -165.702818) (xy 357.617522 -165.675564)
			(xy 357.617982 -165.648088) (xy 357.625879 -165.593707) (xy 357.641505 -165.541025) (xy 357.664536 -165.491132)
			(xy 357.694494 -165.445065) (xy 357.712264 -165.424104) (xy 357.71836 -165.416992) (xy 357.72471 -165.399974)
			(xy 357.72471 -165.314122) (xy 357.71836 -165.297104) (xy 357.712264 -165.289992) (xy 357.69451 -165.269022)
			(xy 357.664585 -165.222942) (xy 357.64157 -165.17305) (xy 357.625942 -165.120375) (xy 357.618023 -165.066004)
			(xy 357.617522 -165.038532) (xy 357.618056 -165.010126) (xy 357.62649 -164.953942) (xy 357.643161 -164.89963)
			(xy 357.667701 -164.84839) (xy 357.699567 -164.801355) (xy 357.738054 -164.759565) (xy 357.782313 -164.723944)
			(xy 357.831364 -164.695278) (xy 357.884123 -164.674202) (xy 357.911654 -164.667184) (xy 357.92918 -164.66312)
			(xy 357.951024 -164.635688) (xy 357.951024 -163.575238) (xy 357.951624 -163.550254) (xy 357.961372 -163.501246)
			(xy 357.980483 -163.455077) (xy 358.008224 -163.413516) (xy 358.025446 -163.395406) (xy 363.346492 -158.07436)
			(xy 363.353198 -158.066889) (xy 363.36078 -158.048322) (xy 363.361224 -158.038292) (xy 363.361224 -151.99233)
			(xy 363.361878 -151.967335) (xy 363.371677 -151.918313) (xy 363.390845 -151.872143) (xy 363.418647 -151.830595)
			(xy 363.4359 -151.812498) (xy 365.037878 -150.21052) (xy 365.055992 -150.193285) (xy 365.09753 -150.16547)
			(xy 365.143696 -150.146291) (xy 365.192715 -150.136485) (xy 365.21771 -150.135844) (xy 371.926866 -150.135844)
			(xy 371.936914 -150.135498) (xy 371.955511 -150.127894) (xy 371.962934 -150.121112) (xy 373.587518 -148.496528)
			(xy 373.594341 -148.489114) (xy 373.60207 -148.470525) (xy 373.602504 -148.46046) (xy 373.602504 -147.414234)
			(xy 373.603107 -147.38925) (xy 373.612855 -147.340243) (xy 373.631965 -147.294074) (xy 373.659705 -147.252513)
			(xy 373.676926 -147.234402) (xy 374.012968 -146.89836) (xy 374.019671 -146.890886) (xy 374.027255 -146.872321)
			(xy 374.0277 -146.862292) (xy 374.0277 -146.329908) (xy 374.010936 -146.304508) (xy 373.996458 -146.298666)
			(xy 373.987032 -146.295286) (xy 373.967027 -146.295274) (xy 373.948527 -146.302886) (xy 373.941086 -146.309588)
			(xy 373.248936 -147.001738) (xy 373.242235 -147.009213) (xy 373.23465 -147.027777) (xy 373.234204 -147.037806)
			(xy 373.234204 -148.03628) (xy 373.233576 -148.061277) (xy 373.223773 -148.110301) (xy 373.204597 -148.156472)
			(xy 373.176785 -148.198017) (xy 373.159528 -148.216112) (xy 372.421658 -148.953982) (xy 372.403541 -148.971196)
			(xy 372.361984 -148.998937) (xy 372.315816 -149.018047) (xy 372.266809 -149.027791) (xy 372.241826 -149.028404)
			(xy 356.39375 -149.028404) (xy 356.38368 -149.028828) (xy 356.365081 -149.036547) (xy 356.357682 -149.04339)
			(xy 352.646304 -152.754768) (xy 358.696256 -152.754768) (xy 358.696256 -152.670072) (xy 358.704307 -152.585758)
			(xy 358.720336 -152.502592) (xy 358.744197 -152.421325) (xy 358.775676 -152.342695) (xy 358.814487 -152.267414)
			(xy 358.860277 -152.196162) (xy 358.912633 -152.129586) (xy 358.971081 -152.068288) (xy 359.035091 -152.012823)
			(xy 359.104083 -151.963694) (xy 359.177433 -151.921345) (xy 359.254476 -151.886161) (xy 359.334515 -151.858459)
			(xy 359.416824 -151.838491) (xy 359.500659 -151.826438) (xy 359.58526 -151.822408) (xy 359.669861 -151.826438)
			(xy 359.753696 -151.838491) (xy 359.836005 -151.858459) (xy 359.916044 -151.886161) (xy 359.993087 -151.921345)
			(xy 360.066437 -151.963694) (xy 360.135429 -152.012823) (xy 360.199439 -152.068288) (xy 360.257887 -152.129586)
			(xy 360.310243 -152.196162) (xy 360.356033 -152.267414) (xy 360.394844 -152.342695) (xy 360.426323 -152.421325)
			(xy 360.450184 -152.502592) (xy 360.466213 -152.585758) (xy 360.474264 -152.670072) (xy 360.474768 -152.71242)
			(xy 361.119173 -152.71242) (xy 361.123176 -152.624558) (xy 361.135152 -152.537424) (xy 361.155003 -152.45174)
			(xy 361.182562 -152.368216) (xy 361.217603 -152.287544) (xy 361.259834 -152.210393) (xy 361.308906 -152.137402)
			(xy 361.364413 -152.069176) (xy 361.425893 -152.00628) (xy 361.492838 -151.949235) (xy 361.564693 -151.898514)
			(xy 361.640863 -151.854537) (xy 361.720716 -151.817669) (xy 361.803591 -151.788216) (xy 361.888801 -151.76642)
			(xy 361.97564 -151.752464) (xy 362.063388 -151.746461) (xy 362.151318 -151.748463) (xy 362.238703 -151.758453)
			(xy 362.324816 -151.776348) (xy 362.408946 -151.801999) (xy 362.490394 -151.835194) (xy 362.568487 -151.875658)
			(xy 362.642576 -151.923056) (xy 362.712048 -151.976995) (xy 362.776327 -152.037028) (xy 362.834881 -152.102657)
			(xy 362.887225 -152.173339) (xy 362.932924 -152.248488) (xy 362.9716 -152.327481) (xy 363.002932 -152.409664)
			(xy 363.026662 -152.494356) (xy 363.042592 -152.580855) (xy 363.05059 -152.668443) (xy 363.05109 -152.71242)
			(xy 363.05059 -152.756397) (xy 363.042592 -152.843985) (xy 363.026662 -152.930484) (xy 363.002932 -153.015176)
			(xy 362.9716 -153.097359) (xy 362.932924 -153.176352) (xy 362.887225 -153.251501) (xy 362.834881 -153.322183)
			(xy 362.776327 -153.387812) (xy 362.712048 -153.447845) (xy 362.642576 -153.501784) (xy 362.568487 -153.549182)
			(xy 362.490394 -153.589646) (xy 362.408946 -153.622841) (xy 362.324816 -153.648492) (xy 362.238703 -153.666387)
			(xy 362.151318 -153.676377) (xy 362.063388 -153.678379) (xy 361.97564 -153.672376) (xy 361.888801 -153.65842)
			(xy 361.803591 -153.636624) (xy 361.720716 -153.607171) (xy 361.640863 -153.570303) (xy 361.564693 -153.526326)
			(xy 361.492838 -153.475605) (xy 361.425893 -153.41856) (xy 361.364413 -153.355664) (xy 361.308906 -153.287438)
			(xy 361.259834 -153.214447) (xy 361.217603 -153.137296) (xy 361.182562 -153.056624) (xy 361.155003 -152.9731)
			(xy 361.135152 -152.887416) (xy 361.123176 -152.800282) (xy 361.119173 -152.71242) (xy 360.474768 -152.71242)
			(xy 360.474264 -152.754768) (xy 360.466213 -152.839082) (xy 360.450184 -152.922248) (xy 360.426323 -153.003515)
			(xy 360.394844 -153.082145) (xy 360.356033 -153.157426) (xy 360.310243 -153.228678) (xy 360.257887 -153.295254)
			(xy 360.199439 -153.356552) (xy 360.135429 -153.412017) (xy 360.066437 -153.461146) (xy 359.993087 -153.503495)
			(xy 359.916044 -153.538679) (xy 359.836005 -153.566381) (xy 359.753696 -153.586349) (xy 359.669861 -153.598402)
			(xy 359.58526 -153.602433) (xy 359.500659 -153.598402) (xy 359.416824 -153.586349) (xy 359.334515 -153.566381)
			(xy 359.254476 -153.538679) (xy 359.177433 -153.503495) (xy 359.104083 -153.461146) (xy 359.035091 -153.412017)
			(xy 358.971081 -153.356552) (xy 358.912633 -153.295254) (xy 358.860277 -153.228678) (xy 358.814487 -153.157426)
			(xy 358.775676 -153.082145) (xy 358.744197 -153.003515) (xy 358.720336 -152.922248) (xy 358.704307 -152.839082)
			(xy 358.696256 -152.754768) (xy 352.646304 -152.754768) (xy 350.600518 -154.800554) (xy 350.593708 -154.807978)
			(xy 350.58597 -154.826559) (xy 350.585532 -154.836622) (xy 350.585532 -157.03931) (xy 350.584913 -157.064293)
			(xy 350.575173 -157.113301) (xy 350.556068 -157.159471) (xy 350.528331 -157.201032) (xy 350.51111 -157.219142)
			(xy 350.37268 -157.357572) (xy 350.649538 -157.357572) (xy 350.653609 -157.30195) (xy 350.665735 -157.247513)
			(xy 350.685658 -157.195422) (xy 350.712954 -157.146787) (xy 350.74704 -157.102644) (xy 350.787189 -157.063935)
			(xy 350.832547 -157.031484) (xy 350.882147 -157.005983) (xy 350.934931 -156.987976) (xy 350.989774 -156.977846)
			(xy 351.045508 -156.975809) (xy 351.100945 -156.981909) (xy 351.154902 -156.996015) (xy 351.206231 -157.017827)
			(xy 351.253837 -157.046881) (xy 351.296705 -157.082556) (xy 351.333922 -157.124093) (xy 351.364695 -157.170606)
			(xy 351.388367 -157.221103) (xy 351.404435 -157.27451) (xy 351.412555 -157.329686) (xy 351.413064 -157.357572)
			(xy 351.412555 -157.385458) (xy 351.404435 -157.440634) (xy 351.388367 -157.494041) (xy 351.364695 -157.544538)
			(xy 351.333922 -157.591051) (xy 351.296705 -157.632588) (xy 351.253837 -157.668263) (xy 351.206231 -157.697317)
			(xy 351.154902 -157.719129) (xy 351.100945 -157.733235) (xy 351.045508 -157.739335) (xy 350.989774 -157.737298)
			(xy 350.934931 -157.727168) (xy 350.882147 -157.709161) (xy 350.832547 -157.68366) (xy 350.787189 -157.651209)
			(xy 350.74704 -157.6125) (xy 350.712954 -157.568357) (xy 350.685658 -157.519722) (xy 350.665735 -157.467631)
			(xy 350.653609 -157.413194) (xy 350.649538 -157.357572) (xy 350.37268 -157.357572) (xy 350.198182 -157.53207)
			(xy 350.180096 -157.549318) (xy 350.138528 -157.577054) (xy 350.092351 -157.596154) (xy 350.043336 -157.605886)
			(xy 350.01835 -157.606492) (xy 349.992188 -157.606492) (xy 349.973646 -157.614366) (xy 349.966534 -157.621478)
			(xy 349.944926 -157.642372) (xy 349.89636 -157.677784) (xy 349.84284 -157.705138) (xy 349.785692 -157.723759)
			(xy 349.726331 -157.733184) (xy 349.696278 -157.733746) (xy 349.669028 -157.733243) (xy 349.615083 -157.725484)
			(xy 349.562791 -157.710128) (xy 349.513216 -157.687487) (xy 349.467367 -157.658022) (xy 349.426178 -157.622333)
			(xy 349.390487 -157.581145) (xy 349.36102 -157.535298) (xy 349.338377 -157.485724) (xy 349.323019 -157.433433)
			(xy 349.315258 -157.379488) (xy 349.31477 -157.352238) (xy 349.315343 -157.323144) (xy 349.324183 -157.265631)
			(xy 349.341663 -157.210131) (xy 349.367376 -157.157932) (xy 349.400726 -157.110249) (xy 349.420434 -157.08884)
			(xy 349.427292 -157.081474) (xy 349.434404 -157.063694) (xy 349.433896 -156.973016) (xy 349.426784 -156.954982)
			(xy 349.419672 -156.94787) (xy 349.399553 -156.926369) (xy 349.365486 -156.878344) (xy 349.3392 -156.825655)
			(xy 349.32132 -156.769554) (xy 349.31227 -156.711373) (xy 349.311722 -156.681932) (xy 348.165539 -156.681932)
			(xy 348.176228 -156.718335) (xy 348.183984 -156.772283) (xy 348.18447 -156.799534) (xy 348.183812 -156.831097)
			(xy 348.173425 -156.893362) (xy 348.152938 -156.953071) (xy 348.138496 -156.981144) (xy 348.13367 -156.990034)
			(xy 348.131638 -157.009592) (xy 348.157292 -157.09773) (xy 348.169738 -157.113224) (xy 348.178628 -157.118304)
			(xy 348.185994 -157.122368) (xy 348.195646 -157.12821) (xy 348.217744 -157.130242) (xy 348.312232 -157.096714)
			(xy 348.328234 -157.08122) (xy 348.332298 -157.070806) (xy 348.342982 -157.044024) (xy 348.371271 -156.993781)
			(xy 348.406801 -156.948371) (xy 348.448765 -156.908828) (xy 348.496204 -156.876054) (xy 348.548037 -156.850798)
			(xy 348.603082 -156.833634) (xy 348.660084 -156.824954) (xy 348.688914 -156.824426) (xy 348.716167 -156.824845)
			(xy 348.770118 -156.832604) (xy 348.822416 -156.847961) (xy 348.871996 -156.870605) (xy 348.917848 -156.900075)
			(xy 348.959041 -156.935769) (xy 348.994734 -156.976963) (xy 349.024201 -157.022817) (xy 349.046844 -157.072397)
			(xy 349.062199 -157.124696) (xy 349.069956 -157.178647) (xy 349.069956 -157.233153) (xy 349.062199 -157.287104)
			(xy 349.046844 -157.339403) (xy 349.024201 -157.388983) (xy 348.994734 -157.434837) (xy 348.959041 -157.476031)
			(xy 348.917848 -157.511725) (xy 348.871996 -157.541195) (xy 348.822416 -157.563839) (xy 348.770118 -157.579196)
			(xy 348.716167 -157.586955) (xy 348.688914 -157.587442) (xy 348.663679 -157.587033) (xy 348.613646 -157.580418)
			(xy 348.564926 -157.567248) (xy 348.518373 -157.547755) (xy 348.496382 -157.535372) (xy 348.48673 -157.52953)
			(xy 348.464632 -157.527498) (xy 348.370144 -157.561026) (xy 348.354142 -157.57652) (xy 348.350078 -157.586934)
			(xy 348.339352 -157.613697) (xy 348.311066 -157.663936) (xy 348.275539 -157.709344) (xy 348.233582 -157.748886)
			(xy 348.186149 -157.781661) (xy 348.134323 -157.806921) (xy 348.079285 -157.824092) (xy 348.022289 -157.832781)
			(xy 347.993462 -157.833314) (xy 347.96621 -157.832858) (xy 347.912262 -157.825096) (xy 347.859967 -157.809736)
			(xy 347.81039 -157.787091) (xy 347.76454 -157.757622) (xy 347.72335 -157.721927) (xy 347.687659 -157.680735)
			(xy 347.658193 -157.634882) (xy 347.635552 -157.585303) (xy 347.620197 -157.533007) (xy 347.61244 -157.479058)
			(xy 347.611954 -157.451806) (xy 347.612586 -157.420242) (xy 347.622984 -157.357976) (xy 347.643481 -157.298267)
			(xy 347.657928 -157.270196) (xy 347.662754 -157.261306) (xy 347.664786 -157.241748) (xy 347.639132 -157.15361)
			(xy 347.626686 -157.138116) (xy 347.617796 -157.133036) (xy 347.592682 -157.118509) (xy 347.5468 -157.083002)
			(xy 347.506825 -157.040954) (xy 347.473682 -156.993337) (xy 347.448133 -156.941249) (xy 347.430769 -156.885891)
			(xy 347.421991 -156.828542) (xy 347.421454 -156.799534) (xy 339.643466 -156.799534) (xy 337.369404 -159.073596)
			(xy 343.63533 -159.073596) (xy 343.635782 -159.046021) (xy 343.643736 -158.991447) (xy 343.659463 -158.938586)
			(xy 343.682636 -158.88854) (xy 343.712771 -158.842351) (xy 343.749241 -158.800981) (xy 343.76995 -158.782766)
			(xy 343.778087 -158.775181) (xy 343.787429 -158.755016) (xy 343.787984 -158.743904) (xy 343.787984 -158.666688)
			(xy 343.787444 -158.655575) (xy 343.778086 -158.635416) (xy 343.76995 -158.627826) (xy 343.749238 -158.609616)
			(xy 343.71277 -158.568246) (xy 343.68264 -158.522056) (xy 343.659474 -158.472008) (xy 343.643757 -158.419146)
			(xy 343.635816 -158.364572) (xy 343.635817 -158.309423) (xy 343.643759 -158.254849) (xy 343.659476 -158.201987)
			(xy 343.682642 -158.15194) (xy 343.712773 -158.10575) (xy 343.749242 -158.06438) (xy 343.76995 -158.046166)
			(xy 343.778087 -158.038581) (xy 343.787429 -158.018416) (xy 343.787984 -158.007304) (xy 343.787984 -157.930088)
			(xy 343.787444 -157.918975) (xy 343.778086 -157.898816) (xy 343.76995 -157.891226) (xy 343.749238 -157.873016)
			(xy 343.71277 -157.831646) (xy 343.682639 -157.785455) (xy 343.659474 -157.735407) (xy 343.643757 -157.682545)
			(xy 343.635816 -157.627971) (xy 343.63533 -157.600396) (xy 343.635752 -157.573141) (xy 343.64351 -157.519187)
			(xy 343.658869 -157.466886) (xy 343.681514 -157.417303) (xy 343.710986 -157.371448) (xy 343.746685 -157.330255)
			(xy 343.787882 -157.294561) (xy 343.83374 -157.265094) (xy 343.883325 -157.242454) (xy 343.935628 -157.227101)
			(xy 343.989583 -157.219349) (xy 344.016838 -157.218888) (xy 344.044694 -157.219386) (xy 344.09981 -157.227514)
			(xy 344.153161 -157.243564) (xy 344.203613 -157.267195) (xy 344.250097 -157.297905) (xy 344.291626 -157.335043)
			(xy 344.327319 -157.37782) (xy 344.356418 -157.425329) (xy 344.378306 -157.476562) (xy 344.3859 -157.503368)
			(xy 344.388186 -157.512258) (xy 344.398854 -157.527498) (xy 344.470736 -157.57525) (xy 344.48877 -157.579314)
			(xy 344.497914 -157.578044) (xy 344.510931 -157.576375) (xy 344.537115 -157.574595) (xy 344.550238 -157.574488)
			(xy 344.564387 -157.574577) (xy 344.59261 -157.576615) (xy 344.606626 -157.578552) (xy 344.616786 -157.580076)
			(xy 344.636344 -157.57525) (xy 344.710766 -157.51937) (xy 344.720926 -157.501844) (xy 344.722196 -157.491684)
			(xy 344.726294 -157.464532) (xy 344.741264 -157.411701) (xy 344.763653 -157.361562) (xy 344.792999 -157.31515)
			(xy 344.828695 -157.273425) (xy 344.870004 -157.237248) (xy 344.916072 -157.207366) (xy 344.965949 -157.184398)
			(xy 345.018603 -157.168817) (xy 345.072947 -157.160945) (xy 345.100402 -157.160468) (xy 345.127652 -157.160976)
			(xy 345.181598 -157.168732) (xy 345.233891 -157.184086) (xy 345.283466 -157.206726) (xy 345.329316 -157.23619)
			(xy 345.370505 -157.271879) (xy 345.406197 -157.313067) (xy 345.435664 -157.358914) (xy 345.458306 -157.408489)
			(xy 345.473663 -157.460781) (xy 345.481423 -157.514726) (xy 345.48191 -157.541976) (xy 345.481424 -157.56955)
			(xy 345.473475 -157.624122) (xy 345.457754 -157.676981) (xy 345.434588 -157.727027) (xy 345.404459 -157.773217)
			(xy 345.367995 -157.814589) (xy 345.34729 -157.832806) (xy 345.339172 -157.840409) (xy 345.329818 -157.86056)
			(xy 345.329256 -157.871668) (xy 345.329256 -157.948884) (xy 345.329799 -157.959997) (xy 345.339153 -157.980157)
			(xy 345.34729 -157.987746) (xy 345.367976 -158.005984) (xy 345.404449 -158.047347) (xy 345.434584 -158.093531)
			(xy 345.457755 -158.143574) (xy 345.473476 -158.196432) (xy 345.481422 -158.251003) (xy 345.481456 -158.252922)
			(xy 350.070418 -158.252922) (xy 350.074489 -158.1973) (xy 350.086615 -158.142863) (xy 350.106538 -158.090772)
			(xy 350.133834 -158.042137) (xy 350.16792 -157.997994) (xy 350.208069 -157.959285) (xy 350.253427 -157.926834)
			(xy 350.303027 -157.901333) (xy 350.355811 -157.883326) (xy 350.410654 -157.873196) (xy 350.466388 -157.871159)
			(xy 350.521825 -157.877259) (xy 350.575782 -157.891365) (xy 350.627111 -157.913177) (xy 350.674717 -157.942231)
			(xy 350.717585 -157.977906) (xy 350.754802 -158.019443) (xy 350.785575 -158.065956) (xy 350.809247 -158.116453)
			(xy 350.825315 -158.16986) (xy 350.833435 -158.225036) (xy 350.833944 -158.252922) (xy 350.833435 -158.280808)
			(xy 350.825315 -158.335984) (xy 350.809247 -158.389391) (xy 350.785575 -158.439888) (xy 350.754802 -158.486401)
			(xy 350.717585 -158.527938) (xy 350.674717 -158.563613) (xy 350.627111 -158.592667) (xy 350.575782 -158.614479)
			(xy 350.521825 -158.628585) (xy 350.466388 -158.634685) (xy 350.410654 -158.632648) (xy 350.355811 -158.622518)
			(xy 350.303027 -158.604511) (xy 350.253427 -158.57901) (xy 350.208069 -158.546559) (xy 350.16792 -158.50785)
			(xy 350.133834 -158.463707) (xy 350.106538 -158.415072) (xy 350.086615 -158.362981) (xy 350.074489 -158.308544)
			(xy 350.070418 -158.252922) (xy 345.481456 -158.252922) (xy 345.48191 -158.278576) (xy 345.481422 -158.305828)
			(xy 345.473669 -158.359778) (xy 345.458316 -158.412075) (xy 345.435676 -158.461655) (xy 345.406211 -158.507508)
			(xy 345.37052 -158.548701) (xy 345.329329 -158.584395) (xy 345.283478 -158.613864) (xy 345.2339 -158.636507)
			(xy 345.181604 -158.651863) (xy 345.127654 -158.659621) (xy 345.100402 -158.660084) (xy 345.066112 -158.65856)
			(xy 345.055952 -158.657544) (xy 345.036648 -158.66364) (xy 344.966036 -158.722822) (xy 344.956638 -158.740856)
			(xy 344.955622 -158.751016) (xy 344.952637 -158.779185) (xy 344.939468 -158.834276) (xy 344.918293 -158.886813)
			(xy 344.88958 -158.935639) (xy 344.85396 -158.979681) (xy 344.812216 -159.017968) (xy 344.765268 -159.049658)
			(xy 344.714148 -159.074055) (xy 344.659981 -159.090621) (xy 344.60396 -159.098991) (xy 344.575638 -159.099504)
			(xy 344.557619 -159.099288) (xy 344.521744 -159.09585) (xy 344.50401 -159.092646) (xy 344.494612 -159.090868)
			(xy 344.475562 -159.094678) (xy 344.400378 -159.14243) (xy 344.388948 -159.158178) (xy 344.386662 -159.167576)
			(xy 344.379304 -159.194632) (xy 344.357669 -159.246359) (xy 344.328699 -159.294365) (xy 344.293018 -159.337616)
			(xy 344.251394 -159.375182) (xy 344.204722 -159.406254) (xy 344.154006 -159.430165) (xy 344.100338 -159.446399)
			(xy 344.044873 -159.454607) (xy 344.016838 -159.455104) (xy 343.989586 -159.454609) (xy 343.935636 -159.446857)
			(xy 343.883338 -159.431506) (xy 343.833758 -159.408868) (xy 343.787905 -159.379403) (xy 343.746711 -159.343713)
			(xy 343.711017 -159.302523) (xy 343.681549 -159.256672) (xy 343.658906 -159.207094) (xy 343.64355 -159.154797)
			(xy 343.635793 -159.100848) (xy 343.63533 -159.073596) (xy 337.369404 -159.073596) (xy 335.809844 -160.633156)
			(xy 345.303348 -160.633156) (xy 345.303835 -160.605582) (xy 345.311781 -160.551009) (xy 345.327501 -160.498149)
			(xy 345.350667 -160.448103) (xy 345.380796 -160.401913) (xy 345.417262 -160.360542) (xy 345.437968 -160.342326)
			(xy 345.446081 -160.334719) (xy 345.455436 -160.314571) (xy 345.456002 -160.303464) (xy 345.456002 -160.226248)
			(xy 345.455423 -160.21514) (xy 345.446092 -160.194981) (xy 345.437968 -160.187386) (xy 345.41724 -160.169193)
			(xy 345.380773 -160.127819) (xy 345.350644 -160.081626) (xy 345.327481 -160.031574) (xy 345.311768 -159.978709)
			(xy 345.303832 -159.924132) (xy 345.303348 -159.896556) (xy 345.30389 -159.867333) (xy 345.312784 -159.809567)
			(xy 345.330389 -159.753835) (xy 345.356291 -159.701441) (xy 345.389885 -159.653614) (xy 345.430382 -159.611472)
			(xy 345.476836 -159.576003) (xy 345.50223 -159.56153) (xy 345.512644 -159.555942) (xy 345.526106 -159.536892)
			(xy 345.543124 -159.43453) (xy 345.53652 -159.412178) (xy 345.528392 -159.403542) (xy 345.509985 -159.382768)
			(xy 345.478854 -159.336819) (xy 345.454881 -159.286762) (xy 345.438595 -159.233703) (xy 345.430355 -159.178817)
			(xy 345.42984 -159.151066) (xy 345.430325 -159.124451) (xy 345.437904 -159.071763) (xy 345.452904 -159.020689)
			(xy 345.475018 -158.97227) (xy 345.503797 -158.92749) (xy 345.538656 -158.887261) (xy 345.578884 -158.852402)
			(xy 345.623663 -158.823622) (xy 345.672082 -158.801506) (xy 345.723155 -158.786506) (xy 345.775843 -158.778925)
			(xy 345.802458 -158.778448) (xy 345.82888 -158.778884) (xy 345.881196 -158.786341) (xy 345.931935 -158.801112)
			(xy 345.980079 -158.8229) (xy 346.024663 -158.851269) (xy 346.045028 -158.86811) (xy 346.051886 -158.874206)
			(xy 346.068904 -158.880302) (xy 346.153232 -158.880302) (xy 346.17025 -158.874206) (xy 346.177108 -158.86811)
			(xy 346.197474 -158.851271) (xy 346.24206 -158.822906) (xy 346.290204 -158.801119) (xy 346.340941 -158.786348)
			(xy 346.393256 -158.778888) (xy 346.4461 -158.778888) (xy 346.498415 -158.786348) (xy 346.549152 -158.801119)
			(xy 346.597296 -158.822906) (xy 346.641882 -158.851271) (xy 346.662248 -158.86811) (xy 346.669106 -158.874206)
			(xy 346.686124 -158.880302) (xy 346.770452 -158.880302) (xy 346.78747 -158.874206) (xy 346.794328 -158.86811)
			(xy 346.814684 -158.85126) (xy 346.859277 -158.822907) (xy 346.907424 -158.80113) (xy 346.958162 -158.786365)
			(xy 347.010476 -158.778907) (xy 347.036898 -158.778448) (xy 347.064782 -158.779011) (xy 347.119928 -158.787323)
			(xy 347.173219 -158.803761) (xy 347.223465 -158.827958) (xy 347.269543 -158.859373) (xy 347.310424 -158.897305)
			(xy 347.345196 -158.940907) (xy 347.37308 -158.989204) (xy 347.393455 -159.041117) (xy 347.405864 -159.095487)
			(xy 347.410032 -159.1511) (xy 347.405864 -159.206713) (xy 347.393455 -159.261083) (xy 347.37308 -159.312996)
			(xy 347.345196 -159.361293) (xy 347.310424 -159.404895) (xy 347.269543 -159.442827) (xy 347.223465 -159.474242)
			(xy 347.173219 -159.498439) (xy 347.119928 -159.514877) (xy 347.064782 -159.523189) (xy 347.036898 -159.523684)
			(xy 347.010477 -159.523208) (xy 346.958163 -159.515759) (xy 346.907426 -159.500997) (xy 346.859281 -159.479218)
			(xy 346.814695 -159.450858) (xy 346.794328 -159.434022) (xy 346.78747 -159.427926) (xy 346.770452 -159.42183)
			(xy 346.686124 -159.42183) (xy 346.669106 -159.427926) (xy 346.662248 -159.434022) (xy 346.641882 -159.450861)
			(xy 346.597296 -159.479226) (xy 346.549152 -159.501013) (xy 346.498415 -159.515784) (xy 346.4461 -159.523244)
			(xy 346.393256 -159.523244) (xy 346.340941 -159.515784) (xy 346.290204 -159.501013) (xy 346.24206 -159.479226)
			(xy 346.197474 -159.450861) (xy 346.177108 -159.434022) (xy 346.17025 -159.427926) (xy 346.153232 -159.42183)
			(xy 346.068904 -159.42183) (xy 346.051886 -159.427926) (xy 346.045028 -159.434022) (xy 346.031089 -159.445692)
			(xy 346.001317 -159.466557) (xy 345.985592 -159.475678) (xy 345.975178 -159.48152) (xy 345.96197 -159.50057)
			(xy 345.946476 -159.603186) (xy 345.953588 -159.625538) (xy 345.961716 -159.63392) (xy 345.981283 -159.655303)
			(xy 346.01435 -159.702903) (xy 346.039827 -159.754962) (xy 346.057126 -159.810278) (xy 346.06585 -159.867576)
			(xy 346.066364 -159.896556) (xy 346.065881 -159.92413) (xy 346.057933 -159.978703) (xy 346.042213 -160.031563)
			(xy 346.019046 -160.081609) (xy 345.988916 -160.127799) (xy 345.986992 -160.129982) (xy 351.02927 -160.129982)
			(xy 351.029757 -160.102071) (xy 351.037894 -160.046845) (xy 351.053991 -159.993394) (xy 351.077705 -159.94286)
			(xy 351.108529 -159.89632) (xy 351.126806 -159.87522) (xy 351.133156 -159.868108) (xy 351.13976 -159.850836)
			(xy 351.13976 -159.763714) (xy 351.133156 -159.746442) (xy 351.126806 -159.73933) (xy 351.108522 -159.718236)
			(xy 351.077695 -159.671696) (xy 351.053981 -159.62116) (xy 351.037886 -159.567707) (xy 351.029754 -159.51248)
			(xy 351.02927 -159.484568) (xy 351.029756 -159.457317) (xy 351.037512 -159.403369) (xy 351.052867 -159.351074)
			(xy 351.075509 -159.301497) (xy 351.104975 -159.255647) (xy 351.140666 -159.214456) (xy 351.181857 -159.178765)
			(xy 351.227707 -159.149299) (xy 351.277284 -159.126657) (xy 351.329579 -159.111302) (xy 351.383527 -159.103546)
			(xy 351.438029 -159.103546) (xy 351.491977 -159.111302) (xy 351.544272 -159.126657) (xy 351.593849 -159.149299)
			(xy 351.639699 -159.178765) (xy 351.68089 -159.214456) (xy 351.716581 -159.255647) (xy 351.746047 -159.301497)
			(xy 351.768689 -159.351074) (xy 351.784044 -159.403369) (xy 351.7918 -159.457317) (xy 351.792286 -159.484568)
			(xy 351.791815 -159.512479) (xy 351.783672 -159.567705) (xy 351.767571 -159.621156) (xy 351.743854 -159.67169)
			(xy 351.713027 -159.71823) (xy 351.69475 -159.73933) (xy 351.6884 -159.746442) (xy 351.681796 -159.763714)
			(xy 351.681796 -159.850836) (xy 351.6884 -159.868108) (xy 351.69475 -159.87522) (xy 351.71302 -159.896326)
			(xy 351.743847 -159.942864) (xy 351.767563 -159.993397) (xy 351.783661 -160.046846) (xy 351.791799 -160.102071)
			(xy 351.792286 -160.129982) (xy 351.7918 -160.157233) (xy 351.784044 -160.211181) (xy 351.768689 -160.263476)
			(xy 351.746047 -160.313053) (xy 351.716581 -160.358903) (xy 351.68089 -160.400094) (xy 351.639699 -160.435785)
			(xy 351.593849 -160.465251) (xy 351.544272 -160.487893) (xy 351.491977 -160.503248) (xy 351.438029 -160.511004)
			(xy 351.383527 -160.511004) (xy 351.329579 -160.503248) (xy 351.277284 -160.487893) (xy 351.227707 -160.465251)
			(xy 351.181857 -160.435785) (xy 351.140666 -160.400094) (xy 351.104975 -160.358903) (xy 351.075509 -160.313053)
			(xy 351.052867 -160.263476) (xy 351.037512 -160.211181) (xy 351.029756 -160.157233) (xy 351.02927 -160.129982)
			(xy 345.986992 -160.129982) (xy 345.95245 -160.16917) (xy 345.931744 -160.187386) (xy 345.923628 -160.19499)
			(xy 345.914275 -160.215141) (xy 345.91371 -160.226248) (xy 345.91371 -160.303464) (xy 345.914279 -160.314574)
			(xy 345.923616 -160.334733) (xy 345.931744 -160.342326) (xy 345.95248 -160.36051) (xy 345.988946 -160.401886)
			(xy 346.019074 -160.448082) (xy 346.042235 -160.498135) (xy 346.057947 -160.551002) (xy 346.065881 -160.60558)
			(xy 346.066364 -160.633156) (xy 346.065878 -160.660407) (xy 346.058122 -160.714355) (xy 346.042767 -160.76665)
			(xy 346.020125 -160.816227) (xy 345.990659 -160.862077) (xy 345.954968 -160.903268) (xy 345.913777 -160.938959)
			(xy 345.867927 -160.968425) (xy 345.81835 -160.991067) (xy 345.766055 -161.006422) (xy 345.712107 -161.014178)
			(xy 345.657605 -161.014178) (xy 345.603657 -161.006422) (xy 345.551362 -160.991067) (xy 345.501785 -160.968425)
			(xy 345.455935 -160.938959) (xy 345.414744 -160.903268) (xy 345.379053 -160.862077) (xy 345.349587 -160.816227)
			(xy 345.326945 -160.76665) (xy 345.31159 -160.714355) (xy 345.303834 -160.660407) (xy 345.303348 -160.633156)
			(xy 335.809844 -160.633156) (xy 334.405986 -162.037014) (xy 334.399132 -162.044409) (xy 334.39139 -162.063008)
			(xy 334.391 -162.073082) (xy 334.391 -164.790374) (xy 334.39117 -164.796527) (xy 334.394123 -164.808474)
			(xy 334.396842 -164.813996) (xy 334.536288 -165.07968) (xy 334.538066 -165.082728) (xy 334.583538 -165.156134)
			(xy 355.727254 -165.156134) (xy 355.72774 -165.128883) (xy 355.735496 -165.074935) (xy 355.750851 -165.02264)
			(xy 355.773493 -164.973063) (xy 355.802959 -164.927213) (xy 355.83865 -164.886022) (xy 355.879841 -164.850331)
			(xy 355.925691 -164.820865) (xy 355.975268 -164.798223) (xy 356.027563 -164.782868) (xy 356.081511 -164.775112)
			(xy 356.136013 -164.775112) (xy 356.189961 -164.782868) (xy 356.242256 -164.798223) (xy 356.291833 -164.820865)
			(xy 356.337683 -164.850331) (xy 356.378874 -164.886022) (xy 356.414565 -164.927213) (xy 356.444031 -164.973063)
			(xy 356.466673 -165.02264) (xy 356.482028 -165.074935) (xy 356.489784 -165.128883) (xy 356.49027 -165.156134)
			(xy 356.489612 -165.187697) (xy 356.479225 -165.249962) (xy 356.458738 -165.309671) (xy 356.444296 -165.337744)
			(xy 356.43947 -165.346634) (xy 356.437438 -165.366192) (xy 356.463092 -165.45433) (xy 356.475538 -165.469824)
			(xy 356.484428 -165.474904) (xy 356.491794 -165.478968) (xy 356.501446 -165.48481) (xy 356.523544 -165.486842)
			(xy 356.618032 -165.453314) (xy 356.634034 -165.43782) (xy 356.638098 -165.427406) (xy 356.648782 -165.400624)
			(xy 356.677071 -165.350381) (xy 356.712601 -165.304971) (xy 356.754565 -165.265428) (xy 356.802004 -165.232654)
			(xy 356.853837 -165.207398) (xy 356.908882 -165.190234) (xy 356.965884 -165.181554) (xy 356.994714 -165.181026)
			(xy 357.021967 -165.181445) (xy 357.075918 -165.189204) (xy 357.128216 -165.204561) (xy 357.177796 -165.227205)
			(xy 357.223648 -165.256675) (xy 357.264841 -165.292369) (xy 357.300534 -165.333563) (xy 357.330001 -165.379417)
			(xy 357.352644 -165.428997) (xy 357.367999 -165.481296) (xy 357.375756 -165.535247) (xy 357.375756 -165.589753)
			(xy 357.367999 -165.643704) (xy 357.352644 -165.696003) (xy 357.330001 -165.745583) (xy 357.300534 -165.791437)
			(xy 357.264841 -165.832631) (xy 357.223648 -165.868325) (xy 357.177796 -165.897795) (xy 357.128216 -165.920439)
			(xy 357.075918 -165.935796) (xy 357.021967 -165.943555) (xy 356.994714 -165.944042) (xy 356.969479 -165.943633)
			(xy 356.919446 -165.937018) (xy 356.870726 -165.923848) (xy 356.824173 -165.904355) (xy 356.802182 -165.891972)
			(xy 356.79253 -165.88613) (xy 356.770432 -165.884098) (xy 356.675944 -165.917626) (xy 356.659942 -165.93312)
			(xy 356.655878 -165.943534) (xy 356.645152 -165.970297) (xy 356.616866 -166.020536) (xy 356.581339 -166.065944)
			(xy 356.539382 -166.105486) (xy 356.491949 -166.138261) (xy 356.440123 -166.163521) (xy 356.385085 -166.180692)
			(xy 356.328089 -166.189381) (xy 356.299262 -166.189914) (xy 356.27201 -166.189458) (xy 356.218062 -166.181696)
			(xy 356.165767 -166.166336) (xy 356.11619 -166.143691) (xy 356.07034 -166.114222) (xy 356.02915 -166.078527)
			(xy 355.993459 -166.037335) (xy 355.963993 -165.991482) (xy 355.941352 -165.941903) (xy 355.925997 -165.889607)
			(xy 355.91824 -165.835658) (xy 355.917754 -165.808406) (xy 355.918386 -165.776842) (xy 355.928784 -165.714576)
			(xy 355.949281 -165.654867) (xy 355.963728 -165.626796) (xy 355.968554 -165.617906) (xy 355.970586 -165.598348)
			(xy 355.944932 -165.51021) (xy 355.932486 -165.494716) (xy 355.923596 -165.489636) (xy 355.898482 -165.475109)
			(xy 355.8526 -165.439602) (xy 355.812625 -165.397554) (xy 355.779482 -165.349937) (xy 355.753933 -165.297849)
			(xy 355.736569 -165.242491) (xy 355.727791 -165.185142) (xy 355.727254 -165.156134) (xy 334.583538 -165.156134)
			(xy 335.456784 -166.565834) (xy 335.464116 -166.576961) (xy 335.4835 -166.595236) (xy 335.506953 -166.607871)
			(xy 335.532877 -166.614003) (xy 335.559506 -166.613215) (xy 335.585022 -166.605561) (xy 335.607687 -166.591562)
			(xy 335.617058 -166.58209) (xy 335.63517 -166.563556) (xy 335.675529 -166.53105) (xy 335.71991 -166.504295)
			(xy 335.7675 -166.483784) (xy 335.817425 -166.469891) (xy 335.868769 -166.462872) (xy 335.89468 -166.462456)
			(xy 335.921951 -166.462918) (xy 335.97594 -166.470678) (xy 336.028274 -166.486043) (xy 336.077888 -166.508699)
			(xy 336.123773 -166.538187) (xy 336.164994 -166.573905) (xy 336.200712 -166.615125) (xy 336.2302 -166.66101)
			(xy 336.252857 -166.710625) (xy 336.268222 -166.762959) (xy 336.275982 -166.816947) (xy 336.276155 -166.8272)
			(xy 336.583526 -166.8272) (xy 336.587597 -166.771578) (xy 336.599723 -166.717141) (xy 336.619646 -166.66505)
			(xy 336.646942 -166.616415) (xy 336.681028 -166.572272) (xy 336.721177 -166.533563) (xy 336.766535 -166.501112)
			(xy 336.816135 -166.475611) (xy 336.868919 -166.457604) (xy 336.923762 -166.447474) (xy 336.979496 -166.445437)
			(xy 337.034933 -166.451537) (xy 337.08889 -166.465643) (xy 337.140219 -166.487455) (xy 337.187825 -166.516509)
			(xy 337.230693 -166.552184) (xy 337.26791 -166.593721) (xy 337.298683 -166.640234) (xy 337.322355 -166.690731)
			(xy 337.338423 -166.744138) (xy 337.346543 -166.799314) (xy 337.347052 -166.8272) (xy 337.346543 -166.855086)
			(xy 337.338423 -166.910262) (xy 337.322355 -166.963669) (xy 337.298683 -167.014166) (xy 337.26791 -167.060679)
			(xy 337.230693 -167.102216) (xy 337.187825 -167.137891) (xy 337.140219 -167.166945) (xy 337.08889 -167.188757)
			(xy 337.034933 -167.202863) (xy 336.979496 -167.208963) (xy 336.923762 -167.206926) (xy 336.868919 -167.196796)
			(xy 336.816135 -167.178789) (xy 336.766535 -167.153288) (xy 336.721177 -167.120837) (xy 336.681028 -167.082128)
			(xy 336.646942 -167.037985) (xy 336.619646 -166.98935) (xy 336.599723 -166.937259) (xy 336.587597 -166.882822)
			(xy 336.583526 -166.8272) (xy 336.276155 -166.8272) (xy 336.276442 -166.844218) (xy 336.275969 -166.871287)
			(xy 336.268318 -166.92488) (xy 336.253171 -166.976856) (xy 336.230834 -167.02617) (xy 336.201754 -167.071834)
			(xy 336.166514 -167.112931) (xy 336.125821 -167.148638) (xy 336.080492 -167.178237) (xy 336.031436 -167.201135)
			(xy 336.005678 -167.20947) (xy 335.993111 -167.213785) (xy 335.970597 -167.227877) (xy 335.952476 -167.247295)
			(xy 335.939973 -167.270729) (xy 335.933932 -167.296593) (xy 335.934762 -167.323141) (xy 335.942408 -167.348577)
			(xy 335.949036 -167.360092) (xy 335.992479 -167.430196) (xy 351.94113 -167.430196) (xy 351.941582 -167.402621)
			(xy 351.949536 -167.348047) (xy 351.965263 -167.295186) (xy 351.988436 -167.24514) (xy 352.018571 -167.198951)
			(xy 352.055041 -167.157581) (xy 352.07575 -167.139366) (xy 352.083887 -167.131781) (xy 352.093229 -167.111616)
			(xy 352.093784 -167.100504) (xy 352.093784 -167.023288) (xy 352.093244 -167.012175) (xy 352.083886 -166.992016)
			(xy 352.07575 -166.984426) (xy 352.055038 -166.966216) (xy 352.01857 -166.924846) (xy 351.98844 -166.878656)
			(xy 351.965274 -166.828608) (xy 351.949557 -166.775746) (xy 351.941616 -166.721172) (xy 351.941617 -166.666023)
			(xy 351.949559 -166.611449) (xy 351.965276 -166.558587) (xy 351.988442 -166.50854) (xy 352.018573 -166.46235)
			(xy 352.055042 -166.42098) (xy 352.07575 -166.402766) (xy 352.083887 -166.395181) (xy 352.093229 -166.375016)
			(xy 352.093784 -166.363904) (xy 352.093784 -166.286688) (xy 352.093244 -166.275575) (xy 352.083886 -166.255416)
			(xy 352.07575 -166.247826) (xy 352.055038 -166.229616) (xy 352.01857 -166.188246) (xy 351.988439 -166.142055)
			(xy 351.965274 -166.092007) (xy 351.949557 -166.039145) (xy 351.941616 -165.984571) (xy 351.94113 -165.956996)
			(xy 351.941552 -165.929741) (xy 351.94931 -165.875787) (xy 351.964669 -165.823486) (xy 351.987314 -165.773903)
			(xy 352.016786 -165.728048) (xy 352.052485 -165.686855) (xy 352.093682 -165.651161) (xy 352.13954 -165.621694)
			(xy 352.189125 -165.599054) (xy 352.241428 -165.583701) (xy 352.295383 -165.575949) (xy 352.322638 -165.575488)
			(xy 352.350494 -165.575986) (xy 352.40561 -165.584114) (xy 352.458961 -165.600164) (xy 352.509413 -165.623795)
			(xy 352.555897 -165.654505) (xy 352.597426 -165.691643) (xy 352.633119 -165.73442) (xy 352.662218 -165.781929)
			(xy 352.684106 -165.833162) (xy 352.6917 -165.859968) (xy 352.693986 -165.868858) (xy 352.704654 -165.884098)
			(xy 352.776536 -165.93185) (xy 352.79457 -165.935914) (xy 352.803714 -165.934644) (xy 352.816731 -165.932975)
			(xy 352.842915 -165.931195) (xy 352.856038 -165.931088) (xy 352.870187 -165.931177) (xy 352.89841 -165.933215)
			(xy 352.912426 -165.935152) (xy 352.922586 -165.936676) (xy 352.942144 -165.93185) (xy 353.016566 -165.87597)
			(xy 353.026726 -165.858444) (xy 353.027996 -165.848284) (xy 353.032094 -165.821132) (xy 353.047064 -165.768301)
			(xy 353.069453 -165.718162) (xy 353.098799 -165.67175) (xy 353.134495 -165.630025) (xy 353.175804 -165.593848)
			(xy 353.221872 -165.563966) (xy 353.271749 -165.540998) (xy 353.324403 -165.525417) (xy 353.378747 -165.517545)
			(xy 353.406202 -165.517068) (xy 353.433452 -165.517576) (xy 353.487398 -165.525332) (xy 353.539691 -165.540686)
			(xy 353.589266 -165.563326) (xy 353.635116 -165.59279) (xy 353.676305 -165.628479) (xy 353.711997 -165.669667)
			(xy 353.741464 -165.715514) (xy 353.764106 -165.765089) (xy 353.779463 -165.817381) (xy 353.787223 -165.871326)
			(xy 353.78771 -165.898576) (xy 353.787224 -165.92615) (xy 353.779275 -165.980722) (xy 353.763554 -166.033581)
			(xy 353.740388 -166.083627) (xy 353.710259 -166.129817) (xy 353.673795 -166.171189) (xy 353.65309 -166.189406)
			(xy 353.644972 -166.197009) (xy 353.635618 -166.21716) (xy 353.635056 -166.228268) (xy 353.635056 -166.305484)
			(xy 353.635599 -166.316597) (xy 353.644953 -166.336757) (xy 353.65309 -166.344346) (xy 353.673776 -166.362584)
			(xy 353.710249 -166.403947) (xy 353.740384 -166.450131) (xy 353.763555 -166.500174) (xy 353.779276 -166.553032)
			(xy 353.787222 -166.607603) (xy 353.787256 -166.609522) (xy 358.376218 -166.609522) (xy 358.380289 -166.5539)
			(xy 358.392415 -166.499463) (xy 358.412338 -166.447372) (xy 358.439634 -166.398737) (xy 358.47372 -166.354594)
			(xy 358.513869 -166.315885) (xy 358.559227 -166.283434) (xy 358.608827 -166.257933) (xy 358.661611 -166.239926)
			(xy 358.716454 -166.229796) (xy 358.772188 -166.227759) (xy 358.827625 -166.233859) (xy 358.881582 -166.247965)
			(xy 358.932911 -166.269777) (xy 358.980517 -166.298831) (xy 359.023385 -166.334506) (xy 359.060602 -166.376043)
			(xy 359.091375 -166.422556) (xy 359.115047 -166.473053) (xy 359.131115 -166.52646) (xy 359.139235 -166.581636)
			(xy 359.139744 -166.609522) (xy 359.139235 -166.637408) (xy 359.131115 -166.692584) (xy 359.115047 -166.745991)
			(xy 359.091375 -166.796488) (xy 359.060602 -166.843001) (xy 359.023385 -166.884538) (xy 358.980517 -166.920213)
			(xy 358.932911 -166.949267) (xy 358.881582 -166.971079) (xy 358.827625 -166.985185) (xy 358.772188 -166.991285)
			(xy 358.716454 -166.989248) (xy 358.661611 -166.979118) (xy 358.608827 -166.961111) (xy 358.559227 -166.93561)
			(xy 358.513869 -166.903159) (xy 358.47372 -166.86445) (xy 358.439634 -166.820307) (xy 358.412338 -166.771672)
			(xy 358.392415 -166.719581) (xy 358.380289 -166.665144) (xy 358.376218 -166.609522) (xy 353.787256 -166.609522)
			(xy 353.78771 -166.635176) (xy 353.787222 -166.662428) (xy 353.779469 -166.716378) (xy 353.764116 -166.768675)
			(xy 353.741476 -166.818255) (xy 353.712011 -166.864108) (xy 353.67632 -166.905301) (xy 353.635129 -166.940995)
			(xy 353.589278 -166.970464) (xy 353.5397 -166.993107) (xy 353.487404 -167.008463) (xy 353.433454 -167.016221)
			(xy 353.406202 -167.016684) (xy 353.371912 -167.01516) (xy 353.361752 -167.014144) (xy 353.342448 -167.02024)
			(xy 353.271836 -167.079422) (xy 353.262438 -167.097456) (xy 353.261422 -167.107616) (xy 353.258437 -167.135785)
			(xy 353.245268 -167.190876) (xy 353.224093 -167.243413) (xy 353.19538 -167.292239) (xy 353.15976 -167.336281)
			(xy 353.118016 -167.374568) (xy 353.071068 -167.406258) (xy 353.019948 -167.430655) (xy 352.965781 -167.447221)
			(xy 352.90976 -167.455591) (xy 352.881438 -167.456104) (xy 352.863419 -167.455888) (xy 352.827544 -167.45245)
			(xy 352.80981 -167.449246) (xy 352.800412 -167.447468) (xy 352.781362 -167.451278) (xy 352.706178 -167.49903)
			(xy 352.694748 -167.514778) (xy 352.692462 -167.524176) (xy 352.685104 -167.551232) (xy 352.663469 -167.602959)
			(xy 352.634499 -167.650965) (xy 352.598818 -167.694216) (xy 352.557194 -167.731782) (xy 352.510522 -167.762854)
			(xy 352.459806 -167.786765) (xy 352.406138 -167.802999) (xy 352.350673 -167.811207) (xy 352.322638 -167.811704)
			(xy 352.295386 -167.811209) (xy 352.241436 -167.803457) (xy 352.189138 -167.788106) (xy 352.139558 -167.765468)
			(xy 352.093705 -167.736003) (xy 352.052511 -167.700313) (xy 352.016817 -167.659123) (xy 351.987349 -167.613272)
			(xy 351.964706 -167.563694) (xy 351.94935 -167.511397) (xy 351.941593 -167.457448) (xy 351.94113 -167.430196)
			(xy 335.992479 -167.430196) (xy 336.954208 -168.982136) (xy 353.609148 -168.982136) (xy 353.609622 -168.954562)
			(xy 353.61757 -168.899988) (xy 353.633293 -168.847128) (xy 353.656461 -168.797081) (xy 353.686593 -168.750892)
			(xy 353.723061 -168.709521) (xy 353.743768 -168.691306) (xy 353.75189 -168.683707) (xy 353.76124 -168.663552)
			(xy 353.761802 -168.652444) (xy 353.761802 -168.575228) (xy 353.761234 -168.564118) (xy 353.751895 -168.54396)
			(xy 353.743768 -168.536366) (xy 353.723031 -168.518183) (xy 353.686564 -168.476808) (xy 353.656436 -168.430612)
			(xy 353.633275 -168.380558) (xy 353.617564 -168.327691) (xy 353.60963 -168.273112) (xy 353.609148 -168.245536)
			(xy 353.609734 -168.216611) (xy 353.618463 -168.159423) (xy 353.635726 -168.104209) (xy 353.661127 -168.052234)
			(xy 353.694085 -168.00469) (xy 353.733843 -167.962667) (xy 353.77949 -167.927129) (xy 353.804474 -167.912542)
			(xy 353.814634 -167.906954) (xy 353.827842 -167.888158) (xy 353.84486 -167.786812) (xy 353.838256 -167.764968)
			(xy 353.830636 -167.756078) (xy 353.81284 -167.73549) (xy 353.782818 -167.690102) (xy 353.759725 -167.640827)
			(xy 353.744052 -167.588714) (xy 353.736134 -167.534875) (xy 353.73564 -167.507666) (xy 353.736125 -167.481051)
			(xy 353.743704 -167.428363) (xy 353.758704 -167.377289) (xy 353.780818 -167.32887) (xy 353.809597 -167.28409)
			(xy 353.844456 -167.243861) (xy 353.884684 -167.209002) (xy 353.929463 -167.180222) (xy 353.977882 -167.158106)
			(xy 354.028955 -167.143106) (xy 354.081643 -167.135525) (xy 354.108258 -167.135048) (xy 354.13468 -167.135484)
			(xy 354.186996 -167.142941) (xy 354.237735 -167.157712) (xy 354.285879 -167.1795) (xy 354.330463 -167.207869)
			(xy 354.350828 -167.22471) (xy 354.357686 -167.230806) (xy 354.374704 -167.236902) (xy 354.459032 -167.236902)
			(xy 354.47605 -167.230806) (xy 354.482908 -167.22471) (xy 354.503274 -167.207871) (xy 354.54786 -167.179506)
			(xy 354.596004 -167.157719) (xy 354.646741 -167.142948) (xy 354.699056 -167.135488) (xy 354.7519 -167.135488)
			(xy 354.804215 -167.142948) (xy 354.854952 -167.157719) (xy 354.903096 -167.179506) (xy 354.947682 -167.207871)
			(xy 354.968048 -167.22471) (xy 354.974906 -167.230806) (xy 354.991924 -167.236902) (xy 355.076252 -167.236902)
			(xy 355.09327 -167.230806) (xy 355.100128 -167.22471) (xy 355.120484 -167.20786) (xy 355.165077 -167.179507)
			(xy 355.213224 -167.15773) (xy 355.263962 -167.142965) (xy 355.316276 -167.135507) (xy 355.342698 -167.135048)
			(xy 355.370582 -167.135611) (xy 355.425728 -167.143923) (xy 355.479019 -167.160361) (xy 355.529265 -167.184558)
			(xy 355.575343 -167.215973) (xy 355.616224 -167.253905) (xy 355.650996 -167.297507) (xy 355.67888 -167.345804)
			(xy 355.699255 -167.397717) (xy 355.711664 -167.452087) (xy 355.715832 -167.5077) (xy 355.711664 -167.563313)
			(xy 355.699255 -167.617683) (xy 355.67888 -167.669596) (xy 355.650996 -167.717893) (xy 355.616224 -167.761495)
			(xy 355.575343 -167.799427) (xy 355.529265 -167.830842) (xy 355.479019 -167.855039) (xy 355.425728 -167.871477)
			(xy 355.370582 -167.879789) (xy 355.342698 -167.880284) (xy 355.316277 -167.879808) (xy 355.263963 -167.872359)
			(xy 355.213226 -167.857597) (xy 355.165081 -167.835818) (xy 355.120495 -167.807458) (xy 355.100128 -167.790622)
			(xy 355.09327 -167.784526) (xy 355.076252 -167.77843) (xy 354.991924 -167.77843) (xy 354.974906 -167.784526)
			(xy 354.968048 -167.790622) (xy 354.947682 -167.807461) (xy 354.903096 -167.835826) (xy 354.854952 -167.857613)
			(xy 354.804215 -167.872384) (xy 354.7519 -167.879844) (xy 354.699056 -167.879844) (xy 354.646741 -167.872384)
			(xy 354.596004 -167.857613) (xy 354.54786 -167.835826) (xy 354.503274 -167.807461) (xy 354.482908 -167.790622)
			(xy 354.47605 -167.784526) (xy 354.459032 -167.77843) (xy 354.374704 -167.77843) (xy 354.357686 -167.784526)
			(xy 354.350828 -167.790622) (xy 354.337682 -167.801642) (xy 354.309697 -167.821485) (xy 354.294948 -167.830246)
			(xy 354.284788 -167.836088) (xy 354.271834 -167.854884) (xy 354.256594 -167.956484) (xy 354.263198 -167.978328)
			(xy 354.271072 -167.986964) (xy 354.289974 -168.008207) (xy 354.321908 -168.055254) (xy 354.346498 -168.106522)
			(xy 354.363199 -168.160875) (xy 354.371641 -168.217106) (xy 354.372164 -168.245536) (xy 354.371667 -168.27311)
			(xy 354.363722 -168.327682) (xy 354.348005 -168.380541) (xy 354.32484 -168.430588) (xy 354.294713 -168.476778)
			(xy 354.286072 -168.486582) (xy 359.33507 -168.486582) (xy 359.335557 -168.458671) (xy 359.343694 -168.403445)
			(xy 359.359791 -168.349994) (xy 359.383505 -168.29946) (xy 359.414329 -168.25292) (xy 359.432606 -168.23182)
			(xy 359.438956 -168.224708) (xy 359.44556 -168.207436) (xy 359.44556 -168.120314) (xy 359.438956 -168.103042)
			(xy 359.432606 -168.09593) (xy 359.414322 -168.074836) (xy 359.383495 -168.028296) (xy 359.359781 -167.97776)
			(xy 359.343686 -167.924307) (xy 359.335554 -167.86908) (xy 359.33507 -167.841168) (xy 359.335556 -167.813917)
			(xy 359.343312 -167.759969) (xy 359.358667 -167.707674) (xy 359.381309 -167.658097) (xy 359.410775 -167.612247)
			(xy 359.446466 -167.571056) (xy 359.487657 -167.535365) (xy 359.533507 -167.505899) (xy 359.583084 -167.483257)
			(xy 359.635379 -167.467902) (xy 359.689327 -167.460146) (xy 359.743829 -167.460146) (xy 359.797777 -167.467902)
			(xy 359.850072 -167.483257) (xy 359.899649 -167.505899) (xy 359.945499 -167.535365) (xy 359.98669 -167.571056)
			(xy 360.022381 -167.612247) (xy 360.051847 -167.658097) (xy 360.074489 -167.707674) (xy 360.089844 -167.759969)
			(xy 360.0976 -167.813917) (xy 360.098086 -167.841168) (xy 360.097615 -167.869079) (xy 360.089472 -167.924305)
			(xy 360.073371 -167.977756) (xy 360.049654 -168.02829) (xy 360.018827 -168.07483) (xy 360.00055 -168.09593)
			(xy 359.9942 -168.103042) (xy 359.987596 -168.120314) (xy 359.987596 -168.207436) (xy 359.9942 -168.224708)
			(xy 360.00055 -168.23182) (xy 360.01882 -168.252926) (xy 360.049647 -168.299464) (xy 360.073363 -168.349997)
			(xy 360.089461 -168.403446) (xy 360.097599 -168.458671) (xy 360.098086 -168.486582) (xy 360.0976 -168.513833)
			(xy 360.089844 -168.567781) (xy 360.074489 -168.620076) (xy 360.051847 -168.669653) (xy 360.022381 -168.715503)
			(xy 359.98669 -168.756694) (xy 359.945499 -168.792385) (xy 359.899649 -168.821851) (xy 359.850072 -168.844493)
			(xy 359.797777 -168.859848) (xy 359.743829 -168.867604) (xy 359.689327 -168.867604) (xy 359.635379 -168.859848)
			(xy 359.583084 -168.844493) (xy 359.533507 -168.821851) (xy 359.487657 -168.792385) (xy 359.446466 -168.756694)
			(xy 359.410775 -168.715503) (xy 359.381309 -168.669653) (xy 359.358667 -168.620076) (xy 359.343312 -168.567781)
			(xy 359.335556 -168.513833) (xy 359.33507 -168.486582) (xy 354.286072 -168.486582) (xy 354.258249 -168.51815)
			(xy 354.237544 -168.536366) (xy 354.229437 -168.543978) (xy 354.220078 -168.564123) (xy 354.21951 -168.575228)
			(xy 354.21951 -168.652444) (xy 354.22009 -168.663552) (xy 354.22942 -168.683711) (xy 354.237544 -168.691306)
			(xy 354.25827 -168.709501) (xy 354.294737 -168.750874) (xy 354.324866 -168.797068) (xy 354.348029 -168.847119)
			(xy 354.363743 -168.899984) (xy 354.37168 -168.954561) (xy 354.372164 -168.982136) (xy 354.371678 -169.009387)
			(xy 354.363922 -169.063335) (xy 354.348567 -169.11563) (xy 354.325925 -169.165207) (xy 354.296459 -169.211057)
			(xy 354.260768 -169.252248) (xy 354.219577 -169.287939) (xy 354.173727 -169.317405) (xy 354.12415 -169.340047)
			(xy 354.071855 -169.355402) (xy 354.017907 -169.363158) (xy 353.963405 -169.363158) (xy 353.909457 -169.355402)
			(xy 353.857162 -169.340047) (xy 353.807585 -169.317405) (xy 353.761735 -169.287939) (xy 353.720544 -169.252248)
			(xy 353.684853 -169.211057) (xy 353.655387 -169.165207) (xy 353.632745 -169.11563) (xy 353.61739 -169.063335)
			(xy 353.609634 -169.009387) (xy 353.609148 -168.982136) (xy 336.954208 -168.982136) (xy 338.300314 -171.154344)
			(xy 338.303108 -171.159932) (xy 338.303616 -171.161456) (xy 338.30387 -171.16171) (xy 338.319364 -171.19854)
			(xy 338.321375 -171.203045) (xy 338.326876 -171.211231) (xy 338.330286 -171.214796) (xy 339.2678 -172.15231)
			(xy 340.04377 -172.15231) (xy 340.044297 -172.122832) (xy 340.053366 -172.064577) (xy 340.071291 -172.008411)
			(xy 340.097643 -171.955672) (xy 340.131797 -171.907616) (xy 340.151974 -171.886118) (xy 340.158832 -171.879006)
			(xy 340.166452 -171.860718) (xy 340.166452 -171.769786) (xy 340.158832 -171.751498) (xy 340.151974 -171.744386)
			(xy 340.131798 -171.722888) (xy 340.097653 -171.674829) (xy 340.071306 -171.622089) (xy 340.053386 -171.565924)
			(xy 340.044318 -171.507671) (xy 340.04377 -171.478194) (xy 340.044256 -171.450943) (xy 340.052012 -171.396995)
			(xy 340.067367 -171.3447) (xy 340.090009 -171.295123) (xy 340.119475 -171.249273) (xy 340.155166 -171.208082)
			(xy 340.196357 -171.172391) (xy 340.242207 -171.142925) (xy 340.291784 -171.120283) (xy 340.344079 -171.104928)
			(xy 340.398027 -171.097172) (xy 340.452529 -171.097172) (xy 340.506477 -171.104928) (xy 340.558772 -171.120283)
			(xy 340.608349 -171.142925) (xy 340.654199 -171.172391) (xy 340.69539 -171.208082) (xy 340.731081 -171.249273)
			(xy 340.760547 -171.295123) (xy 340.783189 -171.3447) (xy 340.798544 -171.396995) (xy 340.8063 -171.450943)
			(xy 340.806786 -171.478194) (xy 340.806246 -171.507672) (xy 340.797177 -171.565925) (xy 340.779255 -171.62209)
			(xy 340.752906 -171.674829) (xy 340.718757 -171.722887) (xy 340.698582 -171.744386) (xy 340.691724 -171.751498)
			(xy 340.684104 -171.769786) (xy 340.684104 -171.860718) (xy 340.691724 -171.879006) (xy 340.698582 -171.886118)
			(xy 340.718769 -171.907605) (xy 340.752911 -171.955668) (xy 340.779254 -172.008411) (xy 340.797172 -172.064578)
			(xy 340.806238 -172.122832) (xy 340.806786 -172.15231) (xy 340.8063 -172.179561) (xy 340.798544 -172.233509)
			(xy 340.783189 -172.285804) (xy 340.760547 -172.335381) (xy 340.731081 -172.381231) (xy 340.69539 -172.422422)
			(xy 340.654199 -172.458113) (xy 340.608349 -172.487579) (xy 340.558772 -172.510221) (xy 340.506477 -172.525576)
			(xy 340.452529 -172.533332) (xy 340.398027 -172.533332) (xy 340.344079 -172.525576) (xy 340.291784 -172.510221)
			(xy 340.242207 -172.487579) (xy 340.196357 -172.458113) (xy 340.155166 -172.422422) (xy 340.119475 -172.381231)
			(xy 340.090009 -172.335381) (xy 340.067367 -172.285804) (xy 340.052012 -172.233509) (xy 340.044256 -172.179561)
			(xy 340.04377 -172.15231) (xy 339.2678 -172.15231) (xy 340.235032 -173.119542) (xy 344.660982 -173.119542)
			(xy 344.661494 -173.092291) (xy 344.669245 -173.038342) (xy 344.684596 -172.986046) (xy 344.707232 -172.936466)
			(xy 344.736695 -172.890613) (xy 344.772384 -172.849421) (xy 344.813572 -172.813726) (xy 344.859421 -172.784257)
			(xy 344.908997 -172.761614) (xy 344.961291 -172.746256) (xy 345.015239 -172.738498) (xy 345.04249 -172.738034)
			(xy 345.06986 -172.738498) (xy 345.12404 -172.746315) (xy 345.176543 -172.761804) (xy 345.22629 -172.784646)
			(xy 345.272257 -172.814372) (xy 345.293188 -172.832014) (xy 345.3003 -172.83811) (xy 345.317318 -172.84446)
			(xy 345.402662 -172.84446) (xy 345.41968 -172.83811) (xy 345.426792 -172.832014) (xy 345.447725 -172.814373)
			(xy 345.493693 -172.784649) (xy 345.543439 -172.761803) (xy 345.595941 -172.746307) (xy 345.650119 -172.738478)
			(xy 345.704861 -172.738478) (xy 345.759039 -172.746307) (xy 345.811541 -172.761803) (xy 345.861287 -172.784649)
			(xy 345.907255 -172.814373) (xy 345.928188 -172.832014) (xy 345.9353 -172.83811) (xy 345.952318 -172.84446)
			(xy 346.037662 -172.84446) (xy 346.05468 -172.83811) (xy 346.061792 -172.832014) (xy 346.082718 -172.814367)
			(xy 346.128692 -172.784656) (xy 346.178441 -172.761821) (xy 346.230943 -172.746332) (xy 346.28512 -172.738507)
			(xy 346.31249 -172.738034) (xy 346.339745 -172.738465) (xy 346.393699 -172.746221) (xy 346.446 -172.761578)
			(xy 346.495583 -172.784223) (xy 346.541438 -172.813694) (xy 346.582632 -172.849391) (xy 346.618326 -172.890588)
			(xy 346.647793 -172.936445) (xy 346.670433 -172.98603) (xy 346.685785 -173.038333) (xy 346.693538 -173.092287)
			(xy 346.693998 -173.119542) (xy 348.676722 -173.119542) (xy 348.677194 -173.092289) (xy 348.684946 -173.038337)
			(xy 348.700299 -172.986037) (xy 348.722939 -172.936455) (xy 348.752405 -172.8906) (xy 348.788098 -172.849406)
			(xy 348.829291 -172.813712) (xy 348.875145 -172.784244) (xy 348.924726 -172.761603) (xy 348.977025 -172.746249)
			(xy 349.030977 -172.738495) (xy 349.05823 -172.738034) (xy 349.085601 -172.738474) (xy 349.139782 -172.746297)
			(xy 349.192286 -172.761792) (xy 349.242032 -172.784639) (xy 349.287997 -172.81437) (xy 349.308928 -172.832014)
			(xy 349.31604 -172.83811) (xy 349.333058 -172.84446) (xy 349.418402 -172.84446) (xy 349.43542 -172.83811)
			(xy 349.442532 -172.832014) (xy 349.463481 -172.814396) (xy 349.509449 -172.78468) (xy 349.559192 -172.76184)
			(xy 349.611689 -172.746344) (xy 349.665862 -172.738511) (xy 349.69323 -172.738034) (xy 349.720486 -172.738427)
			(xy 349.774441 -172.746189) (xy 349.826743 -172.761551) (xy 349.876326 -172.7842) (xy 349.922181 -172.813675)
			(xy 349.963375 -172.849376) (xy 349.999068 -172.890577) (xy 350.028534 -172.936437) (xy 350.051174 -172.986025)
			(xy 350.066526 -173.038329) (xy 350.074278 -173.092286) (xy 350.074738 -173.119542) (xy 350.074268 -173.146676)
			(xy 350.066578 -173.200397) (xy 350.051347 -173.252484) (xy 350.028882 -173.301884) (xy 349.999636 -173.347598)
			(xy 349.982282 -173.368462) (xy 349.976186 -173.375574) (xy 349.97009 -173.392592) (xy 349.970321 -173.431454)
			(xy 364.007654 -173.431454) (xy 364.00814 -173.404203) (xy 364.015896 -173.350255) (xy 364.031251 -173.29796)
			(xy 364.053893 -173.248383) (xy 364.083359 -173.202533) (xy 364.11905 -173.161342) (xy 364.160241 -173.125651)
			(xy 364.206091 -173.096185) (xy 364.255668 -173.073543) (xy 364.307963 -173.058188) (xy 364.361911 -173.050432)
			(xy 364.416413 -173.050432) (xy 364.470361 -173.058188) (xy 364.522656 -173.073543) (xy 364.572233 -173.096185)
			(xy 364.618083 -173.125651) (xy 364.659274 -173.161342) (xy 364.694965 -173.202533) (xy 364.724431 -173.248383)
			(xy 364.747073 -173.29796) (xy 364.762428 -173.350255) (xy 364.770184 -173.404203) (xy 364.77067 -173.431454)
			(xy 364.77002 -173.463017) (xy 364.759629 -173.525283) (xy 364.73914 -173.584992) (xy 364.724696 -173.613064)
			(xy 364.71987 -173.621954) (xy 364.717838 -173.641512) (xy 364.743492 -173.72965) (xy 364.755938 -173.745144)
			(xy 364.764828 -173.750224) (xy 364.772194 -173.754288) (xy 364.781846 -173.76013) (xy 364.803944 -173.762162)
			(xy 364.898432 -173.728634) (xy 364.914434 -173.71314) (xy 364.918498 -173.702726) (xy 364.929193 -173.675949)
			(xy 364.957479 -173.625705) (xy 364.993008 -173.580294) (xy 365.034969 -173.54075) (xy 365.082407 -173.507976)
			(xy 365.134239 -173.482718) (xy 365.189283 -173.465554) (xy 365.246285 -173.456874) (xy 365.275114 -173.456346)
			(xy 365.302361 -173.456925) (xy 365.356301 -173.464682) (xy 365.408588 -173.480037) (xy 365.458157 -173.502676)
			(xy 365.504 -173.532139) (xy 365.545184 -173.567826) (xy 365.580869 -173.609011) (xy 365.610331 -173.654855)
			(xy 365.632968 -173.704425) (xy 365.648321 -173.756713) (xy 365.656076 -173.810653) (xy 365.656076 -173.865147)
			(xy 365.648321 -173.919087) (xy 365.632968 -173.971375) (xy 365.610331 -174.020945) (xy 365.580869 -174.066789)
			(xy 365.545184 -174.107974) (xy 365.504 -174.143661) (xy 365.458157 -174.173124) (xy 365.408588 -174.195763)
			(xy 365.356301 -174.211118) (xy 365.302361 -174.218875) (xy 365.275114 -174.219362) (xy 365.249879 -174.21895)
			(xy 365.199846 -174.212335) (xy 365.151126 -174.199166) (xy 365.104573 -174.179674) (xy 365.082582 -174.167292)
			(xy 365.07293 -174.16145) (xy 365.050832 -174.159418) (xy 364.956344 -174.192946) (xy 364.940342 -174.20844)
			(xy 364.936278 -174.218854) (xy 364.925562 -174.245622) (xy 364.897274 -174.29586) (xy 364.861745 -174.341267)
			(xy 364.819786 -174.380808) (xy 364.772352 -174.413582) (xy 364.720525 -174.438842) (xy 364.665486 -174.456012)
			(xy 364.608489 -174.464701) (xy 364.579662 -174.465234) (xy 364.552411 -174.464758) (xy 364.498464 -174.456997)
			(xy 364.446171 -174.441638) (xy 364.396595 -174.418994) (xy 364.350746 -174.389526) (xy 364.309557 -174.353834)
			(xy 364.273866 -174.312644) (xy 364.2444 -174.266794) (xy 364.221758 -174.217218) (xy 364.206401 -174.164924)
			(xy 364.198642 -174.110977) (xy 364.198154 -174.083726) (xy 364.198793 -174.052162) (xy 364.209188 -173.989896)
			(xy 364.229682 -173.930188) (xy 364.244128 -173.902116) (xy 364.248954 -173.893226) (xy 364.250986 -173.873668)
			(xy 364.225332 -173.78553) (xy 364.212886 -173.770036) (xy 364.203996 -173.764956) (xy 364.17889 -173.750415)
			(xy 364.133008 -173.71491) (xy 364.093034 -173.672865) (xy 364.059889 -173.62525) (xy 364.034339 -173.573164)
			(xy 364.016973 -173.517809) (xy 364.008193 -173.460462) (xy 364.007654 -173.431454) (xy 349.970321 -173.431454)
			(xy 349.970598 -173.477936) (xy 349.976948 -173.494954) (xy 349.983298 -173.502066) (xy 350.001209 -173.523076)
			(xy 350.031401 -173.569298) (xy 350.054614 -173.61939) (xy 350.070362 -173.672305) (xy 350.078316 -173.726938)
			(xy 350.078802 -173.754542) (xy 350.078301 -173.781911) (xy 350.070492 -173.836089) (xy 350.055011 -173.888591)
			(xy 350.032177 -173.938339) (xy 350.00246 -173.984307) (xy 349.984822 -174.00524) (xy 349.978726 -174.012352)
			(xy 349.972376 -174.02937) (xy 349.972376 -174.114714) (xy 349.978726 -174.131732) (xy 349.984822 -174.138844)
			(xy 350.002502 -174.159744) (xy 350.032221 -174.205719) (xy 350.055061 -174.255471) (xy 350.070552 -174.307977)
			(xy 350.078376 -174.36216) (xy 350.078371 -174.416904) (xy 350.070538 -174.471084) (xy 350.055039 -174.523588)
			(xy 350.032191 -174.573337) (xy 350.002464 -174.619306) (xy 349.984822 -174.64024) (xy 349.978726 -174.647352)
			(xy 349.972376 -174.66437) (xy 349.972376 -174.749714) (xy 349.978726 -174.766732) (xy 349.984822 -174.773844)
			(xy 350.002502 -174.794744) (xy 350.032221 -174.840719) (xy 350.055061 -174.890471) (xy 350.070552 -174.942977)
			(xy 350.078376 -174.99716) (xy 350.078371 -175.051904) (xy 350.070538 -175.106084) (xy 350.055039 -175.158588)
			(xy 350.032191 -175.208337) (xy 350.002464 -175.254306) (xy 349.984822 -175.27524) (xy 349.978726 -175.282352)
			(xy 349.972376 -175.29937) (xy 349.972376 -175.384714) (xy 349.978726 -175.401732) (xy 349.984822 -175.408844)
			(xy 350.002452 -175.429784) (xy 350.032164 -175.475755) (xy 350.055002 -175.5255) (xy 350.070495 -175.577999)
			(xy 350.078326 -175.632173) (xy 350.078802 -175.659542) (xy 350.078284 -175.687972) (xy 350.075648 -175.705516)
			(xy 360.22153 -175.705516) (xy 360.221996 -175.677941) (xy 360.229947 -175.623368) (xy 360.245671 -175.570508)
			(xy 360.268841 -175.520462) (xy 360.298974 -175.474272) (xy 360.335442 -175.432901) (xy 360.35615 -175.414686)
			(xy 360.364278 -175.407093) (xy 360.373625 -175.386934) (xy 360.374184 -175.375824) (xy 360.374184 -175.298608)
			(xy 360.373632 -175.287496) (xy 360.364283 -175.267337) (xy 360.35615 -175.259746) (xy 360.335458 -175.241514)
			(xy 360.29899 -175.200147) (xy 360.268859 -175.15396) (xy 360.245693 -175.103915) (xy 360.229975 -175.051055)
			(xy 360.222033 -174.996484) (xy 360.222031 -174.941337) (xy 360.229971 -174.886765) (xy 360.245686 -174.833905)
			(xy 360.268849 -174.783859) (xy 360.298978 -174.73767) (xy 360.335443 -174.6963) (xy 360.35615 -174.678086)
			(xy 360.364278 -174.670493) (xy 360.373625 -174.650334) (xy 360.374184 -174.639224) (xy 360.374184 -174.562008)
			(xy 360.373632 -174.550896) (xy 360.364283 -174.530737) (xy 360.35615 -174.523146) (xy 360.335448 -174.504925)
			(xy 360.298979 -174.463557) (xy 360.268847 -174.417369) (xy 360.24568 -174.367323) (xy 360.229961 -174.314463)
			(xy 360.222018 -174.25989) (xy 360.22153 -174.232316) (xy 360.22197 -174.205062) (xy 360.229726 -174.151108)
			(xy 360.245082 -174.098807) (xy 360.267725 -174.049225) (xy 360.297195 -174.00337) (xy 360.332892 -173.962176)
			(xy 360.374087 -173.926482) (xy 360.419944 -173.897015) (xy 360.469528 -173.874374) (xy 360.52183 -173.859021)
			(xy 360.575784 -173.851269) (xy 360.603038 -173.850808) (xy 360.630895 -173.851291) (xy 360.686012 -173.85942)
			(xy 360.739364 -173.875471) (xy 360.789817 -173.899103) (xy 360.836302 -173.929815) (xy 360.877831 -173.966955)
			(xy 360.913523 -174.009735) (xy 360.942621 -174.057246) (xy 360.964507 -174.108481) (xy 360.9721 -174.135288)
			(xy 360.974386 -174.144178) (xy 360.985054 -174.159418) (xy 361.056936 -174.20717) (xy 361.07497 -174.211234)
			(xy 361.084114 -174.209964) (xy 361.097131 -174.208295) (xy 361.123315 -174.206515) (xy 361.136438 -174.206408)
			(xy 361.150587 -174.206497) (xy 361.17881 -174.208534) (xy 361.192826 -174.210472) (xy 361.202986 -174.211996)
			(xy 361.222544 -174.20717) (xy 361.296966 -174.15129) (xy 361.307126 -174.133764) (xy 361.308396 -174.123604)
			(xy 361.312431 -174.096442) (xy 361.327412 -174.04361) (xy 361.349811 -173.993471) (xy 361.379165 -173.947061)
			(xy 361.414869 -173.905337) (xy 361.456184 -173.869162) (xy 361.502258 -173.839283) (xy 361.552139 -173.816316)
			(xy 361.604797 -173.800736) (xy 361.659145 -173.792865) (xy 361.686602 -173.792388) (xy 361.713853 -173.792876)
			(xy 361.767801 -173.800633) (xy 361.820095 -173.815988) (xy 361.869672 -173.838629) (xy 361.915522 -173.868095)
			(xy 361.956712 -173.903786) (xy 361.992404 -173.944976) (xy 362.02187 -173.990826) (xy 362.044512 -174.040403)
			(xy 362.059867 -174.092697) (xy 362.067624 -174.146645) (xy 362.06811 -174.173896) (xy 362.067638 -174.20147)
			(xy 362.059686 -174.256043) (xy 362.043962 -174.308902) (xy 362.020793 -174.358948) (xy 361.990662 -174.405138)
			(xy 361.954196 -174.44651) (xy 361.93349 -174.464726) (xy 361.925363 -174.472321) (xy 361.916014 -174.492478)
			(xy 361.915456 -174.503588) (xy 361.915456 -174.580804) (xy 361.915988 -174.591919) (xy 361.92535 -174.612078)
			(xy 361.93349 -174.619666) (xy 361.954186 -174.637894) (xy 361.990658 -174.679259) (xy 362.020792 -174.725445)
			(xy 362.043961 -174.77549) (xy 362.05968 -174.82835) (xy 362.067623 -174.882922) (xy 362.067657 -174.884842)
			(xy 366.656618 -174.884842) (xy 366.660689 -174.82922) (xy 366.672815 -174.774783) (xy 366.692738 -174.722692)
			(xy 366.720034 -174.674057) (xy 366.75412 -174.629914) (xy 366.794269 -174.591205) (xy 366.839627 -174.558754)
			(xy 366.889227 -174.533253) (xy 366.942011 -174.515246) (xy 366.996854 -174.505116) (xy 367.052588 -174.503079)
			(xy 367.108025 -174.509179) (xy 367.161982 -174.523285) (xy 367.213311 -174.545097) (xy 367.260917 -174.574151)
			(xy 367.303785 -174.609826) (xy 367.341002 -174.651363) (xy 367.371775 -174.697876) (xy 367.395447 -174.748373)
			(xy 367.411515 -174.80178) (xy 367.419635 -174.856956) (xy 367.420144 -174.884842) (xy 367.419635 -174.912728)
			(xy 367.411515 -174.967904) (xy 367.395447 -175.021311) (xy 367.371775 -175.071808) (xy 367.341002 -175.118321)
			(xy 367.303785 -175.159858) (xy 367.260917 -175.195533) (xy 367.213311 -175.224587) (xy 367.161982 -175.246399)
			(xy 367.108025 -175.260505) (xy 367.052588 -175.266605) (xy 366.996854 -175.264568) (xy 366.942011 -175.254438)
			(xy 366.889227 -175.236431) (xy 366.839627 -175.21093) (xy 366.794269 -175.178479) (xy 366.75412 -175.13977)
			(xy 366.720034 -175.095627) (xy 366.692738 -175.046992) (xy 366.672815 -174.994901) (xy 366.660689 -174.940464)
			(xy 366.656618 -174.884842) (xy 362.067657 -174.884842) (xy 362.06811 -174.910496) (xy 362.067641 -174.937749)
			(xy 362.059885 -174.991699) (xy 362.044529 -175.043997) (xy 362.021887 -175.093577) (xy 361.99242 -175.13943)
			(xy 361.956727 -175.180623) (xy 361.915535 -175.216316) (xy 361.869682 -175.245784) (xy 361.820103 -175.268427)
			(xy 361.767805 -175.283783) (xy 361.713855 -175.291541) (xy 361.686602 -175.292004) (xy 361.652312 -175.29048)
			(xy 361.642152 -175.289464) (xy 361.622848 -175.29556) (xy 361.552236 -175.354742) (xy 361.542838 -175.372776)
			(xy 361.541822 -175.382936) (xy 361.538854 -175.411107) (xy 361.525682 -175.466199) (xy 361.504505 -175.518735)
			(xy 361.475789 -175.567561) (xy 361.440167 -175.611602) (xy 361.398421 -175.649889) (xy 361.351472 -175.681579)
			(xy 361.30035 -175.705976) (xy 361.246183 -175.722541) (xy 361.19016 -175.730911) (xy 361.161838 -175.731424)
			(xy 361.143819 -175.731207) (xy 361.107944 -175.72777) (xy 361.09021 -175.724566) (xy 361.080812 -175.722788)
			(xy 361.061762 -175.726598) (xy 360.986578 -175.77435) (xy 360.975148 -175.790098) (xy 360.972862 -175.799496)
			(xy 360.965518 -175.826556) (xy 360.94388 -175.878283) (xy 360.914908 -175.926288) (xy 360.879225 -175.969538)
			(xy 360.837599 -176.007104) (xy 360.790925 -176.038175) (xy 360.740208 -176.062085) (xy 360.686539 -176.078319)
			(xy 360.631073 -176.086527) (xy 360.603038 -176.087024) (xy 360.575787 -176.086509) (xy 360.521839 -176.078758)
			(xy 360.469543 -176.063408) (xy 360.419964 -176.040771) (xy 360.374111 -176.011308) (xy 360.332918 -175.97562)
			(xy 360.297224 -175.934432) (xy 360.267755 -175.888584) (xy 360.245111 -175.839008) (xy 360.229753 -175.786714)
			(xy 360.221994 -175.732767) (xy 360.22153 -175.705516) (xy 350.075648 -175.705516) (xy 350.069834 -175.744201)
			(xy 350.053128 -175.798551) (xy 350.028537 -175.849818) (xy 349.996606 -175.896866) (xy 349.97771 -175.918114)
			(xy 349.97136 -175.925226) (xy 349.964502 -175.942752) (xy 349.964502 -176.031144) (xy 349.97136 -176.04867)
			(xy 349.97771 -176.055782) (xy 349.996627 -176.077012) (xy 350.028557 -176.124063) (xy 350.053144 -176.175335)
			(xy 350.069842 -176.22969) (xy 350.07828 -176.285923) (xy 350.078802 -176.314354) (xy 350.078308 -176.341723)
			(xy 350.070497 -176.395901) (xy 350.055015 -176.448404) (xy 350.032179 -176.498151) (xy 350.00246 -176.544119)
			(xy 349.984822 -176.565052) (xy 349.978726 -176.572164) (xy 349.972376 -176.589182) (xy 349.972376 -176.674526)
			(xy 349.978726 -176.691544) (xy 349.984822 -176.698656) (xy 350.002416 -176.719626) (xy 350.032139 -176.765589)
			(xy 350.054984 -176.815329) (xy 350.070481 -176.867825) (xy 350.078313 -176.921998) (xy 350.078318 -176.976733)
			(xy 350.070496 -177.030907) (xy 350.055008 -177.083406) (xy 350.032172 -177.13315) (xy 350.002457 -177.179118)
			(xy 349.984822 -177.200052) (xy 349.978726 -177.207164) (xy 349.972376 -177.224182) (xy 349.972376 -177.254916)
			(xy 361.889548 -177.254916) (xy 361.890008 -177.227341) (xy 361.897959 -177.172767) (xy 361.913684 -177.119906)
			(xy 361.936855 -177.06986) (xy 361.96699 -177.023671) (xy 362.00346 -176.982301) (xy 362.024168 -176.964086)
			(xy 362.032299 -176.956496) (xy 362.041644 -176.936334) (xy 362.042202 -176.925224) (xy 362.042202 -176.848008)
			(xy 362.041645 -176.836897) (xy 362.032298 -176.816739) (xy 362.024168 -176.809146) (xy 362.003469 -176.790921)
			(xy 361.967 -176.749555) (xy 361.936867 -176.703367) (xy 361.913699 -176.653322) (xy 361.897979 -176.600462)
			(xy 361.890036 -176.54589) (xy 361.889548 -176.518316) (xy 361.889957 -176.491765) (xy 361.897325 -176.439176)
			(xy 361.911921 -176.388119) (xy 361.933462 -176.339582) (xy 361.961532 -176.294504) (xy 361.995586 -176.253759)
			(xy 362.034966 -176.218135) (xy 362.05668 -176.202848) (xy 362.064808 -176.197006) (xy 362.07573 -176.18075)
			(xy 362.093764 -176.091088) (xy 362.089954 -176.07153) (xy 362.084366 -176.063148) (xy 362.070006 -176.040293)
			(xy 362.047322 -175.991317) (xy 362.031927 -175.939584) (xy 362.024142 -175.886173) (xy 362.02366 -175.859186)
			(xy 362.024144 -175.83257) (xy 362.031721 -175.779881) (xy 362.046719 -175.728807) (xy 362.068832 -175.680386)
			(xy 362.097611 -175.635605) (xy 362.13247 -175.595376) (xy 362.172699 -175.560516) (xy 362.217479 -175.531736)
			(xy 362.265899 -175.509621) (xy 362.316973 -175.494622) (xy 362.369662 -175.487044) (xy 362.396278 -175.486568)
			(xy 362.422699 -175.487046) (xy 362.475013 -175.494492) (xy 362.525751 -175.509253) (xy 362.573896 -175.531032)
			(xy 362.618482 -175.559393) (xy 362.638848 -175.57623) (xy 362.645706 -175.582326) (xy 362.662724 -175.588422)
			(xy 362.747052 -175.588422) (xy 362.76407 -175.582326) (xy 362.770928 -175.57623) (xy 362.791294 -175.559391)
			(xy 362.83588 -175.531026) (xy 362.884024 -175.509239) (xy 362.934761 -175.494468) (xy 362.987076 -175.487008)
			(xy 363.03992 -175.487008) (xy 363.092235 -175.494468) (xy 363.142972 -175.509239) (xy 363.191116 -175.531026)
			(xy 363.235702 -175.559391) (xy 363.256068 -175.57623) (xy 363.262926 -175.582326) (xy 363.279944 -175.588422)
			(xy 363.364272 -175.588422) (xy 363.38129 -175.582326) (xy 363.388148 -175.57623) (xy 363.408499 -175.559374)
			(xy 363.453093 -175.531021) (xy 363.501241 -175.509244) (xy 363.551981 -175.494481) (xy 363.604296 -175.487026)
			(xy 363.630718 -175.486568) (xy 363.658601 -175.487118) (xy 363.713744 -175.495432) (xy 363.767031 -175.511871)
			(xy 363.817274 -175.536069) (xy 363.863349 -175.567484) (xy 363.904227 -175.605416) (xy 363.938995 -175.649016)
			(xy 363.966878 -175.697311) (xy 363.987251 -175.749222) (xy 363.999659 -175.80359) (xy 364.003827 -175.8592)
			(xy 363.999659 -175.91481) (xy 363.987251 -175.969178) (xy 363.966878 -176.021089) (xy 363.938995 -176.069384)
			(xy 363.904227 -176.112984) (xy 363.863349 -176.150916) (xy 363.817274 -176.182331) (xy 363.767031 -176.206529)
			(xy 363.713744 -176.222968) (xy 363.658601 -176.231282) (xy 363.630718 -176.231804) (xy 363.604297 -176.231335)
			(xy 363.551982 -176.223888) (xy 363.501243 -176.209125) (xy 363.453099 -176.187344) (xy 363.408514 -176.158981)
			(xy 363.388148 -176.142142) (xy 363.38129 -176.136046) (xy 363.364272 -176.12995) (xy 363.279944 -176.12995)
			(xy 363.262926 -176.136046) (xy 363.256068 -176.142142) (xy 363.235702 -176.158981) (xy 363.191116 -176.187346)
			(xy 363.142972 -176.209133) (xy 363.092235 -176.223904) (xy 363.03992 -176.231364) (xy 362.987076 -176.231364)
			(xy 362.934761 -176.223904) (xy 362.884024 -176.209133) (xy 362.83588 -176.187346) (xy 362.791294 -176.158981)
			(xy 362.770928 -176.142142) (xy 362.76407 -176.136046) (xy 362.747052 -176.12995) (xy 362.662724 -176.12995)
			(xy 362.645706 -176.136046) (xy 362.638848 -176.142142) (xy 362.61167 -176.163224) (xy 362.603288 -176.169066)
			(xy 362.59262 -176.18583) (xy 362.576618 -176.275746) (xy 362.580682 -176.29505) (xy 362.58627 -176.303432)
			(xy 362.601926 -176.327311) (xy 362.626709 -176.378749) (xy 362.643545 -176.433308) (xy 362.652057 -176.489767)
			(xy 362.652564 -176.518316) (xy 362.652053 -176.545889) (xy 362.644112 -176.60046) (xy 362.628396 -176.65332)
			(xy 362.605235 -176.703366) (xy 362.57511 -176.749557) (xy 362.56423 -176.761902) (xy 367.61547 -176.761902)
			(xy 367.615969 -176.733991) (xy 367.624103 -176.678766) (xy 367.640197 -176.625316) (xy 367.663908 -176.574781)
			(xy 367.69473 -176.528241) (xy 367.713006 -176.50714) (xy 367.719356 -176.500028) (xy 367.72596 -176.482756)
			(xy 367.72596 -176.395634) (xy 367.719356 -176.378362) (xy 367.713006 -176.37125) (xy 367.694731 -176.350148)
			(xy 367.663903 -176.30361) (xy 367.640187 -176.253076) (xy 367.62409 -176.199625) (xy 367.615955 -176.144399)
			(xy 367.61547 -176.116488) (xy 367.615956 -176.089237) (xy 367.623712 -176.035289) (xy 367.639067 -175.982994)
			(xy 367.661709 -175.933417) (xy 367.691175 -175.887567) (xy 367.726866 -175.846376) (xy 367.768057 -175.810685)
			(xy 367.813907 -175.781219) (xy 367.863484 -175.758577) (xy 367.915779 -175.743222) (xy 367.969727 -175.735466)
			(xy 368.024229 -175.735466) (xy 368.078177 -175.743222) (xy 368.130472 -175.758577) (xy 368.180049 -175.781219)
			(xy 368.225899 -175.810685) (xy 368.26709 -175.846376) (xy 368.302781 -175.887567) (xy 368.332247 -175.933417)
			(xy 368.354889 -175.982994) (xy 368.370244 -176.035289) (xy 368.378 -176.089237) (xy 368.378486 -176.116488)
			(xy 368.377967 -176.144398) (xy 368.369836 -176.199621) (xy 368.353746 -176.253071) (xy 368.330039 -176.303606)
			(xy 368.299223 -176.350148) (xy 368.28095 -176.37125) (xy 368.2746 -176.378362) (xy 368.267996 -176.395634)
			(xy 368.267996 -176.482756) (xy 368.2746 -176.500028) (xy 368.28095 -176.50714) (xy 368.299229 -176.528239)
			(xy 368.330055 -176.574778) (xy 368.353769 -176.625313) (xy 368.363388 -176.657254) (xy 395.399768 -176.657254)
			(xy 395.4003 -176.628337) (xy 395.409022 -176.571166) (xy 395.426276 -176.515966) (xy 395.451665 -176.464004)
			(xy 395.484608 -176.41647) (xy 395.524349 -176.374454) (xy 395.546834 -176.356264) (xy 395.555613 -176.348719)
			(xy 395.565786 -176.327947) (xy 395.566392 -176.316386) (xy 395.566392 -176.236122) (xy 395.565812 -176.224555)
			(xy 395.555624 -176.203784) (xy 395.546834 -176.196244) (xy 395.524379 -176.17802) (xy 395.48464 -176.136008)
			(xy 395.451697 -176.08848) (xy 395.426303 -176.036525) (xy 395.409041 -175.981333) (xy 395.400306 -175.924168)
			(xy 395.399768 -175.895254) (xy 395.400301 -175.86727) (xy 395.408459 -175.811899) (xy 395.424621 -175.758315)
			(xy 395.448442 -175.707669) (xy 395.479408 -175.661048) (xy 395.516856 -175.619454) (xy 395.559981 -175.583779)
			(xy 395.583664 -175.568864) (xy 395.593316 -175.563022) (xy 395.605508 -175.545242) (xy 395.622272 -175.447706)
			(xy 395.616938 -175.426624) (xy 395.609826 -175.417988) (xy 395.594097 -175.39796) (xy 395.567643 -175.354446)
			(xy 395.547359 -175.307735) (xy 395.533624 -175.258697) (xy 395.526693 -175.208246) (xy 395.52626 -175.182784)
			(xy 395.526742 -175.156168) (xy 395.534319 -175.103479) (xy 395.549317 -175.052405) (xy 395.571431 -175.003984)
			(xy 395.60021 -174.959203) (xy 395.635069 -174.918974) (xy 395.675298 -174.884114) (xy 395.720079 -174.855334)
			(xy 395.768499 -174.833219) (xy 395.819573 -174.81822) (xy 395.872262 -174.810642) (xy 395.898878 -174.810166)
			(xy 395.925299 -174.810644) (xy 395.977613 -174.818091) (xy 396.028351 -174.832851) (xy 396.076496 -174.85463)
			(xy 396.121082 -174.882991) (xy 396.141448 -174.899828) (xy 396.148306 -174.905924) (xy 396.165324 -174.91202)
			(xy 396.249652 -174.91202) (xy 396.26667 -174.905924) (xy 396.273528 -174.899828) (xy 396.293894 -174.882989)
			(xy 396.33848 -174.854624) (xy 396.386624 -174.832837) (xy 396.437361 -174.818066) (xy 396.489676 -174.810606)
			(xy 396.54252 -174.810606) (xy 396.594835 -174.818066) (xy 396.645572 -174.832837) (xy 396.693716 -174.854624)
			(xy 396.738302 -174.882989) (xy 396.758668 -174.899828) (xy 396.765526 -174.905924) (xy 396.782544 -174.91202)
			(xy 396.866872 -174.91202) (xy 396.88389 -174.905924) (xy 396.890748 -174.899828) (xy 396.911099 -174.882972)
			(xy 396.955693 -174.854619) (xy 397.003841 -174.832842) (xy 397.054581 -174.818079) (xy 397.106896 -174.810624)
			(xy 397.133318 -174.810166) (xy 397.161201 -174.81072) (xy 397.216343 -174.819034) (xy 397.26963 -174.835473)
			(xy 397.319873 -174.859671) (xy 397.365947 -174.891086) (xy 397.406825 -174.929017) (xy 397.441594 -174.972617)
			(xy 397.469476 -175.020912) (xy 397.489849 -175.072823) (xy 397.502257 -175.12719) (xy 397.506425 -175.1828)
			(xy 397.502257 -175.23841) (xy 397.489849 -175.292777) (xy 397.469476 -175.344688) (xy 397.441594 -175.392983)
			(xy 397.406825 -175.436583) (xy 397.365947 -175.474514) (xy 397.319873 -175.505929) (xy 397.26963 -175.530127)
			(xy 397.216343 -175.546566) (xy 397.161201 -175.55488) (xy 397.133318 -175.555402) (xy 397.106897 -175.554933)
			(xy 397.054582 -175.547486) (xy 397.003843 -175.532723) (xy 396.955699 -175.510942) (xy 396.911113 -175.482579)
			(xy 396.890748 -175.46574) (xy 396.88389 -175.459644) (xy 396.866872 -175.453548) (xy 396.782544 -175.453548)
			(xy 396.765526 -175.459644) (xy 396.758668 -175.46574) (xy 396.738302 -175.482579) (xy 396.693716 -175.510944)
			(xy 396.645572 -175.532731) (xy 396.594835 -175.547502) (xy 396.54252 -175.554962) (xy 396.489676 -175.554962)
			(xy 396.437361 -175.547502) (xy 396.386624 -175.532731) (xy 396.33848 -175.510944) (xy 396.293894 -175.482579)
			(xy 396.273528 -175.46574) (xy 396.26667 -175.459644) (xy 396.249652 -175.453548) (xy 396.165324 -175.453548)
			(xy 396.148306 -175.459644) (xy 396.141448 -175.46574) (xy 396.130876 -175.474582) (xy 396.108628 -175.490856)
			(xy 396.096998 -175.498252) (xy 396.0876 -175.504348) (xy 396.075662 -175.522382) (xy 396.060168 -175.620172)
			(xy 396.06601 -175.641254) (xy 396.073376 -175.649636) (xy 396.090191 -175.670369) (xy 396.118506 -175.715623)
			(xy 396.140232 -175.764384) (xy 396.154944 -175.815698) (xy 396.162355 -175.868563) (xy 396.162784 -175.895254)
			(xy 396.162239 -175.92417) (xy 396.153516 -175.98134) (xy 396.136264 -176.036539) (xy 396.110877 -176.088501)
			(xy 396.077938 -176.136035) (xy 396.053667 -176.1617) (xy 401.12569 -176.1617) (xy 401.126182 -176.133789)
			(xy 401.134317 -176.078563) (xy 401.150413 -176.025113) (xy 401.174125 -175.974578) (xy 401.204949 -175.928038)
			(xy 401.223226 -175.906938) (xy 401.229576 -175.899826) (xy 401.23618 -175.882554) (xy 401.23618 -175.795432)
			(xy 401.229576 -175.77816) (xy 401.223226 -175.771048) (xy 401.204938 -175.749957) (xy 401.174114 -175.703415)
			(xy 401.150402 -175.652878) (xy 401.134308 -175.599425) (xy 401.126175 -175.544198) (xy 401.12569 -175.516286)
			(xy 401.126176 -175.489035) (xy 401.133932 -175.435087) (xy 401.149287 -175.382792) (xy 401.171929 -175.333215)
			(xy 401.201395 -175.287365) (xy 401.237086 -175.246174) (xy 401.278277 -175.210483) (xy 401.324127 -175.181017)
			(xy 401.373704 -175.158375) (xy 401.425999 -175.14302) (xy 401.479947 -175.135264) (xy 401.534449 -175.135264)
			(xy 401.588397 -175.14302) (xy 401.640692 -175.158375) (xy 401.690269 -175.181017) (xy 401.736119 -175.210483)
			(xy 401.77731 -175.246174) (xy 401.813001 -175.287365) (xy 401.842467 -175.333215) (xy 401.865109 -175.382792)
			(xy 401.880464 -175.435087) (xy 401.88822 -175.489035) (xy 401.888706 -175.516286) (xy 401.888206 -175.544197)
			(xy 401.880074 -175.599422) (xy 401.86398 -175.652873) (xy 401.840269 -175.703408) (xy 401.809446 -175.749948)
			(xy 401.79117 -175.771048) (xy 401.78482 -175.77816) (xy 401.778216 -175.795432) (xy 401.778216 -175.882554)
			(xy 401.78482 -175.899826) (xy 401.79117 -175.906938) (xy 401.809451 -175.928035) (xy 401.840276 -175.974575)
			(xy 401.863989 -176.02511) (xy 401.880085 -176.078562) (xy 401.88822 -176.133789) (xy 401.888706 -176.1617)
			(xy 401.88822 -176.188951) (xy 401.880464 -176.242899) (xy 401.865109 -176.295194) (xy 401.842467 -176.344771)
			(xy 401.813001 -176.390621) (xy 401.77731 -176.431812) (xy 401.736119 -176.467503) (xy 401.690269 -176.496969)
			(xy 401.640692 -176.519611) (xy 401.588397 -176.534966) (xy 401.534449 -176.542722) (xy 401.479947 -176.542722)
			(xy 401.425999 -176.534966) (xy 401.373704 -176.519611) (xy 401.324127 -176.496969) (xy 401.278277 -176.467503)
			(xy 401.237086 -176.431812) (xy 401.201395 -176.390621) (xy 401.171929 -176.344771) (xy 401.149287 -176.295194)
			(xy 401.133932 -176.242899) (xy 401.126176 -176.188951) (xy 401.12569 -176.1617) (xy 396.053667 -176.1617)
			(xy 396.038202 -176.178053) (xy 396.015718 -176.196244) (xy 396.006927 -176.203777) (xy 395.996763 -176.224558)
			(xy 395.99616 -176.236122) (xy 395.99616 -176.316386) (xy 395.996718 -176.327956) (xy 396.006919 -176.348728)
			(xy 396.015718 -176.356264) (xy 396.038188 -176.374471) (xy 396.077923 -176.416488) (xy 396.110863 -176.46402)
			(xy 396.136254 -176.515978) (xy 396.153513 -176.571172) (xy 396.162247 -176.628339) (xy 396.162784 -176.657254)
			(xy 396.162298 -176.684505) (xy 396.154542 -176.738453) (xy 396.139187 -176.790748) (xy 396.116545 -176.840325)
			(xy 396.087079 -176.886175) (xy 396.051388 -176.927366) (xy 396.010197 -176.963057) (xy 395.964347 -176.992523)
			(xy 395.91477 -177.015165) (xy 395.862475 -177.03052) (xy 395.808527 -177.038276) (xy 395.754025 -177.038276)
			(xy 395.700077 -177.03052) (xy 395.647782 -177.015165) (xy 395.598205 -176.992523) (xy 395.552355 -176.963057)
			(xy 395.511164 -176.927366) (xy 395.475473 -176.886175) (xy 395.446007 -176.840325) (xy 395.423365 -176.790748)
			(xy 395.40801 -176.738453) (xy 395.400254 -176.684505) (xy 395.399768 -176.657254) (xy 368.363388 -176.657254)
			(xy 368.369865 -176.678764) (xy 368.378 -176.733991) (xy 368.378486 -176.761902) (xy 368.378 -176.789153)
			(xy 368.370244 -176.843101) (xy 368.354889 -176.895396) (xy 368.332247 -176.944973) (xy 368.302781 -176.990823)
			(xy 368.26709 -177.032014) (xy 368.225899 -177.067705) (xy 368.180049 -177.097171) (xy 368.130472 -177.119813)
			(xy 368.078177 -177.135168) (xy 368.024229 -177.142924) (xy 367.969727 -177.142924) (xy 367.915779 -177.135168)
			(xy 367.863484 -177.119813) (xy 367.813907 -177.097171) (xy 367.768057 -177.067705) (xy 367.726866 -177.032014)
			(xy 367.691175 -176.990823) (xy 367.661709 -176.944973) (xy 367.639067 -176.895396) (xy 367.623712 -176.843101)
			(xy 367.615956 -176.789153) (xy 367.61547 -176.761902) (xy 362.56423 -176.761902) (xy 362.538648 -176.79093)
			(xy 362.517944 -176.809146) (xy 362.509801 -176.816725) (xy 362.500463 -176.836895) (xy 362.49991 -176.848008)
			(xy 362.49991 -176.925224) (xy 362.500445 -176.936338) (xy 362.509807 -176.956496) (xy 362.517944 -176.964086)
			(xy 362.53866 -176.982291) (xy 362.575128 -177.023662) (xy 362.605259 -177.069854) (xy 362.628423 -177.119903)
			(xy 362.644139 -177.172766) (xy 362.652079 -177.227341) (xy 362.652564 -177.254916) (xy 362.652078 -177.282167)
			(xy 362.644322 -177.336115) (xy 362.628967 -177.38841) (xy 362.606325 -177.437987) (xy 362.576859 -177.483837)
			(xy 362.541168 -177.525028) (xy 362.499977 -177.560719) (xy 362.454127 -177.590185) (xy 362.40455 -177.612827)
			(xy 362.352255 -177.628182) (xy 362.298307 -177.635938) (xy 362.243805 -177.635938) (xy 362.189857 -177.628182)
			(xy 362.137562 -177.612827) (xy 362.087985 -177.590185) (xy 362.042135 -177.560719) (xy 362.000944 -177.525028)
			(xy 361.965253 -177.483837) (xy 361.935787 -177.437987) (xy 361.913145 -177.38841) (xy 361.89779 -177.336115)
			(xy 361.890034 -177.282167) (xy 361.889548 -177.254916) (xy 349.972376 -177.254916) (xy 349.972376 -177.309526)
			(xy 349.978726 -177.326544) (xy 349.984822 -177.333656) (xy 350.002416 -177.354626) (xy 350.032139 -177.400589)
			(xy 350.054984 -177.450329) (xy 350.070481 -177.502825) (xy 350.078313 -177.556998) (xy 350.078318 -177.611733)
			(xy 350.070496 -177.665907) (xy 350.055008 -177.718406) (xy 350.032172 -177.76815) (xy 350.002457 -177.814118)
			(xy 349.984822 -177.835052) (xy 349.978726 -177.842164) (xy 349.972376 -177.859182) (xy 349.972376 -177.944526)
			(xy 349.978726 -177.961544) (xy 349.984822 -177.968656) (xy 350.002416 -177.989626) (xy 350.032139 -178.035589)
			(xy 350.054984 -178.085329) (xy 350.070481 -178.137825) (xy 350.078313 -178.191998) (xy 350.078318 -178.246733)
			(xy 350.070496 -178.300907) (xy 350.055008 -178.353406) (xy 350.032172 -178.40315) (xy 350.002457 -178.449118)
			(xy 349.984822 -178.470052) (xy 349.978726 -178.477164) (xy 349.972376 -178.494182) (xy 349.972376 -178.579526)
			(xy 349.978726 -178.596544) (xy 349.984822 -178.603656) (xy 350.002416 -178.624626) (xy 350.032139 -178.670589)
			(xy 350.054984 -178.720329) (xy 350.070481 -178.772825) (xy 350.078313 -178.826998) (xy 350.078318 -178.881733)
			(xy 350.070496 -178.935907) (xy 350.055008 -178.988406) (xy 350.032172 -179.03815) (xy 350.002457 -179.084118)
			(xy 349.984822 -179.105052) (xy 349.978726 -179.112164) (xy 349.972376 -179.129182) (xy 349.972376 -179.214526)
			(xy 349.978726 -179.231544) (xy 349.97925 -179.232155) (xy 368.583129 -179.232155) (xy 368.583129 -179.177645)
			(xy 368.590887 -179.123689) (xy 368.606244 -179.071387) (xy 368.628889 -179.021803) (xy 368.65836 -178.975946)
			(xy 368.694057 -178.93475) (xy 368.735254 -178.899054) (xy 368.781112 -178.869584) (xy 368.830696 -178.846941)
			(xy 368.882999 -178.831585) (xy 368.936955 -178.823828) (xy 368.96421 -178.823366) (xy 368.975284 -178.823436)
			(xy 368.997396 -178.824709) (xy 369.008406 -178.825906) (xy 369.018312 -178.827176) (xy 369.037108 -178.822096)
			(xy 369.109244 -178.766978) (xy 369.118896 -178.750468) (xy 369.12042 -178.740562) (xy 369.125354 -178.712096)
			(xy 369.142666 -178.656979) (xy 369.168078 -178.605095) (xy 369.201009 -178.557628) (xy 369.24071 -178.515659)
			(xy 369.263168 -178.497484) (xy 369.271944 -178.489936) (xy 369.282117 -178.469166) (xy 369.282726 -178.457606)
			(xy 369.282726 -178.377342) (xy 369.282157 -178.365773) (xy 369.271964 -178.345001) (xy 369.263168 -178.337464)
			(xy 369.240661 -178.319301) (xy 369.200928 -178.277275) (xy 369.167993 -178.229734) (xy 369.142609 -178.177767)
			(xy 369.125358 -178.122565) (xy 369.116634 -178.065392) (xy 369.116102 -178.036474) (xy 369.116588 -178.009223)
			(xy 369.124344 -177.955275) (xy 369.139699 -177.90298) (xy 369.162341 -177.853403) (xy 369.191807 -177.807553)
			(xy 369.227498 -177.766362) (xy 369.268689 -177.730671) (xy 369.314539 -177.701205) (xy 369.364116 -177.678563)
			(xy 369.416411 -177.663208) (xy 369.470359 -177.655452) (xy 369.524861 -177.655452) (xy 369.578809 -177.663208)
			(xy 369.631104 -177.678563) (xy 369.680681 -177.701205) (xy 369.726531 -177.730671) (xy 369.767722 -177.766362)
			(xy 369.803413 -177.807553) (xy 369.832879 -177.853403) (xy 369.855521 -177.90298) (xy 369.870876 -177.955275)
			(xy 369.878632 -178.009223) (xy 369.879118 -178.036474) (xy 369.878612 -178.065392) (xy 369.869885 -178.122565)
			(xy 369.852627 -178.177765) (xy 369.827233 -178.229728) (xy 369.794286 -178.277261) (xy 369.75454 -178.319276)
			(xy 369.732052 -178.337464) (xy 369.723303 -178.345037) (xy 369.713114 -178.365788) (xy 369.712494 -178.377342)
			(xy 369.712494 -178.404012) (xy 372.368826 -178.404012) (xy 372.369312 -178.376761) (xy 372.377068 -178.322813)
			(xy 372.392423 -178.270518) (xy 372.415065 -178.220941) (xy 372.444531 -178.175091) (xy 372.480222 -178.1339)
			(xy 372.521413 -178.098209) (xy 372.567263 -178.068743) (xy 372.61684 -178.046101) (xy 372.669135 -178.030746)
			(xy 372.723083 -178.02299) (xy 372.777585 -178.02299) (xy 372.831533 -178.030746) (xy 372.883828 -178.046101)
			(xy 372.933405 -178.068743) (xy 372.979255 -178.098209) (xy 373.020446 -178.1339) (xy 373.056137 -178.175091)
			(xy 373.085603 -178.220941) (xy 373.108245 -178.270518) (xy 373.112911 -178.28641) (xy 374.259094 -178.28641)
			(xy 374.25958 -178.259159) (xy 374.267336 -178.205211) (xy 374.282691 -178.152916) (xy 374.305333 -178.103339)
			(xy 374.334799 -178.057489) (xy 374.37049 -178.016298) (xy 374.411681 -177.980607) (xy 374.457531 -177.951141)
			(xy 374.507108 -177.928499) (xy 374.559403 -177.913144) (xy 374.613351 -177.905388) (xy 374.667853 -177.905388)
			(xy 374.721801 -177.913144) (xy 374.774096 -177.928499) (xy 374.823673 -177.951141) (xy 374.869523 -177.980607)
			(xy 374.910714 -178.016298) (xy 374.946405 -178.057489) (xy 374.975871 -178.103339) (xy 374.998513 -178.152916)
			(xy 375.013868 -178.205211) (xy 375.021624 -178.259159) (xy 375.02211 -178.28641) (xy 375.021586 -178.314084)
			(xy 375.013594 -178.36885) (xy 375.0031 -178.404012) (xy 380.771654 -178.404012) (xy 380.77214 -178.376761)
			(xy 380.779896 -178.322813) (xy 380.795251 -178.270518) (xy 380.817893 -178.220941) (xy 380.847359 -178.175091)
			(xy 380.88305 -178.1339) (xy 380.924241 -178.098209) (xy 380.970091 -178.068743) (xy 381.019668 -178.046101)
			(xy 381.071963 -178.030746) (xy 381.125911 -178.02299) (xy 381.180413 -178.02299) (xy 381.234361 -178.030746)
			(xy 381.286656 -178.046101) (xy 381.336233 -178.068743) (xy 381.382083 -178.098209) (xy 381.423274 -178.1339)
			(xy 381.458965 -178.175091) (xy 381.488431 -178.220941) (xy 381.511073 -178.270518) (xy 381.526428 -178.322813)
			(xy 381.534184 -178.376761) (xy 381.53467 -178.404012) (xy 381.534003 -178.435575) (xy 381.523619 -178.49784)
			(xy 381.503136 -178.557549) (xy 381.488696 -178.585622) (xy 381.48387 -178.594512) (xy 381.481838 -178.61407)
			(xy 381.507492 -178.702208) (xy 381.519938 -178.717702) (xy 381.528828 -178.722782) (xy 381.536194 -178.726846)
			(xy 381.545846 -178.732688) (xy 381.567944 -178.73472) (xy 381.662432 -178.701192) (xy 381.678434 -178.685698)
			(xy 381.682498 -178.675284) (xy 381.693171 -178.648498) (xy 381.721462 -178.598255) (xy 381.756995 -178.552845)
			(xy 381.79896 -178.513303) (xy 381.846401 -178.480531) (xy 381.898235 -178.455275) (xy 381.953281 -178.438111)
			(xy 382.010284 -178.429432) (xy 382.039114 -178.428904) (xy 382.066365 -178.429367) (xy 382.120313 -178.437125)
			(xy 382.172608 -178.452482) (xy 382.222185 -178.475125) (xy 382.268035 -178.504592) (xy 382.309225 -178.540285)
			(xy 382.344916 -178.581476) (xy 382.374382 -178.627327) (xy 382.397023 -178.676905) (xy 382.412378 -178.7292)
			(xy 382.420134 -178.783149) (xy 382.420134 -178.837651) (xy 382.412378 -178.8916) (xy 382.403028 -178.923442)
			(xy 382.661922 -178.923442) (xy 382.662428 -178.895968) (xy 382.670314 -178.841589) (xy 382.685929 -178.788907)
			(xy 382.70895 -178.739014) (xy 382.738898 -178.692944) (xy 382.756664 -178.671982) (xy 382.76276 -178.66487)
			(xy 382.76911 -178.647852) (xy 382.76911 -178.562) (xy 382.76276 -178.544982) (xy 382.756664 -178.53787)
			(xy 382.738899 -178.516909) (xy 382.708976 -178.470826) (xy 382.685964 -178.420932) (xy 382.670338 -178.368255)
			(xy 382.662421 -178.313882) (xy 382.661922 -178.28641) (xy 382.662408 -178.259159) (xy 382.670164 -178.205211)
			(xy 382.685519 -178.152916) (xy 382.708161 -178.103339) (xy 382.737627 -178.057489) (xy 382.773318 -178.016298)
			(xy 382.814509 -177.980607) (xy 382.860359 -177.951141) (xy 382.909936 -177.928499) (xy 382.962231 -177.913144)
			(xy 383.016179 -177.905388) (xy 383.070681 -177.905388) (xy 383.124629 -177.913144) (xy 383.176924 -177.928499)
			(xy 383.226501 -177.951141) (xy 383.272351 -177.980607) (xy 383.313542 -178.016298) (xy 383.349233 -178.057489)
			(xy 383.378699 -178.103339) (xy 383.401341 -178.152916) (xy 383.416696 -178.205211) (xy 383.424452 -178.259159)
			(xy 383.424938 -178.28641) (xy 383.424448 -178.313884) (xy 383.416556 -178.368263) (xy 383.405957 -178.404012)
			(xy 389.102854 -178.404012) (xy 389.10334 -178.376761) (xy 389.111096 -178.322813) (xy 389.126451 -178.270518)
			(xy 389.149093 -178.220941) (xy 389.178559 -178.175091) (xy 389.21425 -178.1339) (xy 389.255441 -178.098209)
			(xy 389.301291 -178.068743) (xy 389.350868 -178.046101) (xy 389.403163 -178.030746) (xy 389.457111 -178.02299)
			(xy 389.511613 -178.02299) (xy 389.565561 -178.030746) (xy 389.617856 -178.046101) (xy 389.667433 -178.068743)
			(xy 389.713283 -178.098209) (xy 389.754474 -178.1339) (xy 389.790165 -178.175091) (xy 389.819631 -178.220941)
			(xy 389.842273 -178.270518) (xy 389.857628 -178.322813) (xy 389.865384 -178.376761) (xy 389.86587 -178.404012)
			(xy 389.865203 -178.435575) (xy 389.854819 -178.49784) (xy 389.834336 -178.557549) (xy 389.819896 -178.585622)
			(xy 389.81507 -178.594512) (xy 389.813038 -178.61407) (xy 389.838692 -178.702208) (xy 389.851138 -178.717702)
			(xy 389.860028 -178.722782) (xy 389.867394 -178.726846) (xy 389.877046 -178.732688) (xy 389.899144 -178.73472)
			(xy 389.993632 -178.701192) (xy 390.009634 -178.685698) (xy 390.013698 -178.675284) (xy 390.024371 -178.648498)
			(xy 390.052662 -178.598255) (xy 390.088195 -178.552845) (xy 390.13016 -178.513303) (xy 390.177601 -178.480531)
			(xy 390.229435 -178.455275) (xy 390.284481 -178.438111) (xy 390.341484 -178.429432) (xy 390.370314 -178.428904)
			(xy 390.397565 -178.429367) (xy 390.451513 -178.437125) (xy 390.503808 -178.452482) (xy 390.553385 -178.475125)
			(xy 390.599235 -178.504592) (xy 390.640425 -178.540285) (xy 390.676116 -178.581476) (xy 390.705582 -178.627327)
			(xy 390.728223 -178.676905) (xy 390.743578 -178.7292) (xy 390.751334 -178.783149) (xy 390.751334 -178.837651)
			(xy 390.743578 -178.8916) (xy 390.734228 -178.923442) (xy 390.993122 -178.923442) (xy 390.993628 -178.895968)
			(xy 391.001514 -178.841589) (xy 391.017129 -178.788907) (xy 391.04015 -178.739014) (xy 391.070098 -178.692944)
			(xy 391.087864 -178.671982) (xy 391.09396 -178.66487) (xy 391.10031 -178.647852) (xy 391.10031 -178.562)
			(xy 391.09396 -178.544982) (xy 391.087864 -178.53787) (xy 391.070099 -178.516909) (xy 391.040176 -178.470826)
			(xy 391.017164 -178.420932) (xy 391.001538 -178.368255) (xy 390.993621 -178.313882) (xy 390.993122 -178.28641)
			(xy 390.993608 -178.259159) (xy 391.001364 -178.205211) (xy 391.016719 -178.152916) (xy 391.039361 -178.103339)
			(xy 391.068827 -178.057489) (xy 391.104518 -178.016298) (xy 391.145709 -177.980607) (xy 391.191559 -177.951141)
			(xy 391.241136 -177.928499) (xy 391.293431 -177.913144) (xy 391.347379 -177.905388) (xy 391.401881 -177.905388)
			(xy 391.455829 -177.913144) (xy 391.508124 -177.928499) (xy 391.557701 -177.951141) (xy 391.603551 -177.980607)
			(xy 391.644742 -178.016298) (xy 391.680433 -178.057489) (xy 391.709899 -178.103339) (xy 391.732541 -178.152916)
			(xy 391.747896 -178.205211) (xy 391.755652 -178.259159) (xy 391.756138 -178.28641) (xy 391.755648 -178.313884)
			(xy 391.747756 -178.368263) (xy 391.732136 -178.420945) (xy 391.709112 -178.470838) (xy 391.679162 -178.516907)
			(xy 391.661396 -178.53787) (xy 391.6553 -178.544982) (xy 391.64895 -178.562) (xy 391.64895 -178.647852)
			(xy 391.6553 -178.66487) (xy 391.661396 -178.671982) (xy 391.679132 -178.692967) (xy 391.709061 -178.739042)
			(xy 391.732079 -178.788931) (xy 391.747712 -178.841603) (xy 391.755635 -178.895971) (xy 391.756138 -178.923442)
			(xy 391.755652 -178.950693) (xy 391.754019 -178.96205) (xy 392.330938 -178.96205) (xy 392.335009 -178.906428)
			(xy 392.347135 -178.851991) (xy 392.367058 -178.7999) (xy 392.394354 -178.751265) (xy 392.42844 -178.707122)
			(xy 392.468589 -178.668413) (xy 392.513947 -178.635962) (xy 392.563547 -178.610461) (xy 392.616331 -178.592454)
			(xy 392.671174 -178.582324) (xy 392.726908 -178.580287) (xy 392.782345 -178.586387) (xy 392.836302 -178.600493)
			(xy 392.887631 -178.622305) (xy 392.935237 -178.651359) (xy 392.978105 -178.687034) (xy 393.015322 -178.728571)
			(xy 393.046095 -178.775084) (xy 393.069767 -178.825581) (xy 393.085835 -178.878988) (xy 393.093955 -178.934164)
			(xy 393.094464 -178.96205) (xy 393.093955 -178.989936) (xy 393.085835 -179.045112) (xy 393.069767 -179.098519)
			(xy 393.046095 -179.149016) (xy 393.015322 -179.195529) (xy 392.978105 -179.237066) (xy 392.935237 -179.272741)
			(xy 392.887631 -179.301795) (xy 392.836302 -179.323607) (xy 392.782345 -179.337713) (xy 392.726908 -179.343813)
			(xy 392.671174 -179.341776) (xy 392.616331 -179.331646) (xy 392.563547 -179.313639) (xy 392.513947 -179.288138)
			(xy 392.468589 -179.255687) (xy 392.42844 -179.216978) (xy 392.394354 -179.172835) (xy 392.367058 -179.1242)
			(xy 392.347135 -179.072109) (xy 392.335009 -179.017672) (xy 392.330938 -178.96205) (xy 391.754019 -178.96205)
			(xy 391.747896 -179.004641) (xy 391.732541 -179.056936) (xy 391.709899 -179.106513) (xy 391.680433 -179.152363)
			(xy 391.644742 -179.193554) (xy 391.603551 -179.229245) (xy 391.557701 -179.258711) (xy 391.508124 -179.281353)
			(xy 391.455829 -179.296708) (xy 391.401881 -179.304464) (xy 391.347379 -179.304464) (xy 391.293431 -179.296708)
			(xy 391.241136 -179.281353) (xy 391.191559 -179.258711) (xy 391.145709 -179.229245) (xy 391.104518 -179.193554)
			(xy 391.068827 -179.152363) (xy 391.039361 -179.106513) (xy 391.016719 -179.056936) (xy 391.001364 -179.004641)
			(xy 390.993608 -178.950693) (xy 390.993122 -178.923442) (xy 390.734228 -178.923442) (xy 390.728223 -178.943895)
			(xy 390.705582 -178.993473) (xy 390.676116 -179.039324) (xy 390.640425 -179.080515) (xy 390.599235 -179.116208)
			(xy 390.553385 -179.145675) (xy 390.503808 -179.168318) (xy 390.451513 -179.183675) (xy 390.397565 -179.191433)
			(xy 390.370314 -179.19192) (xy 390.345079 -179.191514) (xy 390.295045 -179.184898) (xy 390.246325 -179.171728)
			(xy 390.199773 -179.152234) (xy 390.177782 -179.13985) (xy 390.16813 -179.134008) (xy 390.146032 -179.131976)
			(xy 390.051544 -179.165504) (xy 390.035542 -179.180998) (xy 390.031478 -179.191412) (xy 390.02074 -179.21817)
			(xy 389.992457 -179.26841) (xy 389.956933 -179.313819) (xy 389.914977 -179.353362) (xy 389.867546 -179.386137)
			(xy 389.815721 -179.411399) (xy 389.760684 -179.428569) (xy 389.703689 -179.437259) (xy 389.674862 -179.437792)
			(xy 389.647609 -179.437357) (xy 389.593659 -179.429595) (xy 389.541362 -179.414235) (xy 389.491784 -179.391588)
			(xy 389.445933 -179.362116) (xy 389.404742 -179.326419) (xy 389.369051 -179.285224) (xy 389.339586 -179.239369)
			(xy 389.316946 -179.189787) (xy 389.301593 -179.137488) (xy 389.293839 -179.083537) (xy 389.293354 -179.056284)
			(xy 389.294016 -179.024721) (xy 389.304401 -178.962456) (xy 389.324886 -178.902747) (xy 389.339328 -178.874674)
			(xy 389.344154 -178.865784) (xy 389.346186 -178.846226) (xy 389.320532 -178.758088) (xy 389.308086 -178.742594)
			(xy 389.299196 -178.737514) (xy 389.274072 -178.723003) (xy 389.22819 -178.687493) (xy 389.188216 -178.645443)
			(xy 389.155073 -178.597823) (xy 389.129526 -178.545732) (xy 389.112165 -178.490372) (xy 389.10339 -178.433021)
			(xy 389.102854 -178.404012) (xy 383.405957 -178.404012) (xy 383.400936 -178.420945) (xy 383.377912 -178.470838)
			(xy 383.347962 -178.516907) (xy 383.330196 -178.53787) (xy 383.3241 -178.544982) (xy 383.31775 -178.562)
			(xy 383.31775 -178.647852) (xy 383.3241 -178.66487) (xy 383.330196 -178.671982) (xy 383.347932 -178.692967)
			(xy 383.377861 -178.739042) (xy 383.400879 -178.788931) (xy 383.416512 -178.841603) (xy 383.424435 -178.895971)
			(xy 383.424938 -178.923442) (xy 383.424452 -178.950693) (xy 383.422819 -178.96205) (xy 383.999738 -178.96205)
			(xy 384.003809 -178.906428) (xy 384.015935 -178.851991) (xy 384.035858 -178.7999) (xy 384.063154 -178.751265)
			(xy 384.09724 -178.707122) (xy 384.137389 -178.668413) (xy 384.182747 -178.635962) (xy 384.232347 -178.610461)
			(xy 384.285131 -178.592454) (xy 384.339974 -178.582324) (xy 384.395708 -178.580287) (xy 384.451145 -178.586387)
			(xy 384.505102 -178.600493) (xy 384.556431 -178.622305) (xy 384.604037 -178.651359) (xy 384.646905 -178.687034)
			(xy 384.684122 -178.728571) (xy 384.714895 -178.775084) (xy 384.738567 -178.825581) (xy 384.754635 -178.878988)
			(xy 384.762755 -178.934164) (xy 384.763264 -178.96205) (xy 384.762755 -178.989936) (xy 384.754635 -179.045112)
			(xy 384.738567 -179.098519) (xy 384.714895 -179.149016) (xy 384.684122 -179.195529) (xy 384.646905 -179.237066)
			(xy 384.604037 -179.272741) (xy 384.556431 -179.301795) (xy 384.505102 -179.323607) (xy 384.451145 -179.337713)
			(xy 384.395708 -179.343813) (xy 384.339974 -179.341776) (xy 384.285131 -179.331646) (xy 384.232347 -179.313639)
			(xy 384.182747 -179.288138) (xy 384.137389 -179.255687) (xy 384.09724 -179.216978) (xy 384.063154 -179.172835)
			(xy 384.035858 -179.1242) (xy 384.015935 -179.072109) (xy 384.003809 -179.017672) (xy 383.999738 -178.96205)
			(xy 383.422819 -178.96205) (xy 383.416696 -179.004641) (xy 383.401341 -179.056936) (xy 383.378699 -179.106513)
			(xy 383.349233 -179.152363) (xy 383.313542 -179.193554) (xy 383.272351 -179.229245) (xy 383.226501 -179.258711)
			(xy 383.176924 -179.281353) (xy 383.124629 -179.296708) (xy 383.070681 -179.304464) (xy 383.016179 -179.304464)
			(xy 382.962231 -179.296708) (xy 382.909936 -179.281353) (xy 382.860359 -179.258711) (xy 382.814509 -179.229245)
			(xy 382.773318 -179.193554) (xy 382.737627 -179.152363) (xy 382.708161 -179.106513) (xy 382.685519 -179.056936)
			(xy 382.670164 -179.004641) (xy 382.662408 -178.950693) (xy 382.661922 -178.923442) (xy 382.403028 -178.923442)
			(xy 382.397023 -178.943895) (xy 382.374382 -178.993473) (xy 382.344916 -179.039324) (xy 382.309225 -179.080515)
			(xy 382.268035 -179.116208) (xy 382.222185 -179.145675) (xy 382.172608 -179.168318) (xy 382.120313 -179.183675)
			(xy 382.066365 -179.191433) (xy 382.039114 -179.19192) (xy 382.013879 -179.191514) (xy 381.963845 -179.184898)
			(xy 381.915125 -179.171728) (xy 381.868573 -179.152234) (xy 381.846582 -179.13985) (xy 381.83693 -179.134008)
			(xy 381.814832 -179.131976) (xy 381.720344 -179.165504) (xy 381.704342 -179.180998) (xy 381.700278 -179.191412)
			(xy 381.68954 -179.21817) (xy 381.661257 -179.26841) (xy 381.625733 -179.313819) (xy 381.583777 -179.353362)
			(xy 381.536346 -179.386137) (xy 381.484521 -179.411399) (xy 381.429484 -179.428569) (xy 381.372489 -179.437259)
			(xy 381.343662 -179.437792) (xy 381.316409 -179.437357) (xy 381.262459 -179.429595) (xy 381.210162 -179.414235)
			(xy 381.160584 -179.391588) (xy 381.114733 -179.362116) (xy 381.073542 -179.326419) (xy 381.037851 -179.285224)
			(xy 381.008386 -179.239369) (xy 380.985746 -179.189787) (xy 380.970393 -179.137488) (xy 380.962639 -179.083537)
			(xy 380.962154 -179.056284) (xy 380.962816 -179.024721) (xy 380.973201 -178.962456) (xy 380.993686 -178.902747)
			(xy 381.008128 -178.874674) (xy 381.012954 -178.865784) (xy 381.014986 -178.846226) (xy 380.989332 -178.758088)
			(xy 380.976886 -178.742594) (xy 380.967996 -178.737514) (xy 380.942872 -178.723003) (xy 380.89699 -178.687493)
			(xy 380.857016 -178.645443) (xy 380.823873 -178.597823) (xy 380.798326 -178.545732) (xy 380.780965 -178.490372)
			(xy 380.77219 -178.433021) (xy 380.771654 -178.404012) (xy 375.0031 -178.404012) (xy 374.997766 -178.421886)
			(xy 374.974434 -178.472074) (xy 374.944088 -178.51836) (xy 374.926098 -178.539394) (xy 374.919748 -178.54676)
			(xy 374.913144 -178.564286) (xy 374.914668 -178.652424) (xy 374.922034 -178.66995) (xy 374.928638 -178.676808)
			(xy 374.948251 -178.698239) (xy 374.981448 -178.745911) (xy 375.007042 -178.798061) (xy 375.024442 -178.853486)
			(xy 375.033248 -178.910906) (xy 375.033794 -178.939952) (xy 375.0334 -178.96205) (xy 375.59691 -178.96205)
			(xy 375.600981 -178.906428) (xy 375.613107 -178.851991) (xy 375.63303 -178.7999) (xy 375.660326 -178.751265)
			(xy 375.694412 -178.707122) (xy 375.734561 -178.668413) (xy 375.779919 -178.635962) (xy 375.829519 -178.610461)
			(xy 375.882303 -178.592454) (xy 375.937146 -178.582324) (xy 375.99288 -178.580287) (xy 376.048317 -178.586387)
			(xy 376.102274 -178.600493) (xy 376.153603 -178.622305) (xy 376.201209 -178.651359) (xy 376.244077 -178.687034)
			(xy 376.281294 -178.728571) (xy 376.312067 -178.775084) (xy 376.335739 -178.825581) (xy 376.351807 -178.878988)
			(xy 376.359927 -178.934164) (xy 376.360436 -178.96205) (xy 376.359927 -178.989936) (xy 376.351807 -179.045112)
			(xy 376.335739 -179.098519) (xy 376.312067 -179.149016) (xy 376.281294 -179.195529) (xy 376.244077 -179.237066)
			(xy 376.201209 -179.272741) (xy 376.153603 -179.301795) (xy 376.102274 -179.323607) (xy 376.048317 -179.337713)
			(xy 375.99288 -179.343813) (xy 375.937146 -179.341776) (xy 375.882303 -179.331646) (xy 375.829519 -179.313639)
			(xy 375.779919 -179.288138) (xy 375.734561 -179.255687) (xy 375.694412 -179.216978) (xy 375.660326 -179.172835)
			(xy 375.63303 -179.1242) (xy 375.613107 -179.072109) (xy 375.600981 -179.017672) (xy 375.59691 -178.96205)
			(xy 375.0334 -178.96205) (xy 375.033308 -178.967203) (xy 375.025552 -179.021151) (xy 375.010197 -179.073446)
			(xy 374.987555 -179.123023) (xy 374.958089 -179.168873) (xy 374.922398 -179.210064) (xy 374.881207 -179.245755)
			(xy 374.835357 -179.275221) (xy 374.78578 -179.297863) (xy 374.733485 -179.313218) (xy 374.679537 -179.320974)
			(xy 374.625035 -179.320974) (xy 374.571087 -179.313218) (xy 374.518792 -179.297863) (xy 374.469215 -179.275221)
			(xy 374.423365 -179.245755) (xy 374.382174 -179.210064) (xy 374.346483 -179.168873) (xy 374.317017 -179.123023)
			(xy 374.294375 -179.073446) (xy 374.27902 -179.021151) (xy 374.271264 -178.967203) (xy 374.270778 -178.939952)
			(xy 374.271259 -178.912277) (xy 374.279258 -178.857507) (xy 374.295095 -178.804471) (xy 374.318438 -178.754283)
			(xy 374.348794 -178.707999) (xy 374.36679 -178.686968) (xy 374.37314 -178.679602) (xy 374.379744 -178.662076)
			(xy 374.37822 -178.573938) (xy 374.370854 -178.556412) (xy 374.36425 -178.549554) (xy 374.344616 -178.528141)
			(xy 374.311423 -178.480464) (xy 374.285833 -178.428309) (xy 374.268437 -178.372881) (xy 374.259637 -178.315457)
			(xy 374.259094 -178.28641) (xy 373.112911 -178.28641) (xy 373.1236 -178.322813) (xy 373.131356 -178.376761)
			(xy 373.131842 -178.404012) (xy 373.131179 -178.435575) (xy 373.120794 -178.49784) (xy 373.100309 -178.557549)
			(xy 373.085868 -178.585622) (xy 373.081042 -178.594512) (xy 373.07901 -178.61407) (xy 373.104664 -178.702208)
			(xy 373.11711 -178.717702) (xy 373.126 -178.722782) (xy 373.133366 -178.726846) (xy 373.143018 -178.732688)
			(xy 373.165116 -178.73472) (xy 373.259604 -178.701192) (xy 373.275606 -178.685698) (xy 373.27967 -178.675284)
			(xy 373.290366 -178.648508) (xy 373.318654 -178.598266) (xy 373.354184 -178.552857) (xy 373.396146 -178.513315)
			(xy 373.443583 -178.480541) (xy 373.495414 -178.455283) (xy 373.550457 -178.438117) (xy 373.607457 -178.429434)
			(xy 373.636286 -178.428904) (xy 373.66354 -178.429342) (xy 373.717495 -178.437098) (xy 373.769796 -178.452453)
			(xy 373.819379 -178.475095) (xy 373.865236 -178.504564) (xy 373.906431 -178.540259) (xy 373.942128 -178.581453)
			(xy 373.971598 -178.627308) (xy 373.994242 -178.676891) (xy 374.009599 -178.729192) (xy 374.017357 -178.783146)
			(xy 374.017357 -178.837654) (xy 374.009599 -178.891608) (xy 373.994242 -178.943909) (xy 373.971598 -178.993492)
			(xy 373.942128 -179.039347) (xy 373.906431 -179.080541) (xy 373.865236 -179.116236) (xy 373.819379 -179.145705)
			(xy 373.769796 -179.168347) (xy 373.717495 -179.183702) (xy 373.66354 -179.191458) (xy 373.636286 -179.19192)
			(xy 373.611051 -179.191526) (xy 373.561017 -179.184907) (xy 373.512296 -179.171733) (xy 373.465745 -179.152235)
			(xy 373.443754 -179.13985) (xy 373.434102 -179.134008) (xy 373.412004 -179.131976) (xy 373.317516 -179.165504)
			(xy 373.301514 -179.180998) (xy 373.29745 -179.191412) (xy 373.286735 -179.21818) (xy 373.25845 -179.268421)
			(xy 373.222922 -179.31383) (xy 373.180963 -179.353373) (xy 373.133528 -179.386147) (xy 373.0817 -179.411407)
			(xy 373.02666 -179.428575) (xy 372.969662 -179.437261) (xy 372.940834 -179.437792) (xy 372.913581 -179.437313)
			(xy 372.85963 -179.42956) (xy 372.807332 -179.414208) (xy 372.75775 -179.391568) (xy 372.711896 -179.362102)
			(xy 372.670703 -179.32641) (xy 372.635009 -179.285218) (xy 372.605541 -179.239365) (xy 372.582899 -179.189785)
			(xy 372.567544 -179.137488) (xy 372.559788 -179.083537) (xy 372.559326 -179.056284) (xy 372.559992 -179.024721)
			(xy 372.570376 -178.962456) (xy 372.590859 -178.902747) (xy 372.6053 -178.874674) (xy 372.610126 -178.865784)
			(xy 372.612158 -178.846226) (xy 372.586504 -178.758088) (xy 372.574058 -178.742594) (xy 372.565168 -178.737514)
			(xy 372.540061 -178.722975) (xy 372.494175 -178.687473) (xy 372.454197 -178.645429) (xy 372.421051 -178.597814)
			(xy 372.395502 -178.545726) (xy 372.378138 -178.490369) (xy 372.369362 -178.43302) (xy 372.368826 -178.404012)
			(xy 369.712494 -178.404012) (xy 369.712494 -178.457606) (xy 369.713063 -178.469174) (xy 369.723259 -178.489945)
			(xy 369.732052 -178.497484) (xy 369.75586 -178.516753) (xy 369.797577 -178.561593) (xy 369.831578 -178.612534)
			(xy 369.856986 -178.66826) (xy 369.865656 -178.697636) (xy 369.867942 -178.70678) (xy 369.879372 -178.72202)
			(xy 369.953286 -178.768756) (xy 369.971828 -178.772566) (xy 369.981226 -178.770788) (xy 369.997726 -178.76805)
			(xy 370.031049 -178.765125) (xy 370.047774 -178.764946) (xy 370.075022 -178.765502) (xy 370.128965 -178.773254)
			(xy 370.181256 -178.788604) (xy 370.23083 -178.811238) (xy 370.276678 -178.840698) (xy 370.317867 -178.876382)
			(xy 370.353559 -178.917564) (xy 370.383027 -178.963407) (xy 370.405671 -179.012977) (xy 370.421031 -179.065264)
			(xy 370.428793 -179.119206) (xy 370.429282 -179.146454) (xy 370.428791 -179.174028) (xy 370.420844 -179.2286)
			(xy 370.405125 -179.281459) (xy 370.38196 -179.331506) (xy 370.351831 -179.377696) (xy 370.315367 -179.419068)
			(xy 370.294662 -179.437284) (xy 370.286549 -179.444891) (xy 370.277193 -179.465039) (xy 370.276628 -179.476146)
			(xy 370.276628 -179.553362) (xy 370.277193 -179.564472) (xy 370.286533 -179.584632) (xy 370.294662 -179.592224)
			(xy 370.31538 -179.610428) (xy 370.351852 -179.651797) (xy 370.381984 -179.697988) (xy 370.405149 -179.748038)
			(xy 370.420863 -179.800902) (xy 370.428799 -179.855479) (xy 370.428833 -179.8574) (xy 375.01779 -179.8574)
			(xy 375.021861 -179.801778) (xy 375.033987 -179.747341) (xy 375.05391 -179.69525) (xy 375.081206 -179.646615)
			(xy 375.115292 -179.602472) (xy 375.155441 -179.563763) (xy 375.200799 -179.531312) (xy 375.250399 -179.505811)
			(xy 375.303183 -179.487804) (xy 375.358026 -179.477674) (xy 375.41376 -179.475637) (xy 375.469197 -179.481737)
			(xy 375.523154 -179.495843) (xy 375.574483 -179.517655) (xy 375.622089 -179.546709) (xy 375.664957 -179.582384)
			(xy 375.702174 -179.623921) (xy 375.732947 -179.670434) (xy 375.756619 -179.720931) (xy 375.772687 -179.774338)
			(xy 375.780807 -179.829514) (xy 375.781316 -179.8574) (xy 375.780807 -179.885286) (xy 375.772687 -179.940462)
			(xy 375.756619 -179.993869) (xy 375.732947 -180.044366) (xy 375.702174 -180.090879) (xy 375.664957 -180.132416)
			(xy 375.622089 -180.168091) (xy 375.574483 -180.197145) (xy 375.523154 -180.218957) (xy 375.469197 -180.233063)
			(xy 375.41376 -180.239163) (xy 375.358026 -180.237126) (xy 375.303183 -180.226996) (xy 375.250399 -180.208989)
			(xy 375.200799 -180.183488) (xy 375.155441 -180.151037) (xy 375.115292 -180.112328) (xy 375.081206 -180.068185)
			(xy 375.05391 -180.01955) (xy 375.033987 -179.967459) (xy 375.021861 -179.913022) (xy 375.01779 -179.8574)
			(xy 370.428833 -179.8574) (xy 370.429282 -179.883054) (xy 370.428802 -179.910307) (xy 370.42105 -179.964259)
			(xy 370.405699 -180.016558) (xy 370.38306 -180.066139) (xy 370.353594 -180.111994) (xy 370.317902 -180.153188)
			(xy 370.27671 -180.188882) (xy 370.230857 -180.21835) (xy 370.181276 -180.240992) (xy 370.128978 -180.256346)
			(xy 370.075027 -180.2641) (xy 370.047774 -180.264562) (xy 370.013484 -180.263038) (xy 370.003324 -180.262022)
			(xy 369.98402 -180.268118) (xy 369.913408 -180.3273) (xy 369.90401 -180.345334) (xy 369.902994 -180.355494)
			(xy 369.900102 -180.383674) (xy 369.88692 -180.438769) (xy 369.865734 -180.491308) (xy 369.837009 -180.540135)
			(xy 369.801378 -180.584175) (xy 369.759624 -180.622461) (xy 369.712666 -180.654149) (xy 369.661538 -180.678543)
			(xy 369.607363 -180.695105) (xy 369.551335 -180.703471) (xy 369.52301 -180.703982) (xy 369.495756 -180.703535)
			(xy 369.441803 -180.695779) (xy 369.389504 -180.680423) (xy 369.339922 -180.65778) (xy 369.294067 -180.62831)
			(xy 369.252874 -180.592615) (xy 369.21718 -180.55142) (xy 369.187713 -180.505564) (xy 369.165071 -180.455981)
			(xy 369.149718 -180.403681) (xy 369.141964 -180.349728) (xy 369.141502 -180.322474) (xy 369.141961 -180.29461)
			(xy 369.150067 -180.239476) (xy 369.166104 -180.186106) (xy 369.189729 -180.135635) (xy 369.220443 -180.089136)
			(xy 369.25759 -180.047596) (xy 369.278662 -180.029358) (xy 369.287806 -180.021738) (xy 369.297458 -180.000656)
			(xy 369.293902 -179.89677) (xy 369.28298 -179.876196) (xy 369.273328 -179.869084) (xy 369.252417 -179.853361)
			(xy 369.214661 -179.817144) (xy 369.182219 -179.7761) (xy 369.155703 -179.730999) (xy 369.135611 -179.682693)
			(xy 369.128548 -179.657502) (xy 369.126262 -179.648612) (xy 369.115594 -179.633372) (xy 369.043712 -179.58562)
			(xy 369.025678 -179.581556) (xy 369.016534 -179.582826) (xy 369.003518 -179.5845) (xy 368.977333 -179.586277)
			(xy 368.96421 -179.586382) (xy 368.936955 -179.585972) (xy 368.882999 -179.578215) (xy 368.830696 -179.562859)
			(xy 368.781112 -179.540216) (xy 368.735254 -179.510746) (xy 368.694057 -179.47505) (xy 368.65836 -179.433854)
			(xy 368.628889 -179.387997) (xy 368.606244 -179.338413) (xy 368.590887 -179.286111) (xy 368.583129 -179.232155)
			(xy 349.97925 -179.232155) (xy 349.984822 -179.238656) (xy 350.002457 -179.259591) (xy 350.032169 -179.305563)
			(xy 350.055005 -179.35531) (xy 350.070497 -179.40781) (xy 350.078327 -179.461985) (xy 350.078802 -179.489354)
			(xy 350.078302 -179.516606) (xy 350.070551 -179.570556) (xy 350.055201 -179.622853) (xy 350.032563 -179.672434)
			(xy 350.003099 -179.718287) (xy 349.967409 -179.759481) (xy 349.92622 -179.795175) (xy 349.880369 -179.824644)
			(xy 349.830791 -179.847287) (xy 349.778495 -179.862643) (xy 349.724546 -179.870399) (xy 349.697294 -179.870862)
			(xy 349.669923 -179.870409) (xy 349.615743 -179.862589) (xy 349.56324 -179.847098) (xy 349.513493 -179.824253)
			(xy 349.467527 -179.794525) (xy 349.446596 -179.776882) (xy 349.439484 -179.770786) (xy 349.422466 -179.764436)
			(xy 349.337122 -179.764436) (xy 349.320104 -179.770786) (xy 349.312992 -179.776882) (xy 349.292071 -179.794536)
			(xy 349.246096 -179.824246) (xy 349.196345 -179.847079) (xy 349.143842 -179.862567) (xy 349.089664 -179.870391)
			(xy 349.062294 -179.870862) (xy 349.035039 -179.87045) (xy 348.981084 -179.862691) (xy 348.928782 -179.847332)
			(xy 348.879199 -179.824685) (xy 348.833344 -179.795213) (xy 348.79215 -179.759513) (xy 348.756456 -179.718315)
			(xy 348.72699 -179.672455) (xy 348.70435 -179.622869) (xy 348.688998 -179.570565) (xy 348.681246 -179.516609)
			(xy 348.680786 -179.489354) (xy 348.681287 -179.461985) (xy 348.689097 -179.407808) (xy 348.704578 -179.355305)
			(xy 348.727412 -179.305558) (xy 348.757129 -179.259589) (xy 348.774766 -179.238656) (xy 348.780862 -179.231544)
			(xy 348.787212 -179.214526) (xy 348.787212 -179.129182) (xy 348.780862 -179.112164) (xy 348.774766 -179.105052)
			(xy 348.757079 -179.084157) (xy 348.727353 -179.038183) (xy 348.704508 -178.988431) (xy 348.689013 -178.935923)
			(xy 348.681188 -178.881739) (xy 348.681193 -178.826992) (xy 348.689028 -178.772809) (xy 348.704532 -178.720304)
			(xy 348.727386 -178.670556) (xy 348.75712 -178.624588) (xy 348.774766 -178.603656) (xy 348.780862 -178.596544)
			(xy 348.787212 -178.579526) (xy 348.787212 -178.494182) (xy 348.780862 -178.477164) (xy 348.774766 -178.470052)
			(xy 348.757079 -178.449157) (xy 348.727353 -178.403183) (xy 348.704508 -178.353431) (xy 348.689013 -178.300923)
			(xy 348.681188 -178.246739) (xy 348.681193 -178.191992) (xy 348.689028 -178.137809) (xy 348.704532 -178.085304)
			(xy 348.727386 -178.035556) (xy 348.75712 -177.989588) (xy 348.774766 -177.968656) (xy 348.780862 -177.961544)
			(xy 348.787212 -177.944526) (xy 348.787212 -177.859182) (xy 348.780862 -177.842164) (xy 348.774766 -177.835052)
			(xy 348.757079 -177.814157) (xy 348.727353 -177.768183) (xy 348.704508 -177.718431) (xy 348.689013 -177.665923)
			(xy 348.681188 -177.611739) (xy 348.681193 -177.556992) (xy 348.689028 -177.502809) (xy 348.704532 -177.450304)
			(xy 348.727386 -177.400556) (xy 348.75712 -177.354588) (xy 348.774766 -177.333656) (xy 348.780862 -177.326544)
			(xy 348.787212 -177.309526) (xy 348.787212 -177.224182) (xy 348.780862 -177.207164) (xy 348.774766 -177.200052)
			(xy 348.757079 -177.179157) (xy 348.727353 -177.133183) (xy 348.704508 -177.083431) (xy 348.689013 -177.030923)
			(xy 348.681188 -176.976739) (xy 348.681193 -176.921992) (xy 348.689028 -176.867809) (xy 348.704532 -176.815304)
			(xy 348.727386 -176.765556) (xy 348.75712 -176.719588) (xy 348.774766 -176.698656) (xy 348.780862 -176.691544)
			(xy 348.787212 -176.674526) (xy 348.787212 -176.589182) (xy 348.780862 -176.572164) (xy 348.774766 -176.565052)
			(xy 348.757133 -176.544116) (xy 348.727421 -176.498143) (xy 348.704585 -176.448397) (xy 348.689092 -176.395897)
			(xy 348.681262 -176.341723) (xy 348.680786 -176.314354) (xy 348.681305 -176.285924) (xy 348.689755 -176.229696)
			(xy 348.706461 -176.175345) (xy 348.731052 -176.124078) (xy 348.762983 -176.07703) (xy 348.781878 -176.055782)
			(xy 348.788228 -176.04867) (xy 348.795086 -176.031144) (xy 348.795086 -175.942752) (xy 348.788228 -175.925226)
			(xy 348.781878 -175.918114) (xy 348.762957 -175.896887) (xy 348.731028 -175.849835) (xy 348.706442 -175.798562)
			(xy 348.689745 -175.744206) (xy 348.681307 -175.687973) (xy 348.680786 -175.659542) (xy 348.68128 -175.632173)
			(xy 348.689092 -175.577995) (xy 348.704574 -175.525492) (xy 348.72741 -175.475745) (xy 348.757128 -175.429777)
			(xy 348.774766 -175.408844) (xy 348.780862 -175.401732) (xy 348.787212 -175.384714) (xy 348.787212 -175.29937)
			(xy 348.780862 -175.282352) (xy 348.774766 -175.27524) (xy 348.757165 -175.254275) (xy 348.727435 -175.208314)
			(xy 348.704585 -175.158573) (xy 348.689084 -175.106075) (xy 348.681251 -175.051901) (xy 348.681246 -174.997163)
			(xy 348.68907 -174.942986) (xy 348.704563 -174.890486) (xy 348.727405 -174.840742) (xy 348.757127 -174.794776)
			(xy 348.774766 -174.773844) (xy 348.780862 -174.766732) (xy 348.787212 -174.749714) (xy 348.787212 -174.66437)
			(xy 348.780862 -174.647352) (xy 348.774766 -174.64024) (xy 348.757165 -174.619275) (xy 348.727435 -174.573314)
			(xy 348.704585 -174.523573) (xy 348.689084 -174.471075) (xy 348.681251 -174.416901) (xy 348.681246 -174.362163)
			(xy 348.68907 -174.307986) (xy 348.704563 -174.255486) (xy 348.727405 -174.205742) (xy 348.757127 -174.159776)
			(xy 348.774766 -174.138844) (xy 348.780862 -174.131732) (xy 348.787212 -174.114714) (xy 348.787212 -174.02937)
			(xy 348.780862 -174.012352) (xy 348.774766 -174.00524) (xy 348.757127 -173.984308) (xy 348.727416 -173.938335)
			(xy 348.704581 -173.888587) (xy 348.68909 -173.836087) (xy 348.681261 -173.781911) (xy 348.680786 -173.754542)
			(xy 348.681241 -173.727407) (xy 348.688933 -173.673686) (xy 348.704168 -173.621598) (xy 348.726637 -173.572199)
			(xy 348.755886 -173.526486) (xy 348.773242 -173.505622) (xy 348.779338 -173.49851) (xy 348.785434 -173.481492)
			(xy 348.784926 -173.396148) (xy 348.778576 -173.37913) (xy 348.772226 -173.372018) (xy 348.754296 -173.351024)
			(xy 348.724109 -173.304797) (xy 348.700901 -173.254701) (xy 348.685157 -173.201782) (xy 348.677207 -173.147147)
			(xy 348.676722 -173.119542) (xy 346.693998 -173.119542) (xy 346.693551 -173.146512) (xy 346.685939 -173.199914)
			(xy 346.670874 -173.251708) (xy 346.648657 -173.300861) (xy 346.619731 -173.34639) (xy 346.602558 -173.367192)
			(xy 346.596462 -173.374304) (xy 346.590366 -173.391322) (xy 346.591128 -173.47692) (xy 346.597732 -173.493684)
			(xy 346.604082 -173.500796) (xy 346.622136 -173.521899) (xy 346.652648 -173.568299) (xy 346.676116 -173.618629)
			(xy 346.692045 -173.671829) (xy 346.700099 -173.726775) (xy 346.700602 -173.754542) (xy 346.700101 -173.781911)
			(xy 346.692292 -173.836089) (xy 346.676811 -173.888591) (xy 346.653977 -173.938339) (xy 346.62426 -173.984307)
			(xy 346.606622 -174.00524) (xy 346.600526 -174.012352) (xy 346.594176 -174.02937) (xy 346.594176 -174.114714)
			(xy 346.600526 -174.131732) (xy 346.606622 -174.138844) (xy 346.624302 -174.159744) (xy 346.654021 -174.205719)
			(xy 346.676861 -174.255471) (xy 346.692352 -174.307977) (xy 346.700176 -174.36216) (xy 346.700171 -174.416904)
			(xy 346.692338 -174.471084) (xy 346.676839 -174.523588) (xy 346.653991 -174.573337) (xy 346.624264 -174.619306)
			(xy 346.606622 -174.64024) (xy 346.600526 -174.647352) (xy 346.594176 -174.66437) (xy 346.594176 -174.749714)
			(xy 346.600526 -174.766732) (xy 346.606622 -174.773844) (xy 346.624302 -174.794744) (xy 346.654021 -174.840719)
			(xy 346.676861 -174.890471) (xy 346.692352 -174.942977) (xy 346.700176 -174.99716) (xy 346.700171 -175.051904)
			(xy 346.692338 -175.106084) (xy 346.676839 -175.158588) (xy 346.653991 -175.208337) (xy 346.624264 -175.254306)
			(xy 346.606622 -175.27524) (xy 346.600526 -175.282352) (xy 346.594176 -175.29937) (xy 346.594176 -175.384714)
			(xy 346.600526 -175.401732) (xy 346.606622 -175.408844) (xy 346.624252 -175.429784) (xy 346.653964 -175.475755)
			(xy 346.676802 -175.5255) (xy 346.692295 -175.577999) (xy 346.700126 -175.632173) (xy 346.700602 -175.659542)
			(xy 346.700084 -175.687972) (xy 346.691634 -175.744201) (xy 346.674928 -175.798551) (xy 346.650337 -175.849818)
			(xy 346.618406 -175.896866) (xy 346.59951 -175.918114) (xy 346.59316 -175.925226) (xy 346.586302 -175.942752)
			(xy 346.586302 -176.031144) (xy 346.59316 -176.04867) (xy 346.59951 -176.055782) (xy 346.618427 -176.077012)
			(xy 346.650357 -176.124063) (xy 346.674944 -176.175335) (xy 346.691642 -176.22969) (xy 346.70008 -176.285923)
			(xy 346.700602 -176.314354) (xy 346.700108 -176.341723) (xy 346.692297 -176.395901) (xy 346.676815 -176.448404)
			(xy 346.653979 -176.498151) (xy 346.62426 -176.544119) (xy 346.606622 -176.565052) (xy 346.600526 -176.572164)
			(xy 346.594176 -176.589182) (xy 346.594176 -176.674526) (xy 346.600526 -176.691544) (xy 346.606622 -176.698656)
			(xy 346.624216 -176.719626) (xy 346.653939 -176.765589) (xy 346.676784 -176.815329) (xy 346.692281 -176.867825)
			(xy 346.700113 -176.921998) (xy 346.700118 -176.976733) (xy 346.692296 -177.030907) (xy 346.676808 -177.083406)
			(xy 346.653972 -177.13315) (xy 346.624257 -177.179118) (xy 346.606622 -177.200052) (xy 346.600526 -177.207164)
			(xy 346.594176 -177.224182) (xy 346.594176 -177.309526) (xy 346.600526 -177.326544) (xy 346.606622 -177.333656)
			(xy 346.624257 -177.354591) (xy 346.653969 -177.400563) (xy 346.676805 -177.45031) (xy 346.692297 -177.50281)
			(xy 346.700127 -177.556985) (xy 346.700602 -177.584354) (xy 346.700116 -177.611605) (xy 346.69236 -177.665553)
			(xy 346.677005 -177.717848) (xy 346.654363 -177.767425) (xy 346.624897 -177.813275) (xy 346.589206 -177.854466)
			(xy 346.548015 -177.890157) (xy 346.502165 -177.919623) (xy 346.452588 -177.942265) (xy 346.400293 -177.95762)
			(xy 346.346345 -177.965376) (xy 346.291843 -177.965376) (xy 346.237895 -177.95762) (xy 346.1856 -177.942265)
			(xy 346.136023 -177.919623) (xy 346.090173 -177.890157) (xy 346.048982 -177.854466) (xy 346.013291 -177.813275)
			(xy 345.983825 -177.767425) (xy 345.961183 -177.717848) (xy 345.945828 -177.665553) (xy 345.938072 -177.611605)
			(xy 345.937586 -177.584354) (xy 345.938163 -177.554878) (xy 345.947224 -177.496627) (xy 345.965138 -177.440462)
			(xy 345.991479 -177.387723) (xy 346.025619 -177.339663) (xy 346.04579 -177.318162) (xy 346.052333 -177.310834)
			(xy 346.059774 -177.292669) (xy 346.060268 -177.282856) (xy 346.060268 -177.229516) (xy 346.052902 -177.222658)
			(xy 346.045566 -177.216125) (xy 346.027406 -177.20868) (xy 346.017596 -177.20818) (xy 345.985592 -177.20818)
			(xy 345.975779 -177.208677) (xy 345.957615 -177.216115) (xy 345.950286 -177.222658) (xy 345.928793 -177.242839)
			(xy 345.880732 -177.276983) (xy 345.827991 -177.303328) (xy 345.771825 -177.321247) (xy 345.713571 -177.330314)
			(xy 345.684094 -177.330862) (xy 345.656839 -177.33045) (xy 345.602884 -177.322691) (xy 345.550582 -177.307332)
			(xy 345.500999 -177.284685) (xy 345.455144 -177.255213) (xy 345.41395 -177.219513) (xy 345.378256 -177.178315)
			(xy 345.34879 -177.132455) (xy 345.32615 -177.082869) (xy 345.310798 -177.030565) (xy 345.303046 -176.976609)
			(xy 345.302586 -176.949354) (xy 345.303163 -176.919878) (xy 345.312224 -176.861627) (xy 345.330138 -176.805462)
			(xy 345.356479 -176.752723) (xy 345.390619 -176.704663) (xy 345.41079 -176.683162) (xy 345.417333 -176.675834)
			(xy 345.424774 -176.657669) (xy 345.425268 -176.647856) (xy 345.425268 -176.594516) (xy 345.417902 -176.587658)
			(xy 345.410566 -176.581125) (xy 345.392406 -176.57368) (xy 345.382596 -176.57318) (xy 345.350592 -176.57318)
			(xy 345.340779 -176.573677) (xy 345.322615 -176.581115) (xy 345.315286 -176.587658) (xy 345.293793 -176.607839)
			(xy 345.245732 -176.641983) (xy 345.192991 -176.668328) (xy 345.136825 -176.686247) (xy 345.078571 -176.695314)
			(xy 345.049094 -176.695862) (xy 345.021839 -176.69545) (xy 344.967884 -176.687691) (xy 344.915582 -176.672332)
			(xy 344.865999 -176.649685) (xy 344.820144 -176.620213) (xy 344.77895 -176.584513) (xy 344.743256 -176.543315)
			(xy 344.71379 -176.497455) (xy 344.69115 -176.447869) (xy 344.675798 -176.395565) (xy 344.668046 -176.341609)
			(xy 344.667586 -176.314354) (xy 344.668087 -176.286985) (xy 344.675897 -176.232808) (xy 344.691378 -176.180305)
			(xy 344.714212 -176.130558) (xy 344.743929 -176.084589) (xy 344.761566 -176.063656) (xy 344.767662 -176.056544)
			(xy 344.774012 -176.039526) (xy 344.774012 -175.954182) (xy 344.767662 -175.937164) (xy 344.761566 -175.930052)
			(xy 344.743879 -175.909157) (xy 344.714153 -175.863183) (xy 344.691308 -175.813431) (xy 344.675813 -175.760923)
			(xy 344.667988 -175.706739) (xy 344.667993 -175.651992) (xy 344.675828 -175.597809) (xy 344.691332 -175.545304)
			(xy 344.714186 -175.495556) (xy 344.74392 -175.449588) (xy 344.761566 -175.428656) (xy 344.767662 -175.421544)
			(xy 344.774012 -175.404526) (xy 344.774012 -175.319182) (xy 344.767662 -175.302164) (xy 344.761566 -175.295052)
			(xy 344.743879 -175.274157) (xy 344.714153 -175.228183) (xy 344.691308 -175.178431) (xy 344.675813 -175.125923)
			(xy 344.667988 -175.071739) (xy 344.667993 -175.016992) (xy 344.675828 -174.962809) (xy 344.691332 -174.910304)
			(xy 344.714186 -174.860556) (xy 344.74392 -174.814588) (xy 344.761566 -174.793656) (xy 344.767662 -174.786544)
			(xy 344.774012 -174.769526) (xy 344.774012 -174.684182) (xy 344.767662 -174.667164) (xy 344.761566 -174.660052)
			(xy 344.743879 -174.639157) (xy 344.714153 -174.593183) (xy 344.691308 -174.543431) (xy 344.675813 -174.490923)
			(xy 344.667988 -174.436739) (xy 344.667993 -174.381992) (xy 344.675828 -174.327809) (xy 344.691332 -174.275304)
			(xy 344.714186 -174.225556) (xy 344.74392 -174.179588) (xy 344.761566 -174.158656) (xy 344.767662 -174.151544)
			(xy 344.774012 -174.134526) (xy 344.774012 -174.049182) (xy 344.767662 -174.032164) (xy 344.761566 -174.025052)
			(xy 344.743933 -174.004116) (xy 344.714221 -173.958143) (xy 344.691385 -173.908397) (xy 344.675892 -173.855897)
			(xy 344.668062 -173.801723) (xy 344.667586 -173.774354) (xy 344.66805 -173.746313) (xy 344.676258 -173.690833)
			(xy 344.69249 -173.637151) (xy 344.716399 -173.586419) (xy 344.747469 -173.539729) (xy 344.765884 -173.518576)
			(xy 344.772488 -173.511464) (xy 344.779092 -173.493684) (xy 344.77833 -173.405546) (xy 344.771218 -173.38802)
			(xy 344.764614 -173.380908) (xy 344.745242 -173.359576) (xy 344.712517 -173.312148) (xy 344.6873 -173.260336)
			(xy 344.670166 -173.205321) (xy 344.661505 -173.148353) (xy 344.660982 -173.119542) (xy 340.235032 -173.119542)
			(xy 351.151952 -184.036462) (xy 352.88347 -184.036462) (xy 352.883955 -184.009092) (xy 352.891766 -183.954913)
			(xy 352.90725 -183.90241) (xy 352.930087 -183.852662) (xy 352.95981 -183.806696) (xy 352.97745 -183.785764)
			(xy 352.983546 -183.778652) (xy 352.989896 -183.761634) (xy 352.989896 -183.67629) (xy 352.983546 -183.659272)
			(xy 352.97745 -183.65216) (xy 352.959771 -183.631258) (xy 352.930046 -183.585285) (xy 352.907202 -183.535534)
			(xy 352.891707 -183.483027) (xy 352.883882 -183.428844) (xy 352.883886 -183.374099) (xy 352.891719 -183.319917)
			(xy 352.907222 -183.267412) (xy 352.930074 -183.217664) (xy 352.959806 -183.171696) (xy 352.97745 -183.150764)
			(xy 352.983546 -183.143652) (xy 352.989896 -183.126634) (xy 352.989896 -183.04129) (xy 352.983546 -183.024272)
			(xy 352.97745 -183.01716) (xy 352.959771 -182.996258) (xy 352.930046 -182.950285) (xy 352.907202 -182.900534)
			(xy 352.891707 -182.848027) (xy 352.883882 -182.793844) (xy 352.883886 -182.739099) (xy 352.891719 -182.684917)
			(xy 352.907222 -182.632412) (xy 352.930074 -182.582664) (xy 352.959806 -182.536696) (xy 352.97745 -182.515764)
			(xy 352.983546 -182.508652) (xy 352.989896 -182.491634) (xy 352.989896 -182.40629) (xy 352.983546 -182.389272)
			(xy 352.97745 -182.38216) (xy 352.959833 -182.36121) (xy 352.930116 -182.315243) (xy 352.907275 -182.2655)
			(xy 352.891779 -182.213003) (xy 352.883946 -182.15883) (xy 352.88347 -182.131462) (xy 352.884003 -182.102829)
			(xy 352.892542 -182.046205) (xy 352.909453 -181.991494) (xy 352.934356 -181.939927) (xy 352.966689 -181.892665)
			(xy 352.985832 -181.871366) (xy 352.992436 -181.864254) (xy 352.999294 -181.846728) (xy 352.999802 -181.758336)
			(xy 352.992944 -181.740556) (xy 352.98634 -181.733444) (xy 352.967563 -181.712232) (xy 352.935865 -181.665281)
			(xy 352.911464 -181.614157) (xy 352.894894 -181.559986) (xy 352.886523 -181.503959) (xy 352.88601 -181.475634)
			(xy 352.886487 -181.448381) (xy 352.89424 -181.39443) (xy 352.909592 -181.342131) (xy 352.932232 -181.29255)
			(xy 352.961698 -181.246696) (xy 352.997391 -181.205502) (xy 353.038583 -181.169808) (xy 353.084436 -181.14034)
			(xy 353.134016 -181.117698) (xy 353.186314 -181.102343) (xy 353.240265 -181.094588) (xy 353.267518 -181.094126)
			(xy 353.294889 -181.094575) (xy 353.349069 -181.102396) (xy 353.401573 -181.117889) (xy 353.451319 -181.140734)
			(xy 353.497285 -181.170463) (xy 353.518216 -181.188106) (xy 353.525328 -181.194202) (xy 353.542346 -181.200552)
			(xy 353.62769 -181.200552) (xy 353.644708 -181.194202) (xy 353.65182 -181.188106) (xy 353.672753 -181.170465)
			(xy 353.718721 -181.140741) (xy 353.768467 -181.117895) (xy 353.820969 -181.102399) (xy 353.875147 -181.09457)
			(xy 353.929889 -181.09457) (xy 353.984067 -181.102399) (xy 354.036569 -181.117895) (xy 354.086315 -181.140741)
			(xy 354.132283 -181.170465) (xy 354.153216 -181.188106) (xy 354.160328 -181.194202) (xy 354.177346 -181.200552)
			(xy 354.26269 -181.200552) (xy 354.279708 -181.194202) (xy 354.28682 -181.188106) (xy 354.307772 -181.170492)
			(xy 354.353739 -181.140776) (xy 354.403482 -181.117935) (xy 354.455978 -181.102438) (xy 354.51015 -181.094604)
			(xy 354.537518 -181.094126) (xy 354.564773 -181.094538) (xy 354.618727 -181.102299) (xy 354.671028 -181.117659)
			(xy 354.720611 -181.140306) (xy 354.766466 -181.169779) (xy 354.807659 -181.205478) (xy 354.843352 -181.246676)
			(xy 354.872819 -181.292535) (xy 354.89546 -181.34212) (xy 354.910813 -181.394423) (xy 354.918565 -181.448379)
			(xy 354.919026 -181.475634) (xy 356.90175 -181.475634) (xy 356.90231 -181.448386) (xy 356.910061 -181.394443)
			(xy 356.925409 -181.342152) (xy 356.948043 -181.292578) (xy 356.977502 -181.246729) (xy 357.013186 -181.20554)
			(xy 357.054368 -181.169848) (xy 357.100211 -181.14038) (xy 357.149781 -181.117736) (xy 357.202068 -181.102377)
			(xy 357.25601 -181.094615) (xy 357.283258 -181.094126) (xy 357.310628 -181.09461) (xy 357.364806 -181.102423)
			(xy 357.417309 -181.117907) (xy 357.467057 -181.140745) (xy 357.513024 -181.170466) (xy 357.533956 -181.188106)
			(xy 357.541068 -181.194202) (xy 357.558086 -181.200552) (xy 357.64343 -181.200552) (xy 357.660448 -181.194202)
			(xy 357.66756 -181.188106) (xy 357.688497 -181.170473) (xy 357.734468 -181.14076) (xy 357.784215 -181.117923)
			(xy 357.836714 -181.10243) (xy 357.890889 -181.094601) (xy 357.918258 -181.094126) (xy 357.945511 -181.094594)
			(xy 357.999464 -181.102347) (xy 358.051764 -181.117699) (xy 358.101346 -181.140339) (xy 358.147201 -181.169806)
			(xy 358.188395 -181.205499) (xy 358.224089 -181.246693) (xy 358.253557 -181.292547) (xy 358.276198 -181.342129)
			(xy 358.291552 -181.394428) (xy 358.299305 -181.448381) (xy 358.299766 -181.475634) (xy 358.299284 -181.502768)
			(xy 358.291597 -181.556488) (xy 358.276368 -181.608574) (xy 358.253905 -181.657974) (xy 358.224663 -181.703689)
			(xy 358.20731 -181.724554) (xy 358.201214 -181.731666) (xy 358.195118 -181.748684) (xy 358.195626 -181.834028)
			(xy 358.201976 -181.851046) (xy 358.208326 -181.858158) (xy 358.226238 -181.879168) (xy 358.256429 -181.92539)
			(xy 358.279641 -181.975482) (xy 358.295389 -182.028397) (xy 358.303344 -182.08303) (xy 358.30383 -182.110634)
			(xy 358.303401 -182.138006) (xy 358.302842 -182.141876) (xy 370.14785 -182.141876) (xy 370.148351 -182.114302)
			(xy 370.156294 -182.05973) (xy 370.17201 -182.00687) (xy 370.195174 -181.956824) (xy 370.225301 -181.910634)
			(xy 370.261765 -181.869262) (xy 370.28247 -181.851046) (xy 370.290574 -181.843431) (xy 370.299934 -181.823289)
			(xy 370.300504 -181.812184) (xy 370.300504 -181.734968) (xy 370.299968 -181.723854) (xy 370.290607 -181.703696)
			(xy 370.28247 -181.696106) (xy 370.261753 -181.677902) (xy 370.225284 -181.636531) (xy 370.195153 -181.590339)
			(xy 370.171989 -181.54029) (xy 370.156274 -181.487427) (xy 370.148335 -181.432851) (xy 370.14785 -181.405276)
			(xy 370.148454 -181.37583) (xy 370.157513 -181.317638) (xy 370.175399 -181.261528) (xy 370.201686 -181.208827)
			(xy 370.235752 -181.160788) (xy 370.276789 -181.118547) (xy 370.323824 -181.083106) (xy 370.349526 -181.068726)
			(xy 370.357908 -181.064408) (xy 370.3701 -181.050438) (xy 370.399818 -180.968904) (xy 370.399564 -180.950362)
			(xy 370.396008 -180.941726) (xy 370.387638 -180.919707) (xy 370.375885 -180.87409) (xy 370.369955 -180.827357)
			(xy 370.369592 -180.803804) (xy 370.370038 -180.777186) (xy 370.377614 -180.724491) (xy 370.392612 -180.673411)
			(xy 370.414727 -180.624986) (xy 370.443509 -180.580201) (xy 370.478372 -180.539967) (xy 370.518605 -180.505105)
			(xy 370.563391 -180.476324) (xy 370.611817 -180.45421) (xy 370.662897 -180.439213) (xy 370.715592 -180.431637)
			(xy 370.74221 -180.431186) (xy 370.768632 -180.431641) (xy 370.820947 -180.439092) (xy 370.871686 -180.453858)
			(xy 370.91983 -180.475642) (xy 370.964415 -180.504008) (xy 370.98478 -180.520848) (xy 370.991638 -180.526944)
			(xy 371.008656 -180.53304) (xy 371.092984 -180.53304) (xy 371.110002 -180.526944) (xy 371.11686 -180.520848)
			(xy 371.137226 -180.504009) (xy 371.181812 -180.475644) (xy 371.229956 -180.453857) (xy 371.280693 -180.439086)
			(xy 371.333008 -180.431626) (xy 371.385852 -180.431626) (xy 371.438167 -180.439086) (xy 371.488904 -180.453857)
			(xy 371.537048 -180.475644) (xy 371.581634 -180.504009) (xy 371.602 -180.520848) (xy 371.608858 -180.526944)
			(xy 371.625876 -180.53304) (xy 371.710204 -180.53304) (xy 371.727222 -180.526944) (xy 371.73408 -180.520848)
			(xy 371.754459 -180.504027) (xy 371.799044 -180.475668) (xy 371.847186 -180.453884) (xy 371.897919 -180.439113)
			(xy 371.95023 -180.431649) (xy 371.97665 -180.431186) (xy 372.00454 -180.431669) (xy 372.059696 -180.439976)
			(xy 372.112999 -180.456411) (xy 372.163256 -180.480608) (xy 372.209346 -180.512026) (xy 372.250237 -180.549962)
			(xy 372.285017 -180.59357) (xy 372.312909 -180.641874) (xy 372.327118 -180.678074) (xy 376.98553 -180.678074)
			(xy 376.986036 -180.650501) (xy 376.993979 -180.595929) (xy 377.009695 -180.54307) (xy 377.032858 -180.493023)
			(xy 377.062984 -180.446833) (xy 377.099445 -180.40546) (xy 377.12015 -180.387244) (xy 377.128252 -180.379627)
			(xy 377.137613 -180.359486) (xy 377.138184 -180.348382) (xy 377.138184 -180.271166) (xy 377.137656 -180.260051)
			(xy 377.12829 -180.239893) (xy 377.12015 -180.232304) (xy 377.099416 -180.214118) (xy 377.062948 -180.172745)
			(xy 377.032818 -180.126551) (xy 377.009654 -180.0765) (xy 376.993938 -180.023636) (xy 376.985999 -179.969059)
			(xy 376.986001 -179.913908) (xy 376.993945 -179.859331) (xy 377.009666 -179.806468) (xy 377.032834 -179.756419)
			(xy 377.062969 -179.710229) (xy 377.09944 -179.668858) (xy 377.12015 -179.650644) (xy 377.128252 -179.643027)
			(xy 377.137613 -179.622886) (xy 377.138184 -179.611782) (xy 377.138184 -179.534566) (xy 377.137656 -179.523451)
			(xy 377.12829 -179.503293) (xy 377.12015 -179.495704) (xy 377.099428 -179.477505) (xy 377.06296 -179.436133)
			(xy 377.032831 -179.38994) (xy 377.009667 -179.33989) (xy 376.993953 -179.287025) (xy 376.986015 -179.232449)
			(xy 376.98553 -179.204874) (xy 376.985931 -179.177619) (xy 376.993692 -179.123664) (xy 377.009054 -179.071362)
			(xy 377.031702 -179.021779) (xy 377.061176 -178.975924) (xy 377.096876 -178.934731) (xy 377.138076 -178.899038)
			(xy 377.183936 -178.869571) (xy 377.233522 -178.846931) (xy 377.285826 -178.831579) (xy 377.339783 -178.823826)
			(xy 377.367038 -178.823366) (xy 377.394893 -178.82388) (xy 377.450008 -178.832008) (xy 377.503357 -178.848057)
			(xy 377.553809 -178.871686) (xy 377.600292 -178.902394) (xy 377.641821 -178.93953) (xy 377.677514 -178.982305)
			(xy 377.706615 -179.029811) (xy 377.728505 -179.081041) (xy 377.7361 -179.107846) (xy 377.738386 -179.116736)
			(xy 377.749054 -179.131976) (xy 377.820936 -179.179728) (xy 377.83897 -179.183792) (xy 377.848114 -179.182522)
			(xy 377.861131 -179.180854) (xy 377.887315 -179.179073) (xy 377.900438 -179.178966) (xy 377.914587 -179.179056)
			(xy 377.94281 -179.181093) (xy 377.956826 -179.18303) (xy 377.966986 -179.184554) (xy 377.986544 -179.179728)
			(xy 378.060966 -179.123848) (xy 378.071126 -179.106322) (xy 378.072396 -179.096162) (xy 378.076477 -179.069007)
			(xy 378.09145 -179.016176) (xy 378.113841 -178.966037) (xy 378.143189 -178.919625) (xy 378.178888 -178.877901)
			(xy 378.220198 -178.841724) (xy 378.266268 -178.811843) (xy 378.316146 -178.788875) (xy 378.368801 -178.773295)
			(xy 378.423146 -178.765423) (xy 378.450602 -178.764946) (xy 378.477851 -178.765476) (xy 378.531795 -178.773231)
			(xy 378.584086 -178.788584) (xy 378.63366 -178.811222) (xy 378.679508 -178.840685) (xy 378.720697 -178.876371)
			(xy 378.756389 -178.917556) (xy 378.785856 -178.963401) (xy 378.8085 -179.012973) (xy 378.823859 -179.065262)
			(xy 378.831621 -179.119205) (xy 378.83211 -179.146454) (xy 378.831609 -179.174027) (xy 378.823663 -179.228598)
			(xy 378.807945 -179.281457) (xy 378.784782 -179.331503) (xy 378.754655 -179.377694) (xy 378.718194 -179.419067)
			(xy 378.69749 -179.437284) (xy 378.689382 -179.444896) (xy 378.680022 -179.46504) (xy 378.679456 -179.476146)
			(xy 378.679456 -179.553362) (xy 378.680011 -179.564474) (xy 378.689357 -179.584634) (xy 378.69749 -179.592224)
			(xy 378.718214 -179.610421) (xy 378.754684 -179.651793) (xy 378.784814 -179.697985) (xy 378.807978 -179.748036)
			(xy 378.823692 -179.800901) (xy 378.831627 -179.855478) (xy 378.831661 -179.8574) (xy 383.420618 -179.8574)
			(xy 383.424689 -179.801778) (xy 383.436815 -179.747341) (xy 383.456738 -179.69525) (xy 383.484034 -179.646615)
			(xy 383.51812 -179.602472) (xy 383.558269 -179.563763) (xy 383.603627 -179.531312) (xy 383.653227 -179.505811)
			(xy 383.706011 -179.487804) (xy 383.760854 -179.477674) (xy 383.816588 -179.475637) (xy 383.872025 -179.481737)
			(xy 383.925982 -179.495843) (xy 383.977311 -179.517655) (xy 384.024917 -179.546709) (xy 384.067785 -179.582384)
			(xy 384.105002 -179.623921) (xy 384.135775 -179.670434) (xy 384.159447 -179.720931) (xy 384.175515 -179.774338)
			(xy 384.183635 -179.829514) (xy 384.184144 -179.8574) (xy 384.183635 -179.885286) (xy 384.175515 -179.940462)
			(xy 384.159447 -179.993869) (xy 384.135775 -180.044366) (xy 384.105002 -180.090879) (xy 384.067785 -180.132416)
			(xy 384.024917 -180.168091) (xy 383.977311 -180.197145) (xy 383.925982 -180.218957) (xy 383.872025 -180.233063)
			(xy 383.816588 -180.239163) (xy 383.760854 -180.237126) (xy 383.706011 -180.226996) (xy 383.653227 -180.208989)
			(xy 383.603627 -180.183488) (xy 383.558269 -180.151037) (xy 383.51812 -180.112328) (xy 383.484034 -180.068185)
			(xy 383.456738 -180.01955) (xy 383.436815 -179.967459) (xy 383.424689 -179.913022) (xy 383.420618 -179.8574)
			(xy 378.831661 -179.8574) (xy 378.83211 -179.883054) (xy 378.831602 -179.910306) (xy 378.823851 -179.964255)
			(xy 378.808501 -180.016552) (xy 378.785864 -180.066132) (xy 378.756401 -180.111985) (xy 378.720712 -180.153178)
			(xy 378.679523 -180.188872) (xy 378.633674 -180.218341) (xy 378.584097 -180.240984) (xy 378.531802 -180.256341)
			(xy 378.477854 -180.264098) (xy 378.450602 -180.264562) (xy 378.416312 -180.263038) (xy 378.406152 -180.262022)
			(xy 378.386848 -180.268118) (xy 378.316236 -180.3273) (xy 378.306838 -180.345334) (xy 378.305822 -180.355494)
			(xy 378.302902 -180.383671) (xy 378.289722 -180.438763) (xy 378.268538 -180.4913) (xy 378.239816 -180.540125)
			(xy 378.204187 -180.584165) (xy 378.162437 -180.622451) (xy 378.115483 -180.65414) (xy 378.064358 -180.678535)
			(xy 378.010187 -180.6951) (xy 377.954162 -180.703469) (xy 377.925838 -180.703982) (xy 377.907819 -180.703764)
			(xy 377.871944 -180.700328) (xy 377.85421 -180.697124) (xy 377.844812 -180.695346) (xy 377.825762 -180.699156)
			(xy 377.750578 -180.746908) (xy 377.739148 -180.762656) (xy 377.736862 -180.772054) (xy 377.72949 -180.799106)
			(xy 377.707858 -180.850833) (xy 377.67889 -180.898839) (xy 377.643212 -180.942091) (xy 377.601589 -180.979658)
			(xy 377.554918 -181.010731) (xy 377.504204 -181.034642) (xy 377.450537 -181.050876) (xy 377.395072 -181.059085)
			(xy 377.367038 -181.059582) (xy 377.339785 -181.059109) (xy 377.285833 -181.051357) (xy 377.233534 -181.036004)
			(xy 377.183952 -181.013364) (xy 377.138097 -180.983898) (xy 377.096904 -180.948205) (xy 377.061209 -180.907012)
			(xy 377.031741 -180.861159) (xy 377.0091 -180.811578) (xy 376.993746 -180.759279) (xy 376.985992 -180.705327)
			(xy 376.98553 -180.678074) (xy 372.327118 -180.678074) (xy 372.333289 -180.693797) (xy 372.345702 -180.748177)
			(xy 372.349871 -180.8038) (xy 372.345702 -180.859423) (xy 372.333289 -180.913803) (xy 372.312909 -180.965726)
			(xy 372.285017 -181.01403) (xy 372.250237 -181.057638) (xy 372.209346 -181.095574) (xy 372.163256 -181.126992)
			(xy 372.112999 -181.151189) (xy 372.059696 -181.167624) (xy 372.00454 -181.175931) (xy 371.97665 -181.176422)
			(xy 371.950227 -181.175988) (xy 371.897911 -181.168532) (xy 371.847172 -181.153761) (xy 371.799029 -181.131972)
			(xy 371.754445 -181.103602) (xy 371.73408 -181.08676) (xy 371.727222 -181.080664) (xy 371.710204 -181.074568)
			(xy 371.625876 -181.074568) (xy 371.608858 -181.080664) (xy 371.602 -181.08676) (xy 371.581634 -181.103599)
			(xy 371.537048 -181.131964) (xy 371.488904 -181.153751) (xy 371.438167 -181.168522) (xy 371.385852 -181.175982)
			(xy 371.333008 -181.175982) (xy 371.280693 -181.168522) (xy 371.229956 -181.153751) (xy 371.181812 -181.131964)
			(xy 371.137226 -181.103599) (xy 371.11686 -181.08676) (xy 371.110002 -181.080664) (xy 371.092984 -181.074568)
			(xy 371.008656 -181.074568) (xy 370.991638 -181.080664) (xy 370.98478 -181.08676) (xy 370.970662 -181.098517)
			(xy 370.94051 -181.119513) (xy 370.924582 -181.12867) (xy 370.916454 -181.133242) (xy 370.904516 -181.147466)
			(xy 370.876576 -181.229508) (xy 370.877084 -181.24805) (xy 370.880894 -181.25694) (xy 370.89036 -181.280513)
			(xy 370.903704 -181.329528) (xy 370.910443 -181.379877) (xy 370.910866 -181.405276) (xy 370.910396 -181.432851)
			(xy 370.902446 -181.487424) (xy 370.886722 -181.540284) (xy 370.863553 -181.59033) (xy 370.833421 -181.63652)
			(xy 370.796953 -181.677891) (xy 370.776246 -181.696106) (xy 370.768121 -181.703702) (xy 370.758773 -181.723859)
			(xy 370.758238 -181.73446) (xy 375.976642 -181.73446) (xy 375.977123 -181.706549) (xy 375.985262 -181.651323)
			(xy 376.001361 -181.597873) (xy 376.025076 -181.547338) (xy 376.055901 -181.500798) (xy 376.074178 -181.479698)
			(xy 376.080528 -181.472586) (xy 376.087132 -181.455314) (xy 376.087132 -181.368192) (xy 376.080528 -181.35092)
			(xy 376.074178 -181.343808) (xy 376.055879 -181.322726) (xy 376.025055 -181.276182) (xy 376.001344 -181.225643)
			(xy 375.985253 -181.172188) (xy 375.977124 -181.116958) (xy 375.976642 -181.089046) (xy 375.977128 -181.061795)
			(xy 375.984884 -181.007847) (xy 376.000239 -180.955552) (xy 376.022881 -180.905975) (xy 376.052347 -180.860125)
			(xy 376.088038 -180.818934) (xy 376.129229 -180.783243) (xy 376.175079 -180.753777) (xy 376.224656 -180.731135)
			(xy 376.276951 -180.71578) (xy 376.330899 -180.708024) (xy 376.385401 -180.708024) (xy 376.439349 -180.71578)
			(xy 376.491644 -180.731135) (xy 376.541221 -180.753777) (xy 376.587071 -180.783243) (xy 376.628262 -180.818934)
			(xy 376.663953 -180.860125) (xy 376.693419 -180.905975) (xy 376.716061 -180.955552) (xy 376.731416 -181.007847)
			(xy 376.739172 -181.061795) (xy 376.739658 -181.089046) (xy 376.739181 -181.116957) (xy 376.731041 -181.172183)
			(xy 376.714941 -181.225634) (xy 376.691225 -181.276168) (xy 376.660399 -181.322708) (xy 376.642122 -181.343808)
			(xy 376.635772 -181.35092) (xy 376.629168 -181.368192) (xy 376.629168 -181.455314) (xy 376.635772 -181.472586)
			(xy 376.642122 -181.479698) (xy 376.660377 -181.500817) (xy 376.691207 -181.54735) (xy 376.714926 -181.59788)
			(xy 376.731028 -181.651327) (xy 376.739169 -181.70655) (xy 376.739658 -181.73446) (xy 376.739172 -181.761711)
			(xy 376.731416 -181.815659) (xy 376.716061 -181.867954) (xy 376.693419 -181.917531) (xy 376.663953 -181.963381)
			(xy 376.628262 -182.004572) (xy 376.587071 -182.040263) (xy 376.541221 -182.069729) (xy 376.491644 -182.092371)
			(xy 376.439349 -182.107726) (xy 376.385401 -182.115482) (xy 376.330899 -182.115482) (xy 376.276951 -182.107726)
			(xy 376.224656 -182.092371) (xy 376.175079 -182.069729) (xy 376.129229 -182.040263) (xy 376.088038 -182.004572)
			(xy 376.052347 -181.963381) (xy 376.022881 -181.917531) (xy 376.000239 -181.867954) (xy 375.984884 -181.815659)
			(xy 375.977128 -181.761711) (xy 375.976642 -181.73446) (xy 370.758238 -181.73446) (xy 370.758212 -181.734968)
			(xy 370.758212 -181.812184) (xy 370.758769 -181.823295) (xy 370.768115 -181.843454) (xy 370.776246 -181.851046)
			(xy 370.796943 -181.869272) (xy 370.833413 -181.910639) (xy 370.863546 -181.956826) (xy 370.886713 -182.006871)
			(xy 370.902433 -182.05973) (xy 370.910378 -182.114302) (xy 370.910866 -182.141876) (xy 370.91038 -182.169127)
			(xy 370.902624 -182.223075) (xy 370.900363 -182.230776) (xy 378.653548 -182.230776) (xy 378.654049 -182.203203)
			(xy 378.661992 -182.148631) (xy 378.677709 -182.095771) (xy 378.700872 -182.045724) (xy 378.730999 -181.999534)
			(xy 378.767463 -181.958162) (xy 378.788168 -181.939946) (xy 378.796272 -181.932331) (xy 378.805632 -181.912189)
			(xy 378.806202 -181.901084) (xy 378.806202 -181.823868) (xy 378.805667 -181.812754) (xy 378.796305 -181.792596)
			(xy 378.788168 -181.785006) (xy 378.76745 -181.766802) (xy 378.730982 -181.725431) (xy 378.700851 -181.679239)
			(xy 378.677687 -181.62919) (xy 378.661972 -181.576327) (xy 378.654033 -181.521751) (xy 378.653548 -181.494176)
			(xy 378.654063 -181.465222) (xy 378.662824 -181.40798) (xy 378.680128 -181.352717) (xy 378.705578 -181.3007)
			(xy 378.738589 -181.253122) (xy 378.778405 -181.211074) (xy 378.824113 -181.175519) (xy 378.849128 -181.160928)
			(xy 378.859542 -181.15534) (xy 378.87275 -181.136544) (xy 378.889514 -181.035198) (xy 378.883164 -181.0131)
			(xy 378.87529 -181.004464) (xy 378.857463 -180.983825) (xy 378.827355 -180.938354) (xy 378.804192 -180.888983)
			(xy 378.788467 -180.836764) (xy 378.780517 -180.782811) (xy 378.78004 -180.755544) (xy 378.780575 -180.728929)
			(xy 378.788144 -180.676241) (xy 378.803135 -180.625165) (xy 378.825241 -180.576743) (xy 378.854014 -180.531961)
			(xy 378.888867 -180.491728) (xy 378.929092 -180.456866) (xy 378.973868 -180.428083) (xy 379.022285 -180.405965)
			(xy 379.073356 -180.390962) (xy 379.126043 -180.383381) (xy 379.152658 -180.382926) (xy 379.17908 -180.383368)
			(xy 379.231396 -180.390824) (xy 379.282134 -180.405594) (xy 379.330278 -180.427381) (xy 379.374862 -180.455748)
			(xy 379.395228 -180.472588) (xy 379.402086 -180.478684) (xy 379.419104 -180.48478) (xy 379.503432 -180.48478)
			(xy 379.52045 -180.478684) (xy 379.527308 -180.472588) (xy 379.547674 -180.455749) (xy 379.59226 -180.427384)
			(xy 379.640404 -180.405597) (xy 379.691141 -180.390826) (xy 379.743456 -180.383366) (xy 379.7963 -180.383366)
			(xy 379.848615 -180.390826) (xy 379.899352 -180.405597) (xy 379.947496 -180.427384) (xy 379.992082 -180.455749)
			(xy 380.012448 -180.472588) (xy 380.019306 -180.478684) (xy 380.036324 -180.48478) (xy 380.120652 -180.48478)
			(xy 380.13767 -180.478684) (xy 380.144528 -180.472588) (xy 380.164882 -180.455735) (xy 380.209475 -180.427383)
			(xy 380.257623 -180.405606) (xy 380.308362 -180.390842) (xy 380.360676 -180.383385) (xy 380.387098 -180.382926)
			(xy 380.414988 -180.383333) (xy 380.470145 -180.391646) (xy 380.523448 -180.408088) (xy 380.573704 -180.43229)
			(xy 380.619792 -180.463712) (xy 380.660682 -180.501652) (xy 380.695461 -180.545262) (xy 380.723351 -180.59357)
			(xy 380.74373 -180.645494) (xy 380.751166 -180.678074) (xy 385.31673 -180.678074) (xy 385.317236 -180.650501)
			(xy 385.325179 -180.595929) (xy 385.340895 -180.54307) (xy 385.364058 -180.493023) (xy 385.394184 -180.446833)
			(xy 385.430645 -180.40546) (xy 385.45135 -180.387244) (xy 385.459452 -180.379627) (xy 385.468813 -180.359486)
			(xy 385.469384 -180.348382) (xy 385.469384 -180.271166) (xy 385.468856 -180.260051) (xy 385.45949 -180.239893)
			(xy 385.45135 -180.232304) (xy 385.430616 -180.214118) (xy 385.394148 -180.172745) (xy 385.364018 -180.126551)
			(xy 385.340854 -180.0765) (xy 385.325138 -180.023636) (xy 385.317199 -179.969059) (xy 385.317201 -179.913908)
			(xy 385.325145 -179.859331) (xy 385.340866 -179.806468) (xy 385.364034 -179.756419) (xy 385.394169 -179.710229)
			(xy 385.43064 -179.668858) (xy 385.45135 -179.650644) (xy 385.459452 -179.643027) (xy 385.468813 -179.622886)
			(xy 385.469384 -179.611782) (xy 385.469384 -179.534566) (xy 385.468856 -179.523451) (xy 385.45949 -179.503293)
			(xy 385.45135 -179.495704) (xy 385.430628 -179.477505) (xy 385.39416 -179.436133) (xy 385.364031 -179.38994)
			(xy 385.340867 -179.33989) (xy 385.325153 -179.287025) (xy 385.317215 -179.232449) (xy 385.31673 -179.204874)
			(xy 385.317131 -179.177619) (xy 385.324892 -179.123664) (xy 385.340254 -179.071362) (xy 385.362902 -179.021779)
			(xy 385.392376 -178.975924) (xy 385.428076 -178.934731) (xy 385.469276 -178.899038) (xy 385.515136 -178.869571)
			(xy 385.564722 -178.846931) (xy 385.617026 -178.831579) (xy 385.670983 -178.823826) (xy 385.698238 -178.823366)
			(xy 385.726093 -178.82388) (xy 385.781208 -178.832008) (xy 385.834557 -178.848057) (xy 385.885009 -178.871686)
			(xy 385.931492 -178.902394) (xy 385.973021 -178.93953) (xy 386.008714 -178.982305) (xy 386.037815 -179.029811)
			(xy 386.059705 -179.081041) (xy 386.0673 -179.107846) (xy 386.069586 -179.116736) (xy 386.080254 -179.131976)
			(xy 386.152136 -179.179728) (xy 386.17017 -179.183792) (xy 386.179314 -179.182522) (xy 386.192331 -179.180854)
			(xy 386.218515 -179.179073) (xy 386.231638 -179.178966) (xy 386.245787 -179.179056) (xy 386.27401 -179.181093)
			(xy 386.288026 -179.18303) (xy 386.298186 -179.184554) (xy 386.317744 -179.179728) (xy 386.392166 -179.123848)
			(xy 386.402326 -179.106322) (xy 386.403596 -179.096162) (xy 386.407677 -179.069007) (xy 386.42265 -179.016176)
			(xy 386.445041 -178.966037) (xy 386.474389 -178.919625) (xy 386.510088 -178.877901) (xy 386.551398 -178.841724)
			(xy 386.597468 -178.811843) (xy 386.647346 -178.788875) (xy 386.700001 -178.773295) (xy 386.754346 -178.765423)
			(xy 386.781802 -178.764946) (xy 386.809051 -178.765476) (xy 386.862995 -178.773231) (xy 386.915286 -178.788584)
			(xy 386.96486 -178.811222) (xy 387.010708 -178.840685) (xy 387.051897 -178.876371) (xy 387.087589 -178.917556)
			(xy 387.117056 -178.963401) (xy 387.1397 -179.012973) (xy 387.155059 -179.065262) (xy 387.162821 -179.119205)
			(xy 387.16331 -179.146454) (xy 387.162809 -179.174027) (xy 387.154863 -179.228598) (xy 387.139145 -179.281457)
			(xy 387.115982 -179.331503) (xy 387.085855 -179.377694) (xy 387.049394 -179.419067) (xy 387.02869 -179.437284)
			(xy 387.020582 -179.444896) (xy 387.011222 -179.46504) (xy 387.010656 -179.476146) (xy 387.010656 -179.553362)
			(xy 387.011211 -179.564474) (xy 387.020557 -179.584634) (xy 387.02869 -179.592224) (xy 387.049414 -179.610421)
			(xy 387.085884 -179.651793) (xy 387.116014 -179.697985) (xy 387.139178 -179.748036) (xy 387.154892 -179.800901)
			(xy 387.162827 -179.855478) (xy 387.162861 -179.8574) (xy 391.751818 -179.8574) (xy 391.755889 -179.801778)
			(xy 391.768015 -179.747341) (xy 391.787938 -179.69525) (xy 391.815234 -179.646615) (xy 391.84932 -179.602472)
			(xy 391.889469 -179.563763) (xy 391.934827 -179.531312) (xy 391.984427 -179.505811) (xy 392.037211 -179.487804)
			(xy 392.092054 -179.477674) (xy 392.147788 -179.475637) (xy 392.203225 -179.481737) (xy 392.257182 -179.495843)
			(xy 392.308511 -179.517655) (xy 392.356117 -179.546709) (xy 392.398985 -179.582384) (xy 392.436202 -179.623921)
			(xy 392.466975 -179.670434) (xy 392.490647 -179.720931) (xy 392.506715 -179.774338) (xy 392.514835 -179.829514)
			(xy 392.515344 -179.8574) (xy 392.514835 -179.885286) (xy 392.506715 -179.940462) (xy 392.490647 -179.993869)
			(xy 392.466975 -180.044366) (xy 392.436202 -180.090879) (xy 392.398985 -180.132416) (xy 392.356117 -180.168091)
			(xy 392.308511 -180.197145) (xy 392.257182 -180.218957) (xy 392.203225 -180.233063) (xy 392.147788 -180.239163)
			(xy 392.092054 -180.237126) (xy 392.037211 -180.226996) (xy 391.984427 -180.208989) (xy 391.934827 -180.183488)
			(xy 391.889469 -180.151037) (xy 391.84932 -180.112328) (xy 391.815234 -180.068185) (xy 391.787938 -180.01955)
			(xy 391.768015 -179.967459) (xy 391.755889 -179.913022) (xy 391.751818 -179.8574) (xy 387.162861 -179.8574)
			(xy 387.16331 -179.883054) (xy 387.162802 -179.910306) (xy 387.155051 -179.964255) (xy 387.139701 -180.016552)
			(xy 387.117064 -180.066132) (xy 387.087601 -180.111985) (xy 387.051912 -180.153178) (xy 387.010723 -180.188872)
			(xy 386.964874 -180.218341) (xy 386.915297 -180.240984) (xy 386.863002 -180.256341) (xy 386.809054 -180.264098)
			(xy 386.781802 -180.264562) (xy 386.747512 -180.263038) (xy 386.737352 -180.262022) (xy 386.718048 -180.268118)
			(xy 386.647436 -180.3273) (xy 386.638038 -180.345334) (xy 386.637022 -180.355494) (xy 386.634102 -180.383671)
			(xy 386.620922 -180.438763) (xy 386.599738 -180.4913) (xy 386.571016 -180.540125) (xy 386.535387 -180.584165)
			(xy 386.493637 -180.622451) (xy 386.446683 -180.65414) (xy 386.395558 -180.678535) (xy 386.341387 -180.6951)
			(xy 386.285362 -180.703469) (xy 386.257038 -180.703982) (xy 386.239019 -180.703764) (xy 386.203144 -180.700328)
			(xy 386.18541 -180.697124) (xy 386.176012 -180.695346) (xy 386.156962 -180.699156) (xy 386.081778 -180.746908)
			(xy 386.070348 -180.762656) (xy 386.068062 -180.772054) (xy 386.06069 -180.799106) (xy 386.039058 -180.850833)
			(xy 386.01009 -180.898839) (xy 385.974412 -180.942091) (xy 385.932789 -180.979658) (xy 385.886118 -181.010731)
			(xy 385.835404 -181.034642) (xy 385.781737 -181.050876) (xy 385.726272 -181.059085) (xy 385.698238 -181.059582)
			(xy 385.670985 -181.059109) (xy 385.617033 -181.051357) (xy 385.564734 -181.036004) (xy 385.515152 -181.013364)
			(xy 385.469297 -180.983898) (xy 385.428104 -180.948205) (xy 385.392409 -180.907012) (xy 385.362941 -180.861159)
			(xy 385.3403 -180.811578) (xy 385.324946 -180.759279) (xy 385.317192 -180.705327) (xy 385.31673 -180.678074)
			(xy 380.751166 -180.678074) (xy 380.756142 -180.699876) (xy 380.760311 -180.7555) (xy 380.756142 -180.811124)
			(xy 380.74373 -180.865506) (xy 380.723351 -180.91743) (xy 380.695461 -180.965738) (xy 380.660682 -181.009348)
			(xy 380.619792 -181.047288) (xy 380.573704 -181.07871) (xy 380.523448 -181.102912) (xy 380.470145 -181.119354)
			(xy 380.414988 -181.127667) (xy 380.387098 -181.128162) (xy 380.360677 -181.127691) (xy 380.308363 -181.120242)
			(xy 380.257625 -181.105479) (xy 380.20948 -181.083699) (xy 380.164894 -181.055337) (xy 380.144528 -181.0385)
			(xy 380.13767 -181.032404) (xy 380.120652 -181.026308) (xy 380.036324 -181.026308) (xy 380.019306 -181.032404)
			(xy 380.012448 -181.0385) (xy 379.992082 -181.055339) (xy 379.947496 -181.083704) (xy 379.899352 -181.105491)
			(xy 379.848615 -181.120262) (xy 379.7963 -181.127722) (xy 379.743456 -181.127722) (xy 379.691141 -181.120262)
			(xy 379.640404 -181.105491) (xy 379.59226 -181.083704) (xy 379.547674 -181.055339) (xy 379.527308 -181.0385)
			(xy 379.52045 -181.032404) (xy 379.503432 -181.026308) (xy 379.419104 -181.026308) (xy 379.402086 -181.032404)
			(xy 379.395228 -181.0385) (xy 379.382014 -181.04952) (xy 379.353903 -181.069365) (xy 379.339094 -181.078124)
			(xy 379.328934 -181.08422) (xy 379.31598 -181.103016) (xy 379.300486 -181.204616) (xy 379.30709 -181.22646)
			(xy 379.315218 -181.235096) (xy 379.334155 -181.256385) (xy 379.366166 -181.303519) (xy 379.390819 -181.354885)
			(xy 379.407566 -181.409345) (xy 379.416035 -181.465688) (xy 379.416564 -181.494176) (xy 379.416094 -181.521751)
			(xy 379.408144 -181.576324) (xy 379.392421 -181.629184) (xy 379.369252 -181.67923) (xy 379.339119 -181.72542)
			(xy 379.33115 -181.73446) (xy 384.37947 -181.73446) (xy 384.379944 -181.706549) (xy 384.388084 -181.651322)
			(xy 384.404184 -181.597871) (xy 384.427901 -181.547337) (xy 384.458728 -181.500798) (xy 384.477006 -181.479698)
			(xy 384.483356 -181.472586) (xy 384.48996 -181.455314) (xy 384.48996 -181.368192) (xy 384.483356 -181.35092)
			(xy 384.477006 -181.343808) (xy 384.458711 -181.322722) (xy 384.427886 -181.27618) (xy 384.404174 -181.225642)
			(xy 384.388081 -181.172188) (xy 384.379952 -181.116958) (xy 384.37947 -181.089046) (xy 384.379956 -181.061795)
			(xy 384.387712 -181.007847) (xy 384.403067 -180.955552) (xy 384.425709 -180.905975) (xy 384.455175 -180.860125)
			(xy 384.490866 -180.818934) (xy 384.532057 -180.783243) (xy 384.577907 -180.753777) (xy 384.627484 -180.731135)
			(xy 384.679779 -180.71578) (xy 384.733727 -180.708024) (xy 384.788229 -180.708024) (xy 384.842177 -180.71578)
			(xy 384.894472 -180.731135) (xy 384.944049 -180.753777) (xy 384.989899 -180.783243) (xy 385.03109 -180.818934)
			(xy 385.066781 -180.860125) (xy 385.096247 -180.905975) (xy 385.118889 -180.955552) (xy 385.134244 -181.007847)
			(xy 385.142 -181.061795) (xy 385.142486 -181.089046) (xy 385.142002 -181.116957) (xy 385.133862 -181.172182)
			(xy 385.117764 -181.225632) (xy 385.09405 -181.276167) (xy 385.063226 -181.322707) (xy 385.04495 -181.343808)
			(xy 385.0386 -181.35092) (xy 385.031996 -181.368192) (xy 385.031996 -181.455314) (xy 385.0386 -181.472586)
			(xy 385.04495 -181.479698) (xy 385.063209 -181.500813) (xy 385.094038 -181.547348) (xy 385.117756 -181.597879)
			(xy 385.133857 -181.651326) (xy 385.141997 -181.70655) (xy 385.142486 -181.73446) (xy 385.142 -181.761711)
			(xy 385.134244 -181.815659) (xy 385.118889 -181.867954) (xy 385.096247 -181.917531) (xy 385.066781 -181.963381)
			(xy 385.03109 -182.004572) (xy 384.989899 -182.040263) (xy 384.944049 -182.069729) (xy 384.894472 -182.092371)
			(xy 384.842177 -182.107726) (xy 384.788229 -182.115482) (xy 384.733727 -182.115482) (xy 384.679779 -182.107726)
			(xy 384.627484 -182.092371) (xy 384.577907 -182.069729) (xy 384.532057 -182.040263) (xy 384.490866 -182.004572)
			(xy 384.455175 -181.963381) (xy 384.425709 -181.917531) (xy 384.403067 -181.867954) (xy 384.387712 -181.815659)
			(xy 384.379956 -181.761711) (xy 384.37947 -181.73446) (xy 379.33115 -181.73446) (xy 379.302651 -181.766791)
			(xy 379.281944 -181.785006) (xy 379.273819 -181.792602) (xy 379.264471 -181.812759) (xy 379.26391 -181.823868)
			(xy 379.26391 -181.901084) (xy 379.264468 -181.912195) (xy 379.273813 -181.932354) (xy 379.281944 -181.939946)
			(xy 379.302641 -181.958172) (xy 379.339111 -181.999539) (xy 379.369243 -182.045726) (xy 379.392411 -182.095771)
			(xy 379.408131 -182.14863) (xy 379.416076 -182.203202) (xy 379.416564 -182.230776) (xy 386.984748 -182.230776)
			(xy 386.985249 -182.203203) (xy 386.993192 -182.148631) (xy 387.008909 -182.095771) (xy 387.032072 -182.045724)
			(xy 387.062199 -181.999534) (xy 387.098663 -181.958162) (xy 387.119368 -181.939946) (xy 387.127472 -181.932331)
			(xy 387.136832 -181.912189) (xy 387.137402 -181.901084) (xy 387.137402 -181.823868) (xy 387.136867 -181.812754)
			(xy 387.127505 -181.792596) (xy 387.119368 -181.785006) (xy 387.09865 -181.766802) (xy 387.062182 -181.725431)
			(xy 387.032051 -181.679239) (xy 387.008887 -181.62919) (xy 386.993172 -181.576327) (xy 386.985233 -181.521751)
			(xy 386.984748 -181.494176) (xy 386.985263 -181.465222) (xy 386.994024 -181.40798) (xy 387.011328 -181.352717)
			(xy 387.036778 -181.3007) (xy 387.069789 -181.253122) (xy 387.109605 -181.211074) (xy 387.155313 -181.175519)
			(xy 387.180328 -181.160928) (xy 387.190742 -181.15534) (xy 387.20395 -181.136544) (xy 387.220714 -181.035198)
			(xy 387.214364 -181.0131) (xy 387.20649 -181.004464) (xy 387.188663 -180.983825) (xy 387.158555 -180.938354)
			(xy 387.135392 -180.888983) (xy 387.119667 -180.836764) (xy 387.111717 -180.782811) (xy 387.11124 -180.755544)
			(xy 387.111775 -180.728929) (xy 387.119344 -180.676241) (xy 387.134335 -180.625165) (xy 387.156441 -180.576743)
			(xy 387.185214 -180.531961) (xy 387.220067 -180.491728) (xy 387.260292 -180.456866) (xy 387.305068 -180.428083)
			(xy 387.353485 -180.405965) (xy 387.404556 -180.390962) (xy 387.457243 -180.383381) (xy 387.483858 -180.382926)
			(xy 387.51028 -180.383368) (xy 387.562596 -180.390824) (xy 387.613334 -180.405594) (xy 387.661478 -180.427381)
			(xy 387.706062 -180.455748) (xy 387.726428 -180.472588) (xy 387.733286 -180.478684) (xy 387.750304 -180.48478)
			(xy 387.834632 -180.48478) (xy 387.85165 -180.478684) (xy 387.858508 -180.472588) (xy 387.878874 -180.455749)
			(xy 387.92346 -180.427384) (xy 387.971604 -180.405597) (xy 388.022341 -180.390826) (xy 388.074656 -180.383366)
			(xy 388.1275 -180.383366) (xy 388.179815 -180.390826) (xy 388.230552 -180.405597) (xy 388.278696 -180.427384)
			(xy 388.323282 -180.455749) (xy 388.343648 -180.472588) (xy 388.350506 -180.478684) (xy 388.367524 -180.48478)
			(xy 388.451852 -180.48478) (xy 388.46887 -180.478684) (xy 388.475728 -180.472588) (xy 388.496082 -180.455735)
			(xy 388.540675 -180.427383) (xy 388.588823 -180.405606) (xy 388.639562 -180.390842) (xy 388.691876 -180.383385)
			(xy 388.718298 -180.382926) (xy 388.746188 -180.383333) (xy 388.801345 -180.391646) (xy 388.854648 -180.408088)
			(xy 388.904904 -180.43229) (xy 388.950992 -180.463712) (xy 388.991882 -180.501652) (xy 389.026661 -180.545262)
			(xy 389.054551 -180.59357) (xy 389.07493 -180.645494) (xy 389.087342 -180.699876) (xy 389.091511 -180.7555)
			(xy 389.087342 -180.811124) (xy 389.07493 -180.865506) (xy 389.054551 -180.91743) (xy 389.026661 -180.965738)
			(xy 388.991882 -181.009348) (xy 388.950992 -181.047288) (xy 388.904904 -181.07871) (xy 388.854648 -181.102912)
			(xy 388.801345 -181.119354) (xy 388.746188 -181.127667) (xy 388.718298 -181.128162) (xy 388.691877 -181.127691)
			(xy 388.639563 -181.120242) (xy 388.588825 -181.105479) (xy 388.54068 -181.083699) (xy 388.496094 -181.055337)
			(xy 388.475728 -181.0385) (xy 388.46887 -181.032404) (xy 388.451852 -181.026308) (xy 388.367524 -181.026308)
			(xy 388.350506 -181.032404) (xy 388.343648 -181.0385) (xy 388.323282 -181.055339) (xy 388.278696 -181.083704)
			(xy 388.230552 -181.105491) (xy 388.179815 -181.120262) (xy 388.1275 -181.127722) (xy 388.074656 -181.127722)
			(xy 388.022341 -181.120262) (xy 387.971604 -181.105491) (xy 387.92346 -181.083704) (xy 387.878874 -181.055339)
			(xy 387.858508 -181.0385) (xy 387.85165 -181.032404) (xy 387.834632 -181.026308) (xy 387.750304 -181.026308)
			(xy 387.733286 -181.032404) (xy 387.726428 -181.0385) (xy 387.713214 -181.04952) (xy 387.685103 -181.069365)
			(xy 387.670294 -181.078124) (xy 387.660134 -181.08422) (xy 387.64718 -181.103016) (xy 387.631686 -181.204616)
			(xy 387.63829 -181.22646) (xy 387.646418 -181.235096) (xy 387.665355 -181.256385) (xy 387.697366 -181.303519)
			(xy 387.722019 -181.354885) (xy 387.738766 -181.409345) (xy 387.747235 -181.465688) (xy 387.747764 -181.494176)
			(xy 387.747294 -181.521751) (xy 387.739344 -181.576324) (xy 387.723621 -181.629184) (xy 387.700452 -181.67923)
			(xy 387.670319 -181.72542) (xy 387.66235 -181.73446) (xy 392.71067 -181.73446) (xy 392.711144 -181.706549)
			(xy 392.719284 -181.651322) (xy 392.735384 -181.597871) (xy 392.759101 -181.547337) (xy 392.789928 -181.500798)
			(xy 392.808206 -181.479698) (xy 392.814556 -181.472586) (xy 392.82116 -181.455314) (xy 392.82116 -181.368192)
			(xy 392.814556 -181.35092) (xy 392.808206 -181.343808) (xy 392.789911 -181.322722) (xy 392.759086 -181.27618)
			(xy 392.735374 -181.225642) (xy 392.719281 -181.172188) (xy 392.711152 -181.116958) (xy 392.71067 -181.089046)
			(xy 392.711156 -181.061795) (xy 392.718912 -181.007847) (xy 392.734267 -180.955552) (xy 392.756909 -180.905975)
			(xy 392.786375 -180.860125) (xy 392.822066 -180.818934) (xy 392.863257 -180.783243) (xy 392.909107 -180.753777)
			(xy 392.958684 -180.731135) (xy 393.010979 -180.71578) (xy 393.064927 -180.708024) (xy 393.119429 -180.708024)
			(xy 393.173377 -180.71578) (xy 393.225672 -180.731135) (xy 393.275249 -180.753777) (xy 393.321099 -180.783243)
			(xy 393.36229 -180.818934) (xy 393.397981 -180.860125) (xy 393.427447 -180.905975) (xy 393.450089 -180.955552)
			(xy 393.465444 -181.007847) (xy 393.4732 -181.061795) (xy 393.473686 -181.089046) (xy 393.473202 -181.116957)
			(xy 393.465062 -181.172182) (xy 393.448964 -181.225632) (xy 393.42525 -181.276167) (xy 393.394426 -181.322707)
			(xy 393.37615 -181.343808) (xy 393.3698 -181.35092) (xy 393.363196 -181.368192) (xy 393.363196 -181.455314)
			(xy 393.3698 -181.472586) (xy 393.37615 -181.479698) (xy 393.394409 -181.500813) (xy 393.425238 -181.547348)
			(xy 393.448956 -181.597879) (xy 393.465057 -181.651326) (xy 393.473197 -181.70655) (xy 393.473686 -181.73446)
			(xy 393.4732 -181.761711) (xy 393.465444 -181.815659) (xy 393.450089 -181.867954) (xy 393.427447 -181.917531)
			(xy 393.397981 -181.963381) (xy 393.36229 -182.004572) (xy 393.321099 -182.040263) (xy 393.275249 -182.069729)
			(xy 393.225672 -182.092371) (xy 393.173377 -182.107726) (xy 393.119429 -182.115482) (xy 393.064927 -182.115482)
			(xy 393.010979 -182.107726) (xy 392.958684 -182.092371) (xy 392.909107 -182.069729) (xy 392.863257 -182.040263)
			(xy 392.822066 -182.004572) (xy 392.786375 -181.963381) (xy 392.756909 -181.917531) (xy 392.734267 -181.867954)
			(xy 392.718912 -181.815659) (xy 392.711156 -181.761711) (xy 392.71067 -181.73446) (xy 387.66235 -181.73446)
			(xy 387.633851 -181.766791) (xy 387.613144 -181.785006) (xy 387.605019 -181.792602) (xy 387.595671 -181.812759)
			(xy 387.59511 -181.823868) (xy 387.59511 -181.901084) (xy 387.595668 -181.912195) (xy 387.605013 -181.932354)
			(xy 387.613144 -181.939946) (xy 387.633841 -181.958172) (xy 387.670311 -181.999539) (xy 387.700443 -182.045726)
			(xy 387.723611 -182.095771) (xy 387.739331 -182.14863) (xy 387.747276 -182.203202) (xy 387.747764 -182.230776)
			(xy 387.747278 -182.258027) (xy 387.739522 -182.311975) (xy 387.724167 -182.36427) (xy 387.701525 -182.413847)
			(xy 387.672059 -182.459697) (xy 387.636368 -182.500888) (xy 387.595177 -182.536579) (xy 387.549327 -182.566045)
			(xy 387.49975 -182.588687) (xy 387.447455 -182.604042) (xy 387.393507 -182.611798) (xy 387.339005 -182.611798)
			(xy 387.285057 -182.604042) (xy 387.232762 -182.588687) (xy 387.183185 -182.566045) (xy 387.137335 -182.536579)
			(xy 387.096144 -182.500888) (xy 387.060453 -182.459697) (xy 387.030987 -182.413847) (xy 387.008345 -182.36427)
			(xy 386.99299 -182.311975) (xy 386.985234 -182.258027) (xy 386.984748 -182.230776) (xy 379.416564 -182.230776)
			(xy 379.416078 -182.258027) (xy 379.408322 -182.311975) (xy 379.392967 -182.36427) (xy 379.370325 -182.413847)
			(xy 379.340859 -182.459697) (xy 379.305168 -182.500888) (xy 379.263977 -182.536579) (xy 379.218127 -182.566045)
			(xy 379.16855 -182.588687) (xy 379.116255 -182.604042) (xy 379.062307 -182.611798) (xy 379.007805 -182.611798)
			(xy 378.953857 -182.604042) (xy 378.901562 -182.588687) (xy 378.851985 -182.566045) (xy 378.806135 -182.536579)
			(xy 378.764944 -182.500888) (xy 378.729253 -182.459697) (xy 378.699787 -182.413847) (xy 378.677145 -182.36427)
			(xy 378.66179 -182.311975) (xy 378.654034 -182.258027) (xy 378.653548 -182.230776) (xy 370.900363 -182.230776)
			(xy 370.887269 -182.27537) (xy 370.864627 -182.324947) (xy 370.835161 -182.370797) (xy 370.79947 -182.411988)
			(xy 370.758279 -182.447679) (xy 370.712429 -182.477145) (xy 370.662852 -182.499787) (xy 370.610557 -182.515142)
			(xy 370.556609 -182.522898) (xy 370.502107 -182.522898) (xy 370.448159 -182.515142) (xy 370.395864 -182.499787)
			(xy 370.346287 -182.477145) (xy 370.300437 -182.447679) (xy 370.259246 -182.411988) (xy 370.223555 -182.370797)
			(xy 370.194089 -182.324947) (xy 370.171447 -182.27537) (xy 370.156092 -182.223075) (xy 370.148336 -182.169127)
			(xy 370.14785 -182.141876) (xy 358.302842 -182.141876) (xy 358.295577 -182.192187) (xy 358.28008 -182.244691)
			(xy 358.25723 -182.294438) (xy 358.227496 -182.340402) (xy 358.20985 -182.361332) (xy 358.203754 -182.368444)
			(xy 358.197404 -182.385462) (xy 358.197404 -182.470806) (xy 358.203754 -182.487824) (xy 358.20985 -182.494936)
			(xy 358.227525 -182.515841) (xy 358.25725 -182.561813) (xy 358.280095 -182.611564) (xy 358.29559 -182.66407)
			(xy 358.303415 -182.718253) (xy 358.303412 -182.772998) (xy 358.295579 -182.82718) (xy 358.280077 -182.879684)
			(xy 358.257225 -182.929432) (xy 358.227494 -182.9754) (xy 358.20985 -182.996332) (xy 358.203754 -183.003444)
			(xy 358.197404 -183.020462) (xy 358.197404 -183.105806) (xy 358.203754 -183.122824) (xy 358.20985 -183.129936)
			(xy 358.227525 -183.150841) (xy 358.25725 -183.196813) (xy 358.280095 -183.246564) (xy 358.29559 -183.29907)
			(xy 358.303415 -183.353253) (xy 358.303412 -183.407998) (xy 358.295579 -183.46218) (xy 358.280077 -183.514684)
			(xy 358.257225 -183.564432) (xy 358.227494 -183.6104) (xy 358.20985 -183.631332) (xy 358.203754 -183.638444)
			(xy 358.197404 -183.655462) (xy 358.197404 -183.740806) (xy 358.203754 -183.757824) (xy 358.20985 -183.764936)
			(xy 358.227465 -183.785888) (xy 358.257182 -183.831854) (xy 358.280023 -183.881597) (xy 358.29552 -183.934093)
			(xy 358.303353 -183.988266) (xy 358.30383 -184.015634) (xy 358.303325 -184.043343) (xy 358.295298 -184.098177)
			(xy 358.279418 -184.151271) (xy 358.25602 -184.201507) (xy 358.225597 -184.247828) (xy 358.207564 -184.268872)
			(xy 358.201214 -184.276238) (xy 358.19461 -184.29351) (xy 358.195626 -184.380886) (xy 358.20223 -184.398158)
			(xy 358.208834 -184.40527) (xy 358.227749 -184.426502) (xy 358.259679 -184.473552) (xy 358.284265 -184.524824)
			(xy 358.300964 -184.579179) (xy 358.309403 -184.635411) (xy 358.309926 -184.663842) (xy 358.309444 -184.691212)
			(xy 358.301633 -184.745391) (xy 358.286148 -184.797895) (xy 358.26331 -184.847642) (xy 358.233587 -184.893609)
			(xy 358.215946 -184.91454) (xy 358.20985 -184.921652) (xy 358.2035 -184.93867) (xy 358.2035 -185.024014)
			(xy 358.20985 -185.041032) (xy 358.215946 -185.048144) (xy 358.233629 -185.069043) (xy 358.263354 -185.115016)
			(xy 358.286199 -185.164768) (xy 358.301693 -185.217275) (xy 358.309518 -185.271459) (xy 358.309514 -185.326205)
			(xy 358.301679 -185.380387) (xy 358.286176 -185.432892) (xy 358.263324 -185.48264) (xy 358.233591 -185.528608)
			(xy 358.215946 -185.54954) (xy 358.20985 -185.556652) (xy 358.2035 -185.57367) (xy 358.2035 -185.659014)
			(xy 358.20985 -185.676032) (xy 358.215946 -185.683144) (xy 358.233629 -185.704043) (xy 358.263354 -185.750016)
			(xy 358.286199 -185.799768) (xy 358.301693 -185.852275) (xy 358.309518 -185.906459) (xy 358.309514 -185.961205)
			(xy 358.301679 -186.015387) (xy 358.286176 -186.067892) (xy 358.263324 -186.11764) (xy 358.233591 -186.163608)
			(xy 358.215946 -186.18454) (xy 358.20985 -186.191652) (xy 358.2035 -186.20867) (xy 358.2035 -186.294014)
			(xy 358.20985 -186.311032) (xy 358.215946 -186.318144) (xy 358.233629 -186.339043) (xy 358.263354 -186.385016)
			(xy 358.286199 -186.434768) (xy 358.301693 -186.487275) (xy 358.309518 -186.541459) (xy 358.309514 -186.596205)
			(xy 358.301679 -186.650387) (xy 358.286176 -186.702892) (xy 358.263324 -186.75264) (xy 358.233591 -186.798608)
			(xy 358.215946 -186.81954) (xy 358.20985 -186.826652) (xy 358.2035 -186.84367) (xy 358.2035 -186.929014)
			(xy 358.20985 -186.946032) (xy 358.210721 -186.947048) (xy 404.034244 -186.947048) (xy 404.034727 -186.919678)
			(xy 404.042539 -186.8655) (xy 404.058024 -186.812996) (xy 404.080862 -186.763249) (xy 404.110584 -186.717282)
			(xy 404.128224 -186.69635) (xy 404.13432 -186.689238) (xy 404.14067 -186.67222) (xy 404.14067 -186.586876)
			(xy 404.13432 -186.569858) (xy 404.128224 -186.562746) (xy 404.11063 -186.541775) (xy 404.080904 -186.495814)
			(xy 404.058056 -186.446074) (xy 404.042556 -186.393578) (xy 404.034723 -186.339404) (xy 404.034718 -186.284668)
			(xy 404.042541 -186.230493) (xy 404.058031 -186.177994) (xy 404.080869 -186.12825) (xy 404.110587 -186.082283)
			(xy 404.128224 -186.06135) (xy 404.13432 -186.054238) (xy 404.14067 -186.03722) (xy 404.14067 -185.951876)
			(xy 404.13432 -185.934858) (xy 404.128224 -185.927746) (xy 404.11063 -185.906775) (xy 404.080904 -185.860814)
			(xy 404.058056 -185.811074) (xy 404.042556 -185.758578) (xy 404.034723 -185.704404) (xy 404.034718 -185.649668)
			(xy 404.042541 -185.595493) (xy 404.058031 -185.542994) (xy 404.080869 -185.49325) (xy 404.110587 -185.447283)
			(xy 404.128224 -185.42635) (xy 404.13432 -185.419238) (xy 404.14067 -185.40222) (xy 404.14067 -185.316876)
			(xy 404.13432 -185.299858) (xy 404.128224 -185.292746) (xy 404.11063 -185.271775) (xy 404.080904 -185.225814)
			(xy 404.058056 -185.176074) (xy 404.042556 -185.123578) (xy 404.034723 -185.069404) (xy 404.034718 -185.014668)
			(xy 404.042541 -184.960493) (xy 404.058031 -184.907994) (xy 404.080869 -184.85825) (xy 404.110587 -184.812283)
			(xy 404.128224 -184.79135) (xy 404.13432 -184.784238) (xy 404.14067 -184.76722) (xy 404.14067 -184.681876)
			(xy 404.13432 -184.664858) (xy 404.128224 -184.657746) (xy 404.11063 -184.636775) (xy 404.080904 -184.590814)
			(xy 404.058056 -184.541074) (xy 404.042556 -184.488578) (xy 404.034723 -184.434404) (xy 404.034718 -184.379668)
			(xy 404.042541 -184.325493) (xy 404.058031 -184.272994) (xy 404.080869 -184.22325) (xy 404.110587 -184.177283)
			(xy 404.128224 -184.15635) (xy 404.13432 -184.149238) (xy 404.14067 -184.13222) (xy 404.14067 -184.046876)
			(xy 404.13432 -184.029858) (xy 404.128224 -184.022746) (xy 404.110597 -184.001804) (xy 404.080882 -183.955835)
			(xy 404.058044 -183.90609) (xy 404.04255 -183.853591) (xy 404.034719 -183.799417) (xy 404.034244 -183.772048)
			(xy 404.034643 -183.746226) (xy 404.041601 -183.695052) (xy 404.055395 -183.645284) (xy 404.075773 -183.597831)
			(xy 404.102365 -183.553559) (xy 404.134683 -183.513276) (xy 404.153116 -183.495188) (xy 404.160482 -183.48833)
			(xy 404.168356 -183.471312) (xy 404.17369 -183.382412) (xy 404.167848 -183.364378) (xy 404.161498 -183.356758)
			(xy 404.144997 -183.336149) (xy 404.117263 -183.291225) (xy 404.095989 -183.242906) (xy 404.081579 -183.192116)
			(xy 404.07431 -183.139824) (xy 404.073868 -183.113426) (xy 404.074333 -183.086056) (xy 404.082148 -183.031876)
			(xy 404.097637 -182.979372) (xy 404.120479 -182.929625) (xy 404.150206 -182.883659) (xy 404.167848 -182.862728)
			(xy 404.173944 -182.855616) (xy 404.180294 -182.838598) (xy 404.180294 -182.753254) (xy 404.173944 -182.736236)
			(xy 404.167848 -182.729124) (xy 404.150232 -182.708171) (xy 404.120504 -182.662207) (xy 404.097656 -182.612464)
			(xy 404.082157 -182.559965) (xy 404.074326 -182.505789) (xy 404.074323 -182.45105) (xy 404.082149 -182.396873)
			(xy 404.097643 -182.344372) (xy 404.120486 -182.294627) (xy 404.150208 -182.24866) (xy 404.167848 -182.227728)
			(xy 404.173944 -182.220616) (xy 404.180294 -182.203598) (xy 404.180294 -182.118254) (xy 404.173944 -182.101236)
			(xy 404.167848 -182.094124) (xy 404.150232 -182.073171) (xy 404.120504 -182.027207) (xy 404.097656 -181.977464)
			(xy 404.082157 -181.924965) (xy 404.074326 -181.870789) (xy 404.074323 -181.81605) (xy 404.082149 -181.761873)
			(xy 404.097643 -181.709372) (xy 404.120486 -181.659627) (xy 404.150208 -181.61366) (xy 404.167848 -181.592728)
			(xy 404.173944 -181.585616) (xy 404.180294 -181.568598) (xy 404.180294 -181.483254) (xy 404.173944 -181.466236)
			(xy 404.167848 -181.459124) (xy 404.150214 -181.438188) (xy 404.1205 -181.392217) (xy 404.097662 -181.34247)
			(xy 404.08217 -181.28997) (xy 404.074342 -181.235795) (xy 404.073868 -181.208426) (xy 404.074379 -181.181175)
			(xy 404.082132 -181.127227) (xy 404.097484 -181.074931) (xy 404.120121 -181.025353) (xy 404.149585 -180.979501)
			(xy 404.185273 -180.938309) (xy 404.226461 -180.902615) (xy 404.272309 -180.873145) (xy 404.321885 -180.850501)
			(xy 404.374178 -180.835143) (xy 404.428125 -180.827383) (xy 404.455376 -180.826918) (xy 404.484853 -180.827468)
			(xy 404.543106 -180.836534) (xy 404.599271 -180.854454) (xy 404.65201 -180.880801) (xy 404.700069 -180.914948)
			(xy 404.721568 -180.935122) (xy 404.728916 -180.941639) (xy 404.747066 -180.949094) (xy 404.756874 -180.9496)
			(xy 404.810214 -180.9496) (xy 404.814278 -180.945028) (xy 404.820692 -180.937574) (xy 404.827887 -180.919294)
			(xy 404.828248 -180.909468) (xy 404.827994 -180.877718) (xy 404.827431 -180.867883) (xy 404.819867 -180.849718)
			(xy 404.813262 -180.842412) (xy 404.792587 -180.820843) (xy 404.757575 -180.772433) (xy 404.73054 -180.719156)
			(xy 404.712144 -180.662314) (xy 404.702839 -180.603298) (xy 404.702264 -180.573426) (xy 404.70275 -180.546175)
			(xy 404.710506 -180.492227) (xy 404.725861 -180.439932) (xy 404.748503 -180.390355) (xy 404.777969 -180.344505)
			(xy 404.81366 -180.303314) (xy 404.854851 -180.267623) (xy 404.900701 -180.238157) (xy 404.950278 -180.215515)
			(xy 405.002573 -180.20016) (xy 405.056521 -180.192404) (xy 405.111023 -180.192404) (xy 405.164971 -180.20016)
			(xy 405.217266 -180.215515) (xy 405.266843 -180.238157) (xy 405.312693 -180.267623) (xy 405.353884 -180.303314)
			(xy 405.389575 -180.344505) (xy 405.419041 -180.390355) (xy 405.441683 -180.439932) (xy 405.457038 -180.492227)
			(xy 405.464794 -180.546175) (xy 405.46528 -180.573426) (xy 405.464827 -180.600396) (xy 405.457217 -180.653797)
			(xy 405.442154 -180.705592) (xy 405.419938 -180.754745) (xy 405.391013 -180.800274) (xy 405.37384 -180.821076)
			(xy 405.367744 -180.828188) (xy 405.361648 -180.845206) (xy 405.36241 -180.930804) (xy 405.369014 -180.947568)
			(xy 405.375364 -180.95468) (xy 405.393471 -180.975739) (xy 405.423972 -181.022152) (xy 405.447429 -181.072495)
			(xy 405.463345 -181.125703) (xy 405.471387 -181.180657) (xy 405.471884 -181.208426) (xy 405.471437 -181.235797)
			(xy 405.463615 -181.289977) (xy 405.448122 -181.342481) (xy 405.425276 -181.392227) (xy 405.395547 -181.438193)
			(xy 405.377904 -181.459124) (xy 405.371808 -181.466236) (xy 405.365458 -181.483254) (xy 405.365458 -181.568598)
			(xy 405.371808 -181.585616) (xy 405.377904 -181.592728) (xy 405.395569 -181.613641) (xy 405.42529 -181.659613)
			(xy 405.448132 -181.709363) (xy 405.463625 -181.761867) (xy 405.471451 -181.816048) (xy 405.471448 -181.870791)
			(xy 405.463617 -181.924971) (xy 405.448118 -181.977474) (xy 405.425271 -182.027222) (xy 405.395545 -182.073191)
			(xy 405.377904 -182.094124) (xy 405.371808 -182.101236) (xy 405.365458 -182.118254) (xy 405.365458 -182.203598)
			(xy 405.371808 -182.220616) (xy 405.377904 -182.227728) (xy 405.395569 -182.248641) (xy 405.42529 -182.294613)
			(xy 405.448132 -182.344363) (xy 405.463625 -182.396867) (xy 405.471451 -182.451048) (xy 405.471448 -182.505791)
			(xy 405.463617 -182.559971) (xy 405.448118 -182.612474) (xy 405.425271 -182.662222) (xy 405.395545 -182.708191)
			(xy 405.377904 -182.729124) (xy 405.371808 -182.736236) (xy 405.365458 -182.753254) (xy 405.365458 -182.838598)
			(xy 405.371808 -182.855616) (xy 405.377904 -182.862728) (xy 405.395523 -182.883676) (xy 405.425238 -182.929644)
			(xy 405.448078 -182.979388) (xy 405.463573 -183.031885) (xy 405.471407 -183.086058) (xy 405.471884 -183.113426)
			(xy 405.47149 -183.139249) (xy 405.464535 -183.190423) (xy 405.450741 -183.240192) (xy 405.430361 -183.287646)
			(xy 405.403768 -183.331918) (xy 405.371447 -183.372199) (xy 405.353012 -183.390286) (xy 405.345646 -183.397144)
			(xy 405.337772 -183.414162) (xy 405.332438 -183.503062) (xy 405.33828 -183.521096) (xy 405.34463 -183.528716)
			(xy 405.361123 -183.549331) (xy 405.388857 -183.594254) (xy 405.410133 -183.642571) (xy 405.424544 -183.69336)
			(xy 405.431816 -183.745651) (xy 405.43226 -183.772048) (xy 405.431773 -183.799418) (xy 405.423962 -183.853596)
			(xy 405.408478 -183.906099) (xy 405.385641 -183.955847) (xy 405.35592 -184.001814) (xy 405.33828 -184.022746)
			(xy 405.332184 -184.029858) (xy 405.325834 -184.046876) (xy 405.325834 -184.13222) (xy 405.332184 -184.149238)
			(xy 405.33828 -184.15635) (xy 405.355967 -184.177245) (xy 405.38569 -184.223219) (xy 405.408532 -184.272972)
			(xy 405.424024 -184.32548) (xy 405.431848 -184.379663) (xy 405.431843 -184.434409) (xy 405.424009 -184.488591)
			(xy 405.408506 -184.541096) (xy 405.385655 -184.590844) (xy 405.355924 -184.636813) (xy 405.33828 -184.657746)
			(xy 405.332184 -184.664858) (xy 405.325834 -184.681876) (xy 405.325834 -184.76722) (xy 405.332184 -184.784238)
			(xy 405.33828 -184.79135) (xy 405.355967 -184.812245) (xy 405.38569 -184.858219) (xy 405.408532 -184.907972)
			(xy 405.424024 -184.96048) (xy 405.431848 -185.014663) (xy 405.431845 -185.042048) (xy 407.445464 -185.042048)
			(xy 407.445943 -185.014678) (xy 407.453755 -184.960499) (xy 407.46924 -184.907995) (xy 407.49208 -184.858248)
			(xy 407.521803 -184.812281) (xy 407.539444 -184.79135) (xy 407.54554 -184.784238) (xy 407.55189 -184.76722)
			(xy 407.55189 -184.681876) (xy 407.54554 -184.664858) (xy 407.539444 -184.657746) (xy 407.52185 -184.636776)
			(xy 407.492122 -184.590815) (xy 407.469272 -184.541075) (xy 407.453772 -184.488578) (xy 407.445938 -184.434405)
			(xy 407.445933 -184.379668) (xy 407.453756 -184.325492) (xy 407.469247 -184.272993) (xy 407.492087 -184.223249)
			(xy 407.521806 -184.177282) (xy 407.539444 -184.15635) (xy 407.54554 -184.149238) (xy 407.55189 -184.13222)
			(xy 407.55189 -184.046876) (xy 407.54554 -184.029858) (xy 407.539444 -184.022746) (xy 407.52182 -184.001802)
			(xy 407.492104 -183.955833) (xy 407.469265 -183.906089) (xy 407.45377 -183.85359) (xy 407.445939 -183.799416)
			(xy 407.445464 -183.772048) (xy 407.446035 -183.743037) (xy 407.454796 -183.685682) (xy 407.472139 -183.630313)
			(xy 407.497665 -183.578209) (xy 407.530784 -183.530569) (xy 407.550366 -183.509158) (xy 407.557224 -183.502046)
			(xy 407.564336 -183.48452) (xy 407.565352 -183.39562) (xy 407.558494 -183.37784) (xy 407.55189 -183.370728)
			(xy 407.533224 -183.349514) (xy 407.501686 -183.30263) (xy 407.477407 -183.251608) (xy 407.460918 -183.197564)
			(xy 407.452581 -183.141678) (xy 407.452068 -183.113426) (xy 407.452533 -183.086056) (xy 407.460348 -183.031876)
			(xy 407.475837 -182.979372) (xy 407.498679 -182.929625) (xy 407.528406 -182.883659) (xy 407.546048 -182.862728)
			(xy 407.552144 -182.855616) (xy 407.558494 -182.838598) (xy 407.558494 -182.753254) (xy 407.552144 -182.736236)
			(xy 407.546048 -182.729124) (xy 407.528432 -182.708171) (xy 407.498704 -182.662207) (xy 407.475856 -182.612464)
			(xy 407.460357 -182.559965) (xy 407.452526 -182.505789) (xy 407.452523 -182.45105) (xy 407.460349 -182.396873)
			(xy 407.475843 -182.344372) (xy 407.498686 -182.294627) (xy 407.528408 -182.24866) (xy 407.546048 -182.227728)
			(xy 407.552144 -182.220616) (xy 407.558494 -182.203598) (xy 407.558494 -182.118254) (xy 407.552144 -182.101236)
			(xy 407.546048 -182.094124) (xy 407.528432 -182.073171) (xy 407.498704 -182.027207) (xy 407.475856 -181.977464)
			(xy 407.460357 -181.924965) (xy 407.452526 -181.870789) (xy 407.452523 -181.81605) (xy 407.460349 -181.761873)
			(xy 407.475843 -181.709372) (xy 407.498686 -181.659627) (xy 407.528408 -181.61366) (xy 407.546048 -181.592728)
			(xy 407.552144 -181.585616) (xy 407.558494 -181.568598) (xy 407.558494 -181.483254) (xy 407.552144 -181.466236)
			(xy 407.546048 -181.459124) (xy 407.528414 -181.438188) (xy 407.4987 -181.392217) (xy 407.475862 -181.34247)
			(xy 407.46037 -181.28997) (xy 407.452542 -181.235795) (xy 407.452068 -181.208426) (xy 407.452518 -181.181291)
			(xy 407.460212 -181.127569) (xy 407.475448 -181.075482) (xy 407.497918 -181.026083) (xy 407.527168 -180.98037)
			(xy 407.544524 -180.959506) (xy 407.55062 -180.952394) (xy 407.556716 -180.935376) (xy 407.556208 -180.850032)
			(xy 407.549858 -180.833014) (xy 407.543508 -180.825902) (xy 407.52563 -180.804865) (xy 407.495432 -180.758651)
			(xy 407.472213 -180.708566) (xy 407.456458 -180.655657) (xy 407.448495 -180.601029) (xy 407.448004 -180.573426)
			(xy 407.44848 -180.546173) (xy 407.456233 -180.492222) (xy 407.471587 -180.439924) (xy 407.494227 -180.390343)
			(xy 407.523693 -180.344489) (xy 407.559386 -180.303296) (xy 407.600578 -180.267602) (xy 407.646431 -180.238134)
			(xy 407.696011 -180.215492) (xy 407.748308 -180.200136) (xy 407.802259 -180.192381) (xy 407.829512 -180.191918)
			(xy 407.856883 -180.192373) (xy 407.911062 -180.200193) (xy 407.963566 -180.215684) (xy 408.013313 -180.238528)
			(xy 408.059279 -180.268256) (xy 408.08021 -180.285898) (xy 408.087322 -180.291994) (xy 408.10434 -180.298344)
			(xy 408.189684 -180.298344) (xy 408.206702 -180.291994) (xy 408.213814 -180.285898) (xy 408.234747 -180.268257)
			(xy 408.280715 -180.238533) (xy 408.330461 -180.215687) (xy 408.382963 -180.200191) (xy 408.437141 -180.192362)
			(xy 408.491883 -180.192362) (xy 408.546061 -180.200191) (xy 408.598563 -180.215687) (xy 408.648309 -180.238533)
			(xy 408.694277 -180.268257) (xy 408.71521 -180.285898) (xy 408.722322 -180.291994) (xy 408.73934 -180.298344)
			(xy 408.824684 -180.298344) (xy 408.841702 -180.291994) (xy 408.848814 -180.285898) (xy 408.869767 -180.268285)
			(xy 408.915734 -180.23857) (xy 408.965476 -180.215729) (xy 409.017972 -180.200231) (xy 409.072144 -180.192396)
			(xy 409.099512 -180.191918) (xy 409.126766 -180.192344) (xy 409.18072 -180.200103) (xy 409.23302 -180.215462)
			(xy 409.282602 -180.238108) (xy 409.328457 -180.267579) (xy 409.36965 -180.303277) (xy 409.405343 -180.344474)
			(xy 409.43481 -180.390331) (xy 409.457451 -180.439915) (xy 409.472805 -180.492217) (xy 409.480559 -180.546172)
			(xy 409.48102 -180.573426) (xy 409.480529 -180.600759) (xy 409.472725 -180.654865) (xy 409.45728 -180.707303)
			(xy 409.43451 -180.757001) (xy 409.404881 -180.802942) (xy 409.387294 -180.82387) (xy 409.38069 -180.831236)
			(xy 409.374594 -180.84927) (xy 409.374655 -180.851048) (xy 412.39821 -180.851048) (xy 412.398702 -180.823679)
			(xy 412.406513 -180.769501) (xy 412.421996 -180.716998) (xy 412.444832 -180.66725) (xy 412.474551 -180.621282)
			(xy 412.49219 -180.60035) (xy 412.498286 -180.593238) (xy 412.504636 -180.57622) (xy 412.504636 -180.490876)
			(xy 412.498286 -180.473858) (xy 412.49219 -180.466746) (xy 412.474598 -180.445774) (xy 412.444874 -180.399812)
			(xy 412.422028 -180.350072) (xy 412.40653 -180.297577) (xy 412.398697 -180.243404) (xy 412.398692 -180.188668)
			(xy 412.406514 -180.134494) (xy 412.422003 -180.081995) (xy 412.444839 -180.032251) (xy 412.474554 -179.986283)
			(xy 412.49219 -179.96535) (xy 412.498286 -179.958238) (xy 412.504636 -179.94122) (xy 412.504636 -179.855876)
			(xy 412.498286 -179.838858) (xy 412.49219 -179.831746) (xy 412.474598 -179.810774) (xy 412.444874 -179.764812)
			(xy 412.422028 -179.715072) (xy 412.40653 -179.662577) (xy 412.398697 -179.608404) (xy 412.398692 -179.553668)
			(xy 412.406514 -179.499494) (xy 412.422003 -179.446995) (xy 412.444839 -179.397251) (xy 412.474554 -179.351283)
			(xy 412.49219 -179.33035) (xy 412.498286 -179.323238) (xy 412.504636 -179.30622) (xy 412.504636 -179.220876)
			(xy 412.498286 -179.203858) (xy 412.49219 -179.196746) (xy 412.474557 -179.175809) (xy 412.444845 -179.129837)
			(xy 412.422008 -179.080091) (xy 412.406515 -179.027592) (xy 412.398685 -178.973417) (xy 412.39821 -178.946048)
			(xy 412.398768 -178.917037) (xy 412.407531 -178.85968) (xy 412.424876 -178.804311) (xy 412.450405 -178.752207)
			(xy 412.483528 -178.704568) (xy 412.503112 -178.683158) (xy 412.50997 -178.676046) (xy 412.517082 -178.65852)
			(xy 412.518098 -178.56962) (xy 412.51124 -178.55184) (xy 412.504636 -178.544728) (xy 412.485962 -178.523521)
			(xy 412.454426 -178.476635) (xy 412.43015 -178.425611) (xy 412.413663 -178.371565) (xy 412.405327 -178.315678)
			(xy 412.404814 -178.287426) (xy 412.405292 -178.260056) (xy 412.413106 -178.205877) (xy 412.428592 -178.153374)
			(xy 412.451432 -178.103627) (xy 412.481154 -178.05766) (xy 412.498794 -178.036728) (xy 412.50489 -178.029616)
			(xy 412.51124 -178.012598) (xy 412.51124 -177.927254) (xy 412.50489 -177.910236) (xy 412.498794 -177.903124)
			(xy 412.48118 -177.88217) (xy 412.451457 -177.836205) (xy 412.428612 -177.786462) (xy 412.413115 -177.733964)
			(xy 412.405285 -177.679789) (xy 412.405282 -177.625051) (xy 412.413107 -177.570875) (xy 412.428598 -177.518375)
			(xy 412.451438 -177.468629) (xy 412.481157 -177.422661) (xy 412.498794 -177.401728) (xy 412.50489 -177.394616)
			(xy 412.51124 -177.377598) (xy 412.51124 -177.292254) (xy 412.50489 -177.275236) (xy 412.498794 -177.268124)
			(xy 412.48118 -177.24717) (xy 412.451457 -177.201205) (xy 412.428612 -177.151462) (xy 412.413115 -177.098964)
			(xy 412.405285 -177.044789) (xy 412.405282 -176.990051) (xy 412.413107 -176.935875) (xy 412.428598 -176.883375)
			(xy 412.451438 -176.833629) (xy 412.481157 -176.787661) (xy 412.498794 -176.766728) (xy 412.50489 -176.759616)
			(xy 412.51124 -176.742598) (xy 412.51124 -176.657254) (xy 412.50489 -176.640236) (xy 412.498794 -176.633124)
			(xy 412.481152 -176.612194) (xy 412.451441 -176.566221) (xy 412.428605 -176.516473) (xy 412.413115 -176.463972)
			(xy 412.405288 -176.409795) (xy 412.404814 -176.382426) (xy 412.405298 -176.355457) (xy 412.412901 -176.302057)
			(xy 412.427957 -176.250263) (xy 412.450166 -176.20111) (xy 412.479085 -176.155579) (xy 412.496254 -176.134776)
			(xy 412.50235 -176.127664) (xy 412.508446 -176.110646) (xy 412.507684 -176.025048) (xy 412.50108 -176.008284)
			(xy 412.49473 -176.001172) (xy 412.476663 -175.98008) (xy 412.446152 -175.933677) (xy 412.422686 -175.883344)
			(xy 412.406761 -175.830142) (xy 412.398711 -175.775193) (xy 412.39821 -175.747426) (xy 412.39868 -175.720173)
			(xy 412.406433 -175.666221) (xy 412.421787 -175.613922) (xy 412.444428 -175.564341) (xy 412.473895 -175.518487)
			(xy 412.509588 -175.477294) (xy 412.550781 -175.4416) (xy 412.596634 -175.412132) (xy 412.646215 -175.38949)
			(xy 412.698514 -175.374135) (xy 412.752465 -175.36638) (xy 412.779718 -175.365918) (xy 412.807089 -175.366369)
			(xy 412.861269 -175.37419) (xy 412.913772 -175.389682) (xy 412.963519 -175.412527) (xy 413.009485 -175.442255)
			(xy 413.030416 -175.459898) (xy 413.037528 -175.465994) (xy 413.054546 -175.472344) (xy 413.13989 -175.472344)
			(xy 413.156908 -175.465994) (xy 413.16402 -175.459898) (xy 413.184971 -175.442283) (xy 413.230939 -175.412567)
			(xy 413.280681 -175.389727) (xy 413.333178 -175.37423) (xy 413.38735 -175.366396) (xy 413.414718 -175.365918)
			(xy 413.441973 -175.366338) (xy 413.495926 -175.374098) (xy 413.548227 -175.389458) (xy 413.597809 -175.412104)
			(xy 413.643663 -175.441577) (xy 413.684856 -175.477275) (xy 413.72055 -175.518472) (xy 413.750017 -175.56433)
			(xy 413.772657 -175.613915) (xy 413.788011 -175.666217) (xy 413.795765 -175.720171) (xy 413.796226 -175.747426)
			(xy 413.795786 -175.774397) (xy 413.788175 -175.827799) (xy 413.773109 -175.879594) (xy 413.75089 -175.928747)
			(xy 413.721961 -175.974275) (xy 413.704786 -175.995076) (xy 413.69869 -176.002188) (xy 413.692594 -176.019206)
			(xy 413.693356 -176.104804) (xy 413.69996 -176.121568) (xy 413.70631 -176.12868) (xy 413.724408 -176.149746)
			(xy 413.754913 -176.196157) (xy 413.778372 -176.246497) (xy 413.79429 -176.299705) (xy 413.802333 -176.354657)
			(xy 413.80283 -176.382426) (xy 413.802396 -176.409798) (xy 413.794573 -176.463979) (xy 413.779078 -176.516483)
			(xy 413.756228 -176.566229) (xy 413.726495 -176.612194) (xy 413.70885 -176.633124) (xy 413.702754 -176.640236)
			(xy 413.696404 -176.657254) (xy 413.696404 -176.742598) (xy 413.702754 -176.759616) (xy 413.70885 -176.766728)
			(xy 413.726517 -176.78764) (xy 413.756243 -176.833611) (xy 413.779088 -176.88336) (xy 413.794583 -176.935866)
			(xy 413.80241 -176.990047) (xy 413.802407 -177.044792) (xy 413.794575 -177.098973) (xy 413.779074 -177.151477)
			(xy 413.756224 -177.201224) (xy 413.726493 -177.247192) (xy 413.70885 -177.268124) (xy 413.702754 -177.275236)
			(xy 413.696404 -177.292254) (xy 413.696404 -177.377598) (xy 413.702754 -177.394616) (xy 413.70885 -177.401728)
			(xy 413.726517 -177.42264) (xy 413.756243 -177.468611) (xy 413.779088 -177.51836) (xy 413.794583 -177.570866)
			(xy 413.80241 -177.625047) (xy 413.802407 -177.679792) (xy 413.794575 -177.733973) (xy 413.779074 -177.786477)
			(xy 413.756224 -177.836224) (xy 413.726493 -177.882192) (xy 413.70885 -177.903124) (xy 413.702754 -177.910236)
			(xy 413.696404 -177.927254) (xy 413.696404 -178.012598) (xy 413.702754 -178.029616) (xy 413.70885 -178.036728)
			(xy 413.726461 -178.057683) (xy 413.756179 -178.103649) (xy 413.779021 -178.15339) (xy 413.794518 -178.205886)
			(xy 413.802353 -178.260058) (xy 413.80283 -178.287426) (xy 413.802306 -178.316438) (xy 413.793534 -178.373796)
			(xy 413.77618 -178.429165) (xy 413.750644 -178.481269) (xy 413.717515 -178.528906) (xy 413.697928 -178.550316)
			(xy 413.69107 -178.557428) (xy 413.683958 -178.574954) (xy 413.682942 -178.663854) (xy 413.6898 -178.681634)
			(xy 413.696404 -178.688746) (xy 413.715056 -178.709972) (xy 413.746597 -178.756852) (xy 413.770879 -178.807871)
			(xy 413.78737 -178.861913) (xy 413.795711 -178.917797) (xy 413.796226 -178.946048) (xy 413.795747 -178.973418)
			(xy 413.787935 -179.027597) (xy 413.77245 -179.080101) (xy 413.749611 -179.129848) (xy 413.719887 -179.175815)
			(xy 413.702246 -179.196746) (xy 413.69615 -179.203858) (xy 413.6898 -179.220876) (xy 413.6898 -179.30622)
			(xy 413.69615 -179.323238) (xy 413.702246 -179.33035) (xy 413.719935 -179.351244) (xy 413.74966 -179.397218)
			(xy 413.772504 -179.44697) (xy 413.787998 -179.499479) (xy 413.795822 -179.553663) (xy 413.795817 -179.608409)
			(xy 413.787982 -179.662592) (xy 413.772479 -179.715097) (xy 413.749625 -179.764846) (xy 413.719891 -179.810814)
			(xy 413.702246 -179.831746) (xy 413.69615 -179.838858) (xy 413.6898 -179.855876) (xy 413.6898 -179.94122)
			(xy 413.69615 -179.958238) (xy 413.702246 -179.96535) (xy 413.719935 -179.986244) (xy 413.74966 -180.032218)
			(xy 413.772504 -180.08197) (xy 413.787998 -180.134479) (xy 413.795822 -180.188663) (xy 413.795817 -180.243409)
			(xy 413.787982 -180.297592) (xy 413.772479 -180.350097) (xy 413.749625 -180.399846) (xy 413.719891 -180.445814)
			(xy 413.702246 -180.466746) (xy 413.69615 -180.473858) (xy 413.6898 -180.490876) (xy 413.6898 -180.57622)
			(xy 413.69615 -180.593238) (xy 413.702246 -180.60035) (xy 413.719867 -180.621297) (xy 413.749583 -180.667265)
			(xy 413.772424 -180.717008) (xy 413.787919 -180.769506) (xy 413.79575 -180.82368) (xy 413.796049 -180.840888)
			(xy 415.76625 -180.840888) (xy 415.766697 -180.813517) (xy 415.774517 -180.759337) (xy 415.79001 -180.706833)
			(xy 415.812857 -180.657086) (xy 415.842586 -180.611121) (xy 415.86023 -180.59019) (xy 415.866326 -180.583078)
			(xy 415.872676 -180.56606) (xy 415.872676 -180.480716) (xy 415.866326 -180.463698) (xy 415.86023 -180.456586)
			(xy 415.842577 -180.435663) (xy 415.812853 -180.389693) (xy 415.790008 -180.339946) (xy 415.774513 -180.287442)
			(xy 415.766685 -180.233262) (xy 415.766686 -180.17852) (xy 415.774516 -180.12434) (xy 415.790014 -180.071837)
			(xy 415.812862 -180.022091) (xy 415.842588 -179.976123) (xy 415.86023 -179.95519) (xy 415.866326 -179.948078)
			(xy 415.872676 -179.93106) (xy 415.872676 -179.845716) (xy 415.866326 -179.828698) (xy 415.86023 -179.821586)
			(xy 415.842577 -179.800663) (xy 415.812853 -179.754693) (xy 415.790008 -179.704946) (xy 415.774513 -179.652442)
			(xy 415.766685 -179.598262) (xy 415.766686 -179.54352) (xy 415.774516 -179.48934) (xy 415.790014 -179.436837)
			(xy 415.812862 -179.387091) (xy 415.842588 -179.341123) (xy 415.86023 -179.32019) (xy 415.866326 -179.313078)
			(xy 415.872676 -179.29606) (xy 415.872676 -179.210716) (xy 415.866326 -179.193698) (xy 415.86023 -179.186586)
			(xy 415.842622 -179.165628) (xy 415.812905 -179.119663) (xy 415.790062 -179.069922) (xy 415.774564 -179.017427)
			(xy 415.766728 -178.963256) (xy 415.76625 -178.935888) (xy 415.766777 -178.906805) (xy 415.775602 -178.849312)
			(xy 415.793047 -178.793823) (xy 415.818707 -178.741622) (xy 415.851989 -178.693918) (xy 415.87166 -178.67249)
			(xy 415.878518 -178.665632) (xy 415.88563 -178.64836) (xy 415.887662 -178.560984) (xy 415.881566 -178.543458)
			(xy 415.875216 -178.536092) (xy 415.857881 -178.515257) (xy 415.828724 -178.469568) (xy 415.806329 -178.420211)
			(xy 415.791147 -178.368181) (xy 415.783485 -178.314526) (xy 415.783014 -178.287426) (xy 415.783492 -178.260056)
			(xy 415.791306 -178.205877) (xy 415.806792 -178.153374) (xy 415.829632 -178.103627) (xy 415.859354 -178.05766)
			(xy 415.876994 -178.036728) (xy 415.88309 -178.029616) (xy 415.88944 -178.012598) (xy 415.88944 -177.927254)
			(xy 415.88309 -177.910236) (xy 415.876994 -177.903124) (xy 415.85938 -177.88217) (xy 415.829657 -177.836205)
			(xy 415.806812 -177.786462) (xy 415.791315 -177.733964) (xy 415.783485 -177.679789) (xy 415.783482 -177.625051)
			(xy 415.791307 -177.570875) (xy 415.806798 -177.518375) (xy 415.829638 -177.468629) (xy 415.859357 -177.422661)
			(xy 415.876994 -177.401728) (xy 415.88309 -177.394616) (xy 415.88944 -177.377598) (xy 415.88944 -177.292254)
			(xy 415.88309 -177.275236) (xy 415.876994 -177.268124) (xy 415.85938 -177.24717) (xy 415.829657 -177.201205)
			(xy 415.806812 -177.151462) (xy 415.791315 -177.098964) (xy 415.783485 -177.044789) (xy 415.783482 -176.990051)
			(xy 415.791307 -176.935875) (xy 415.806798 -176.883375) (xy 415.829638 -176.833629) (xy 415.859357 -176.787661)
			(xy 415.876994 -176.766728) (xy 415.88309 -176.759616) (xy 415.88944 -176.742598) (xy 415.88944 -176.657254)
			(xy 415.88309 -176.640236) (xy 415.876994 -176.633124) (xy 415.859352 -176.612194) (xy 415.829641 -176.566221)
			(xy 415.806805 -176.516473) (xy 415.791315 -176.463972) (xy 415.783488 -176.409795) (xy 415.783014 -176.382426)
			(xy 415.783477 -176.355292) (xy 415.79117 -176.301571) (xy 415.806404 -176.249484) (xy 415.82887 -176.200085)
			(xy 415.858116 -176.154371) (xy 415.87547 -176.133506) (xy 415.881566 -176.126394) (xy 415.887662 -176.109376)
			(xy 415.887154 -176.024032) (xy 415.880804 -176.007014) (xy 415.874454 -175.999902) (xy 415.856568 -175.978872)
			(xy 415.826373 -175.932655) (xy 415.803156 -175.882568) (xy 415.787403 -175.829658) (xy 415.779441 -175.775029)
			(xy 415.77895 -175.747426) (xy 415.779502 -175.720177) (xy 415.787254 -175.666234) (xy 415.802604 -175.613943)
			(xy 415.825239 -175.564369) (xy 415.854699 -175.518521) (xy 415.890383 -175.477331) (xy 415.931566 -175.441639)
			(xy 415.977409 -175.412172) (xy 416.02698 -175.389528) (xy 416.079268 -175.374169) (xy 416.133209 -175.366407)
			(xy 416.160458 -175.365918) (xy 416.187828 -175.366404) (xy 416.242006 -175.374217) (xy 416.294509 -175.389701)
			(xy 416.344256 -175.412538) (xy 416.390224 -175.442259) (xy 416.411156 -175.459898) (xy 416.418268 -175.465994)
			(xy 416.435286 -175.472344) (xy 416.52063 -175.472344) (xy 416.537648 -175.465994) (xy 416.54476 -175.459898)
			(xy 416.565693 -175.442257) (xy 416.611661 -175.412533) (xy 416.661407 -175.389687) (xy 416.713909 -175.374191)
			(xy 416.768087 -175.366362) (xy 416.822829 -175.366362) (xy 416.877007 -175.374191) (xy 416.929509 -175.389687)
			(xy 416.979255 -175.412533) (xy 417.025223 -175.442257) (xy 417.046156 -175.459898) (xy 417.053268 -175.465994)
			(xy 417.070286 -175.472344) (xy 417.15563 -175.472344) (xy 417.172648 -175.465994) (xy 417.17976 -175.459898)
			(xy 417.200696 -175.442264) (xy 417.246668 -175.412551) (xy 417.296414 -175.389715) (xy 417.348914 -175.374222)
			(xy 417.403089 -175.366393) (xy 417.430458 -175.365918) (xy 417.457711 -175.366394) (xy 417.511663 -175.374146)
			(xy 417.563962 -175.389498) (xy 417.613544 -175.412138) (xy 417.659398 -175.441604) (xy 417.700592 -175.477297)
			(xy 417.736286 -175.518489) (xy 417.765754 -175.564342) (xy 417.788396 -175.613923) (xy 417.80375 -175.666222)
			(xy 417.811504 -175.720173) (xy 417.811966 -175.747426) (xy 417.811488 -175.77476) (xy 417.803683 -175.828867)
			(xy 417.788235 -175.881306) (xy 417.765462 -175.931004) (xy 417.735829 -175.976943) (xy 417.71824 -175.99787)
			(xy 417.711636 -176.005236) (xy 417.70554 -176.02327) (xy 417.708588 -176.11217) (xy 417.715954 -176.129442)
			(xy 417.723066 -176.136554) (xy 417.74386 -176.158159) (xy 417.779117 -176.206658) (xy 417.806349 -176.260077)
			(xy 417.824885 -176.317101) (xy 417.834268 -176.376322) (xy 417.834826 -176.406302) (xy 417.834379 -176.433673)
			(xy 417.826559 -176.487854) (xy 417.811067 -176.540358) (xy 417.78822 -176.590104) (xy 417.75849 -176.63607)
			(xy 417.740846 -176.657) (xy 417.73475 -176.664112) (xy 417.7284 -176.68113) (xy 417.7284 -176.766474)
			(xy 417.73475 -176.783492) (xy 417.740846 -176.790604) (xy 417.75849 -176.811535) (xy 417.788217 -176.857502)
			(xy 417.789456 -176.8602) (xy 421.86225 -176.8602) (xy 421.862749 -176.831282) (xy 421.87148 -176.774109)
			(xy 421.88874 -176.718909) (xy 421.914135 -176.666947) (xy 421.947083 -176.619414) (xy 421.986828 -176.577399)
			(xy 422.009316 -176.55921) (xy 422.018072 -176.551642) (xy 422.028258 -176.530888) (xy 422.028874 -176.519332)
			(xy 422.028874 -176.439068) (xy 422.028274 -176.427504) (xy 422.018101 -176.406732) (xy 422.009316 -176.39919)
			(xy 421.986831 -176.381001) (xy 421.947095 -176.338981) (xy 421.914156 -176.291446) (xy 421.888768 -176.239484)
			(xy 421.871512 -176.184286) (xy 421.862784 -176.127116) (xy 421.86225 -176.0982) (xy 421.862736 -176.070949)
			(xy 421.870492 -176.017001) (xy 421.885847 -175.964706) (xy 421.908489 -175.915129) (xy 421.937955 -175.869279)
			(xy 421.973646 -175.828088) (xy 422.014837 -175.792397) (xy 422.060687 -175.762931) (xy 422.110264 -175.740289)
			(xy 422.162559 -175.724934) (xy 422.216507 -175.717178) (xy 422.271009 -175.717178) (xy 422.324957 -175.724934)
			(xy 422.377252 -175.740289) (xy 422.426829 -175.762931) (xy 422.472679 -175.792397) (xy 422.51387 -175.828088)
			(xy 422.549561 -175.869279) (xy 422.579027 -175.915129) (xy 422.601669 -175.964706) (xy 422.617024 -176.017001)
			(xy 422.62478 -176.070949) (xy 422.625266 -176.0982) (xy 422.62476 -176.127118) (xy 422.616031 -176.18429)
			(xy 422.598771 -176.23949) (xy 422.573377 -176.291451) (xy 422.540431 -176.338985) (xy 422.500687 -176.381001)
			(xy 422.4782 -176.39919) (xy 422.469447 -176.406761) (xy 422.459259 -176.427513) (xy 422.458642 -176.439068)
			(xy 422.458642 -176.519332) (xy 422.459237 -176.530897) (xy 422.469413 -176.551669) (xy 422.4782 -176.55921)
			(xy 422.500688 -176.577395) (xy 422.540423 -176.619416) (xy 422.573362 -176.666952) (xy 422.598749 -176.718915)
			(xy 422.616004 -176.774113) (xy 422.624732 -176.831284) (xy 422.625266 -176.8602) (xy 422.62478 -176.887451)
			(xy 422.617024 -176.941399) (xy 422.601669 -176.993694) (xy 422.579027 -177.043271) (xy 422.549561 -177.089121)
			(xy 422.51387 -177.130312) (xy 422.472679 -177.166003) (xy 422.426829 -177.195469) (xy 422.377252 -177.218111)
			(xy 422.324957 -177.233466) (xy 422.271009 -177.241222) (xy 422.216507 -177.241222) (xy 422.162559 -177.233466)
			(xy 422.110264 -177.218111) (xy 422.060687 -177.195469) (xy 422.014837 -177.166003) (xy 421.973646 -177.130312)
			(xy 421.937955 -177.089121) (xy 421.908489 -177.043271) (xy 421.885847 -176.993694) (xy 421.870492 -176.941399)
			(xy 421.862736 -176.887451) (xy 421.86225 -176.8602) (xy 417.789456 -176.8602) (xy 417.811063 -176.907249)
			(xy 417.826561 -176.959751) (xy 417.83439 -177.01393) (xy 417.83439 -177.068673) (xy 417.82656 -177.122852)
			(xy 417.811062 -177.175354) (xy 417.788215 -177.225101) (xy 417.758488 -177.271068) (xy 417.740846 -177.292)
			(xy 417.73475 -177.299112) (xy 417.7284 -177.31613) (xy 417.7284 -177.401474) (xy 417.73475 -177.418492)
			(xy 417.740846 -177.425604) (xy 417.75849 -177.446535) (xy 417.788217 -177.492502) (xy 417.811063 -177.542249)
			(xy 417.826561 -177.594751) (xy 417.83439 -177.64893) (xy 417.83439 -177.703673) (xy 417.82656 -177.757852)
			(xy 417.811062 -177.810354) (xy 417.788215 -177.860101) (xy 417.758488 -177.906068) (xy 417.740846 -177.927)
			(xy 417.73475 -177.934112) (xy 417.7284 -177.95113) (xy 417.7284 -178.036474) (xy 417.73475 -178.053492)
			(xy 417.740846 -178.060604) (xy 417.758492 -178.081531) (xy 417.788205 -178.127504) (xy 417.81104 -178.177253)
			(xy 417.826529 -178.229755) (xy 417.834354 -178.283932) (xy 417.834826 -178.311302) (xy 417.834273 -178.340815)
			(xy 417.825182 -178.399136) (xy 417.807217 -178.455361) (xy 417.780808 -178.508149) (xy 417.746584 -178.55624)
			(xy 417.726368 -178.577748) (xy 417.719764 -178.584606) (xy 417.712398 -178.601116) (xy 417.707572 -178.68646)
			(xy 417.71316 -178.703732) (xy 417.718748 -178.711098) (xy 417.73393 -178.731286) (xy 417.759435 -178.774884)
			(xy 417.778966 -178.821465) (xy 417.792183 -178.870216) (xy 417.798853 -178.920285) (xy 417.799266 -178.94554)
			(xy 417.798773 -178.972909) (xy 417.790963 -179.027088) (xy 417.775481 -179.079591) (xy 417.752645 -179.129338)
			(xy 417.722925 -179.175306) (xy 417.705286 -179.196238) (xy 417.69919 -179.20335) (xy 417.69284 -179.220368)
			(xy 417.69284 -179.305712) (xy 417.69919 -179.32273) (xy 417.705286 -179.329842) (xy 417.722965 -179.350743)
			(xy 417.752688 -179.396717) (xy 417.77553 -179.446468) (xy 417.791022 -179.498975) (xy 417.798847 -179.553158)
			(xy 417.798843 -179.607902) (xy 417.791009 -179.662084) (xy 417.775509 -179.714588) (xy 417.752658 -179.764336)
			(xy 417.722929 -179.810305) (xy 417.705286 -179.831238) (xy 417.69919 -179.83835) (xy 417.69284 -179.855368)
			(xy 417.69284 -179.940712) (xy 417.69919 -179.95773) (xy 417.705286 -179.964842) (xy 417.722965 -179.985743)
			(xy 417.752688 -180.031717) (xy 417.77553 -180.081468) (xy 417.791022 -180.133975) (xy 417.798847 -180.188158)
			(xy 417.798843 -180.242902) (xy 417.791009 -180.297084) (xy 417.775509 -180.349588) (xy 417.752658 -180.399336)
			(xy 417.722929 -180.445305) (xy 417.705286 -180.466238) (xy 417.69919 -180.47335) (xy 417.69284 -180.490368)
			(xy 417.69284 -180.575712) (xy 417.69919 -180.59273) (xy 417.705286 -180.599842) (xy 417.722909 -180.620787)
			(xy 417.752624 -180.666756) (xy 417.775463 -180.7165) (xy 417.790958 -180.768998) (xy 417.79879 -180.823172)
			(xy 417.799266 -180.85054) (xy 417.798882 -180.877796) (xy 417.791119 -180.931752) (xy 417.775755 -180.984054)
			(xy 417.753105 -181.033637) (xy 417.723629 -181.079492) (xy 417.687927 -181.120685) (xy 417.646726 -181.156378)
			(xy 417.600865 -181.185845) (xy 417.551277 -181.208484) (xy 417.498972 -181.223836) (xy 417.445014 -181.231588)
			(xy 417.417758 -181.232048) (xy 417.389811 -181.231583) (xy 417.334518 -181.223411) (xy 417.281008 -181.207262)
			(xy 417.230426 -181.183481) (xy 417.183852 -181.152578) (xy 417.162742 -181.134258) (xy 417.15563 -181.127908)
			(xy 417.138866 -181.121304) (xy 417.053268 -181.120034) (xy 417.03625 -181.12613) (xy 417.029138 -181.132226)
			(xy 417.008385 -181.149181) (xy 416.96302 -181.17771) (xy 416.91411 -181.199611) (xy 416.862617 -181.214454)
			(xy 416.809553 -181.221946) (xy 416.782758 -181.222396) (xy 416.755389 -181.221897) (xy 416.701211 -181.214087)
			(xy 416.648708 -181.198606) (xy 416.598961 -181.175771) (xy 416.552993 -181.146054) (xy 416.53206 -181.128416)
			(xy 416.524948 -181.12232) (xy 416.50793 -181.11597) (xy 416.422586 -181.11597) (xy 416.405568 -181.12232)
			(xy 416.398456 -181.128416) (xy 416.377516 -181.146045) (xy 416.331545 -181.175758) (xy 416.281799 -181.198595)
			(xy 416.229301 -181.214089) (xy 416.175127 -181.22192) (xy 416.147758 -181.222396) (xy 416.120505 -181.221961)
			(xy 416.066555 -181.214199) (xy 416.014259 -181.198838) (xy 415.96468 -181.176191) (xy 415.91883 -181.146719)
			(xy 415.87764 -181.111022) (xy 415.841949 -181.069827) (xy 415.812483 -181.023972) (xy 415.789843 -180.974391)
			(xy 415.77449 -180.922092) (xy 415.766735 -180.868141) (xy 415.76625 -180.840888) (xy 413.796049 -180.840888)
			(xy 413.796226 -180.851048) (xy 413.795767 -180.8783) (xy 413.788004 -180.932247) (xy 413.772644 -180.984541)
			(xy 413.749999 -181.034118) (xy 413.720529 -181.079967) (xy 413.684835 -181.121156) (xy 413.643643 -181.156847)
			(xy 413.597791 -181.186313) (xy 413.548213 -181.208955) (xy 413.495918 -181.224311) (xy 413.44197 -181.232069)
			(xy 413.414718 -181.232556) (xy 413.387348 -181.23209) (xy 413.333168 -181.224274) (xy 413.280665 -181.208785)
			(xy 413.230918 -181.185943) (xy 413.184951 -181.156218) (xy 413.16402 -181.138576) (xy 413.156908 -181.13248)
			(xy 413.13989 -181.12613) (xy 413.054546 -181.12613) (xy 413.037528 -181.13248) (xy 413.030416 -181.138576)
			(xy 413.009486 -181.156217) (xy 412.963513 -181.18593) (xy 412.913765 -181.208766) (xy 412.861264 -181.224256)
			(xy 412.807087 -181.232083) (xy 412.779718 -181.232556) (xy 412.752469 -181.232005) (xy 412.698527 -181.224252)
			(xy 412.646236 -181.208902) (xy 412.596662 -181.186266) (xy 412.550814 -181.156807) (xy 412.509625 -181.121122)
			(xy 412.473933 -181.079939) (xy 412.444465 -181.034096) (xy 412.421821 -180.984526) (xy 412.406462 -180.932238)
			(xy 412.3987 -180.878297) (xy 412.39821 -180.851048) (xy 409.374655 -180.851048) (xy 409.377642 -180.93817)
			(xy 409.385008 -180.955442) (xy 409.39212 -180.962554) (xy 409.412923 -180.98415) (xy 409.448177 -181.032653)
			(xy 409.475406 -181.086074) (xy 409.49394 -181.143099) (xy 409.503322 -181.202321) (xy 409.50388 -181.232302)
			(xy 409.50342 -181.259673) (xy 409.495601 -181.313852) (xy 409.480111 -181.366355) (xy 409.457268 -181.416102)
			(xy 409.427542 -181.462069) (xy 409.4099 -181.483) (xy 409.403804 -181.490112) (xy 409.397454 -181.50713)
			(xy 409.397454 -181.592474) (xy 409.403804 -181.609492) (xy 409.4099 -181.616604) (xy 409.427542 -181.637536)
			(xy 409.457264 -181.683504) (xy 409.480108 -181.733251) (xy 409.495603 -181.785753) (xy 409.503431 -181.839931)
			(xy 409.50343 -181.894672) (xy 409.495602 -181.94885) (xy 409.480107 -182.001352) (xy 409.457263 -182.051098)
			(xy 409.42754 -182.097067) (xy 409.4099 -182.118) (xy 409.403804 -182.125112) (xy 409.397454 -182.14213)
			(xy 409.397454 -182.227474) (xy 409.403804 -182.244492) (xy 409.4099 -182.251604) (xy 409.427542 -182.272536)
			(xy 409.457264 -182.318504) (xy 409.480108 -182.368251) (xy 409.495603 -182.420753) (xy 409.503431 -182.474931)
			(xy 409.50343 -182.529672) (xy 409.495602 -182.58385) (xy 409.480107 -182.636352) (xy 409.457263 -182.686098)
			(xy 409.42754 -182.732067) (xy 409.4099 -182.753) (xy 409.403804 -182.760112) (xy 409.397454 -182.77713)
			(xy 409.397454 -182.862474) (xy 409.403804 -182.879492) (xy 409.4099 -182.886604) (xy 409.427554 -182.907524)
			(xy 409.457264 -182.9535) (xy 409.480097 -183.003251) (xy 409.495584 -183.055754) (xy 409.503408 -183.109932)
			(xy 409.50388 -183.137302) (xy 409.503376 -183.16622) (xy 409.494639 -183.223394) (xy 409.477365 -183.278591)
			(xy 409.451952 -183.330545) (xy 409.418982 -183.378065) (xy 409.399486 -183.39943) (xy 409.393136 -183.406288)
			(xy 409.386024 -183.422798) (xy 409.382722 -183.508396) (xy 409.38831 -183.525668) (xy 409.394152 -183.533034)
			(xy 409.410035 -183.553429) (xy 409.436709 -183.597709) (xy 409.457164 -183.645184) (xy 409.471023 -183.694985)
			(xy 409.478034 -183.746201) (xy 409.47848 -183.772048) (xy 409.478067 -183.799302) (xy 409.470303 -183.853253)
			(xy 409.45494 -183.905551) (xy 409.432292 -183.955131) (xy 409.402818 -184.000982) (xy 409.367119 -184.042172)
			(xy 409.325921 -184.077863) (xy 409.280064 -184.107328) (xy 409.23048 -184.129967) (xy 409.178179 -184.145319)
			(xy 409.124226 -184.153072) (xy 409.096972 -184.153556) (xy 409.067496 -184.152983) (xy 409.009243 -184.143924)
			(xy 408.953078 -184.126009) (xy 408.900339 -184.099667) (xy 408.85228 -184.065524) (xy 408.83078 -184.045352)
			(xy 408.823452 -184.038809) (xy 408.805286 -184.03137) (xy 408.795474 -184.030874) (xy 408.742134 -184.030874)
			(xy 408.735276 -184.03824) (xy 408.728728 -184.045564) (xy 408.721291 -184.063733) (xy 408.720798 -184.073546)
			(xy 408.720798 -184.10555) (xy 408.721268 -184.115366) (xy 408.728724 -184.13353) (xy 408.735276 -184.140856)
			(xy 408.755433 -184.16237) (xy 408.789579 -184.210426) (xy 408.815928 -184.263162) (xy 408.833853 -184.319323)
			(xy 408.842928 -184.377572) (xy 408.84348 -184.407048) (xy 408.843067 -184.434302) (xy 408.835303 -184.488253)
			(xy 408.81994 -184.540551) (xy 408.797292 -184.590131) (xy 408.767818 -184.635982) (xy 408.732119 -184.677172)
			(xy 408.690921 -184.712863) (xy 408.645064 -184.742328) (xy 408.59548 -184.764967) (xy 408.543179 -184.780319)
			(xy 408.489226 -184.788072) (xy 408.461972 -184.788556) (xy 408.432496 -184.787983) (xy 408.374243 -184.778924)
			(xy 408.318078 -184.761009) (xy 408.265339 -184.734667) (xy 408.21728 -184.700524) (xy 408.19578 -184.680352)
			(xy 408.188452 -184.673809) (xy 408.170286 -184.66637) (xy 408.160474 -184.665874) (xy 408.107134 -184.665874)
			(xy 408.100276 -184.67324) (xy 408.093728 -184.680564) (xy 408.086291 -184.698733) (xy 408.085798 -184.708546)
			(xy 408.085798 -184.74055) (xy 408.086268 -184.750366) (xy 408.093724 -184.76853) (xy 408.100276 -184.775856)
			(xy 408.120433 -184.79737) (xy 408.154579 -184.845426) (xy 408.180928 -184.898162) (xy 408.198853 -184.954323)
			(xy 408.207928 -185.012572) (xy 408.20848 -185.042048) (xy 408.207994 -185.069299) (xy 408.200238 -185.123247)
			(xy 408.184883 -185.175542) (xy 408.162241 -185.225119) (xy 408.132775 -185.270969) (xy 408.097084 -185.31216)
			(xy 408.055893 -185.347851) (xy 408.010043 -185.377317) (xy 407.960466 -185.399959) (xy 407.908171 -185.415314)
			(xy 407.854223 -185.42307) (xy 407.799721 -185.42307) (xy 407.745773 -185.415314) (xy 407.693478 -185.399959)
			(xy 407.643901 -185.377317) (xy 407.598051 -185.347851) (xy 407.55686 -185.31216) (xy 407.521169 -185.270969)
			(xy 407.491703 -185.225119) (xy 407.469061 -185.175542) (xy 407.453706 -185.123247) (xy 407.44595 -185.069299)
			(xy 407.445464 -185.042048) (xy 405.431845 -185.042048) (xy 405.431843 -185.069409) (xy 405.424009 -185.123591)
			(xy 405.408506 -185.176096) (xy 405.385655 -185.225844) (xy 405.355924 -185.271813) (xy 405.33828 -185.292746)
			(xy 405.332184 -185.299858) (xy 405.325834 -185.316876) (xy 405.325834 -185.40222) (xy 405.332184 -185.419238)
			(xy 405.33828 -185.42635) (xy 405.355967 -185.447245) (xy 405.38569 -185.493219) (xy 405.408532 -185.542972)
			(xy 405.424024 -185.59548) (xy 405.431848 -185.649663) (xy 405.431843 -185.704409) (xy 405.424009 -185.758591)
			(xy 405.408506 -185.811096) (xy 405.385655 -185.860844) (xy 405.355924 -185.906813) (xy 405.33828 -185.927746)
			(xy 405.332184 -185.934858) (xy 405.325834 -185.951876) (xy 405.325834 -186.03722) (xy 405.332184 -186.054238)
			(xy 405.33828 -186.06135) (xy 405.355967 -186.082245) (xy 405.38569 -186.128219) (xy 405.408532 -186.177972)
			(xy 405.424024 -186.23048) (xy 405.431848 -186.284663) (xy 405.431843 -186.339409) (xy 405.424009 -186.393591)
			(xy 405.408506 -186.446096) (xy 405.385655 -186.495844) (xy 405.355924 -186.541813) (xy 405.33828 -186.562746)
			(xy 405.332184 -186.569858) (xy 405.325834 -186.586876) (xy 405.325834 -186.67222) (xy 405.332184 -186.689238)
			(xy 405.33828 -186.69635) (xy 405.355906 -186.717293) (xy 405.38562 -186.763262) (xy 405.408459 -186.813007)
			(xy 405.423953 -186.865505) (xy 405.431785 -186.91968) (xy 405.43226 -186.947048) (xy 405.431867 -186.974303)
			(xy 405.424102 -187.028256) (xy 405.408739 -187.080556) (xy 405.386089 -187.130136) (xy 405.356613 -187.175989)
			(xy 405.320912 -187.21718) (xy 405.279712 -187.25287) (xy 405.233852 -187.282335) (xy 405.184265 -187.304972)
			(xy 405.131962 -187.320323) (xy 405.078007 -187.328074) (xy 405.050752 -187.328556) (xy 405.023382 -187.32807)
			(xy 404.969204 -187.320259) (xy 404.9167 -187.304775) (xy 404.866953 -187.281937) (xy 404.820986 -187.252216)
			(xy 404.800054 -187.234576) (xy 404.792942 -187.22848) (xy 404.775924 -187.22213) (xy 404.69058 -187.22213)
			(xy 404.673562 -187.22848) (xy 404.66645 -187.234576) (xy 404.645507 -187.252201) (xy 404.599537 -187.281916)
			(xy 404.549793 -187.304755) (xy 404.497294 -187.320249) (xy 404.44312 -187.328081) (xy 404.415752 -187.328556)
			(xy 404.388502 -187.328067) (xy 404.334557 -187.320305) (xy 404.282265 -187.304946) (xy 404.232691 -187.282303)
			(xy 404.186843 -187.252836) (xy 404.145654 -187.217146) (xy 404.109964 -187.175957) (xy 404.080497 -187.130109)
			(xy 404.057854 -187.080535) (xy 404.042495 -187.028243) (xy 404.034733 -186.974298) (xy 404.034244 -186.947048)
			(xy 358.210721 -186.947048) (xy 358.215946 -186.953144) (xy 358.233629 -186.974043) (xy 358.263354 -187.020016)
			(xy 358.286199 -187.069768) (xy 358.301693 -187.122275) (xy 358.309518 -187.176459) (xy 358.309514 -187.231205)
			(xy 358.301679 -187.285387) (xy 358.286176 -187.337892) (xy 358.263324 -187.38764) (xy 358.233591 -187.433608)
			(xy 358.215946 -187.45454) (xy 358.20985 -187.461652) (xy 358.2035 -187.47867) (xy 358.2035 -187.564014)
			(xy 358.20985 -187.581032) (xy 358.215946 -187.588144) (xy 358.233564 -187.609093) (xy 358.263281 -187.655061)
			(xy 358.286122 -187.704804) (xy 358.301618 -187.757301) (xy 358.30945 -187.811474) (xy 358.309926 -187.838842)
			(xy 358.309461 -187.866093) (xy 358.3017 -187.920041) (xy 358.28634 -187.972335) (xy 358.263695 -188.021911)
			(xy 358.234226 -188.067761) (xy 358.198533 -188.10895) (xy 358.157341 -188.144641) (xy 358.11149 -188.174107)
			(xy 358.061913 -188.196748) (xy 358.009618 -188.212105) (xy 357.955669 -188.219863) (xy 357.928418 -188.22035)
			(xy 357.901048 -188.219886) (xy 357.846868 -188.212069) (xy 357.794364 -188.19658) (xy 357.744617 -188.173738)
			(xy 357.698651 -188.144012) (xy 357.67772 -188.12637) (xy 357.670608 -188.120274) (xy 357.65359 -188.113924)
			(xy 357.568246 -188.113924) (xy 357.551228 -188.120274) (xy 357.544116 -188.12637) (xy 357.523185 -188.14401)
			(xy 357.477212 -188.173723) (xy 357.427465 -188.196559) (xy 357.374964 -188.21205) (xy 357.320787 -188.219877)
			(xy 357.293418 -188.22035) (xy 357.266169 -188.219805) (xy 357.212226 -188.212052) (xy 357.159935 -188.196701)
			(xy 357.11036 -188.174065) (xy 357.064512 -188.144605) (xy 357.023323 -188.10892) (xy 356.987631 -188.067736)
			(xy 356.958163 -188.021892) (xy 356.93552 -187.972322) (xy 356.920161 -187.920033) (xy 356.912399 -187.866091)
			(xy 356.91191 -187.838842) (xy 356.912398 -187.811473) (xy 356.92021 -187.757294) (xy 356.935694 -187.704791)
			(xy 356.958531 -187.655044) (xy 356.988251 -187.609076) (xy 357.00589 -187.588144) (xy 357.011986 -187.581032)
			(xy 357.018336 -187.564014) (xy 357.018336 -187.47867) (xy 357.011986 -187.461652) (xy 357.00589 -187.45454)
			(xy 356.988292 -187.433573) (xy 356.958568 -187.38761) (xy 356.935723 -187.33787) (xy 356.920225 -187.285373)
			(xy 356.912393 -187.2312) (xy 356.912389 -187.176463) (xy 356.920211 -187.122289) (xy 356.935701 -187.06979)
			(xy 356.958538 -187.020045) (xy 356.988254 -186.974077) (xy 357.00589 -186.953144) (xy 357.011986 -186.946032)
			(xy 357.018336 -186.929014) (xy 357.018336 -186.84367) (xy 357.011986 -186.826652) (xy 357.00589 -186.81954)
			(xy 356.988292 -186.798573) (xy 356.958568 -186.75261) (xy 356.935723 -186.70287) (xy 356.920225 -186.650373)
			(xy 356.912393 -186.5962) (xy 356.912389 -186.541463) (xy 356.920211 -186.487289) (xy 356.935701 -186.43479)
			(xy 356.958538 -186.385045) (xy 356.988254 -186.339077) (xy 357.00589 -186.318144) (xy 357.011986 -186.311032)
			(xy 357.018336 -186.294014) (xy 357.018336 -186.20867) (xy 357.011986 -186.191652) (xy 357.00589 -186.18454)
			(xy 356.988292 -186.163573) (xy 356.958568 -186.11761) (xy 356.935723 -186.06787) (xy 356.920225 -186.015373)
			(xy 356.912393 -185.9612) (xy 356.912389 -185.906463) (xy 356.920211 -185.852289) (xy 356.935701 -185.79979)
			(xy 356.958538 -185.750045) (xy 356.988254 -185.704077) (xy 357.00589 -185.683144) (xy 357.011986 -185.676032)
			(xy 357.018336 -185.659014) (xy 357.018336 -185.57367) (xy 357.011986 -185.556652) (xy 357.00589 -185.54954)
			(xy 356.988292 -185.528573) (xy 356.958568 -185.48261) (xy 356.935723 -185.43287) (xy 356.920225 -185.380373)
			(xy 356.912393 -185.3262) (xy 356.912389 -185.271463) (xy 356.920211 -185.217289) (xy 356.935701 -185.16479)
			(xy 356.958538 -185.115045) (xy 356.988254 -185.069077) (xy 357.00589 -185.048144) (xy 357.011986 -185.041032)
			(xy 357.018336 -185.024014) (xy 357.018336 -184.93867) (xy 357.011986 -184.921652) (xy 357.00589 -184.91454)
			(xy 356.988255 -184.893605) (xy 356.958543 -184.847633) (xy 356.935706 -184.797886) (xy 356.920214 -184.745386)
			(xy 356.912385 -184.691211) (xy 356.91191 -184.663842) (xy 356.912391 -184.636132) (xy 356.920422 -184.581297)
			(xy 356.936307 -184.528202) (xy 356.959711 -184.477966) (xy 356.99014 -184.431647) (xy 357.008176 -184.410604)
			(xy 357.014526 -184.403238) (xy 357.02113 -184.385966) (xy 357.020114 -184.29859) (xy 357.01351 -184.281318)
			(xy 357.006906 -184.274206) (xy 356.988033 -184.252938) (xy 356.956096 -184.205898) (xy 356.931501 -184.154636)
			(xy 356.914793 -184.100289) (xy 356.906342 -184.044063) (xy 356.905814 -184.015634) (xy 356.906297 -183.988264)
			(xy 356.91411 -183.934086) (xy 356.929595 -183.881583) (xy 356.952433 -183.831836) (xy 356.982154 -183.785868)
			(xy 356.999794 -183.764936) (xy 357.00589 -183.757824) (xy 357.01224 -183.740806) (xy 357.01224 -183.655462)
			(xy 357.00589 -183.638444) (xy 356.999794 -183.631332) (xy 356.982188 -183.610372) (xy 356.952464 -183.564408)
			(xy 356.929619 -183.514666) (xy 356.914122 -183.462168) (xy 356.90629 -183.407994) (xy 356.906287 -183.353257)
			(xy 356.914111 -183.299082) (xy 356.929601 -183.246582) (xy 356.95244 -183.196837) (xy 356.982157 -183.150869)
			(xy 356.999794 -183.129936) (xy 357.00589 -183.122824) (xy 357.01224 -183.105806) (xy 357.01224 -183.020462)
			(xy 357.00589 -183.003444) (xy 356.999794 -182.996332) (xy 356.982188 -182.975372) (xy 356.952464 -182.929408)
			(xy 356.929619 -182.879666) (xy 356.914122 -182.827168) (xy 356.90629 -182.772994) (xy 356.906287 -182.718257)
			(xy 356.914111 -182.664082) (xy 356.929601 -182.611582) (xy 356.95244 -182.561837) (xy 356.982157 -182.515869)
			(xy 356.999794 -182.494936) (xy 357.00589 -182.487824) (xy 357.01224 -182.470806) (xy 357.01224 -182.385462)
			(xy 357.00589 -182.368444) (xy 356.999794 -182.361332) (xy 356.982156 -182.340399) (xy 356.952444 -182.294427)
			(xy 356.929608 -182.244679) (xy 356.914117 -182.192179) (xy 356.906288 -182.138003) (xy 356.905814 -182.110634)
			(xy 356.906282 -182.0835) (xy 356.913973 -182.029779) (xy 356.929206 -181.977693) (xy 356.951672 -181.928293)
			(xy 356.980916 -181.882579) (xy 356.99827 -181.861714) (xy 357.004366 -181.854602) (xy 357.010462 -181.837584)
			(xy 357.009954 -181.75224) (xy 357.003604 -181.735222) (xy 356.997254 -181.72811) (xy 356.979371 -181.707077)
			(xy 356.949176 -181.660861) (xy 356.925959 -181.610775) (xy 356.910204 -181.557865) (xy 356.902241 -181.503237)
			(xy 356.90175 -181.475634) (xy 354.919026 -181.475634) (xy 354.918591 -181.502605) (xy 354.910979 -181.556007)
			(xy 354.895912 -181.607803) (xy 354.873691 -181.656955) (xy 354.844761 -181.702483) (xy 354.827586 -181.723284)
			(xy 354.82149 -181.730396) (xy 354.815394 -181.747414) (xy 354.816156 -181.833012) (xy 354.82276 -181.849776)
			(xy 354.82911 -181.856888) (xy 354.847212 -181.877951) (xy 354.877716 -181.924363) (xy 354.901174 -181.974703)
			(xy 354.917092 -182.027912) (xy 354.925133 -182.082865) (xy 354.92563 -182.110634) (xy 354.925201 -182.138006)
			(xy 354.917377 -182.192187) (xy 354.90188 -182.244691) (xy 354.87903 -182.294438) (xy 354.849296 -182.340402)
			(xy 354.83165 -182.361332) (xy 354.825554 -182.368444) (xy 354.819204 -182.385462) (xy 354.819204 -182.470806)
			(xy 354.825554 -182.487824) (xy 354.83165 -182.494936) (xy 354.849325 -182.515841) (xy 354.87905 -182.561813)
			(xy 354.901895 -182.611564) (xy 354.91739 -182.66407) (xy 354.925215 -182.718253) (xy 354.925212 -182.772998)
			(xy 354.917379 -182.82718) (xy 354.901877 -182.879684) (xy 354.879025 -182.929432) (xy 354.849294 -182.9754)
			(xy 354.83165 -182.996332) (xy 354.825554 -183.003444) (xy 354.819204 -183.020462) (xy 354.819204 -183.105806)
			(xy 354.825554 -183.122824) (xy 354.83165 -183.129936) (xy 354.849325 -183.150841) (xy 354.87905 -183.196813)
			(xy 354.901895 -183.246564) (xy 354.91739 -183.29907) (xy 354.925215 -183.353253) (xy 354.925212 -183.407998)
			(xy 354.917379 -183.46218) (xy 354.901877 -183.514684) (xy 354.879025 -183.564432) (xy 354.849294 -183.6104)
			(xy 354.83165 -183.631332) (xy 354.825554 -183.638444) (xy 354.819204 -183.655462) (xy 354.819204 -183.740806)
			(xy 354.825554 -183.757824) (xy 354.83165 -183.764936) (xy 354.849265 -183.785888) (xy 354.878982 -183.831854)
			(xy 354.901823 -183.881597) (xy 354.91732 -183.934093) (xy 354.925153 -183.988266) (xy 354.92563 -184.015634)
			(xy 354.925125 -184.043343) (xy 354.917098 -184.098177) (xy 354.901218 -184.151271) (xy 354.87782 -184.201507)
			(xy 354.847397 -184.247828) (xy 354.829364 -184.268872) (xy 354.823014 -184.276238) (xy 354.81641 -184.29351)
			(xy 354.817426 -184.380886) (xy 354.82403 -184.398158) (xy 354.830634 -184.40527) (xy 354.849549 -184.426502)
			(xy 354.881479 -184.473552) (xy 354.906065 -184.524824) (xy 354.922764 -184.579179) (xy 354.931203 -184.635411)
			(xy 354.931726 -184.663842) (xy 354.931244 -184.691212) (xy 354.923433 -184.745391) (xy 354.907948 -184.797895)
			(xy 354.88511 -184.847642) (xy 354.855387 -184.893609) (xy 354.837746 -184.91454) (xy 354.83165 -184.921652)
			(xy 354.8253 -184.93867) (xy 354.8253 -185.024014) (xy 354.83165 -185.041032) (xy 354.837746 -185.048144)
			(xy 354.855429 -185.069043) (xy 354.885154 -185.115016) (xy 354.907999 -185.164768) (xy 354.923493 -185.217275)
			(xy 354.931318 -185.271459) (xy 354.931314 -185.326205) (xy 354.923479 -185.380387) (xy 354.907976 -185.432892)
			(xy 354.885124 -185.48264) (xy 354.855391 -185.528608) (xy 354.837746 -185.54954) (xy 354.83165 -185.556652)
			(xy 354.8253 -185.57367) (xy 354.8253 -185.659014) (xy 354.83165 -185.676032) (xy 354.837746 -185.683144)
			(xy 354.855364 -185.704093) (xy 354.885081 -185.750061) (xy 354.907922 -185.799804) (xy 354.923418 -185.852301)
			(xy 354.93125 -185.906474) (xy 354.931726 -185.933842) (xy 354.93124 -185.961093) (xy 354.923484 -186.015041)
			(xy 354.908129 -186.067336) (xy 354.885487 -186.116913) (xy 354.856021 -186.162763) (xy 354.82033 -186.203954)
			(xy 354.779139 -186.239645) (xy 354.733289 -186.269111) (xy 354.683712 -186.291753) (xy 354.631417 -186.307108)
			(xy 354.577469 -186.314864) (xy 354.522967 -186.314864) (xy 354.469019 -186.307108) (xy 354.416724 -186.291753)
			(xy 354.367147 -186.269111) (xy 354.321297 -186.239645) (xy 354.280106 -186.203954) (xy 354.244415 -186.162763)
			(xy 354.214949 -186.116913) (xy 354.192307 -186.067336) (xy 354.176952 -186.015041) (xy 354.169196 -185.961093)
			(xy 354.16871 -185.933842) (xy 354.169273 -185.904365) (xy 354.178336 -185.846113) (xy 354.196253 -185.789948)
			(xy 354.222597 -185.737209) (xy 354.256742 -185.68915) (xy 354.276914 -185.66765) (xy 354.283422 -185.660295)
			(xy 354.290882 -185.64215) (xy 354.291392 -185.632344) (xy 354.291392 -185.579004) (xy 354.284026 -185.572146)
			(xy 354.276683 -185.565622) (xy 354.258529 -185.558172) (xy 354.24872 -185.557668) (xy 354.216716 -185.557668)
			(xy 354.206899 -185.558128) (xy 354.188735 -185.565592) (xy 354.18141 -185.572146) (xy 354.159905 -185.592314)
			(xy 354.111847 -185.62646) (xy 354.059109 -185.652807) (xy 354.002946 -185.67073) (xy 353.944695 -185.6798)
			(xy 353.915218 -185.68035) (xy 353.887969 -185.679805) (xy 353.834026 -185.672052) (xy 353.781735 -185.656701)
			(xy 353.73216 -185.634065) (xy 353.686312 -185.604605) (xy 353.645123 -185.56892) (xy 353.609431 -185.527736)
			(xy 353.579963 -185.481892) (xy 353.55732 -185.432322) (xy 353.541961 -185.380033) (xy 353.534199 -185.326091)
			(xy 353.53371 -185.298842) (xy 353.534273 -185.269365) (xy 353.543336 -185.211113) (xy 353.561253 -185.154948)
			(xy 353.587597 -185.102209) (xy 353.621742 -185.05415) (xy 353.641914 -185.03265) (xy 353.648422 -185.025295)
			(xy 353.655882 -185.00715) (xy 353.656392 -184.997344) (xy 353.656392 -184.944004) (xy 353.650804 -184.938924)
			(xy 353.643346 -184.932375) (xy 353.62491 -184.925065) (xy 353.61499 -184.9247) (xy 353.582986 -184.924954)
			(xy 353.573122 -184.925523) (xy 353.554955 -184.933252) (xy 353.54768 -184.93994) (xy 353.526057 -184.960975)
			(xy 353.477395 -184.996621) (xy 353.423727 -185.024162) (xy 353.366393 -185.042911) (xy 353.306823 -185.052401)
			(xy 353.276662 -185.05297) (xy 353.249408 -185.052557) (xy 353.195456 -185.044795) (xy 353.143157 -185.029433)
			(xy 353.093577 -185.006785) (xy 353.047725 -184.977311) (xy 353.006535 -184.941612) (xy 352.970844 -184.900414)
			(xy 352.941379 -184.854556) (xy 352.918741 -184.804971) (xy 352.903389 -184.75267) (xy 352.895637 -184.698716)
			(xy 352.895154 -184.671462) (xy 352.895604 -184.644797) (xy 352.903045 -184.591989) (xy 352.917765 -184.54073)
			(xy 352.939475 -184.492019) (xy 352.967754 -184.446803) (xy 352.984562 -184.426098) (xy 352.990658 -184.418732)
			(xy 352.996754 -184.401714) (xy 352.994976 -184.31637) (xy 352.988372 -184.299352) (xy 352.982022 -184.292494)
			(xy 352.963583 -184.271317) (xy 352.93244 -184.224596) (xy 352.908474 -184.173819) (xy 352.892201 -184.120079)
			(xy 352.883971 -184.064537) (xy 352.88347 -184.036462) (xy 351.151952 -184.036462) (xy 356.266242 -189.150752)
			(xy 395.017244 -189.150752) (xy 395.017733 -189.123502) (xy 395.025495 -189.069557) (xy 395.040854 -189.017265)
			(xy 395.063497 -188.967691) (xy 395.092964 -188.921843) (xy 395.128654 -188.880654) (xy 395.169843 -188.844964)
			(xy 395.215691 -188.815497) (xy 395.265265 -188.792854) (xy 395.317557 -188.777495) (xy 395.371502 -188.769733)
			(xy 395.398752 -188.769244) (xy 395.426122 -188.769727) (xy 395.4803 -188.777539) (xy 395.532804 -188.793024)
			(xy 395.582551 -188.815862) (xy 395.628518 -188.845584) (xy 395.64945 -188.863224) (xy 395.656562 -188.86932)
			(xy 395.67358 -188.87567) (xy 395.758924 -188.87567) (xy 395.775942 -188.86932) (xy 395.783054 -188.863224)
			(xy 395.803987 -188.845583) (xy 395.849955 -188.815859) (xy 395.899701 -188.793013) (xy 395.952203 -188.777517)
			(xy 396.006381 -188.769688) (xy 396.061123 -188.769688) (xy 396.115301 -188.777517) (xy 396.167803 -188.793013)
			(xy 396.217549 -188.815859) (xy 396.263517 -188.845583) (xy 396.28445 -188.863224) (xy 396.291562 -188.86932)
			(xy 396.30858 -188.87567) (xy 396.393924 -188.87567) (xy 396.410942 -188.86932) (xy 396.418054 -188.863224)
			(xy 396.438996 -188.845597) (xy 396.484965 -188.815882) (xy 396.53471 -188.793044) (xy 396.587209 -188.77755)
			(xy 396.641383 -188.769719) (xy 396.668752 -188.769244) (xy 396.696 -188.769823) (xy 396.749942 -188.777571)
			(xy 396.802232 -188.792918) (xy 396.851806 -188.81555) (xy 396.897654 -188.845007) (xy 396.938843 -188.880689)
			(xy 396.974536 -188.921869) (xy 397.004004 -188.96771) (xy 397.026648 -189.017278) (xy 397.042008 -189.069564)
			(xy 397.04977 -189.123504) (xy 397.05026 -189.150752) (xy 399.032984 -189.150752) (xy 399.033433 -189.1235)
			(xy 399.041196 -189.069551) (xy 399.056557 -189.017256) (xy 399.079203 -188.96768) (xy 399.108673 -188.92183)
			(xy 399.144369 -188.88064) (xy 399.185562 -188.844949) (xy 399.231415 -188.815484) (xy 399.280994 -188.792843)
			(xy 399.33329 -188.777487) (xy 399.38724 -188.76973) (xy 399.414492 -188.769244) (xy 399.441863 -188.769704)
			(xy 399.496042 -188.777522) (xy 399.548546 -188.793012) (xy 399.598293 -188.815855) (xy 399.644259 -188.845582)
			(xy 399.66519 -188.863224) (xy 399.672302 -188.86932) (xy 399.68932 -188.87567) (xy 399.774664 -188.87567)
			(xy 399.791682 -188.86932) (xy 399.798794 -188.863224) (xy 399.819727 -188.845583) (xy 399.865695 -188.815859)
			(xy 399.915441 -188.793013) (xy 399.967943 -188.777517) (xy 400.022121 -188.769688) (xy 400.076863 -188.769688)
			(xy 400.131041 -188.777517) (xy 400.183543 -188.793013) (xy 400.233289 -188.815859) (xy 400.279257 -188.845583)
			(xy 400.30019 -188.863224) (xy 400.307302 -188.86932) (xy 400.32432 -188.87567) (xy 400.409664 -188.87567)
			(xy 400.426682 -188.86932) (xy 400.433794 -188.863224) (xy 400.454721 -188.845578) (xy 400.500695 -188.815866)
			(xy 400.550443 -188.793031) (xy 400.602945 -188.777542) (xy 400.657122 -188.769716) (xy 400.684492 -188.769244)
			(xy 400.711741 -188.769785) (xy 400.765684 -188.777539) (xy 400.817975 -188.792891) (xy 400.867549 -188.815528)
			(xy 400.913397 -188.844989) (xy 400.954586 -188.880674) (xy 400.990278 -188.921858) (xy 401.019745 -188.967702)
			(xy 401.042389 -189.017273) (xy 401.057749 -189.069561) (xy 401.065511 -189.123503) (xy 401.066 -189.150752)
			(xy 401.065529 -189.178086) (xy 401.057721 -189.232193) (xy 401.042271 -189.284632) (xy 401.019497 -189.334329)
			(xy 400.989863 -189.380268) (xy 400.972274 -189.401196) (xy 400.96567 -189.408562) (xy 400.959574 -189.426596)
			(xy 400.962622 -189.515496) (xy 400.969988 -189.532768) (xy 400.9771 -189.53988) (xy 400.997912 -189.561467)
			(xy 401.033165 -189.609972) (xy 401.060393 -189.663396) (xy 401.078925 -189.720423) (xy 401.088304 -189.779647)
			(xy 401.08886 -189.809628) (xy 401.08842 -189.836999) (xy 401.080597 -189.89118) (xy 401.065103 -189.943684)
			(xy 401.042255 -189.99343) (xy 401.012524 -190.039395) (xy 400.99488 -190.060326) (xy 400.988784 -190.067438)
			(xy 400.982434 -190.084456) (xy 400.982434 -190.1698) (xy 400.988784 -190.186818) (xy 400.99488 -190.19393)
			(xy 401.012548 -190.214841) (xy 401.042271 -190.260812) (xy 401.065114 -190.310562) (xy 401.080608 -190.363068)
			(xy 401.088434 -190.417249) (xy 401.088431 -190.471993) (xy 401.080599 -190.526173) (xy 401.065099 -190.578677)
			(xy 401.042251 -190.628425) (xy 401.012522 -190.674393) (xy 400.99488 -190.695326) (xy 400.988784 -190.702438)
			(xy 400.982434 -190.719456) (xy 400.982434 -190.8048) (xy 400.988784 -190.821818) (xy 400.99488 -190.82893)
			(xy 401.012548 -190.849841) (xy 401.042271 -190.895812) (xy 401.065114 -190.945562) (xy 401.080608 -190.998068)
			(xy 401.088434 -191.052249) (xy 401.088431 -191.106993) (xy 401.080599 -191.161173) (xy 401.065099 -191.213677)
			(xy 401.042251 -191.263425) (xy 401.012522 -191.309393) (xy 400.99488 -191.330326) (xy 400.988784 -191.337438)
			(xy 400.982434 -191.354456) (xy 400.982434 -191.4398) (xy 400.988784 -191.456818) (xy 400.99488 -191.46393)
			(xy 401.012497 -191.48488) (xy 401.042213 -191.530848) (xy 401.065053 -191.580591) (xy 401.080549 -191.633087)
			(xy 401.088383 -191.68726) (xy 401.08886 -191.714628) (xy 401.088471 -191.741884) (xy 401.080709 -191.79584)
			(xy 401.065347 -191.848142) (xy 401.042698 -191.897726) (xy 401.013222 -191.943581) (xy 400.977521 -191.984775)
			(xy 400.93632 -192.020468) (xy 400.890459 -192.049934) (xy 400.840871 -192.072574) (xy 400.788566 -192.087925)
			(xy 400.734608 -192.095676) (xy 400.707352 -192.096136) (xy 400.680648 -192.095706) (xy 400.627762 -192.088251)
			(xy 400.576432 -192.073494) (xy 400.527662 -192.051723) (xy 400.482405 -192.023363) (xy 400.441545 -191.98897)
			(xy 400.42338 -191.96939) (xy 400.416144 -191.962107) (xy 400.397544 -191.953459) (xy 400.387312 -191.952626)
			(xy 400.332956 -191.950594) (xy 400.324066 -191.959738) (xy 400.31713 -191.967446) (xy 400.309518 -191.98671)
			(xy 400.309334 -191.997076) (xy 400.310096 -192.029334) (xy 400.310885 -192.039673) (xy 400.319677 -192.058429)
			(xy 400.327114 -192.065656) (xy 400.346701 -192.083813) (xy 400.381094 -192.124674) (xy 400.409451 -192.169933)
			(xy 400.431218 -192.218705) (xy 400.445968 -192.270036) (xy 400.453414 -192.322924) (xy 400.45386 -192.349628)
			(xy 400.453471 -192.376884) (xy 400.445709 -192.43084) (xy 400.430347 -192.483142) (xy 400.407698 -192.532726)
			(xy 400.378222 -192.578581) (xy 400.342521 -192.619775) (xy 400.30132 -192.655468) (xy 400.255459 -192.684934)
			(xy 400.205871 -192.707574) (xy 400.153566 -192.722925) (xy 400.099608 -192.730676) (xy 400.072352 -192.731136)
			(xy 400.042875 -192.730581) (xy 399.984621 -192.721518) (xy 399.928456 -192.7036) (xy 399.875717 -192.677254)
			(xy 399.827659 -192.643106) (xy 399.80616 -192.622932) (xy 399.798841 -192.616378) (xy 399.780668 -192.608946)
			(xy 399.770854 -192.608454) (xy 399.717514 -192.608454) (xy 399.710656 -192.61582) (xy 399.704114 -192.623148)
			(xy 399.696674 -192.641314) (xy 399.696178 -192.651126) (xy 399.696178 -192.68313) (xy 399.696664 -192.692944)
			(xy 399.70411 -192.711108) (xy 399.710656 -192.718436) (xy 399.730847 -192.739919) (xy 399.76499 -192.787983)
			(xy 399.791333 -192.840727) (xy 399.809249 -192.896895) (xy 399.818314 -192.95515) (xy 399.81886 -192.984628)
			(xy 399.818374 -193.011879) (xy 399.810618 -193.065827) (xy 399.795263 -193.118122) (xy 399.772621 -193.167699)
			(xy 399.743155 -193.213549) (xy 399.707464 -193.25474) (xy 399.666273 -193.290431) (xy 399.620423 -193.319897)
			(xy 399.570846 -193.342539) (xy 399.518551 -193.357894) (xy 399.464603 -193.36565) (xy 399.410101 -193.36565)
			(xy 399.356153 -193.357894) (xy 399.303858 -193.342539) (xy 399.254281 -193.319897) (xy 399.208431 -193.290431)
			(xy 399.16724 -193.25474) (xy 399.131549 -193.213549) (xy 399.102083 -193.167699) (xy 399.079441 -193.118122)
			(xy 399.064086 -193.065827) (xy 399.05633 -193.011879) (xy 399.055844 -192.984628) (xy 399.056316 -192.957258)
			(xy 399.064131 -192.903079) (xy 399.079618 -192.850575) (xy 399.102458 -192.800828) (xy 399.132183 -192.754861)
			(xy 399.149824 -192.73393) (xy 399.15592 -192.726818) (xy 399.16227 -192.7098) (xy 399.16227 -192.624456)
			(xy 399.15592 -192.607438) (xy 399.149824 -192.600326) (xy 399.132187 -192.579392) (xy 399.102474 -192.53342)
			(xy 399.079638 -192.483673) (xy 399.064146 -192.431173) (xy 399.056318 -192.376997) (xy 399.055844 -192.349628)
			(xy 399.056294 -192.322058) (xy 399.064231 -192.267491) (xy 399.079943 -192.214636) (xy 399.103103 -192.164595)
			(xy 399.133228 -192.11841) (xy 399.151094 -192.097406) (xy 399.157698 -192.09004) (xy 399.164048 -192.07226)
			(xy 399.161508 -191.98336) (xy 399.154142 -191.965834) (xy 399.14703 -191.958976) (xy 399.126553 -191.937383)
			(xy 399.091827 -191.889064) (xy 399.065027 -191.835937) (xy 399.046804 -191.779292) (xy 399.0376 -191.720504)
			(xy 399.037048 -191.690752) (xy 399.037533 -191.663382) (xy 399.045344 -191.609204) (xy 399.060828 -191.5567)
			(xy 399.083666 -191.506953) (xy 399.113388 -191.460986) (xy 399.131028 -191.440054) (xy 399.137124 -191.432942)
			(xy 399.143474 -191.415924) (xy 399.143474 -191.33058) (xy 399.137124 -191.313562) (xy 399.131028 -191.30645)
			(xy 399.11334 -191.285555) (xy 399.083617 -191.239581) (xy 399.060775 -191.189828) (xy 399.045282 -191.137321)
			(xy 399.037458 -191.083137) (xy 399.037463 -191.028391) (xy 399.045298 -190.974209) (xy 399.0608 -190.921704)
			(xy 399.083652 -190.871956) (xy 399.113384 -190.825987) (xy 399.131028 -190.805054) (xy 399.137124 -190.797942)
			(xy 399.143474 -190.780924) (xy 399.143474 -190.69558) (xy 399.137124 -190.678562) (xy 399.131028 -190.67145)
			(xy 399.11334 -190.650555) (xy 399.083617 -190.604581) (xy 399.060775 -190.554828) (xy 399.045282 -190.502321)
			(xy 399.037458 -190.448137) (xy 399.037463 -190.393391) (xy 399.045298 -190.339209) (xy 399.0608 -190.286704)
			(xy 399.083652 -190.236956) (xy 399.113384 -190.190987) (xy 399.131028 -190.170054) (xy 399.137124 -190.162942)
			(xy 399.143474 -190.145924) (xy 399.143474 -190.06058) (xy 399.137124 -190.043562) (xy 399.131028 -190.03645)
			(xy 399.113403 -190.015506) (xy 399.083688 -189.969537) (xy 399.060849 -189.919793) (xy 399.045355 -189.867294)
			(xy 399.037524 -189.81312) (xy 399.037048 -189.785752) (xy 399.037518 -189.758618) (xy 399.045208 -189.704897)
			(xy 399.06044 -189.65281) (xy 399.082905 -189.603411) (xy 399.11215 -189.557697) (xy 399.129504 -189.536832)
			(xy 399.1356 -189.52972) (xy 399.141696 -189.512702) (xy 399.141188 -189.427358) (xy 399.134838 -189.41034)
			(xy 399.128488 -189.403228) (xy 399.110572 -189.382222) (xy 399.080381 -189.335999) (xy 399.057169 -189.285906)
			(xy 399.041422 -189.23299) (xy 399.033469 -189.178357) (xy 399.032984 -189.150752) (xy 397.05026 -189.150752)
			(xy 397.049769 -189.177721) (xy 397.042169 -189.231121) (xy 397.027115 -189.282915) (xy 397.004907 -189.332069)
			(xy 396.975989 -189.377599) (xy 396.95882 -189.398402) (xy 396.952724 -189.405514) (xy 396.946628 -189.422532)
			(xy 396.94739 -189.50813) (xy 396.953994 -189.524894) (xy 396.960344 -189.532006) (xy 396.978413 -189.553096)
			(xy 397.00892 -189.599501) (xy 397.032385 -189.649835) (xy 397.04831 -189.703037) (xy 397.056361 -189.757985)
			(xy 397.056864 -189.785752) (xy 397.056379 -189.813122) (xy 397.048567 -189.8673) (xy 397.033083 -189.919803)
			(xy 397.010245 -189.969551) (xy 396.980524 -190.015518) (xy 396.962884 -190.03645) (xy 396.956788 -190.043562)
			(xy 396.950438 -190.06058) (xy 396.950438 -190.145924) (xy 396.956788 -190.162942) (xy 396.962884 -190.170054)
			(xy 396.980477 -190.191025) (xy 397.010203 -190.236986) (xy 397.033051 -190.286726) (xy 397.04855 -190.339223)
			(xy 397.056383 -190.393396) (xy 397.056388 -190.448132) (xy 397.048566 -190.502307) (xy 397.033076 -190.554806)
			(xy 397.010238 -190.60455) (xy 396.980521 -190.650517) (xy 396.962884 -190.67145) (xy 396.956788 -190.678562)
			(xy 396.950438 -190.69558) (xy 396.950438 -190.780924) (xy 396.956788 -190.797942) (xy 396.962884 -190.805054)
			(xy 396.980477 -190.826025) (xy 397.010203 -190.871986) (xy 397.033051 -190.921726) (xy 397.04855 -190.974223)
			(xy 397.056383 -191.028396) (xy 397.056388 -191.083132) (xy 397.048566 -191.137307) (xy 397.033076 -191.189806)
			(xy 397.010238 -191.23955) (xy 396.980521 -191.285517) (xy 396.962884 -191.30645) (xy 396.956788 -191.313562)
			(xy 396.950438 -191.33058) (xy 396.950438 -191.415924) (xy 396.956788 -191.432942) (xy 396.962884 -191.440054)
			(xy 396.980513 -191.460995) (xy 397.010226 -191.506965) (xy 397.033065 -191.55671) (xy 397.048558 -191.609209)
			(xy 397.056389 -191.663383) (xy 397.056864 -191.690752) (xy 397.056355 -191.719491) (xy 397.047726 -191.776318)
			(xy 397.030672 -191.831209) (xy 397.005577 -191.88292) (xy 396.973011 -191.930283) (xy 396.95374 -191.95161)
			(xy 396.947136 -191.958722) (xy 396.940024 -191.976248) (xy 396.93977 -192.065402) (xy 396.946882 -192.082928)
			(xy 396.953486 -192.09004) (xy 396.972533 -192.111328) (xy 397.004699 -192.15853) (xy 397.029473 -192.209999)
			(xy 397.046302 -192.264584) (xy 397.054809 -192.321068) (xy 397.05534 -192.349628) (xy 397.054905 -192.377)
			(xy 397.047082 -192.431181) (xy 397.031586 -192.483685) (xy 397.008737 -192.533431) (xy 396.979005 -192.579396)
			(xy 396.96136 -192.600326) (xy 396.955264 -192.607438) (xy 396.948914 -192.624456) (xy 396.948914 -192.7098)
			(xy 396.955264 -192.726818) (xy 396.96136 -192.73393) (xy 396.979029 -192.75484) (xy 397.008753 -192.800812)
			(xy 397.031598 -192.850562) (xy 397.047092 -192.903067) (xy 397.054919 -192.957249) (xy 397.054916 -193.011993)
			(xy 397.047083 -193.066174) (xy 397.031583 -193.118678) (xy 397.008733 -193.168425) (xy 396.979003 -193.214393)
			(xy 396.96136 -193.235326) (xy 396.955264 -193.242438) (xy 396.948914 -193.259456) (xy 396.948914 -193.3448)
			(xy 396.955264 -193.361818) (xy 396.96136 -193.36893) (xy 396.979029 -193.38984) (xy 397.008753 -193.435812)
			(xy 397.031598 -193.485562) (xy 397.047092 -193.538067) (xy 397.054919 -193.592249) (xy 397.054916 -193.646993)
			(xy 397.047083 -193.701174) (xy 397.031583 -193.753678) (xy 397.008733 -193.803425) (xy 396.979003 -193.849393)
			(xy 396.96136 -193.870326) (xy 396.955264 -193.877438) (xy 396.948914 -193.894456) (xy 396.948914 -193.9798)
			(xy 396.955264 -193.996818) (xy 396.96136 -194.00393) (xy 396.979029 -194.02484) (xy 397.008753 -194.070812)
			(xy 397.031598 -194.120562) (xy 397.047092 -194.173067) (xy 397.054919 -194.227249) (xy 397.054916 -194.281993)
			(xy 397.047083 -194.336174) (xy 397.031583 -194.388678) (xy 397.008733 -194.438425) (xy 396.979003 -194.484393)
			(xy 396.96136 -194.505326) (xy 396.955264 -194.512438) (xy 396.948914 -194.529456) (xy 396.948914 -194.6148)
			(xy 396.955264 -194.631818) (xy 396.96136 -194.63893) (xy 396.979029 -194.65984) (xy 397.008753 -194.705812)
			(xy 397.031598 -194.755562) (xy 397.047092 -194.808067) (xy 397.054919 -194.862249) (xy 397.054916 -194.916993)
			(xy 397.047083 -194.971174) (xy 397.031583 -195.023678) (xy 397.008733 -195.073425) (xy 396.979003 -195.119393)
			(xy 396.96136 -195.140326) (xy 396.955264 -195.147438) (xy 396.948914 -195.164456) (xy 396.948914 -195.2498)
			(xy 396.955264 -195.266818) (xy 396.96136 -195.27393) (xy 396.978974 -195.294883) (xy 397.008691 -195.340849)
			(xy 397.031532 -195.390591) (xy 397.047029 -195.443088) (xy 397.054863 -195.49726) (xy 397.05534 -195.524628)
			(xy 397.054848 -195.551878) (xy 397.047089 -195.605824) (xy 397.031732 -195.658117) (xy 397.00909 -195.707692)
			(xy 396.979623 -195.753541) (xy 396.943933 -195.79473) (xy 396.902744 -195.830421) (xy 396.856896 -195.859888)
			(xy 396.807321 -195.88253) (xy 396.755028 -195.897888) (xy 396.701082 -195.905648) (xy 396.673832 -195.906136)
			(xy 396.646462 -195.905667) (xy 396.592282 -195.897852) (xy 396.539778 -195.882365) (xy 396.490031 -195.859523)
			(xy 396.444065 -195.829798) (xy 396.423134 -195.812156) (xy 396.416022 -195.80606) (xy 396.399004 -195.79971)
			(xy 396.31366 -195.79971) (xy 396.296642 -195.80606) (xy 396.28953 -195.812156) (xy 396.268597 -195.829797)
			(xy 396.222629 -195.859521) (xy 396.172883 -195.882367) (xy 396.120381 -195.897863) (xy 396.066203 -195.905692)
			(xy 396.011461 -195.905692) (xy 395.957283 -195.897863) (xy 395.904781 -195.882367) (xy 395.855035 -195.859521)
			(xy 395.809067 -195.829797) (xy 395.788134 -195.812156) (xy 395.781022 -195.80606) (xy 395.764004 -195.79971)
			(xy 395.67866 -195.79971) (xy 395.661642 -195.80606) (xy 395.65453 -195.812156) (xy 395.633592 -195.829788)
			(xy 395.587621 -195.859502) (xy 395.537876 -195.88234) (xy 395.485376 -195.897833) (xy 395.431201 -195.905662)
			(xy 395.403832 -195.906136) (xy 395.376581 -195.905615) (xy 395.322634 -195.897863) (xy 395.270339 -195.882513)
			(xy 395.220761 -195.859876) (xy 395.174909 -195.830414) (xy 395.133716 -195.794726) (xy 395.098022 -195.753539)
			(xy 395.068553 -195.707692) (xy 395.045908 -195.658118) (xy 395.03055 -195.605825) (xy 395.022789 -195.551879)
			(xy 395.022324 -195.524628) (xy 395.022801 -195.497258) (xy 395.030615 -195.443079) (xy 395.046101 -195.390576)
			(xy 395.068941 -195.340829) (xy 395.098664 -195.294862) (xy 395.116304 -195.27393) (xy 395.1224 -195.266818)
			(xy 395.12875 -195.2498) (xy 395.12875 -195.164456) (xy 395.1224 -195.147438) (xy 395.116304 -195.140326)
			(xy 395.098692 -195.119371) (xy 395.068968 -195.073406) (xy 395.046122 -195.023664) (xy 395.030624 -194.971165)
			(xy 395.022794 -194.91699) (xy 395.022791 -194.862252) (xy 395.030615 -194.808076) (xy 395.046107 -194.755576)
			(xy 395.068947 -194.705831) (xy 395.098666 -194.659863) (xy 395.116304 -194.63893) (xy 395.1224 -194.631818)
			(xy 395.12875 -194.6148) (xy 395.12875 -194.529456) (xy 395.1224 -194.512438) (xy 395.116304 -194.505326)
			(xy 395.098692 -194.484371) (xy 395.068968 -194.438406) (xy 395.046122 -194.388664) (xy 395.030624 -194.336165)
			(xy 395.022794 -194.28199) (xy 395.022791 -194.227252) (xy 395.030615 -194.173076) (xy 395.046107 -194.120576)
			(xy 395.068947 -194.070831) (xy 395.098666 -194.024863) (xy 395.116304 -194.00393) (xy 395.1224 -193.996818)
			(xy 395.12875 -193.9798) (xy 395.12875 -193.894456) (xy 395.1224 -193.877438) (xy 395.116304 -193.870326)
			(xy 395.098692 -193.849371) (xy 395.068968 -193.803406) (xy 395.046122 -193.753664) (xy 395.030624 -193.701165)
			(xy 395.022794 -193.64699) (xy 395.022791 -193.592252) (xy 395.030615 -193.538076) (xy 395.046107 -193.485576)
			(xy 395.068947 -193.435831) (xy 395.098666 -193.389863) (xy 395.116304 -193.36893) (xy 395.1224 -193.361818)
			(xy 395.12875 -193.3448) (xy 395.12875 -193.259456) (xy 395.1224 -193.242438) (xy 395.116304 -193.235326)
			(xy 395.098692 -193.214371) (xy 395.068968 -193.168406) (xy 395.046122 -193.118664) (xy 395.030624 -193.066165)
			(xy 395.022794 -193.01199) (xy 395.022791 -192.957252) (xy 395.030615 -192.903076) (xy 395.046107 -192.850576)
			(xy 395.068947 -192.800831) (xy 395.098666 -192.754863) (xy 395.116304 -192.73393) (xy 395.1224 -192.726818)
			(xy 395.12875 -192.7098) (xy 395.12875 -192.624456) (xy 395.1224 -192.607438) (xy 395.116304 -192.600326)
			(xy 395.098692 -192.579371) (xy 395.068968 -192.533406) (xy 395.046122 -192.483664) (xy 395.030624 -192.431165)
			(xy 395.022794 -192.37699) (xy 395.022791 -192.322252) (xy 395.030615 -192.268076) (xy 395.046107 -192.215576)
			(xy 395.068947 -192.165831) (xy 395.098666 -192.119863) (xy 395.116304 -192.09893) (xy 395.1224 -192.091818)
			(xy 395.12875 -192.0748) (xy 395.12875 -191.989456) (xy 395.1224 -191.972438) (xy 395.116304 -191.965326)
			(xy 395.098692 -191.944371) (xy 395.068968 -191.898406) (xy 395.046122 -191.848664) (xy 395.030624 -191.796165)
			(xy 395.022794 -191.74199) (xy 395.022791 -191.687252) (xy 395.030615 -191.633076) (xy 395.046107 -191.580576)
			(xy 395.068947 -191.530831) (xy 395.098666 -191.484863) (xy 395.116304 -191.46393) (xy 395.1224 -191.456818)
			(xy 395.12875 -191.4398) (xy 395.12875 -191.354456) (xy 395.1224 -191.337438) (xy 395.116304 -191.330326)
			(xy 395.098692 -191.309371) (xy 395.068968 -191.263406) (xy 395.046122 -191.213664) (xy 395.030624 -191.161165)
			(xy 395.022794 -191.10699) (xy 395.022791 -191.052252) (xy 395.030615 -190.998076) (xy 395.046107 -190.945576)
			(xy 395.068947 -190.895831) (xy 395.098666 -190.849863) (xy 395.116304 -190.82893) (xy 395.1224 -190.821818)
			(xy 395.12875 -190.8048) (xy 395.12875 -190.719456) (xy 395.1224 -190.702438) (xy 395.116304 -190.695326)
			(xy 395.098692 -190.674371) (xy 395.068968 -190.628406) (xy 395.046122 -190.578664) (xy 395.030624 -190.526165)
			(xy 395.022794 -190.47199) (xy 395.022791 -190.417252) (xy 395.030615 -190.363076) (xy 395.046107 -190.310576)
			(xy 395.068947 -190.260831) (xy 395.098666 -190.214863) (xy 395.116304 -190.19393) (xy 395.1224 -190.186818)
			(xy 395.12875 -190.1698) (xy 395.12875 -190.084456) (xy 395.1224 -190.067438) (xy 395.116304 -190.060326)
			(xy 395.098664 -190.039394) (xy 395.068952 -189.993422) (xy 395.046116 -189.943674) (xy 395.030626 -189.891173)
			(xy 395.022798 -189.836997) (xy 395.022324 -189.809628) (xy 395.022851 -189.781268) (xy 395.03124 -189.725173)
			(xy 395.04785 -189.670941) (xy 395.072315 -189.619771) (xy 395.104095 -189.572791) (xy 395.122908 -189.551564)
			(xy 395.129512 -189.544452) (xy 395.13637 -189.526672) (xy 395.135608 -189.437772) (xy 395.128496 -189.420246)
			(xy 395.121638 -189.413134) (xy 395.102126 -189.39175) (xy 395.069135 -189.344185) (xy 395.043718 -189.292177)
			(xy 395.026459 -189.236924) (xy 395.017756 -189.179696) (xy 395.017244 -189.150752) (xy 356.266242 -189.150752)
			(xy 358.148128 -191.032638) (xy 358.151938 -191.03594) (xy 359.709653 -192.311782) (xy 361.16387 -192.311782)
			(xy 361.164308 -192.284411) (xy 361.17213 -192.23023) (xy 361.187625 -192.177726) (xy 361.210473 -192.127979)
			(xy 361.240205 -192.082014) (xy 361.25785 -192.061084) (xy 361.263946 -192.053972) (xy 361.270296 -192.036954)
			(xy 361.270296 -191.95161) (xy 361.263946 -191.934592) (xy 361.25785 -191.92748) (xy 361.240191 -191.906562)
			(xy 361.210465 -191.860592) (xy 361.187619 -191.810844) (xy 361.172123 -191.758339) (xy 361.164296 -191.704158)
			(xy 361.164298 -191.649415) (xy 361.172129 -191.595234) (xy 361.187629 -191.542731) (xy 361.210478 -191.492984)
			(xy 361.240207 -191.447016) (xy 361.25785 -191.426084) (xy 361.263946 -191.418972) (xy 361.270296 -191.401954)
			(xy 361.270296 -191.31661) (xy 361.263946 -191.299592) (xy 361.25785 -191.29248) (xy 361.240191 -191.271562)
			(xy 361.210465 -191.225592) (xy 361.187619 -191.175844) (xy 361.172123 -191.123339) (xy 361.164296 -191.069158)
			(xy 361.164298 -191.014415) (xy 361.172129 -190.960234) (xy 361.187629 -190.907731) (xy 361.210478 -190.857984)
			(xy 361.240207 -190.812016) (xy 361.25785 -190.791084) (xy 361.263946 -190.783972) (xy 361.270296 -190.766954)
			(xy 361.270296 -190.68161) (xy 361.263946 -190.664592) (xy 361.25785 -190.65748) (xy 361.240243 -190.636522)
			(xy 361.210524 -190.590557) (xy 361.187682 -190.540816) (xy 361.172183 -190.488321) (xy 361.164348 -190.43415)
			(xy 361.16387 -190.406782) (xy 361.164354 -190.378148) (xy 361.172906 -190.321521) (xy 361.189828 -190.26681)
			(xy 361.214741 -190.215244) (xy 361.247085 -190.167983) (xy 361.266232 -190.146686) (xy 361.272836 -190.139574)
			(xy 361.279694 -190.122048) (xy 361.280202 -190.033656) (xy 361.273344 -190.015876) (xy 361.26674 -190.008764)
			(xy 361.247972 -189.987544) (xy 361.216273 -189.940595) (xy 361.19187 -189.889473) (xy 361.175299 -189.835304)
			(xy 361.166924 -189.779278) (xy 361.16641 -189.750954) (xy 361.166835 -189.723701) (xy 361.174598 -189.66975)
			(xy 361.18996 -189.617453) (xy 361.212608 -189.567874) (xy 361.242081 -189.522023) (xy 361.277779 -189.480833)
			(xy 361.318975 -189.445142) (xy 361.364831 -189.415677) (xy 361.414413 -189.393038) (xy 361.466713 -189.377685)
			(xy 361.520665 -189.369931) (xy 361.547918 -189.369446) (xy 361.575289 -189.36989) (xy 361.62947 -189.377712)
			(xy 361.681973 -189.393205) (xy 361.73172 -189.416052) (xy 361.777685 -189.445782) (xy 361.798616 -189.463426)
			(xy 361.805728 -189.469522) (xy 361.822746 -189.475872) (xy 361.90809 -189.475872) (xy 361.925108 -189.469522)
			(xy 361.93222 -189.463426) (xy 361.953153 -189.445785) (xy 361.999121 -189.416061) (xy 362.048867 -189.393215)
			(xy 362.101369 -189.377719) (xy 362.155547 -189.36989) (xy 362.210289 -189.36989) (xy 362.264467 -189.377719)
			(xy 362.316969 -189.393215) (xy 362.366715 -189.416061) (xy 362.412683 -189.445785) (xy 362.433616 -189.463426)
			(xy 362.440728 -189.469522) (xy 362.457746 -189.475872) (xy 362.54309 -189.475872) (xy 362.560108 -189.469522)
			(xy 362.56722 -189.463426) (xy 362.588175 -189.445815) (xy 362.634141 -189.416098) (xy 362.683883 -189.393256)
			(xy 362.736378 -189.377759) (xy 362.79055 -189.369924) (xy 362.817918 -189.369446) (xy 362.845168 -189.369961)
			(xy 362.899112 -189.377719) (xy 362.951403 -189.393074) (xy 363.000978 -189.415714) (xy 363.046826 -189.445178)
			(xy 363.088014 -189.480866) (xy 363.123706 -189.522052) (xy 363.153173 -189.567898) (xy 363.175816 -189.61747)
			(xy 363.191175 -189.669761) (xy 363.198937 -189.723704) (xy 363.199426 -189.750954) (xy 365.18215 -189.750954)
			(xy 365.182635 -189.723704) (xy 365.190397 -189.669758) (xy 365.205755 -189.617466) (xy 365.228399 -189.567891)
			(xy 365.257866 -189.522043) (xy 365.293557 -189.480854) (xy 365.334746 -189.445164) (xy 365.380595 -189.415697)
			(xy 365.43017 -189.393054) (xy 365.482462 -189.377696) (xy 365.536408 -189.369935) (xy 365.563658 -189.369446)
			(xy 365.591028 -189.369925) (xy 365.645207 -189.377738) (xy 365.69771 -189.393224) (xy 365.747457 -189.416063)
			(xy 365.793424 -189.445785) (xy 365.814356 -189.463426) (xy 365.821468 -189.469522) (xy 365.838486 -189.475872)
			(xy 365.92383 -189.475872) (xy 365.940848 -189.469522) (xy 365.94796 -189.463426) (xy 365.9689 -189.445796)
			(xy 366.01487 -189.416082) (xy 366.064616 -189.393244) (xy 366.117115 -189.377751) (xy 366.171289 -189.369921)
			(xy 366.198658 -189.369446) (xy 366.225906 -189.370017) (xy 366.279848 -189.377767) (xy 366.332139 -189.393114)
			(xy 366.381713 -189.415747) (xy 366.427561 -189.445205) (xy 366.46875 -189.480887) (xy 366.504443 -189.522069)
			(xy 366.533911 -189.56791) (xy 366.556555 -189.617479) (xy 366.571915 -189.669766) (xy 366.579677 -189.723706)
			(xy 366.580166 -189.750954) (xy 366.579696 -189.778088) (xy 366.572006 -189.831809) (xy 366.556774 -189.883895)
			(xy 366.534308 -189.933295) (xy 366.505064 -189.979009) (xy 366.48771 -189.999874) (xy 366.481614 -190.006986)
			(xy 366.475518 -190.024004) (xy 366.476026 -190.109348) (xy 366.482376 -190.126366) (xy 366.488726 -190.133478)
			(xy 366.506647 -190.15448) (xy 366.536837 -190.200704) (xy 366.560047 -190.250798) (xy 366.575793 -190.303715)
			(xy 366.583745 -190.358349) (xy 366.58423 -190.385954) (xy 366.583754 -190.413324) (xy 366.575941 -190.467503)
			(xy 366.560455 -190.520007) (xy 366.537615 -190.569754) (xy 366.507891 -190.615721) (xy 366.49025 -190.636652)
			(xy 366.484154 -190.643764) (xy 366.477804 -190.660782) (xy 366.477804 -190.746126) (xy 366.484154 -190.763144)
			(xy 366.49025 -190.770256) (xy 366.507847 -190.791225) (xy 366.537575 -190.837186) (xy 366.560424 -190.886926)
			(xy 366.575925 -190.939423) (xy 366.583759 -190.993597) (xy 366.583764 -191.048334) (xy 366.57594 -191.10251)
			(xy 366.560449 -191.155009) (xy 366.537608 -191.204753) (xy 366.507888 -191.25072) (xy 366.49025 -191.271652)
			(xy 366.484154 -191.278764) (xy 366.477804 -191.295782) (xy 366.477804 -191.381126) (xy 366.484154 -191.398144)
			(xy 366.49025 -191.405256) (xy 366.507874 -191.4262) (xy 366.53759 -191.472169) (xy 366.56043 -191.521913)
			(xy 366.575924 -191.574412) (xy 366.583755 -191.628586) (xy 366.58423 -191.655954) (xy 366.583681 -191.685431)
			(xy 366.574617 -191.743685) (xy 366.556697 -191.79985) (xy 366.530349 -191.85259) (xy 366.496201 -191.900647)
			(xy 366.476026 -191.922146) (xy 366.469469 -191.929463) (xy 366.462039 -191.947637) (xy 366.461548 -191.957452)
			(xy 366.461548 -192.010792) (xy 366.464088 -192.013078) (xy 366.470946 -192.019428) (xy 366.487964 -192.02654)
			(xy 366.573816 -192.029334) (xy 366.591342 -192.023492) (xy 366.598454 -192.017396) (xy 366.61903 -192.000962)
			(xy 366.663881 -191.973366) (xy 366.712104 -191.952208) (xy 366.762781 -191.937893) (xy 366.814947 -191.930693)
			(xy 366.841278 -191.930274) (xy 366.868529 -191.930776) (xy 366.922478 -191.938529) (xy 366.974774 -191.953882)
			(xy 367.024353 -191.97652) (xy 367.070205 -192.005984) (xy 367.111398 -192.041674) (xy 367.147092 -192.082863)
			(xy 367.176561 -192.128712) (xy 367.199204 -192.178288) (xy 367.214562 -192.230583) (xy 367.222321 -192.284531)
			(xy 367.222786 -192.311782) (xy 367.222313 -192.339152) (xy 367.214497 -192.393331) (xy 367.19901 -192.445834)
			(xy 367.17617 -192.495581) (xy 367.146447 -192.541548) (xy 367.128806 -192.56248) (xy 367.12271 -192.569592)
			(xy 367.11636 -192.58661) (xy 367.11636 -192.671954) (xy 367.12271 -192.688972) (xy 367.128806 -192.696084)
			(xy 367.146428 -192.717032) (xy 367.176151 -192.762998) (xy 367.198995 -192.812742) (xy 367.214491 -192.865241)
			(xy 367.222321 -192.919417) (xy 367.222323 -192.974156) (xy 367.214497 -193.028332) (xy 367.199005 -193.080833)
			(xy 367.176164 -193.130579) (xy 367.146444 -193.176547) (xy 367.128806 -193.19748) (xy 367.12271 -193.204592)
			(xy 367.11636 -193.22161) (xy 367.11636 -193.306954) (xy 367.12271 -193.323972) (xy 367.128806 -193.331084)
			(xy 367.146428 -193.352032) (xy 367.176151 -193.397998) (xy 367.198995 -193.447742) (xy 367.214491 -193.500241)
			(xy 367.222321 -193.554417) (xy 367.222323 -193.609156) (xy 367.214497 -193.663332) (xy 367.199005 -193.715833)
			(xy 367.176164 -193.765579) (xy 367.146444 -193.811547) (xy 367.128806 -193.83248) (xy 367.12271 -193.839592)
			(xy 367.11636 -193.85661) (xy 367.11636 -193.941954) (xy 367.12271 -193.958972) (xy 367.128806 -193.966084)
			(xy 367.146428 -193.987032) (xy 367.176151 -194.032998) (xy 367.198995 -194.082742) (xy 367.214491 -194.135241)
			(xy 367.222321 -194.189417) (xy 367.222323 -194.244156) (xy 367.214497 -194.298332) (xy 367.199005 -194.350833)
			(xy 367.176164 -194.400579) (xy 367.146444 -194.446547) (xy 367.128806 -194.46748) (xy 367.12271 -194.474592)
			(xy 367.11636 -194.49161) (xy 367.11636 -194.576954) (xy 367.12271 -194.593972) (xy 367.128806 -194.601084)
			(xy 367.146428 -194.622032) (xy 367.176151 -194.667998) (xy 367.198995 -194.717742) (xy 367.214491 -194.770241)
			(xy 367.222321 -194.824417) (xy 367.222323 -194.879156) (xy 367.214497 -194.933332) (xy 367.199005 -194.985833)
			(xy 367.176164 -195.035579) (xy 367.146444 -195.081547) (xy 367.128806 -195.10248) (xy 367.12271 -195.109592)
			(xy 367.11636 -195.12661) (xy 367.11636 -195.211954) (xy 367.12271 -195.228972) (xy 367.128806 -195.236084)
			(xy 367.146428 -195.257032) (xy 367.176151 -195.302998) (xy 367.198995 -195.352742) (xy 367.214491 -195.405241)
			(xy 367.222321 -195.459417) (xy 367.222323 -195.514156) (xy 367.214497 -195.568332) (xy 367.199005 -195.620833)
			(xy 367.176164 -195.670579) (xy 367.146444 -195.716547) (xy 367.128806 -195.73748) (xy 367.12271 -195.744592)
			(xy 367.11636 -195.76161) (xy 367.11636 -195.846954) (xy 367.12271 -195.863972) (xy 367.128806 -195.871084)
			(xy 367.146452 -195.89201) (xy 367.176163 -195.937985) (xy 367.198997 -195.987734) (xy 367.214487 -196.040236)
			(xy 367.222313 -196.094412) (xy 367.222786 -196.121782) (xy 367.222328 -196.149035) (xy 367.214573 -196.202988)
			(xy 367.199218 -196.255287) (xy 367.176576 -196.304868) (xy 367.147108 -196.350723) (xy 367.111413 -196.391916)
			(xy 367.07022 -196.42761) (xy 367.024365 -196.457078) (xy 366.974783 -196.479719) (xy 366.922484 -196.495074)
			(xy 366.868531 -196.502828) (xy 366.841278 -196.50329) (xy 366.813907 -196.502839) (xy 366.759727 -196.495018)
			(xy 366.707224 -196.479526) (xy 366.657477 -196.45668) (xy 366.611511 -196.426953) (xy 366.59058 -196.40931)
			(xy 366.583468 -196.403214) (xy 366.56645 -196.396864) (xy 366.481106 -196.396864) (xy 366.464088 -196.403214)
			(xy 366.456976 -196.40931) (xy 366.436027 -196.426928) (xy 366.390059 -196.456643) (xy 366.340316 -196.479483)
			(xy 366.287819 -196.494979) (xy 366.233646 -196.502813) (xy 366.206278 -196.50329) (xy 366.179025 -196.502843)
			(xy 366.125075 -196.495083) (xy 366.072779 -196.479724) (xy 366.0232 -196.457079) (xy 365.977349 -196.427609)
			(xy 365.936159 -196.391913) (xy 365.900467 -196.350719) (xy 365.871002 -196.304865) (xy 365.848362 -196.255284)
			(xy 365.833009 -196.202986) (xy 365.825255 -196.149035) (xy 365.82477 -196.121782) (xy 365.825279 -196.092303)
			(xy 365.834353 -196.034047) (xy 365.852282 -195.977882) (xy 365.878638 -195.925143) (xy 365.912795 -195.877087)
			(xy 365.932974 -195.85559) (xy 365.939516 -195.848261) (xy 365.946955 -195.830096) (xy 365.947452 -195.820284)
			(xy 365.947452 -195.766944) (xy 365.940086 -195.760086) (xy 365.932752 -195.75355) (xy 365.914591 -195.746106)
			(xy 365.90478 -195.745608) (xy 365.872776 -195.745608) (xy 365.862961 -195.746089) (xy 365.844797 -195.753537)
			(xy 365.83747 -195.760086) (xy 365.815989 -195.78028) (xy 365.767924 -195.81442) (xy 365.71518 -195.840762)
			(xy 365.659012 -195.858679) (xy 365.600756 -195.867743) (xy 365.571278 -195.86829) (xy 365.544025 -195.867843)
			(xy 365.490075 -195.860083) (xy 365.437779 -195.844724) (xy 365.3882 -195.822079) (xy 365.342349 -195.792609)
			(xy 365.301159 -195.756913) (xy 365.265467 -195.715719) (xy 365.236002 -195.669865) (xy 365.213362 -195.620284)
			(xy 365.198009 -195.567986) (xy 365.190255 -195.514035) (xy 365.18977 -195.486782) (xy 365.190208 -195.459411)
			(xy 365.19803 -195.40523) (xy 365.213525 -195.352726) (xy 365.236373 -195.302979) (xy 365.266105 -195.257014)
			(xy 365.28375 -195.236084) (xy 365.289846 -195.228972) (xy 365.296196 -195.211954) (xy 365.296196 -195.12661)
			(xy 365.289846 -195.109592) (xy 365.28375 -195.10248) (xy 365.266091 -195.081562) (xy 365.236365 -195.035592)
			(xy 365.213519 -194.985844) (xy 365.198023 -194.933339) (xy 365.190196 -194.879158) (xy 365.190198 -194.824415)
			(xy 365.198029 -194.770234) (xy 365.213529 -194.717731) (xy 365.236378 -194.667984) (xy 365.266107 -194.622016)
			(xy 365.28375 -194.601084) (xy 365.289846 -194.593972) (xy 365.296196 -194.576954) (xy 365.296196 -194.49161)
			(xy 365.289846 -194.474592) (xy 365.28375 -194.46748) (xy 365.266091 -194.446562) (xy 365.236365 -194.400592)
			(xy 365.213519 -194.350844) (xy 365.198023 -194.298339) (xy 365.190196 -194.244158) (xy 365.190198 -194.189415)
			(xy 365.198029 -194.135234) (xy 365.213529 -194.082731) (xy 365.236378 -194.032984) (xy 365.266107 -193.987016)
			(xy 365.28375 -193.966084) (xy 365.289846 -193.958972) (xy 365.296196 -193.941954) (xy 365.296196 -193.85661)
			(xy 365.289846 -193.839592) (xy 365.28375 -193.83248) (xy 365.266091 -193.811562) (xy 365.236365 -193.765592)
			(xy 365.213519 -193.715844) (xy 365.198023 -193.663339) (xy 365.190196 -193.609158) (xy 365.190198 -193.554415)
			(xy 365.198029 -193.500234) (xy 365.213529 -193.447731) (xy 365.236378 -193.397984) (xy 365.266107 -193.352016)
			(xy 365.28375 -193.331084) (xy 365.289846 -193.323972) (xy 365.296196 -193.306954) (xy 365.296196 -193.22161)
			(xy 365.289846 -193.204592) (xy 365.28375 -193.19748) (xy 365.266143 -193.176522) (xy 365.236424 -193.130557)
			(xy 365.213582 -193.080816) (xy 365.198083 -193.028321) (xy 365.190248 -192.97415) (xy 365.18977 -192.946782)
			(xy 365.190317 -192.918496) (xy 365.198672 -192.862543) (xy 365.215196 -192.808438) (xy 365.239527 -192.757364)
			(xy 365.271132 -192.710443) (xy 365.289846 -192.689226) (xy 365.296196 -192.682114) (xy 365.303054 -192.664588)
			(xy 365.302546 -192.576196) (xy 365.295688 -192.558416) (xy 365.289084 -192.551304) (xy 365.269864 -192.530013)
			(xy 365.237402 -192.482726) (xy 365.212384 -192.431113) (xy 365.195371 -192.376337) (xy 365.186749 -192.319632)
			(xy 365.186214 -192.290954) (xy 365.186708 -192.263585) (xy 365.194519 -192.209407) (xy 365.210001 -192.156904)
			(xy 365.232837 -192.107156) (xy 365.262555 -192.061188) (xy 365.280194 -192.040256) (xy 365.28629 -192.033144)
			(xy 365.29264 -192.016126) (xy 365.29264 -191.930782) (xy 365.28629 -191.913764) (xy 365.280194 -191.906652)
			(xy 365.26251 -191.885755) (xy 365.232789 -191.83978) (xy 365.209949 -191.790028) (xy 365.194457 -191.737521)
			(xy 365.186634 -191.683338) (xy 365.186639 -191.628593) (xy 365.194472 -191.574412) (xy 365.209973 -191.521907)
			(xy 365.232823 -191.472159) (xy 365.262551 -191.426189) (xy 365.280194 -191.405256) (xy 365.28629 -191.398144)
			(xy 365.29264 -191.381126) (xy 365.29264 -191.295782) (xy 365.28629 -191.278764) (xy 365.280194 -191.271652)
			(xy 365.26251 -191.250755) (xy 365.232789 -191.20478) (xy 365.209949 -191.155028) (xy 365.194457 -191.102521)
			(xy 365.186634 -191.048338) (xy 365.186639 -190.993593) (xy 365.194472 -190.939412) (xy 365.209973 -190.886907)
			(xy 365.232823 -190.837159) (xy 365.262551 -190.791189) (xy 365.280194 -190.770256) (xy 365.28629 -190.763144)
			(xy 365.29264 -190.746126) (xy 365.29264 -190.660782) (xy 365.28629 -190.643764) (xy 365.280194 -190.636652)
			(xy 365.262565 -190.615712) (xy 365.232852 -190.569741) (xy 365.210014 -190.519996) (xy 365.194521 -190.467497)
			(xy 365.18669 -190.413323) (xy 365.186214 -190.385954) (xy 365.186693 -190.35882) (xy 365.194382 -190.3051)
			(xy 365.209612 -190.253014) (xy 365.232075 -190.203614) (xy 365.261318 -190.157899) (xy 365.27867 -190.137034)
			(xy 365.284766 -190.129922) (xy 365.290862 -190.112904) (xy 365.290354 -190.02756) (xy 365.284004 -190.010542)
			(xy 365.277654 -190.00343) (xy 365.259734 -189.982428) (xy 365.229544 -189.936203) (xy 365.206334 -189.886109)
			(xy 365.190588 -189.833193) (xy 365.182635 -189.778559) (xy 365.18215 -189.750954) (xy 363.199426 -189.750954)
			(xy 363.198944 -189.777923) (xy 363.191343 -189.831324) (xy 363.176288 -189.883118) (xy 363.154077 -189.932272)
			(xy 363.125157 -189.977802) (xy 363.107986 -189.998604) (xy 363.10189 -190.005716) (xy 363.095794 -190.022734)
			(xy 363.096556 -190.108332) (xy 363.10316 -190.125096) (xy 363.10951 -190.132208) (xy 363.127574 -190.153302)
			(xy 363.158084 -190.199705) (xy 363.181549 -190.250038) (xy 363.197476 -190.30324) (xy 363.205528 -190.358187)
			(xy 363.20603 -190.385954) (xy 363.205554 -190.413324) (xy 363.197741 -190.467503) (xy 363.182255 -190.520007)
			(xy 363.159415 -190.569754) (xy 363.129691 -190.615721) (xy 363.11205 -190.636652) (xy 363.105954 -190.643764)
			(xy 363.099604 -190.660782) (xy 363.099604 -190.746126) (xy 363.105954 -190.763144) (xy 363.11205 -190.770256)
			(xy 363.129647 -190.791225) (xy 363.159375 -190.837186) (xy 363.182224 -190.886926) (xy 363.197725 -190.939423)
			(xy 363.205559 -190.993597) (xy 363.205564 -191.048334) (xy 363.19774 -191.10251) (xy 363.182249 -191.155009)
			(xy 363.159408 -191.204753) (xy 363.129688 -191.25072) (xy 363.11205 -191.271652) (xy 363.105954 -191.278764)
			(xy 363.099604 -191.295782) (xy 363.099604 -191.381126) (xy 363.105954 -191.398144) (xy 363.11205 -191.405256)
			(xy 363.129647 -191.426225) (xy 363.159375 -191.472186) (xy 363.182224 -191.521926) (xy 363.197725 -191.574423)
			(xy 363.205559 -191.628597) (xy 363.205564 -191.683334) (xy 363.19774 -191.73751) (xy 363.182249 -191.790009)
			(xy 363.159408 -191.839753) (xy 363.129688 -191.88572) (xy 363.11205 -191.906652) (xy 363.105954 -191.913764)
			(xy 363.099604 -191.930782) (xy 363.099604 -192.016126) (xy 363.105954 -192.033144) (xy 363.11205 -192.040256)
			(xy 363.129674 -192.0612) (xy 363.15939 -192.107169) (xy 363.18223 -192.156913) (xy 363.197724 -192.209412)
			(xy 363.205555 -192.263586) (xy 363.20603 -192.290954) (xy 363.205462 -192.319965) (xy 363.1967 -192.377321)
			(xy 363.179357 -192.432689) (xy 363.153831 -192.484793) (xy 363.120711 -192.532433) (xy 363.101128 -192.553844)
			(xy 363.09427 -192.560956) (xy 363.087158 -192.578482) (xy 363.085888 -192.666874) (xy 363.092492 -192.6844)
			(xy 363.099096 -192.691766) (xy 363.117437 -192.712859) (xy 363.148343 -192.759433) (xy 363.172118 -192.81002)
			(xy 363.188253 -192.863536) (xy 363.196402 -192.918834) (xy 363.196886 -192.946782) (xy 363.196413 -192.974152)
			(xy 363.188597 -193.028331) (xy 363.17311 -193.080834) (xy 363.15027 -193.130581) (xy 363.120547 -193.176548)
			(xy 363.102906 -193.19748) (xy 363.09681 -193.204592) (xy 363.09046 -193.22161) (xy 363.09046 -193.306954)
			(xy 363.09681 -193.323972) (xy 363.102906 -193.331084) (xy 363.120552 -193.35201) (xy 363.150263 -193.397985)
			(xy 363.173097 -193.447734) (xy 363.188587 -193.500236) (xy 363.196413 -193.554412) (xy 363.196886 -193.581782)
			(xy 363.1964 -193.609033) (xy 363.188644 -193.662981) (xy 363.173289 -193.715276) (xy 363.150647 -193.764853)
			(xy 363.121181 -193.810703) (xy 363.08549 -193.851894) (xy 363.044299 -193.887585) (xy 362.998449 -193.917051)
			(xy 362.948872 -193.939693) (xy 362.896577 -193.955048) (xy 362.842629 -193.962804) (xy 362.788127 -193.962804)
			(xy 362.734179 -193.955048) (xy 362.681884 -193.939693) (xy 362.632307 -193.917051) (xy 362.586457 -193.887585)
			(xy 362.545266 -193.851894) (xy 362.509575 -193.810703) (xy 362.480109 -193.764853) (xy 362.457467 -193.715276)
			(xy 362.442112 -193.662981) (xy 362.434356 -193.609033) (xy 362.43387 -193.581782) (xy 362.434379 -193.552303)
			(xy 362.443453 -193.494047) (xy 362.461382 -193.437882) (xy 362.487738 -193.385143) (xy 362.521895 -193.337087)
			(xy 362.542074 -193.31559) (xy 362.548616 -193.308261) (xy 362.556055 -193.290096) (xy 362.556552 -193.280284)
			(xy 362.556552 -193.226944) (xy 362.549186 -193.220086) (xy 362.541852 -193.21355) (xy 362.523691 -193.206106)
			(xy 362.51388 -193.205608) (xy 362.481876 -193.205608) (xy 362.472061 -193.206089) (xy 362.453897 -193.213537)
			(xy 362.44657 -193.220086) (xy 362.425089 -193.24028) (xy 362.377024 -193.27442) (xy 362.32428 -193.300762)
			(xy 362.268112 -193.318679) (xy 362.209856 -193.327743) (xy 362.180378 -193.32829) (xy 362.153125 -193.327843)
			(xy 362.099175 -193.320083) (xy 362.046879 -193.304724) (xy 361.9973 -193.282079) (xy 361.951449 -193.252609)
			(xy 361.910259 -193.216913) (xy 361.874567 -193.175719) (xy 361.845102 -193.129865) (xy 361.822462 -193.080284)
			(xy 361.807109 -193.027986) (xy 361.799355 -192.974035) (xy 361.79887 -192.946782) (xy 361.799306 -192.920708)
			(xy 361.8064 -192.869043) (xy 361.820466 -192.818828) (xy 361.841242 -192.770996) (xy 361.868342 -192.726441)
			(xy 361.901258 -192.685994) (xy 361.920028 -192.66789) (xy 361.927239 -192.66057) (xy 361.935614 -192.641823)
			(xy 361.936284 -192.631568) (xy 361.937046 -192.576958) (xy 361.928156 -192.56883) (xy 361.920505 -192.562272)
			(xy 361.901656 -192.555196) (xy 361.89158 -192.555114) (xy 361.859576 -192.55613) (xy 361.849618 -192.556927)
			(xy 361.831444 -192.565178) (xy 361.82427 -192.572132) (xy 361.806179 -192.590915) (xy 361.765726 -192.623827)
			(xy 361.721168 -192.650923) (xy 361.673335 -192.671699) (xy 361.623118 -192.685768) (xy 361.571453 -192.692867)
			(xy 361.545378 -192.69329) (xy 361.518125 -192.692843) (xy 361.464175 -192.685083) (xy 361.411879 -192.669724)
			(xy 361.3623 -192.647079) (xy 361.316449 -192.617609) (xy 361.275259 -192.581913) (xy 361.239567 -192.540719)
			(xy 361.210102 -192.494865) (xy 361.187462 -192.445284) (xy 361.172109 -192.392986) (xy 361.164355 -192.339035)
			(xy 361.16387 -192.311782) (xy 359.709653 -192.311782) (xy 365.780803 -197.28434) (xy 369.527582 -197.28434)
			(xy 369.528052 -197.25697) (xy 369.535865 -197.20279) (xy 369.551353 -197.150286) (xy 369.574194 -197.100539)
			(xy 369.60392 -197.054573) (xy 369.621562 -197.033642) (xy 369.627658 -197.02653) (xy 369.634008 -197.009512)
			(xy 369.634008 -196.924168) (xy 369.627658 -196.90715) (xy 369.621562 -196.900038) (xy 369.603959 -196.879074)
			(xy 369.57423 -196.833113) (xy 369.55138 -196.783372) (xy 369.535879 -196.730874) (xy 369.528046 -196.676699)
			(xy 369.528042 -196.621961) (xy 369.535866 -196.567785) (xy 369.551359 -196.515285) (xy 369.574201 -196.46554)
			(xy 369.603923 -196.419574) (xy 369.621562 -196.398642) (xy 369.627658 -196.39153) (xy 369.634008 -196.374512)
			(xy 369.634008 -196.289168) (xy 369.627658 -196.27215) (xy 369.621562 -196.265038) (xy 369.603959 -196.244074)
			(xy 369.57423 -196.198113) (xy 369.55138 -196.148372) (xy 369.535879 -196.095874) (xy 369.528046 -196.041699)
			(xy 369.528042 -195.986961) (xy 369.535866 -195.932785) (xy 369.551359 -195.880285) (xy 369.574201 -195.83054)
			(xy 369.603923 -195.784574) (xy 369.621562 -195.763642) (xy 369.627658 -195.75653) (xy 369.634008 -195.739512)
			(xy 369.634008 -195.654168) (xy 369.627658 -195.63715) (xy 369.621562 -195.630038) (xy 369.603921 -195.609108)
			(xy 369.574211 -195.563134) (xy 369.551376 -195.513386) (xy 369.535885 -195.460885) (xy 369.528056 -195.406709)
			(xy 369.527582 -195.37934) (xy 369.528079 -195.35085) (xy 369.536545 -195.294502) (xy 369.553294 -195.240039)
			(xy 369.577955 -195.188671) (xy 369.609979 -195.141541) (xy 369.628928 -195.12026) (xy 369.635532 -195.113148)
			(xy 369.64239 -195.095622) (xy 369.64239 -195.00723) (xy 369.635532 -194.989704) (xy 369.628928 -194.982592)
			(xy 369.609976 -194.961315) (xy 369.577969 -194.914177) (xy 369.55332 -194.862808) (xy 369.536577 -194.808346)
			(xy 369.52811 -194.752001) (xy 369.527582 -194.723512) (xy 369.528066 -194.69626) (xy 369.535822 -194.64231)
			(xy 369.551176 -194.590013) (xy 369.573816 -194.540434) (xy 369.603282 -194.494581) (xy 369.638973 -194.453389)
			(xy 369.680164 -194.417695) (xy 369.726015 -194.388226) (xy 369.775593 -194.365583) (xy 369.827889 -194.350226)
			(xy 369.881838 -194.342468) (xy 369.90909 -194.342004) (xy 369.93646 -194.342475) (xy 369.990639 -194.350291)
			(xy 370.043142 -194.365779) (xy 370.092889 -194.38862) (xy 370.138856 -194.418343) (xy 370.159788 -194.435984)
			(xy 370.1669 -194.44208) (xy 370.183918 -194.44843) (xy 370.269262 -194.44843) (xy 370.28628 -194.44208)
			(xy 370.293392 -194.435984) (xy 370.314325 -194.418343) (xy 370.360293 -194.388619) (xy 370.410039 -194.365773)
			(xy 370.462541 -194.350277) (xy 370.516719 -194.342448) (xy 370.571461 -194.342448) (xy 370.625639 -194.350277)
			(xy 370.678141 -194.365773) (xy 370.727887 -194.388619) (xy 370.773855 -194.418343) (xy 370.794788 -194.435984)
			(xy 370.8019 -194.44208) (xy 370.818918 -194.44843) (xy 370.904262 -194.44843) (xy 370.92128 -194.44208)
			(xy 370.928392 -194.435984) (xy 370.949314 -194.418333) (xy 370.99529 -194.388623) (xy 371.04504 -194.36579)
			(xy 371.097543 -194.350302) (xy 371.15172 -194.342476) (xy 371.17909 -194.342004) (xy 371.206343 -194.342465)
			(xy 371.260295 -194.350221) (xy 371.312593 -194.365576) (xy 371.362174 -194.388218) (xy 371.408028 -194.417686)
			(xy 371.449221 -194.45338) (xy 371.484915 -194.494574) (xy 371.514383 -194.540427) (xy 371.537025 -194.590008)
			(xy 371.55238 -194.642307) (xy 371.560135 -194.696259) (xy 371.560598 -194.723512) (xy 373.543322 -194.723512)
			(xy 373.543767 -194.696258) (xy 373.551523 -194.642305) (xy 373.566879 -194.590005) (xy 373.589522 -194.540423)
			(xy 373.618992 -194.494568) (xy 373.654687 -194.453375) (xy 373.695883 -194.417681) (xy 373.741739 -194.388213)
			(xy 373.791322 -194.365572) (xy 373.843623 -194.350219) (xy 373.897576 -194.342465) (xy 373.92483 -194.342004)
			(xy 373.952201 -194.342452) (xy 374.006381 -194.350274) (xy 374.058884 -194.365767) (xy 374.108631 -194.388613)
			(xy 374.154597 -194.418341) (xy 374.175528 -194.435984) (xy 374.18264 -194.44208) (xy 374.199658 -194.44843)
			(xy 374.285002 -194.44843) (xy 374.30202 -194.44208) (xy 374.309132 -194.435984) (xy 374.330065 -194.418343)
			(xy 374.376033 -194.388619) (xy 374.425779 -194.365773) (xy 374.478281 -194.350277) (xy 374.532459 -194.342448)
			(xy 374.587201 -194.342448) (xy 374.641379 -194.350277) (xy 374.693881 -194.365773) (xy 374.743627 -194.388619)
			(xy 374.789595 -194.418343) (xy 374.810528 -194.435984) (xy 374.81764 -194.44208) (xy 374.834658 -194.44843)
			(xy 374.920002 -194.44843) (xy 374.93702 -194.44208) (xy 374.944132 -194.435984) (xy 374.965077 -194.418361)
			(xy 375.011046 -194.388647) (xy 375.060791 -194.365808) (xy 375.113288 -194.350314) (xy 375.167462 -194.342481)
			(xy 375.19483 -194.342004) (xy 375.222083 -194.34245) (xy 375.276032 -194.350211) (xy 375.328329 -194.36557)
			(xy 375.377907 -194.388216) (xy 375.423757 -194.417686) (xy 375.464948 -194.453382) (xy 375.500639 -194.494576)
			(xy 375.530104 -194.54043) (xy 375.552744 -194.590011) (xy 375.568098 -194.642309) (xy 375.575853 -194.696259)
			(xy 375.576338 -194.723512) (xy 375.575846 -194.751423) (xy 375.56771 -194.806648) (xy 375.551614 -194.860099)
			(xy 375.527901 -194.910634) (xy 375.497078 -194.957174) (xy 375.478802 -194.978274) (xy 375.472452 -194.985386)
			(xy 375.465848 -195.003166) (xy 375.46661 -195.090796) (xy 375.473722 -195.108322) (xy 375.480326 -195.115434)
			(xy 375.499512 -195.136741) (xy 375.531918 -195.184041) (xy 375.556883 -195.235657) (xy 375.573846 -195.290426)
			(xy 375.582426 -195.347116) (xy 375.582942 -195.375784) (xy 375.582481 -195.403155) (xy 375.574664 -195.457334)
			(xy 375.559174 -195.509838) (xy 375.536331 -195.559585) (xy 375.506605 -195.605551) (xy 375.488962 -195.626482)
			(xy 375.482866 -195.633594) (xy 375.476516 -195.650612) (xy 375.476516 -195.735956) (xy 375.482866 -195.752974)
			(xy 375.488962 -195.760086) (xy 375.506587 -195.781031) (xy 375.536314 -195.826997) (xy 375.559161 -195.876741)
			(xy 375.574659 -195.929241) (xy 375.582489 -195.983418) (xy 375.582491 -196.038158) (xy 375.574664 -196.092335)
			(xy 375.559169 -196.144837) (xy 375.536325 -196.194582) (xy 375.506602 -196.24055) (xy 375.488962 -196.261482)
			(xy 375.482866 -196.268594) (xy 375.476516 -196.285612) (xy 375.476516 -196.370956) (xy 375.482866 -196.387974)
			(xy 375.488962 -196.395086) (xy 375.506587 -196.416031) (xy 375.536314 -196.461997) (xy 375.559161 -196.511741)
			(xy 375.574659 -196.564241) (xy 375.582489 -196.618418) (xy 375.582491 -196.673158) (xy 375.574664 -196.727335)
			(xy 375.559169 -196.779837) (xy 375.536325 -196.829582) (xy 375.506602 -196.87555) (xy 375.488962 -196.896482)
			(xy 375.482866 -196.903594) (xy 375.476516 -196.920612) (xy 375.476516 -197.005956) (xy 375.482866 -197.022974)
			(xy 375.488962 -197.030086) (xy 375.506587 -197.051031) (xy 375.536314 -197.096997) (xy 375.559161 -197.146741)
			(xy 375.574659 -197.199241) (xy 375.582489 -197.253418) (xy 375.58249 -197.28434) (xy 377.93041 -197.28434)
			(xy 377.930897 -197.25697) (xy 377.938709 -197.202792) (xy 377.954193 -197.150289) (xy 377.977031 -197.100542)
			(xy 378.006751 -197.054574) (xy 378.02439 -197.033642) (xy 378.030486 -197.02653) (xy 378.036836 -197.009512)
			(xy 378.036836 -196.924168) (xy 378.030486 -196.90715) (xy 378.02439 -196.900038) (xy 378.00679 -196.879073)
			(xy 377.977066 -196.83311) (xy 377.954221 -196.783369) (xy 377.938723 -196.730872) (xy 377.930892 -196.676698)
			(xy 377.930887 -196.621962) (xy 377.93871 -196.567787) (xy 377.9542 -196.515288) (xy 377.977037 -196.465543)
			(xy 378.006754 -196.419575) (xy 378.02439 -196.398642) (xy 378.030486 -196.39153) (xy 378.036836 -196.374512)
			(xy 378.036836 -196.289168) (xy 378.030486 -196.27215) (xy 378.02439 -196.265038) (xy 378.00679 -196.244073)
			(xy 377.977066 -196.19811) (xy 377.954221 -196.148369) (xy 377.938723 -196.095872) (xy 377.930892 -196.041698)
			(xy 377.930887 -195.986962) (xy 377.93871 -195.932787) (xy 377.9542 -195.880288) (xy 377.977037 -195.830543)
			(xy 378.006754 -195.784575) (xy 378.02439 -195.763642) (xy 378.030486 -195.75653) (xy 378.036836 -195.739512)
			(xy 378.036836 -195.654168) (xy 378.030486 -195.63715) (xy 378.02439 -195.630038) (xy 378.006754 -195.609104)
			(xy 377.977042 -195.563131) (xy 377.954205 -195.513384) (xy 377.938714 -195.460884) (xy 377.930885 -195.406709)
			(xy 377.93041 -195.37934) (xy 377.930926 -195.350851) (xy 377.93939 -195.294504) (xy 377.956136 -195.240042)
			(xy 377.980792 -195.188675) (xy 378.01281 -195.141543) (xy 378.031756 -195.12026) (xy 378.03836 -195.113148)
			(xy 378.045218 -195.095622) (xy 378.045218 -195.00723) (xy 378.03836 -194.989704) (xy 378.031756 -194.982592)
			(xy 378.012809 -194.961311) (xy 377.9808 -194.914175) (xy 377.95615 -194.862806) (xy 377.939405 -194.808345)
			(xy 377.930938 -194.752001) (xy 377.93041 -194.723512) (xy 377.930867 -194.696259) (xy 377.938622 -194.642307)
			(xy 377.953978 -194.590007) (xy 377.97662 -194.540426) (xy 378.006089 -194.494572) (xy 378.041783 -194.453379)
			(xy 378.082977 -194.417685) (xy 378.128831 -194.388217) (xy 378.178413 -194.365576) (xy 378.230712 -194.350221)
			(xy 378.284665 -194.342466) (xy 378.311918 -194.342004) (xy 378.339289 -194.342459) (xy 378.393468 -194.350279)
			(xy 378.445972 -194.365771) (xy 378.495718 -194.388615) (xy 378.541685 -194.418342) (xy 378.562616 -194.435984)
			(xy 378.569728 -194.44208) (xy 378.586746 -194.44843) (xy 378.67209 -194.44843) (xy 378.689108 -194.44208)
			(xy 378.69622 -194.435984) (xy 378.717153 -194.418343) (xy 378.763121 -194.388619) (xy 378.812867 -194.365773)
			(xy 378.865369 -194.350277) (xy 378.919547 -194.342448) (xy 378.974289 -194.342448) (xy 379.028467 -194.350277)
			(xy 379.080969 -194.365773) (xy 379.130715 -194.388619) (xy 379.176683 -194.418343) (xy 379.197616 -194.435984)
			(xy 379.204728 -194.44208) (xy 379.221746 -194.44843) (xy 379.30709 -194.44843) (xy 379.324108 -194.44208)
			(xy 379.33122 -194.435984) (xy 379.352169 -194.418366) (xy 379.398138 -194.388652) (xy 379.447881 -194.365812)
			(xy 379.500378 -194.350316) (xy 379.55455 -194.342482) (xy 379.581918 -194.342004) (xy 379.60917 -194.342461)
			(xy 379.66312 -194.35022) (xy 379.715416 -194.365578) (xy 379.764994 -194.388222) (xy 379.810845 -194.417692)
			(xy 379.852035 -194.453386) (xy 379.887726 -194.494579) (xy 379.917192 -194.540433) (xy 379.939832 -194.590013)
			(xy 379.955186 -194.64231) (xy 379.962941 -194.69626) (xy 379.963426 -194.723512) (xy 381.94615 -194.723512)
			(xy 381.946689 -194.696263) (xy 381.954443 -194.642319) (xy 381.969795 -194.590028) (xy 381.992431 -194.540454)
			(xy 382.021892 -194.494606) (xy 382.057578 -194.453416) (xy 382.098762 -194.417725) (xy 382.144607 -194.388257)
			(xy 382.194178 -194.365613) (xy 382.246467 -194.350255) (xy 382.300409 -194.342493) (xy 382.327658 -194.342004)
			(xy 382.355027 -194.342494) (xy 382.409205 -194.350306) (xy 382.461708 -194.365789) (xy 382.511456 -194.388626)
			(xy 382.557424 -194.418345) (xy 382.578356 -194.435984) (xy 382.585468 -194.44208) (xy 382.602486 -194.44843)
			(xy 382.68783 -194.44843) (xy 382.704848 -194.44208) (xy 382.71196 -194.435984) (xy 382.732893 -194.418343)
			(xy 382.778861 -194.388619) (xy 382.828607 -194.365773) (xy 382.881109 -194.350277) (xy 382.935287 -194.342448)
			(xy 382.990029 -194.342448) (xy 383.044207 -194.350277) (xy 383.096709 -194.365773) (xy 383.146455 -194.388619)
			(xy 383.192423 -194.418343) (xy 383.213356 -194.435984) (xy 383.220468 -194.44208) (xy 383.237486 -194.44843)
			(xy 383.32283 -194.44843) (xy 383.339848 -194.44208) (xy 383.34696 -194.435984) (xy 383.367894 -194.418348)
			(xy 383.413867 -194.388636) (xy 383.463614 -194.3658) (xy 383.516114 -194.350308) (xy 383.570289 -194.342479)
			(xy 383.597658 -194.342004) (xy 383.62491 -194.342494) (xy 383.678861 -194.350246) (xy 383.731159 -194.365597)
			(xy 383.78074 -194.388236) (xy 383.826594 -194.417701) (xy 383.867787 -194.453392) (xy 383.903481 -194.494582)
			(xy 383.93295 -194.540434) (xy 383.955592 -194.590013) (xy 383.970948 -194.64231) (xy 383.978703 -194.69626)
			(xy 383.979166 -194.723512) (xy 383.978663 -194.751115) (xy 383.970705 -194.805745) (xy 383.954957 -194.858657)
			(xy 383.931748 -194.908747) (xy 383.901562 -194.95497) (xy 383.883662 -194.975988) (xy 383.877312 -194.983354)
			(xy 383.870708 -195.001134) (xy 383.87274 -195.089526) (xy 383.880106 -195.106798) (xy 383.886964 -195.11391)
			(xy 383.90698 -195.135409) (xy 383.940892 -195.183366) (xy 383.967056 -195.235954) (xy 383.984852 -195.29193)
			(xy 383.993861 -195.349972) (xy 383.994406 -195.37934) (xy 383.993903 -195.406709) (xy 383.986094 -195.460886)
			(xy 383.970613 -195.513389) (xy 383.94778 -195.563136) (xy 383.918063 -195.609105) (xy 383.900426 -195.630038)
			(xy 383.89433 -195.63715) (xy 383.88798 -195.654168) (xy 383.88798 -195.739512) (xy 383.89433 -195.75653)
			(xy 383.900426 -195.763642) (xy 383.918108 -195.784542) (xy 383.947835 -195.830514) (xy 383.97068 -195.880266)
			(xy 383.986176 -195.932773) (xy 383.994002 -195.986957) (xy 383.993997 -196.041703) (xy 383.986163 -196.095886)
			(xy 383.970659 -196.148391) (xy 383.947806 -196.198139) (xy 383.918071 -196.244106) (xy 383.900426 -196.265038)
			(xy 383.89433 -196.27215) (xy 383.88798 -196.289168) (xy 383.88798 -196.374512) (xy 383.89433 -196.39153)
			(xy 383.900426 -196.398642) (xy 383.918108 -196.419542) (xy 383.947835 -196.465514) (xy 383.97068 -196.515266)
			(xy 383.986176 -196.567773) (xy 383.994002 -196.621957) (xy 383.993997 -196.676703) (xy 383.986163 -196.730886)
			(xy 383.970659 -196.783391) (xy 383.947806 -196.833139) (xy 383.918071 -196.879106) (xy 383.900426 -196.900038)
			(xy 383.89433 -196.90715) (xy 383.88798 -196.924168) (xy 383.88798 -197.009512) (xy 383.89433 -197.02653)
			(xy 383.900426 -197.033642) (xy 383.918108 -197.054542) (xy 383.947835 -197.100514) (xy 383.97068 -197.150266)
			(xy 383.986176 -197.202773) (xy 383.994002 -197.256957) (xy 383.993997 -197.311703) (xy 383.986163 -197.365886)
			(xy 383.970659 -197.418391) (xy 383.947806 -197.468139) (xy 383.918071 -197.514106) (xy 383.900426 -197.535038)
			(xy 383.89433 -197.54215) (xy 383.88798 -197.559168) (xy 383.88798 -197.644512) (xy 383.89433 -197.66153)
			(xy 383.900426 -197.668642) (xy 383.918108 -197.689542) (xy 383.947835 -197.735514) (xy 383.97068 -197.785266)
			(xy 383.986176 -197.837773) (xy 383.994002 -197.891957) (xy 383.993997 -197.946703) (xy 383.986163 -198.000886)
			(xy 383.970659 -198.053391) (xy 383.947806 -198.103139) (xy 383.918071 -198.149106) (xy 383.900426 -198.170038)
			(xy 383.89433 -198.17715) (xy 383.88798 -198.194168) (xy 383.88798 -198.279512) (xy 383.89433 -198.29653)
			(xy 383.900426 -198.303642) (xy 383.918108 -198.324542) (xy 383.947835 -198.370514) (xy 383.97068 -198.420266)
			(xy 383.986176 -198.472773) (xy 383.994002 -198.526957) (xy 383.993997 -198.581703) (xy 383.986163 -198.635886)
			(xy 383.970659 -198.688391) (xy 383.947806 -198.738139) (xy 383.918071 -198.784106) (xy 383.900426 -198.805038)
			(xy 383.89433 -198.81215) (xy 383.88798 -198.829168) (xy 383.88798 -198.914512) (xy 383.89433 -198.93153)
			(xy 383.900426 -198.938642) (xy 383.918108 -198.959542) (xy 383.947835 -199.005514) (xy 383.97068 -199.055266)
			(xy 383.986176 -199.107773) (xy 383.994002 -199.161957) (xy 383.993997 -199.216703) (xy 383.986163 -199.270886)
			(xy 383.970659 -199.323391) (xy 383.947806 -199.373139) (xy 383.918071 -199.419106) (xy 383.900426 -199.440038)
			(xy 383.89433 -199.44715) (xy 383.88798 -199.464168) (xy 383.88798 -199.549512) (xy 383.89433 -199.56653)
			(xy 383.900426 -199.573642) (xy 383.918055 -199.594582) (xy 383.947768 -199.640553) (xy 383.970605 -199.690298)
			(xy 383.986099 -199.742797) (xy 383.99393 -199.796971) (xy 383.994406 -199.82434) (xy 386.26161 -199.82434)
			(xy 386.262097 -199.79697) (xy 386.269909 -199.742792) (xy 386.285393 -199.690289) (xy 386.308231 -199.640542)
			(xy 386.337951 -199.594574) (xy 386.35559 -199.573642) (xy 386.361686 -199.56653) (xy 386.368036 -199.549512)
			(xy 386.368036 -199.464168) (xy 386.361686 -199.44715) (xy 386.35559 -199.440038) (xy 386.33799 -199.419073)
			(xy 386.308266 -199.37311) (xy 386.285421 -199.323369) (xy 386.269923 -199.270872) (xy 386.262092 -199.216698)
			(xy 386.262087 -199.161962) (xy 386.26991 -199.107787) (xy 386.2854 -199.055288) (xy 386.308237 -199.005543)
			(xy 386.337954 -198.959575) (xy 386.35559 -198.938642) (xy 386.361686 -198.93153) (xy 386.368036 -198.914512)
			(xy 386.368036 -198.829168) (xy 386.361686 -198.81215) (xy 386.35559 -198.805038) (xy 386.33799 -198.784073)
			(xy 386.308266 -198.73811) (xy 386.285421 -198.688369) (xy 386.269923 -198.635872) (xy 386.262092 -198.581698)
			(xy 386.262087 -198.526962) (xy 386.26991 -198.472787) (xy 386.2854 -198.420288) (xy 386.308237 -198.370543)
			(xy 386.337954 -198.324575) (xy 386.35559 -198.303642) (xy 386.361686 -198.29653) (xy 386.368036 -198.279512)
			(xy 386.368036 -198.194168) (xy 386.361686 -198.17715) (xy 386.35559 -198.170038) (xy 386.33799 -198.149073)
			(xy 386.308266 -198.10311) (xy 386.285421 -198.053369) (xy 386.269923 -198.000872) (xy 386.262092 -197.946698)
			(xy 386.262087 -197.891962) (xy 386.26991 -197.837787) (xy 386.2854 -197.785288) (xy 386.308237 -197.735543)
			(xy 386.337954 -197.689575) (xy 386.35559 -197.668642) (xy 386.361686 -197.66153) (xy 386.368036 -197.644512)
			(xy 386.368036 -197.559168) (xy 386.361686 -197.54215) (xy 386.35559 -197.535038) (xy 386.33799 -197.514073)
			(xy 386.308266 -197.46811) (xy 386.285421 -197.418369) (xy 386.269923 -197.365872) (xy 386.262092 -197.311698)
			(xy 386.262087 -197.256962) (xy 386.26991 -197.202787) (xy 386.2854 -197.150288) (xy 386.308237 -197.100543)
			(xy 386.337954 -197.054575) (xy 386.35559 -197.033642) (xy 386.361686 -197.02653) (xy 386.368036 -197.009512)
			(xy 386.368036 -196.924168) (xy 386.361686 -196.90715) (xy 386.35559 -196.900038) (xy 386.33799 -196.879073)
			(xy 386.308266 -196.83311) (xy 386.285421 -196.783369) (xy 386.269923 -196.730872) (xy 386.262092 -196.676698)
			(xy 386.262087 -196.621962) (xy 386.26991 -196.567787) (xy 386.2854 -196.515288) (xy 386.308237 -196.465543)
			(xy 386.337954 -196.419575) (xy 386.35559 -196.398642) (xy 386.361686 -196.39153) (xy 386.368036 -196.374512)
			(xy 386.368036 -196.289168) (xy 386.361686 -196.27215) (xy 386.35559 -196.265038) (xy 386.33799 -196.244073)
			(xy 386.308266 -196.19811) (xy 386.285421 -196.148369) (xy 386.269923 -196.095872) (xy 386.262092 -196.041698)
			(xy 386.262087 -195.986962) (xy 386.26991 -195.932787) (xy 386.2854 -195.880288) (xy 386.308237 -195.830543)
			(xy 386.337954 -195.784575) (xy 386.35559 -195.763642) (xy 386.361686 -195.75653) (xy 386.368036 -195.739512)
			(xy 386.368036 -195.654168) (xy 386.361686 -195.63715) (xy 386.35559 -195.630038) (xy 386.337954 -195.609104)
			(xy 386.308242 -195.563131) (xy 386.285405 -195.513384) (xy 386.269914 -195.460884) (xy 386.262085 -195.406709)
			(xy 386.26161 -195.37934) (xy 386.262126 -195.350851) (xy 386.27059 -195.294504) (xy 386.287336 -195.240042)
			(xy 386.311992 -195.188675) (xy 386.34401 -195.141543) (xy 386.362956 -195.12026) (xy 386.36956 -195.113148)
			(xy 386.376418 -195.095622) (xy 386.376418 -195.00723) (xy 386.36956 -194.989704) (xy 386.362956 -194.982592)
			(xy 386.344009 -194.961311) (xy 386.312 -194.914175) (xy 386.28735 -194.862806) (xy 386.270605 -194.808345)
			(xy 386.262138 -194.752001) (xy 386.26161 -194.723512) (xy 386.262067 -194.696259) (xy 386.269822 -194.642307)
			(xy 386.285178 -194.590007) (xy 386.30782 -194.540426) (xy 386.337289 -194.494572) (xy 386.372983 -194.453379)
			(xy 386.414177 -194.417685) (xy 386.460031 -194.388217) (xy 386.509613 -194.365576) (xy 386.561912 -194.350221)
			(xy 386.615865 -194.342466) (xy 386.643118 -194.342004) (xy 386.670489 -194.342459) (xy 386.724668 -194.350279)
			(xy 386.777172 -194.365771) (xy 386.826918 -194.388615) (xy 386.872885 -194.418342) (xy 386.893816 -194.435984)
			(xy 386.900928 -194.44208) (xy 386.917946 -194.44843) (xy 387.00329 -194.44843) (xy 387.020308 -194.44208)
			(xy 387.02742 -194.435984) (xy 387.048353 -194.418343) (xy 387.094321 -194.388619) (xy 387.144067 -194.365773)
			(xy 387.196569 -194.350277) (xy 387.250747 -194.342448) (xy 387.305489 -194.342448) (xy 387.359667 -194.350277)
			(xy 387.412169 -194.365773) (xy 387.461915 -194.388619) (xy 387.507883 -194.418343) (xy 387.528816 -194.435984)
			(xy 387.535928 -194.44208) (xy 387.552946 -194.44843) (xy 387.63829 -194.44843) (xy 387.655308 -194.44208)
			(xy 387.66242 -194.435984) (xy 387.683369 -194.418366) (xy 387.729338 -194.388652) (xy 387.779081 -194.365812)
			(xy 387.831578 -194.350316) (xy 387.88575 -194.342482) (xy 387.913118 -194.342004) (xy 387.94037 -194.342461)
			(xy 387.99432 -194.35022) (xy 388.046616 -194.365578) (xy 388.096194 -194.388222) (xy 388.142045 -194.417692)
			(xy 388.183235 -194.453386) (xy 388.218926 -194.494579) (xy 388.248392 -194.540433) (xy 388.271032 -194.590013)
			(xy 388.286386 -194.64231) (xy 388.294141 -194.69626) (xy 388.294626 -194.723512) (xy 388.294178 -194.750483)
			(xy 388.286569 -194.803884) (xy 388.271505 -194.855679) (xy 388.249287 -194.904832) (xy 388.22036 -194.950361)
			(xy 388.203186 -194.971162) (xy 388.19709 -194.978274) (xy 388.190994 -194.995292) (xy 388.191756 -195.08089)
			(xy 388.19836 -195.097654) (xy 388.20471 -195.104766) (xy 388.222802 -195.125838) (xy 388.253307 -195.172247)
			(xy 388.276767 -195.222585) (xy 388.292688 -195.275792) (xy 388.300732 -195.330743) (xy 388.30123 -195.358512)
			(xy 388.300788 -195.385883) (xy 388.292967 -195.440064) (xy 388.277473 -195.492568) (xy 388.254626 -195.542315)
			(xy 388.224895 -195.58828) (xy 388.20725 -195.60921) (xy 388.201154 -195.616322) (xy 388.194804 -195.63334)
			(xy 388.194804 -195.718684) (xy 388.201154 -195.735702) (xy 388.20725 -195.742814) (xy 388.224903 -195.763737)
			(xy 388.254629 -195.809706) (xy 388.277476 -195.859453) (xy 388.292972 -195.911957) (xy 388.3008 -195.966138)
			(xy 388.300799 -196.02088) (xy 388.292968 -196.07506) (xy 388.277469 -196.127563) (xy 388.254621 -196.17731)
			(xy 388.224892 -196.223278) (xy 388.20725 -196.24421) (xy 388.201154 -196.251322) (xy 388.194804 -196.26834)
			(xy 388.194804 -196.353684) (xy 388.201154 -196.370702) (xy 388.20725 -196.377814) (xy 388.224903 -196.398737)
			(xy 388.254629 -196.444706) (xy 388.277476 -196.494453) (xy 388.292972 -196.546957) (xy 388.3008 -196.601138)
			(xy 388.300799 -196.65588) (xy 388.292968 -196.71006) (xy 388.277469 -196.762563) (xy 388.254621 -196.81231)
			(xy 388.224892 -196.858278) (xy 388.20725 -196.87921) (xy 388.201154 -196.886322) (xy 388.194804 -196.90334)
			(xy 388.194804 -196.988684) (xy 388.201154 -197.005702) (xy 388.20725 -197.012814) (xy 388.224854 -197.033774)
			(xy 388.254573 -197.079738) (xy 388.277417 -197.129479) (xy 388.292916 -197.181973) (xy 388.300752 -197.236145)
			(xy 388.30123 -197.263512) (xy 388.300721 -197.292382) (xy 388.292039 -197.349466) (xy 388.274858 -197.404592)
			(xy 388.249572 -197.456501) (xy 388.216756 -197.50401) (xy 388.197344 -197.525386) (xy 388.190486 -197.532244)
			(xy 388.183628 -197.550024) (xy 388.182612 -197.638416) (xy 388.189216 -197.655942) (xy 388.19582 -197.663308)
			(xy 388.214294 -197.684467) (xy 388.245486 -197.731179) (xy 388.269503 -197.781955) (xy 388.285826 -197.8357)
			(xy 388.294103 -197.891256) (xy 388.294626 -197.91934) (xy 388.294143 -197.94671) (xy 388.286332 -198.000889)
			(xy 388.270848 -198.053393) (xy 388.248009 -198.10314) (xy 388.218287 -198.149107) (xy 388.200646 -198.170038)
			(xy 388.19455 -198.17715) (xy 388.1882 -198.194168) (xy 388.1882 -198.279512) (xy 388.19455 -198.29653)
			(xy 388.200646 -198.303642) (xy 388.218327 -198.324542) (xy 388.248052 -198.370515) (xy 388.270897 -198.420267)
			(xy 388.286391 -198.472774) (xy 388.294217 -198.526957) (xy 388.294212 -198.581703) (xy 388.286378 -198.635885)
			(xy 388.270876 -198.68839) (xy 388.248023 -198.738138) (xy 388.218291 -198.784106) (xy 388.200646 -198.805038)
			(xy 388.19455 -198.81215) (xy 388.1882 -198.829168) (xy 388.1882 -198.914512) (xy 388.19455 -198.93153)
			(xy 388.200646 -198.938642) (xy 388.218327 -198.959542) (xy 388.248052 -199.005515) (xy 388.270897 -199.055267)
			(xy 388.286391 -199.107774) (xy 388.294217 -199.161957) (xy 388.294212 -199.216703) (xy 388.286378 -199.270885)
			(xy 388.272957 -199.31634) (xy 390.27735 -199.31634) (xy 390.277878 -199.287423) (xy 390.286602 -199.230252)
			(xy 390.303857 -199.175052) (xy 390.329247 -199.12309) (xy 390.36219 -199.075556) (xy 390.40193 -199.03354)
			(xy 390.424416 -199.01535) (xy 390.433154 -199.007765) (xy 390.44335 -198.987024) (xy 390.443974 -198.975472)
			(xy 390.443974 -198.895208) (xy 390.443408 -198.883639) (xy 390.433211 -198.862868) (xy 390.424416 -198.85533)
			(xy 390.40195 -198.837118) (xy 390.362213 -198.795103) (xy 390.329272 -198.747573) (xy 390.30388 -198.695615)
			(xy 390.28662 -198.640421) (xy 390.277887 -198.583255) (xy 390.27735 -198.55434) (xy 390.277827 -198.52697)
			(xy 390.285641 -198.472791) (xy 390.301126 -198.420287) (xy 390.323966 -198.37054) (xy 390.353689 -198.324574)
			(xy 390.37133 -198.303642) (xy 390.377426 -198.29653) (xy 390.383776 -198.279512) (xy 390.383776 -198.194168)
			(xy 390.377426 -198.17715) (xy 390.37133 -198.170038) (xy 390.3537 -198.149099) (xy 390.323986 -198.103128)
			(xy 390.301148 -198.053383) (xy 390.285654 -198.000883) (xy 390.277825 -197.946709) (xy 390.27735 -197.91934)
			(xy 390.27787 -197.890636) (xy 390.286467 -197.833876) (xy 390.303472 -197.779046) (xy 390.328502 -197.727382)
			(xy 390.360991 -197.680053) (xy 390.38022 -197.658736) (xy 390.387078 -197.651624) (xy 390.393936 -197.634098)
			(xy 390.394444 -197.545452) (xy 390.38784 -197.527926) (xy 390.381236 -197.520814) (xy 390.362555 -197.499613)
			(xy 390.331021 -197.452725) (xy 390.306745 -197.4017) (xy 390.29026 -197.347652) (xy 390.281926 -197.291765)
			(xy 390.281414 -197.263512) (xy 390.281884 -197.236142) (xy 390.2897 -197.181963) (xy 390.305188 -197.12946)
			(xy 390.328029 -197.079713) (xy 390.357753 -197.033746) (xy 390.375394 -197.012814) (xy 390.38149 -197.005702)
			(xy 390.38784 -196.988684) (xy 390.38784 -196.90334) (xy 390.38149 -196.886322) (xy 390.375394 -196.87921)
			(xy 390.357766 -196.858267) (xy 390.328044 -196.8123) (xy 390.3052 -196.762555) (xy 390.289704 -196.710055)
			(xy 390.281875 -196.655879) (xy 390.281874 -196.601139) (xy 390.2897 -196.546962) (xy 390.305193 -196.494461)
			(xy 390.328035 -196.444716) (xy 390.357756 -196.398747) (xy 390.375394 -196.377814) (xy 390.38149 -196.370702)
			(xy 390.38784 -196.353684) (xy 390.38784 -196.26834) (xy 390.38149 -196.251322) (xy 390.375394 -196.24421)
			(xy 390.357766 -196.223267) (xy 390.328044 -196.1773) (xy 390.3052 -196.127555) (xy 390.289704 -196.075055)
			(xy 390.281875 -196.020879) (xy 390.281874 -195.966139) (xy 390.2897 -195.911962) (xy 390.305193 -195.859461)
			(xy 390.328035 -195.809716) (xy 390.357756 -195.763747) (xy 390.375394 -195.742814) (xy 390.38149 -195.735702)
			(xy 390.38784 -195.718684) (xy 390.38784 -195.63334) (xy 390.38149 -195.616322) (xy 390.375394 -195.60921)
			(xy 390.357745 -195.588286) (xy 390.328035 -195.542311) (xy 390.305201 -195.492561) (xy 390.289712 -195.440059)
			(xy 390.281887 -195.385882) (xy 390.281414 -195.358512) (xy 390.281869 -195.331377) (xy 390.289564 -195.277656)
			(xy 390.304799 -195.22557) (xy 390.327268 -195.17617) (xy 390.356515 -195.130456) (xy 390.37387 -195.109592)
			(xy 390.379966 -195.10248) (xy 390.386062 -195.085462) (xy 390.385554 -195.000118) (xy 390.379204 -194.9831)
			(xy 390.372854 -194.975988) (xy 390.354961 -194.954963) (xy 390.324767 -194.908745) (xy 390.301552 -194.858657)
			(xy 390.2858 -194.805745) (xy 390.27784 -194.751115) (xy 390.27735 -194.723512) (xy 390.277889 -194.696263)
			(xy 390.285643 -194.642319) (xy 390.300995 -194.590028) (xy 390.323631 -194.540454) (xy 390.353092 -194.494606)
			(xy 390.388778 -194.453416) (xy 390.429962 -194.417725) (xy 390.475807 -194.388257) (xy 390.525378 -194.365613)
			(xy 390.577667 -194.350255) (xy 390.631609 -194.342493) (xy 390.658858 -194.342004) (xy 390.686227 -194.342494)
			(xy 390.740405 -194.350306) (xy 390.792908 -194.365789) (xy 390.842656 -194.388626) (xy 390.888624 -194.418345)
			(xy 390.909556 -194.435984) (xy 390.916668 -194.44208) (xy 390.933686 -194.44843) (xy 391.01903 -194.44843)
			(xy 391.036048 -194.44208) (xy 391.04316 -194.435984) (xy 391.064094 -194.418348) (xy 391.110067 -194.388636)
			(xy 391.159814 -194.3658) (xy 391.212314 -194.350308) (xy 391.266489 -194.342479) (xy 391.293858 -194.342004)
			(xy 391.32111 -194.342494) (xy 391.375061 -194.350246) (xy 391.427359 -194.365597) (xy 391.47694 -194.388236)
			(xy 391.522794 -194.417701) (xy 391.563987 -194.453392) (xy 391.599681 -194.494582) (xy 391.62915 -194.540434)
			(xy 391.651792 -194.590013) (xy 391.667148 -194.64231) (xy 391.674903 -194.69626) (xy 391.675366 -194.723512)
			(xy 391.674872 -194.750645) (xy 391.667187 -194.804365) (xy 391.651961 -194.856451) (xy 391.629501 -194.905851)
			(xy 391.600261 -194.951567) (xy 391.58291 -194.972432) (xy 391.576814 -194.979544) (xy 391.570718 -194.996562)
			(xy 391.571226 -195.081906) (xy 391.577576 -195.098924) (xy 391.583926 -195.106036) (xy 391.601827 -195.127054)
			(xy 391.63202 -195.173274) (xy 391.655234 -195.223364) (xy 391.670985 -195.276277) (xy 391.678942 -195.330908)
			(xy 391.67943 -195.358512) (xy 391.678988 -195.385883) (xy 391.671167 -195.440064) (xy 391.655673 -195.492568)
			(xy 391.632826 -195.542315) (xy 391.603095 -195.58828) (xy 391.58545 -195.60921) (xy 391.579354 -195.616322)
			(xy 391.573004 -195.63334) (xy 391.573004 -195.718684) (xy 391.579354 -195.735702) (xy 391.58545 -195.742814)
			(xy 391.603103 -195.763737) (xy 391.632829 -195.809706) (xy 391.655676 -195.859453) (xy 391.671172 -195.911957)
			(xy 391.679 -195.966138) (xy 391.678999 -196.02088) (xy 391.671168 -196.07506) (xy 391.655669 -196.127563)
			(xy 391.632821 -196.17731) (xy 391.603092 -196.223278) (xy 391.58545 -196.24421) (xy 391.579354 -196.251322)
			(xy 391.573004 -196.26834) (xy 391.573004 -196.353684) (xy 391.579354 -196.370702) (xy 391.58545 -196.377814)
			(xy 391.603103 -196.398737) (xy 391.632829 -196.444706) (xy 391.655676 -196.494453) (xy 391.671172 -196.546957)
			(xy 391.679 -196.601138) (xy 391.678999 -196.65588) (xy 391.671168 -196.71006) (xy 391.655669 -196.762563)
			(xy 391.632821 -196.81231) (xy 391.603092 -196.858278) (xy 391.58545 -196.87921) (xy 391.579354 -196.886322)
			(xy 391.573004 -196.90334) (xy 391.573004 -196.988684) (xy 391.579354 -197.005702) (xy 391.58545 -197.012814)
			(xy 391.603054 -197.033774) (xy 391.632773 -197.079738) (xy 391.655617 -197.129479) (xy 391.671116 -197.181973)
			(xy 391.678952 -197.236145) (xy 391.67943 -197.263512) (xy 391.678947 -197.292217) (xy 391.670342 -197.348979)
			(xy 391.653328 -197.40381) (xy 391.62829 -197.455473) (xy 391.595793 -197.5028) (xy 391.57656 -197.524116)
			(xy 391.569702 -197.531228) (xy 391.562844 -197.548754) (xy 391.562336 -197.6374) (xy 391.56894 -197.654926)
			(xy 391.575544 -197.662038) (xy 391.594246 -197.683221) (xy 391.625778 -197.730114) (xy 391.65005 -197.781144)
			(xy 391.66653 -197.835195) (xy 391.674858 -197.891086) (xy 391.675366 -197.91934) (xy 391.674873 -197.946709)
			(xy 391.667063 -198.000888) (xy 391.651581 -198.053391) (xy 391.628745 -198.103138) (xy 391.599025 -198.149106)
			(xy 391.581386 -198.170038) (xy 391.57529 -198.17715) (xy 391.56894 -198.194168) (xy 391.56894 -198.279512)
			(xy 391.57529 -198.29653) (xy 391.581386 -198.303642) (xy 391.599009 -198.324587) (xy 391.628724 -198.370556)
			(xy 391.651563 -198.4203) (xy 391.667058 -198.472798) (xy 391.67489 -198.526972) (xy 391.675366 -198.55434)
			(xy 391.674982 -198.581596) (xy 391.667219 -198.635552) (xy 391.651855 -198.687854) (xy 391.629205 -198.737437)
			(xy 391.599729 -198.783292) (xy 391.564027 -198.824485) (xy 391.522826 -198.860178) (xy 391.476965 -198.889645)
			(xy 391.427377 -198.912284) (xy 391.375072 -198.927636) (xy 391.321114 -198.935388) (xy 391.293858 -198.935848)
			(xy 391.266488 -198.935361) (xy 391.21231 -198.92755) (xy 391.159806 -198.912066) (xy 391.110059 -198.889229)
			(xy 391.064092 -198.859508) (xy 391.04316 -198.841868) (xy 391.036048 -198.835772) (xy 391.01903 -198.829422)
			(xy 390.933686 -198.829422) (xy 390.916668 -198.835772) (xy 390.909556 -198.841868) (xy 390.8933 -198.85533)
			(xy 390.884529 -198.862883) (xy 390.874351 -198.883648) (xy 390.873742 -198.895208) (xy 390.873742 -198.975472)
			(xy 390.874314 -198.98704) (xy 390.884506 -199.007812) (xy 390.8933 -199.01535) (xy 390.91576 -199.033569)
			(xy 390.955496 -199.075583) (xy 390.988438 -199.123112) (xy 391.013831 -199.175068) (xy 391.031092 -199.23026)
			(xy 391.039827 -199.287426) (xy 391.040366 -199.31634) (xy 391.03988 -199.343591) (xy 391.032124 -199.397539)
			(xy 391.016769 -199.449834) (xy 390.994127 -199.499411) (xy 390.964661 -199.545261) (xy 390.92897 -199.586452)
			(xy 390.887779 -199.622143) (xy 390.841929 -199.651609) (xy 390.792352 -199.674251) (xy 390.740057 -199.689606)
			(xy 390.686109 -199.697362) (xy 390.631607 -199.697362) (xy 390.577659 -199.689606) (xy 390.525364 -199.674251)
			(xy 390.475787 -199.651609) (xy 390.429937 -199.622143) (xy 390.388746 -199.586452) (xy 390.353055 -199.545261)
			(xy 390.323589 -199.499411) (xy 390.300947 -199.449834) (xy 390.285592 -199.397539) (xy 390.277836 -199.343591)
			(xy 390.27735 -199.31634) (xy 388.272957 -199.31634) (xy 388.270876 -199.32339) (xy 388.248023 -199.373138)
			(xy 388.218291 -199.419106) (xy 388.200646 -199.440038) (xy 388.19455 -199.44715) (xy 388.1882 -199.464168)
			(xy 388.1882 -199.549512) (xy 388.19455 -199.56653) (xy 388.200646 -199.573642) (xy 388.218263 -199.594592)
			(xy 388.24798 -199.640559) (xy 388.270821 -199.690302) (xy 388.286317 -199.742799) (xy 388.29415 -199.796972)
			(xy 388.294626 -199.82434) (xy 388.294159 -199.851591) (xy 388.286398 -199.905539) (xy 388.271039 -199.957833)
			(xy 388.248394 -200.007409) (xy 388.218925 -200.053258) (xy 388.183232 -200.094448) (xy 388.142041 -200.130139)
			(xy 388.09619 -200.159605) (xy 388.046612 -200.182246) (xy 387.994317 -200.197603) (xy 387.940369 -200.205361)
			(xy 387.913118 -200.205848) (xy 387.885748 -200.205384) (xy 387.831568 -200.197568) (xy 387.779064 -200.182079)
			(xy 387.729317 -200.159236) (xy 387.683351 -200.12951) (xy 387.66242 -200.111868) (xy 387.655308 -200.105772)
			(xy 387.63829 -200.099422) (xy 387.552946 -200.099422) (xy 387.535928 -200.105772) (xy 387.528816 -200.111868)
			(xy 387.507883 -200.129509) (xy 387.461915 -200.159233) (xy 387.412169 -200.182079) (xy 387.359667 -200.197575)
			(xy 387.305489 -200.205404) (xy 387.250747 -200.205404) (xy 387.196569 -200.197575) (xy 387.144067 -200.182079)
			(xy 387.094321 -200.159233) (xy 387.048353 -200.129509) (xy 387.02742 -200.111868) (xy 387.020308 -200.105772)
			(xy 387.00329 -200.099422) (xy 386.917946 -200.099422) (xy 386.900928 -200.105772) (xy 386.893816 -200.111868)
			(xy 386.872885 -200.129508) (xy 386.826912 -200.159221) (xy 386.777165 -200.182057) (xy 386.724663 -200.197548)
			(xy 386.670487 -200.205375) (xy 386.643118 -200.205848) (xy 386.615869 -200.205305) (xy 386.561925 -200.197552)
			(xy 386.509634 -200.182201) (xy 386.46006 -200.159565) (xy 386.414211 -200.130105) (xy 386.373022 -200.094419)
			(xy 386.33733 -200.053235) (xy 386.307863 -200.007391) (xy 386.285219 -199.95782) (xy 386.26986 -199.905531)
			(xy 386.262099 -199.851589) (xy 386.26161 -199.82434) (xy 383.994406 -199.82434) (xy 383.993959 -199.851592)
			(xy 383.986197 -199.905542) (xy 383.970837 -199.957837) (xy 383.948191 -200.007415) (xy 383.91872 -200.053265)
			(xy 383.883025 -200.094455) (xy 383.841831 -200.130146) (xy 383.795978 -200.159611) (xy 383.746398 -200.182252)
			(xy 383.6941 -200.197606) (xy 383.64015 -200.205362) (xy 383.612898 -200.205848) (xy 383.585527 -200.205396)
			(xy 383.531347 -200.197577) (xy 383.478843 -200.182085) (xy 383.429096 -200.15924) (xy 383.383131 -200.129511)
			(xy 383.3622 -200.111868) (xy 383.355088 -200.105772) (xy 383.33807 -200.099422) (xy 383.252726 -200.099422)
			(xy 383.235708 -200.105772) (xy 383.228596 -200.111868) (xy 383.207663 -200.129509) (xy 383.161695 -200.159233)
			(xy 383.111949 -200.182079) (xy 383.059447 -200.197575) (xy 383.005269 -200.205404) (xy 382.950527 -200.205404)
			(xy 382.896349 -200.197575) (xy 382.843847 -200.182079) (xy 382.794101 -200.159233) (xy 382.748133 -200.129509)
			(xy 382.7272 -200.111868) (xy 382.720088 -200.105772) (xy 382.70307 -200.099422) (xy 382.617726 -200.099422)
			(xy 382.600708 -200.105772) (xy 382.593596 -200.111868) (xy 382.572672 -200.129517) (xy 382.526698 -200.159229)
			(xy 382.476948 -200.182063) (xy 382.424445 -200.197552) (xy 382.370268 -200.205376) (xy 382.342898 -200.205848)
			(xy 382.315649 -200.205324) (xy 382.261704 -200.197568) (xy 382.209413 -200.182215) (xy 382.159838 -200.159577)
			(xy 382.11399 -200.130114) (xy 382.0728 -200.094426) (xy 382.037109 -200.053241) (xy 382.007642 -200.007395)
			(xy 381.984998 -199.957823) (xy 381.96964 -199.905533) (xy 381.961879 -199.851589) (xy 381.96139 -199.82434)
			(xy 381.961882 -199.796971) (xy 381.969694 -199.742793) (xy 381.985177 -199.69029) (xy 382.008013 -199.640543)
			(xy 382.037732 -199.594575) (xy 382.05537 -199.573642) (xy 382.061466 -199.56653) (xy 382.067816 -199.549512)
			(xy 382.067816 -199.464168) (xy 382.061466 -199.44715) (xy 382.05537 -199.440038) (xy 382.037767 -199.419074)
			(xy 382.008037 -199.373113) (xy 381.985187 -199.323372) (xy 381.969685 -199.270874) (xy 381.961852 -199.216699)
			(xy 381.961848 -199.161961) (xy 381.969673 -199.107785) (xy 381.985165 -199.055284) (xy 382.008008 -199.00554)
			(xy 382.03773 -198.959574) (xy 382.05537 -198.938642) (xy 382.061466 -198.93153) (xy 382.067816 -198.914512)
			(xy 382.067816 -198.829168) (xy 382.061466 -198.81215) (xy 382.05537 -198.805038) (xy 382.037767 -198.784074)
			(xy 382.008037 -198.738113) (xy 381.985187 -198.688372) (xy 381.969685 -198.635874) (xy 381.961852 -198.581699)
			(xy 381.961848 -198.526961) (xy 381.969673 -198.472785) (xy 381.985165 -198.420284) (xy 382.008008 -198.37054)
			(xy 382.03773 -198.324574) (xy 382.05537 -198.303642) (xy 382.061466 -198.29653) (xy 382.067816 -198.279512)
			(xy 382.067816 -198.194168) (xy 382.061466 -198.17715) (xy 382.05537 -198.170038) (xy 382.037731 -198.149106)
			(xy 382.00802 -198.103133) (xy 381.985184 -198.053385) (xy 381.969693 -198.000885) (xy 381.961865 -197.946709)
			(xy 381.96139 -197.91934) (xy 381.961892 -197.891502) (xy 381.969997 -197.83642) (xy 381.986012 -197.783097)
			(xy 382.009598 -197.732663) (xy 382.040254 -197.686188) (xy 382.058418 -197.665086) (xy 382.064768 -197.657974)
			(xy 382.071372 -197.640194) (xy 382.069848 -197.551802) (xy 382.062736 -197.534276) (xy 382.056132 -197.527164)
			(xy 382.036377 -197.505752) (xy 382.002977 -197.45802) (xy 381.977212 -197.405771) (xy 381.959679 -197.350214)
			(xy 381.950786 -197.29264) (xy 381.950214 -197.263512) (xy 381.950684 -197.236142) (xy 381.9585 -197.181963)
			(xy 381.973988 -197.12946) (xy 381.996829 -197.079713) (xy 382.026553 -197.033746) (xy 382.044194 -197.012814)
			(xy 382.05029 -197.005702) (xy 382.05664 -196.988684) (xy 382.05664 -196.90334) (xy 382.05029 -196.886322)
			(xy 382.044194 -196.87921) (xy 382.026566 -196.858267) (xy 381.996844 -196.8123) (xy 381.974 -196.762555)
			(xy 381.958504 -196.710055) (xy 381.950675 -196.655879) (xy 381.950674 -196.601139) (xy 381.9585 -196.546962)
			(xy 381.973993 -196.494461) (xy 381.996835 -196.444716) (xy 382.026556 -196.398747) (xy 382.044194 -196.377814)
			(xy 382.05029 -196.370702) (xy 382.05664 -196.353684) (xy 382.05664 -196.26834) (xy 382.05029 -196.251322)
			(xy 382.044194 -196.24421) (xy 382.026566 -196.223267) (xy 381.996844 -196.1773) (xy 381.974 -196.127555)
			(xy 381.958504 -196.075055) (xy 381.950675 -196.020879) (xy 381.950674 -195.966139) (xy 381.9585 -195.911962)
			(xy 381.973993 -195.859461) (xy 381.996835 -195.809716) (xy 382.026556 -195.763747) (xy 382.044194 -195.742814)
			(xy 382.05029 -195.735702) (xy 382.05664 -195.718684) (xy 382.05664 -195.63334) (xy 382.05029 -195.616322)
			(xy 382.044194 -195.60921) (xy 382.026545 -195.588286) (xy 381.996835 -195.542311) (xy 381.974001 -195.492561)
			(xy 381.958512 -195.440059) (xy 381.950687 -195.385882) (xy 381.950214 -195.358512) (xy 381.950669 -195.331377)
			(xy 381.958364 -195.277656) (xy 381.973599 -195.22557) (xy 381.996068 -195.17617) (xy 382.025315 -195.130456)
			(xy 382.04267 -195.109592) (xy 382.048766 -195.10248) (xy 382.054862 -195.085462) (xy 382.054354 -195.000118)
			(xy 382.048004 -194.9831) (xy 382.041654 -194.975988) (xy 382.023761 -194.954963) (xy 381.993567 -194.908745)
			(xy 381.970352 -194.858657) (xy 381.9546 -194.805745) (xy 381.94664 -194.751115) (xy 381.94615 -194.723512)
			(xy 379.963426 -194.723512) (xy 379.962978 -194.750483) (xy 379.955369 -194.803884) (xy 379.940305 -194.855679)
			(xy 379.918087 -194.904832) (xy 379.88916 -194.950361) (xy 379.871986 -194.971162) (xy 379.86589 -194.978274)
			(xy 379.859794 -194.995292) (xy 379.860556 -195.08089) (xy 379.86716 -195.097654) (xy 379.87351 -195.104766)
			(xy 379.891602 -195.125838) (xy 379.922107 -195.172247) (xy 379.945567 -195.222585) (xy 379.961488 -195.275792)
			(xy 379.969532 -195.330743) (xy 379.97003 -195.358512) (xy 379.969588 -195.385883) (xy 379.961767 -195.440064)
			(xy 379.946273 -195.492568) (xy 379.923426 -195.542315) (xy 379.893695 -195.58828) (xy 379.87605 -195.60921)
			(xy 379.869954 -195.616322) (xy 379.863604 -195.63334) (xy 379.863604 -195.718684) (xy 379.869954 -195.735702)
			(xy 379.87605 -195.742814) (xy 379.893703 -195.763737) (xy 379.923429 -195.809706) (xy 379.946276 -195.859453)
			(xy 379.961772 -195.911957) (xy 379.9696 -195.966138) (xy 379.969599 -196.02088) (xy 379.961768 -196.07506)
			(xy 379.946269 -196.127563) (xy 379.923421 -196.17731) (xy 379.893692 -196.223278) (xy 379.87605 -196.24421)
			(xy 379.869954 -196.251322) (xy 379.863604 -196.26834) (xy 379.863604 -196.353684) (xy 379.869954 -196.370702)
			(xy 379.87605 -196.377814) (xy 379.893703 -196.398737) (xy 379.923429 -196.444706) (xy 379.946276 -196.494453)
			(xy 379.961772 -196.546957) (xy 379.9696 -196.601138) (xy 379.969599 -196.65588) (xy 379.961768 -196.71006)
			(xy 379.946269 -196.762563) (xy 379.923421 -196.81231) (xy 379.893692 -196.858278) (xy 379.87605 -196.87921)
			(xy 379.869954 -196.886322) (xy 379.863604 -196.90334) (xy 379.863604 -196.988684) (xy 379.869954 -197.005702)
			(xy 379.87605 -197.012814) (xy 379.893654 -197.033774) (xy 379.923373 -197.079738) (xy 379.946217 -197.129479)
			(xy 379.961716 -197.181973) (xy 379.969552 -197.236145) (xy 379.97003 -197.263512) (xy 379.969519 -197.29135)
			(xy 379.961419 -197.346433) (xy 379.945408 -197.399756) (xy 379.921823 -197.45019) (xy 379.891166 -197.496665)
			(xy 379.873002 -197.517766) (xy 379.866652 -197.524878) (xy 379.860048 -197.542658) (xy 379.861572 -197.63105)
			(xy 379.868684 -197.648576) (xy 379.875288 -197.655688) (xy 379.895007 -197.677132) (xy 379.928415 -197.724854)
			(xy 379.954188 -197.777095) (xy 379.971729 -197.832645) (xy 379.98063 -197.890214) (xy 379.981206 -197.91934)
			(xy 379.980703 -197.946709) (xy 379.972894 -198.000886) (xy 379.957413 -198.053389) (xy 379.93458 -198.103136)
			(xy 379.904863 -198.149105) (xy 379.887226 -198.170038) (xy 379.88113 -198.17715) (xy 379.87478 -198.194168)
			(xy 379.87478 -198.279512) (xy 379.88113 -198.29653) (xy 379.887226 -198.303642) (xy 379.904908 -198.324542)
			(xy 379.934635 -198.370514) (xy 379.95748 -198.420266) (xy 379.972976 -198.472773) (xy 379.980802 -198.526957)
			(xy 379.980797 -198.581703) (xy 379.972963 -198.635886) (xy 379.957459 -198.688391) (xy 379.934606 -198.738139)
			(xy 379.904871 -198.784106) (xy 379.887226 -198.805038) (xy 379.88113 -198.81215) (xy 379.87478 -198.829168)
			(xy 379.87478 -198.914512) (xy 379.88113 -198.93153) (xy 379.887226 -198.938642) (xy 379.904908 -198.959542)
			(xy 379.934635 -199.005514) (xy 379.95748 -199.055266) (xy 379.972976 -199.107773) (xy 379.980802 -199.161957)
			(xy 379.980797 -199.216703) (xy 379.972963 -199.270886) (xy 379.957459 -199.323391) (xy 379.934606 -199.373139)
			(xy 379.904871 -199.419106) (xy 379.887226 -199.440038) (xy 379.88113 -199.44715) (xy 379.87478 -199.464168)
			(xy 379.87478 -199.549512) (xy 379.88113 -199.56653) (xy 379.887226 -199.573642) (xy 379.904855 -199.594582)
			(xy 379.934568 -199.640553) (xy 379.957405 -199.690298) (xy 379.972899 -199.742797) (xy 379.98073 -199.796971)
			(xy 379.981206 -199.82434) (xy 379.980759 -199.851592) (xy 379.972997 -199.905542) (xy 379.957637 -199.957837)
			(xy 379.934991 -200.007415) (xy 379.90552 -200.053265) (xy 379.869825 -200.094455) (xy 379.828631 -200.130146)
			(xy 379.782778 -200.159611) (xy 379.733198 -200.182252) (xy 379.6809 -200.197606) (xy 379.62695 -200.205362)
			(xy 379.599698 -200.205848) (xy 379.572327 -200.205396) (xy 379.518147 -200.197577) (xy 379.465643 -200.182085)
			(xy 379.415896 -200.15924) (xy 379.369931 -200.129511) (xy 379.349 -200.111868) (xy 379.341888 -200.105772)
			(xy 379.32487 -200.099422) (xy 379.239526 -200.099422) (xy 379.222508 -200.105772) (xy 379.215396 -200.111868)
			(xy 379.194463 -200.129509) (xy 379.148495 -200.159233) (xy 379.098749 -200.182079) (xy 379.046247 -200.197575)
			(xy 378.992069 -200.205404) (xy 378.937327 -200.205404) (xy 378.883149 -200.197575) (xy 378.830647 -200.182079)
			(xy 378.780901 -200.159233) (xy 378.734933 -200.129509) (xy 378.714 -200.111868) (xy 378.706888 -200.105772)
			(xy 378.68987 -200.099422) (xy 378.604526 -200.099422) (xy 378.587508 -200.105772) (xy 378.580396 -200.111868)
			(xy 378.559472 -200.129517) (xy 378.513498 -200.159229) (xy 378.463748 -200.182063) (xy 378.411245 -200.197552)
			(xy 378.357068 -200.205376) (xy 378.329698 -200.205848) (xy 378.302449 -200.205324) (xy 378.248504 -200.197568)
			(xy 378.196213 -200.182215) (xy 378.146638 -200.159577) (xy 378.10079 -200.130114) (xy 378.0596 -200.094426)
			(xy 378.023909 -200.053241) (xy 377.994442 -200.007395) (xy 377.971798 -199.957823) (xy 377.95644 -199.905533)
			(xy 377.948679 -199.851589) (xy 377.94819 -199.82434) (xy 377.948682 -199.796971) (xy 377.956494 -199.742793)
			(xy 377.971977 -199.69029) (xy 377.994813 -199.640543) (xy 378.024532 -199.594575) (xy 378.04217 -199.573642)
			(xy 378.048266 -199.56653) (xy 378.054616 -199.549512) (xy 378.054616 -199.464168) (xy 378.048266 -199.44715)
			(xy 378.04217 -199.440038) (xy 378.024567 -199.419074) (xy 377.994837 -199.373113) (xy 377.971987 -199.323372)
			(xy 377.956485 -199.270874) (xy 377.948652 -199.216699) (xy 377.948648 -199.161961) (xy 377.956473 -199.107785)
			(xy 377.971965 -199.055284) (xy 377.994808 -199.00554) (xy 378.02453 -198.959574) (xy 378.04217 -198.938642)
			(xy 378.048266 -198.93153) (xy 378.054616 -198.914512) (xy 378.054616 -198.829168) (xy 378.048266 -198.81215)
			(xy 378.04217 -198.805038) (xy 378.024567 -198.784074) (xy 377.994837 -198.738113) (xy 377.971987 -198.688372)
			(xy 377.956485 -198.635874) (xy 377.948652 -198.581699) (xy 377.948648 -198.526961) (xy 377.956473 -198.472785)
			(xy 377.971965 -198.420284) (xy 377.994808 -198.37054) (xy 378.02453 -198.324574) (xy 378.04217 -198.303642)
			(xy 378.048266 -198.29653) (xy 378.054616 -198.279512) (xy 378.054616 -198.194168) (xy 378.048266 -198.17715)
			(xy 378.04217 -198.170038) (xy 378.024531 -198.149106) (xy 377.99482 -198.103133) (xy 377.971984 -198.053385)
			(xy 377.956493 -198.000885) (xy 377.948665 -197.946709) (xy 377.94819 -197.91934) (xy 377.948668 -197.893038)
			(xy 377.955894 -197.840933) (xy 377.970215 -197.790316) (xy 377.991358 -197.742149) (xy 378.018922 -197.697345)
			(xy 378.035312 -197.67677) (xy 378.041408 -197.669404) (xy 378.04725 -197.652386) (xy 378.04471 -197.566788)
			(xy 378.037852 -197.550024) (xy 378.031502 -197.543166) (xy 378.012619 -197.521877) (xy 377.980695 -197.474774)
			(xy 377.956108 -197.423457) (xy 377.939401 -197.369062) (xy 377.930943 -197.312791) (xy 377.93041 -197.28434)
			(xy 375.58249 -197.28434) (xy 375.582491 -197.308158) (xy 375.574664 -197.362335) (xy 375.559169 -197.414837)
			(xy 375.536325 -197.464582) (xy 375.506602 -197.51055) (xy 375.488962 -197.531482) (xy 375.482866 -197.538594)
			(xy 375.476516 -197.555612) (xy 375.476516 -197.640956) (xy 375.482866 -197.657974) (xy 375.488962 -197.665086)
			(xy 375.506587 -197.686031) (xy 375.536314 -197.731997) (xy 375.559161 -197.781741) (xy 375.574659 -197.834241)
			(xy 375.582489 -197.888418) (xy 375.582491 -197.943158) (xy 375.574664 -197.997335) (xy 375.559169 -198.049837)
			(xy 375.536325 -198.099582) (xy 375.506602 -198.14555) (xy 375.488962 -198.166482) (xy 375.482866 -198.173594)
			(xy 375.476516 -198.190612) (xy 375.476516 -198.275956) (xy 375.482866 -198.292974) (xy 375.488962 -198.300086)
			(xy 375.506587 -198.321031) (xy 375.536314 -198.366997) (xy 375.559161 -198.416741) (xy 375.574659 -198.469241)
			(xy 375.582489 -198.523418) (xy 375.582491 -198.578158) (xy 375.574664 -198.632335) (xy 375.559169 -198.684837)
			(xy 375.536325 -198.734582) (xy 375.506602 -198.78055) (xy 375.488962 -198.801482) (xy 375.482866 -198.808594)
			(xy 375.476516 -198.825612) (xy 375.476516 -198.910956) (xy 375.482866 -198.927974) (xy 375.488962 -198.935086)
			(xy 375.506587 -198.956031) (xy 375.536314 -199.001997) (xy 375.559161 -199.051741) (xy 375.574659 -199.104241)
			(xy 375.582489 -199.158418) (xy 375.582491 -199.213158) (xy 375.574664 -199.267335) (xy 375.559169 -199.319837)
			(xy 375.536325 -199.369582) (xy 375.506602 -199.41555) (xy 375.488962 -199.436482) (xy 375.482866 -199.443594)
			(xy 375.476516 -199.460612) (xy 375.476516 -199.545956) (xy 375.482866 -199.562974) (xy 375.488962 -199.570086)
			(xy 375.506587 -199.591031) (xy 375.536314 -199.636997) (xy 375.559161 -199.686741) (xy 375.574659 -199.739241)
			(xy 375.582489 -199.793418) (xy 375.582491 -199.848158) (xy 375.574664 -199.902335) (xy 375.559169 -199.954837)
			(xy 375.536325 -200.004582) (xy 375.506602 -200.05055) (xy 375.488962 -200.071482) (xy 375.482866 -200.078594)
			(xy 375.476516 -200.095612) (xy 375.476516 -200.180956) (xy 375.482866 -200.197974) (xy 375.488962 -200.205086)
			(xy 375.506587 -200.226031) (xy 375.536314 -200.271997) (xy 375.559161 -200.321741) (xy 375.574659 -200.374241)
			(xy 375.582489 -200.428418) (xy 375.582491 -200.483158) (xy 375.574664 -200.537335) (xy 375.559169 -200.589837)
			(xy 375.536325 -200.639582) (xy 375.506602 -200.68555) (xy 375.488962 -200.706482) (xy 375.482866 -200.713594)
			(xy 375.476516 -200.730612) (xy 375.476516 -200.815956) (xy 375.482866 -200.832974) (xy 375.488962 -200.840086)
			(xy 375.506602 -200.861017) (xy 375.536315 -200.90699) (xy 375.559151 -200.956737) (xy 375.574642 -201.009238)
			(xy 375.582469 -201.063415) (xy 375.582942 -201.090784) (xy 375.582407 -201.118033) (xy 375.574654 -201.171977)
			(xy 375.559302 -201.224269) (xy 375.536665 -201.273844) (xy 375.507204 -201.319693) (xy 375.471518 -201.360882)
			(xy 375.430333 -201.396574) (xy 375.384488 -201.426041) (xy 375.334916 -201.448685) (xy 375.282626 -201.464043)
			(xy 375.228683 -201.471803) (xy 375.201434 -201.472292) (xy 375.174064 -201.471808) (xy 375.119886 -201.463995)
			(xy 375.067383 -201.44851) (xy 375.017636 -201.425672) (xy 374.971668 -201.395951) (xy 374.950736 -201.378312)
			(xy 374.943624 -201.372216) (xy 374.926606 -201.365866) (xy 374.841262 -201.365866) (xy 374.824244 -201.372216)
			(xy 374.817132 -201.378312) (xy 374.796199 -201.395953) (xy 374.750231 -201.425677) (xy 374.700485 -201.448523)
			(xy 374.647983 -201.464019) (xy 374.593805 -201.471848) (xy 374.539063 -201.471848) (xy 374.484885 -201.464019)
			(xy 374.432383 -201.448523) (xy 374.382637 -201.425677) (xy 374.336669 -201.395953) (xy 374.315736 -201.378312)
			(xy 374.308624 -201.372216) (xy 374.291606 -201.365866) (xy 374.206262 -201.365866) (xy 374.189244 -201.372216)
			(xy 374.182132 -201.378312) (xy 374.1612 -201.395951) (xy 374.115227 -201.425663) (xy 374.06548 -201.448498)
			(xy 374.012979 -201.46399) (xy 373.958803 -201.471818) (xy 373.931434 -201.472292) (xy 373.904181 -201.471813)
			(xy 373.85023 -201.46406) (xy 373.797932 -201.448708) (xy 373.74835 -201.426068) (xy 373.702496 -201.396602)
			(xy 373.661303 -201.36091) (xy 373.625609 -201.319718) (xy 373.596141 -201.273865) (xy 373.573499 -201.224285)
			(xy 373.558144 -201.171988) (xy 373.550388 -201.118037) (xy 373.549926 -201.090784) (xy 373.550376 -201.063413)
			(xy 373.558197 -201.009233) (xy 373.573689 -200.95673) (xy 373.596535 -200.906983) (xy 373.626263 -200.861017)
			(xy 373.643906 -200.840086) (xy 373.650002 -200.832974) (xy 373.656352 -200.815956) (xy 373.656352 -200.730612)
			(xy 373.650002 -200.713594) (xy 373.643906 -200.706482) (xy 373.626251 -200.685562) (xy 373.596528 -200.639591)
			(xy 373.573685 -200.589843) (xy 373.558191 -200.537339) (xy 373.550364 -200.483159) (xy 373.550366 -200.428417)
			(xy 373.558196 -200.374237) (xy 373.573693 -200.321735) (xy 373.59654 -200.271988) (xy 373.626265 -200.226019)
			(xy 373.643906 -200.205086) (xy 373.650002 -200.197974) (xy 373.656352 -200.180956) (xy 373.656352 -200.095612)
			(xy 373.650002 -200.078594) (xy 373.643906 -200.071482) (xy 373.626251 -200.050562) (xy 373.596528 -200.004591)
			(xy 373.573685 -199.954843) (xy 373.558191 -199.902339) (xy 373.550364 -199.848159) (xy 373.550366 -199.793417)
			(xy 373.558196 -199.739237) (xy 373.573693 -199.686735) (xy 373.59654 -199.636988) (xy 373.626265 -199.591019)
			(xy 373.643906 -199.570086) (xy 373.650002 -199.562974) (xy 373.656352 -199.545956) (xy 373.656352 -199.460612)
			(xy 373.650002 -199.443594) (xy 373.643906 -199.436482) (xy 373.626251 -199.415562) (xy 373.596528 -199.369591)
			(xy 373.573685 -199.319843) (xy 373.558191 -199.267339) (xy 373.550364 -199.213159) (xy 373.550366 -199.158417)
			(xy 373.558196 -199.104237) (xy 373.573693 -199.051735) (xy 373.59654 -199.001988) (xy 373.626265 -198.956019)
			(xy 373.643906 -198.935086) (xy 373.650002 -198.927974) (xy 373.656352 -198.910956) (xy 373.656352 -198.825612)
			(xy 373.650002 -198.808594) (xy 373.643906 -198.801482) (xy 373.626251 -198.780562) (xy 373.596528 -198.734591)
			(xy 373.573685 -198.684843) (xy 373.558191 -198.632339) (xy 373.550364 -198.578159) (xy 373.550366 -198.523417)
			(xy 373.558196 -198.469237) (xy 373.573693 -198.416735) (xy 373.59654 -198.366988) (xy 373.626265 -198.321019)
			(xy 373.643906 -198.300086) (xy 373.650002 -198.292974) (xy 373.656352 -198.275956) (xy 373.656352 -198.190612)
			(xy 373.650002 -198.173594) (xy 373.643906 -198.166482) (xy 373.626293 -198.145529) (xy 373.596577 -198.099562)
			(xy 373.573736 -198.04982) (xy 373.558239 -197.997324) (xy 373.550404 -197.943152) (xy 373.549926 -197.915784)
			(xy 373.550459 -197.887639) (xy 373.558725 -197.83196) (xy 373.575076 -197.778097) (xy 373.599158 -197.727219)
			(xy 373.630447 -197.680427) (xy 373.648986 -197.659244) (xy 373.655336 -197.652132) (xy 373.662194 -197.634606)
			(xy 373.66194 -197.546722) (xy 373.654828 -197.529196) (xy 373.648478 -197.522084) (xy 373.62959 -197.500829)
			(xy 373.597656 -197.453785) (xy 373.573064 -197.402519) (xy 373.556359 -197.348169) (xy 373.547912 -197.291941)
			(xy 373.547386 -197.263512) (xy 373.547863 -197.236142) (xy 373.555678 -197.181964) (xy 373.571165 -197.129461)
			(xy 373.594004 -197.079714) (xy 373.623726 -197.033746) (xy 373.641366 -197.012814) (xy 373.647462 -197.005702)
			(xy 373.653812 -196.988684) (xy 373.653812 -196.90334) (xy 373.647462 -196.886322) (xy 373.641366 -196.87921)
			(xy 373.623735 -196.858269) (xy 373.594007 -196.812303) (xy 373.571159 -196.762559) (xy 373.55566 -196.710058)
			(xy 373.547829 -196.65588) (xy 373.547828 -196.601139) (xy 373.555656 -196.54696) (xy 373.571152 -196.494458)
			(xy 373.593998 -196.444713) (xy 373.623725 -196.398746) (xy 373.641366 -196.377814) (xy 373.647462 -196.370702)
			(xy 373.653812 -196.353684) (xy 373.653812 -196.26834) (xy 373.647462 -196.251322) (xy 373.641366 -196.24421)
			(xy 373.623735 -196.223269) (xy 373.594007 -196.177303) (xy 373.571159 -196.127559) (xy 373.55566 -196.075058)
			(xy 373.547829 -196.02088) (xy 373.547828 -195.966139) (xy 373.555656 -195.91196) (xy 373.571152 -195.859458)
			(xy 373.593998 -195.809713) (xy 373.623725 -195.763746) (xy 373.641366 -195.742814) (xy 373.647462 -195.735702)
			(xy 373.653812 -195.718684) (xy 373.653812 -195.63334) (xy 373.647462 -195.616322) (xy 373.641366 -195.60921)
			(xy 373.623713 -195.588289) (xy 373.594004 -195.542313) (xy 373.571172 -195.492562) (xy 373.555684 -195.440059)
			(xy 373.547859 -195.385882) (xy 373.547386 -195.358512) (xy 373.547824 -195.331377) (xy 373.55552 -195.277654)
			(xy 373.570759 -195.225567) (xy 373.593232 -195.176167) (xy 373.622484 -195.130455) (xy 373.639842 -195.109592)
			(xy 373.645938 -195.10248) (xy 373.652034 -195.085462) (xy 373.651526 -195.000118) (xy 373.645176 -194.9831)
			(xy 373.638826 -194.975988) (xy 373.620929 -194.954967) (xy 373.590737 -194.908747) (xy 373.567523 -194.858658)
			(xy 373.551771 -194.805746) (xy 373.543812 -194.751116) (xy 373.543322 -194.723512) (xy 371.560598 -194.723512)
			(xy 371.560133 -194.750482) (xy 371.552525 -194.803882) (xy 371.537465 -194.855676) (xy 371.515251 -194.90483)
			(xy 371.486329 -194.95036) (xy 371.469158 -194.971162) (xy 371.463062 -194.978274) (xy 371.456966 -194.995292)
			(xy 371.457728 -195.08089) (xy 371.464332 -195.097654) (xy 371.470682 -195.104766) (xy 371.488769 -195.125842)
			(xy 371.519276 -195.172249) (xy 371.542738 -195.222587) (xy 371.558659 -195.275793) (xy 371.566704 -195.330744)
			(xy 371.567202 -195.358512) (xy 371.566742 -195.385882) (xy 371.558923 -195.440062) (xy 371.543432 -195.492565)
			(xy 371.520589 -195.542312) (xy 371.490864 -195.588278) (xy 371.473222 -195.60921) (xy 371.467126 -195.616322)
			(xy 371.460776 -195.63334) (xy 371.460776 -195.718684) (xy 371.467126 -195.735702) (xy 371.473222 -195.742814)
			(xy 371.490872 -195.763738) (xy 371.520593 -195.809709) (xy 371.543435 -195.859457) (xy 371.558928 -195.91196)
			(xy 371.566754 -195.966138) (xy 371.566753 -196.02088) (xy 371.558924 -196.075058) (xy 371.543428 -196.12756)
			(xy 371.520584 -196.177307) (xy 371.490861 -196.223276) (xy 371.473222 -196.24421) (xy 371.467126 -196.251322)
			(xy 371.460776 -196.26834) (xy 371.460776 -196.353684) (xy 371.467126 -196.370702) (xy 371.473222 -196.377814)
			(xy 371.490872 -196.398738) (xy 371.520593 -196.444709) (xy 371.543435 -196.494457) (xy 371.558928 -196.54696)
			(xy 371.566754 -196.601138) (xy 371.566753 -196.65588) (xy 371.558924 -196.710058) (xy 371.543428 -196.76256)
			(xy 371.520584 -196.812307) (xy 371.490861 -196.858276) (xy 371.473222 -196.87921) (xy 371.467126 -196.886322)
			(xy 371.460776 -196.90334) (xy 371.460776 -196.988684) (xy 371.467126 -197.005702) (xy 371.473222 -197.012814)
			(xy 371.490838 -197.033765) (xy 371.520552 -197.079733) (xy 371.543392 -197.129476) (xy 371.558889 -197.181972)
			(xy 371.566724 -197.236144) (xy 371.567202 -197.263512) (xy 371.566685 -197.291658) (xy 371.558418 -197.347339)
			(xy 371.542064 -197.401202) (xy 371.517979 -197.45208) (xy 371.486683 -197.498871) (xy 371.468142 -197.520052)
			(xy 371.461792 -197.527164) (xy 371.454934 -197.54469) (xy 371.455188 -197.632574) (xy 371.4623 -197.6501)
			(xy 371.46865 -197.657212) (xy 371.48754 -197.678465) (xy 371.519473 -197.72551) (xy 371.544064 -197.776776)
			(xy 371.560768 -197.831126) (xy 371.569215 -197.887354) (xy 371.569742 -197.915784) (xy 371.569281 -197.943155)
			(xy 371.561464 -197.997334) (xy 371.545974 -198.049838) (xy 371.523131 -198.099585) (xy 371.493405 -198.145551)
			(xy 371.475762 -198.166482) (xy 371.469666 -198.173594) (xy 371.463316 -198.190612) (xy 371.463316 -198.275956)
			(xy 371.469666 -198.292974) (xy 371.475762 -198.300086) (xy 371.493387 -198.321031) (xy 371.523114 -198.366997)
			(xy 371.545961 -198.416741) (xy 371.561459 -198.469241) (xy 371.569289 -198.523418) (xy 371.569291 -198.578158)
			(xy 371.561464 -198.632335) (xy 371.545969 -198.684837) (xy 371.523125 -198.734582) (xy 371.493402 -198.78055)
			(xy 371.475762 -198.801482) (xy 371.469666 -198.808594) (xy 371.463316 -198.825612) (xy 371.463316 -198.910956)
			(xy 371.469666 -198.927974) (xy 371.475762 -198.935086) (xy 371.493387 -198.956031) (xy 371.523114 -199.001997)
			(xy 371.545961 -199.051741) (xy 371.561459 -199.104241) (xy 371.569289 -199.158418) (xy 371.569291 -199.213158)
			(xy 371.561464 -199.267335) (xy 371.545969 -199.319837) (xy 371.523125 -199.369582) (xy 371.493402 -199.41555)
			(xy 371.475762 -199.436482) (xy 371.469666 -199.443594) (xy 371.463316 -199.460612) (xy 371.463316 -199.545956)
			(xy 371.469666 -199.562974) (xy 371.475762 -199.570086) (xy 371.493387 -199.591031) (xy 371.523114 -199.636997)
			(xy 371.545961 -199.686741) (xy 371.561459 -199.739241) (xy 371.569289 -199.793418) (xy 371.569291 -199.848158)
			(xy 371.561464 -199.902335) (xy 371.545969 -199.954837) (xy 371.523125 -200.004582) (xy 371.493402 -200.05055)
			(xy 371.475762 -200.071482) (xy 371.469666 -200.078594) (xy 371.463316 -200.095612) (xy 371.463316 -200.180956)
			(xy 371.469666 -200.197974) (xy 371.475762 -200.205086) (xy 371.493387 -200.226031) (xy 371.523114 -200.271997)
			(xy 371.545961 -200.321741) (xy 371.561459 -200.374241) (xy 371.569289 -200.428418) (xy 371.569291 -200.483158)
			(xy 371.561464 -200.537335) (xy 371.545969 -200.589837) (xy 371.523125 -200.639582) (xy 371.493402 -200.68555)
			(xy 371.475762 -200.706482) (xy 371.469666 -200.713594) (xy 371.463316 -200.730612) (xy 371.463316 -200.815956)
			(xy 371.469666 -200.832974) (xy 371.475762 -200.840086) (xy 371.493402 -200.861017) (xy 371.523115 -200.90699)
			(xy 371.545951 -200.956737) (xy 371.561442 -201.009238) (xy 371.569269 -201.063415) (xy 371.569742 -201.090784)
			(xy 371.569256 -201.118035) (xy 371.5615 -201.171983) (xy 371.546145 -201.224278) (xy 371.523503 -201.273855)
			(xy 371.494037 -201.319705) (xy 371.458346 -201.360896) (xy 371.417155 -201.396587) (xy 371.371305 -201.426053)
			(xy 371.321728 -201.448695) (xy 371.269433 -201.46405) (xy 371.215485 -201.471806) (xy 371.160983 -201.471806)
			(xy 371.107035 -201.46405) (xy 371.05474 -201.448695) (xy 371.005163 -201.426053) (xy 370.959313 -201.396587)
			(xy 370.918122 -201.360896) (xy 370.882431 -201.319705) (xy 370.852965 -201.273855) (xy 370.830323 -201.224278)
			(xy 370.814968 -201.171983) (xy 370.807212 -201.118035) (xy 370.806726 -201.090784) (xy 370.807176 -201.063413)
			(xy 370.814997 -201.009233) (xy 370.830489 -200.95673) (xy 370.853335 -200.906983) (xy 370.883063 -200.861017)
			(xy 370.900706 -200.840086) (xy 370.906802 -200.832974) (xy 370.913152 -200.815956) (xy 370.913152 -200.730612)
			(xy 370.906802 -200.713594) (xy 370.900706 -200.706482) (xy 370.883093 -200.685529) (xy 370.853377 -200.639562)
			(xy 370.830536 -200.58982) (xy 370.815039 -200.537324) (xy 370.807204 -200.483152) (xy 370.806726 -200.455784)
			(xy 370.807249 -200.426306) (xy 370.816321 -200.368051) (xy 370.834247 -200.311886) (xy 370.860601 -200.259147)
			(xy 370.894753 -200.21109) (xy 370.91493 -200.189592) (xy 370.921465 -200.182258) (xy 370.928909 -200.164097)
			(xy 370.929408 -200.154286) (xy 370.929408 -200.100946) (xy 370.922042 -200.094088) (xy 370.914689 -200.087577)
			(xy 370.896543 -200.080118) (xy 370.886736 -200.07961) (xy 370.854732 -200.07961) (xy 370.844914 -200.080068)
			(xy 370.82675 -200.087532) (xy 370.819426 -200.094088) (xy 370.797921 -200.114255) (xy 370.749862 -200.1484)
			(xy 370.697124 -200.174746) (xy 370.640961 -200.192669) (xy 370.582711 -200.201741) (xy 370.553234 -200.202292)
			(xy 370.525981 -200.201813) (xy 370.47203 -200.19406) (xy 370.419732 -200.178708) (xy 370.37015 -200.156068)
			(xy 370.324296 -200.126602) (xy 370.283103 -200.09091) (xy 370.247409 -200.049718) (xy 370.217941 -200.003865)
			(xy 370.195299 -199.954285) (xy 370.179944 -199.901988) (xy 370.172188 -199.848037) (xy 370.171726 -199.820784)
			(xy 370.172249 -199.791306) (xy 370.181321 -199.733051) (xy 370.199247 -199.676886) (xy 370.225601 -199.624147)
			(xy 370.259753 -199.57609) (xy 370.27993 -199.554592) (xy 370.286465 -199.547258) (xy 370.293909 -199.529097)
			(xy 370.294408 -199.519286) (xy 370.294408 -199.465946) (xy 370.288566 -199.460612) (xy 370.281141 -199.454125)
			(xy 370.262856 -199.446801) (xy 370.253006 -199.446388) (xy 370.221256 -199.446642) (xy 370.211442 -199.44713)
			(xy 370.193279 -199.454575) (xy 370.18595 -199.46112) (xy 370.16443 -199.481586) (xy 370.116174 -199.516201)
			(xy 370.063136 -199.542919) (xy 370.006599 -199.561094) (xy 369.947928 -199.570287) (xy 369.918234 -199.570848)
			(xy 369.890985 -199.57029) (xy 369.837042 -199.562539) (xy 369.784751 -199.547191) (xy 369.735177 -199.524556)
			(xy 369.689329 -199.495097) (xy 369.648139 -199.459413) (xy 369.612447 -199.418231) (xy 369.582979 -199.372388)
			(xy 369.560335 -199.322818) (xy 369.544976 -199.27053) (xy 369.537215 -199.216588) (xy 369.536726 -199.18934)
			(xy 369.537209 -199.16197) (xy 369.545022 -199.107792) (xy 369.560507 -199.055289) (xy 369.583345 -199.005541)
			(xy 369.613066 -198.959574) (xy 369.630706 -198.938642) (xy 369.636802 -198.93153) (xy 369.643152 -198.914512)
			(xy 369.643152 -198.829168) (xy 369.636802 -198.81215) (xy 369.630706 -198.805038) (xy 369.613105 -198.784073)
			(xy 369.583381 -198.73811) (xy 369.560534 -198.688369) (xy 369.545036 -198.635872) (xy 369.537204 -198.581699)
			(xy 369.537199 -198.526962) (xy 369.545023 -198.472787) (xy 369.560513 -198.420287) (xy 369.583352 -198.370543)
			(xy 369.613069 -198.324575) (xy 369.630706 -198.303642) (xy 369.636802 -198.29653) (xy 369.643152 -198.279512)
			(xy 369.643152 -198.194168) (xy 369.636802 -198.17715) (xy 369.630706 -198.170038) (xy 369.613072 -198.149102)
			(xy 369.583359 -198.10313) (xy 369.560522 -198.053384) (xy 369.54503 -198.000884) (xy 369.537201 -197.946709)
			(xy 369.536726 -197.91934) (xy 369.537161 -197.892509) (xy 369.544677 -197.839377) (xy 369.559567 -197.787823)
			(xy 369.581536 -197.738865) (xy 369.610151 -197.693469) (xy 369.62715 -197.672706) (xy 369.633246 -197.665594)
			(xy 369.639342 -197.648576) (xy 369.638072 -197.562978) (xy 369.631468 -197.546214) (xy 369.625118 -197.539102)
			(xy 369.60687 -197.517978) (xy 369.576037 -197.471447) (xy 369.552316 -197.420918) (xy 369.536213 -197.367472)
			(xy 369.528071 -197.31225) (xy 369.527582 -197.28434) (xy 365.780803 -197.28434) (xy 368.772186 -199.734424)
			(xy 368.777774 -199.73925) (xy 368.778536 -199.740012) (xy 368.83594 -199.786748) (xy 368.839292 -199.789661)
			(xy 368.84504 -199.79643) (xy 368.84737 -199.80021) (xy 368.887756 -199.86879) (xy 368.88801 -199.869298)
			(xy 368.895122 -199.880982) (xy 370.248942 -202.17257) (xy 370.253744 -202.179943) (xy 370.267298 -202.191143)
			(xy 370.283839 -202.197105) (xy 370.29263 -202.197462)
		)
		(stroke
			(width 0)
			(type solid)
		)
		(fill yes)
		(layer "In11.Cu")
		(net "GND")
	)
	(gr_poly
		(pts
			(xy 385.582668 -263.71931) (xy 385.587344 -263.719226) (xy 385.596545 -263.717561) (xy 385.600956 -263.716008)
			(xy 385.611116 -263.711944) (xy 385.617661 -263.709207) (xy 385.629 -263.700691) (xy 385.633468 -263.69518)
			(xy 385.63677 -263.6901) (xy 385.642612 -263.680194) (xy 385.64439 -263.673082) (xy 385.654532 -263.636026)
			(xy 385.683591 -263.564905) (xy 385.702302 -263.53135) (xy 385.762246 -263.428226) (xy 385.767436 -263.417934)
			(xy 385.769148 -263.39498) (xy 385.765548 -263.38403) (xy 385.732528 -263.300718) (xy 385.71551 -263.28497)
			(xy 385.704334 -263.281668) (xy 385.67414 -263.272166) (xy 385.61594 -263.247271) (xy 385.560925 -263.21596)
			(xy 385.5098 -263.178634) (xy 385.463218 -263.135772) (xy 385.421777 -263.087921) (xy 385.386008 -263.035695)
			(xy 385.356367 -262.979762) (xy 385.344416 -262.950452) (xy 385.339336 -262.937498) (xy 385.317492 -262.92048)
			(xy 385.217924 -262.907272) (xy 385.208886 -262.906455) (xy 385.191212 -262.910512) (xy 385.176068 -262.920485)
			(xy 385.170426 -262.927592) (xy 385.155908 -262.946438) (xy 385.122018 -262.979819) (xy 385.083363 -263.007544)
			(xy 385.040878 -263.028942) (xy 384.99559 -263.043497) (xy 384.948593 -263.050856) (xy 384.924808 -263.05129)
			(xy 384.899551 -263.050798) (xy 384.849727 -263.042485) (xy 384.80195 -263.026084) (xy 384.757525 -263.002043)
			(xy 384.717662 -262.971018) (xy 384.68345 -262.933855) (xy 384.655821 -262.891567) (xy 384.63553 -262.845308)
			(xy 384.623129 -262.796341) (xy 384.618958 -262.746) (xy 384.623129 -262.695659) (xy 384.63553 -262.646692)
			(xy 384.655821 -262.600433) (xy 384.68345 -262.558145) (xy 384.717662 -262.520982) (xy 384.757525 -262.489957)
			(xy 384.80195 -262.465916) (xy 384.849727 -262.449515) (xy 384.899551 -262.441202) (xy 384.924808 -262.440674)
			(xy 384.948595 -262.441106) (xy 384.995599 -262.448445) (xy 385.040894 -262.462989) (xy 385.083384 -262.484387)
			(xy 385.122037 -262.512121) (xy 385.155918 -262.545517) (xy 385.170426 -262.564372) (xy 385.176085 -262.571461)
			(xy 385.191226 -262.581429) (xy 385.20889 -262.585504) (xy 385.217924 -262.584692) (xy 385.317746 -262.571484)
			(xy 385.339336 -262.554466) (xy 385.344416 -262.541512) (xy 385.35234 -262.521806) (xy 385.370778 -262.483539)
			(xy 385.381246 -262.465058) (xy 385.42595 -262.388096) (xy 385.431743 -262.376883) (xy 385.43269 -262.351693)
			(xy 385.427728 -262.34009) (xy 385.391406 -262.26643) (xy 385.385353 -262.255472) (xy 385.3651 -262.240806)
			(xy 385.352798 -262.23849) (xy 385.328765 -262.234689) (xy 385.282237 -262.220461) (xy 385.238556 -262.199031)
			(xy 385.198828 -262.170941) (xy 385.164062 -262.136904) (xy 385.135136 -262.097781) (xy 385.112785 -262.054564)
			(xy 385.097574 -262.008348) (xy 385.089889 -261.960304) (xy 385.0894 -261.935976) (xy 385.089872 -261.911986)
			(xy 385.097382 -261.864598) (xy 385.112211 -261.818968) (xy 385.133996 -261.776219) (xy 385.1622 -261.737404)
			(xy 385.196129 -261.703479) (xy 385.234946 -261.675279) (xy 385.277697 -261.653499) (xy 385.323329 -261.638674)
			(xy 385.370718 -261.63117) (xy 385.394708 -261.630668) (xy 385.406248 -261.630795) (xy 385.42926 -261.632574)
			(xy 385.440682 -261.634224) (xy 385.444492 -261.634732) (xy 385.445508 -261.634732) (xy 385.467963 -261.638955)
			(xy 385.51138 -261.653182) (xy 385.552196 -261.673711) (xy 385.589503 -261.700087) (xy 385.62247 -261.73172)
			(xy 385.63677 -261.74954) (xy 385.63677 -261.749794) (xy 385.644991 -261.759295) (xy 385.667896 -261.769553)
			(xy 385.680458 -261.769352) (xy 385.7625 -261.763764) (xy 385.775012 -261.762305) (xy 385.796344 -261.748971)
			(xy 385.80314 -261.738364) (xy 385.823714 -261.702296) (xy 385.828032 -261.692644) (xy 385.830318 -261.680706)
			(xy 385.830572 -261.676896) (xy 385.830572 -261.454138) (xy 385.809236 -261.42696) (xy 385.791964 -261.422642)
			(xy 385.767427 -261.416074) (xy 385.720801 -261.395928) (xy 385.678149 -261.368348) (xy 385.640645 -261.334094)
			(xy 385.609322 -261.29411) (xy 385.585043 -261.249496) (xy 385.568476 -261.201482) (xy 385.560078 -261.151389)
			(xy 385.560079 -261.100597) (xy 385.56848 -261.050504) (xy 385.585049 -261.00249) (xy 385.60933 -260.957878)
			(xy 385.640655 -260.917895) (xy 385.67816 -260.883643) (xy 385.720814 -260.856065) (xy 385.76744 -260.835921)
			(xy 385.791964 -260.829298) (xy 385.809236 -260.82498) (xy 385.830572 -260.797802) (xy 385.830572 -257.004566)
			(xy 385.830572 -257.001518) (xy 385.829391 -256.990618) (xy 385.819121 -256.971273) (xy 385.81076 -256.96418)
			(xy 385.807458 -256.961894) (xy 385.726686 -256.90957) (xy 385.701286 -256.907538) (xy 385.689348 -256.912872)
			(xy 385.669686 -256.921276) (xy 385.628602 -256.93313) (xy 385.586267 -256.93915) (xy 385.564888 -256.939542)
			(xy 385.540896 -256.939071) (xy 385.493504 -256.931563) (xy 385.44787 -256.916735) (xy 385.405116 -256.894951)
			(xy 385.366296 -256.866748) (xy 385.332366 -256.83282) (xy 385.30416 -256.794003) (xy 385.282373 -256.751251)
			(xy 385.267542 -256.705617) (xy 385.260031 -256.658226) (xy 385.25958 -256.634234) (xy 385.260046 -256.609627)
			(xy 385.267936 -256.561051) (xy 385.283518 -256.51437) (xy 385.306388 -256.470793) (xy 385.335952 -256.43145)
			(xy 385.371446 -256.39736) (xy 385.41195 -256.369407) (xy 385.456413 -256.348313) (xy 385.503685 -256.334627)
			(xy 385.528058 -256.331212) (xy 385.542028 -256.329434) (xy 385.563618 -256.312924) (xy 385.607306 -256.207768)
			(xy 385.603496 -256.180336) (xy 385.59486 -256.169668) (xy 385.583348 -256.154749) (xy 385.562123 -256.123606)
			(xy 385.552442 -256.107438) (xy 385.54914 -256.101596) (xy 385.469638 -256.022094) (xy 385.462018 -256.014474)
			(xy 385.442714 -256.006854) (xy 385.349496 -256.009648) (xy 385.330446 -256.018538) (xy 385.323588 -256.026412)
			(xy 385.306031 -256.045436) (xy 385.26569 -256.077871) (xy 385.220461 -256.103047) (xy 385.171638 -256.120243)
			(xy 385.120616 -256.128969) (xy 385.094734 -256.129536) (xy 385.070738 -256.129092) (xy 385.023337 -256.12159)
			(xy 384.977693 -256.106765) (xy 384.93493 -256.084982) (xy 384.896102 -256.056777) (xy 384.862163 -256.022846)
			(xy 384.833951 -255.984023) (xy 384.812159 -255.941264) (xy 384.797324 -255.895623) (xy 384.789813 -255.848224)
			(xy 384.789426 -255.824228) (xy 384.789903 -255.799905) (xy 384.797624 -255.751877) (xy 384.812859 -255.705679)
			(xy 384.835223 -255.662479) (xy 384.864151 -255.62337) (xy 384.898911 -255.589339) (xy 384.938626 -255.561248)
			(xy 384.98229 -255.539805) (xy 385.028801 -255.525554) (xy 385.052824 -255.521714) (xy 385.065093 -255.519323)
			(xy 385.085313 -255.504674) (xy 385.091432 -255.493774) (xy 385.127754 -255.420114) (xy 385.132692 -255.408505)
			(xy 385.131746 -255.383328) (xy 385.125976 -255.372108) (xy 385.081272 -255.295146) (xy 385.070802 -255.276666)
			(xy 385.052368 -255.238397) (xy 385.044442 -255.218692) (xy 385.039362 -255.205738) (xy 385.017772 -255.18872)
			(xy 384.91795 -255.175512) (xy 384.908911 -255.174691) (xy 384.891233 -255.178743) (xy 384.876087 -255.188718)
			(xy 384.870452 -255.195832) (xy 384.855937 -255.214682) (xy 384.82205 -255.248072) (xy 384.783396 -255.275806)
			(xy 384.740911 -255.297212) (xy 384.695621 -255.311774) (xy 384.648621 -255.319139) (xy 384.624834 -255.31953)
			(xy 384.599573 -255.31904) (xy 384.549738 -255.310729) (xy 384.501952 -255.294329) (xy 384.457516 -255.270286)
			(xy 384.417645 -255.239257) (xy 384.383425 -255.202088) (xy 384.35579 -255.159793) (xy 384.335494 -255.113527)
			(xy 384.32309 -255.06455) (xy 384.318918 -255.0142) (xy 384.32309 -254.96385) (xy 384.335494 -254.914873)
			(xy 384.35579 -254.868607) (xy 384.383425 -254.826312) (xy 384.417645 -254.789143) (xy 384.457516 -254.758114)
			(xy 384.501952 -254.734071) (xy 384.549738 -254.717671) (xy 384.599573 -254.70936) (xy 384.624834 -254.708914)
			(xy 384.64862 -254.709349) (xy 384.69562 -254.716691) (xy 384.740911 -254.73124) (xy 384.783396 -254.752642)
			(xy 384.822043 -254.780379) (xy 384.855917 -254.813778) (xy 384.870452 -254.832612) (xy 384.876108 -254.839705)
			(xy 384.891249 -254.849677) (xy 384.908915 -254.853748) (xy 384.91795 -254.852932) (xy 385.017518 -254.839724)
			(xy 385.039362 -254.822706) (xy 385.044442 -254.809752) (xy 385.056169 -254.781061) (xy 385.085081 -254.726233)
			(xy 385.119872 -254.674933) (xy 385.160116 -254.62779) (xy 385.205321 -254.58538) (xy 385.254934 -254.548223)
			(xy 385.281424 -254.53213) (xy 385.281678 -254.53213) (xy 385.287177 -254.528572) (xy 385.296297 -254.519178)
			(xy 385.299712 -254.513588) (xy 385.311396 -254.493522) (xy 385.314532 -254.487643) (xy 385.317994 -254.474781)
			(xy 385.318254 -254.468122) (xy 385.318254 -254.075946) (xy 385.318129 -254.071134) (xy 385.316336 -254.061677)
			(xy 385.314698 -254.05715) (xy 385.304792 -254.032258) (xy 385.298696 -254.0254) (xy 385.298696 -254.025146)
			(xy 385.279451 -254.003325) (xy 385.245089 -253.956367) (xy 385.230116 -253.93142) (xy 385.081272 -253.675134)
			(xy 385.070802 -253.656654) (xy 385.052369 -253.618385) (xy 385.044442 -253.59868) (xy 385.039362 -253.585726)
			(xy 385.017772 -253.568708) (xy 384.91795 -253.5555) (xy 384.908911 -253.554679) (xy 384.891232 -253.55873)
			(xy 384.876084 -253.568704) (xy 384.870452 -253.57582) (xy 384.855934 -253.594665) (xy 384.822043 -253.628047)
			(xy 384.783388 -253.655772) (xy 384.740904 -253.677172) (xy 384.695616 -253.691729) (xy 384.648619 -253.699091)
			(xy 384.624834 -253.699518) (xy 384.599574 -253.699028) (xy 384.549741 -253.690718) (xy 384.501956 -253.674318)
			(xy 384.457523 -253.650276) (xy 384.417653 -253.619248) (xy 384.383434 -253.582081) (xy 384.3558 -253.539787)
			(xy 384.335505 -253.493523) (xy 384.323102 -253.444548) (xy 384.31893 -253.3942) (xy 384.323102 -253.343852)
			(xy 384.335505 -253.294877) (xy 384.3558 -253.248613) (xy 384.383434 -253.206319) (xy 384.417653 -253.169152)
			(xy 384.457523 -253.138124) (xy 384.501956 -253.114082) (xy 384.549741 -253.097682) (xy 384.599574 -253.089372)
			(xy 384.624834 -253.088902) (xy 384.64862 -253.089337) (xy 384.695621 -253.096679) (xy 384.740912 -253.111227)
			(xy 384.783397 -253.132629) (xy 384.822045 -253.160365) (xy 384.85592 -253.193763) (xy 384.870452 -253.2126)
			(xy 384.876108 -253.219694) (xy 384.891248 -253.229669) (xy 384.908915 -253.233741) (xy 384.91795 -253.23292)
			(xy 385.017772 -253.219712) (xy 385.039362 -253.202694) (xy 385.044442 -253.18974) (xy 385.059992 -253.152068)
			(xy 385.100414 -253.081304) (xy 385.12496 -253.04877) (xy 385.130228 -253.04143) (xy 385.135725 -253.024232)
			(xy 385.134946 -253.006193) (xy 385.131818 -252.997716) (xy 385.093464 -252.905514) (xy 385.071874 -252.889258)
			(xy 385.058158 -252.88748) (xy 385.033852 -252.884059) (xy 384.986688 -252.870472) (xy 384.942304 -252.849517)
			(xy 384.901841 -252.821736) (xy 384.866341 -252.787842) (xy 384.836717 -252.748708) (xy 384.813732 -252.705341)
			(xy 384.797977 -252.658856) (xy 384.789858 -252.610451) (xy 384.789582 -252.56137) (xy 384.797159 -252.512876)
			(xy 384.812391 -252.466218) (xy 384.834889 -252.422595) (xy 384.849116 -252.402594) (xy 384.863964 -252.383298)
			(xy 384.898747 -252.349232) (xy 384.938498 -252.321123) (xy 384.982209 -252.299683) (xy 385.02877 -252.285457)
			(xy 385.052824 -252.28169) (xy 385.065091 -252.279298) (xy 385.085305 -252.264646) (xy 385.091432 -252.25375)
			(xy 385.127754 -252.18009) (xy 385.13271 -252.16848) (xy 385.131797 -252.143283) (xy 385.125976 -252.132084)
			(xy 385.081272 -252.055122) (xy 385.063352 -252.023051) (xy 385.035146 -251.955216) (xy 385.016063 -251.884271)
			(xy 385.006431 -251.811439) (xy 385.005834 -251.774706) (xy 385.005834 -251.77369) (xy 385.006248 -251.742703)
			(xy 385.013099 -251.68111) (xy 385.026725 -251.620653) (xy 385.046959 -251.562076) (xy 385.073553 -251.506099)
			(xy 385.10618 -251.453409) (xy 385.12496 -251.428758) (xy 385.133596 -251.417582) (xy 385.137406 -251.390658)
			(xy 385.093464 -251.285502) (xy 385.071874 -251.269246) (xy 385.058158 -251.267468) (xy 385.033852 -251.264047)
			(xy 384.98669 -251.25046) (xy 384.942307 -251.229506) (xy 384.901846 -251.201725) (xy 384.866347 -251.167831)
			(xy 384.836725 -251.128698) (xy 384.813741 -251.085331) (xy 384.797987 -251.038847) (xy 384.789869 -250.990443)
			(xy 384.789595 -250.941363) (xy 384.797172 -250.892871) (xy 384.812406 -250.846214) (xy 384.834904 -250.802594)
			(xy 384.849116 -250.782582) (xy 384.863964 -250.763286) (xy 384.898748 -250.729222) (xy 384.938499 -250.701114)
			(xy 384.98221 -250.679675) (xy 385.028771 -250.66545) (xy 385.052824 -250.661678) (xy 385.06509 -250.659285)
			(xy 385.085301 -250.644631) (xy 385.091432 -250.633738) (xy 385.127754 -250.560078) (xy 385.132708 -250.548468)
			(xy 385.131789 -250.523275) (xy 385.125976 -250.512072) (xy 385.081272 -250.43511) (xy 385.070803 -250.41663)
			(xy 385.052371 -250.37836) (xy 385.044442 -250.358656) (xy 385.039362 -250.345702) (xy 385.017772 -250.328684)
			(xy 384.91795 -250.315476) (xy 384.908911 -250.314655) (xy 384.89123 -250.318705) (xy 384.876079 -250.328676)
			(xy 384.870452 -250.335796) (xy 384.855935 -250.354643) (xy 384.822045 -250.388026) (xy 384.783391 -250.415754)
			(xy 384.740906 -250.437156) (xy 384.695617 -250.451714) (xy 384.64862 -250.459077) (xy 384.624834 -250.459494)
			(xy 384.599576 -250.459004) (xy 384.549747 -250.450694) (xy 384.501966 -250.434296) (xy 384.457536 -250.410256)
			(xy 384.417669 -250.37923) (xy 384.383453 -250.342066) (xy 384.355822 -250.299776) (xy 384.335528 -250.253515)
			(xy 384.323126 -250.204544) (xy 384.318954 -250.1542) (xy 384.323126 -250.103856) (xy 384.335528 -250.054885)
			(xy 384.355822 -250.008624) (xy 384.383453 -249.966334) (xy 384.417669 -249.92917) (xy 384.457536 -249.898144)
			(xy 384.501966 -249.874104) (xy 384.549747 -249.857706) (xy 384.599576 -249.849396) (xy 384.624834 -249.848878)
			(xy 384.64862 -249.849313) (xy 384.695621 -249.856655) (xy 384.740914 -249.871202) (xy 384.7834 -249.892603)
			(xy 384.82205 -249.920337) (xy 384.855927 -249.953734) (xy 384.870452 -249.972576) (xy 384.876112 -249.979662)
			(xy 384.891254 -249.989621) (xy 384.908915 -249.993686) (xy 384.91795 -249.992896) (xy 385.017518 -249.979688)
			(xy 385.039362 -249.96267) (xy 385.044442 -249.949716) (xy 385.057555 -249.91774) (xy 385.090559 -249.857017)
			(xy 385.130796 -249.800825) (xy 385.177652 -249.750021) (xy 385.230414 -249.70538) (xy 385.259072 -249.686064)
			(xy 385.264152 -249.682508) (xy 385.272534 -249.673618) (xy 385.286504 -249.648472) (xy 385.289459 -249.642747)
			(xy 385.292666 -249.630274) (xy 385.292854 -249.623834) (xy 385.292854 -249.185938) (xy 385.292765 -249.181528)
			(xy 385.291229 -249.172842) (xy 385.289806 -249.168666) (xy 385.284218 -249.152918) (xy 385.282697 -249.149092)
			(xy 385.278618 -249.141943) (xy 385.27609 -249.138694) (xy 385.263534 -249.122616) (xy 385.240525 -249.088928)
			(xy 385.230116 -249.071384) (xy 385.081272 -248.815098) (xy 385.0708 -248.796619) (xy 385.052363 -248.758351)
			(xy 385.044442 -248.738644) (xy 385.039362 -248.72569) (xy 385.017772 -248.708672) (xy 384.91795 -248.695464)
			(xy 384.90891 -248.694643) (xy 384.891229 -248.698692) (xy 384.876076 -248.708662) (xy 384.870452 -248.715784)
			(xy 384.855935 -248.734631) (xy 384.822046 -248.768016) (xy 384.783392 -248.795745) (xy 384.740907 -248.817148)
			(xy 384.695618 -248.831706) (xy 384.64862 -248.83907) (xy 384.624834 -248.839482) (xy 384.599577 -248.838992)
			(xy 384.54975 -248.830683) (xy 384.501971 -248.814285) (xy 384.457543 -248.790246) (xy 384.417677 -248.759222)
			(xy 384.383463 -248.722058) (xy 384.355832 -248.67977) (xy 384.335539 -248.633511) (xy 384.323138 -248.584542)
			(xy 384.318966 -248.5342) (xy 384.323138 -248.483858) (xy 384.335539 -248.434889) (xy 384.355832 -248.38863)
			(xy 384.383463 -248.346342) (xy 384.417677 -248.309178) (xy 384.457543 -248.278154) (xy 384.501971 -248.254115)
			(xy 384.54975 -248.237717) (xy 384.599577 -248.229408) (xy 384.624834 -248.228866) (xy 384.64862 -248.2293)
			(xy 384.695622 -248.236642) (xy 384.740915 -248.251189) (xy 384.783401 -248.272589) (xy 384.822052 -248.300323)
			(xy 384.855931 -248.333719) (xy 384.870452 -248.352564) (xy 384.876112 -248.359651) (xy 384.891253 -248.369612)
			(xy 384.908915 -248.373679) (xy 384.91795 -248.372884) (xy 385.017772 -248.359676) (xy 385.039362 -248.342658)
			(xy 385.044442 -248.329704) (xy 385.059988 -248.29203) (xy 385.100404 -248.221261) (xy 385.12496 -248.188734)
			(xy 385.130239 -248.181395) (xy 385.135757 -248.164192) (xy 385.134998 -248.146141) (xy 385.131818 -248.13768)
			(xy 385.093464 -248.045478) (xy 385.071874 -248.029222) (xy 385.058158 -248.027444) (xy 385.033854 -248.024023)
			(xy 384.986694 -248.010436) (xy 384.942314 -247.989482) (xy 384.901855 -247.961701) (xy 384.866359 -247.927809)
			(xy 384.83674 -247.888677) (xy 384.813759 -247.845311) (xy 384.798007 -247.79883) (xy 384.789891 -247.750427)
			(xy 384.78962 -247.70135) (xy 384.797199 -247.652861) (xy 384.812435 -247.606207) (xy 384.834934 -247.56259)
			(xy 384.849116 -247.542558) (xy 384.863965 -247.523263) (xy 384.89875 -247.489202) (xy 384.938502 -247.461096)
			(xy 384.982213 -247.439659) (xy 385.028773 -247.425435) (xy 385.052824 -247.421654) (xy 385.065088 -247.419259)
			(xy 385.085294 -247.404602) (xy 385.091432 -247.393714) (xy 385.127754 -247.320054) (xy 385.132701 -247.308445)
			(xy 385.131772 -247.283257) (xy 385.125976 -247.272048) (xy 385.081272 -247.195086) (xy 385.063348 -247.163016)
			(xy 385.035134 -247.095181) (xy 385.016043 -247.024237) (xy 385.006403 -246.951404) (xy 385.005834 -246.91467)
			(xy 385.005834 -246.913654) (xy 385.006245 -246.882666) (xy 385.013089 -246.821069) (xy 385.026709 -246.760609)
			(xy 385.046938 -246.702028) (xy 385.073527 -246.646046) (xy 385.10615 -246.593351) (xy 385.12496 -246.568722)
			(xy 385.133596 -246.557546) (xy 385.137406 -246.530622) (xy 385.093464 -246.425466) (xy 385.071874 -246.40921)
			(xy 385.058158 -246.407432) (xy 385.033854 -246.404011) (xy 384.986696 -246.390424) (xy 384.942317 -246.36947)
			(xy 384.90186 -246.34169) (xy 384.866365 -246.307798) (xy 384.836747 -246.268666) (xy 384.813767 -246.225302)
			(xy 384.798017 -246.178821) (xy 384.789903 -246.130419) (xy 384.789632 -246.081343) (xy 384.797213 -246.032856)
			(xy 384.812449 -245.986204) (xy 384.834949 -245.942589) (xy 384.849116 -245.922546) (xy 384.863962 -245.903247)
			(xy 384.898743 -245.869176) (xy 384.938493 -245.841062) (xy 384.982204 -245.819619) (xy 385.028767 -245.80539)
			(xy 385.052824 -245.801642) (xy 385.065094 -245.799253) (xy 385.085321 -245.784608) (xy 385.091432 -245.773702)
			(xy 385.127754 -245.700042) (xy 385.132698 -245.688433) (xy 385.131764 -245.663248) (xy 385.125976 -245.652036)
			(xy 385.081272 -245.575074) (xy 385.070801 -245.556595) (xy 385.052365 -245.518327) (xy 385.044442 -245.49862)
			(xy 385.039362 -245.485666) (xy 385.017772 -245.468648) (xy 384.91795 -245.45544) (xy 384.908912 -245.454619)
			(xy 384.891236 -245.458673) (xy 384.876093 -245.468651) (xy 384.870452 -245.47576) (xy 384.855936 -245.494609)
			(xy 384.822048 -245.527996) (xy 384.783394 -245.555727) (xy 384.740909 -245.577131) (xy 384.695619 -245.591691)
			(xy 384.64862 -245.599055) (xy 384.624834 -245.599458) (xy 384.59957 -245.598968) (xy 384.549731 -245.590656)
			(xy 384.50194 -245.574254) (xy 384.457501 -245.550209) (xy 384.417626 -245.519177) (xy 384.383403 -245.482005)
			(xy 384.355765 -245.439707) (xy 384.335467 -245.393436) (xy 384.323063 -245.344455) (xy 384.31889 -245.2941)
			(xy 384.323063 -245.243745) (xy 384.335467 -245.194764) (xy 384.355765 -245.148493) (xy 384.383403 -245.106195)
			(xy 384.417626 -245.069023) (xy 384.457501 -245.037991) (xy 384.50194 -245.013946) (xy 384.549731 -244.997544)
			(xy 384.59957 -244.989232) (xy 384.624834 -244.988842) (xy 384.648619 -244.989277) (xy 384.695619 -244.99662)
			(xy 384.740909 -245.01117) (xy 384.783392 -245.032573) (xy 384.822038 -245.060311) (xy 384.85591 -245.093712)
			(xy 384.870452 -245.11254) (xy 384.87611 -245.11963) (xy 384.891251 -245.129596) (xy 384.908915 -245.133665)
			(xy 384.91795 -245.13286) (xy 385.017518 -245.119652) (xy 385.039362 -245.102634) (xy 385.044442 -245.08968)
			(xy 385.057557 -245.057705) (xy 385.090563 -244.996985) (xy 385.130802 -244.940796) (xy 385.17766 -244.889995)
			(xy 385.230423 -244.845357) (xy 385.259072 -244.826028) (xy 385.264152 -244.822472) (xy 385.272534 -244.813582)
			(xy 385.286504 -244.788436) (xy 385.289466 -244.782713) (xy 385.292689 -244.77024) (xy 385.292854 -244.763798)
			(xy 385.292854 -244.325902) (xy 385.29277 -244.32149) (xy 385.291245 -244.312801) (xy 385.289806 -244.30863)
			(xy 385.284218 -244.292882) (xy 385.282695 -244.289058) (xy 385.278612 -244.281911) (xy 385.27609 -244.278658)
			(xy 385.263535 -244.26258) (xy 385.240528 -244.22889) (xy 385.230116 -244.211348) (xy 385.081272 -243.955062)
			(xy 385.070801 -243.936583) (xy 385.052366 -243.898314) (xy 385.044442 -243.878608) (xy 385.039362 -243.865654)
			(xy 385.017772 -243.848636) (xy 384.91795 -243.835428) (xy 384.908912 -243.834607) (xy 384.891235 -243.83866)
			(xy 384.87609 -243.848637) (xy 384.870452 -243.855748) (xy 384.855936 -243.874597) (xy 384.822049 -243.907986)
			(xy 384.783395 -243.935718) (xy 384.74091 -243.957123) (xy 384.69562 -243.971684) (xy 384.648621 -243.979048)
			(xy 384.624834 -243.979446) (xy 384.599571 -243.978956) (xy 384.549734 -243.970645) (xy 384.501945 -243.954243)
			(xy 384.457508 -243.930199) (xy 384.417634 -243.899169) (xy 384.383412 -243.861998) (xy 384.355776 -243.819701)
			(xy 384.335479 -243.773432) (xy 384.323075 -243.724453) (xy 384.318902 -243.6741) (xy 384.323075 -243.623747)
			(xy 384.335479 -243.574768) (xy 384.355776 -243.528499) (xy 384.383412 -243.486202) (xy 384.417634 -243.449031)
			(xy 384.457508 -243.418001) (xy 384.501945 -243.393957) (xy 384.549734 -243.377555) (xy 384.599571 -243.369244)
			(xy 384.624834 -243.36883) (xy 384.648619 -243.369265) (xy 384.69562 -243.376608) (xy 384.74091 -243.391157)
			(xy 384.783394 -243.41256) (xy 384.82204 -243.440297) (xy 384.855913 -243.473697) (xy 384.870452 -243.492528)
			(xy 384.876109 -243.499619) (xy 384.89125 -243.509588) (xy 384.908915 -243.513658) (xy 384.91795 -243.512848)
			(xy 385.017772 -243.49964) (xy 385.039362 -243.482622) (xy 385.044442 -243.469668) (xy 385.05999 -243.431996)
			(xy 385.10041 -243.361229) (xy 385.12496 -243.328698) (xy 385.130233 -243.321358) (xy 385.135739 -243.304158)
			(xy 385.134968 -243.286114) (xy 385.131818 -243.277644) (xy 385.093464 -243.185442) (xy 385.071874 -243.169186)
			(xy 385.058158 -243.167408) (xy 385.03385 -243.163987) (xy 384.986683 -243.150399) (xy 384.942296 -243.129445)
			(xy 384.90183 -243.101663) (xy 384.866327 -243.067768) (xy 384.8367 -243.028633) (xy 384.813712 -242.985264)
			(xy 384.797954 -242.938777) (xy 384.789831 -242.890369) (xy 384.789553 -242.841285) (xy 384.797127 -242.792788)
			(xy 384.812358 -242.746126) (xy 384.834854 -242.702499) (xy 384.849116 -242.682522) (xy 384.863963 -242.663224)
			(xy 384.898744 -242.629156) (xy 384.938495 -242.601044) (xy 384.982206 -242.579602) (xy 385.028768 -242.565375)
			(xy 385.052824 -242.561618) (xy 385.065093 -242.559227) (xy 385.085314 -242.544579) (xy 385.091432 -242.533678)
			(xy 385.127754 -242.460018) (xy 385.132693 -242.448409) (xy 385.131748 -242.423231) (xy 385.125976 -242.412012)
			(xy 385.081272 -242.33505) (xy 385.06335 -242.30298) (xy 385.035141 -242.235144) (xy 385.016054 -242.1642)
			(xy 385.006419 -242.091367) (xy 385.005834 -242.054634) (xy 385.005834 -242.053618) (xy 385.006247 -242.022631)
			(xy 385.013094 -241.961036) (xy 385.026718 -241.900577) (xy 385.04695 -241.841999) (xy 385.073542 -241.786019)
			(xy 385.106167 -241.733328) (xy 385.12496 -241.708686) (xy 385.133596 -241.69751) (xy 385.137406 -241.670586)
			(xy 385.093464 -241.56543) (xy 385.071874 -241.549174) (xy 385.058158 -241.547396) (xy 385.033851 -241.543975)
			(xy 384.986685 -241.530387) (xy 384.942299 -241.509433) (xy 384.901835 -241.481651) (xy 384.866333 -241.447757)
			(xy 384.836708 -241.408622) (xy 384.813721 -241.365254) (xy 384.797964 -241.318768) (xy 384.789843 -241.270361)
			(xy 384.789566 -241.221278) (xy 384.797141 -241.172783) (xy 384.812372 -241.126122) (xy 384.834869 -241.082497)
			(xy 384.849116 -241.06251) (xy 384.863963 -241.043213) (xy 384.898745 -241.009146) (xy 384.938496 -240.981035)
			(xy 384.982208 -240.959594) (xy 385.028769 -240.945367) (xy 385.052824 -240.941606) (xy 385.065092 -240.939214)
			(xy 385.08531 -240.924565) (xy 385.091432 -240.913666) (xy 385.127754 -240.840006) (xy 385.132689 -240.828398)
			(xy 385.13174 -240.803222) (xy 385.125976 -240.792) (xy 385.081272 -240.715038) (xy 385.070802 -240.696558)
			(xy 385.052368 -240.658289) (xy 385.044442 -240.638584) (xy 385.039362 -240.62563) (xy 385.017772 -240.608612)
			(xy 384.91795 -240.595404) (xy 384.908911 -240.594583) (xy 384.891233 -240.598634) (xy 384.876085 -240.608609)
			(xy 384.870452 -240.615724) (xy 384.855934 -240.634569) (xy 384.822043 -240.66795) (xy 384.783388 -240.695675)
			(xy 384.740903 -240.717075) (xy 384.695616 -240.731631) (xy 384.648619 -240.738994) (xy 384.624834 -240.739422)
			(xy 384.599573 -240.738932) (xy 384.54974 -240.730621) (xy 384.501955 -240.714221) (xy 384.457521 -240.690179)
			(xy 384.41765 -240.659151) (xy 384.383431 -240.621983) (xy 384.355797 -240.579689) (xy 384.335501 -240.533424)
			(xy 384.323098 -240.484449) (xy 384.318926 -240.4341) (xy 384.323098 -240.383751) (xy 384.335501 -240.334776)
			(xy 384.355797 -240.288511) (xy 384.383431 -240.246217) (xy 384.41765 -240.209049) (xy 384.457521 -240.178021)
			(xy 384.501955 -240.153979) (xy 384.54974 -240.137579) (xy 384.599573 -240.129268) (xy 384.624834 -240.128806)
			(xy 384.64862 -240.129241) (xy 384.69562 -240.136583) (xy 384.740912 -240.151132) (xy 384.783397 -240.172533)
			(xy 384.822045 -240.20027) (xy 384.855919 -240.233668) (xy 384.870452 -240.252504) (xy 384.876108 -240.259598)
			(xy 384.891248 -240.269571) (xy 384.908915 -240.273643) (xy 384.91795 -240.272824) (xy 385.017518 -240.259616)
			(xy 385.039362 -240.242598) (xy 385.044442 -240.229644) (xy 385.057558 -240.197671) (xy 385.090568 -240.136953)
			(xy 385.130809 -240.080767) (xy 385.177669 -240.029969) (xy 385.230432 -239.985334) (xy 385.259072 -239.965992)
			(xy 385.264152 -239.962436) (xy 385.272534 -239.953546) (xy 385.286504 -239.9284) (xy 385.289462 -239.922676)
			(xy 385.292676 -239.910203) (xy 385.292854 -239.903762) (xy 385.292854 -239.465866) (xy 385.292767 -239.461455)
			(xy 385.291236 -239.452767) (xy 385.289806 -239.448594) (xy 385.284218 -239.432846) (xy 385.282699 -239.42902)
			(xy 385.278622 -239.421868) (xy 385.27609 -239.418622) (xy 385.263534 -239.402545) (xy 385.240523 -239.368857)
			(xy 385.230116 -239.351312) (xy 385.081272 -239.095026) (xy 385.070802 -239.076546) (xy 385.05237 -239.038277)
			(xy 385.044442 -239.018572) (xy 385.039362 -239.005618) (xy 385.017772 -238.9886) (xy 384.91795 -238.975392)
			(xy 384.908911 -238.974571) (xy 384.891232 -238.978622) (xy 384.876082 -238.988595) (xy 384.870452 -238.995712)
			(xy 384.855934 -239.014558) (xy 384.822044 -239.04794) (xy 384.783389 -239.075666) (xy 384.740904 -239.097067)
			(xy 384.695616 -239.111624) (xy 384.648619 -239.118986) (xy 384.624834 -239.11941) (xy 384.599574 -239.11892)
			(xy 384.549743 -239.11061) (xy 384.50196 -239.09421) (xy 384.457527 -239.070169) (xy 384.417658 -239.039142)
			(xy 384.383441 -239.001976) (xy 384.355808 -238.959684) (xy 384.335513 -238.91342) (xy 384.32311 -238.864447)
			(xy 384.318938 -238.8141) (xy 384.32311 -238.763753) (xy 384.335513 -238.71478) (xy 384.355808 -238.668516)
			(xy 384.383441 -238.626224) (xy 384.417658 -238.589058) (xy 384.457527 -238.558031) (xy 384.50196 -238.53399)
			(xy 384.549743 -238.51759) (xy 384.599574 -238.50928) (xy 384.624834 -238.508794) (xy 384.64862 -238.509229)
			(xy 384.695621 -238.516571) (xy 384.740913 -238.531119) (xy 384.783398 -238.55252) (xy 384.822047 -238.580256)
			(xy 384.855923 -238.613654) (xy 384.870452 -238.632492) (xy 384.876107 -238.639587) (xy 384.891247 -238.649563)
			(xy 384.908915 -238.653636) (xy 384.91795 -238.652812) (xy 385.017772 -238.639604) (xy 385.039362 -238.622586)
			(xy 385.044442 -238.609632) (xy 385.059992 -238.571961) (xy 385.100416 -238.501197) (xy 385.12496 -238.468662)
			(xy 385.130227 -238.461322) (xy 385.135721 -238.444124) (xy 385.13494 -238.426087) (xy 385.131818 -238.417608)
			(xy 385.093464 -238.325406) (xy 385.071874 -238.30915) (xy 385.058158 -238.307372) (xy 385.033852 -238.303951)
			(xy 384.986689 -238.290364) (xy 384.942306 -238.26941) (xy 384.901844 -238.241628) (xy 384.866345 -238.207735)
			(xy 384.836722 -238.168601) (xy 384.813738 -238.125234) (xy 384.797984 -238.07875) (xy 384.789865 -238.030346)
			(xy 384.789591 -237.981265) (xy 384.797168 -237.932773) (xy 384.812401 -237.886115) (xy 384.834899 -237.842494)
			(xy 384.849116 -237.822486) (xy 384.863964 -237.80319) (xy 384.898747 -237.769125) (xy 384.938499 -237.741017)
			(xy 384.98221 -237.719578) (xy 385.028771 -237.705352) (xy 385.052824 -237.701582) (xy 385.06509 -237.699189)
			(xy 385.085302 -237.684536) (xy 385.091432 -237.673642) (xy 385.127754 -237.599982) (xy 385.132709 -237.588372)
			(xy 385.131792 -237.563177) (xy 385.125976 -237.551976) (xy 385.081272 -237.475014) (xy 385.063352 -237.442943)
			(xy 385.035147 -237.375107) (xy 385.016065 -237.304163) (xy 385.006435 -237.231331) (xy 385.005834 -237.194598)
			(xy 385.005834 -237.193582) (xy 385.006249 -237.162595) (xy 385.0131 -237.101002) (xy 385.026727 -237.040546)
			(xy 385.046962 -236.981969) (xy 385.073556 -236.925993) (xy 385.106184 -236.873304) (xy 385.12496 -236.84865)
			(xy 385.133596 -236.837474) (xy 385.137406 -236.81055) (xy 385.093464 -236.705394) (xy 385.071874 -236.689138)
			(xy 385.058158 -236.68736) (xy 385.033853 -236.683939) (xy 384.986691 -236.670352) (xy 384.942309 -236.649398)
			(xy 384.901849 -236.621617) (xy 384.866351 -236.587724) (xy 384.83673 -236.548591) (xy 384.813747 -236.505225)
			(xy 384.797994 -236.458742) (xy 384.789876 -236.410338) (xy 384.789603 -236.361259) (xy 384.797181 -236.312767)
			(xy 384.812415 -236.266112) (xy 384.834914 -236.222493) (xy 384.849116 -236.202474) (xy 384.863964 -236.183179)
			(xy 384.898748 -236.149115) (xy 384.9385 -236.121008) (xy 384.982211 -236.09957) (xy 385.028772 -236.085345)
			(xy 385.052824 -236.08157) (xy 385.06509 -236.079176) (xy 385.085299 -236.064522) (xy 385.091432 -236.05363)
			(xy 385.127754 -235.97997) (xy 385.132705 -235.96836) (xy 385.131783 -235.943169) (xy 385.125976 -235.931964)
			(xy 385.081272 -235.855002) (xy 385.070803 -235.836522) (xy 385.052372 -235.798252) (xy 385.044442 -235.778548)
			(xy 385.039362 -235.765594) (xy 385.017772 -235.748576) (xy 384.91795 -235.735368) (xy 384.90891 -235.734547)
			(xy 384.89123 -235.738596) (xy 384.876077 -235.748566) (xy 384.870452 -235.755688) (xy 384.855935 -235.774535)
			(xy 384.822046 -235.80792) (xy 384.783391 -235.835648) (xy 384.740906 -235.85705) (xy 384.695618 -235.871609)
			(xy 384.64862 -235.878972) (xy 384.624834 -235.879386) (xy 384.599576 -235.878896) (xy 384.549749 -235.870586)
			(xy 384.501969 -235.854188) (xy 384.45754 -235.830149) (xy 384.417675 -235.799124) (xy 384.38346 -235.761961)
			(xy 384.355829 -235.719672) (xy 384.335535 -235.673412) (xy 384.323134 -235.624443) (xy 384.318962 -235.5741)
			(xy 384.323134 -235.523757) (xy 384.335535 -235.474788) (xy 384.355829 -235.428528) (xy 384.38346 -235.386239)
			(xy 384.417675 -235.349076) (xy 384.45754 -235.318051) (xy 384.501969 -235.294012) (xy 384.549749 -235.277614)
			(xy 384.599576 -235.269304) (xy 384.624834 -235.26877) (xy 384.64862 -235.269204) (xy 384.695622 -235.276546)
			(xy 384.740915 -235.291093) (xy 384.783401 -235.312493) (xy 384.822052 -235.340228) (xy 384.85593 -235.373624)
			(xy 384.870452 -235.392468) (xy 384.876112 -235.399555) (xy 384.891253 -235.409515) (xy 384.908915 -235.413582)
			(xy 384.91795 -235.412788) (xy 385.017518 -235.39958) (xy 385.039362 -235.382562) (xy 385.044442 -235.369608)
			(xy 385.057556 -235.337632) (xy 385.09056 -235.27691) (xy 385.130797 -235.220718) (xy 385.177654 -235.169915)
			(xy 385.230416 -235.125275) (xy 385.259072 -235.105956) (xy 385.264152 -235.1024) (xy 385.272534 -235.09351)
			(xy 385.286504 -235.068364) (xy 385.289458 -235.062639) (xy 385.292663 -235.050166) (xy 385.292854 -235.043726)
			(xy 385.292854 -234.60583) (xy 385.292764 -234.60142) (xy 385.291227 -234.592734) (xy 385.289806 -234.588558)
			(xy 385.284218 -234.57281) (xy 385.282697 -234.568985) (xy 385.278616 -234.561836) (xy 385.27609 -234.558586)
			(xy 385.263535 -234.542508) (xy 385.240525 -234.508819) (xy 385.230116 -234.491276) (xy 385.081272 -234.23499)
			(xy 385.070801 -234.216511) (xy 385.052364 -234.178243) (xy 385.044442 -234.158536) (xy 385.039362 -234.145582)
			(xy 385.017772 -234.128564) (xy 384.91795 -234.115356) (xy 384.90891 -234.114535) (xy 384.891229 -234.118584)
			(xy 384.876075 -234.128552) (xy 384.870452 -234.135676) (xy 384.855935 -234.154524) (xy 384.822046 -234.18791)
			(xy 384.783392 -234.215639) (xy 384.740907 -234.237042) (xy 384.695618 -234.251601) (xy 384.64862 -234.258965)
			(xy 384.624834 -234.259374) (xy 384.599577 -234.258884) (xy 384.549752 -234.250575) (xy 384.501974 -234.234177)
			(xy 384.457547 -234.210139) (xy 384.417683 -234.179116) (xy 384.383469 -234.141954) (xy 384.355839 -234.099667)
			(xy 384.335547 -234.053408) (xy 384.323146 -234.004441) (xy 384.318974 -233.9541) (xy 384.323146 -233.903759)
			(xy 384.335547 -233.854792) (xy 384.355839 -233.808533) (xy 384.383469 -233.766246) (xy 384.417683 -233.729084)
			(xy 384.457547 -233.698061) (xy 384.501974 -233.674023) (xy 384.549752 -233.657625) (xy 384.599577 -233.649316)
			(xy 384.624834 -233.648758) (xy 384.64862 -233.649192) (xy 384.695622 -233.656534) (xy 384.740915 -233.671081)
			(xy 384.783402 -233.69248) (xy 384.822054 -233.720214) (xy 384.855933 -233.75361) (xy 384.870452 -233.772456)
			(xy 384.876111 -233.779544) (xy 384.891252 -233.789507) (xy 384.908915 -233.793574) (xy 384.91795 -233.792776)
			(xy 385.017772 -233.779568) (xy 385.039362 -233.76255) (xy 385.044442 -233.749596) (xy 385.059989 -233.711923)
			(xy 385.100405 -233.641154) (xy 385.12496 -233.608626) (xy 385.130238 -233.601287) (xy 385.135754 -233.584084)
			(xy 385.134991 -233.566035) (xy 385.131818 -233.557572) (xy 385.093464 -233.46537) (xy 385.071874 -233.449114)
			(xy 385.058158 -233.447336) (xy 385.033854 -233.443915) (xy 384.986695 -233.430328) (xy 384.942316 -233.409374)
			(xy 384.901858 -233.381594) (xy 384.866363 -233.347701) (xy 384.836745 -233.30857) (xy 384.813764 -233.265205)
			(xy 384.798014 -233.218724) (xy 384.789899 -233.170322) (xy 384.789628 -233.121246) (xy 384.797208 -233.072757)
			(xy 384.812444 -233.026105) (xy 384.834944 -232.982489) (xy 384.849116 -232.96245) (xy 384.863962 -232.943151)
			(xy 384.898742 -232.90908) (xy 384.938493 -232.880965) (xy 384.982204 -232.859522) (xy 385.028766 -232.845293)
			(xy 385.052824 -232.841546) (xy 385.065043 -232.83903) (xy 385.085217 -232.824424) (xy 385.091432 -232.813606)
			(xy 385.127754 -232.739946) (xy 385.132699 -232.728337) (xy 385.131767 -232.703151) (xy 385.125976 -232.69194)
			(xy 385.081272 -232.614978) (xy 385.062331 -232.581019) (xy 385.033011 -232.509002) (xy 385.022852 -232.471468)
			(xy 385.021074 -232.464864) (xy 385.01447 -232.452926) (xy 384.875786 -232.314242) (xy 384.869065 -232.307007)
			(xy 384.861451 -232.288802) (xy 384.861054 -232.278936) (xy 384.861054 -231.746552) (xy 384.861 -231.74248)
			(xy 384.859723 -231.734438) (xy 384.858514 -231.73055) (xy 384.850894 -231.708198) (xy 384.846576 -231.701848)
			(xy 384.846322 -231.701594) (xy 384.832918 -231.68205) (xy 384.811667 -231.639693) (xy 384.797207 -231.594563)
			(xy 384.789886 -231.547743) (xy 384.789426 -231.524048) (xy 384.789863 -231.500422) (xy 384.797129 -231.453732)
			(xy 384.811496 -231.408717) (xy 384.821684 -231.387396) (xy 384.833876 -231.365552) (xy 384.846322 -231.346502)
			(xy 384.850894 -231.340152) (xy 384.858514 -231.317546) (xy 384.85969 -231.31365) (xy 384.860959 -231.305613)
			(xy 384.861054 -231.301544) (xy 384.861054 -231.096566) (xy 384.860344 -231.08431) (xy 384.849082 -231.062536)
			(xy 384.839464 -231.05491) (xy 384.773424 -231.008428) (xy 384.763068 -231.001778) (xy 384.738709 -230.998465)
			(xy 384.726942 -231.002078) (xy 384.726688 -231.002078) (xy 384.702014 -231.010226) (xy 384.650812 -231.019044)
			(xy 384.624834 -231.019604) (xy 384.621024 -231.019604) (xy 384.597227 -231.018854) (xy 384.55029 -231.010883)
			(xy 384.505159 -230.995724) (xy 384.462928 -230.973743) (xy 384.424621 -230.945474) (xy 384.391165 -230.911602)
			(xy 384.363373 -230.872947) (xy 384.341917 -230.830447) (xy 384.327317 -230.785132) (xy 384.319928 -230.7381)
			(xy 384.319526 -230.714296) (xy 384.319973 -230.690304) (xy 384.32748 -230.642911) (xy 384.342309 -230.597276)
			(xy 384.364095 -230.554523) (xy 384.392302 -230.515705) (xy 384.426234 -230.481777) (xy 384.465055 -230.453575)
			(xy 384.507811 -230.431795) (xy 384.553448 -230.416971) (xy 384.600842 -230.40947) (xy 384.624834 -230.408988)
			(xy 384.637597 -230.409126) (xy 384.663031 -230.411289) (xy 384.675634 -230.413306) (xy 384.675634 -230.413052)
			(xy 384.698377 -230.417323) (xy 384.742323 -230.431811) (xy 384.783586 -230.452753) (xy 384.821225 -230.47967)
			(xy 384.85438 -230.511948) (xy 384.868674 -230.530146) (xy 384.875278 -230.539036) (xy 384.894328 -230.54945)
			(xy 384.98018 -230.555546) (xy 384.991084 -230.555802) (xy 385.011487 -230.548159) (xy 385.01955 -230.540814)
			(xy 385.032758 -230.527606) (xy 385.040378 -230.519986) (xy 385.044188 -230.51008) (xy 385.056748 -230.479353)
			(xy 385.088129 -230.420857) (xy 385.126211 -230.366485) (xy 385.170459 -230.317) (xy 385.220251 -230.273098)
			(xy 385.274887 -230.235396) (xy 385.30403 -230.219504) (xy 385.31038 -230.216202) (xy 385.320032 -230.207312)
			(xy 385.336034 -230.180896) (xy 385.339487 -230.174839) (xy 385.343344 -230.161446) (xy 385.343654 -230.15448)
			(xy 385.343654 -229.805992) (xy 385.343228 -229.795923) (xy 385.335506 -229.777326) (xy 385.328668 -229.769924)
			(xy 384.903218 -229.344474) (xy 384.896251 -229.338161) (xy 384.879052 -229.330604) (xy 384.86969 -229.329742)
			(xy 384.847592 -229.328726) (xy 384.84281 -229.328647) (xy 384.83335 -229.330057) (xy 384.828796 -229.33152)
			(xy 384.815334 -229.336092) (xy 384.811896 -229.33732) (xy 384.80539 -229.34063) (xy 384.80238 -229.342696)
			(xy 384.782835 -229.356098) (xy 384.740478 -229.377346) (xy 384.695348 -229.391803) (xy 384.648528 -229.399121)
			(xy 384.624834 -229.399592) (xy 384.599576 -229.399102) (xy 384.549748 -229.390792) (xy 384.501967 -229.374394)
			(xy 384.457537 -229.350354) (xy 384.417671 -229.319329) (xy 384.383455 -229.282165) (xy 384.355823 -229.239875)
			(xy 384.33553 -229.193614) (xy 384.323128 -229.144644) (xy 384.318956 -229.0943) (xy 384.323128 -229.043956)
			(xy 384.33553 -228.994986) (xy 384.355823 -228.948725) (xy 384.383455 -228.906435) (xy 384.417671 -228.869271)
			(xy 384.457537 -228.838246) (xy 384.501967 -228.814206) (xy 384.549748 -228.797808) (xy 384.599576 -228.789498)
			(xy 384.624834 -228.788976) (xy 384.645608 -228.789346) (xy 384.686769 -228.795013) (xy 384.726785 -228.806197)
			(xy 384.745992 -228.814122) (xy 384.75793 -228.819202) (xy 384.78333 -228.816916) (xy 384.86334 -228.764592)
			(xy 384.870278 -228.759733) (xy 384.880707 -228.746399) (xy 384.886194 -228.730385) (xy 384.886454 -228.72192)
			(xy 384.886454 -228.527864) (xy 384.872992 -228.494336) (xy 384.86715 -228.487732) (xy 384.850999 -228.468959)
			(xy 384.824371 -228.427207) (xy 384.804837 -228.381703) (xy 384.792908 -228.333641) (xy 384.788899 -228.284284)
			(xy 384.792914 -228.234927) (xy 384.804847 -228.186866) (xy 384.824387 -228.141364) (xy 384.851018 -228.099615)
			(xy 384.86715 -228.080824) (xy 384.872992 -228.07422) (xy 384.886454 -228.040692) (xy 384.886454 -226.907852)
			(xy 384.872992 -226.874324) (xy 384.86715 -226.86772) (xy 384.850999 -226.848947) (xy 384.824374 -226.807196)
			(xy 384.804842 -226.761692) (xy 384.792915 -226.713631) (xy 384.788907 -226.664275) (xy 384.792923 -226.614919)
			(xy 384.804858 -226.56686) (xy 384.824398 -226.52136) (xy 384.85103 -226.479612) (xy 384.86715 -226.460812)
			(xy 384.872992 -226.454208) (xy 384.886454 -226.42068) (xy 384.886454 -226.226624) (xy 384.885751 -226.213892)
			(xy 384.873616 -226.191503) (xy 384.86334 -226.183952) (xy 384.78333 -226.131628) (xy 384.75793 -226.129342)
			(xy 384.745992 -226.134422) (xy 384.726791 -226.142363) (xy 384.686775 -226.153557) (xy 384.64561 -226.159209)
			(xy 384.624834 -226.159568) (xy 384.599578 -226.159078) (xy 384.549753 -226.150769) (xy 384.501976 -226.134372)
			(xy 384.45755 -226.110334) (xy 384.417687 -226.079311) (xy 384.383474 -226.04215) (xy 384.355844 -225.999864)
			(xy 384.335552 -225.953606) (xy 384.323152 -225.90464) (xy 384.31898 -225.8543) (xy 384.323152 -225.80396)
			(xy 384.335552 -225.754994) (xy 384.355844 -225.708736) (xy 384.383474 -225.66645) (xy 384.417687 -225.629289)
			(xy 384.45755 -225.598266) (xy 384.501976 -225.574228) (xy 384.549753 -225.557831) (xy 384.599578 -225.549522)
			(xy 384.624834 -225.548952) (xy 384.651305 -225.549518) (xy 384.703455 -225.558649) (xy 384.75325 -225.576631)
			(xy 384.799201 -225.602925) (xy 384.839933 -225.636746) (xy 384.874226 -225.677081) (xy 384.901054 -225.722723)
			(xy 384.910838 -225.747326) (xy 384.914648 -225.75774) (xy 384.922522 -225.76536) (xy 384.929888 -225.7722)
			(xy 384.948421 -225.779942) (xy 384.968505 -225.779942) (xy 384.987038 -225.7722) (xy 384.994404 -225.76536)
			(xy 385.011422 -225.748342) (xy 385.01828 -225.73615) (xy 385.019804 -225.729038) (xy 385.02811 -225.695255)
			(xy 385.05198 -225.629908) (xy 385.08377 -225.568025) (xy 385.12299 -225.510564) (xy 385.169034 -225.45841)
			(xy 385.22119 -225.412369) (xy 385.278654 -225.373153) (xy 385.340538 -225.341366) (xy 385.405887 -225.3175)
			(xy 385.439666 -225.309176) (xy 385.446778 -225.307652) (xy 385.45897 -225.300794) (xy 385.716272 -225.043492)
			(xy 385.719367 -225.040295) (xy 385.72448 -225.033013) (xy 385.726432 -225.029014) (xy 385.729988 -225.021394)
			(xy 385.731004 -225.012758) (xy 385.731004 -225.012504) (xy 385.734232 -224.986655) (xy 385.74835 -224.936516)
			(xy 385.770769 -224.889499) (xy 385.800839 -224.846966) (xy 385.837688 -224.810151) (xy 385.880249 -224.780122)
			(xy 385.927288 -224.757748) (xy 385.97744 -224.743678) (xy 386.003292 -224.74047) (xy 386.011928 -224.739454)
			(xy 386.019548 -224.735898) (xy 386.02353 -224.733917) (xy 386.030809 -224.728809) (xy 386.034026 -224.725738)
			(xy 386.25145 -224.508314) (xy 386.25776 -224.501345) (xy 386.265312 -224.484147) (xy 386.266182 -224.474786)
			(xy 386.267198 -224.452688) (xy 386.267303 -224.448043) (xy 386.266025 -224.438841) (xy 386.264658 -224.4344)
			(xy 386.258054 -224.413826) (xy 386.253736 -224.407984) (xy 386.240958 -224.388726) (xy 386.220731 -224.347173)
			(xy 386.206992 -224.303047) (xy 386.200055 -224.257356) (xy 386.199634 -224.234248) (xy 386.199634 -224.23247)
			(xy 386.199634 -224.227136) (xy 386.20063 -224.203461) (xy 386.209033 -224.156829) (xy 386.224541 -224.112055)
			(xy 386.246781 -224.070216) (xy 386.275219 -224.032316) (xy 386.309173 -223.999265) (xy 386.347825 -223.971858)
			(xy 386.390248 -223.950753) (xy 386.435423 -223.936456) (xy 386.482265 -223.929312) (xy 386.505958 -223.92894)
			(xy 386.512562 -223.92894) (xy 386.535521 -223.929931) (xy 386.580768 -223.937955) (xy 386.624302 -223.952668)
			(xy 386.66514 -223.973738) (xy 386.684012 -223.986852) (xy 386.691224 -223.991674) (xy 386.707848 -223.9966)
			(xy 386.716524 -223.996504) (xy 386.746242 -223.99498) (xy 386.755547 -223.994108) (xy 386.772629 -223.986564)
			(xy 386.779516 -223.980248) (xy 386.888736 -223.871028) (xy 386.897197 -223.861736) (xy 386.904546 -223.837738)
			(xy 386.902706 -223.825308) (xy 386.88391 -223.730058) (xy 386.868162 -223.710754) (xy 386.856224 -223.705674)
			(xy 386.832868 -223.695244) (xy 386.789723 -223.667771) (xy 386.751753 -223.633501) (xy 386.720017 -223.593389)
			(xy 386.695399 -223.548554) (xy 386.678588 -223.500247) (xy 386.670051 -223.449816) (xy 386.669534 -223.424242)
			(xy 386.669977 -223.400248) (xy 386.677479 -223.35285) (xy 386.692304 -223.307209) (xy 386.714088 -223.26445)
			(xy 386.742294 -223.225626) (xy 386.776226 -223.191694) (xy 386.81505 -223.163488) (xy 386.857809 -223.141704)
			(xy 386.90345 -223.126879) (xy 386.950848 -223.119377) (xy 386.974842 -223.118934) (xy 386.987605 -223.119073)
			(xy 387.013039 -223.121235) (xy 387.025642 -223.123252) (xy 387.025642 -223.122998) (xy 387.050797 -223.127761)
			(xy 387.099155 -223.144563) (xy 387.14403 -223.1692) (xy 387.184165 -223.20098) (xy 387.218433 -223.239012)
			(xy 387.245874 -223.282229) (xy 387.256274 -223.305624) (xy 387.261354 -223.317562) (xy 387.280912 -223.33331)
			(xy 387.375908 -223.352106) (xy 387.38833 -223.353839) (xy 387.412285 -223.346506) (xy 387.421628 -223.338136)
			(xy 387.564122 -223.195642) (xy 387.570842 -223.188406) (xy 387.578455 -223.170202) (xy 387.578854 -223.160336)
			(xy 387.578854 -223.019874) (xy 387.578305 -223.009275) (xy 387.569768 -222.989869) (xy 387.562344 -222.982282)
			(xy 387.499606 -222.924624) (xy 387.479794 -222.917766) (xy 387.469126 -222.918528) (xy 387.444742 -222.919544)
			(xy 387.419479 -222.919055) (xy 387.369641 -222.910744) (xy 387.321851 -222.894344) (xy 387.277413 -222.8703)
			(xy 387.237539 -222.83927) (xy 387.203316 -222.802099) (xy 387.175679 -222.759802) (xy 387.155381 -222.713533)
			(xy 387.142977 -222.664553) (xy 387.138804 -222.6142) (xy 387.142977 -222.563847) (xy 387.155381 -222.514867)
			(xy 387.175679 -222.468598) (xy 387.203316 -222.426301) (xy 387.237539 -222.38913) (xy 387.277413 -222.3581)
			(xy 387.321851 -222.334056) (xy 387.369641 -222.317656) (xy 387.419479 -222.309345) (xy 387.444742 -222.308928)
			(xy 387.469126 -222.309944) (xy 387.479794 -222.310706) (xy 387.499606 -222.303848) (xy 387.562344 -222.24619)
			(xy 387.569886 -222.23869) (xy 387.578419 -222.219227) (xy 387.578854 -222.208598) (xy 387.578854 -221.046548)
			(xy 387.578449 -221.03667) (xy 387.570903 -221.018411) (xy 387.556943 -221.004433) (xy 387.538694 -220.996863)
			(xy 387.528816 -220.99651) (xy 377.876308 -220.99651) (xy 377.866286 -220.996928) (xy 377.847768 -221.004597)
			(xy 377.833596 -221.01877) (xy 377.825928 -221.037288) (xy 377.825508 -221.04731) (xy 377.825508 -221.17431)
			(xy 377.825003 -221.207766) (xy 377.817232 -221.274226) (xy 377.810014 -221.306898) (xy 377.80272 -221.336129)
			(xy 377.782869 -221.393015) (xy 377.77039 -221.420436) (xy 377.765564 -221.430596) (xy 377.765564 -221.654624)
			(xy 377.765818 -221.654624) (xy 377.765818 -221.80423) (xy 381.028968 -221.80423) (xy 381.032928 -221.755176)
			(xy 381.044705 -221.707392) (xy 381.063996 -221.662116) (xy 381.090299 -221.62052) (xy 381.122934 -221.583683)
			(xy 381.161055 -221.552558) (xy 381.203676 -221.527951) (xy 381.249692 -221.510499) (xy 381.297911 -221.500655)
			(xy 381.347086 -221.498674) (xy 381.395941 -221.504606) (xy 381.443212 -221.518298) (xy 381.487674 -221.539396)
			(xy 381.528177 -221.567352) (xy 381.56367 -221.601444) (xy 381.593235 -221.640788) (xy 381.616106 -221.684365)
			(xy 381.63169 -221.731046) (xy 381.639585 -221.779623) (xy 381.64008 -221.80423) (xy 384.78893 -221.80423)
			(xy 384.79289 -221.755176) (xy 384.804667 -221.707392) (xy 384.823958 -221.662116) (xy 384.850261 -221.62052)
			(xy 384.882896 -221.583683) (xy 384.921017 -221.552558) (xy 384.963638 -221.527951) (xy 385.009654 -221.510499)
			(xy 385.057873 -221.500655) (xy 385.107048 -221.498674) (xy 385.155903 -221.504606) (xy 385.203174 -221.518298)
			(xy 385.247636 -221.539396) (xy 385.288139 -221.567352) (xy 385.323632 -221.601444) (xy 385.353197 -221.640788)
			(xy 385.376068 -221.684365) (xy 385.391652 -221.731046) (xy 385.399547 -221.779623) (xy 385.400042 -221.80423)
			(xy 385.728984 -221.80423) (xy 385.732944 -221.755176) (xy 385.744721 -221.707392) (xy 385.764012 -221.662116)
			(xy 385.790315 -221.62052) (xy 385.82295 -221.583683) (xy 385.861071 -221.552558) (xy 385.903692 -221.527951)
			(xy 385.949708 -221.510499) (xy 385.997927 -221.500655) (xy 386.047102 -221.498674) (xy 386.095957 -221.504606)
			(xy 386.143228 -221.518298) (xy 386.18769 -221.539396) (xy 386.228193 -221.567352) (xy 386.263686 -221.601444)
			(xy 386.293251 -221.640788) (xy 386.316122 -221.684365) (xy 386.331706 -221.731046) (xy 386.339601 -221.779623)
			(xy 386.340096 -221.80423) (xy 386.669038 -221.80423) (xy 386.672998 -221.755176) (xy 386.684775 -221.707392)
			(xy 386.704066 -221.662116) (xy 386.730369 -221.62052) (xy 386.763004 -221.583683) (xy 386.801125 -221.552558)
			(xy 386.843746 -221.527951) (xy 386.889762 -221.510499) (xy 386.937981 -221.500655) (xy 386.987156 -221.498674)
			(xy 387.036011 -221.504606) (xy 387.083282 -221.518298) (xy 387.127744 -221.539396) (xy 387.168247 -221.567352)
			(xy 387.20374 -221.601444) (xy 387.233305 -221.640788) (xy 387.256176 -221.684365) (xy 387.27176 -221.731046)
			(xy 387.279655 -221.779623) (xy 387.28015 -221.80423) (xy 387.279655 -221.828837) (xy 387.27176 -221.877414)
			(xy 387.256176 -221.924095) (xy 387.233305 -221.967672) (xy 387.20374 -222.007016) (xy 387.168247 -222.041108)
			(xy 387.127744 -222.069064) (xy 387.083282 -222.090162) (xy 387.036011 -222.103854) (xy 386.987156 -222.109786)
			(xy 386.937981 -222.107805) (xy 386.889762 -222.097961) (xy 386.843746 -222.080509) (xy 386.801125 -222.055902)
			(xy 386.763004 -222.024777) (xy 386.730369 -221.98794) (xy 386.704066 -221.946344) (xy 386.684775 -221.901068)
			(xy 386.672998 -221.853284) (xy 386.669038 -221.80423) (xy 386.340096 -221.80423) (xy 386.339601 -221.828837)
			(xy 386.331706 -221.877414) (xy 386.316122 -221.924095) (xy 386.293251 -221.967672) (xy 386.263686 -222.007016)
			(xy 386.228193 -222.041108) (xy 386.18769 -222.069064) (xy 386.143228 -222.090162) (xy 386.095957 -222.103854)
			(xy 386.047102 -222.109786) (xy 385.997927 -222.107805) (xy 385.949708 -222.097961) (xy 385.903692 -222.080509)
			(xy 385.861071 -222.055902) (xy 385.82295 -222.024777) (xy 385.790315 -221.98794) (xy 385.764012 -221.946344)
			(xy 385.744721 -221.901068) (xy 385.732944 -221.853284) (xy 385.728984 -221.80423) (xy 385.400042 -221.80423)
			(xy 385.399547 -221.828837) (xy 385.391652 -221.877414) (xy 385.376068 -221.924095) (xy 385.353197 -221.967672)
			(xy 385.323632 -222.007016) (xy 385.288139 -222.041108) (xy 385.247636 -222.069064) (xy 385.203174 -222.090162)
			(xy 385.155903 -222.103854) (xy 385.107048 -222.109786) (xy 385.057873 -222.107805) (xy 385.009654 -222.097961)
			(xy 384.963638 -222.080509) (xy 384.921017 -222.055902) (xy 384.882896 -222.024777) (xy 384.850261 -221.98794)
			(xy 384.823958 -221.946344) (xy 384.804667 -221.901068) (xy 384.79289 -221.853284) (xy 384.78893 -221.80423)
			(xy 381.64008 -221.80423) (xy 381.639585 -221.828837) (xy 381.63169 -221.877414) (xy 381.616106 -221.924095)
			(xy 381.593235 -221.967672) (xy 381.56367 -222.007016) (xy 381.528177 -222.041108) (xy 381.487674 -222.069064)
			(xy 381.443212 -222.090162) (xy 381.395941 -222.103854) (xy 381.347086 -222.109786) (xy 381.297911 -222.107805)
			(xy 381.249692 -222.097961) (xy 381.203676 -222.080509) (xy 381.161055 -222.055902) (xy 381.122934 -222.024777)
			(xy 381.090299 -221.98794) (xy 381.063996 -221.946344) (xy 381.044705 -221.901068) (xy 381.032928 -221.853284)
			(xy 381.028968 -221.80423) (xy 377.765818 -221.80423) (xy 377.765277 -221.853958) (xy 377.75654 -221.953029)
			(xy 377.739136 -222.05095) (xy 377.7132 -222.146964) (xy 377.678932 -222.24033) (xy 377.636596 -222.330325)
			(xy 377.586521 -222.416255) (xy 377.529092 -222.497455) (xy 377.464754 -222.573297) (xy 377.429776 -222.608648)
			(xy 377.424188 -222.614236) (xy 377.738906 -222.614236) (xy 377.742866 -222.565182) (xy 377.754643 -222.517398)
			(xy 377.773934 -222.472122) (xy 377.800237 -222.430526) (xy 377.832872 -222.393689) (xy 377.870993 -222.362564)
			(xy 377.913614 -222.337957) (xy 377.95963 -222.320505) (xy 378.007849 -222.310661) (xy 378.057024 -222.30868)
			(xy 378.105879 -222.314612) (xy 378.15315 -222.328304) (xy 378.197612 -222.349402) (xy 378.238115 -222.377358)
			(xy 378.273608 -222.41145) (xy 378.303173 -222.450794) (xy 378.326044 -222.494371) (xy 378.341628 -222.541052)
			(xy 378.349523 -222.589629) (xy 378.350018 -222.614236) (xy 378.67896 -222.614236) (xy 378.68292 -222.565182)
			(xy 378.694697 -222.517398) (xy 378.713988 -222.472122) (xy 378.740291 -222.430526) (xy 378.772926 -222.393689)
			(xy 378.811047 -222.362564) (xy 378.853668 -222.337957) (xy 378.899684 -222.320505) (xy 378.947903 -222.310661)
			(xy 378.997078 -222.30868) (xy 379.045933 -222.314612) (xy 379.093204 -222.328304) (xy 379.137666 -222.349402)
			(xy 379.178169 -222.377358) (xy 379.213662 -222.41145) (xy 379.243227 -222.450794) (xy 379.266098 -222.494371)
			(xy 379.281682 -222.541052) (xy 379.289577 -222.589629) (xy 379.290072 -222.614236) (xy 382.438922 -222.614236)
			(xy 382.442882 -222.565182) (xy 382.454659 -222.517398) (xy 382.47395 -222.472122) (xy 382.500253 -222.430526)
			(xy 382.532888 -222.393689) (xy 382.571009 -222.362564) (xy 382.61363 -222.337957) (xy 382.659646 -222.320505)
			(xy 382.707865 -222.310661) (xy 382.75704 -222.30868) (xy 382.805895 -222.314612) (xy 382.853166 -222.328304)
			(xy 382.897628 -222.349402) (xy 382.938131 -222.377358) (xy 382.973624 -222.41145) (xy 383.003189 -222.450794)
			(xy 383.02606 -222.494371) (xy 383.041644 -222.541052) (xy 383.049539 -222.589629) (xy 383.050034 -222.614236)
			(xy 383.378976 -222.614236) (xy 383.382936 -222.565182) (xy 383.394713 -222.517398) (xy 383.414004 -222.472122)
			(xy 383.440307 -222.430526) (xy 383.472942 -222.393689) (xy 383.511063 -222.362564) (xy 383.553684 -222.337957)
			(xy 383.5997 -222.320505) (xy 383.647919 -222.310661) (xy 383.697094 -222.30868) (xy 383.745949 -222.314612)
			(xy 383.79322 -222.328304) (xy 383.837682 -222.349402) (xy 383.878185 -222.377358) (xy 383.913678 -222.41145)
			(xy 383.943243 -222.450794) (xy 383.966114 -222.494371) (xy 383.981698 -222.541052) (xy 383.989593 -222.589629)
			(xy 383.990088 -222.614236) (xy 384.31903 -222.614236) (xy 384.32299 -222.565182) (xy 384.334767 -222.517398)
			(xy 384.354058 -222.472122) (xy 384.380361 -222.430526) (xy 384.412996 -222.393689) (xy 384.451117 -222.362564)
			(xy 384.493738 -222.337957) (xy 384.539754 -222.320505) (xy 384.587973 -222.310661) (xy 384.637148 -222.30868)
			(xy 384.686003 -222.314612) (xy 384.733274 -222.328304) (xy 384.777736 -222.349402) (xy 384.818239 -222.377358)
			(xy 384.853732 -222.41145) (xy 384.883297 -222.450794) (xy 384.906168 -222.494371) (xy 384.921752 -222.541052)
			(xy 384.929647 -222.589629) (xy 384.930142 -222.614236) (xy 385.259084 -222.614236) (xy 385.263044 -222.565182)
			(xy 385.274821 -222.517398) (xy 385.294112 -222.472122) (xy 385.320415 -222.430526) (xy 385.35305 -222.393689)
			(xy 385.391171 -222.362564) (xy 385.433792 -222.337957) (xy 385.479808 -222.320505) (xy 385.528027 -222.310661)
			(xy 385.577202 -222.30868) (xy 385.626057 -222.314612) (xy 385.673328 -222.328304) (xy 385.71779 -222.349402)
			(xy 385.758293 -222.377358) (xy 385.793786 -222.41145) (xy 385.823351 -222.450794) (xy 385.846222 -222.494371)
			(xy 385.861806 -222.541052) (xy 385.869701 -222.589629) (xy 385.870196 -222.614236) (xy 386.199138 -222.614236)
			(xy 386.203098 -222.565182) (xy 386.214875 -222.517398) (xy 386.234166 -222.472122) (xy 386.260469 -222.430526)
			(xy 386.293104 -222.393689) (xy 386.331225 -222.362564) (xy 386.373846 -222.337957) (xy 386.419862 -222.320505)
			(xy 386.468081 -222.310661) (xy 386.517256 -222.30868) (xy 386.566111 -222.314612) (xy 386.613382 -222.328304)
			(xy 386.657844 -222.349402) (xy 386.698347 -222.377358) (xy 386.73384 -222.41145) (xy 386.763405 -222.450794)
			(xy 386.786276 -222.494371) (xy 386.80186 -222.541052) (xy 386.809755 -222.589629) (xy 386.81025 -222.614236)
			(xy 386.809755 -222.638843) (xy 386.80186 -222.68742) (xy 386.786276 -222.734101) (xy 386.763405 -222.777678)
			(xy 386.73384 -222.817022) (xy 386.698347 -222.851114) (xy 386.657844 -222.87907) (xy 386.613382 -222.900168)
			(xy 386.566111 -222.91386) (xy 386.517256 -222.919792) (xy 386.468081 -222.917811) (xy 386.419862 -222.907967)
			(xy 386.373846 -222.890515) (xy 386.331225 -222.865908) (xy 386.293104 -222.834783) (xy 386.260469 -222.797946)
			(xy 386.234166 -222.75635) (xy 386.214875 -222.711074) (xy 386.203098 -222.66329) (xy 386.199138 -222.614236)
			(xy 385.870196 -222.614236) (xy 385.869701 -222.638843) (xy 385.861806 -222.68742) (xy 385.846222 -222.734101)
			(xy 385.823351 -222.777678) (xy 385.793786 -222.817022) (xy 385.758293 -222.851114) (xy 385.71779 -222.87907)
			(xy 385.673328 -222.900168) (xy 385.626057 -222.91386) (xy 385.577202 -222.919792) (xy 385.528027 -222.917811)
			(xy 385.479808 -222.907967) (xy 385.433792 -222.890515) (xy 385.391171 -222.865908) (xy 385.35305 -222.834783)
			(xy 385.320415 -222.797946) (xy 385.294112 -222.75635) (xy 385.274821 -222.711074) (xy 385.263044 -222.66329)
			(xy 385.259084 -222.614236) (xy 384.930142 -222.614236) (xy 384.929647 -222.638843) (xy 384.921752 -222.68742)
			(xy 384.906168 -222.734101) (xy 384.883297 -222.777678) (xy 384.853732 -222.817022) (xy 384.818239 -222.851114)
			(xy 384.777736 -222.87907) (xy 384.733274 -222.900168) (xy 384.686003 -222.91386) (xy 384.637148 -222.919792)
			(xy 384.587973 -222.917811) (xy 384.539754 -222.907967) (xy 384.493738 -222.890515) (xy 384.451117 -222.865908)
			(xy 384.412996 -222.834783) (xy 384.380361 -222.797946) (xy 384.354058 -222.75635) (xy 384.334767 -222.711074)
			(xy 384.32299 -222.66329) (xy 384.31903 -222.614236) (xy 383.990088 -222.614236) (xy 383.989593 -222.638843)
			(xy 383.981698 -222.68742) (xy 383.966114 -222.734101) (xy 383.943243 -222.777678) (xy 383.913678 -222.817022)
			(xy 383.878185 -222.851114) (xy 383.837682 -222.87907) (xy 383.79322 -222.900168) (xy 383.745949 -222.91386)
			(xy 383.697094 -222.919792) (xy 383.647919 -222.917811) (xy 383.5997 -222.907967) (xy 383.553684 -222.890515)
			(xy 383.511063 -222.865908) (xy 383.472942 -222.834783) (xy 383.440307 -222.797946) (xy 383.414004 -222.75635)
			(xy 383.394713 -222.711074) (xy 383.382936 -222.66329) (xy 383.378976 -222.614236) (xy 383.050034 -222.614236)
			(xy 383.049539 -222.638843) (xy 383.041644 -222.68742) (xy 383.02606 -222.734101) (xy 383.003189 -222.777678)
			(xy 382.973624 -222.817022) (xy 382.938131 -222.851114) (xy 382.897628 -222.87907) (xy 382.853166 -222.900168)
			(xy 382.805895 -222.91386) (xy 382.75704 -222.919792) (xy 382.707865 -222.917811) (xy 382.659646 -222.907967)
			(xy 382.61363 -222.890515) (xy 382.571009 -222.865908) (xy 382.532888 -222.834783) (xy 382.500253 -222.797946)
			(xy 382.47395 -222.75635) (xy 382.454659 -222.711074) (xy 382.442882 -222.66329) (xy 382.438922 -222.614236)
			(xy 379.290072 -222.614236) (xy 379.289577 -222.638843) (xy 379.281682 -222.68742) (xy 379.266098 -222.734101)
			(xy 379.243227 -222.777678) (xy 379.213662 -222.817022) (xy 379.178169 -222.851114) (xy 379.137666 -222.87907)
			(xy 379.093204 -222.900168) (xy 379.045933 -222.91386) (xy 378.997078 -222.919792) (xy 378.947903 -222.917811)
			(xy 378.899684 -222.907967) (xy 378.853668 -222.890515) (xy 378.811047 -222.865908) (xy 378.772926 -222.834783)
			(xy 378.740291 -222.797946) (xy 378.713988 -222.75635) (xy 378.694697 -222.711074) (xy 378.68292 -222.66329)
			(xy 378.67896 -222.614236) (xy 378.350018 -222.614236) (xy 378.349523 -222.638843) (xy 378.341628 -222.68742)
			(xy 378.326044 -222.734101) (xy 378.303173 -222.777678) (xy 378.273608 -222.817022) (xy 378.238115 -222.851114)
			(xy 378.197612 -222.87907) (xy 378.15315 -222.900168) (xy 378.105879 -222.91386) (xy 378.057024 -222.919792)
			(xy 378.007849 -222.917811) (xy 377.95963 -222.907967) (xy 377.913614 -222.890515) (xy 377.870993 -222.865908)
			(xy 377.832872 -222.834783) (xy 377.800237 -222.797946) (xy 377.773934 -222.75635) (xy 377.754643 -222.711074)
			(xy 377.742866 -222.66329) (xy 377.738906 -222.614236) (xy 377.424188 -222.614236) (xy 377.423426 -222.614998)
			(xy 377.408694 -222.645732) (xy 377.407678 -222.653606) (xy 377.403933 -222.678596) (xy 377.389258 -222.726947)
			(xy 377.366819 -222.772219) (xy 377.337228 -222.813177) (xy 377.301294 -222.8487) (xy 377.280932 -222.863664)
			(xy 377.273748 -222.869138) (xy 377.263462 -222.88397) (xy 377.260866 -222.89262) (xy 377.247747 -222.942051)
			(xy 377.213759 -223.038517) (xy 377.171192 -223.131517) (xy 377.120393 -223.220289) (xy 377.06178 -223.304106)
			(xy 376.99583 -223.382283) (xy 376.959876 -223.418654) (xy 376.954055 -223.424242) (xy 377.269006 -223.424242)
			(xy 377.272966 -223.375188) (xy 377.284743 -223.327404) (xy 377.304034 -223.282128) (xy 377.330337 -223.240532)
			(xy 377.362972 -223.203695) (xy 377.401093 -223.17257) (xy 377.443714 -223.147963) (xy 377.48973 -223.130511)
			(xy 377.537949 -223.120667) (xy 377.587124 -223.118686) (xy 377.635979 -223.124618) (xy 377.68325 -223.13831)
			(xy 377.727712 -223.159408) (xy 377.768215 -223.187364) (xy 377.803708 -223.221456) (xy 377.833273 -223.2608)
			(xy 377.856144 -223.304377) (xy 377.871728 -223.351058) (xy 377.879623 -223.399635) (xy 377.880118 -223.424242)
			(xy 378.20906 -223.424242) (xy 378.21302 -223.375188) (xy 378.224797 -223.327404) (xy 378.244088 -223.282128)
			(xy 378.270391 -223.240532) (xy 378.303026 -223.203695) (xy 378.341147 -223.17257) (xy 378.383768 -223.147963)
			(xy 378.429784 -223.130511) (xy 378.478003 -223.120667) (xy 378.527178 -223.118686) (xy 378.576033 -223.124618)
			(xy 378.623304 -223.13831) (xy 378.667766 -223.159408) (xy 378.708269 -223.187364) (xy 378.743762 -223.221456)
			(xy 378.773327 -223.2608) (xy 378.796198 -223.304377) (xy 378.811782 -223.351058) (xy 378.819677 -223.399635)
			(xy 378.820172 -223.424242) (xy 381.028968 -223.424242) (xy 381.032928 -223.375188) (xy 381.044705 -223.327404)
			(xy 381.063996 -223.282128) (xy 381.090299 -223.240532) (xy 381.122934 -223.203695) (xy 381.161055 -223.17257)
			(xy 381.203676 -223.147963) (xy 381.249692 -223.130511) (xy 381.297911 -223.120667) (xy 381.347086 -223.118686)
			(xy 381.395941 -223.124618) (xy 381.443212 -223.13831) (xy 381.487674 -223.159408) (xy 381.528177 -223.187364)
			(xy 381.56367 -223.221456) (xy 381.593235 -223.2608) (xy 381.616106 -223.304377) (xy 381.63169 -223.351058)
			(xy 381.639585 -223.399635) (xy 381.64008 -223.424242) (xy 381.969022 -223.424242) (xy 381.972982 -223.375188)
			(xy 381.984759 -223.327404) (xy 382.00405 -223.282128) (xy 382.030353 -223.240532) (xy 382.062988 -223.203695)
			(xy 382.101109 -223.17257) (xy 382.14373 -223.147963) (xy 382.189746 -223.130511) (xy 382.237965 -223.120667)
			(xy 382.28714 -223.118686) (xy 382.335995 -223.124618) (xy 382.383266 -223.13831) (xy 382.427728 -223.159408)
			(xy 382.468231 -223.187364) (xy 382.503724 -223.221456) (xy 382.533289 -223.2608) (xy 382.55616 -223.304377)
			(xy 382.571744 -223.351058) (xy 382.579639 -223.399635) (xy 382.580134 -223.424242) (xy 382.909076 -223.424242)
			(xy 382.913036 -223.375188) (xy 382.924813 -223.327404) (xy 382.944104 -223.282128) (xy 382.970407 -223.240532)
			(xy 383.003042 -223.203695) (xy 383.041163 -223.17257) (xy 383.083784 -223.147963) (xy 383.1298 -223.130511)
			(xy 383.178019 -223.120667) (xy 383.227194 -223.118686) (xy 383.276049 -223.124618) (xy 383.32332 -223.13831)
			(xy 383.367782 -223.159408) (xy 383.408285 -223.187364) (xy 383.443778 -223.221456) (xy 383.473343 -223.2608)
			(xy 383.496214 -223.304377) (xy 383.511798 -223.351058) (xy 383.519693 -223.399635) (xy 383.520188 -223.424242)
			(xy 383.84913 -223.424242) (xy 383.85309 -223.375188) (xy 383.864867 -223.327404) (xy 383.884158 -223.282128)
			(xy 383.910461 -223.240532) (xy 383.943096 -223.203695) (xy 383.981217 -223.17257) (xy 384.023838 -223.147963)
			(xy 384.069854 -223.130511) (xy 384.118073 -223.120667) (xy 384.167248 -223.118686) (xy 384.216103 -223.124618)
			(xy 384.263374 -223.13831) (xy 384.307836 -223.159408) (xy 384.348339 -223.187364) (xy 384.383832 -223.221456)
			(xy 384.413397 -223.2608) (xy 384.436268 -223.304377) (xy 384.451852 -223.351058) (xy 384.459747 -223.399635)
			(xy 384.460242 -223.424242) (xy 384.78893 -223.424242) (xy 384.79289 -223.375188) (xy 384.804667 -223.327404)
			(xy 384.823958 -223.282128) (xy 384.850261 -223.240532) (xy 384.882896 -223.203695) (xy 384.921017 -223.17257)
			(xy 384.963638 -223.147963) (xy 385.009654 -223.130511) (xy 385.057873 -223.120667) (xy 385.107048 -223.118686)
			(xy 385.155903 -223.124618) (xy 385.203174 -223.13831) (xy 385.247636 -223.159408) (xy 385.288139 -223.187364)
			(xy 385.323632 -223.221456) (xy 385.353197 -223.2608) (xy 385.376068 -223.304377) (xy 385.391652 -223.351058)
			(xy 385.399547 -223.399635) (xy 385.400042 -223.424242) (xy 385.728984 -223.424242) (xy 385.732944 -223.375188)
			(xy 385.744721 -223.327404) (xy 385.764012 -223.282128) (xy 385.790315 -223.240532) (xy 385.82295 -223.203695)
			(xy 385.861071 -223.17257) (xy 385.903692 -223.147963) (xy 385.949708 -223.130511) (xy 385.997927 -223.120667)
			(xy 386.047102 -223.118686) (xy 386.095957 -223.124618) (xy 386.143228 -223.13831) (xy 386.18769 -223.159408)
			(xy 386.228193 -223.187364) (xy 386.263686 -223.221456) (xy 386.293251 -223.2608) (xy 386.316122 -223.304377)
			(xy 386.331706 -223.351058) (xy 386.339601 -223.399635) (xy 386.340096 -223.424242) (xy 386.339601 -223.448849)
			(xy 386.331706 -223.497426) (xy 386.316122 -223.544107) (xy 386.293251 -223.587684) (xy 386.263686 -223.627028)
			(xy 386.228193 -223.66112) (xy 386.18769 -223.689076) (xy 386.143228 -223.710174) (xy 386.095957 -223.723866)
			(xy 386.047102 -223.729798) (xy 385.997927 -223.727817) (xy 385.949708 -223.717973) (xy 385.903692 -223.700521)
			(xy 385.861071 -223.675914) (xy 385.82295 -223.644789) (xy 385.790315 -223.607952) (xy 385.764012 -223.566356)
			(xy 385.744721 -223.52108) (xy 385.732944 -223.473296) (xy 385.728984 -223.424242) (xy 385.400042 -223.424242)
			(xy 385.399547 -223.448849) (xy 385.391652 -223.497426) (xy 385.376068 -223.544107) (xy 385.353197 -223.587684)
			(xy 385.323632 -223.627028) (xy 385.288139 -223.66112) (xy 385.247636 -223.689076) (xy 385.203174 -223.710174)
			(xy 385.155903 -223.723866) (xy 385.107048 -223.729798) (xy 385.057873 -223.727817) (xy 385.009654 -223.717973)
			(xy 384.963638 -223.700521) (xy 384.921017 -223.675914) (xy 384.882896 -223.644789) (xy 384.850261 -223.607952)
			(xy 384.823958 -223.566356) (xy 384.804667 -223.52108) (xy 384.79289 -223.473296) (xy 384.78893 -223.424242)
			(xy 384.460242 -223.424242) (xy 384.459747 -223.448849) (xy 384.451852 -223.497426) (xy 384.436268 -223.544107)
			(xy 384.413397 -223.587684) (xy 384.383832 -223.627028) (xy 384.348339 -223.66112) (xy 384.307836 -223.689076)
			(xy 384.263374 -223.710174) (xy 384.216103 -223.723866) (xy 384.167248 -223.729798) (xy 384.118073 -223.727817)
			(xy 384.069854 -223.717973) (xy 384.023838 -223.700521) (xy 383.981217 -223.675914) (xy 383.943096 -223.644789)
			(xy 383.910461 -223.607952) (xy 383.884158 -223.566356) (xy 383.864867 -223.52108) (xy 383.85309 -223.473296)
			(xy 383.84913 -223.424242) (xy 383.520188 -223.424242) (xy 383.519693 -223.448849) (xy 383.511798 -223.497426)
			(xy 383.496214 -223.544107) (xy 383.473343 -223.587684) (xy 383.443778 -223.627028) (xy 383.408285 -223.66112)
			(xy 383.367782 -223.689076) (xy 383.32332 -223.710174) (xy 383.276049 -223.723866) (xy 383.227194 -223.729798)
			(xy 383.178019 -223.727817) (xy 383.1298 -223.717973) (xy 383.083784 -223.700521) (xy 383.041163 -223.675914)
			(xy 383.003042 -223.644789) (xy 382.970407 -223.607952) (xy 382.944104 -223.566356) (xy 382.924813 -223.52108)
			(xy 382.913036 -223.473296) (xy 382.909076 -223.424242) (xy 382.580134 -223.424242) (xy 382.579639 -223.448849)
			(xy 382.571744 -223.497426) (xy 382.55616 -223.544107) (xy 382.533289 -223.587684) (xy 382.503724 -223.627028)
			(xy 382.468231 -223.66112) (xy 382.427728 -223.689076) (xy 382.383266 -223.710174) (xy 382.335995 -223.723866)
			(xy 382.28714 -223.729798) (xy 382.237965 -223.727817) (xy 382.189746 -223.717973) (xy 382.14373 -223.700521)
			(xy 382.101109 -223.675914) (xy 382.062988 -223.644789) (xy 382.030353 -223.607952) (xy 382.00405 -223.566356)
			(xy 381.984759 -223.52108) (xy 381.972982 -223.473296) (xy 381.969022 -223.424242) (xy 381.64008 -223.424242)
			(xy 381.639585 -223.448849) (xy 381.63169 -223.497426) (xy 381.616106 -223.544107) (xy 381.593235 -223.587684)
			(xy 381.56367 -223.627028) (xy 381.528177 -223.66112) (xy 381.487674 -223.689076) (xy 381.443212 -223.710174)
			(xy 381.395941 -223.723866) (xy 381.347086 -223.729798) (xy 381.297911 -223.727817) (xy 381.249692 -223.717973)
			(xy 381.203676 -223.700521) (xy 381.161055 -223.675914) (xy 381.122934 -223.644789) (xy 381.090299 -223.607952)
			(xy 381.063996 -223.566356) (xy 381.044705 -223.52108) (xy 381.032928 -223.473296) (xy 381.028968 -223.424242)
			(xy 378.820172 -223.424242) (xy 378.819677 -223.448849) (xy 378.811782 -223.497426) (xy 378.796198 -223.544107)
			(xy 378.773327 -223.587684) (xy 378.743762 -223.627028) (xy 378.708269 -223.66112) (xy 378.667766 -223.689076)
			(xy 378.623304 -223.710174) (xy 378.576033 -223.723866) (xy 378.527178 -223.729798) (xy 378.478003 -223.727817)
			(xy 378.429784 -223.717973) (xy 378.383768 -223.700521) (xy 378.341147 -223.675914) (xy 378.303026 -223.644789)
			(xy 378.270391 -223.607952) (xy 378.244088 -223.566356) (xy 378.224797 -223.52108) (xy 378.21302 -223.473296)
			(xy 378.20906 -223.424242) (xy 377.880118 -223.424242) (xy 377.879623 -223.448849) (xy 377.871728 -223.497426)
			(xy 377.856144 -223.544107) (xy 377.833273 -223.587684) (xy 377.803708 -223.627028) (xy 377.768215 -223.66112)
			(xy 377.727712 -223.689076) (xy 377.68325 -223.710174) (xy 377.635979 -223.723866) (xy 377.587124 -223.729798)
			(xy 377.537949 -223.727817) (xy 377.48973 -223.717973) (xy 377.443714 -223.700521) (xy 377.401093 -223.675914)
			(xy 377.362972 -223.644789) (xy 377.330337 -223.607952) (xy 377.304034 -223.566356) (xy 377.284743 -223.52108)
			(xy 377.272966 -223.473296) (xy 377.269006 -223.424242) (xy 376.954055 -223.424242) (xy 376.953526 -223.42475)
			(xy 376.93854 -223.455738) (xy 376.937524 -223.463866) (xy 376.933446 -223.490603) (xy 376.917099 -223.542155)
			(xy 376.891919 -223.590016) (xy 376.858695 -223.632687) (xy 376.818466 -223.668832) (xy 376.795792 -223.683576)
			(xy 376.795284 -223.684592) (xy 376.782838 -223.732852) (xy 376.781822 -223.736154) (xy 376.780806 -223.742758)
			(xy 376.780417 -223.746372) (xy 376.780547 -223.753638) (xy 376.78106 -223.757236) (xy 376.782076 -223.764602)
			(xy 376.783092 -223.768158) (xy 376.792432 -223.800049) (xy 376.80882 -223.864459) (xy 376.815858 -223.896936)
			(xy 376.81885 -223.908458) (xy 376.833551 -223.927143) (xy 376.844052 -223.93275) (xy 376.926602 -223.971104)
			(xy 376.950224 -223.970342) (xy 376.960892 -223.964754) (xy 376.983185 -223.953407) (xy 377.03055 -223.93733)
			(xy 377.079901 -223.929184) (xy 377.10491 -223.928686) (xy 377.114816 -223.928686) (xy 377.128532 -223.929956)
			(xy 377.153753 -223.932423) (xy 377.202931 -223.944646) (xy 377.249415 -223.96482) (xy 377.291932 -223.992391)
			(xy 377.329315 -224.026602) (xy 377.360537 -224.066514) (xy 377.384742 -224.111033) (xy 377.401266 -224.158937)
			(xy 377.409656 -224.208911) (xy 377.410218 -224.234248) (xy 377.738906 -224.234248) (xy 377.742866 -224.185194)
			(xy 377.754643 -224.13741) (xy 377.773934 -224.092134) (xy 377.800237 -224.050538) (xy 377.832872 -224.013701)
			(xy 377.870993 -223.982576) (xy 377.913614 -223.957969) (xy 377.95963 -223.940517) (xy 378.007849 -223.930673)
			(xy 378.057024 -223.928692) (xy 378.105879 -223.934624) (xy 378.15315 -223.948316) (xy 378.197612 -223.969414)
			(xy 378.238115 -223.99737) (xy 378.273608 -224.031462) (xy 378.303173 -224.070806) (xy 378.326044 -224.114383)
			(xy 378.341628 -224.161064) (xy 378.349523 -224.209641) (xy 378.350018 -224.234248) (xy 378.67896 -224.234248)
			(xy 378.68292 -224.185194) (xy 378.694697 -224.13741) (xy 378.713988 -224.092134) (xy 378.740291 -224.050538)
			(xy 378.772926 -224.013701) (xy 378.811047 -223.982576) (xy 378.853668 -223.957969) (xy 378.899684 -223.940517)
			(xy 378.947903 -223.930673) (xy 378.997078 -223.928692) (xy 379.045933 -223.934624) (xy 379.093204 -223.948316)
			(xy 379.137666 -223.969414) (xy 379.178169 -223.99737) (xy 379.213662 -224.031462) (xy 379.243227 -224.070806)
			(xy 379.266098 -224.114383) (xy 379.281682 -224.161064) (xy 379.289577 -224.209641) (xy 379.290072 -224.234248)
			(xy 379.619014 -224.234248) (xy 379.622974 -224.185194) (xy 379.634751 -224.13741) (xy 379.654042 -224.092134)
			(xy 379.680345 -224.050538) (xy 379.71298 -224.013701) (xy 379.751101 -223.982576) (xy 379.793722 -223.957969)
			(xy 379.839738 -223.940517) (xy 379.887957 -223.930673) (xy 379.937132 -223.928692) (xy 379.985987 -223.934624)
			(xy 380.033258 -223.948316) (xy 380.07772 -223.969414) (xy 380.118223 -223.99737) (xy 380.153716 -224.031462)
			(xy 380.183281 -224.070806) (xy 380.206152 -224.114383) (xy 380.221736 -224.161064) (xy 380.229631 -224.209641)
			(xy 380.230126 -224.234248) (xy 380.559068 -224.234248) (xy 380.563028 -224.185194) (xy 380.574805 -224.13741)
			(xy 380.594096 -224.092134) (xy 380.620399 -224.050538) (xy 380.653034 -224.013701) (xy 380.691155 -223.982576)
			(xy 380.733776 -223.957969) (xy 380.779792 -223.940517) (xy 380.828011 -223.930673) (xy 380.877186 -223.928692)
			(xy 380.926041 -223.934624) (xy 380.973312 -223.948316) (xy 381.017774 -223.969414) (xy 381.058277 -223.99737)
			(xy 381.09377 -224.031462) (xy 381.123335 -224.070806) (xy 381.146206 -224.114383) (xy 381.16179 -224.161064)
			(xy 381.169685 -224.209641) (xy 381.17018 -224.234248) (xy 382.438922 -224.234248) (xy 382.442882 -224.185194)
			(xy 382.454659 -224.13741) (xy 382.47395 -224.092134) (xy 382.500253 -224.050538) (xy 382.532888 -224.013701)
			(xy 382.571009 -223.982576) (xy 382.61363 -223.957969) (xy 382.659646 -223.940517) (xy 382.707865 -223.930673)
			(xy 382.75704 -223.928692) (xy 382.805895 -223.934624) (xy 382.853166 -223.948316) (xy 382.897628 -223.969414)
			(xy 382.938131 -223.99737) (xy 382.973624 -224.031462) (xy 383.003189 -224.070806) (xy 383.02606 -224.114383)
			(xy 383.041644 -224.161064) (xy 383.049539 -224.209641) (xy 383.050034 -224.234248) (xy 383.378976 -224.234248)
			(xy 383.382936 -224.185194) (xy 383.394713 -224.13741) (xy 383.414004 -224.092134) (xy 383.440307 -224.050538)
			(xy 383.472942 -224.013701) (xy 383.511063 -223.982576) (xy 383.553684 -223.957969) (xy 383.5997 -223.940517)
			(xy 383.647919 -223.930673) (xy 383.697094 -223.928692) (xy 383.745949 -223.934624) (xy 383.79322 -223.948316)
			(xy 383.837682 -223.969414) (xy 383.878185 -223.99737) (xy 383.913678 -224.031462) (xy 383.943243 -224.070806)
			(xy 383.966114 -224.114383) (xy 383.981698 -224.161064) (xy 383.989593 -224.209641) (xy 383.990088 -224.234248)
			(xy 384.31903 -224.234248) (xy 384.32299 -224.185194) (xy 384.334767 -224.13741) (xy 384.354058 -224.092134)
			(xy 384.380361 -224.050538) (xy 384.412996 -224.013701) (xy 384.451117 -223.982576) (xy 384.493738 -223.957969)
			(xy 384.539754 -223.940517) (xy 384.587973 -223.930673) (xy 384.637148 -223.928692) (xy 384.686003 -223.934624)
			(xy 384.733274 -223.948316) (xy 384.777736 -223.969414) (xy 384.818239 -223.99737) (xy 384.853732 -224.031462)
			(xy 384.883297 -224.070806) (xy 384.906168 -224.114383) (xy 384.921752 -224.161064) (xy 384.929647 -224.209641)
			(xy 384.930142 -224.234248) (xy 384.929647 -224.258855) (xy 384.921752 -224.307432) (xy 384.906168 -224.354113)
			(xy 384.883297 -224.39769) (xy 384.853732 -224.437034) (xy 384.818239 -224.471126) (xy 384.777736 -224.499082)
			(xy 384.733274 -224.52018) (xy 384.686003 -224.533872) (xy 384.637148 -224.539804) (xy 384.587973 -224.537823)
			(xy 384.539754 -224.527979) (xy 384.493738 -224.510527) (xy 384.451117 -224.48592) (xy 384.412996 -224.454795)
			(xy 384.380361 -224.417958) (xy 384.354058 -224.376362) (xy 384.334767 -224.331086) (xy 384.32299 -224.283302)
			(xy 384.31903 -224.234248) (xy 383.990088 -224.234248) (xy 383.989593 -224.258855) (xy 383.981698 -224.307432)
			(xy 383.966114 -224.354113) (xy 383.943243 -224.39769) (xy 383.913678 -224.437034) (xy 383.878185 -224.471126)
			(xy 383.837682 -224.499082) (xy 383.79322 -224.52018) (xy 383.745949 -224.533872) (xy 383.697094 -224.539804)
			(xy 383.647919 -224.537823) (xy 383.5997 -224.527979) (xy 383.553684 -224.510527) (xy 383.511063 -224.48592)
			(xy 383.472942 -224.454795) (xy 383.440307 -224.417958) (xy 383.414004 -224.376362) (xy 383.394713 -224.331086)
			(xy 383.382936 -224.283302) (xy 383.378976 -224.234248) (xy 383.050034 -224.234248) (xy 383.049539 -224.258855)
			(xy 383.041644 -224.307432) (xy 383.02606 -224.354113) (xy 383.003189 -224.39769) (xy 382.973624 -224.437034)
			(xy 382.938131 -224.471126) (xy 382.897628 -224.499082) (xy 382.853166 -224.52018) (xy 382.805895 -224.533872)
			(xy 382.75704 -224.539804) (xy 382.707865 -224.537823) (xy 382.659646 -224.527979) (xy 382.61363 -224.510527)
			(xy 382.571009 -224.48592) (xy 382.532888 -224.454795) (xy 382.500253 -224.417958) (xy 382.47395 -224.376362)
			(xy 382.454659 -224.331086) (xy 382.442882 -224.283302) (xy 382.438922 -224.234248) (xy 381.17018 -224.234248)
			(xy 381.169685 -224.258855) (xy 381.16179 -224.307432) (xy 381.146206 -224.354113) (xy 381.123335 -224.39769)
			(xy 381.09377 -224.437034) (xy 381.058277 -224.471126) (xy 381.017774 -224.499082) (xy 380.973312 -224.52018)
			(xy 380.926041 -224.533872) (xy 380.877186 -224.539804) (xy 380.828011 -224.537823) (xy 380.779792 -224.527979)
			(xy 380.733776 -224.510527) (xy 380.691155 -224.48592) (xy 380.653034 -224.454795) (xy 380.620399 -224.417958)
			(xy 380.594096 -224.376362) (xy 380.574805 -224.331086) (xy 380.563028 -224.283302) (xy 380.559068 -224.234248)
			(xy 380.230126 -224.234248) (xy 380.229631 -224.258855) (xy 380.221736 -224.307432) (xy 380.206152 -224.354113)
			(xy 380.183281 -224.39769) (xy 380.153716 -224.437034) (xy 380.118223 -224.471126) (xy 380.07772 -224.499082)
			(xy 380.033258 -224.52018) (xy 379.985987 -224.533872) (xy 379.937132 -224.539804) (xy 379.887957 -224.537823)
			(xy 379.839738 -224.527979) (xy 379.793722 -224.510527) (xy 379.751101 -224.48592) (xy 379.71298 -224.454795)
			(xy 379.680345 -224.417958) (xy 379.654042 -224.376362) (xy 379.634751 -224.331086) (xy 379.622974 -224.283302)
			(xy 379.619014 -224.234248) (xy 379.290072 -224.234248) (xy 379.289577 -224.258855) (xy 379.281682 -224.307432)
			(xy 379.266098 -224.354113) (xy 379.243227 -224.39769) (xy 379.213662 -224.437034) (xy 379.178169 -224.471126)
			(xy 379.137666 -224.499082) (xy 379.093204 -224.52018) (xy 379.045933 -224.533872) (xy 378.997078 -224.539804)
			(xy 378.947903 -224.537823) (xy 378.899684 -224.527979) (xy 378.853668 -224.510527) (xy 378.811047 -224.48592)
			(xy 378.772926 -224.454795) (xy 378.740291 -224.417958) (xy 378.713988 -224.376362) (xy 378.694697 -224.331086)
			(xy 378.68292 -224.283302) (xy 378.67896 -224.234248) (xy 378.350018 -224.234248) (xy 378.349523 -224.258855)
			(xy 378.341628 -224.307432) (xy 378.326044 -224.354113) (xy 378.303173 -224.39769) (xy 378.273608 -224.437034)
			(xy 378.238115 -224.471126) (xy 378.197612 -224.499082) (xy 378.15315 -224.52018) (xy 378.105879 -224.533872)
			(xy 378.057024 -224.539804) (xy 378.007849 -224.537823) (xy 377.95963 -224.527979) (xy 377.913614 -224.510527)
			(xy 377.870993 -224.48592) (xy 377.832872 -224.454795) (xy 377.800237 -224.417958) (xy 377.773934 -224.376362)
			(xy 377.754643 -224.331086) (xy 377.742866 -224.283302) (xy 377.738906 -224.234248) (xy 377.410218 -224.234248)
			(xy 377.409744 -224.258237) (xy 377.402232 -224.305624) (xy 377.3874 -224.351252) (xy 377.365614 -224.393998)
			(xy 377.33741 -224.432811) (xy 377.303482 -224.466735) (xy 377.264666 -224.494934) (xy 377.221917 -224.516715)
			(xy 377.176287 -224.531541) (xy 377.128899 -224.539047) (xy 377.10491 -224.539556) (xy 377.080039 -224.539044)
			(xy 377.03096 -224.53094) (xy 376.983841 -224.514993) (xy 376.961654 -224.503742) (xy 376.961146 -224.503742)
			(xy 376.961146 -224.503488) (xy 376.950429 -224.49854) (xy 376.926858 -224.498003) (xy 376.915934 -224.502472)
			(xy 376.833384 -224.541334) (xy 376.818652 -224.559622) (xy 376.816112 -224.57156) (xy 376.807907 -224.608709)
			(xy 376.788468 -224.682273) (xy 376.77725 -224.718626) (xy 376.77725 -224.71888) (xy 376.776996 -224.719388)
			(xy 376.774536 -224.729243) (xy 376.776778 -224.749414) (xy 376.781314 -224.758504) (xy 376.792744 -224.779078)
			(xy 376.800618 -224.787714) (xy 376.805698 -224.791016) (xy 376.826026 -224.805367) (xy 376.86217 -224.839565)
			(xy 376.892299 -224.879165) (xy 376.915618 -224.92312) (xy 376.931512 -224.970272) (xy 376.93956 -225.019375)
			(xy 376.940064 -225.044254) (xy 377.258575 -225.044254) (xy 377.26267 -224.993526) (xy 377.274849 -224.944112)
			(xy 377.294797 -224.897292) (xy 377.321998 -224.854278) (xy 377.355746 -224.816184) (xy 377.395168 -224.783997)
			(xy 377.439242 -224.758551) (xy 377.486828 -224.740504) (xy 377.536692 -224.730324) (xy 377.587544 -224.728275)
			(xy 377.638065 -224.734409) (xy 377.686949 -224.748569) (xy 377.732928 -224.770386) (xy 377.774812 -224.799296)
			(xy 377.811516 -224.834551) (xy 377.842089 -224.875237) (xy 377.86574 -224.9203) (xy 377.881856 -224.968574)
			(xy 377.89002 -225.018808) (xy 377.890532 -225.044254) (xy 378.20906 -225.044254) (xy 378.21302 -224.9952)
			(xy 378.224797 -224.947416) (xy 378.244088 -224.90214) (xy 378.270391 -224.860544) (xy 378.303026 -224.823707)
			(xy 378.341147 -224.792582) (xy 378.383768 -224.767975) (xy 378.429784 -224.750523) (xy 378.478003 -224.740679)
			(xy 378.527178 -224.738698) (xy 378.576033 -224.74463) (xy 378.623304 -224.758322) (xy 378.667766 -224.77942)
			(xy 378.708269 -224.807376) (xy 378.743762 -224.841468) (xy 378.773327 -224.880812) (xy 378.796198 -224.924389)
			(xy 378.811782 -224.97107) (xy 378.819677 -225.019647) (xy 378.820172 -225.044254) (xy 379.149114 -225.044254)
			(xy 379.153074 -224.9952) (xy 379.164851 -224.947416) (xy 379.184142 -224.90214) (xy 379.210445 -224.860544)
			(xy 379.24308 -224.823707) (xy 379.281201 -224.792582) (xy 379.323822 -224.767975) (xy 379.369838 -224.750523)
			(xy 379.418057 -224.740679) (xy 379.467232 -224.738698) (xy 379.516087 -224.74463) (xy 379.563358 -224.758322)
			(xy 379.60782 -224.77942) (xy 379.648323 -224.807376) (xy 379.683816 -224.841468) (xy 379.713381 -224.880812)
			(xy 379.736252 -224.924389) (xy 379.751836 -224.97107) (xy 379.759731 -225.019647) (xy 379.760226 -225.044254)
			(xy 380.078483 -225.044254) (xy 380.082578 -224.993526) (xy 380.094757 -224.944112) (xy 380.114705 -224.897292)
			(xy 380.141906 -224.854278) (xy 380.175654 -224.816184) (xy 380.215076 -224.783997) (xy 380.25915 -224.758551)
			(xy 380.306736 -224.740504) (xy 380.3566 -224.730324) (xy 380.407452 -224.728275) (xy 380.457973 -224.734409)
			(xy 380.506857 -224.748569) (xy 380.552836 -224.770386) (xy 380.59472 -224.799296) (xy 380.631424 -224.834551)
			(xy 380.661997 -224.875237) (xy 380.685648 -224.9203) (xy 380.701764 -224.968574) (xy 380.709928 -225.018808)
			(xy 380.71044 -225.044254) (xy 381.028968 -225.044254) (xy 381.032928 -224.9952) (xy 381.044705 -224.947416)
			(xy 381.063996 -224.90214) (xy 381.090299 -224.860544) (xy 381.122934 -224.823707) (xy 381.161055 -224.792582)
			(xy 381.203676 -224.767975) (xy 381.249692 -224.750523) (xy 381.297911 -224.740679) (xy 381.347086 -224.738698)
			(xy 381.395941 -224.74463) (xy 381.443212 -224.758322) (xy 381.487674 -224.77942) (xy 381.528177 -224.807376)
			(xy 381.56367 -224.841468) (xy 381.593235 -224.880812) (xy 381.616106 -224.924389) (xy 381.63169 -224.97107)
			(xy 381.639585 -225.019647) (xy 381.64008 -225.044254) (xy 381.969022 -225.044254) (xy 381.972982 -224.9952)
			(xy 381.984759 -224.947416) (xy 382.00405 -224.90214) (xy 382.030353 -224.860544) (xy 382.062988 -224.823707)
			(xy 382.101109 -224.792582) (xy 382.14373 -224.767975) (xy 382.189746 -224.750523) (xy 382.237965 -224.740679)
			(xy 382.28714 -224.738698) (xy 382.335995 -224.74463) (xy 382.383266 -224.758322) (xy 382.427728 -224.77942)
			(xy 382.468231 -224.807376) (xy 382.503724 -224.841468) (xy 382.533289 -224.880812) (xy 382.55616 -224.924389)
			(xy 382.571744 -224.97107) (xy 382.579639 -225.019647) (xy 382.580134 -225.044254) (xy 382.909076 -225.044254)
			(xy 382.913036 -224.9952) (xy 382.924813 -224.947416) (xy 382.944104 -224.90214) (xy 382.970407 -224.860544)
			(xy 383.003042 -224.823707) (xy 383.041163 -224.792582) (xy 383.083784 -224.767975) (xy 383.1298 -224.750523)
			(xy 383.178019 -224.740679) (xy 383.227194 -224.738698) (xy 383.276049 -224.74463) (xy 383.32332 -224.758322)
			(xy 383.367782 -224.77942) (xy 383.408285 -224.807376) (xy 383.443778 -224.841468) (xy 383.473343 -224.880812)
			(xy 383.496214 -224.924389) (xy 383.511798 -224.97107) (xy 383.519693 -225.019647) (xy 383.520188 -225.044254)
			(xy 383.84913 -225.044254) (xy 383.85309 -224.9952) (xy 383.864867 -224.947416) (xy 383.884158 -224.90214)
			(xy 383.910461 -224.860544) (xy 383.943096 -224.823707) (xy 383.981217 -224.792582) (xy 384.023838 -224.767975)
			(xy 384.069854 -224.750523) (xy 384.118073 -224.740679) (xy 384.167248 -224.738698) (xy 384.216103 -224.74463)
			(xy 384.263374 -224.758322) (xy 384.307836 -224.77942) (xy 384.348339 -224.807376) (xy 384.383832 -224.841468)
			(xy 384.413397 -224.880812) (xy 384.436268 -224.924389) (xy 384.451852 -224.97107) (xy 384.459747 -225.019647)
			(xy 384.460242 -225.044254) (xy 384.459747 -225.068861) (xy 384.451852 -225.117438) (xy 384.436268 -225.164119)
			(xy 384.413397 -225.207696) (xy 384.383832 -225.24704) (xy 384.348339 -225.281132) (xy 384.307836 -225.309088)
			(xy 384.263374 -225.330186) (xy 384.216103 -225.343878) (xy 384.167248 -225.34981) (xy 384.118073 -225.347829)
			(xy 384.069854 -225.337985) (xy 384.023838 -225.320533) (xy 383.981217 -225.295926) (xy 383.943096 -225.264801)
			(xy 383.910461 -225.227964) (xy 383.884158 -225.186368) (xy 383.864867 -225.141092) (xy 383.85309 -225.093308)
			(xy 383.84913 -225.044254) (xy 383.520188 -225.044254) (xy 383.519693 -225.068861) (xy 383.511798 -225.117438)
			(xy 383.496214 -225.164119) (xy 383.473343 -225.207696) (xy 383.443778 -225.24704) (xy 383.408285 -225.281132)
			(xy 383.367782 -225.309088) (xy 383.32332 -225.330186) (xy 383.276049 -225.343878) (xy 383.227194 -225.34981)
			(xy 383.178019 -225.347829) (xy 383.1298 -225.337985) (xy 383.083784 -225.320533) (xy 383.041163 -225.295926)
			(xy 383.003042 -225.264801) (xy 382.970407 -225.227964) (xy 382.944104 -225.186368) (xy 382.924813 -225.141092)
			(xy 382.913036 -225.093308) (xy 382.909076 -225.044254) (xy 382.580134 -225.044254) (xy 382.579639 -225.068861)
			(xy 382.571744 -225.117438) (xy 382.55616 -225.164119) (xy 382.533289 -225.207696) (xy 382.503724 -225.24704)
			(xy 382.468231 -225.281132) (xy 382.427728 -225.309088) (xy 382.383266 -225.330186) (xy 382.335995 -225.343878)
			(xy 382.28714 -225.34981) (xy 382.237965 -225.347829) (xy 382.189746 -225.337985) (xy 382.14373 -225.320533)
			(xy 382.101109 -225.295926) (xy 382.062988 -225.264801) (xy 382.030353 -225.227964) (xy 382.00405 -225.186368)
			(xy 381.984759 -225.141092) (xy 381.972982 -225.093308) (xy 381.969022 -225.044254) (xy 381.64008 -225.044254)
			(xy 381.639585 -225.068861) (xy 381.63169 -225.117438) (xy 381.616106 -225.164119) (xy 381.593235 -225.207696)
			(xy 381.56367 -225.24704) (xy 381.528177 -225.281132) (xy 381.487674 -225.309088) (xy 381.443212 -225.330186)
			(xy 381.395941 -225.343878) (xy 381.347086 -225.34981) (xy 381.297911 -225.347829) (xy 381.249692 -225.337985)
			(xy 381.203676 -225.320533) (xy 381.161055 -225.295926) (xy 381.122934 -225.264801) (xy 381.090299 -225.227964)
			(xy 381.063996 -225.186368) (xy 381.044705 -225.141092) (xy 381.032928 -225.093308) (xy 381.028968 -225.044254)
			(xy 380.71044 -225.044254) (xy 380.709928 -225.0697) (xy 380.701764 -225.119934) (xy 380.685648 -225.168208)
			(xy 380.661997 -225.213271) (xy 380.631424 -225.253957) (xy 380.59472 -225.289212) (xy 380.552836 -225.318122)
			(xy 380.506857 -225.339939) (xy 380.457973 -225.354099) (xy 380.407452 -225.360233) (xy 380.3566 -225.358184)
			(xy 380.306736 -225.348004) (xy 380.25915 -225.329957) (xy 380.215076 -225.304511) (xy 380.175654 -225.272324)
			(xy 380.141906 -225.23423) (xy 380.114705 -225.191216) (xy 380.094757 -225.144396) (xy 380.082578 -225.094982)
			(xy 380.078483 -225.044254) (xy 379.760226 -225.044254) (xy 379.759731 -225.068861) (xy 379.751836 -225.117438)
			(xy 379.736252 -225.164119) (xy 379.713381 -225.207696) (xy 379.683816 -225.24704) (xy 379.648323 -225.281132)
			(xy 379.60782 -225.309088) (xy 379.563358 -225.330186) (xy 379.516087 -225.343878) (xy 379.467232 -225.34981)
			(xy 379.418057 -225.347829) (xy 379.369838 -225.337985) (xy 379.323822 -225.320533) (xy 379.281201 -225.295926)
			(xy 379.24308 -225.264801) (xy 379.210445 -225.227964) (xy 379.184142 -225.186368) (xy 379.164851 -225.141092)
			(xy 379.153074 -225.093308) (xy 379.149114 -225.044254) (xy 378.820172 -225.044254) (xy 378.819677 -225.068861)
			(xy 378.811782 -225.117438) (xy 378.796198 -225.164119) (xy 378.773327 -225.207696) (xy 378.743762 -225.24704)
			(xy 378.708269 -225.281132) (xy 378.667766 -225.309088) (xy 378.623304 -225.330186) (xy 378.576033 -225.343878)
			(xy 378.527178 -225.34981) (xy 378.478003 -225.347829) (xy 378.429784 -225.337985) (xy 378.383768 -225.320533)
			(xy 378.341147 -225.295926) (xy 378.303026 -225.264801) (xy 378.270391 -225.227964) (xy 378.244088 -225.186368)
			(xy 378.224797 -225.141092) (xy 378.21302 -225.093308) (xy 378.20906 -225.044254) (xy 377.890532 -225.044254)
			(xy 377.89002 -225.0697) (xy 377.881856 -225.119934) (xy 377.86574 -225.168208) (xy 377.842089 -225.213271)
			(xy 377.811516 -225.253957) (xy 377.774812 -225.289212) (xy 377.732928 -225.318122) (xy 377.686949 -225.339939)
			(xy 377.638065 -225.354099) (xy 377.587544 -225.360233) (xy 377.536692 -225.358184) (xy 377.486828 -225.348004)
			(xy 377.439242 -225.329957) (xy 377.395168 -225.304511) (xy 377.355746 -225.272324) (xy 377.321998 -225.23423)
			(xy 377.294797 -225.191216) (xy 377.274849 -225.144396) (xy 377.26267 -225.094982) (xy 377.258575 -225.044254)
			(xy 376.940064 -225.044254) (xy 376.939595 -225.068492) (xy 376.931931 -225.116357) (xy 376.916803 -225.162411)
			(xy 376.894591 -225.205498) (xy 376.865852 -225.244536) (xy 376.831309 -225.278545) (xy 376.791828 -225.306672)
			(xy 376.748401 -225.32821) (xy 376.702117 -225.342619) (xy 376.67819 -225.346514) (xy 376.664728 -225.348292)
			(xy 376.634756 -225.349816) (xy 376.611183 -225.349399) (xy 376.56459 -225.342198) (xy 376.519655 -225.327927)
			(xy 376.498358 -225.317812) (xy 376.49658 -225.316796) (xy 376.4915 -225.314764) (xy 376.481836 -225.311418)
			(xy 376.461404 -225.31181) (xy 376.451876 -225.315526) (xy 376.431556 -225.32467) (xy 376.424444 -225.332544)
			(xy 376.406929 -225.351522) (xy 376.370854 -225.388487) (xy 376.352308 -225.406458) (xy 376.347228 -225.411538)
			(xy 376.333258 -225.435668) (xy 376.33148 -225.442526) (xy 376.326074 -225.463745) (xy 376.314262 -225.505915)
			(xy 376.307858 -225.526854) (xy 376.30504 -225.537762) (xy 376.308104 -225.560054) (xy 376.320422 -225.578884)
			(xy 376.329702 -225.585274) (xy 376.352321 -225.59977) (xy 376.392708 -225.635191) (xy 376.426512 -225.676942)
			(xy 376.452756 -225.723814) (xy 376.470681 -225.774455) (xy 376.47977 -225.8274) (xy 376.480324 -225.85426)
			(xy 376.788675 -225.85426) (xy 376.79277 -225.803532) (xy 376.804949 -225.754118) (xy 376.824897 -225.707298)
			(xy 376.852098 -225.664284) (xy 376.885846 -225.62619) (xy 376.925268 -225.594003) (xy 376.969342 -225.568557)
			(xy 377.016928 -225.55051) (xy 377.066792 -225.54033) (xy 377.117644 -225.538281) (xy 377.168165 -225.544415)
			(xy 377.217049 -225.558575) (xy 377.263028 -225.580392) (xy 377.304912 -225.609302) (xy 377.341616 -225.644557)
			(xy 377.372189 -225.685243) (xy 377.39584 -225.730306) (xy 377.411956 -225.77858) (xy 377.42012 -225.828814)
			(xy 377.420632 -225.85426) (xy 377.738906 -225.85426) (xy 377.742866 -225.805206) (xy 377.754643 -225.757422)
			(xy 377.773934 -225.712146) (xy 377.800237 -225.67055) (xy 377.832872 -225.633713) (xy 377.870993 -225.602588)
			(xy 377.913614 -225.577981) (xy 377.95963 -225.560529) (xy 378.007849 -225.550685) (xy 378.057024 -225.548704)
			(xy 378.105879 -225.554636) (xy 378.15315 -225.568328) (xy 378.197612 -225.589426) (xy 378.238115 -225.617382)
			(xy 378.273608 -225.651474) (xy 378.303173 -225.690818) (xy 378.326044 -225.734395) (xy 378.341628 -225.781076)
			(xy 378.349523 -225.829653) (xy 378.350018 -225.85426) (xy 378.668529 -225.85426) (xy 378.672624 -225.803532)
			(xy 378.684803 -225.754118) (xy 378.704751 -225.707298) (xy 378.731952 -225.664284) (xy 378.7657 -225.62619)
			(xy 378.805122 -225.594003) (xy 378.849196 -225.568557) (xy 378.896782 -225.55051) (xy 378.946646 -225.54033)
			(xy 378.997498 -225.538281) (xy 379.048019 -225.544415) (xy 379.096903 -225.558575) (xy 379.142882 -225.580392)
			(xy 379.184766 -225.609302) (xy 379.22147 -225.644557) (xy 379.252043 -225.685243) (xy 379.275694 -225.730306)
			(xy 379.29181 -225.77858) (xy 379.299974 -225.828814) (xy 379.300486 -225.85426) (xy 379.619014 -225.85426)
			(xy 379.622974 -225.805206) (xy 379.634751 -225.757422) (xy 379.654042 -225.712146) (xy 379.680345 -225.67055)
			(xy 379.71298 -225.633713) (xy 379.751101 -225.602588) (xy 379.793722 -225.577981) (xy 379.839738 -225.560529)
			(xy 379.887957 -225.550685) (xy 379.937132 -225.548704) (xy 379.985987 -225.554636) (xy 380.033258 -225.568328)
			(xy 380.07772 -225.589426) (xy 380.118223 -225.617382) (xy 380.153716 -225.651474) (xy 380.183281 -225.690818)
			(xy 380.206152 -225.734395) (xy 380.221736 -225.781076) (xy 380.229631 -225.829653) (xy 380.230126 -225.85426)
			(xy 380.548637 -225.85426) (xy 380.552732 -225.803532) (xy 380.564911 -225.754118) (xy 380.584859 -225.707298)
			(xy 380.61206 -225.664284) (xy 380.645808 -225.62619) (xy 380.68523 -225.594003) (xy 380.729304 -225.568557)
			(xy 380.77689 -225.55051) (xy 380.826754 -225.54033) (xy 380.877606 -225.538281) (xy 380.928127 -225.544415)
			(xy 380.977011 -225.558575) (xy 381.02299 -225.580392) (xy 381.064874 -225.609302) (xy 381.101578 -225.644557)
			(xy 381.132151 -225.685243) (xy 381.155802 -225.730306) (xy 381.171918 -225.77858) (xy 381.180082 -225.828814)
			(xy 381.180594 -225.85426) (xy 381.499122 -225.85426) (xy 381.503082 -225.805206) (xy 381.514859 -225.757422)
			(xy 381.53415 -225.712146) (xy 381.560453 -225.67055) (xy 381.593088 -225.633713) (xy 381.631209 -225.602588)
			(xy 381.67383 -225.577981) (xy 381.719846 -225.560529) (xy 381.768065 -225.550685) (xy 381.81724 -225.548704)
			(xy 381.866095 -225.554636) (xy 381.913366 -225.568328) (xy 381.957828 -225.589426) (xy 381.998331 -225.617382)
			(xy 382.033824 -225.651474) (xy 382.063389 -225.690818) (xy 382.08626 -225.734395) (xy 382.101844 -225.781076)
			(xy 382.109739 -225.829653) (xy 382.110234 -225.85426) (xy 382.438922 -225.85426) (xy 382.442882 -225.805206)
			(xy 382.454659 -225.757422) (xy 382.47395 -225.712146) (xy 382.500253 -225.67055) (xy 382.532888 -225.633713)
			(xy 382.571009 -225.602588) (xy 382.61363 -225.577981) (xy 382.659646 -225.560529) (xy 382.707865 -225.550685)
			(xy 382.75704 -225.548704) (xy 382.805895 -225.554636) (xy 382.853166 -225.568328) (xy 382.897628 -225.589426)
			(xy 382.938131 -225.617382) (xy 382.973624 -225.651474) (xy 383.003189 -225.690818) (xy 383.02606 -225.734395)
			(xy 383.041644 -225.781076) (xy 383.049539 -225.829653) (xy 383.050034 -225.85426) (xy 383.378976 -225.85426)
			(xy 383.382936 -225.805206) (xy 383.394713 -225.757422) (xy 383.414004 -225.712146) (xy 383.440307 -225.67055)
			(xy 383.472942 -225.633713) (xy 383.511063 -225.602588) (xy 383.553684 -225.577981) (xy 383.5997 -225.560529)
			(xy 383.647919 -225.550685) (xy 383.697094 -225.548704) (xy 383.745949 -225.554636) (xy 383.79322 -225.568328)
			(xy 383.837682 -225.589426) (xy 383.878185 -225.617382) (xy 383.913678 -225.651474) (xy 383.943243 -225.690818)
			(xy 383.966114 -225.734395) (xy 383.981698 -225.781076) (xy 383.989593 -225.829653) (xy 383.990088 -225.85426)
			(xy 383.989593 -225.878867) (xy 383.981698 -225.927444) (xy 383.966114 -225.974125) (xy 383.943243 -226.017702)
			(xy 383.913678 -226.057046) (xy 383.878185 -226.091138) (xy 383.837682 -226.119094) (xy 383.79322 -226.140192)
			(xy 383.745949 -226.153884) (xy 383.697094 -226.159816) (xy 383.647919 -226.157835) (xy 383.5997 -226.147991)
			(xy 383.553684 -226.130539) (xy 383.511063 -226.105932) (xy 383.472942 -226.074807) (xy 383.440307 -226.03797)
			(xy 383.414004 -225.996374) (xy 383.394713 -225.951098) (xy 383.382936 -225.903314) (xy 383.378976 -225.85426)
			(xy 383.050034 -225.85426) (xy 383.049539 -225.878867) (xy 383.041644 -225.927444) (xy 383.02606 -225.974125)
			(xy 383.003189 -226.017702) (xy 382.973624 -226.057046) (xy 382.938131 -226.091138) (xy 382.897628 -226.119094)
			(xy 382.853166 -226.140192) (xy 382.805895 -226.153884) (xy 382.75704 -226.159816) (xy 382.707865 -226.157835)
			(xy 382.659646 -226.147991) (xy 382.61363 -226.130539) (xy 382.571009 -226.105932) (xy 382.532888 -226.074807)
			(xy 382.500253 -226.03797) (xy 382.47395 -225.996374) (xy 382.454659 -225.951098) (xy 382.442882 -225.903314)
			(xy 382.438922 -225.85426) (xy 382.110234 -225.85426) (xy 382.109739 -225.878867) (xy 382.101844 -225.927444)
			(xy 382.08626 -225.974125) (xy 382.063389 -226.017702) (xy 382.033824 -226.057046) (xy 381.998331 -226.091138)
			(xy 381.957828 -226.119094) (xy 381.913366 -226.140192) (xy 381.866095 -226.153884) (xy 381.81724 -226.159816)
			(xy 381.768065 -226.157835) (xy 381.719846 -226.147991) (xy 381.67383 -226.130539) (xy 381.631209 -226.105932)
			(xy 381.593088 -226.074807) (xy 381.560453 -226.03797) (xy 381.53415 -225.996374) (xy 381.514859 -225.951098)
			(xy 381.503082 -225.903314) (xy 381.499122 -225.85426) (xy 381.180594 -225.85426) (xy 381.180082 -225.879706)
			(xy 381.171918 -225.92994) (xy 381.155802 -225.978214) (xy 381.132151 -226.023277) (xy 381.101578 -226.063963)
			(xy 381.064874 -226.099218) (xy 381.02299 -226.128128) (xy 380.977011 -226.149945) (xy 380.928127 -226.164105)
			(xy 380.877606 -226.170239) (xy 380.826754 -226.16819) (xy 380.77689 -226.15801) (xy 380.729304 -226.139963)
			(xy 380.68523 -226.114517) (xy 380.645808 -226.08233) (xy 380.61206 -226.044236) (xy 380.584859 -226.001222)
			(xy 380.564911 -225.954402) (xy 380.552732 -225.904988) (xy 380.548637 -225.85426) (xy 380.230126 -225.85426)
			(xy 380.229631 -225.878867) (xy 380.221736 -225.927444) (xy 380.206152 -225.974125) (xy 380.183281 -226.017702)
			(xy 380.153716 -226.057046) (xy 380.118223 -226.091138) (xy 380.07772 -226.119094) (xy 380.033258 -226.140192)
			(xy 379.985987 -226.153884) (xy 379.937132 -226.159816) (xy 379.887957 -226.157835) (xy 379.839738 -226.147991)
			(xy 379.793722 -226.130539) (xy 379.751101 -226.105932) (xy 379.71298 -226.074807) (xy 379.680345 -226.03797)
			(xy 379.654042 -225.996374) (xy 379.634751 -225.951098) (xy 379.622974 -225.903314) (xy 379.619014 -225.85426)
			(xy 379.300486 -225.85426) (xy 379.299974 -225.879706) (xy 379.29181 -225.92994) (xy 379.275694 -225.978214)
			(xy 379.252043 -226.023277) (xy 379.22147 -226.063963) (xy 379.184766 -226.099218) (xy 379.142882 -226.128128)
			(xy 379.096903 -226.149945) (xy 379.048019 -226.164105) (xy 378.997498 -226.170239) (xy 378.946646 -226.16819)
			(xy 378.896782 -226.15801) (xy 378.849196 -226.139963) (xy 378.805122 -226.114517) (xy 378.7657 -226.08233)
			(xy 378.731952 -226.044236) (xy 378.704751 -226.001222) (xy 378.684803 -225.954402) (xy 378.672624 -225.904988)
			(xy 378.668529 -225.85426) (xy 378.350018 -225.85426) (xy 378.349523 -225.878867) (xy 378.341628 -225.927444)
			(xy 378.326044 -225.974125) (xy 378.303173 -226.017702) (xy 378.273608 -226.057046) (xy 378.238115 -226.091138)
			(xy 378.197612 -226.119094) (xy 378.15315 -226.140192) (xy 378.105879 -226.153884) (xy 378.057024 -226.159816)
			(xy 378.007849 -226.157835) (xy 377.95963 -226.147991) (xy 377.913614 -226.130539) (xy 377.870993 -226.105932)
			(xy 377.832872 -226.074807) (xy 377.800237 -226.03797) (xy 377.773934 -225.996374) (xy 377.754643 -225.951098)
			(xy 377.742866 -225.903314) (xy 377.738906 -225.85426) (xy 377.420632 -225.85426) (xy 377.42012 -225.879706)
			(xy 377.411956 -225.92994) (xy 377.39584 -225.978214) (xy 377.372189 -226.023277) (xy 377.341616 -226.063963)
			(xy 377.304912 -226.099218) (xy 377.263028 -226.128128) (xy 377.217049 -226.149945) (xy 377.168165 -226.164105)
			(xy 377.117644 -226.170239) (xy 377.066792 -226.16819) (xy 377.016928 -226.15801) (xy 376.969342 -226.139963)
			(xy 376.925268 -226.114517) (xy 376.885846 -226.08233) (xy 376.852098 -226.044236) (xy 376.824897 -226.001222)
			(xy 376.804949 -225.954402) (xy 376.79277 -225.904988) (xy 376.788675 -225.85426) (xy 376.480324 -225.85426)
			(xy 376.479866 -225.879052) (xy 376.472114 -225.928027) (xy 376.456795 -225.975186) (xy 376.434286 -226.019368)
			(xy 376.405142 -226.059483) (xy 376.37008 -226.094544) (xy 376.329964 -226.123688) (xy 376.285783 -226.146197)
			(xy 376.238623 -226.161515) (xy 376.189648 -226.169266) (xy 376.164856 -226.169728) (xy 376.135733 -226.169081)
			(xy 376.078471 -226.158431) (xy 376.024138 -226.137447) (xy 375.998994 -226.122738) (xy 375.988834 -226.122484)
			(xy 375.960894 -226.134676) (xy 375.953782 -226.14255) (xy 375.936567 -226.161193) (xy 375.901127 -226.197522)
			(xy 375.882916 -226.215194) (xy 375.877582 -226.220274) (xy 375.863612 -226.244658) (xy 375.861834 -226.251516)
			(xy 375.861834 -226.25177) (xy 375.856371 -226.273181) (xy 375.844432 -226.315732) (xy 375.837958 -226.33686)
			(xy 375.835141 -226.347768) (xy 375.838207 -226.370058) (xy 375.850526 -226.388885) (xy 375.859802 -226.39528)
			(xy 375.880704 -226.408626) (xy 375.918417 -226.440827) (xy 375.950628 -226.478532) (xy 375.976543 -226.520812)
			(xy 375.995525 -226.566626) (xy 376.007105 -226.614845) (xy 376.010998 -226.664266) (xy 376.328952 -226.664266)
			(xy 376.332912 -226.615212) (xy 376.344689 -226.567428) (xy 376.36398 -226.522152) (xy 376.390283 -226.480556)
			(xy 376.422918 -226.443719) (xy 376.461039 -226.412594) (xy 376.50366 -226.387987) (xy 376.549676 -226.370535)
			(xy 376.597895 -226.360691) (xy 376.64707 -226.35871) (xy 376.695925 -226.364642) (xy 376.743196 -226.378334)
			(xy 376.787658 -226.399432) (xy 376.828161 -226.427388) (xy 376.863654 -226.46148) (xy 376.893219 -226.500824)
			(xy 376.91609 -226.544401) (xy 376.931674 -226.591082) (xy 376.939569 -226.639659) (xy 376.940064 -226.664266)
			(xy 377.258575 -226.664266) (xy 377.26267 -226.613538) (xy 377.274849 -226.564124) (xy 377.294797 -226.517304)
			(xy 377.321998 -226.47429) (xy 377.355746 -226.436196) (xy 377.395168 -226.404009) (xy 377.439242 -226.378563)
			(xy 377.486828 -226.360516) (xy 377.536692 -226.350336) (xy 377.587544 -226.348287) (xy 377.638065 -226.354421)
			(xy 377.686949 -226.368581) (xy 377.732928 -226.390398) (xy 377.774812 -226.419308) (xy 377.811516 -226.454563)
			(xy 377.842089 -226.495249) (xy 377.86574 -226.540312) (xy 377.881856 -226.588586) (xy 377.89002 -226.63882)
			(xy 377.890532 -226.664266) (xy 378.20906 -226.664266) (xy 378.21302 -226.615212) (xy 378.224797 -226.567428)
			(xy 378.244088 -226.522152) (xy 378.270391 -226.480556) (xy 378.303026 -226.443719) (xy 378.341147 -226.412594)
			(xy 378.383768 -226.387987) (xy 378.429784 -226.370535) (xy 378.478003 -226.360691) (xy 378.527178 -226.35871)
			(xy 378.576033 -226.364642) (xy 378.623304 -226.378334) (xy 378.667766 -226.399432) (xy 378.708269 -226.427388)
			(xy 378.743762 -226.46148) (xy 378.773327 -226.500824) (xy 378.796198 -226.544401) (xy 378.811782 -226.591082)
			(xy 378.819677 -226.639659) (xy 378.820172 -226.664266) (xy 379.138683 -226.664266) (xy 379.142778 -226.613538)
			(xy 379.154957 -226.564124) (xy 379.174905 -226.517304) (xy 379.202106 -226.47429) (xy 379.235854 -226.436196)
			(xy 379.275276 -226.404009) (xy 379.31935 -226.378563) (xy 379.366936 -226.360516) (xy 379.4168 -226.350336)
			(xy 379.467652 -226.348287) (xy 379.518173 -226.354421) (xy 379.567057 -226.368581) (xy 379.613036 -226.390398)
			(xy 379.65492 -226.419308) (xy 379.691624 -226.454563) (xy 379.722197 -226.495249) (xy 379.745848 -226.540312)
			(xy 379.761964 -226.588586) (xy 379.770128 -226.63882) (xy 379.77064 -226.664266) (xy 380.078483 -226.664266)
			(xy 380.082578 -226.613538) (xy 380.094757 -226.564124) (xy 380.114705 -226.517304) (xy 380.141906 -226.47429)
			(xy 380.175654 -226.436196) (xy 380.215076 -226.404009) (xy 380.25915 -226.378563) (xy 380.306736 -226.360516)
			(xy 380.3566 -226.350336) (xy 380.407452 -226.348287) (xy 380.457973 -226.354421) (xy 380.506857 -226.368581)
			(xy 380.552836 -226.390398) (xy 380.59472 -226.419308) (xy 380.631424 -226.454563) (xy 380.661997 -226.495249)
			(xy 380.685648 -226.540312) (xy 380.701764 -226.588586) (xy 380.709928 -226.63882) (xy 380.71044 -226.664266)
			(xy 381.028968 -226.664266) (xy 381.032928 -226.615212) (xy 381.044705 -226.567428) (xy 381.063996 -226.522152)
			(xy 381.090299 -226.480556) (xy 381.122934 -226.443719) (xy 381.161055 -226.412594) (xy 381.203676 -226.387987)
			(xy 381.249692 -226.370535) (xy 381.297911 -226.360691) (xy 381.347086 -226.35871) (xy 381.395941 -226.364642)
			(xy 381.443212 -226.378334) (xy 381.487674 -226.399432) (xy 381.528177 -226.427388) (xy 381.56367 -226.46148)
			(xy 381.593235 -226.500824) (xy 381.616106 -226.544401) (xy 381.63169 -226.591082) (xy 381.639585 -226.639659)
			(xy 381.64008 -226.664266) (xy 381.969022 -226.664266) (xy 381.972982 -226.615212) (xy 381.984759 -226.567428)
			(xy 382.00405 -226.522152) (xy 382.030353 -226.480556) (xy 382.062988 -226.443719) (xy 382.101109 -226.412594)
			(xy 382.14373 -226.387987) (xy 382.189746 -226.370535) (xy 382.237965 -226.360691) (xy 382.28714 -226.35871)
			(xy 382.335995 -226.364642) (xy 382.383266 -226.378334) (xy 382.427728 -226.399432) (xy 382.468231 -226.427388)
			(xy 382.503724 -226.46148) (xy 382.533289 -226.500824) (xy 382.55616 -226.544401) (xy 382.571744 -226.591082)
			(xy 382.579639 -226.639659) (xy 382.580134 -226.664266) (xy 382.909076 -226.664266) (xy 382.913036 -226.615212)
			(xy 382.924813 -226.567428) (xy 382.944104 -226.522152) (xy 382.970407 -226.480556) (xy 383.003042 -226.443719)
			(xy 383.041163 -226.412594) (xy 383.083784 -226.387987) (xy 383.1298 -226.370535) (xy 383.178019 -226.360691)
			(xy 383.227194 -226.35871) (xy 383.276049 -226.364642) (xy 383.32332 -226.378334) (xy 383.367782 -226.399432)
			(xy 383.408285 -226.427388) (xy 383.443778 -226.46148) (xy 383.473343 -226.500824) (xy 383.496214 -226.544401)
			(xy 383.511798 -226.591082) (xy 383.519693 -226.639659) (xy 383.520188 -226.664266) (xy 383.84913 -226.664266)
			(xy 383.85309 -226.615212) (xy 383.864867 -226.567428) (xy 383.884158 -226.522152) (xy 383.910461 -226.480556)
			(xy 383.943096 -226.443719) (xy 383.981217 -226.412594) (xy 384.023838 -226.387987) (xy 384.069854 -226.370535)
			(xy 384.118073 -226.360691) (xy 384.167248 -226.35871) (xy 384.216103 -226.364642) (xy 384.263374 -226.378334)
			(xy 384.307836 -226.399432) (xy 384.348339 -226.427388) (xy 384.383832 -226.46148) (xy 384.413397 -226.500824)
			(xy 384.436268 -226.544401) (xy 384.451852 -226.591082) (xy 384.459747 -226.639659) (xy 384.460242 -226.664266)
			(xy 384.459747 -226.688873) (xy 384.451852 -226.73745) (xy 384.436268 -226.784131) (xy 384.413397 -226.827708)
			(xy 384.383832 -226.867052) (xy 384.348339 -226.901144) (xy 384.307836 -226.9291) (xy 384.263374 -226.950198)
			(xy 384.216103 -226.96389) (xy 384.167248 -226.969822) (xy 384.118073 -226.967841) (xy 384.069854 -226.957997)
			(xy 384.023838 -226.940545) (xy 383.981217 -226.915938) (xy 383.943096 -226.884813) (xy 383.910461 -226.847976)
			(xy 383.884158 -226.80638) (xy 383.864867 -226.761104) (xy 383.85309 -226.71332) (xy 383.84913 -226.664266)
			(xy 383.520188 -226.664266) (xy 383.519693 -226.688873) (xy 383.511798 -226.73745) (xy 383.496214 -226.784131)
			(xy 383.473343 -226.827708) (xy 383.443778 -226.867052) (xy 383.408285 -226.901144) (xy 383.367782 -226.9291)
			(xy 383.32332 -226.950198) (xy 383.276049 -226.96389) (xy 383.227194 -226.969822) (xy 383.178019 -226.967841)
			(xy 383.1298 -226.957997) (xy 383.083784 -226.940545) (xy 383.041163 -226.915938) (xy 383.003042 -226.884813)
			(xy 382.970407 -226.847976) (xy 382.944104 -226.80638) (xy 382.924813 -226.761104) (xy 382.913036 -226.71332)
			(xy 382.909076 -226.664266) (xy 382.580134 -226.664266) (xy 382.579639 -226.688873) (xy 382.571744 -226.73745)
			(xy 382.55616 -226.784131) (xy 382.533289 -226.827708) (xy 382.503724 -226.867052) (xy 382.468231 -226.901144)
			(xy 382.427728 -226.9291) (xy 382.383266 -226.950198) (xy 382.335995 -226.96389) (xy 382.28714 -226.969822)
			(xy 382.237965 -226.967841) (xy 382.189746 -226.957997) (xy 382.14373 -226.940545) (xy 382.101109 -226.915938)
			(xy 382.062988 -226.884813) (xy 382.030353 -226.847976) (xy 382.00405 -226.80638) (xy 381.984759 -226.761104)
			(xy 381.972982 -226.71332) (xy 381.969022 -226.664266) (xy 381.64008 -226.664266) (xy 381.639585 -226.688873)
			(xy 381.63169 -226.73745) (xy 381.616106 -226.784131) (xy 381.593235 -226.827708) (xy 381.56367 -226.867052)
			(xy 381.528177 -226.901144) (xy 381.487674 -226.9291) (xy 381.443212 -226.950198) (xy 381.395941 -226.96389)
			(xy 381.347086 -226.969822) (xy 381.297911 -226.967841) (xy 381.249692 -226.957997) (xy 381.203676 -226.940545)
			(xy 381.161055 -226.915938) (xy 381.122934 -226.884813) (xy 381.090299 -226.847976) (xy 381.063996 -226.80638)
			(xy 381.044705 -226.761104) (xy 381.032928 -226.71332) (xy 381.028968 -226.664266) (xy 380.71044 -226.664266)
			(xy 380.709928 -226.689712) (xy 380.701764 -226.739946) (xy 380.685648 -226.78822) (xy 380.661997 -226.833283)
			(xy 380.631424 -226.873969) (xy 380.59472 -226.909224) (xy 380.552836 -226.938134) (xy 380.506857 -226.959951)
			(xy 380.457973 -226.974111) (xy 380.407452 -226.980245) (xy 380.3566 -226.978196) (xy 380.306736 -226.968016)
			(xy 380.25915 -226.949969) (xy 380.215076 -226.924523) (xy 380.175654 -226.892336) (xy 380.141906 -226.854242)
			(xy 380.114705 -226.811228) (xy 380.094757 -226.764408) (xy 380.082578 -226.714994) (xy 380.078483 -226.664266)
			(xy 379.77064 -226.664266) (xy 379.770128 -226.689712) (xy 379.761964 -226.739946) (xy 379.745848 -226.78822)
			(xy 379.722197 -226.833283) (xy 379.691624 -226.873969) (xy 379.65492 -226.909224) (xy 379.613036 -226.938134)
			(xy 379.567057 -226.959951) (xy 379.518173 -226.974111) (xy 379.467652 -226.980245) (xy 379.4168 -226.978196)
			(xy 379.366936 -226.968016) (xy 379.31935 -226.949969) (xy 379.275276 -226.924523) (xy 379.235854 -226.892336)
			(xy 379.202106 -226.854242) (xy 379.174905 -226.811228) (xy 379.154957 -226.764408) (xy 379.142778 -226.714994)
			(xy 379.138683 -226.664266) (xy 378.820172 -226.664266) (xy 378.819677 -226.688873) (xy 378.811782 -226.73745)
			(xy 378.796198 -226.784131) (xy 378.773327 -226.827708) (xy 378.743762 -226.867052) (xy 378.708269 -226.901144)
			(xy 378.667766 -226.9291) (xy 378.623304 -226.950198) (xy 378.576033 -226.96389) (xy 378.527178 -226.969822)
			(xy 378.478003 -226.967841) (xy 378.429784 -226.957997) (xy 378.383768 -226.940545) (xy 378.341147 -226.915938)
			(xy 378.303026 -226.884813) (xy 378.270391 -226.847976) (xy 378.244088 -226.80638) (xy 378.224797 -226.761104)
			(xy 378.21302 -226.71332) (xy 378.20906 -226.664266) (xy 377.890532 -226.664266) (xy 377.89002 -226.689712)
			(xy 377.881856 -226.739946) (xy 377.86574 -226.78822) (xy 377.842089 -226.833283) (xy 377.811516 -226.873969)
			(xy 377.774812 -226.909224) (xy 377.732928 -226.938134) (xy 377.686949 -226.959951) (xy 377.638065 -226.974111)
			(xy 377.587544 -226.980245) (xy 377.536692 -226.978196) (xy 377.486828 -226.968016) (xy 377.439242 -226.949969)
			(xy 377.395168 -226.924523) (xy 377.355746 -226.892336) (xy 377.321998 -226.854242) (xy 377.294797 -226.811228)
			(xy 377.274849 -226.764408) (xy 377.26267 -226.714994) (xy 377.258575 -226.664266) (xy 376.940064 -226.664266)
			(xy 376.939569 -226.688873) (xy 376.931674 -226.73745) (xy 376.91609 -226.784131) (xy 376.893219 -226.827708)
			(xy 376.863654 -226.867052) (xy 376.828161 -226.901144) (xy 376.787658 -226.9291) (xy 376.743196 -226.950198)
			(xy 376.695925 -226.96389) (xy 376.64707 -226.969822) (xy 376.597895 -226.967841) (xy 376.549676 -226.957997)
			(xy 376.50366 -226.940545) (xy 376.461039 -226.915938) (xy 376.422918 -226.884813) (xy 376.390283 -226.847976)
			(xy 376.36398 -226.80638) (xy 376.344689 -226.761104) (xy 376.332912 -226.71332) (xy 376.328952 -226.664266)
			(xy 376.010998 -226.664266) (xy 376.010999 -226.664282) (xy 376.007111 -226.71372) (xy 375.995536 -226.76194)
			(xy 375.976559 -226.807756) (xy 375.950649 -226.850039) (xy 375.918442 -226.887748) (xy 375.880733 -226.919953)
			(xy 375.859802 -226.933252) (xy 375.85056 -226.93967) (xy 375.838301 -226.958506) (xy 375.835197 -226.980764)
			(xy 375.837958 -226.991672) (xy 375.848879 -227.027598) (xy 375.867808 -227.100272) (xy 375.875804 -227.13696)
			(xy 375.875804 -227.137468) (xy 375.878847 -227.148869) (xy 375.893551 -227.167287) (xy 375.903998 -227.172774)
			(xy 375.975372 -227.206048) (xy 375.999756 -227.205032) (xy 376.010424 -227.198936) (xy 376.034174 -227.186287)
			(xy 376.084913 -227.168379) (xy 376.137952 -227.159324) (xy 376.164856 -227.158804) (xy 376.189652 -227.159262)
			(xy 376.238634 -227.167014) (xy 376.285801 -227.182333) (xy 376.32999 -227.204843) (xy 376.370113 -227.233989)
			(xy 376.405182 -227.269053) (xy 376.434334 -227.309173) (xy 376.45685 -227.353358) (xy 376.472176 -227.400523)
			(xy 376.479935 -227.449504) (xy 376.479935 -227.474272) (xy 376.788675 -227.474272) (xy 376.79277 -227.423544)
			(xy 376.804949 -227.37413) (xy 376.824897 -227.32731) (xy 376.852098 -227.284296) (xy 376.885846 -227.246202)
			(xy 376.925268 -227.214015) (xy 376.969342 -227.188569) (xy 377.016928 -227.170522) (xy 377.066792 -227.160342)
			(xy 377.117644 -227.158293) (xy 377.168165 -227.164427) (xy 377.217049 -227.178587) (xy 377.263028 -227.200404)
			(xy 377.304912 -227.229314) (xy 377.341616 -227.264569) (xy 377.372189 -227.305255) (xy 377.39584 -227.350318)
			(xy 377.411956 -227.398592) (xy 377.42012 -227.448826) (xy 377.420632 -227.474272) (xy 378.668529 -227.474272)
			(xy 378.672624 -227.423544) (xy 378.684803 -227.37413) (xy 378.704751 -227.32731) (xy 378.731952 -227.284296)
			(xy 378.7657 -227.246202) (xy 378.805122 -227.214015) (xy 378.849196 -227.188569) (xy 378.896782 -227.170522)
			(xy 378.946646 -227.160342) (xy 378.997498 -227.158293) (xy 379.048019 -227.164427) (xy 379.096903 -227.178587)
			(xy 379.142882 -227.200404) (xy 379.184766 -227.229314) (xy 379.22147 -227.264569) (xy 379.252043 -227.305255)
			(xy 379.275694 -227.350318) (xy 379.29181 -227.398592) (xy 379.299974 -227.448826) (xy 379.300486 -227.474272)
			(xy 379.619014 -227.474272) (xy 379.622974 -227.425218) (xy 379.634751 -227.377434) (xy 379.654042 -227.332158)
			(xy 379.680345 -227.290562) (xy 379.71298 -227.253725) (xy 379.751101 -227.2226) (xy 379.793722 -227.197993)
			(xy 379.839738 -227.180541) (xy 379.887957 -227.170697) (xy 379.937132 -227.168716) (xy 379.985987 -227.174648)
			(xy 380.033258 -227.18834) (xy 380.07772 -227.209438) (xy 380.118223 -227.237394) (xy 380.153716 -227.271486)
			(xy 380.183281 -227.31083) (xy 380.206152 -227.354407) (xy 380.221736 -227.401088) (xy 380.229631 -227.449665)
			(xy 380.230126 -227.474272) (xy 380.548637 -227.474272) (xy 380.552732 -227.423544) (xy 380.564911 -227.37413)
			(xy 380.584859 -227.32731) (xy 380.61206 -227.284296) (xy 380.645808 -227.246202) (xy 380.68523 -227.214015)
			(xy 380.729304 -227.188569) (xy 380.77689 -227.170522) (xy 380.826754 -227.160342) (xy 380.877606 -227.158293)
			(xy 380.928127 -227.164427) (xy 380.977011 -227.178587) (xy 381.02299 -227.200404) (xy 381.064874 -227.229314)
			(xy 381.101578 -227.264569) (xy 381.132151 -227.305255) (xy 381.155802 -227.350318) (xy 381.171918 -227.398592)
			(xy 381.180082 -227.448826) (xy 381.180594 -227.474272) (xy 381.499122 -227.474272) (xy 381.503082 -227.425218)
			(xy 381.514859 -227.377434) (xy 381.53415 -227.332158) (xy 381.560453 -227.290562) (xy 381.593088 -227.253725)
			(xy 381.631209 -227.2226) (xy 381.67383 -227.197993) (xy 381.719846 -227.180541) (xy 381.768065 -227.170697)
			(xy 381.81724 -227.168716) (xy 381.866095 -227.174648) (xy 381.913366 -227.18834) (xy 381.957828 -227.209438)
			(xy 381.998331 -227.237394) (xy 382.033824 -227.271486) (xy 382.063389 -227.31083) (xy 382.08626 -227.354407)
			(xy 382.101844 -227.401088) (xy 382.109739 -227.449665) (xy 382.110234 -227.474272) (xy 382.438922 -227.474272)
			(xy 382.442882 -227.425218) (xy 382.454659 -227.377434) (xy 382.47395 -227.332158) (xy 382.500253 -227.290562)
			(xy 382.532888 -227.253725) (xy 382.571009 -227.2226) (xy 382.61363 -227.197993) (xy 382.659646 -227.180541)
			(xy 382.707865 -227.170697) (xy 382.75704 -227.168716) (xy 382.805895 -227.174648) (xy 382.853166 -227.18834)
			(xy 382.897628 -227.209438) (xy 382.938131 -227.237394) (xy 382.973624 -227.271486) (xy 383.003189 -227.31083)
			(xy 383.02606 -227.354407) (xy 383.041644 -227.401088) (xy 383.049539 -227.449665) (xy 383.050034 -227.474272)
			(xy 383.378976 -227.474272) (xy 383.382936 -227.425218) (xy 383.394713 -227.377434) (xy 383.414004 -227.332158)
			(xy 383.440307 -227.290562) (xy 383.472942 -227.253725) (xy 383.511063 -227.2226) (xy 383.553684 -227.197993)
			(xy 383.5997 -227.180541) (xy 383.647919 -227.170697) (xy 383.697094 -227.168716) (xy 383.745949 -227.174648)
			(xy 383.79322 -227.18834) (xy 383.837682 -227.209438) (xy 383.878185 -227.237394) (xy 383.913678 -227.271486)
			(xy 383.943243 -227.31083) (xy 383.966114 -227.354407) (xy 383.981698 -227.401088) (xy 383.989593 -227.449665)
			(xy 383.990088 -227.474272) (xy 383.989593 -227.498879) (xy 383.981698 -227.547456) (xy 383.966114 -227.594137)
			(xy 383.943243 -227.637714) (xy 383.913678 -227.677058) (xy 383.878185 -227.71115) (xy 383.837682 -227.739106)
			(xy 383.79322 -227.760204) (xy 383.745949 -227.773896) (xy 383.697094 -227.779828) (xy 383.647919 -227.777847)
			(xy 383.5997 -227.768003) (xy 383.553684 -227.750551) (xy 383.511063 -227.725944) (xy 383.472942 -227.694819)
			(xy 383.440307 -227.657982) (xy 383.414004 -227.616386) (xy 383.394713 -227.57111) (xy 383.382936 -227.523326)
			(xy 383.378976 -227.474272) (xy 383.050034 -227.474272) (xy 383.049539 -227.498879) (xy 383.041644 -227.547456)
			(xy 383.02606 -227.594137) (xy 383.003189 -227.637714) (xy 382.973624 -227.677058) (xy 382.938131 -227.71115)
			(xy 382.897628 -227.739106) (xy 382.853166 -227.760204) (xy 382.805895 -227.773896) (xy 382.75704 -227.779828)
			(xy 382.707865 -227.777847) (xy 382.659646 -227.768003) (xy 382.61363 -227.750551) (xy 382.571009 -227.725944)
			(xy 382.532888 -227.694819) (xy 382.500253 -227.657982) (xy 382.47395 -227.616386) (xy 382.454659 -227.57111)
			(xy 382.442882 -227.523326) (xy 382.438922 -227.474272) (xy 382.110234 -227.474272) (xy 382.109739 -227.498879)
			(xy 382.101844 -227.547456) (xy 382.08626 -227.594137) (xy 382.063389 -227.637714) (xy 382.033824 -227.677058)
			(xy 381.998331 -227.71115) (xy 381.957828 -227.739106) (xy 381.913366 -227.760204) (xy 381.866095 -227.773896)
			(xy 381.81724 -227.779828) (xy 381.768065 -227.777847) (xy 381.719846 -227.768003) (xy 381.67383 -227.750551)
			(xy 381.631209 -227.725944) (xy 381.593088 -227.694819) (xy 381.560453 -227.657982) (xy 381.53415 -227.616386)
			(xy 381.514859 -227.57111) (xy 381.503082 -227.523326) (xy 381.499122 -227.474272) (xy 381.180594 -227.474272)
			(xy 381.180082 -227.499718) (xy 381.171918 -227.549952) (xy 381.155802 -227.598226) (xy 381.132151 -227.643289)
			(xy 381.101578 -227.683975) (xy 381.064874 -227.71923) (xy 381.02299 -227.74814) (xy 380.977011 -227.769957)
			(xy 380.928127 -227.784117) (xy 380.877606 -227.790251) (xy 380.826754 -227.788202) (xy 380.77689 -227.778022)
			(xy 380.729304 -227.759975) (xy 380.68523 -227.734529) (xy 380.645808 -227.702342) (xy 380.61206 -227.664248)
			(xy 380.584859 -227.621234) (xy 380.564911 -227.574414) (xy 380.552732 -227.525) (xy 380.548637 -227.474272)
			(xy 380.230126 -227.474272) (xy 380.229631 -227.498879) (xy 380.221736 -227.547456) (xy 380.206152 -227.594137)
			(xy 380.183281 -227.637714) (xy 380.153716 -227.677058) (xy 380.118223 -227.71115) (xy 380.07772 -227.739106)
			(xy 380.033258 -227.760204) (xy 379.985987 -227.773896) (xy 379.937132 -227.779828) (xy 379.887957 -227.777847)
			(xy 379.839738 -227.768003) (xy 379.793722 -227.750551) (xy 379.751101 -227.725944) (xy 379.71298 -227.694819)
			(xy 379.680345 -227.657982) (xy 379.654042 -227.616386) (xy 379.634751 -227.57111) (xy 379.622974 -227.523326)
			(xy 379.619014 -227.474272) (xy 379.300486 -227.474272) (xy 379.299974 -227.499718) (xy 379.29181 -227.549952)
			(xy 379.275694 -227.598226) (xy 379.252043 -227.643289) (xy 379.22147 -227.683975) (xy 379.184766 -227.71923)
			(xy 379.142882 -227.74814) (xy 379.096903 -227.769957) (xy 379.048019 -227.784117) (xy 378.997498 -227.790251)
			(xy 378.946646 -227.788202) (xy 378.896782 -227.778022) (xy 378.849196 -227.759975) (xy 378.805122 -227.734529)
			(xy 378.7657 -227.702342) (xy 378.731952 -227.664248) (xy 378.704751 -227.621234) (xy 378.684803 -227.574414)
			(xy 378.672624 -227.525) (xy 378.668529 -227.474272) (xy 377.420632 -227.474272) (xy 377.42012 -227.499718)
			(xy 377.411956 -227.549952) (xy 377.39584 -227.598226) (xy 377.372189 -227.643289) (xy 377.341616 -227.683975)
			(xy 377.304912 -227.71923) (xy 377.263028 -227.74814) (xy 377.217049 -227.769957) (xy 377.168165 -227.784117)
			(xy 377.117644 -227.790251) (xy 377.066792 -227.788202) (xy 377.016928 -227.778022) (xy 376.969342 -227.759975)
			(xy 376.925268 -227.734529) (xy 376.885846 -227.702342) (xy 376.852098 -227.664248) (xy 376.824897 -227.621234)
			(xy 376.804949 -227.574414) (xy 376.79277 -227.525) (xy 376.788675 -227.474272) (xy 376.479935 -227.474272)
			(xy 376.479935 -227.499096) (xy 376.472176 -227.548077) (xy 376.45685 -227.595242) (xy 376.434334 -227.639427)
			(xy 376.405182 -227.679547) (xy 376.370113 -227.714611) (xy 376.32999 -227.743757) (xy 376.285801 -227.766267)
			(xy 376.238634 -227.781586) (xy 376.189652 -227.789338) (xy 376.164856 -227.78974) (xy 376.13795 -227.78924)
			(xy 376.084906 -227.780194) (xy 376.03417 -227.762269) (xy 376.010424 -227.749608) (xy 375.999756 -227.743512)
			(xy 375.975372 -227.742496) (xy 375.903998 -227.77577) (xy 375.893614 -227.781327) (xy 375.878945 -227.799723)
			(xy 375.875804 -227.811076) (xy 375.875804 -227.811584) (xy 375.867821 -227.848275) (xy 375.84889 -227.920949)
			(xy 375.837958 -227.956872) (xy 375.835144 -227.967779) (xy 375.838214 -227.990065) (xy 375.850534 -228.008888)
			(xy 375.859802 -228.015292) (xy 375.880703 -228.028638) (xy 375.918414 -228.060839) (xy 375.950623 -228.098543)
			(xy 375.976537 -228.140822) (xy 375.995517 -228.186635) (xy 376.007096 -228.234853) (xy 376.010988 -228.284278)
			(xy 376.328952 -228.284278) (xy 376.332912 -228.235224) (xy 376.344689 -228.18744) (xy 376.36398 -228.142164)
			(xy 376.390283 -228.100568) (xy 376.422918 -228.063731) (xy 376.461039 -228.032606) (xy 376.50366 -228.007999)
			(xy 376.549676 -227.990547) (xy 376.597895 -227.980703) (xy 376.64707 -227.978722) (xy 376.695925 -227.984654)
			(xy 376.743196 -227.998346) (xy 376.787658 -228.019444) (xy 376.828161 -228.0474) (xy 376.863654 -228.081492)
			(xy 376.893219 -228.120836) (xy 376.91609 -228.164413) (xy 376.931674 -228.211094) (xy 376.939569 -228.259671)
			(xy 376.940064 -228.284278) (xy 377.258575 -228.284278) (xy 377.26267 -228.23355) (xy 377.274849 -228.184136)
			(xy 377.294797 -228.137316) (xy 377.321998 -228.094302) (xy 377.355746 -228.056208) (xy 377.395168 -228.024021)
			(xy 377.439242 -227.998575) (xy 377.486828 -227.980528) (xy 377.536692 -227.970348) (xy 377.587544 -227.968299)
			(xy 377.638065 -227.974433) (xy 377.686949 -227.988593) (xy 377.732928 -228.01041) (xy 377.774812 -228.03932)
			(xy 377.811516 -228.074575) (xy 377.842089 -228.115261) (xy 377.86574 -228.160324) (xy 377.881856 -228.208598)
			(xy 377.89002 -228.258832) (xy 377.890532 -228.284278) (xy 378.20906 -228.284278) (xy 378.21302 -228.235224)
			(xy 378.224797 -228.18744) (xy 378.244088 -228.142164) (xy 378.270391 -228.100568) (xy 378.303026 -228.063731)
			(xy 378.341147 -228.032606) (xy 378.383768 -228.007999) (xy 378.429784 -227.990547) (xy 378.478003 -227.980703)
			(xy 378.527178 -227.978722) (xy 378.576033 -227.984654) (xy 378.623304 -227.998346) (xy 378.667766 -228.019444)
			(xy 378.708269 -228.0474) (xy 378.743762 -228.081492) (xy 378.773327 -228.120836) (xy 378.796198 -228.164413)
			(xy 378.811782 -228.211094) (xy 378.819677 -228.259671) (xy 378.820172 -228.284278) (xy 379.138683 -228.284278)
			(xy 379.142778 -228.23355) (xy 379.154957 -228.184136) (xy 379.174905 -228.137316) (xy 379.202106 -228.094302)
			(xy 379.235854 -228.056208) (xy 379.275276 -228.024021) (xy 379.31935 -227.998575) (xy 379.366936 -227.980528)
			(xy 379.4168 -227.970348) (xy 379.467652 -227.968299) (xy 379.518173 -227.974433) (xy 379.567057 -227.988593)
			(xy 379.613036 -228.01041) (xy 379.65492 -228.03932) (xy 379.691624 -228.074575) (xy 379.722197 -228.115261)
			(xy 379.745848 -228.160324) (xy 379.761964 -228.208598) (xy 379.770128 -228.258832) (xy 379.77064 -228.284278)
			(xy 380.078483 -228.284278) (xy 380.082578 -228.23355) (xy 380.094757 -228.184136) (xy 380.114705 -228.137316)
			(xy 380.141906 -228.094302) (xy 380.175654 -228.056208) (xy 380.215076 -228.024021) (xy 380.25915 -227.998575)
			(xy 380.306736 -227.980528) (xy 380.3566 -227.970348) (xy 380.407452 -227.968299) (xy 380.457973 -227.974433)
			(xy 380.506857 -227.988593) (xy 380.552836 -228.01041) (xy 380.59472 -228.03932) (xy 380.631424 -228.074575)
			(xy 380.661997 -228.115261) (xy 380.685648 -228.160324) (xy 380.701764 -228.208598) (xy 380.709928 -228.258832)
			(xy 380.71044 -228.284278) (xy 381.028968 -228.284278) (xy 381.032928 -228.235224) (xy 381.044705 -228.18744)
			(xy 381.063996 -228.142164) (xy 381.090299 -228.100568) (xy 381.122934 -228.063731) (xy 381.161055 -228.032606)
			(xy 381.203676 -228.007999) (xy 381.249692 -227.990547) (xy 381.297911 -227.980703) (xy 381.347086 -227.978722)
			(xy 381.395941 -227.984654) (xy 381.443212 -227.998346) (xy 381.487674 -228.019444) (xy 381.528177 -228.0474)
			(xy 381.56367 -228.081492) (xy 381.593235 -228.120836) (xy 381.616106 -228.164413) (xy 381.63169 -228.211094)
			(xy 381.639585 -228.259671) (xy 381.64008 -228.284278) (xy 381.969022 -228.284278) (xy 381.972982 -228.235224)
			(xy 381.984759 -228.18744) (xy 382.00405 -228.142164) (xy 382.030353 -228.100568) (xy 382.062988 -228.063731)
			(xy 382.101109 -228.032606) (xy 382.14373 -228.007999) (xy 382.189746 -227.990547) (xy 382.237965 -227.980703)
			(xy 382.28714 -227.978722) (xy 382.335995 -227.984654) (xy 382.383266 -227.998346) (xy 382.427728 -228.019444)
			(xy 382.468231 -228.0474) (xy 382.503724 -228.081492) (xy 382.533289 -228.120836) (xy 382.55616 -228.164413)
			(xy 382.571744 -228.211094) (xy 382.579639 -228.259671) (xy 382.580134 -228.284278) (xy 382.909076 -228.284278)
			(xy 382.913036 -228.235224) (xy 382.924813 -228.18744) (xy 382.944104 -228.142164) (xy 382.970407 -228.100568)
			(xy 383.003042 -228.063731) (xy 383.041163 -228.032606) (xy 383.083784 -228.007999) (xy 383.1298 -227.990547)
			(xy 383.178019 -227.980703) (xy 383.227194 -227.978722) (xy 383.276049 -227.984654) (xy 383.32332 -227.998346)
			(xy 383.367782 -228.019444) (xy 383.408285 -228.0474) (xy 383.443778 -228.081492) (xy 383.473343 -228.120836)
			(xy 383.496214 -228.164413) (xy 383.511798 -228.211094) (xy 383.519693 -228.259671) (xy 383.520188 -228.284278)
			(xy 383.84913 -228.284278) (xy 383.85309 -228.235224) (xy 383.864867 -228.18744) (xy 383.884158 -228.142164)
			(xy 383.910461 -228.100568) (xy 383.943096 -228.063731) (xy 383.981217 -228.032606) (xy 384.023838 -228.007999)
			(xy 384.069854 -227.990547) (xy 384.118073 -227.980703) (xy 384.167248 -227.978722) (xy 384.216103 -227.984654)
			(xy 384.263374 -227.998346) (xy 384.307836 -228.019444) (xy 384.348339 -228.0474) (xy 384.383832 -228.081492)
			(xy 384.413397 -228.120836) (xy 384.436268 -228.164413) (xy 384.451852 -228.211094) (xy 384.459747 -228.259671)
			(xy 384.460242 -228.284278) (xy 384.459747 -228.308885) (xy 384.451852 -228.357462) (xy 384.436268 -228.404143)
			(xy 384.413397 -228.44772) (xy 384.383832 -228.487064) (xy 384.348339 -228.521156) (xy 384.307836 -228.549112)
			(xy 384.263374 -228.57021) (xy 384.216103 -228.583902) (xy 384.167248 -228.589834) (xy 384.118073 -228.587853)
			(xy 384.069854 -228.578009) (xy 384.023838 -228.560557) (xy 383.981217 -228.53595) (xy 383.943096 -228.504825)
			(xy 383.910461 -228.467988) (xy 383.884158 -228.426392) (xy 383.864867 -228.381116) (xy 383.85309 -228.333332)
			(xy 383.84913 -228.284278) (xy 383.520188 -228.284278) (xy 383.519693 -228.308885) (xy 383.511798 -228.357462)
			(xy 383.496214 -228.404143) (xy 383.473343 -228.44772) (xy 383.443778 -228.487064) (xy 383.408285 -228.521156)
			(xy 383.367782 -228.549112) (xy 383.32332 -228.57021) (xy 383.276049 -228.583902) (xy 383.227194 -228.589834)
			(xy 383.178019 -228.587853) (xy 383.1298 -228.578009) (xy 383.083784 -228.560557) (xy 383.041163 -228.53595)
			(xy 383.003042 -228.504825) (xy 382.970407 -228.467988) (xy 382.944104 -228.426392) (xy 382.924813 -228.381116)
			(xy 382.913036 -228.333332) (xy 382.909076 -228.284278) (xy 382.580134 -228.284278) (xy 382.579639 -228.308885)
			(xy 382.571744 -228.357462) (xy 382.55616 -228.404143) (xy 382.533289 -228.44772) (xy 382.503724 -228.487064)
			(xy 382.468231 -228.521156) (xy 382.427728 -228.549112) (xy 382.383266 -228.57021) (xy 382.335995 -228.583902)
			(xy 382.28714 -228.589834) (xy 382.237965 -228.587853) (xy 382.189746 -228.578009) (xy 382.14373 -228.560557)
			(xy 382.101109 -228.53595) (xy 382.062988 -228.504825) (xy 382.030353 -228.467988) (xy 382.00405 -228.426392)
			(xy 381.984759 -228.381116) (xy 381.972982 -228.333332) (xy 381.969022 -228.284278) (xy 381.64008 -228.284278)
			(xy 381.639585 -228.308885) (xy 381.63169 -228.357462) (xy 381.616106 -228.404143) (xy 381.593235 -228.44772)
			(xy 381.56367 -228.487064) (xy 381.528177 -228.521156) (xy 381.487674 -228.549112) (xy 381.443212 -228.57021)
			(xy 381.395941 -228.583902) (xy 381.347086 -228.589834) (xy 381.297911 -228.587853) (xy 381.249692 -228.578009)
			(xy 381.203676 -228.560557) (xy 381.161055 -228.53595) (xy 381.122934 -228.504825) (xy 381.090299 -228.467988)
			(xy 381.063996 -228.426392) (xy 381.044705 -228.381116) (xy 381.032928 -228.333332) (xy 381.028968 -228.284278)
			(xy 380.71044 -228.284278) (xy 380.709928 -228.309724) (xy 380.701764 -228.359958) (xy 380.685648 -228.408232)
			(xy 380.661997 -228.453295) (xy 380.631424 -228.493981) (xy 380.59472 -228.529236) (xy 380.552836 -228.558146)
			(xy 380.506857 -228.579963) (xy 380.457973 -228.594123) (xy 380.407452 -228.600257) (xy 380.3566 -228.598208)
			(xy 380.306736 -228.588028) (xy 380.25915 -228.569981) (xy 380.215076 -228.544535) (xy 380.175654 -228.512348)
			(xy 380.141906 -228.474254) (xy 380.114705 -228.43124) (xy 380.094757 -228.38442) (xy 380.082578 -228.335006)
			(xy 380.078483 -228.284278) (xy 379.77064 -228.284278) (xy 379.770128 -228.309724) (xy 379.761964 -228.359958)
			(xy 379.745848 -228.408232) (xy 379.722197 -228.453295) (xy 379.691624 -228.493981) (xy 379.65492 -228.529236)
			(xy 379.613036 -228.558146) (xy 379.567057 -228.579963) (xy 379.518173 -228.594123) (xy 379.467652 -228.600257)
			(xy 379.4168 -228.598208) (xy 379.366936 -228.588028) (xy 379.31935 -228.569981) (xy 379.275276 -228.544535)
			(xy 379.235854 -228.512348) (xy 379.202106 -228.474254) (xy 379.174905 -228.43124) (xy 379.154957 -228.38442)
			(xy 379.142778 -228.335006) (xy 379.138683 -228.284278) (xy 378.820172 -228.284278) (xy 378.819677 -228.308885)
			(xy 378.811782 -228.357462) (xy 378.796198 -228.404143) (xy 378.773327 -228.44772) (xy 378.743762 -228.487064)
			(xy 378.708269 -228.521156) (xy 378.667766 -228.549112) (xy 378.623304 -228.57021) (xy 378.576033 -228.583902)
			(xy 378.527178 -228.589834) (xy 378.478003 -228.587853) (xy 378.429784 -228.578009) (xy 378.383768 -228.560557)
			(xy 378.341147 -228.53595) (xy 378.303026 -228.504825) (xy 378.270391 -228.467988) (xy 378.244088 -228.426392)
			(xy 378.224797 -228.381116) (xy 378.21302 -228.333332) (xy 378.20906 -228.284278) (xy 377.890532 -228.284278)
			(xy 377.89002 -228.309724) (xy 377.881856 -228.359958) (xy 377.86574 -228.408232) (xy 377.842089 -228.453295)
			(xy 377.811516 -228.493981) (xy 377.774812 -228.529236) (xy 377.732928 -228.558146) (xy 377.686949 -228.579963)
			(xy 377.638065 -228.594123) (xy 377.587544 -228.600257) (xy 377.536692 -228.598208) (xy 377.486828 -228.588028)
			(xy 377.439242 -228.569981) (xy 377.395168 -228.544535) (xy 377.355746 -228.512348) (xy 377.321998 -228.474254)
			(xy 377.294797 -228.43124) (xy 377.274849 -228.38442) (xy 377.26267 -228.335006) (xy 377.258575 -228.284278)
			(xy 376.940064 -228.284278) (xy 376.939569 -228.308885) (xy 376.931674 -228.357462) (xy 376.91609 -228.404143)
			(xy 376.893219 -228.44772) (xy 376.863654 -228.487064) (xy 376.828161 -228.521156) (xy 376.787658 -228.549112)
			(xy 376.743196 -228.57021) (xy 376.695925 -228.583902) (xy 376.64707 -228.589834) (xy 376.597895 -228.587853)
			(xy 376.549676 -228.578009) (xy 376.50366 -228.560557) (xy 376.461039 -228.53595) (xy 376.422918 -228.504825)
			(xy 376.390283 -228.467988) (xy 376.36398 -228.426392) (xy 376.344689 -228.381116) (xy 376.332912 -228.333332)
			(xy 376.328952 -228.284278) (xy 376.010988 -228.284278) (xy 376.010989 -228.284288) (xy 376.0071 -228.333724)
			(xy 375.995524 -228.381943) (xy 375.976547 -228.427757) (xy 375.950637 -228.470038) (xy 375.918431 -228.507745)
			(xy 375.880722 -228.539949) (xy 375.859802 -228.553264) (xy 375.850562 -228.559682) (xy 375.838307 -228.578518)
			(xy 375.835208 -228.600774) (xy 375.837958 -228.611684) (xy 375.848881 -228.64761) (xy 375.867813 -228.720282)
			(xy 375.875804 -228.756972) (xy 375.875804 -228.75748) (xy 375.878849 -228.768879) (xy 375.893555 -228.787293)
			(xy 375.903998 -228.792786) (xy 375.975372 -228.82606) (xy 375.999756 -228.825044) (xy 376.010424 -228.818948)
			(xy 376.034174 -228.806299) (xy 376.084913 -228.78839) (xy 376.137952 -228.779334) (xy 376.164856 -228.778816)
			(xy 376.189651 -228.779274) (xy 376.238632 -228.787025) (xy 376.285796 -228.802344) (xy 376.329984 -228.824853)
			(xy 376.370105 -228.853998) (xy 376.405173 -228.889061) (xy 376.434324 -228.929179) (xy 376.456839 -228.973363)
			(xy 376.472164 -229.020526) (xy 376.479923 -229.069505) (xy 376.479923 -229.094284) (xy 376.788675 -229.094284)
			(xy 376.79277 -229.043556) (xy 376.804949 -228.994142) (xy 376.824897 -228.947322) (xy 376.852098 -228.904308)
			(xy 376.885846 -228.866214) (xy 376.925268 -228.834027) (xy 376.969342 -228.808581) (xy 377.016928 -228.790534)
			(xy 377.066792 -228.780354) (xy 377.117644 -228.778305) (xy 377.168165 -228.784439) (xy 377.217049 -228.798599)
			(xy 377.263028 -228.820416) (xy 377.304912 -228.849326) (xy 377.341616 -228.884581) (xy 377.372189 -228.925267)
			(xy 377.39584 -228.97033) (xy 377.411956 -229.018604) (xy 377.42012 -229.068838) (xy 377.420632 -229.094284)
			(xy 377.738906 -229.094284) (xy 377.742866 -229.04523) (xy 377.754643 -228.997446) (xy 377.773934 -228.95217)
			(xy 377.800237 -228.910574) (xy 377.832872 -228.873737) (xy 377.870993 -228.842612) (xy 377.913614 -228.818005)
			(xy 377.95963 -228.800553) (xy 378.007849 -228.790709) (xy 378.057024 -228.788728) (xy 378.105879 -228.79466)
			(xy 378.15315 -228.808352) (xy 378.197612 -228.82945) (xy 378.238115 -228.857406) (xy 378.273608 -228.891498)
			(xy 378.303173 -228.930842) (xy 378.326044 -228.974419) (xy 378.341628 -229.0211) (xy 378.349523 -229.069677)
			(xy 378.350018 -229.094284) (xy 378.668529 -229.094284) (xy 378.672624 -229.043556) (xy 378.684803 -228.994142)
			(xy 378.704751 -228.947322) (xy 378.731952 -228.904308) (xy 378.7657 -228.866214) (xy 378.805122 -228.834027)
			(xy 378.849196 -228.808581) (xy 378.896782 -228.790534) (xy 378.946646 -228.780354) (xy 378.997498 -228.778305)
			(xy 379.048019 -228.784439) (xy 379.096903 -228.798599) (xy 379.142882 -228.820416) (xy 379.184766 -228.849326)
			(xy 379.22147 -228.884581) (xy 379.252043 -228.925267) (xy 379.275694 -228.97033) (xy 379.29181 -229.018604)
			(xy 379.299974 -229.068838) (xy 379.300486 -229.094284) (xy 379.619014 -229.094284) (xy 379.622974 -229.04523)
			(xy 379.634751 -228.997446) (xy 379.654042 -228.95217) (xy 379.680345 -228.910574) (xy 379.71298 -228.873737)
			(xy 379.751101 -228.842612) (xy 379.793722 -228.818005) (xy 379.839738 -228.800553) (xy 379.887957 -228.790709)
			(xy 379.937132 -228.788728) (xy 379.985987 -228.79466) (xy 380.033258 -228.808352) (xy 380.07772 -228.82945)
			(xy 380.118223 -228.857406) (xy 380.153716 -228.891498) (xy 380.183281 -228.930842) (xy 380.206152 -228.974419)
			(xy 380.221736 -229.0211) (xy 380.229631 -229.069677) (xy 380.230126 -229.094284) (xy 380.548637 -229.094284)
			(xy 380.552732 -229.043556) (xy 380.564911 -228.994142) (xy 380.584859 -228.947322) (xy 380.61206 -228.904308)
			(xy 380.645808 -228.866214) (xy 380.68523 -228.834027) (xy 380.729304 -228.808581) (xy 380.77689 -228.790534)
			(xy 380.826754 -228.780354) (xy 380.877606 -228.778305) (xy 380.928127 -228.784439) (xy 380.977011 -228.798599)
			(xy 381.02299 -228.820416) (xy 381.064874 -228.849326) (xy 381.101578 -228.884581) (xy 381.132151 -228.925267)
			(xy 381.155802 -228.97033) (xy 381.171918 -229.018604) (xy 381.180082 -229.068838) (xy 381.180594 -229.094284)
			(xy 381.499122 -229.094284) (xy 381.503082 -229.04523) (xy 381.514859 -228.997446) (xy 381.53415 -228.95217)
			(xy 381.560453 -228.910574) (xy 381.593088 -228.873737) (xy 381.631209 -228.842612) (xy 381.67383 -228.818005)
			(xy 381.719846 -228.800553) (xy 381.768065 -228.790709) (xy 381.81724 -228.788728) (xy 381.866095 -228.79466)
			(xy 381.913366 -228.808352) (xy 381.957828 -228.82945) (xy 381.998331 -228.857406) (xy 382.033824 -228.891498)
			(xy 382.063389 -228.930842) (xy 382.08626 -228.974419) (xy 382.101844 -229.0211) (xy 382.109739 -229.069677)
			(xy 382.110234 -229.094284) (xy 382.438922 -229.094284) (xy 382.442882 -229.04523) (xy 382.454659 -228.997446)
			(xy 382.47395 -228.95217) (xy 382.500253 -228.910574) (xy 382.532888 -228.873737) (xy 382.571009 -228.842612)
			(xy 382.61363 -228.818005) (xy 382.659646 -228.800553) (xy 382.707865 -228.790709) (xy 382.75704 -228.788728)
			(xy 382.805895 -228.79466) (xy 382.853166 -228.808352) (xy 382.897628 -228.82945) (xy 382.938131 -228.857406)
			(xy 382.973624 -228.891498) (xy 383.003189 -228.930842) (xy 383.02606 -228.974419) (xy 383.041644 -229.0211)
			(xy 383.049539 -229.069677) (xy 383.050034 -229.094284) (xy 383.378976 -229.094284) (xy 383.382936 -229.04523)
			(xy 383.394713 -228.997446) (xy 383.414004 -228.95217) (xy 383.440307 -228.910574) (xy 383.472942 -228.873737)
			(xy 383.511063 -228.842612) (xy 383.553684 -228.818005) (xy 383.5997 -228.800553) (xy 383.647919 -228.790709)
			(xy 383.697094 -228.788728) (xy 383.745949 -228.79466) (xy 383.79322 -228.808352) (xy 383.837682 -228.82945)
			(xy 383.878185 -228.857406) (xy 383.913678 -228.891498) (xy 383.943243 -228.930842) (xy 383.966114 -228.974419)
			(xy 383.981698 -229.0211) (xy 383.989593 -229.069677) (xy 383.990088 -229.094284) (xy 383.989593 -229.118891)
			(xy 383.981698 -229.167468) (xy 383.966114 -229.214149) (xy 383.943243 -229.257726) (xy 383.913678 -229.29707)
			(xy 383.878185 -229.331162) (xy 383.837682 -229.359118) (xy 383.79322 -229.380216) (xy 383.745949 -229.393908)
			(xy 383.697094 -229.39984) (xy 383.647919 -229.397859) (xy 383.5997 -229.388015) (xy 383.553684 -229.370563)
			(xy 383.511063 -229.345956) (xy 383.472942 -229.314831) (xy 383.440307 -229.277994) (xy 383.414004 -229.236398)
			(xy 383.394713 -229.191122) (xy 383.382936 -229.143338) (xy 383.378976 -229.094284) (xy 383.050034 -229.094284)
			(xy 383.049539 -229.118891) (xy 383.041644 -229.167468) (xy 383.02606 -229.214149) (xy 383.003189 -229.257726)
			(xy 382.973624 -229.29707) (xy 382.938131 -229.331162) (xy 382.897628 -229.359118) (xy 382.853166 -229.380216)
			(xy 382.805895 -229.393908) (xy 382.75704 -229.39984) (xy 382.707865 -229.397859) (xy 382.659646 -229.388015)
			(xy 382.61363 -229.370563) (xy 382.571009 -229.345956) (xy 382.532888 -229.314831) (xy 382.500253 -229.277994)
			(xy 382.47395 -229.236398) (xy 382.454659 -229.191122) (xy 382.442882 -229.143338) (xy 382.438922 -229.094284)
			(xy 382.110234 -229.094284) (xy 382.109739 -229.118891) (xy 382.101844 -229.167468) (xy 382.08626 -229.214149)
			(xy 382.063389 -229.257726) (xy 382.033824 -229.29707) (xy 381.998331 -229.331162) (xy 381.957828 -229.359118)
			(xy 381.913366 -229.380216) (xy 381.866095 -229.393908) (xy 381.81724 -229.39984) (xy 381.768065 -229.397859)
			(xy 381.719846 -229.388015) (xy 381.67383 -229.370563) (xy 381.631209 -229.345956) (xy 381.593088 -229.314831)
			(xy 381.560453 -229.277994) (xy 381.53415 -229.236398) (xy 381.514859 -229.191122) (xy 381.503082 -229.143338)
			(xy 381.499122 -229.094284) (xy 381.180594 -229.094284) (xy 381.180082 -229.11973) (xy 381.171918 -229.169964)
			(xy 381.155802 -229.218238) (xy 381.132151 -229.263301) (xy 381.101578 -229.303987) (xy 381.064874 -229.339242)
			(xy 381.02299 -229.368152) (xy 380.977011 -229.389969) (xy 380.928127 -229.404129) (xy 380.877606 -229.410263)
			(xy 380.826754 -229.408214) (xy 380.77689 -229.398034) (xy 380.729304 -229.379987) (xy 380.68523 -229.354541)
			(xy 380.645808 -229.322354) (xy 380.61206 -229.28426) (xy 380.584859 -229.241246) (xy 380.564911 -229.194426)
			(xy 380.552732 -229.145012) (xy 380.548637 -229.094284) (xy 380.230126 -229.094284) (xy 380.229631 -229.118891)
			(xy 380.221736 -229.167468) (xy 380.206152 -229.214149) (xy 380.183281 -229.257726) (xy 380.153716 -229.29707)
			(xy 380.118223 -229.331162) (xy 380.07772 -229.359118) (xy 380.033258 -229.380216) (xy 379.985987 -229.393908)
			(xy 379.937132 -229.39984) (xy 379.887957 -229.397859) (xy 379.839738 -229.388015) (xy 379.793722 -229.370563)
			(xy 379.751101 -229.345956) (xy 379.71298 -229.314831) (xy 379.680345 -229.277994) (xy 379.654042 -229.236398)
			(xy 379.634751 -229.191122) (xy 379.622974 -229.143338) (xy 379.619014 -229.094284) (xy 379.300486 -229.094284)
			(xy 379.299974 -229.11973) (xy 379.29181 -229.169964) (xy 379.275694 -229.218238) (xy 379.252043 -229.263301)
			(xy 379.22147 -229.303987) (xy 379.184766 -229.339242) (xy 379.142882 -229.368152) (xy 379.096903 -229.389969)
			(xy 379.048019 -229.404129) (xy 378.997498 -229.410263) (xy 378.946646 -229.408214) (xy 378.896782 -229.398034)
			(xy 378.849196 -229.379987) (xy 378.805122 -229.354541) (xy 378.7657 -229.322354) (xy 378.731952 -229.28426)
			(xy 378.704751 -229.241246) (xy 378.684803 -229.194426) (xy 378.672624 -229.145012) (xy 378.668529 -229.094284)
			(xy 378.350018 -229.094284) (xy 378.349523 -229.118891) (xy 378.341628 -229.167468) (xy 378.326044 -229.214149)
			(xy 378.303173 -229.257726) (xy 378.273608 -229.29707) (xy 378.238115 -229.331162) (xy 378.197612 -229.359118)
			(xy 378.15315 -229.380216) (xy 378.105879 -229.393908) (xy 378.057024 -229.39984) (xy 378.007849 -229.397859)
			(xy 377.95963 -229.388015) (xy 377.913614 -229.370563) (xy 377.870993 -229.345956) (xy 377.832872 -229.314831)
			(xy 377.800237 -229.277994) (xy 377.773934 -229.236398) (xy 377.754643 -229.191122) (xy 377.742866 -229.143338)
			(xy 377.738906 -229.094284) (xy 377.420632 -229.094284) (xy 377.42012 -229.11973) (xy 377.411956 -229.169964)
			(xy 377.39584 -229.218238) (xy 377.372189 -229.263301) (xy 377.341616 -229.303987) (xy 377.304912 -229.339242)
			(xy 377.263028 -229.368152) (xy 377.217049 -229.389969) (xy 377.168165 -229.404129) (xy 377.117644 -229.410263)
			(xy 377.066792 -229.408214) (xy 377.016928 -229.398034) (xy 376.969342 -229.379987) (xy 376.925268 -229.354541)
			(xy 376.885846 -229.322354) (xy 376.852098 -229.28426) (xy 376.824897 -229.241246) (xy 376.804949 -229.194426)
			(xy 376.79277 -229.145012) (xy 376.788675 -229.094284) (xy 376.479923 -229.094284) (xy 376.479923 -229.119095)
			(xy 376.472164 -229.168074) (xy 376.456839 -229.215237) (xy 376.434324 -229.259421) (xy 376.405173 -229.299539)
			(xy 376.370105 -229.334602) (xy 376.329984 -229.363747) (xy 376.285796 -229.386256) (xy 376.238632 -229.401575)
			(xy 376.189651 -229.409326) (xy 376.164856 -229.409752) (xy 376.13795 -229.409252) (xy 376.084906 -229.400206)
			(xy 376.034169 -229.382282) (xy 376.010424 -229.36962) (xy 375.999756 -229.363524) (xy 375.975372 -229.362762)
			(xy 375.893076 -229.401116) (xy 375.878344 -229.419658) (xy 375.875804 -229.431596) (xy 375.867753 -229.468226)
			(xy 375.848695 -229.540772) (xy 375.837704 -229.57663) (xy 375.834958 -229.587564) (xy 375.838137 -229.609856)
			(xy 375.850507 -229.628671) (xy 375.859802 -229.63505) (xy 375.882422 -229.649545) (xy 375.922812 -229.684966)
			(xy 375.956619 -229.726716) (xy 375.982866 -229.773588) (xy 376.000796 -229.824229) (xy 376.009888 -229.877175)
			(xy 376.010424 -229.904036) (xy 376.328952 -229.904036) (xy 376.332912 -229.854982) (xy 376.344689 -229.807198)
			(xy 376.36398 -229.761922) (xy 376.390283 -229.720326) (xy 376.422918 -229.683489) (xy 376.461039 -229.652364)
			(xy 376.50366 -229.627757) (xy 376.549676 -229.610305) (xy 376.597895 -229.600461) (xy 376.64707 -229.59848)
			(xy 376.695925 -229.604412) (xy 376.743196 -229.618104) (xy 376.787658 -229.639202) (xy 376.828161 -229.667158)
			(xy 376.863654 -229.70125) (xy 376.893219 -229.740594) (xy 376.91609 -229.784171) (xy 376.931674 -229.830852)
			(xy 376.939569 -229.879429) (xy 376.940064 -229.904036) (xy 377.258575 -229.904036) (xy 377.26267 -229.853308)
			(xy 377.274849 -229.803894) (xy 377.294797 -229.757074) (xy 377.321998 -229.71406) (xy 377.355746 -229.675966)
			(xy 377.395168 -229.643779) (xy 377.439242 -229.618333) (xy 377.486828 -229.600286) (xy 377.536692 -229.590106)
			(xy 377.587544 -229.588057) (xy 377.638065 -229.594191) (xy 377.686949 -229.608351) (xy 377.732928 -229.630168)
			(xy 377.774812 -229.659078) (xy 377.811516 -229.694333) (xy 377.842089 -229.735019) (xy 377.86574 -229.780082)
			(xy 377.881856 -229.828356) (xy 377.89002 -229.87859) (xy 377.890532 -229.904036) (xy 379.138683 -229.904036)
			(xy 379.142778 -229.853308) (xy 379.154957 -229.803894) (xy 379.174905 -229.757074) (xy 379.202106 -229.71406)
			(xy 379.235854 -229.675966) (xy 379.275276 -229.643779) (xy 379.31935 -229.618333) (xy 379.366936 -229.600286)
			(xy 379.4168 -229.590106) (xy 379.467652 -229.588057) (xy 379.518173 -229.594191) (xy 379.567057 -229.608351)
			(xy 379.613036 -229.630168) (xy 379.65492 -229.659078) (xy 379.691624 -229.694333) (xy 379.722197 -229.735019)
			(xy 379.745848 -229.780082) (xy 379.761964 -229.828356) (xy 379.770128 -229.87859) (xy 379.77064 -229.904036)
			(xy 380.078483 -229.904036) (xy 380.082578 -229.853308) (xy 380.094757 -229.803894) (xy 380.114705 -229.757074)
			(xy 380.141906 -229.71406) (xy 380.175654 -229.675966) (xy 380.215076 -229.643779) (xy 380.25915 -229.618333)
			(xy 380.306736 -229.600286) (xy 380.3566 -229.590106) (xy 380.407452 -229.588057) (xy 380.457973 -229.594191)
			(xy 380.506857 -229.608351) (xy 380.552836 -229.630168) (xy 380.59472 -229.659078) (xy 380.631424 -229.694333)
			(xy 380.661997 -229.735019) (xy 380.685648 -229.780082) (xy 380.701764 -229.828356) (xy 380.709928 -229.87859)
			(xy 380.71044 -229.904036) (xy 381.028968 -229.904036) (xy 381.032928 -229.854982) (xy 381.044705 -229.807198)
			(xy 381.063996 -229.761922) (xy 381.090299 -229.720326) (xy 381.122934 -229.683489) (xy 381.161055 -229.652364)
			(xy 381.203676 -229.627757) (xy 381.249692 -229.610305) (xy 381.297911 -229.600461) (xy 381.347086 -229.59848)
			(xy 381.395941 -229.604412) (xy 381.443212 -229.618104) (xy 381.487674 -229.639202) (xy 381.528177 -229.667158)
			(xy 381.56367 -229.70125) (xy 381.593235 -229.740594) (xy 381.616106 -229.784171) (xy 381.63169 -229.830852)
			(xy 381.639585 -229.879429) (xy 381.64008 -229.904036) (xy 381.969022 -229.904036) (xy 381.972982 -229.854982)
			(xy 381.984759 -229.807198) (xy 382.00405 -229.761922) (xy 382.030353 -229.720326) (xy 382.062988 -229.683489)
			(xy 382.101109 -229.652364) (xy 382.14373 -229.627757) (xy 382.189746 -229.610305) (xy 382.237965 -229.600461)
			(xy 382.28714 -229.59848) (xy 382.335995 -229.604412) (xy 382.383266 -229.618104) (xy 382.427728 -229.639202)
			(xy 382.468231 -229.667158) (xy 382.503724 -229.70125) (xy 382.533289 -229.740594) (xy 382.55616 -229.784171)
			(xy 382.571744 -229.830852) (xy 382.579639 -229.879429) (xy 382.580134 -229.904036) (xy 382.909076 -229.904036)
			(xy 382.913036 -229.854982) (xy 382.924813 -229.807198) (xy 382.944104 -229.761922) (xy 382.970407 -229.720326)
			(xy 383.003042 -229.683489) (xy 383.041163 -229.652364) (xy 383.083784 -229.627757) (xy 383.1298 -229.610305)
			(xy 383.178019 -229.600461) (xy 383.227194 -229.59848) (xy 383.276049 -229.604412) (xy 383.32332 -229.618104)
			(xy 383.367782 -229.639202) (xy 383.408285 -229.667158) (xy 383.443778 -229.70125) (xy 383.473343 -229.740594)
			(xy 383.496214 -229.784171) (xy 383.511798 -229.830852) (xy 383.519693 -229.879429) (xy 383.520188 -229.904036)
			(xy 383.84913 -229.904036) (xy 383.85309 -229.854982) (xy 383.864867 -229.807198) (xy 383.884158 -229.761922)
			(xy 383.910461 -229.720326) (xy 383.943096 -229.683489) (xy 383.981217 -229.652364) (xy 384.023838 -229.627757)
			(xy 384.069854 -229.610305) (xy 384.118073 -229.600461) (xy 384.167248 -229.59848) (xy 384.216103 -229.604412)
			(xy 384.263374 -229.618104) (xy 384.307836 -229.639202) (xy 384.348339 -229.667158) (xy 384.383832 -229.70125)
			(xy 384.413397 -229.740594) (xy 384.436268 -229.784171) (xy 384.451852 -229.830852) (xy 384.459747 -229.879429)
			(xy 384.460242 -229.904036) (xy 384.459747 -229.928643) (xy 384.451852 -229.97722) (xy 384.436268 -230.023901)
			(xy 384.413397 -230.067478) (xy 384.383832 -230.106822) (xy 384.348339 -230.140914) (xy 384.307836 -230.16887)
			(xy 384.263374 -230.189968) (xy 384.216103 -230.20366) (xy 384.167248 -230.209592) (xy 384.118073 -230.207611)
			(xy 384.069854 -230.197767) (xy 384.023838 -230.180315) (xy 383.981217 -230.155708) (xy 383.943096 -230.124583)
			(xy 383.910461 -230.087746) (xy 383.884158 -230.04615) (xy 383.864867 -230.000874) (xy 383.85309 -229.95309)
			(xy 383.84913 -229.904036) (xy 383.520188 -229.904036) (xy 383.519693 -229.928643) (xy 383.511798 -229.97722)
			(xy 383.496214 -230.023901) (xy 383.473343 -230.067478) (xy 383.443778 -230.106822) (xy 383.408285 -230.140914)
			(xy 383.367782 -230.16887) (xy 383.32332 -230.189968) (xy 383.276049 -230.20366) (xy 383.227194 -230.209592)
			(xy 383.178019 -230.207611) (xy 383.1298 -230.197767) (xy 383.083784 -230.180315) (xy 383.041163 -230.155708)
			(xy 383.003042 -230.124583) (xy 382.970407 -230.087746) (xy 382.944104 -230.04615) (xy 382.924813 -230.000874)
			(xy 382.913036 -229.95309) (xy 382.909076 -229.904036) (xy 382.580134 -229.904036) (xy 382.579639 -229.928643)
			(xy 382.571744 -229.97722) (xy 382.55616 -230.023901) (xy 382.533289 -230.067478) (xy 382.503724 -230.106822)
			(xy 382.468231 -230.140914) (xy 382.427728 -230.16887) (xy 382.383266 -230.189968) (xy 382.335995 -230.20366)
			(xy 382.28714 -230.209592) (xy 382.237965 -230.207611) (xy 382.189746 -230.197767) (xy 382.14373 -230.180315)
			(xy 382.101109 -230.155708) (xy 382.062988 -230.124583) (xy 382.030353 -230.087746) (xy 382.00405 -230.04615)
			(xy 381.984759 -230.000874) (xy 381.972982 -229.95309) (xy 381.969022 -229.904036) (xy 381.64008 -229.904036)
			(xy 381.639585 -229.928643) (xy 381.63169 -229.97722) (xy 381.616106 -230.023901) (xy 381.593235 -230.067478)
			(xy 381.56367 -230.106822) (xy 381.528177 -230.140914) (xy 381.487674 -230.16887) (xy 381.443212 -230.189968)
			(xy 381.395941 -230.20366) (xy 381.347086 -230.209592) (xy 381.297911 -230.207611) (xy 381.249692 -230.197767)
			(xy 381.203676 -230.180315) (xy 381.161055 -230.155708) (xy 381.122934 -230.124583) (xy 381.090299 -230.087746)
			(xy 381.063996 -230.04615) (xy 381.044705 -230.000874) (xy 381.032928 -229.95309) (xy 381.028968 -229.904036)
			(xy 380.71044 -229.904036) (xy 380.709928 -229.929482) (xy 380.701764 -229.979716) (xy 380.685648 -230.02799)
			(xy 380.661997 -230.073053) (xy 380.631424 -230.113739) (xy 380.59472 -230.148994) (xy 380.552836 -230.177904)
			(xy 380.506857 -230.199721) (xy 380.457973 -230.213881) (xy 380.407452 -230.220015) (xy 380.3566 -230.217966)
			(xy 380.306736 -230.207786) (xy 380.25915 -230.189739) (xy 380.215076 -230.164293) (xy 380.175654 -230.132106)
			(xy 380.141906 -230.094012) (xy 380.114705 -230.050998) (xy 380.094757 -230.004178) (xy 380.082578 -229.954764)
			(xy 380.078483 -229.904036) (xy 379.77064 -229.904036) (xy 379.770128 -229.929482) (xy 379.761964 -229.979716)
			(xy 379.745848 -230.02799) (xy 379.722197 -230.073053) (xy 379.691624 -230.113739) (xy 379.65492 -230.148994)
			(xy 379.613036 -230.177904) (xy 379.567057 -230.199721) (xy 379.518173 -230.213881) (xy 379.467652 -230.220015)
			(xy 379.4168 -230.217966) (xy 379.366936 -230.207786) (xy 379.31935 -230.189739) (xy 379.275276 -230.164293)
			(xy 379.235854 -230.132106) (xy 379.202106 -230.094012) (xy 379.174905 -230.050998) (xy 379.154957 -230.004178)
			(xy 379.142778 -229.954764) (xy 379.138683 -229.904036) (xy 377.890532 -229.904036) (xy 377.89002 -229.929482)
			(xy 377.881856 -229.979716) (xy 377.86574 -230.02799) (xy 377.842089 -230.073053) (xy 377.811516 -230.113739)
			(xy 377.774812 -230.148994) (xy 377.732928 -230.177904) (xy 377.686949 -230.199721) (xy 377.638065 -230.213881)
			(xy 377.587544 -230.220015) (xy 377.536692 -230.217966) (xy 377.486828 -230.207786) (xy 377.439242 -230.189739)
			(xy 377.395168 -230.164293) (xy 377.355746 -230.132106) (xy 377.321998 -230.094012) (xy 377.294797 -230.050998)
			(xy 377.274849 -230.004178) (xy 377.26267 -229.954764) (xy 377.258575 -229.904036) (xy 376.940064 -229.904036)
			(xy 376.939569 -229.928643) (xy 376.931674 -229.97722) (xy 376.91609 -230.023901) (xy 376.893219 -230.067478)
			(xy 376.863654 -230.106822) (xy 376.828161 -230.140914) (xy 376.787658 -230.16887) (xy 376.743196 -230.189968)
			(xy 376.695925 -230.20366) (xy 376.64707 -230.209592) (xy 376.597895 -230.207611) (xy 376.549676 -230.197767)
			(xy 376.50366 -230.180315) (xy 376.461039 -230.155708) (xy 376.422918 -230.124583) (xy 376.390283 -230.087746)
			(xy 376.36398 -230.04615) (xy 376.344689 -230.000874) (xy 376.332912 -229.95309) (xy 376.328952 -229.904036)
			(xy 376.010424 -229.904036) (xy 376.009863 -229.930906) (xy 376.000724 -229.983864) (xy 375.982749 -230.03451)
			(xy 375.956458 -230.08138) (xy 375.92261 -230.123122) (xy 375.882182 -230.15853) (xy 375.859548 -230.173022)
			(xy 375.850278 -230.179477) (xy 375.837995 -230.198402) (xy 375.834909 -230.220751) (xy 375.837704 -230.231696)
			(xy 375.848696 -230.267682) (xy 375.867756 -230.340482) (xy 375.875804 -230.377238) (xy 375.878344 -230.388922)
			(xy 375.893076 -230.407464) (xy 375.975372 -230.446072) (xy 375.999756 -230.445056) (xy 376.010424 -230.43896)
			(xy 376.034174 -230.42631) (xy 376.084913 -230.4084) (xy 376.137952 -230.399345) (xy 376.164856 -230.398828)
			(xy 376.18965 -230.399286) (xy 376.238629 -230.407037) (xy 376.285792 -230.422355) (xy 376.329977 -230.444864)
			(xy 376.370097 -230.474007) (xy 376.405164 -230.509069) (xy 376.434313 -230.549185) (xy 376.456828 -230.593368)
			(xy 376.472153 -230.640528) (xy 376.479911 -230.689506) (xy 376.479911 -230.714296) (xy 376.788675 -230.714296)
			(xy 376.79277 -230.663568) (xy 376.804949 -230.614154) (xy 376.824897 -230.567334) (xy 376.852098 -230.52432)
			(xy 376.885846 -230.486226) (xy 376.925268 -230.454039) (xy 376.969342 -230.428593) (xy 377.016928 -230.410546)
			(xy 377.066792 -230.400366) (xy 377.117644 -230.398317) (xy 377.168165 -230.404451) (xy 377.217049 -230.418611)
			(xy 377.263028 -230.440428) (xy 377.304912 -230.469338) (xy 377.341616 -230.504593) (xy 377.372189 -230.545279)
			(xy 377.39584 -230.590342) (xy 377.411956 -230.638616) (xy 377.42012 -230.68885) (xy 377.420632 -230.714296)
			(xy 377.738906 -230.714296) (xy 377.742866 -230.665242) (xy 377.754643 -230.617458) (xy 377.773934 -230.572182)
			(xy 377.800237 -230.530586) (xy 377.832872 -230.493749) (xy 377.870993 -230.462624) (xy 377.913614 -230.438017)
			(xy 377.95963 -230.420565) (xy 378.007849 -230.410721) (xy 378.057024 -230.40874) (xy 378.105879 -230.414672)
			(xy 378.15315 -230.428364) (xy 378.197612 -230.449462) (xy 378.238115 -230.477418) (xy 378.273608 -230.51151)
			(xy 378.303173 -230.550854) (xy 378.326044 -230.594431) (xy 378.341628 -230.641112) (xy 378.349523 -230.689689)
			(xy 378.350018 -230.714296) (xy 378.668529 -230.714296) (xy 378.672624 -230.663568) (xy 378.684803 -230.614154)
			(xy 378.704751 -230.567334) (xy 378.731952 -230.52432) (xy 378.7657 -230.486226) (xy 378.805122 -230.454039)
			(xy 378.849196 -230.428593) (xy 378.896782 -230.410546) (xy 378.946646 -230.400366) (xy 378.997498 -230.398317)
			(xy 379.048019 -230.404451) (xy 379.096903 -230.418611) (xy 379.142882 -230.440428) (xy 379.184766 -230.469338)
			(xy 379.22147 -230.504593) (xy 379.252043 -230.545279) (xy 379.275694 -230.590342) (xy 379.29181 -230.638616)
			(xy 379.299974 -230.68885) (xy 379.300486 -230.714296) (xy 379.619014 -230.714296) (xy 379.622974 -230.665242)
			(xy 379.634751 -230.617458) (xy 379.654042 -230.572182) (xy 379.680345 -230.530586) (xy 379.71298 -230.493749)
			(xy 379.751101 -230.462624) (xy 379.793722 -230.438017) (xy 379.839738 -230.420565) (xy 379.887957 -230.410721)
			(xy 379.937132 -230.40874) (xy 379.985987 -230.414672) (xy 380.033258 -230.428364) (xy 380.07772 -230.449462)
			(xy 380.118223 -230.477418) (xy 380.153716 -230.51151) (xy 380.183281 -230.550854) (xy 380.206152 -230.594431)
			(xy 380.221736 -230.641112) (xy 380.229631 -230.689689) (xy 380.230126 -230.714296) (xy 380.548637 -230.714296)
			(xy 380.552732 -230.663568) (xy 380.564911 -230.614154) (xy 380.584859 -230.567334) (xy 380.61206 -230.52432)
			(xy 380.645808 -230.486226) (xy 380.68523 -230.454039) (xy 380.729304 -230.428593) (xy 380.77689 -230.410546)
			(xy 380.826754 -230.400366) (xy 380.877606 -230.398317) (xy 380.928127 -230.404451) (xy 380.977011 -230.418611)
			(xy 381.02299 -230.440428) (xy 381.064874 -230.469338) (xy 381.101578 -230.504593) (xy 381.132151 -230.545279)
			(xy 381.155802 -230.590342) (xy 381.171918 -230.638616) (xy 381.180082 -230.68885) (xy 381.180589 -230.714042)
			(xy 381.499122 -230.714042) (xy 381.503082 -230.664988) (xy 381.514859 -230.617204) (xy 381.53415 -230.571928)
			(xy 381.560453 -230.530332) (xy 381.593088 -230.493495) (xy 381.631209 -230.46237) (xy 381.67383 -230.437763)
			(xy 381.719846 -230.420311) (xy 381.768065 -230.410467) (xy 381.81724 -230.408486) (xy 381.866095 -230.414418)
			(xy 381.913366 -230.42811) (xy 381.957828 -230.449208) (xy 381.998331 -230.477164) (xy 382.033824 -230.511256)
			(xy 382.063389 -230.5506) (xy 382.08626 -230.594177) (xy 382.101844 -230.640858) (xy 382.109739 -230.689435)
			(xy 382.110234 -230.714042) (xy 382.110229 -230.714296) (xy 382.438922 -230.714296) (xy 382.442882 -230.665242)
			(xy 382.454659 -230.617458) (xy 382.47395 -230.572182) (xy 382.500253 -230.530586) (xy 382.532888 -230.493749)
			(xy 382.571009 -230.462624) (xy 382.61363 -230.438017) (xy 382.659646 -230.420565) (xy 382.707865 -230.410721)
			(xy 382.75704 -230.40874) (xy 382.805895 -230.414672) (xy 382.853166 -230.428364) (xy 382.897628 -230.449462)
			(xy 382.938131 -230.477418) (xy 382.973624 -230.51151) (xy 383.003189 -230.550854) (xy 383.02606 -230.594431)
			(xy 383.041644 -230.641112) (xy 383.049539 -230.689689) (xy 383.050034 -230.714296) (xy 383.378976 -230.714296)
			(xy 383.382936 -230.665242) (xy 383.394713 -230.617458) (xy 383.414004 -230.572182) (xy 383.440307 -230.530586)
			(xy 383.472942 -230.493749) (xy 383.511063 -230.462624) (xy 383.553684 -230.438017) (xy 383.5997 -230.420565)
			(xy 383.647919 -230.410721) (xy 383.697094 -230.40874) (xy 383.745949 -230.414672) (xy 383.79322 -230.428364)
			(xy 383.837682 -230.449462) (xy 383.878185 -230.477418) (xy 383.913678 -230.51151) (xy 383.943243 -230.550854)
			(xy 383.966114 -230.594431) (xy 383.981698 -230.641112) (xy 383.989593 -230.689689) (xy 383.990088 -230.714296)
			(xy 383.989593 -230.738903) (xy 383.981698 -230.78748) (xy 383.966114 -230.834161) (xy 383.943243 -230.877738)
			(xy 383.913678 -230.917082) (xy 383.878185 -230.951174) (xy 383.837682 -230.97913) (xy 383.79322 -231.000228)
			(xy 383.745949 -231.01392) (xy 383.697094 -231.019852) (xy 383.647919 -231.017871) (xy 383.5997 -231.008027)
			(xy 383.553684 -230.990575) (xy 383.511063 -230.965968) (xy 383.472942 -230.934843) (xy 383.440307 -230.898006)
			(xy 383.414004 -230.85641) (xy 383.394713 -230.811134) (xy 383.382936 -230.76335) (xy 383.378976 -230.714296)
			(xy 383.050034 -230.714296) (xy 383.049539 -230.738903) (xy 383.041644 -230.78748) (xy 383.02606 -230.834161)
			(xy 383.003189 -230.877738) (xy 382.973624 -230.917082) (xy 382.938131 -230.951174) (xy 382.897628 -230.97913)
			(xy 382.853166 -231.000228) (xy 382.805895 -231.01392) (xy 382.75704 -231.019852) (xy 382.707865 -231.017871)
			(xy 382.659646 -231.008027) (xy 382.61363 -230.990575) (xy 382.571009 -230.965968) (xy 382.532888 -230.934843)
			(xy 382.500253 -230.898006) (xy 382.47395 -230.85641) (xy 382.454659 -230.811134) (xy 382.442882 -230.76335)
			(xy 382.438922 -230.714296) (xy 382.110229 -230.714296) (xy 382.109739 -230.738649) (xy 382.101844 -230.787226)
			(xy 382.08626 -230.833907) (xy 382.063389 -230.877484) (xy 382.033824 -230.916828) (xy 381.998331 -230.95092)
			(xy 381.957828 -230.978876) (xy 381.913366 -230.999974) (xy 381.866095 -231.013666) (xy 381.81724 -231.019598)
			(xy 381.768065 -231.017617) (xy 381.719846 -231.007773) (xy 381.67383 -230.990321) (xy 381.631209 -230.965714)
			(xy 381.593088 -230.934589) (xy 381.560453 -230.897752) (xy 381.53415 -230.856156) (xy 381.514859 -230.81088)
			(xy 381.503082 -230.763096) (xy 381.499122 -230.714042) (xy 381.180589 -230.714042) (xy 381.180594 -230.714296)
			(xy 381.180082 -230.739742) (xy 381.171918 -230.789976) (xy 381.155802 -230.83825) (xy 381.132151 -230.883313)
			(xy 381.101578 -230.923999) (xy 381.064874 -230.959254) (xy 381.02299 -230.988164) (xy 380.977011 -231.009981)
			(xy 380.928127 -231.024141) (xy 380.877606 -231.030275) (xy 380.826754 -231.028226) (xy 380.77689 -231.018046)
			(xy 380.729304 -230.999999) (xy 380.68523 -230.974553) (xy 380.645808 -230.942366) (xy 380.61206 -230.904272)
			(xy 380.584859 -230.861258) (xy 380.564911 -230.814438) (xy 380.552732 -230.765024) (xy 380.548637 -230.714296)
			(xy 380.230126 -230.714296) (xy 380.229631 -230.738903) (xy 380.221736 -230.78748) (xy 380.206152 -230.834161)
			(xy 380.183281 -230.877738) (xy 380.153716 -230.917082) (xy 380.118223 -230.951174) (xy 380.07772 -230.97913)
			(xy 380.033258 -231.000228) (xy 379.985987 -231.01392) (xy 379.937132 -231.019852) (xy 379.887957 -231.017871)
			(xy 379.839738 -231.008027) (xy 379.793722 -230.990575) (xy 379.751101 -230.965968) (xy 379.71298 -230.934843)
			(xy 379.680345 -230.898006) (xy 379.654042 -230.85641) (xy 379.634751 -230.811134) (xy 379.622974 -230.76335)
			(xy 379.619014 -230.714296) (xy 379.300486 -230.714296) (xy 379.299974 -230.739742) (xy 379.29181 -230.789976)
			(xy 379.275694 -230.83825) (xy 379.252043 -230.883313) (xy 379.22147 -230.923999) (xy 379.184766 -230.959254)
			(xy 379.142882 -230.988164) (xy 379.096903 -231.009981) (xy 379.048019 -231.024141) (xy 378.997498 -231.030275)
			(xy 378.946646 -231.028226) (xy 378.896782 -231.018046) (xy 378.849196 -230.999999) (xy 378.805122 -230.974553)
			(xy 378.7657 -230.942366) (xy 378.731952 -230.904272) (xy 378.704751 -230.861258) (xy 378.684803 -230.814438)
			(xy 378.672624 -230.765024) (xy 378.668529 -230.714296) (xy 378.350018 -230.714296) (xy 378.349523 -230.738903)
			(xy 378.341628 -230.78748) (xy 378.326044 -230.834161) (xy 378.303173 -230.877738) (xy 378.273608 -230.917082)
			(xy 378.238115 -230.951174) (xy 378.197612 -230.97913) (xy 378.15315 -231.000228) (xy 378.105879 -231.01392)
			(xy 378.057024 -231.019852) (xy 378.007849 -231.017871) (xy 377.95963 -231.008027) (xy 377.913614 -230.990575)
			(xy 377.870993 -230.965968) (xy 377.832872 -230.934843) (xy 377.800237 -230.898006) (xy 377.773934 -230.85641)
			(xy 377.754643 -230.811134) (xy 377.742866 -230.76335) (xy 377.738906 -230.714296) (xy 377.420632 -230.714296)
			(xy 377.42012 -230.739742) (xy 377.411956 -230.789976) (xy 377.39584 -230.83825) (xy 377.372189 -230.883313)
			(xy 377.341616 -230.923999) (xy 377.304912 -230.959254) (xy 377.263028 -230.988164) (xy 377.217049 -231.009981)
			(xy 377.168165 -231.024141) (xy 377.117644 -231.030275) (xy 377.066792 -231.028226) (xy 377.016928 -231.018046)
			(xy 376.969342 -230.999999) (xy 376.925268 -230.974553) (xy 376.885846 -230.942366) (xy 376.852098 -230.904272)
			(xy 376.824897 -230.861258) (xy 376.804949 -230.814438) (xy 376.79277 -230.765024) (xy 376.788675 -230.714296)
			(xy 376.479911 -230.714296) (xy 376.479911 -230.739094) (xy 376.472153 -230.788072) (xy 376.456828 -230.835232)
			(xy 376.434313 -230.879415) (xy 376.405164 -230.919531) (xy 376.370097 -230.954593) (xy 376.329977 -230.983736)
			(xy 376.285792 -231.006245) (xy 376.238629 -231.021563) (xy 376.18965 -231.029314) (xy 376.164856 -231.029764)
			(xy 376.13795 -231.029264) (xy 376.084906 -231.020219) (xy 376.034169 -231.002295) (xy 376.010424 -230.989632)
			(xy 375.999756 -230.983536) (xy 375.975372 -230.982774) (xy 375.893076 -231.021128) (xy 375.878344 -231.03967)
			(xy 375.875804 -231.051608) (xy 375.867752 -231.088238) (xy 375.848695 -231.160784) (xy 375.837704 -231.196642)
			(xy 375.834961 -231.207575) (xy 375.838144 -231.229863) (xy 375.850514 -231.248673) (xy 375.859802 -231.255062)
			(xy 375.880698 -231.268408) (xy 375.918398 -231.300607) (xy 375.950597 -231.338308) (xy 375.9765 -231.380582)
			(xy 375.995472 -231.426388) (xy 376.007043 -231.474598) (xy 376.010929 -231.524025) (xy 376.010927 -231.524048)
			(xy 376.328952 -231.524048) (xy 376.332912 -231.474994) (xy 376.344689 -231.42721) (xy 376.36398 -231.381934)
			(xy 376.390283 -231.340338) (xy 376.422918 -231.303501) (xy 376.461039 -231.272376) (xy 376.50366 -231.247769)
			(xy 376.549676 -231.230317) (xy 376.597895 -231.220473) (xy 376.64707 -231.218492) (xy 376.695925 -231.224424)
			(xy 376.743196 -231.238116) (xy 376.787658 -231.259214) (xy 376.828161 -231.28717) (xy 376.863654 -231.321262)
			(xy 376.893219 -231.360606) (xy 376.91609 -231.404183) (xy 376.931674 -231.450864) (xy 376.939569 -231.499441)
			(xy 376.940064 -231.524048) (xy 377.258575 -231.524048) (xy 377.26267 -231.47332) (xy 377.274849 -231.423906)
			(xy 377.294797 -231.377086) (xy 377.321998 -231.334072) (xy 377.355746 -231.295978) (xy 377.395168 -231.263791)
			(xy 377.439242 -231.238345) (xy 377.486828 -231.220298) (xy 377.536692 -231.210118) (xy 377.587544 -231.208069)
			(xy 377.638065 -231.214203) (xy 377.686949 -231.228363) (xy 377.732928 -231.25018) (xy 377.774812 -231.27909)
			(xy 377.811516 -231.314345) (xy 377.842089 -231.355031) (xy 377.86574 -231.400094) (xy 377.881856 -231.448368)
			(xy 377.89002 -231.498602) (xy 377.890532 -231.524048) (xy 378.20906 -231.524048) (xy 378.21302 -231.474994)
			(xy 378.224797 -231.42721) (xy 378.244088 -231.381934) (xy 378.270391 -231.340338) (xy 378.303026 -231.303501)
			(xy 378.341147 -231.272376) (xy 378.383768 -231.247769) (xy 378.429784 -231.230317) (xy 378.478003 -231.220473)
			(xy 378.527178 -231.218492) (xy 378.576033 -231.224424) (xy 378.623304 -231.238116) (xy 378.667766 -231.259214)
			(xy 378.708269 -231.28717) (xy 378.743762 -231.321262) (xy 378.773327 -231.360606) (xy 378.796198 -231.404183)
			(xy 378.811782 -231.450864) (xy 378.819677 -231.499441) (xy 378.820172 -231.524048) (xy 379.138683 -231.524048)
			(xy 379.142778 -231.47332) (xy 379.154957 -231.423906) (xy 379.174905 -231.377086) (xy 379.202106 -231.334072)
			(xy 379.235854 -231.295978) (xy 379.275276 -231.263791) (xy 379.31935 -231.238345) (xy 379.366936 -231.220298)
			(xy 379.4168 -231.210118) (xy 379.467652 -231.208069) (xy 379.518173 -231.214203) (xy 379.567057 -231.228363)
			(xy 379.613036 -231.25018) (xy 379.65492 -231.27909) (xy 379.691624 -231.314345) (xy 379.722197 -231.355031)
			(xy 379.745848 -231.400094) (xy 379.761964 -231.448368) (xy 379.770128 -231.498602) (xy 379.77064 -231.524048)
			(xy 380.078483 -231.524048) (xy 380.082578 -231.47332) (xy 380.094757 -231.423906) (xy 380.114705 -231.377086)
			(xy 380.141906 -231.334072) (xy 380.175654 -231.295978) (xy 380.215076 -231.263791) (xy 380.25915 -231.238345)
			(xy 380.306736 -231.220298) (xy 380.3566 -231.210118) (xy 380.407452 -231.208069) (xy 380.457973 -231.214203)
			(xy 380.506857 -231.228363) (xy 380.552836 -231.25018) (xy 380.59472 -231.27909) (xy 380.631424 -231.314345)
			(xy 380.661997 -231.355031) (xy 380.685648 -231.400094) (xy 380.701764 -231.448368) (xy 380.709928 -231.498602)
			(xy 380.71044 -231.524048) (xy 381.028968 -231.524048) (xy 381.032928 -231.474994) (xy 381.044705 -231.42721)
			(xy 381.063996 -231.381934) (xy 381.090299 -231.340338) (xy 381.122934 -231.303501) (xy 381.161055 -231.272376)
			(xy 381.203676 -231.247769) (xy 381.249692 -231.230317) (xy 381.297911 -231.220473) (xy 381.347086 -231.218492)
			(xy 381.395941 -231.224424) (xy 381.443212 -231.238116) (xy 381.487674 -231.259214) (xy 381.528177 -231.28717)
			(xy 381.56367 -231.321262) (xy 381.593235 -231.360606) (xy 381.616106 -231.404183) (xy 381.63169 -231.450864)
			(xy 381.639585 -231.499441) (xy 381.64008 -231.524048) (xy 381.969022 -231.524048) (xy 381.972982 -231.474994)
			(xy 381.984759 -231.42721) (xy 382.00405 -231.381934) (xy 382.030353 -231.340338) (xy 382.062988 -231.303501)
			(xy 382.101109 -231.272376) (xy 382.14373 -231.247769) (xy 382.189746 -231.230317) (xy 382.237965 -231.220473)
			(xy 382.28714 -231.218492) (xy 382.335995 -231.224424) (xy 382.383266 -231.238116) (xy 382.427728 -231.259214)
			(xy 382.468231 -231.28717) (xy 382.503724 -231.321262) (xy 382.533289 -231.360606) (xy 382.55616 -231.404183)
			(xy 382.571744 -231.450864) (xy 382.579639 -231.499441) (xy 382.580134 -231.524048) (xy 382.909076 -231.524048)
			(xy 382.913036 -231.474994) (xy 382.924813 -231.42721) (xy 382.944104 -231.381934) (xy 382.970407 -231.340338)
			(xy 383.003042 -231.303501) (xy 383.041163 -231.272376) (xy 383.083784 -231.247769) (xy 383.1298 -231.230317)
			(xy 383.178019 -231.220473) (xy 383.227194 -231.218492) (xy 383.276049 -231.224424) (xy 383.32332 -231.238116)
			(xy 383.367782 -231.259214) (xy 383.408285 -231.28717) (xy 383.443778 -231.321262) (xy 383.473343 -231.360606)
			(xy 383.496214 -231.404183) (xy 383.511798 -231.450864) (xy 383.519693 -231.499441) (xy 383.520188 -231.524048)
			(xy 383.84913 -231.524048) (xy 383.85309 -231.474994) (xy 383.864867 -231.42721) (xy 383.884158 -231.381934)
			(xy 383.910461 -231.340338) (xy 383.943096 -231.303501) (xy 383.981217 -231.272376) (xy 384.023838 -231.247769)
			(xy 384.069854 -231.230317) (xy 384.118073 -231.220473) (xy 384.167248 -231.218492) (xy 384.216103 -231.224424)
			(xy 384.263374 -231.238116) (xy 384.307836 -231.259214) (xy 384.348339 -231.28717) (xy 384.383832 -231.321262)
			(xy 384.413397 -231.360606) (xy 384.436268 -231.404183) (xy 384.451852 -231.450864) (xy 384.459747 -231.499441)
			(xy 384.460242 -231.524048) (xy 384.459747 -231.548655) (xy 384.451852 -231.597232) (xy 384.436268 -231.643913)
			(xy 384.413397 -231.68749) (xy 384.383832 -231.726834) (xy 384.348339 -231.760926) (xy 384.307836 -231.788882)
			(xy 384.263374 -231.80998) (xy 384.216103 -231.823672) (xy 384.167248 -231.829604) (xy 384.118073 -231.827623)
			(xy 384.069854 -231.817779) (xy 384.023838 -231.800327) (xy 383.981217 -231.77572) (xy 383.943096 -231.744595)
			(xy 383.910461 -231.707758) (xy 383.884158 -231.666162) (xy 383.864867 -231.620886) (xy 383.85309 -231.573102)
			(xy 383.84913 -231.524048) (xy 383.520188 -231.524048) (xy 383.519693 -231.548655) (xy 383.511798 -231.597232)
			(xy 383.496214 -231.643913) (xy 383.473343 -231.68749) (xy 383.443778 -231.726834) (xy 383.408285 -231.760926)
			(xy 383.367782 -231.788882) (xy 383.32332 -231.80998) (xy 383.276049 -231.823672) (xy 383.227194 -231.829604)
			(xy 383.178019 -231.827623) (xy 383.1298 -231.817779) (xy 383.083784 -231.800327) (xy 383.041163 -231.77572)
			(xy 383.003042 -231.744595) (xy 382.970407 -231.707758) (xy 382.944104 -231.666162) (xy 382.924813 -231.620886)
			(xy 382.913036 -231.573102) (xy 382.909076 -231.524048) (xy 382.580134 -231.524048) (xy 382.579639 -231.548655)
			(xy 382.571744 -231.597232) (xy 382.55616 -231.643913) (xy 382.533289 -231.68749) (xy 382.503724 -231.726834)
			(xy 382.468231 -231.760926) (xy 382.427728 -231.788882) (xy 382.383266 -231.80998) (xy 382.335995 -231.823672)
			(xy 382.28714 -231.829604) (xy 382.237965 -231.827623) (xy 382.189746 -231.817779) (xy 382.14373 -231.800327)
			(xy 382.101109 -231.77572) (xy 382.062988 -231.744595) (xy 382.030353 -231.707758) (xy 382.00405 -231.666162)
			(xy 381.984759 -231.620886) (xy 381.972982 -231.573102) (xy 381.969022 -231.524048) (xy 381.64008 -231.524048)
			(xy 381.639585 -231.548655) (xy 381.63169 -231.597232) (xy 381.616106 -231.643913) (xy 381.593235 -231.68749)
			(xy 381.56367 -231.726834) (xy 381.528177 -231.760926) (xy 381.487674 -231.788882) (xy 381.443212 -231.80998)
			(xy 381.395941 -231.823672) (xy 381.347086 -231.829604) (xy 381.297911 -231.827623) (xy 381.249692 -231.817779)
			(xy 381.203676 -231.800327) (xy 381.161055 -231.77572) (xy 381.122934 -231.744595) (xy 381.090299 -231.707758)
			(xy 381.063996 -231.666162) (xy 381.044705 -231.620886) (xy 381.032928 -231.573102) (xy 381.028968 -231.524048)
			(xy 380.71044 -231.524048) (xy 380.709928 -231.549494) (xy 380.701764 -231.599728) (xy 380.685648 -231.648002)
			(xy 380.661997 -231.693065) (xy 380.631424 -231.733751) (xy 380.59472 -231.769006) (xy 380.552836 -231.797916)
			(xy 380.506857 -231.819733) (xy 380.457973 -231.833893) (xy 380.407452 -231.840027) (xy 380.3566 -231.837978)
			(xy 380.306736 -231.827798) (xy 380.25915 -231.809751) (xy 380.215076 -231.784305) (xy 380.175654 -231.752118)
			(xy 380.141906 -231.714024) (xy 380.114705 -231.67101) (xy 380.094757 -231.62419) (xy 380.082578 -231.574776)
			(xy 380.078483 -231.524048) (xy 379.77064 -231.524048) (xy 379.770128 -231.549494) (xy 379.761964 -231.599728)
			(xy 379.745848 -231.648002) (xy 379.722197 -231.693065) (xy 379.691624 -231.733751) (xy 379.65492 -231.769006)
			(xy 379.613036 -231.797916) (xy 379.567057 -231.819733) (xy 379.518173 -231.833893) (xy 379.467652 -231.840027)
			(xy 379.4168 -231.837978) (xy 379.366936 -231.827798) (xy 379.31935 -231.809751) (xy 379.275276 -231.784305)
			(xy 379.235854 -231.752118) (xy 379.202106 -231.714024) (xy 379.174905 -231.67101) (xy 379.154957 -231.62419)
			(xy 379.142778 -231.574776) (xy 379.138683 -231.524048) (xy 378.820172 -231.524048) (xy 378.819677 -231.548655)
			(xy 378.811782 -231.597232) (xy 378.796198 -231.643913) (xy 378.773327 -231.68749) (xy 378.743762 -231.726834)
			(xy 378.708269 -231.760926) (xy 378.667766 -231.788882) (xy 378.623304 -231.80998) (xy 378.576033 -231.823672)
			(xy 378.527178 -231.829604) (xy 378.478003 -231.827623) (xy 378.429784 -231.817779) (xy 378.383768 -231.800327)
			(xy 378.341147 -231.77572) (xy 378.303026 -231.744595) (xy 378.270391 -231.707758) (xy 378.244088 -231.666162)
			(xy 378.224797 -231.620886) (xy 378.21302 -231.573102) (xy 378.20906 -231.524048) (xy 377.890532 -231.524048)
			(xy 377.89002 -231.549494) (xy 377.881856 -231.599728) (xy 377.86574 -231.648002) (xy 377.842089 -231.693065)
			(xy 377.811516 -231.733751) (xy 377.774812 -231.769006) (xy 377.732928 -231.797916) (xy 377.686949 -231.819733)
			(xy 377.638065 -231.833893) (xy 377.587544 -231.840027) (xy 377.536692 -231.837978) (xy 377.486828 -231.827798)
			(xy 377.439242 -231.809751) (xy 377.395168 -231.784305) (xy 377.355746 -231.752118) (xy 377.321998 -231.714024)
			(xy 377.294797 -231.67101) (xy 377.274849 -231.62419) (xy 377.26267 -231.574776) (xy 377.258575 -231.524048)
			(xy 376.940064 -231.524048) (xy 376.939569 -231.548655) (xy 376.931674 -231.597232) (xy 376.91609 -231.643913)
			(xy 376.893219 -231.68749) (xy 376.863654 -231.726834) (xy 376.828161 -231.760926) (xy 376.787658 -231.788882)
			(xy 376.743196 -231.80998) (xy 376.695925 -231.823672) (xy 376.64707 -231.829604) (xy 376.597895 -231.827623)
			(xy 376.549676 -231.817779) (xy 376.50366 -231.800327) (xy 376.461039 -231.77572) (xy 376.422918 -231.744595)
			(xy 376.390283 -231.707758) (xy 376.36398 -231.666162) (xy 376.344689 -231.620886) (xy 376.332912 -231.573102)
			(xy 376.328952 -231.524048) (xy 376.010927 -231.524048) (xy 376.007035 -231.573451) (xy 375.995456 -231.62166)
			(xy 375.976478 -231.667463) (xy 375.950567 -231.709733) (xy 375.918363 -231.747429) (xy 375.880657 -231.779622)
			(xy 375.859802 -231.793034) (xy 375.850557 -231.799452) (xy 375.838291 -231.818288) (xy 375.83518 -231.840549)
			(xy 375.837958 -231.851454) (xy 375.848879 -231.88738) (xy 375.867809 -231.960053) (xy 375.875804 -231.996742)
			(xy 375.875804 -231.99725) (xy 375.878862 -232.008639) (xy 375.893578 -232.027029) (xy 375.903998 -232.032556)
			(xy 375.975372 -232.06583) (xy 375.999756 -232.064814) (xy 376.010424 -232.058718) (xy 376.03416 -232.046014)
			(xy 376.08489 -232.028003) (xy 376.13794 -232.018861) (xy 376.164856 -232.018332) (xy 376.189673 -232.01879)
			(xy 376.238698 -232.026549) (xy 376.285905 -232.041881) (xy 376.330132 -232.064411) (xy 376.37029 -232.093582)
			(xy 376.405389 -232.128677) (xy 376.434566 -232.16883) (xy 376.457102 -232.213054) (xy 376.472441 -232.260259)
			(xy 376.480206 -232.309283) (xy 376.480206 -232.334054) (xy 376.788675 -232.334054) (xy 376.79277 -232.283326)
			(xy 376.804949 -232.233912) (xy 376.824897 -232.187092) (xy 376.852098 -232.144078) (xy 376.885846 -232.105984)
			(xy 376.925268 -232.073797) (xy 376.969342 -232.048351) (xy 377.016928 -232.030304) (xy 377.066792 -232.020124)
			(xy 377.117644 -232.018075) (xy 377.168165 -232.024209) (xy 377.217049 -232.038369) (xy 377.263028 -232.060186)
			(xy 377.304912 -232.089096) (xy 377.341616 -232.124351) (xy 377.372189 -232.165037) (xy 377.39584 -232.2101)
			(xy 377.411956 -232.258374) (xy 377.42012 -232.308608) (xy 377.420632 -232.334054) (xy 378.668529 -232.334054)
			(xy 378.672624 -232.283326) (xy 378.684803 -232.233912) (xy 378.704751 -232.187092) (xy 378.731952 -232.144078)
			(xy 378.7657 -232.105984) (xy 378.805122 -232.073797) (xy 378.849196 -232.048351) (xy 378.896782 -232.030304)
			(xy 378.946646 -232.020124) (xy 378.997498 -232.018075) (xy 379.048019 -232.024209) (xy 379.096903 -232.038369)
			(xy 379.142882 -232.060186) (xy 379.184766 -232.089096) (xy 379.22147 -232.124351) (xy 379.252043 -232.165037)
			(xy 379.275694 -232.2101) (xy 379.29181 -232.258374) (xy 379.299974 -232.308608) (xy 379.300486 -232.334054)
			(xy 379.619014 -232.334054) (xy 379.622974 -232.285) (xy 379.634751 -232.237216) (xy 379.654042 -232.19194)
			(xy 379.680345 -232.150344) (xy 379.71298 -232.113507) (xy 379.751101 -232.082382) (xy 379.793722 -232.057775)
			(xy 379.839738 -232.040323) (xy 379.887957 -232.030479) (xy 379.937132 -232.028498) (xy 379.985987 -232.03443)
			(xy 380.033258 -232.048122) (xy 380.07772 -232.06922) (xy 380.118223 -232.097176) (xy 380.153716 -232.131268)
			(xy 380.183281 -232.170612) (xy 380.206152 -232.214189) (xy 380.221736 -232.26087) (xy 380.229631 -232.309447)
			(xy 380.230126 -232.334054) (xy 380.548637 -232.334054) (xy 380.552732 -232.283326) (xy 380.564911 -232.233912)
			(xy 380.584859 -232.187092) (xy 380.61206 -232.144078) (xy 380.645808 -232.105984) (xy 380.68523 -232.073797)
			(xy 380.729304 -232.048351) (xy 380.77689 -232.030304) (xy 380.826754 -232.020124) (xy 380.877606 -232.018075)
			(xy 380.928127 -232.024209) (xy 380.977011 -232.038369) (xy 381.02299 -232.060186) (xy 381.064874 -232.089096)
			(xy 381.101578 -232.124351) (xy 381.132151 -232.165037) (xy 381.155802 -232.2101) (xy 381.171918 -232.258374)
			(xy 381.180082 -232.308608) (xy 381.180594 -232.334054) (xy 381.499122 -232.334054) (xy 381.503082 -232.285)
			(xy 381.514859 -232.237216) (xy 381.53415 -232.19194) (xy 381.560453 -232.150344) (xy 381.593088 -232.113507)
			(xy 381.631209 -232.082382) (xy 381.67383 -232.057775) (xy 381.719846 -232.040323) (xy 381.768065 -232.030479)
			(xy 381.81724 -232.028498) (xy 381.866095 -232.03443) (xy 381.913366 -232.048122) (xy 381.957828 -232.06922)
			(xy 381.998331 -232.097176) (xy 382.033824 -232.131268) (xy 382.063389 -232.170612) (xy 382.08626 -232.214189)
			(xy 382.101844 -232.26087) (xy 382.109739 -232.309447) (xy 382.110234 -232.334054) (xy 382.438922 -232.334054)
			(xy 382.442882 -232.285) (xy 382.454659 -232.237216) (xy 382.47395 -232.19194) (xy 382.500253 -232.150344)
			(xy 382.532888 -232.113507) (xy 382.571009 -232.082382) (xy 382.61363 -232.057775) (xy 382.659646 -232.040323)
			(xy 382.707865 -232.030479) (xy 382.75704 -232.028498) (xy 382.805895 -232.03443) (xy 382.853166 -232.048122)
			(xy 382.897628 -232.06922) (xy 382.938131 -232.097176) (xy 382.973624 -232.131268) (xy 383.003189 -232.170612)
			(xy 383.02606 -232.214189) (xy 383.041644 -232.26087) (xy 383.049539 -232.309447) (xy 383.050034 -232.334054)
			(xy 383.378976 -232.334054) (xy 383.382936 -232.285) (xy 383.394713 -232.237216) (xy 383.414004 -232.19194)
			(xy 383.440307 -232.150344) (xy 383.472942 -232.113507) (xy 383.511063 -232.082382) (xy 383.553684 -232.057775)
			(xy 383.5997 -232.040323) (xy 383.647919 -232.030479) (xy 383.697094 -232.028498) (xy 383.745949 -232.03443)
			(xy 383.79322 -232.048122) (xy 383.837682 -232.06922) (xy 383.878185 -232.097176) (xy 383.913678 -232.131268)
			(xy 383.943243 -232.170612) (xy 383.966114 -232.214189) (xy 383.981698 -232.26087) (xy 383.989593 -232.309447)
			(xy 383.990088 -232.334054) (xy 383.989593 -232.358661) (xy 383.981698 -232.407238) (xy 383.966114 -232.453919)
			(xy 383.943243 -232.497496) (xy 383.913678 -232.53684) (xy 383.878185 -232.570932) (xy 383.837682 -232.598888)
			(xy 383.79322 -232.619986) (xy 383.745949 -232.633678) (xy 383.697094 -232.63961) (xy 383.647919 -232.637629)
			(xy 383.5997 -232.627785) (xy 383.553684 -232.610333) (xy 383.511063 -232.585726) (xy 383.472942 -232.554601)
			(xy 383.440307 -232.517764) (xy 383.414004 -232.476168) (xy 383.394713 -232.430892) (xy 383.382936 -232.383108)
			(xy 383.378976 -232.334054) (xy 383.050034 -232.334054) (xy 383.049539 -232.358661) (xy 383.041644 -232.407238)
			(xy 383.02606 -232.453919) (xy 383.003189 -232.497496) (xy 382.973624 -232.53684) (xy 382.938131 -232.570932)
			(xy 382.897628 -232.598888) (xy 382.853166 -232.619986) (xy 382.805895 -232.633678) (xy 382.75704 -232.63961)
			(xy 382.707865 -232.637629) (xy 382.659646 -232.627785) (xy 382.61363 -232.610333) (xy 382.571009 -232.585726)
			(xy 382.532888 -232.554601) (xy 382.500253 -232.517764) (xy 382.47395 -232.476168) (xy 382.454659 -232.430892)
			(xy 382.442882 -232.383108) (xy 382.438922 -232.334054) (xy 382.110234 -232.334054) (xy 382.109739 -232.358661)
			(xy 382.101844 -232.407238) (xy 382.08626 -232.453919) (xy 382.063389 -232.497496) (xy 382.033824 -232.53684)
			(xy 381.998331 -232.570932) (xy 381.957828 -232.598888) (xy 381.913366 -232.619986) (xy 381.866095 -232.633678)
			(xy 381.81724 -232.63961) (xy 381.768065 -232.637629) (xy 381.719846 -232.627785) (xy 381.67383 -232.610333)
			(xy 381.631209 -232.585726) (xy 381.593088 -232.554601) (xy 381.560453 -232.517764) (xy 381.53415 -232.476168)
			(xy 381.514859 -232.430892) (xy 381.503082 -232.383108) (xy 381.499122 -232.334054) (xy 381.180594 -232.334054)
			(xy 381.180082 -232.3595) (xy 381.171918 -232.409734) (xy 381.155802 -232.458008) (xy 381.132151 -232.503071)
			(xy 381.101578 -232.543757) (xy 381.064874 -232.579012) (xy 381.02299 -232.607922) (xy 380.977011 -232.629739)
			(xy 380.928127 -232.643899) (xy 380.877606 -232.650033) (xy 380.826754 -232.647984) (xy 380.77689 -232.637804)
			(xy 380.729304 -232.619757) (xy 380.68523 -232.594311) (xy 380.645808 -232.562124) (xy 380.61206 -232.52403)
			(xy 380.584859 -232.481016) (xy 380.564911 -232.434196) (xy 380.552732 -232.384782) (xy 380.548637 -232.334054)
			(xy 380.230126 -232.334054) (xy 380.229631 -232.358661) (xy 380.221736 -232.407238) (xy 380.206152 -232.453919)
			(xy 380.183281 -232.497496) (xy 380.153716 -232.53684) (xy 380.118223 -232.570932) (xy 380.07772 -232.598888)
			(xy 380.033258 -232.619986) (xy 379.985987 -232.633678) (xy 379.937132 -232.63961) (xy 379.887957 -232.637629)
			(xy 379.839738 -232.627785) (xy 379.793722 -232.610333) (xy 379.751101 -232.585726) (xy 379.71298 -232.554601)
			(xy 379.680345 -232.517764) (xy 379.654042 -232.476168) (xy 379.634751 -232.430892) (xy 379.622974 -232.383108)
			(xy 379.619014 -232.334054) (xy 379.300486 -232.334054) (xy 379.299974 -232.3595) (xy 379.29181 -232.409734)
			(xy 379.275694 -232.458008) (xy 379.252043 -232.503071) (xy 379.22147 -232.543757) (xy 379.184766 -232.579012)
			(xy 379.142882 -232.607922) (xy 379.096903 -232.629739) (xy 379.048019 -232.643899) (xy 378.997498 -232.650033)
			(xy 378.946646 -232.647984) (xy 378.896782 -232.637804) (xy 378.849196 -232.619757) (xy 378.805122 -232.594311)
			(xy 378.7657 -232.562124) (xy 378.731952 -232.52403) (xy 378.704751 -232.481016) (xy 378.684803 -232.434196)
			(xy 378.672624 -232.384782) (xy 378.668529 -232.334054) (xy 377.420632 -232.334054) (xy 377.42012 -232.3595)
			(xy 377.411956 -232.409734) (xy 377.39584 -232.458008) (xy 377.372189 -232.503071) (xy 377.341616 -232.543757)
			(xy 377.304912 -232.579012) (xy 377.263028 -232.607922) (xy 377.217049 -232.629739) (xy 377.168165 -232.643899)
			(xy 377.117644 -232.650033) (xy 377.066792 -232.647984) (xy 377.016928 -232.637804) (xy 376.969342 -232.619757)
			(xy 376.925268 -232.594311) (xy 376.885846 -232.562124) (xy 376.852098 -232.52403) (xy 376.824897 -232.481016)
			(xy 376.804949 -232.434196) (xy 376.79277 -232.384782) (xy 376.788675 -232.334054) (xy 376.480206 -232.334054)
			(xy 376.480206 -232.358917) (xy 376.472441 -232.407941) (xy 376.457102 -232.455146) (xy 376.434566 -232.49937)
			(xy 376.405389 -232.539523) (xy 376.37029 -232.574618) (xy 376.330132 -232.603789) (xy 376.285905 -232.626319)
			(xy 376.238698 -232.641651) (xy 376.189673 -232.64941) (xy 376.164856 -232.649776) (xy 376.137942 -232.649227)
			(xy 376.084895 -232.640085) (xy 376.034168 -232.622076) (xy 376.010424 -232.60939) (xy 375.999756 -232.603294)
			(xy 375.975372 -232.602278) (xy 375.903998 -232.635552) (xy 375.893612 -232.641108) (xy 375.878937 -232.659502)
			(xy 375.875804 -232.670858) (xy 375.875804 -232.671366) (xy 375.867821 -232.708058) (xy 375.848892 -232.780731)
			(xy 375.837958 -232.816654) (xy 375.83514 -232.827562) (xy 375.838204 -232.849854) (xy 375.850522 -232.868684)
			(xy 375.859802 -232.875074) (xy 375.880705 -232.88842) (xy 375.918419 -232.920621) (xy 375.95063 -232.958327)
			(xy 375.976546 -233.000607) (xy 375.995529 -233.046421) (xy 376.00711 -233.094641) (xy 376.011003 -233.14406)
			(xy 376.328952 -233.14406) (xy 376.332912 -233.095006) (xy 376.344689 -233.047222) (xy 376.36398 -233.001946)
			(xy 376.390283 -232.96035) (xy 376.422918 -232.923513) (xy 376.461039 -232.892388) (xy 376.50366 -232.867781)
			(xy 376.549676 -232.850329) (xy 376.597895 -232.840485) (xy 376.64707 -232.838504) (xy 376.695925 -232.844436)
			(xy 376.743196 -232.858128) (xy 376.787658 -232.879226) (xy 376.828161 -232.907182) (xy 376.863654 -232.941274)
			(xy 376.893219 -232.980618) (xy 376.91609 -233.024195) (xy 376.931674 -233.070876) (xy 376.939569 -233.119453)
			(xy 376.940064 -233.14406) (xy 377.258575 -233.14406) (xy 377.26267 -233.093332) (xy 377.274849 -233.043918)
			(xy 377.294797 -232.997098) (xy 377.321998 -232.954084) (xy 377.355746 -232.91599) (xy 377.395168 -232.883803)
			(xy 377.439242 -232.858357) (xy 377.486828 -232.84031) (xy 377.536692 -232.83013) (xy 377.587544 -232.828081)
			(xy 377.638065 -232.834215) (xy 377.686949 -232.848375) (xy 377.732928 -232.870192) (xy 377.774812 -232.899102)
			(xy 377.811516 -232.934357) (xy 377.842089 -232.975043) (xy 377.86574 -233.020106) (xy 377.881856 -233.06838)
			(xy 377.89002 -233.118614) (xy 377.890532 -233.14406) (xy 378.20906 -233.14406) (xy 378.21302 -233.095006)
			(xy 378.224797 -233.047222) (xy 378.244088 -233.001946) (xy 378.270391 -232.96035) (xy 378.303026 -232.923513)
			(xy 378.341147 -232.892388) (xy 378.383768 -232.867781) (xy 378.429784 -232.850329) (xy 378.478003 -232.840485)
			(xy 378.527178 -232.838504) (xy 378.576033 -232.844436) (xy 378.623304 -232.858128) (xy 378.667766 -232.879226)
			(xy 378.708269 -232.907182) (xy 378.743762 -232.941274) (xy 378.773327 -232.980618) (xy 378.796198 -233.024195)
			(xy 378.811782 -233.070876) (xy 378.819677 -233.119453) (xy 378.820172 -233.14406) (xy 379.138683 -233.14406)
			(xy 379.142778 -233.093332) (xy 379.154957 -233.043918) (xy 379.174905 -232.997098) (xy 379.202106 -232.954084)
			(xy 379.235854 -232.91599) (xy 379.275276 -232.883803) (xy 379.31935 -232.858357) (xy 379.366936 -232.84031)
			(xy 379.4168 -232.83013) (xy 379.467652 -232.828081) (xy 379.518173 -232.834215) (xy 379.567057 -232.848375)
			(xy 379.613036 -232.870192) (xy 379.65492 -232.899102) (xy 379.691624 -232.934357) (xy 379.722197 -232.975043)
			(xy 379.745848 -233.020106) (xy 379.761964 -233.06838) (xy 379.770128 -233.118614) (xy 379.77064 -233.14406)
			(xy 380.078483 -233.14406) (xy 380.082578 -233.093332) (xy 380.094757 -233.043918) (xy 380.114705 -232.997098)
			(xy 380.141906 -232.954084) (xy 380.175654 -232.91599) (xy 380.215076 -232.883803) (xy 380.25915 -232.858357)
			(xy 380.306736 -232.84031) (xy 380.3566 -232.83013) (xy 380.407452 -232.828081) (xy 380.457973 -232.834215)
			(xy 380.506857 -232.848375) (xy 380.552836 -232.870192) (xy 380.59472 -232.899102) (xy 380.631424 -232.934357)
			(xy 380.661997 -232.975043) (xy 380.685648 -233.020106) (xy 380.701764 -233.06838) (xy 380.709928 -233.118614)
			(xy 380.71044 -233.14406) (xy 381.028968 -233.14406) (xy 381.032928 -233.095006) (xy 381.044705 -233.047222)
			(xy 381.063996 -233.001946) (xy 381.090299 -232.96035) (xy 381.122934 -232.923513) (xy 381.161055 -232.892388)
			(xy 381.203676 -232.867781) (xy 381.249692 -232.850329) (xy 381.297911 -232.840485) (xy 381.347086 -232.838504)
			(xy 381.395941 -232.844436) (xy 381.443212 -232.858128) (xy 381.487674 -232.879226) (xy 381.528177 -232.907182)
			(xy 381.56367 -232.941274) (xy 381.593235 -232.980618) (xy 381.616106 -233.024195) (xy 381.63169 -233.070876)
			(xy 381.639585 -233.119453) (xy 381.64008 -233.14406) (xy 381.969022 -233.14406) (xy 381.972982 -233.095006)
			(xy 381.984759 -233.047222) (xy 382.00405 -233.001946) (xy 382.030353 -232.96035) (xy 382.062988 -232.923513)
			(xy 382.101109 -232.892388) (xy 382.14373 -232.867781) (xy 382.189746 -232.850329) (xy 382.237965 -232.840485)
			(xy 382.28714 -232.838504) (xy 382.335995 -232.844436) (xy 382.383266 -232.858128) (xy 382.427728 -232.879226)
			(xy 382.468231 -232.907182) (xy 382.503724 -232.941274) (xy 382.533289 -232.980618) (xy 382.55616 -233.024195)
			(xy 382.571744 -233.070876) (xy 382.579639 -233.119453) (xy 382.580134 -233.14406) (xy 382.909076 -233.14406)
			(xy 382.913036 -233.095006) (xy 382.924813 -233.047222) (xy 382.944104 -233.001946) (xy 382.970407 -232.96035)
			(xy 383.003042 -232.923513) (xy 383.041163 -232.892388) (xy 383.083784 -232.867781) (xy 383.1298 -232.850329)
			(xy 383.178019 -232.840485) (xy 383.227194 -232.838504) (xy 383.276049 -232.844436) (xy 383.32332 -232.858128)
			(xy 383.367782 -232.879226) (xy 383.408285 -232.907182) (xy 383.443778 -232.941274) (xy 383.473343 -232.980618)
			(xy 383.496214 -233.024195) (xy 383.511798 -233.070876) (xy 383.519693 -233.119453) (xy 383.520188 -233.14406)
			(xy 383.84913 -233.14406) (xy 383.85309 -233.095006) (xy 383.864867 -233.047222) (xy 383.884158 -233.001946)
			(xy 383.910461 -232.96035) (xy 383.943096 -232.923513) (xy 383.981217 -232.892388) (xy 384.023838 -232.867781)
			(xy 384.069854 -232.850329) (xy 384.118073 -232.840485) (xy 384.167248 -232.838504) (xy 384.216103 -232.844436)
			(xy 384.263374 -232.858128) (xy 384.307836 -232.879226) (xy 384.348339 -232.907182) (xy 384.383832 -232.941274)
			(xy 384.413397 -232.980618) (xy 384.436268 -233.024195) (xy 384.451852 -233.070876) (xy 384.459747 -233.119453)
			(xy 384.460242 -233.14406) (xy 384.459747 -233.168667) (xy 384.451852 -233.217244) (xy 384.436268 -233.263925)
			(xy 384.413397 -233.307502) (xy 384.383832 -233.346846) (xy 384.348339 -233.380938) (xy 384.307836 -233.408894)
			(xy 384.263374 -233.429992) (xy 384.216103 -233.443684) (xy 384.167248 -233.449616) (xy 384.118073 -233.447635)
			(xy 384.069854 -233.437791) (xy 384.023838 -233.420339) (xy 383.981217 -233.395732) (xy 383.943096 -233.364607)
			(xy 383.910461 -233.32777) (xy 383.884158 -233.286174) (xy 383.864867 -233.240898) (xy 383.85309 -233.193114)
			(xy 383.84913 -233.14406) (xy 383.520188 -233.14406) (xy 383.519693 -233.168667) (xy 383.511798 -233.217244)
			(xy 383.496214 -233.263925) (xy 383.473343 -233.307502) (xy 383.443778 -233.346846) (xy 383.408285 -233.380938)
			(xy 383.367782 -233.408894) (xy 383.32332 -233.429992) (xy 383.276049 -233.443684) (xy 383.227194 -233.449616)
			(xy 383.178019 -233.447635) (xy 383.1298 -233.437791) (xy 383.083784 -233.420339) (xy 383.041163 -233.395732)
			(xy 383.003042 -233.364607) (xy 382.970407 -233.32777) (xy 382.944104 -233.286174) (xy 382.924813 -233.240898)
			(xy 382.913036 -233.193114) (xy 382.909076 -233.14406) (xy 382.580134 -233.14406) (xy 382.579639 -233.168667)
			(xy 382.571744 -233.217244) (xy 382.55616 -233.263925) (xy 382.533289 -233.307502) (xy 382.503724 -233.346846)
			(xy 382.468231 -233.380938) (xy 382.427728 -233.408894) (xy 382.383266 -233.429992) (xy 382.335995 -233.443684)
			(xy 382.28714 -233.449616) (xy 382.237965 -233.447635) (xy 382.189746 -233.437791) (xy 382.14373 -233.420339)
			(xy 382.101109 -233.395732) (xy 382.062988 -233.364607) (xy 382.030353 -233.32777) (xy 382.00405 -233.286174)
			(xy 381.984759 -233.240898) (xy 381.972982 -233.193114) (xy 381.969022 -233.14406) (xy 381.64008 -233.14406)
			(xy 381.639585 -233.168667) (xy 381.63169 -233.217244) (xy 381.616106 -233.263925) (xy 381.593235 -233.307502)
			(xy 381.56367 -233.346846) (xy 381.528177 -233.380938) (xy 381.487674 -233.408894) (xy 381.443212 -233.429992)
			(xy 381.395941 -233.443684) (xy 381.347086 -233.449616) (xy 381.297911 -233.447635) (xy 381.249692 -233.437791)
			(xy 381.203676 -233.420339) (xy 381.161055 -233.395732) (xy 381.122934 -233.364607) (xy 381.090299 -233.32777)
			(xy 381.063996 -233.286174) (xy 381.044705 -233.240898) (xy 381.032928 -233.193114) (xy 381.028968 -233.14406)
			(xy 380.71044 -233.14406) (xy 380.709928 -233.169506) (xy 380.701764 -233.21974) (xy 380.685648 -233.268014)
			(xy 380.661997 -233.313077) (xy 380.631424 -233.353763) (xy 380.59472 -233.389018) (xy 380.552836 -233.417928)
			(xy 380.506857 -233.439745) (xy 380.457973 -233.453905) (xy 380.407452 -233.460039) (xy 380.3566 -233.45799)
			(xy 380.306736 -233.44781) (xy 380.25915 -233.429763) (xy 380.215076 -233.404317) (xy 380.175654 -233.37213)
			(xy 380.141906 -233.334036) (xy 380.114705 -233.291022) (xy 380.094757 -233.244202) (xy 380.082578 -233.194788)
			(xy 380.078483 -233.14406) (xy 379.77064 -233.14406) (xy 379.770128 -233.169506) (xy 379.761964 -233.21974)
			(xy 379.745848 -233.268014) (xy 379.722197 -233.313077) (xy 379.691624 -233.353763) (xy 379.65492 -233.389018)
			(xy 379.613036 -233.417928) (xy 379.567057 -233.439745) (xy 379.518173 -233.453905) (xy 379.467652 -233.460039)
			(xy 379.4168 -233.45799) (xy 379.366936 -233.44781) (xy 379.31935 -233.429763) (xy 379.275276 -233.404317)
			(xy 379.235854 -233.37213) (xy 379.202106 -233.334036) (xy 379.174905 -233.291022) (xy 379.154957 -233.244202)
			(xy 379.142778 -233.194788) (xy 379.138683 -233.14406) (xy 378.820172 -233.14406) (xy 378.819677 -233.168667)
			(xy 378.811782 -233.217244) (xy 378.796198 -233.263925) (xy 378.773327 -233.307502) (xy 378.743762 -233.346846)
			(xy 378.708269 -233.380938) (xy 378.667766 -233.408894) (xy 378.623304 -233.429992) (xy 378.576033 -233.443684)
			(xy 378.527178 -233.449616) (xy 378.478003 -233.447635) (xy 378.429784 -233.437791) (xy 378.383768 -233.420339)
			(xy 378.341147 -233.395732) (xy 378.303026 -233.364607) (xy 378.270391 -233.32777) (xy 378.244088 -233.286174)
			(xy 378.224797 -233.240898) (xy 378.21302 -233.193114) (xy 378.20906 -233.14406) (xy 377.890532 -233.14406)
			(xy 377.89002 -233.169506) (xy 377.881856 -233.21974) (xy 377.86574 -233.268014) (xy 377.842089 -233.313077)
			(xy 377.811516 -233.353763) (xy 377.774812 -233.389018) (xy 377.732928 -233.417928) (xy 377.686949 -233.439745)
			(xy 377.638065 -233.453905) (xy 377.587544 -233.460039) (xy 377.536692 -233.45799) (xy 377.486828 -233.44781)
			(xy 377.439242 -233.429763) (xy 377.395168 -233.404317) (xy 377.355746 -233.37213) (xy 377.321998 -233.334036)
			(xy 377.294797 -233.291022) (xy 377.274849 -233.244202) (xy 377.26267 -233.194788) (xy 377.258575 -233.14406)
			(xy 376.940064 -233.14406) (xy 376.939569 -233.168667) (xy 376.931674 -233.217244) (xy 376.91609 -233.263925)
			(xy 376.893219 -233.307502) (xy 376.863654 -233.346846) (xy 376.828161 -233.380938) (xy 376.787658 -233.408894)
			(xy 376.743196 -233.429992) (xy 376.695925 -233.443684) (xy 376.64707 -233.449616) (xy 376.597895 -233.447635)
			(xy 376.549676 -233.437791) (xy 376.50366 -233.420339) (xy 376.461039 -233.395732) (xy 376.422918 -233.364607)
			(xy 376.390283 -233.32777) (xy 376.36398 -233.286174) (xy 376.344689 -233.240898) (xy 376.332912 -233.193114)
			(xy 376.328952 -233.14406) (xy 376.011003 -233.14406) (xy 376.011004 -233.144079) (xy 376.007116 -233.193518)
			(xy 375.995542 -233.241739) (xy 375.976565 -233.287556) (xy 375.950655 -233.32984) (xy 375.918448 -233.367549)
			(xy 375.880739 -233.399756) (xy 375.859802 -233.413046) (xy 375.850559 -233.419464) (xy 375.838297 -233.4383)
			(xy 375.835191 -233.460559) (xy 375.837958 -233.471466) (xy 375.848879 -233.507392) (xy 375.867808 -233.580066)
			(xy 375.875804 -233.616754) (xy 375.875804 -233.617262) (xy 375.878846 -233.628664) (xy 375.89355 -233.647084)
			(xy 375.903998 -233.652568) (xy 375.975372 -233.685842) (xy 375.999756 -233.684826) (xy 376.010424 -233.67873)
			(xy 376.03416 -233.666026) (xy 376.084889 -233.648014) (xy 376.13794 -233.638871) (xy 376.164856 -233.638344)
			(xy 376.189672 -233.638802) (xy 376.238695 -233.64656) (xy 376.285901 -233.661892) (xy 376.330126 -233.684421)
			(xy 376.370282 -233.713591) (xy 376.40538 -233.748684) (xy 376.434556 -233.788836) (xy 376.457091 -233.833059)
			(xy 376.472429 -233.880262) (xy 376.480194 -233.929284) (xy 376.480194 -233.954066) (xy 376.788675 -233.954066)
			(xy 376.79277 -233.903338) (xy 376.804949 -233.853924) (xy 376.824897 -233.807104) (xy 376.852098 -233.76409)
			(xy 376.885846 -233.725996) (xy 376.925268 -233.693809) (xy 376.969342 -233.668363) (xy 377.016928 -233.650316)
			(xy 377.066792 -233.640136) (xy 377.117644 -233.638087) (xy 377.168165 -233.644221) (xy 377.217049 -233.658381)
			(xy 377.263028 -233.680198) (xy 377.304912 -233.709108) (xy 377.341616 -233.744363) (xy 377.372189 -233.785049)
			(xy 377.39584 -233.830112) (xy 377.411956 -233.878386) (xy 377.42012 -233.92862) (xy 377.420632 -233.954066)
			(xy 377.738906 -233.954066) (xy 377.742866 -233.905012) (xy 377.754643 -233.857228) (xy 377.773934 -233.811952)
			(xy 377.800237 -233.770356) (xy 377.832872 -233.733519) (xy 377.870993 -233.702394) (xy 377.913614 -233.677787)
			(xy 377.95963 -233.660335) (xy 378.007849 -233.650491) (xy 378.057024 -233.64851) (xy 378.105879 -233.654442)
			(xy 378.15315 -233.668134) (xy 378.197612 -233.689232) (xy 378.238115 -233.717188) (xy 378.273608 -233.75128)
			(xy 378.303173 -233.790624) (xy 378.326044 -233.834201) (xy 378.341628 -233.880882) (xy 378.349523 -233.929459)
			(xy 378.350018 -233.954066) (xy 378.668529 -233.954066) (xy 378.672624 -233.903338) (xy 378.684803 -233.853924)
			(xy 378.704751 -233.807104) (xy 378.731952 -233.76409) (xy 378.7657 -233.725996) (xy 378.805122 -233.693809)
			(xy 378.849196 -233.668363) (xy 378.896782 -233.650316) (xy 378.946646 -233.640136) (xy 378.997498 -233.638087)
			(xy 379.048019 -233.644221) (xy 379.096903 -233.658381) (xy 379.142882 -233.680198) (xy 379.184766 -233.709108)
			(xy 379.22147 -233.744363) (xy 379.252043 -233.785049) (xy 379.275694 -233.830112) (xy 379.29181 -233.878386)
			(xy 379.299974 -233.92862) (xy 379.300486 -233.954066) (xy 379.619014 -233.954066) (xy 379.622974 -233.905012)
			(xy 379.634751 -233.857228) (xy 379.654042 -233.811952) (xy 379.680345 -233.770356) (xy 379.71298 -233.733519)
			(xy 379.751101 -233.702394) (xy 379.793722 -233.677787) (xy 379.839738 -233.660335) (xy 379.887957 -233.650491)
			(xy 379.937132 -233.64851) (xy 379.985987 -233.654442) (xy 380.033258 -233.668134) (xy 380.07772 -233.689232)
			(xy 380.118223 -233.717188) (xy 380.153716 -233.75128) (xy 380.183281 -233.790624) (xy 380.206152 -233.834201)
			(xy 380.221736 -233.880882) (xy 380.229631 -233.929459) (xy 380.230126 -233.954066) (xy 380.548637 -233.954066)
			(xy 380.552732 -233.903338) (xy 380.564911 -233.853924) (xy 380.584859 -233.807104) (xy 380.61206 -233.76409)
			(xy 380.645808 -233.725996) (xy 380.68523 -233.693809) (xy 380.729304 -233.668363) (xy 380.77689 -233.650316)
			(xy 380.826754 -233.640136) (xy 380.877606 -233.638087) (xy 380.928127 -233.644221) (xy 380.977011 -233.658381)
			(xy 381.02299 -233.680198) (xy 381.064874 -233.709108) (xy 381.101578 -233.744363) (xy 381.132151 -233.785049)
			(xy 381.155802 -233.830112) (xy 381.171918 -233.878386) (xy 381.180082 -233.92862) (xy 381.180594 -233.954066)
			(xy 381.499122 -233.954066) (xy 381.503082 -233.905012) (xy 381.514859 -233.857228) (xy 381.53415 -233.811952)
			(xy 381.560453 -233.770356) (xy 381.593088 -233.733519) (xy 381.631209 -233.702394) (xy 381.67383 -233.677787)
			(xy 381.719846 -233.660335) (xy 381.768065 -233.650491) (xy 381.81724 -233.64851) (xy 381.866095 -233.654442)
			(xy 381.913366 -233.668134) (xy 381.957828 -233.689232) (xy 381.998331 -233.717188) (xy 382.033824 -233.75128)
			(xy 382.063389 -233.790624) (xy 382.08626 -233.834201) (xy 382.101844 -233.880882) (xy 382.109739 -233.929459)
			(xy 382.110234 -233.954066) (xy 382.438922 -233.954066) (xy 382.442882 -233.905012) (xy 382.454659 -233.857228)
			(xy 382.47395 -233.811952) (xy 382.500253 -233.770356) (xy 382.532888 -233.733519) (xy 382.571009 -233.702394)
			(xy 382.61363 -233.677787) (xy 382.659646 -233.660335) (xy 382.707865 -233.650491) (xy 382.75704 -233.64851)
			(xy 382.805895 -233.654442) (xy 382.853166 -233.668134) (xy 382.897628 -233.689232) (xy 382.938131 -233.717188)
			(xy 382.973624 -233.75128) (xy 383.003189 -233.790624) (xy 383.02606 -233.834201) (xy 383.041644 -233.880882)
			(xy 383.049539 -233.929459) (xy 383.050034 -233.954066) (xy 383.378976 -233.954066) (xy 383.382936 -233.905012)
			(xy 383.394713 -233.857228) (xy 383.414004 -233.811952) (xy 383.440307 -233.770356) (xy 383.472942 -233.733519)
			(xy 383.511063 -233.702394) (xy 383.553684 -233.677787) (xy 383.5997 -233.660335) (xy 383.647919 -233.650491)
			(xy 383.697094 -233.64851) (xy 383.745949 -233.654442) (xy 383.79322 -233.668134) (xy 383.837682 -233.689232)
			(xy 383.878185 -233.717188) (xy 383.913678 -233.75128) (xy 383.943243 -233.790624) (xy 383.966114 -233.834201)
			(xy 383.981698 -233.880882) (xy 383.989593 -233.929459) (xy 383.990088 -233.954066) (xy 383.989593 -233.978673)
			(xy 383.981698 -234.02725) (xy 383.966114 -234.073931) (xy 383.943243 -234.117508) (xy 383.913678 -234.156852)
			(xy 383.878185 -234.190944) (xy 383.837682 -234.2189) (xy 383.79322 -234.239998) (xy 383.745949 -234.25369)
			(xy 383.697094 -234.259622) (xy 383.647919 -234.257641) (xy 383.5997 -234.247797) (xy 383.553684 -234.230345)
			(xy 383.511063 -234.205738) (xy 383.472942 -234.174613) (xy 383.440307 -234.137776) (xy 383.414004 -234.09618)
			(xy 383.394713 -234.050904) (xy 383.382936 -234.00312) (xy 383.378976 -233.954066) (xy 383.050034 -233.954066)
			(xy 383.049539 -233.978673) (xy 383.041644 -234.02725) (xy 383.02606 -234.073931) (xy 383.003189 -234.117508)
			(xy 382.973624 -234.156852) (xy 382.938131 -234.190944) (xy 382.897628 -234.2189) (xy 382.853166 -234.239998)
			(xy 382.805895 -234.25369) (xy 382.75704 -234.259622) (xy 382.707865 -234.257641) (xy 382.659646 -234.247797)
			(xy 382.61363 -234.230345) (xy 382.571009 -234.205738) (xy 382.532888 -234.174613) (xy 382.500253 -234.137776)
			(xy 382.47395 -234.09618) (xy 382.454659 -234.050904) (xy 382.442882 -234.00312) (xy 382.438922 -233.954066)
			(xy 382.110234 -233.954066) (xy 382.109739 -233.978673) (xy 382.101844 -234.02725) (xy 382.08626 -234.073931)
			(xy 382.063389 -234.117508) (xy 382.033824 -234.156852) (xy 381.998331 -234.190944) (xy 381.957828 -234.2189)
			(xy 381.913366 -234.239998) (xy 381.866095 -234.25369) (xy 381.81724 -234.259622) (xy 381.768065 -234.257641)
			(xy 381.719846 -234.247797) (xy 381.67383 -234.230345) (xy 381.631209 -234.205738) (xy 381.593088 -234.174613)
			(xy 381.560453 -234.137776) (xy 381.53415 -234.09618) (xy 381.514859 -234.050904) (xy 381.503082 -234.00312)
			(xy 381.499122 -233.954066) (xy 381.180594 -233.954066) (xy 381.180082 -233.979512) (xy 381.171918 -234.029746)
			(xy 381.155802 -234.07802) (xy 381.132151 -234.123083) (xy 381.101578 -234.163769) (xy 381.064874 -234.199024)
			(xy 381.02299 -234.227934) (xy 380.977011 -234.249751) (xy 380.928127 -234.263911) (xy 380.877606 -234.270045)
			(xy 380.826754 -234.267996) (xy 380.77689 -234.257816) (xy 380.729304 -234.239769) (xy 380.68523 -234.214323)
			(xy 380.645808 -234.182136) (xy 380.61206 -234.144042) (xy 380.584859 -234.101028) (xy 380.564911 -234.054208)
			(xy 380.552732 -234.004794) (xy 380.548637 -233.954066) (xy 380.230126 -233.954066) (xy 380.229631 -233.978673)
			(xy 380.221736 -234.02725) (xy 380.206152 -234.073931) (xy 380.183281 -234.117508) (xy 380.153716 -234.156852)
			(xy 380.118223 -234.190944) (xy 380.07772 -234.2189) (xy 380.033258 -234.239998) (xy 379.985987 -234.25369)
			(xy 379.937132 -234.259622) (xy 379.887957 -234.257641) (xy 379.839738 -234.247797) (xy 379.793722 -234.230345)
			(xy 379.751101 -234.205738) (xy 379.71298 -234.174613) (xy 379.680345 -234.137776) (xy 379.654042 -234.09618)
			(xy 379.634751 -234.050904) (xy 379.622974 -234.00312) (xy 379.619014 -233.954066) (xy 379.300486 -233.954066)
			(xy 379.299974 -233.979512) (xy 379.29181 -234.029746) (xy 379.275694 -234.07802) (xy 379.252043 -234.123083)
			(xy 379.22147 -234.163769) (xy 379.184766 -234.199024) (xy 379.142882 -234.227934) (xy 379.096903 -234.249751)
			(xy 379.048019 -234.263911) (xy 378.997498 -234.270045) (xy 378.946646 -234.267996) (xy 378.896782 -234.257816)
			(xy 378.849196 -234.239769) (xy 378.805122 -234.214323) (xy 378.7657 -234.182136) (xy 378.731952 -234.144042)
			(xy 378.704751 -234.101028) (xy 378.684803 -234.054208) (xy 378.672624 -234.004794) (xy 378.668529 -233.954066)
			(xy 378.350018 -233.954066) (xy 378.349523 -233.978673) (xy 378.341628 -234.02725) (xy 378.326044 -234.073931)
			(xy 378.303173 -234.117508) (xy 378.273608 -234.156852) (xy 378.238115 -234.190944) (xy 378.197612 -234.2189)
			(xy 378.15315 -234.239998) (xy 378.105879 -234.25369) (xy 378.057024 -234.259622) (xy 378.007849 -234.257641)
			(xy 377.95963 -234.247797) (xy 377.913614 -234.230345) (xy 377.870993 -234.205738) (xy 377.832872 -234.174613)
			(xy 377.800237 -234.137776) (xy 377.773934 -234.09618) (xy 377.754643 -234.050904) (xy 377.742866 -234.00312)
			(xy 377.738906 -233.954066) (xy 377.420632 -233.954066) (xy 377.42012 -233.979512) (xy 377.411956 -234.029746)
			(xy 377.39584 -234.07802) (xy 377.372189 -234.123083) (xy 377.341616 -234.163769) (xy 377.304912 -234.199024)
			(xy 377.263028 -234.227934) (xy 377.217049 -234.249751) (xy 377.168165 -234.263911) (xy 377.117644 -234.270045)
			(xy 377.066792 -234.267996) (xy 377.016928 -234.257816) (xy 376.969342 -234.239769) (xy 376.925268 -234.214323)
			(xy 376.885846 -234.182136) (xy 376.852098 -234.144042) (xy 376.824897 -234.101028) (xy 376.804949 -234.054208)
			(xy 376.79277 -234.004794) (xy 376.788675 -233.954066) (xy 376.480194 -233.954066) (xy 376.480194 -233.978916)
			(xy 376.472429 -234.027938) (xy 376.457091 -234.075141) (xy 376.434556 -234.119364) (xy 376.40538 -234.159516)
			(xy 376.370282 -234.194609) (xy 376.330126 -234.223779) (xy 376.285901 -234.246308) (xy 376.238695 -234.26164)
			(xy 376.189672 -234.269398) (xy 376.164856 -234.269788) (xy 376.137942 -234.269239) (xy 376.084894 -234.260098)
			(xy 376.034168 -234.242089) (xy 376.010424 -234.229402) (xy 375.999756 -234.223306) (xy 375.975372 -234.22229)
			(xy 375.903998 -234.255564) (xy 375.893613 -234.261121) (xy 375.878942 -234.279516) (xy 375.875804 -234.29087)
			(xy 375.875804 -234.291378) (xy 375.867821 -234.32807) (xy 375.848891 -234.400743) (xy 375.837958 -234.436666)
			(xy 375.835142 -234.447573) (xy 375.83821 -234.469861) (xy 375.85053 -234.488686) (xy 375.859802 -234.495086)
			(xy 375.880704 -234.508432) (xy 375.918416 -234.540633) (xy 375.950626 -234.578338) (xy 375.97654 -234.620617)
			(xy 375.995521 -234.66643) (xy 376.007101 -234.714649) (xy 376.010993 -234.764072) (xy 376.328952 -234.764072)
			(xy 376.332912 -234.715018) (xy 376.344689 -234.667234) (xy 376.36398 -234.621958) (xy 376.390283 -234.580362)
			(xy 376.422918 -234.543525) (xy 376.461039 -234.5124) (xy 376.50366 -234.487793) (xy 376.549676 -234.470341)
			(xy 376.597895 -234.460497) (xy 376.64707 -234.458516) (xy 376.695925 -234.464448) (xy 376.743196 -234.47814)
			(xy 376.787658 -234.499238) (xy 376.828161 -234.527194) (xy 376.863654 -234.561286) (xy 376.893219 -234.60063)
			(xy 376.91609 -234.644207) (xy 376.931674 -234.690888) (xy 376.939569 -234.739465) (xy 376.940064 -234.764072)
			(xy 377.258575 -234.764072) (xy 377.26267 -234.713344) (xy 377.274849 -234.66393) (xy 377.294797 -234.61711)
			(xy 377.321998 -234.574096) (xy 377.355746 -234.536002) (xy 377.395168 -234.503815) (xy 377.439242 -234.478369)
			(xy 377.486828 -234.460322) (xy 377.536692 -234.450142) (xy 377.587544 -234.448093) (xy 377.638065 -234.454227)
			(xy 377.686949 -234.468387) (xy 377.732928 -234.490204) (xy 377.774812 -234.519114) (xy 377.811516 -234.554369)
			(xy 377.842089 -234.595055) (xy 377.86574 -234.640118) (xy 377.881856 -234.688392) (xy 377.89002 -234.738626)
			(xy 377.890532 -234.764072) (xy 379.138683 -234.764072) (xy 379.142778 -234.713344) (xy 379.154957 -234.66393)
			(xy 379.174905 -234.61711) (xy 379.202106 -234.574096) (xy 379.235854 -234.536002) (xy 379.275276 -234.503815)
			(xy 379.31935 -234.478369) (xy 379.366936 -234.460322) (xy 379.4168 -234.450142) (xy 379.467652 -234.448093)
			(xy 379.518173 -234.454227) (xy 379.567057 -234.468387) (xy 379.613036 -234.490204) (xy 379.65492 -234.519114)
			(xy 379.691624 -234.554369) (xy 379.722197 -234.595055) (xy 379.745848 -234.640118) (xy 379.761964 -234.688392)
			(xy 379.770128 -234.738626) (xy 379.77064 -234.764072) (xy 380.078483 -234.764072) (xy 380.082578 -234.713344)
			(xy 380.094757 -234.66393) (xy 380.114705 -234.61711) (xy 380.141906 -234.574096) (xy 380.175654 -234.536002)
			(xy 380.215076 -234.503815) (xy 380.25915 -234.478369) (xy 380.306736 -234.460322) (xy 380.3566 -234.450142)
			(xy 380.407452 -234.448093) (xy 380.457973 -234.454227) (xy 380.506857 -234.468387) (xy 380.552836 -234.490204)
			(xy 380.59472 -234.519114) (xy 380.631424 -234.554369) (xy 380.661997 -234.595055) (xy 380.685648 -234.640118)
			(xy 380.701764 -234.688392) (xy 380.709928 -234.738626) (xy 380.71044 -234.764072) (xy 381.028968 -234.764072)
			(xy 381.032928 -234.715018) (xy 381.044705 -234.667234) (xy 381.063996 -234.621958) (xy 381.090299 -234.580362)
			(xy 381.122934 -234.543525) (xy 381.161055 -234.5124) (xy 381.203676 -234.487793) (xy 381.249692 -234.470341)
			(xy 381.297911 -234.460497) (xy 381.347086 -234.458516) (xy 381.395941 -234.464448) (xy 381.443212 -234.47814)
			(xy 381.487674 -234.499238) (xy 381.528177 -234.527194) (xy 381.56367 -234.561286) (xy 381.593235 -234.60063)
			(xy 381.616106 -234.644207) (xy 381.63169 -234.690888) (xy 381.639585 -234.739465) (xy 381.64008 -234.764072)
			(xy 381.969022 -234.764072) (xy 381.972982 -234.715018) (xy 381.984759 -234.667234) (xy 382.00405 -234.621958)
			(xy 382.030353 -234.580362) (xy 382.062988 -234.543525) (xy 382.101109 -234.5124) (xy 382.14373 -234.487793)
			(xy 382.189746 -234.470341) (xy 382.237965 -234.460497) (xy 382.28714 -234.458516) (xy 382.335995 -234.464448)
			(xy 382.383266 -234.47814) (xy 382.427728 -234.499238) (xy 382.468231 -234.527194) (xy 382.503724 -234.561286)
			(xy 382.533289 -234.60063) (xy 382.55616 -234.644207) (xy 382.571744 -234.690888) (xy 382.579639 -234.739465)
			(xy 382.580134 -234.764072) (xy 382.909076 -234.764072) (xy 382.913036 -234.715018) (xy 382.924813 -234.667234)
			(xy 382.944104 -234.621958) (xy 382.970407 -234.580362) (xy 383.003042 -234.543525) (xy 383.041163 -234.5124)
			(xy 383.083784 -234.487793) (xy 383.1298 -234.470341) (xy 383.178019 -234.460497) (xy 383.227194 -234.458516)
			(xy 383.276049 -234.464448) (xy 383.32332 -234.47814) (xy 383.367782 -234.499238) (xy 383.408285 -234.527194)
			(xy 383.443778 -234.561286) (xy 383.473343 -234.60063) (xy 383.496214 -234.644207) (xy 383.511798 -234.690888)
			(xy 383.519693 -234.739465) (xy 383.520188 -234.764072) (xy 383.84913 -234.764072) (xy 383.85309 -234.715018)
			(xy 383.864867 -234.667234) (xy 383.884158 -234.621958) (xy 383.910461 -234.580362) (xy 383.943096 -234.543525)
			(xy 383.981217 -234.5124) (xy 384.023838 -234.487793) (xy 384.069854 -234.470341) (xy 384.118073 -234.460497)
			(xy 384.167248 -234.458516) (xy 384.216103 -234.464448) (xy 384.263374 -234.47814) (xy 384.307836 -234.499238)
			(xy 384.348339 -234.527194) (xy 384.383832 -234.561286) (xy 384.413397 -234.60063) (xy 384.436268 -234.644207)
			(xy 384.451852 -234.690888) (xy 384.459747 -234.739465) (xy 384.460242 -234.764072) (xy 384.459747 -234.788679)
			(xy 384.451852 -234.837256) (xy 384.436268 -234.883937) (xy 384.413397 -234.927514) (xy 384.383832 -234.966858)
			(xy 384.348339 -235.00095) (xy 384.307836 -235.028906) (xy 384.263374 -235.050004) (xy 384.216103 -235.063696)
			(xy 384.167248 -235.069628) (xy 384.118073 -235.067647) (xy 384.069854 -235.057803) (xy 384.023838 -235.040351)
			(xy 383.981217 -235.015744) (xy 383.943096 -234.984619) (xy 383.910461 -234.947782) (xy 383.884158 -234.906186)
			(xy 383.864867 -234.86091) (xy 383.85309 -234.813126) (xy 383.84913 -234.764072) (xy 383.520188 -234.764072)
			(xy 383.519693 -234.788679) (xy 383.511798 -234.837256) (xy 383.496214 -234.883937) (xy 383.473343 -234.927514)
			(xy 383.443778 -234.966858) (xy 383.408285 -235.00095) (xy 383.367782 -235.028906) (xy 383.32332 -235.050004)
			(xy 383.276049 -235.063696) (xy 383.227194 -235.069628) (xy 383.178019 -235.067647) (xy 383.1298 -235.057803)
			(xy 383.083784 -235.040351) (xy 383.041163 -235.015744) (xy 383.003042 -234.984619) (xy 382.970407 -234.947782)
			(xy 382.944104 -234.906186) (xy 382.924813 -234.86091) (xy 382.913036 -234.813126) (xy 382.909076 -234.764072)
			(xy 382.580134 -234.764072) (xy 382.579639 -234.788679) (xy 382.571744 -234.837256) (xy 382.55616 -234.883937)
			(xy 382.533289 -234.927514) (xy 382.503724 -234.966858) (xy 382.468231 -235.00095) (xy 382.427728 -235.028906)
			(xy 382.383266 -235.050004) (xy 382.335995 -235.063696) (xy 382.28714 -235.069628) (xy 382.237965 -235.067647)
			(xy 382.189746 -235.057803) (xy 382.14373 -235.040351) (xy 382.101109 -235.015744) (xy 382.062988 -234.984619)
			(xy 382.030353 -234.947782) (xy 382.00405 -234.906186) (xy 381.984759 -234.86091) (xy 381.972982 -234.813126)
			(xy 381.969022 -234.764072) (xy 381.64008 -234.764072) (xy 381.639585 -234.788679) (xy 381.63169 -234.837256)
			(xy 381.616106 -234.883937) (xy 381.593235 -234.927514) (xy 381.56367 -234.966858) (xy 381.528177 -235.00095)
			(xy 381.487674 -235.028906) (xy 381.443212 -235.050004) (xy 381.395941 -235.063696) (xy 381.347086 -235.069628)
			(xy 381.297911 -235.067647) (xy 381.249692 -235.057803) (xy 381.203676 -235.040351) (xy 381.161055 -235.015744)
			(xy 381.122934 -234.984619) (xy 381.090299 -234.947782) (xy 381.063996 -234.906186) (xy 381.044705 -234.86091)
			(xy 381.032928 -234.813126) (xy 381.028968 -234.764072) (xy 380.71044 -234.764072) (xy 380.709928 -234.789518)
			(xy 380.701764 -234.839752) (xy 380.685648 -234.888026) (xy 380.661997 -234.933089) (xy 380.631424 -234.973775)
			(xy 380.59472 -235.00903) (xy 380.552836 -235.03794) (xy 380.506857 -235.059757) (xy 380.457973 -235.073917)
			(xy 380.407452 -235.080051) (xy 380.3566 -235.078002) (xy 380.306736 -235.067822) (xy 380.25915 -235.049775)
			(xy 380.215076 -235.024329) (xy 380.175654 -234.992142) (xy 380.141906 -234.954048) (xy 380.114705 -234.911034)
			(xy 380.094757 -234.864214) (xy 380.082578 -234.8148) (xy 380.078483 -234.764072) (xy 379.77064 -234.764072)
			(xy 379.770128 -234.789518) (xy 379.761964 -234.839752) (xy 379.745848 -234.888026) (xy 379.722197 -234.933089)
			(xy 379.691624 -234.973775) (xy 379.65492 -235.00903) (xy 379.613036 -235.03794) (xy 379.567057 -235.059757)
			(xy 379.518173 -235.073917) (xy 379.467652 -235.080051) (xy 379.4168 -235.078002) (xy 379.366936 -235.067822)
			(xy 379.31935 -235.049775) (xy 379.275276 -235.024329) (xy 379.235854 -234.992142) (xy 379.202106 -234.954048)
			(xy 379.174905 -234.911034) (xy 379.154957 -234.864214) (xy 379.142778 -234.8148) (xy 379.138683 -234.764072)
			(xy 377.890532 -234.764072) (xy 377.89002 -234.789518) (xy 377.881856 -234.839752) (xy 377.86574 -234.888026)
			(xy 377.842089 -234.933089) (xy 377.811516 -234.973775) (xy 377.774812 -235.00903) (xy 377.732928 -235.03794)
			(xy 377.686949 -235.059757) (xy 377.638065 -235.073917) (xy 377.587544 -235.080051) (xy 377.536692 -235.078002)
			(xy 377.486828 -235.067822) (xy 377.439242 -235.049775) (xy 377.395168 -235.024329) (xy 377.355746 -234.992142)
			(xy 377.321998 -234.954048) (xy 377.294797 -234.911034) (xy 377.274849 -234.864214) (xy 377.26267 -234.8148)
			(xy 377.258575 -234.764072) (xy 376.940064 -234.764072) (xy 376.939569 -234.788679) (xy 376.931674 -234.837256)
			(xy 376.91609 -234.883937) (xy 376.893219 -234.927514) (xy 376.863654 -234.966858) (xy 376.828161 -235.00095)
			(xy 376.787658 -235.028906) (xy 376.743196 -235.050004) (xy 376.695925 -235.063696) (xy 376.64707 -235.069628)
			(xy 376.597895 -235.067647) (xy 376.549676 -235.057803) (xy 376.50366 -235.040351) (xy 376.461039 -235.015744)
			(xy 376.422918 -234.984619) (xy 376.390283 -234.947782) (xy 376.36398 -234.906186) (xy 376.344689 -234.86091)
			(xy 376.332912 -234.813126) (xy 376.328952 -234.764072) (xy 376.010993 -234.764072) (xy 376.010994 -234.764085)
			(xy 376.007105 -234.813522) (xy 375.99553 -234.861742) (xy 375.976553 -234.907557) (xy 375.950643 -234.949839)
			(xy 375.918437 -234.987546) (xy 375.880727 -235.019751) (xy 375.859802 -235.033058) (xy 375.850561 -235.039476)
			(xy 375.838304 -235.058312) (xy 375.835202 -235.080569) (xy 375.837958 -235.091478) (xy 375.848879 -235.127404)
			(xy 375.867807 -235.200078) (xy 375.875804 -235.236766) (xy 375.875804 -235.237274) (xy 375.878848 -235.248674)
			(xy 375.893553 -235.26709) (xy 375.903998 -235.27258) (xy 375.975372 -235.305854) (xy 375.999756 -235.304838)
			(xy 376.010424 -235.298742) (xy 376.03416 -235.286038) (xy 376.084889 -235.268025) (xy 376.13794 -235.258882)
			(xy 376.164856 -235.258356) (xy 376.189672 -235.258814) (xy 376.238692 -235.266572) (xy 376.285896 -235.281904)
			(xy 376.33012 -235.304431) (xy 376.370274 -235.3336) (xy 376.405371 -235.368692) (xy 376.434546 -235.408843)
			(xy 376.45708 -235.453063) (xy 376.472418 -235.500265) (xy 376.480182 -235.549285) (xy 376.480182 -235.574078)
			(xy 376.788675 -235.574078) (xy 376.79277 -235.52335) (xy 376.804949 -235.473936) (xy 376.824897 -235.427116)
			(xy 376.852098 -235.384102) (xy 376.885846 -235.346008) (xy 376.925268 -235.313821) (xy 376.969342 -235.288375)
			(xy 377.016928 -235.270328) (xy 377.066792 -235.260148) (xy 377.117644 -235.258099) (xy 377.168165 -235.264233)
			(xy 377.217049 -235.278393) (xy 377.263028 -235.30021) (xy 377.304912 -235.32912) (xy 377.341616 -235.364375)
			(xy 377.372189 -235.405061) (xy 377.39584 -235.450124) (xy 377.411956 -235.498398) (xy 377.42012 -235.548632)
			(xy 377.420632 -235.574078) (xy 377.738906 -235.574078) (xy 377.742866 -235.525024) (xy 377.754643 -235.47724)
			(xy 377.773934 -235.431964) (xy 377.800237 -235.390368) (xy 377.832872 -235.353531) (xy 377.870993 -235.322406)
			(xy 377.913614 -235.297799) (xy 377.95963 -235.280347) (xy 378.007849 -235.270503) (xy 378.057024 -235.268522)
			(xy 378.105879 -235.274454) (xy 378.15315 -235.288146) (xy 378.197612 -235.309244) (xy 378.238115 -235.3372)
			(xy 378.273608 -235.371292) (xy 378.303173 -235.410636) (xy 378.326044 -235.454213) (xy 378.341628 -235.500894)
			(xy 378.349523 -235.549471) (xy 378.350018 -235.574078) (xy 378.668529 -235.574078) (xy 378.672624 -235.52335)
			(xy 378.684803 -235.473936) (xy 378.704751 -235.427116) (xy 378.731952 -235.384102) (xy 378.7657 -235.346008)
			(xy 378.805122 -235.313821) (xy 378.849196 -235.288375) (xy 378.896782 -235.270328) (xy 378.946646 -235.260148)
			(xy 378.997498 -235.258099) (xy 379.048019 -235.264233) (xy 379.096903 -235.278393) (xy 379.142882 -235.30021)
			(xy 379.184766 -235.32912) (xy 379.22147 -235.364375) (xy 379.252043 -235.405061) (xy 379.275694 -235.450124)
			(xy 379.29181 -235.498398) (xy 379.299974 -235.548632) (xy 379.300486 -235.574078) (xy 379.619014 -235.574078)
			(xy 379.622974 -235.525024) (xy 379.634751 -235.47724) (xy 379.654042 -235.431964) (xy 379.680345 -235.390368)
			(xy 379.71298 -235.353531) (xy 379.751101 -235.322406) (xy 379.793722 -235.297799) (xy 379.839738 -235.280347)
			(xy 379.887957 -235.270503) (xy 379.937132 -235.268522) (xy 379.985987 -235.274454) (xy 380.033258 -235.288146)
			(xy 380.07772 -235.309244) (xy 380.118223 -235.3372) (xy 380.153716 -235.371292) (xy 380.183281 -235.410636)
			(xy 380.206152 -235.454213) (xy 380.221736 -235.500894) (xy 380.229631 -235.549471) (xy 380.230126 -235.574078)
			(xy 380.548637 -235.574078) (xy 380.552732 -235.52335) (xy 380.564911 -235.473936) (xy 380.584859 -235.427116)
			(xy 380.61206 -235.384102) (xy 380.645808 -235.346008) (xy 380.68523 -235.313821) (xy 380.729304 -235.288375)
			(xy 380.77689 -235.270328) (xy 380.826754 -235.260148) (xy 380.877606 -235.258099) (xy 380.928127 -235.264233)
			(xy 380.977011 -235.278393) (xy 381.02299 -235.30021) (xy 381.064874 -235.32912) (xy 381.101578 -235.364375)
			(xy 381.132151 -235.405061) (xy 381.155802 -235.450124) (xy 381.171918 -235.498398) (xy 381.180082 -235.548632)
			(xy 381.180594 -235.574078) (xy 381.499122 -235.574078) (xy 381.503082 -235.525024) (xy 381.514859 -235.47724)
			(xy 381.53415 -235.431964) (xy 381.560453 -235.390368) (xy 381.593088 -235.353531) (xy 381.631209 -235.322406)
			(xy 381.67383 -235.297799) (xy 381.719846 -235.280347) (xy 381.768065 -235.270503) (xy 381.81724 -235.268522)
			(xy 381.866095 -235.274454) (xy 381.913366 -235.288146) (xy 381.957828 -235.309244) (xy 381.998331 -235.3372)
			(xy 382.033824 -235.371292) (xy 382.063389 -235.410636) (xy 382.08626 -235.454213) (xy 382.101844 -235.500894)
			(xy 382.109739 -235.549471) (xy 382.110234 -235.574078) (xy 382.438922 -235.574078) (xy 382.442882 -235.525024)
			(xy 382.454659 -235.47724) (xy 382.47395 -235.431964) (xy 382.500253 -235.390368) (xy 382.532888 -235.353531)
			(xy 382.571009 -235.322406) (xy 382.61363 -235.297799) (xy 382.659646 -235.280347) (xy 382.707865 -235.270503)
			(xy 382.75704 -235.268522) (xy 382.805895 -235.274454) (xy 382.853166 -235.288146) (xy 382.897628 -235.309244)
			(xy 382.938131 -235.3372) (xy 382.973624 -235.371292) (xy 383.003189 -235.410636) (xy 383.02606 -235.454213)
			(xy 383.041644 -235.500894) (xy 383.049539 -235.549471) (xy 383.050034 -235.574078) (xy 383.378976 -235.574078)
			(xy 383.382936 -235.525024) (xy 383.394713 -235.47724) (xy 383.414004 -235.431964) (xy 383.440307 -235.390368)
			(xy 383.472942 -235.353531) (xy 383.511063 -235.322406) (xy 383.553684 -235.297799) (xy 383.5997 -235.280347)
			(xy 383.647919 -235.270503) (xy 383.697094 -235.268522) (xy 383.745949 -235.274454) (xy 383.79322 -235.288146)
			(xy 383.837682 -235.309244) (xy 383.878185 -235.3372) (xy 383.913678 -235.371292) (xy 383.943243 -235.410636)
			(xy 383.966114 -235.454213) (xy 383.981698 -235.500894) (xy 383.989593 -235.549471) (xy 383.990088 -235.574078)
			(xy 383.989593 -235.598685) (xy 383.981698 -235.647262) (xy 383.966114 -235.693943) (xy 383.943243 -235.73752)
			(xy 383.913678 -235.776864) (xy 383.878185 -235.810956) (xy 383.837682 -235.838912) (xy 383.79322 -235.86001)
			(xy 383.745949 -235.873702) (xy 383.697094 -235.879634) (xy 383.647919 -235.877653) (xy 383.5997 -235.867809)
			(xy 383.553684 -235.850357) (xy 383.511063 -235.82575) (xy 383.472942 -235.794625) (xy 383.440307 -235.757788)
			(xy 383.414004 -235.716192) (xy 383.394713 -235.670916) (xy 383.382936 -235.623132) (xy 383.378976 -235.574078)
			(xy 383.050034 -235.574078) (xy 383.049539 -235.598685) (xy 383.041644 -235.647262) (xy 383.02606 -235.693943)
			(xy 383.003189 -235.73752) (xy 382.973624 -235.776864) (xy 382.938131 -235.810956) (xy 382.897628 -235.838912)
			(xy 382.853166 -235.86001) (xy 382.805895 -235.873702) (xy 382.75704 -235.879634) (xy 382.707865 -235.877653)
			(xy 382.659646 -235.867809) (xy 382.61363 -235.850357) (xy 382.571009 -235.82575) (xy 382.532888 -235.794625)
			(xy 382.500253 -235.757788) (xy 382.47395 -235.716192) (xy 382.454659 -235.670916) (xy 382.442882 -235.623132)
			(xy 382.438922 -235.574078) (xy 382.110234 -235.574078) (xy 382.109739 -235.598685) (xy 382.101844 -235.647262)
			(xy 382.08626 -235.693943) (xy 382.063389 -235.73752) (xy 382.033824 -235.776864) (xy 381.998331 -235.810956)
			(xy 381.957828 -235.838912) (xy 381.913366 -235.86001) (xy 381.866095 -235.873702) (xy 381.81724 -235.879634)
			(xy 381.768065 -235.877653) (xy 381.719846 -235.867809) (xy 381.67383 -235.850357) (xy 381.631209 -235.82575)
			(xy 381.593088 -235.794625) (xy 381.560453 -235.757788) (xy 381.53415 -235.716192) (xy 381.514859 -235.670916)
			(xy 381.503082 -235.623132) (xy 381.499122 -235.574078) (xy 381.180594 -235.574078) (xy 381.180082 -235.599524)
			(xy 381.171918 -235.649758) (xy 381.155802 -235.698032) (xy 381.132151 -235.743095) (xy 381.101578 -235.783781)
			(xy 381.064874 -235.819036) (xy 381.02299 -235.847946) (xy 380.977011 -235.869763) (xy 380.928127 -235.883923)
			(xy 380.877606 -235.890057) (xy 380.826754 -235.888008) (xy 380.77689 -235.877828) (xy 380.729304 -235.859781)
			(xy 380.68523 -235.834335) (xy 380.645808 -235.802148) (xy 380.61206 -235.764054) (xy 380.584859 -235.72104)
			(xy 380.564911 -235.67422) (xy 380.552732 -235.624806) (xy 380.548637 -235.574078) (xy 380.230126 -235.574078)
			(xy 380.229631 -235.598685) (xy 380.221736 -235.647262) (xy 380.206152 -235.693943) (xy 380.183281 -235.73752)
			(xy 380.153716 -235.776864) (xy 380.118223 -235.810956) (xy 380.07772 -235.838912) (xy 380.033258 -235.86001)
			(xy 379.985987 -235.873702) (xy 379.937132 -235.879634) (xy 379.887957 -235.877653) (xy 379.839738 -235.867809)
			(xy 379.793722 -235.850357) (xy 379.751101 -235.82575) (xy 379.71298 -235.794625) (xy 379.680345 -235.757788)
			(xy 379.654042 -235.716192) (xy 379.634751 -235.670916) (xy 379.622974 -235.623132) (xy 379.619014 -235.574078)
			(xy 379.300486 -235.574078) (xy 379.299974 -235.599524) (xy 379.29181 -235.649758) (xy 379.275694 -235.698032)
			(xy 379.252043 -235.743095) (xy 379.22147 -235.783781) (xy 379.184766 -235.819036) (xy 379.142882 -235.847946)
			(xy 379.096903 -235.869763) (xy 379.048019 -235.883923) (xy 378.997498 -235.890057) (xy 378.946646 -235.888008)
			(xy 378.896782 -235.877828) (xy 378.849196 -235.859781) (xy 378.805122 -235.834335) (xy 378.7657 -235.802148)
			(xy 378.731952 -235.764054) (xy 378.704751 -235.72104) (xy 378.684803 -235.67422) (xy 378.672624 -235.624806)
			(xy 378.668529 -235.574078) (xy 378.350018 -235.574078) (xy 378.349523 -235.598685) (xy 378.341628 -235.647262)
			(xy 378.326044 -235.693943) (xy 378.303173 -235.73752) (xy 378.273608 -235.776864) (xy 378.238115 -235.810956)
			(xy 378.197612 -235.838912) (xy 378.15315 -235.86001) (xy 378.105879 -235.873702) (xy 378.057024 -235.879634)
			(xy 378.007849 -235.877653) (xy 377.95963 -235.867809) (xy 377.913614 -235.850357) (xy 377.870993 -235.82575)
			(xy 377.832872 -235.794625) (xy 377.800237 -235.757788) (xy 377.773934 -235.716192) (xy 377.754643 -235.670916)
			(xy 377.742866 -235.623132) (xy 377.738906 -235.574078) (xy 377.420632 -235.574078) (xy 377.42012 -235.599524)
			(xy 377.411956 -235.649758) (xy 377.39584 -235.698032) (xy 377.372189 -235.743095) (xy 377.341616 -235.783781)
			(xy 377.304912 -235.819036) (xy 377.263028 -235.847946) (xy 377.217049 -235.869763) (xy 377.168165 -235.883923)
			(xy 377.117644 -235.890057) (xy 377.066792 -235.888008) (xy 377.016928 -235.877828) (xy 376.969342 -235.859781)
			(xy 376.925268 -235.834335) (xy 376.885846 -235.802148) (xy 376.852098 -235.764054) (xy 376.824897 -235.72104)
			(xy 376.804949 -235.67422) (xy 376.79277 -235.624806) (xy 376.788675 -235.574078) (xy 376.480182 -235.574078)
			(xy 376.480182 -235.598915) (xy 376.472418 -235.647935) (xy 376.45708 -235.695137) (xy 376.434546 -235.739357)
			(xy 376.405371 -235.779508) (xy 376.370274 -235.8146) (xy 376.33012 -235.843769) (xy 376.285896 -235.866296)
			(xy 376.238692 -235.881628) (xy 376.189672 -235.889386) (xy 376.164856 -235.8898) (xy 376.137942 -235.889251)
			(xy 376.084896 -235.880107) (xy 376.034171 -235.862094) (xy 376.010424 -235.849414) (xy 375.999756 -235.843318)
			(xy 375.975372 -235.842302) (xy 375.903998 -235.875576) (xy 375.893615 -235.881134) (xy 375.878948 -235.89953)
			(xy 375.875804 -235.910882) (xy 375.875804 -235.91139) (xy 375.867821 -235.948081) (xy 375.84889 -236.020755)
			(xy 375.837958 -236.056678) (xy 375.835145 -236.067584) (xy 375.838217 -236.089868) (xy 375.850537 -236.108689)
			(xy 375.859802 -236.115098) (xy 375.880703 -236.128444) (xy 375.918413 -236.160645) (xy 375.950621 -236.198349)
			(xy 375.976534 -236.240627) (xy 375.995513 -236.286439) (xy 376.007091 -236.334657) (xy 376.010983 -236.384084)
			(xy 376.328952 -236.384084) (xy 376.332912 -236.33503) (xy 376.344689 -236.287246) (xy 376.36398 -236.24197)
			(xy 376.390283 -236.200374) (xy 376.422918 -236.163537) (xy 376.461039 -236.132412) (xy 376.50366 -236.107805)
			(xy 376.549676 -236.090353) (xy 376.597895 -236.080509) (xy 376.64707 -236.078528) (xy 376.695925 -236.08446)
			(xy 376.743196 -236.098152) (xy 376.787658 -236.11925) (xy 376.828161 -236.147206) (xy 376.863654 -236.181298)
			(xy 376.893219 -236.220642) (xy 376.91609 -236.264219) (xy 376.931674 -236.3109) (xy 376.939569 -236.359477)
			(xy 376.940064 -236.384084) (xy 377.258575 -236.384084) (xy 377.26267 -236.333356) (xy 377.274849 -236.283942)
			(xy 377.294797 -236.237122) (xy 377.321998 -236.194108) (xy 377.355746 -236.156014) (xy 377.395168 -236.123827)
			(xy 377.439242 -236.098381) (xy 377.486828 -236.080334) (xy 377.536692 -236.070154) (xy 377.587544 -236.068105)
			(xy 377.638065 -236.074239) (xy 377.686949 -236.088399) (xy 377.732928 -236.110216) (xy 377.774812 -236.139126)
			(xy 377.811516 -236.174381) (xy 377.842089 -236.215067) (xy 377.86574 -236.26013) (xy 377.881856 -236.308404)
			(xy 377.89002 -236.358638) (xy 377.890532 -236.384084) (xy 378.20906 -236.384084) (xy 378.21302 -236.33503)
			(xy 378.224797 -236.287246) (xy 378.244088 -236.24197) (xy 378.270391 -236.200374) (xy 378.303026 -236.163537)
			(xy 378.341147 -236.132412) (xy 378.383768 -236.107805) (xy 378.429784 -236.090353) (xy 378.478003 -236.080509)
			(xy 378.527178 -236.078528) (xy 378.576033 -236.08446) (xy 378.623304 -236.098152) (xy 378.667766 -236.11925)
			(xy 378.708269 -236.147206) (xy 378.743762 -236.181298) (xy 378.773327 -236.220642) (xy 378.796198 -236.264219)
			(xy 378.811782 -236.3109) (xy 378.819677 -236.359477) (xy 378.820172 -236.384084) (xy 379.138683 -236.384084)
			(xy 379.142778 -236.333356) (xy 379.154957 -236.283942) (xy 379.174905 -236.237122) (xy 379.202106 -236.194108)
			(xy 379.235854 -236.156014) (xy 379.275276 -236.123827) (xy 379.31935 -236.098381) (xy 379.366936 -236.080334)
			(xy 379.4168 -236.070154) (xy 379.467652 -236.068105) (xy 379.518173 -236.074239) (xy 379.567057 -236.088399)
			(xy 379.613036 -236.110216) (xy 379.65492 -236.139126) (xy 379.691624 -236.174381) (xy 379.722197 -236.215067)
			(xy 379.745848 -236.26013) (xy 379.761964 -236.308404) (xy 379.770128 -236.358638) (xy 379.77064 -236.384084)
			(xy 380.078483 -236.384084) (xy 380.082578 -236.333356) (xy 380.094757 -236.283942) (xy 380.114705 -236.237122)
			(xy 380.141906 -236.194108) (xy 380.175654 -236.156014) (xy 380.215076 -236.123827) (xy 380.25915 -236.098381)
			(xy 380.306736 -236.080334) (xy 380.3566 -236.070154) (xy 380.407452 -236.068105) (xy 380.457973 -236.074239)
			(xy 380.506857 -236.088399) (xy 380.552836 -236.110216) (xy 380.59472 -236.139126) (xy 380.631424 -236.174381)
			(xy 380.661997 -236.215067) (xy 380.685648 -236.26013) (xy 380.701764 -236.308404) (xy 380.709928 -236.358638)
			(xy 380.71044 -236.384084) (xy 381.028968 -236.384084) (xy 381.032928 -236.33503) (xy 381.044705 -236.287246)
			(xy 381.063996 -236.24197) (xy 381.090299 -236.200374) (xy 381.122934 -236.163537) (xy 381.161055 -236.132412)
			(xy 381.203676 -236.107805) (xy 381.249692 -236.090353) (xy 381.297911 -236.080509) (xy 381.347086 -236.078528)
			(xy 381.395941 -236.08446) (xy 381.443212 -236.098152) (xy 381.487674 -236.11925) (xy 381.528177 -236.147206)
			(xy 381.56367 -236.181298) (xy 381.593235 -236.220642) (xy 381.616106 -236.264219) (xy 381.63169 -236.3109)
			(xy 381.639585 -236.359477) (xy 381.64008 -236.384084) (xy 381.969022 -236.384084) (xy 381.972982 -236.33503)
			(xy 381.984759 -236.287246) (xy 382.00405 -236.24197) (xy 382.030353 -236.200374) (xy 382.062988 -236.163537)
			(xy 382.101109 -236.132412) (xy 382.14373 -236.107805) (xy 382.189746 -236.090353) (xy 382.237965 -236.080509)
			(xy 382.28714 -236.078528) (xy 382.335995 -236.08446) (xy 382.383266 -236.098152) (xy 382.427728 -236.11925)
			(xy 382.468231 -236.147206) (xy 382.503724 -236.181298) (xy 382.533289 -236.220642) (xy 382.55616 -236.264219)
			(xy 382.571744 -236.3109) (xy 382.579639 -236.359477) (xy 382.580134 -236.384084) (xy 382.909076 -236.384084)
			(xy 382.913036 -236.33503) (xy 382.924813 -236.287246) (xy 382.944104 -236.24197) (xy 382.970407 -236.200374)
			(xy 383.003042 -236.163537) (xy 383.041163 -236.132412) (xy 383.083784 -236.107805) (xy 383.1298 -236.090353)
			(xy 383.178019 -236.080509) (xy 383.227194 -236.078528) (xy 383.276049 -236.08446) (xy 383.32332 -236.098152)
			(xy 383.367782 -236.11925) (xy 383.408285 -236.147206) (xy 383.443778 -236.181298) (xy 383.473343 -236.220642)
			(xy 383.496214 -236.264219) (xy 383.511798 -236.3109) (xy 383.519693 -236.359477) (xy 383.520188 -236.384084)
			(xy 383.84913 -236.384084) (xy 383.85309 -236.33503) (xy 383.864867 -236.287246) (xy 383.884158 -236.24197)
			(xy 383.910461 -236.200374) (xy 383.943096 -236.163537) (xy 383.981217 -236.132412) (xy 384.023838 -236.107805)
			(xy 384.069854 -236.090353) (xy 384.118073 -236.080509) (xy 384.167248 -236.078528) (xy 384.216103 -236.08446)
			(xy 384.263374 -236.098152) (xy 384.307836 -236.11925) (xy 384.348339 -236.147206) (xy 384.383832 -236.181298)
			(xy 384.413397 -236.220642) (xy 384.436268 -236.264219) (xy 384.451852 -236.3109) (xy 384.459747 -236.359477)
			(xy 384.460242 -236.384084) (xy 384.459747 -236.408691) (xy 384.451852 -236.457268) (xy 384.436268 -236.503949)
			(xy 384.413397 -236.547526) (xy 384.383832 -236.58687) (xy 384.348339 -236.620962) (xy 384.307836 -236.648918)
			(xy 384.263374 -236.670016) (xy 384.216103 -236.683708) (xy 384.167248 -236.68964) (xy 384.118073 -236.687659)
			(xy 384.069854 -236.677815) (xy 384.023838 -236.660363) (xy 383.981217 -236.635756) (xy 383.943096 -236.604631)
			(xy 383.910461 -236.567794) (xy 383.884158 -236.526198) (xy 383.864867 -236.480922) (xy 383.85309 -236.433138)
			(xy 383.84913 -236.384084) (xy 383.520188 -236.384084) (xy 383.519693 -236.408691) (xy 383.511798 -236.457268)
			(xy 383.496214 -236.503949) (xy 383.473343 -236.547526) (xy 383.443778 -236.58687) (xy 383.408285 -236.620962)
			(xy 383.367782 -236.648918) (xy 383.32332 -236.670016) (xy 383.276049 -236.683708) (xy 383.227194 -236.68964)
			(xy 383.178019 -236.687659) (xy 383.1298 -236.677815) (xy 383.083784 -236.660363) (xy 383.041163 -236.635756)
			(xy 383.003042 -236.604631) (xy 382.970407 -236.567794) (xy 382.944104 -236.526198) (xy 382.924813 -236.480922)
			(xy 382.913036 -236.433138) (xy 382.909076 -236.384084) (xy 382.580134 -236.384084) (xy 382.579639 -236.408691)
			(xy 382.571744 -236.457268) (xy 382.55616 -236.503949) (xy 382.533289 -236.547526) (xy 382.503724 -236.58687)
			(xy 382.468231 -236.620962) (xy 382.427728 -236.648918) (xy 382.383266 -236.670016) (xy 382.335995 -236.683708)
			(xy 382.28714 -236.68964) (xy 382.237965 -236.687659) (xy 382.189746 -236.677815) (xy 382.14373 -236.660363)
			(xy 382.101109 -236.635756) (xy 382.062988 -236.604631) (xy 382.030353 -236.567794) (xy 382.00405 -236.526198)
			(xy 381.984759 -236.480922) (xy 381.972982 -236.433138) (xy 381.969022 -236.384084) (xy 381.64008 -236.384084)
			(xy 381.639585 -236.408691) (xy 381.63169 -236.457268) (xy 381.616106 -236.503949) (xy 381.593235 -236.547526)
			(xy 381.56367 -236.58687) (xy 381.528177 -236.620962) (xy 381.487674 -236.648918) (xy 381.443212 -236.670016)
			(xy 381.395941 -236.683708) (xy 381.347086 -236.68964) (xy 381.297911 -236.687659) (xy 381.249692 -236.677815)
			(xy 381.203676 -236.660363) (xy 381.161055 -236.635756) (xy 381.122934 -236.604631) (xy 381.090299 -236.567794)
			(xy 381.063996 -236.526198) (xy 381.044705 -236.480922) (xy 381.032928 -236.433138) (xy 381.028968 -236.384084)
			(xy 380.71044 -236.384084) (xy 380.709928 -236.40953) (xy 380.701764 -236.459764) (xy 380.685648 -236.508038)
			(xy 380.661997 -236.553101) (xy 380.631424 -236.593787) (xy 380.59472 -236.629042) (xy 380.552836 -236.657952)
			(xy 380.506857 -236.679769) (xy 380.457973 -236.693929) (xy 380.407452 -236.700063) (xy 380.3566 -236.698014)
			(xy 380.306736 -236.687834) (xy 380.25915 -236.669787) (xy 380.215076 -236.644341) (xy 380.175654 -236.612154)
			(xy 380.141906 -236.57406) (xy 380.114705 -236.531046) (xy 380.094757 -236.484226) (xy 380.082578 -236.434812)
			(xy 380.078483 -236.384084) (xy 379.77064 -236.384084) (xy 379.770128 -236.40953) (xy 379.761964 -236.459764)
			(xy 379.745848 -236.508038) (xy 379.722197 -236.553101) (xy 379.691624 -236.593787) (xy 379.65492 -236.629042)
			(xy 379.613036 -236.657952) (xy 379.567057 -236.679769) (xy 379.518173 -236.693929) (xy 379.467652 -236.700063)
			(xy 379.4168 -236.698014) (xy 379.366936 -236.687834) (xy 379.31935 -236.669787) (xy 379.275276 -236.644341)
			(xy 379.235854 -236.612154) (xy 379.202106 -236.57406) (xy 379.174905 -236.531046) (xy 379.154957 -236.484226)
			(xy 379.142778 -236.434812) (xy 379.138683 -236.384084) (xy 378.820172 -236.384084) (xy 378.819677 -236.408691)
			(xy 378.811782 -236.457268) (xy 378.796198 -236.503949) (xy 378.773327 -236.547526) (xy 378.743762 -236.58687)
			(xy 378.708269 -236.620962) (xy 378.667766 -236.648918) (xy 378.623304 -236.670016) (xy 378.576033 -236.683708)
			(xy 378.527178 -236.68964) (xy 378.478003 -236.687659) (xy 378.429784 -236.677815) (xy 378.383768 -236.660363)
			(xy 378.341147 -236.635756) (xy 378.303026 -236.604631) (xy 378.270391 -236.567794) (xy 378.244088 -236.526198)
			(xy 378.224797 -236.480922) (xy 378.21302 -236.433138) (xy 378.20906 -236.384084) (xy 377.890532 -236.384084)
			(xy 377.89002 -236.40953) (xy 377.881856 -236.459764) (xy 377.86574 -236.508038) (xy 377.842089 -236.553101)
			(xy 377.811516 -236.593787) (xy 377.774812 -236.629042) (xy 377.732928 -236.657952) (xy 377.686949 -236.679769)
			(xy 377.638065 -236.693929) (xy 377.587544 -236.700063) (xy 377.536692 -236.698014) (xy 377.486828 -236.687834)
			(xy 377.439242 -236.669787) (xy 377.395168 -236.644341) (xy 377.355746 -236.612154) (xy 377.321998 -236.57406)
			(xy 377.294797 -236.531046) (xy 377.274849 -236.484226) (xy 377.26267 -236.434812) (xy 377.258575 -236.384084)
			(xy 376.940064 -236.384084) (xy 376.939569 -236.408691) (xy 376.931674 -236.457268) (xy 376.91609 -236.503949)
			(xy 376.893219 -236.547526) (xy 376.863654 -236.58687) (xy 376.828161 -236.620962) (xy 376.787658 -236.648918)
			(xy 376.743196 -236.670016) (xy 376.695925 -236.683708) (xy 376.64707 -236.68964) (xy 376.597895 -236.687659)
			(xy 376.549676 -236.677815) (xy 376.50366 -236.660363) (xy 376.461039 -236.635756) (xy 376.422918 -236.604631)
			(xy 376.390283 -236.567794) (xy 376.36398 -236.526198) (xy 376.344689 -236.480922) (xy 376.332912 -236.433138)
			(xy 376.328952 -236.384084) (xy 376.010983 -236.384084) (xy 376.010984 -236.384092) (xy 376.007094 -236.433527)
			(xy 375.995518 -236.481745) (xy 375.976541 -236.527558) (xy 375.950631 -236.569838) (xy 375.918425 -236.607544)
			(xy 375.880716 -236.639746) (xy 375.859802 -236.65307) (xy 375.850563 -236.659489) (xy 375.83831 -236.678324)
			(xy 375.835213 -236.700579) (xy 375.837958 -236.71149) (xy 375.848881 -236.747416) (xy 375.867813 -236.820088)
			(xy 375.875804 -236.856778) (xy 375.875804 -236.857286) (xy 375.87885 -236.868685) (xy 375.893557 -236.887096)
			(xy 375.903998 -236.892592) (xy 375.975372 -236.925866) (xy 375.999756 -236.92485) (xy 376.010424 -236.918754)
			(xy 376.03416 -236.906049) (xy 376.084889 -236.888036) (xy 376.13794 -236.878892) (xy 376.164856 -236.878368)
			(xy 376.189671 -236.878826) (xy 376.23869 -236.886584) (xy 376.285891 -236.901915) (xy 376.330113 -236.924441)
			(xy 376.370267 -236.953609) (xy 376.405362 -236.9887) (xy 376.434536 -237.028849) (xy 376.457069 -237.073068)
			(xy 376.472406 -237.120268) (xy 376.48017 -237.169285) (xy 376.48017 -237.19409) (xy 376.788675 -237.19409)
			(xy 376.79277 -237.143362) (xy 376.804949 -237.093948) (xy 376.824897 -237.047128) (xy 376.852098 -237.004114)
			(xy 376.885846 -236.96602) (xy 376.925268 -236.933833) (xy 376.969342 -236.908387) (xy 377.016928 -236.89034)
			(xy 377.066792 -236.88016) (xy 377.117644 -236.878111) (xy 377.168165 -236.884245) (xy 377.217049 -236.898405)
			(xy 377.263028 -236.920222) (xy 377.304912 -236.949132) (xy 377.341616 -236.984387) (xy 377.372189 -237.025073)
			(xy 377.39584 -237.070136) (xy 377.411956 -237.11841) (xy 377.42012 -237.168644) (xy 377.420632 -237.19409)
			(xy 378.668529 -237.19409) (xy 378.672624 -237.143362) (xy 378.684803 -237.093948) (xy 378.704751 -237.047128)
			(xy 378.731952 -237.004114) (xy 378.7657 -236.96602) (xy 378.805122 -236.933833) (xy 378.849196 -236.908387)
			(xy 378.896782 -236.89034) (xy 378.946646 -236.88016) (xy 378.997498 -236.878111) (xy 379.048019 -236.884245)
			(xy 379.096903 -236.898405) (xy 379.142882 -236.920222) (xy 379.184766 -236.949132) (xy 379.22147 -236.984387)
			(xy 379.252043 -237.025073) (xy 379.275694 -237.070136) (xy 379.29181 -237.11841) (xy 379.299974 -237.168644)
			(xy 379.300486 -237.19409) (xy 379.619014 -237.19409) (xy 379.622974 -237.145036) (xy 379.634751 -237.097252)
			(xy 379.654042 -237.051976) (xy 379.680345 -237.01038) (xy 379.71298 -236.973543) (xy 379.751101 -236.942418)
			(xy 379.793722 -236.917811) (xy 379.839738 -236.900359) (xy 379.887957 -236.890515) (xy 379.937132 -236.888534)
			(xy 379.985987 -236.894466) (xy 380.033258 -236.908158) (xy 380.07772 -236.929256) (xy 380.118223 -236.957212)
			(xy 380.153716 -236.991304) (xy 380.183281 -237.030648) (xy 380.206152 -237.074225) (xy 380.221736 -237.120906)
			(xy 380.229631 -237.169483) (xy 380.230126 -237.19409) (xy 380.548637 -237.19409) (xy 380.552732 -237.143362)
			(xy 380.564911 -237.093948) (xy 380.584859 -237.047128) (xy 380.61206 -237.004114) (xy 380.645808 -236.96602)
			(xy 380.68523 -236.933833) (xy 380.729304 -236.908387) (xy 380.77689 -236.89034) (xy 380.826754 -236.88016)
			(xy 380.877606 -236.878111) (xy 380.928127 -236.884245) (xy 380.977011 -236.898405) (xy 381.02299 -236.920222)
			(xy 381.064874 -236.949132) (xy 381.101578 -236.984387) (xy 381.132151 -237.025073) (xy 381.155802 -237.070136)
			(xy 381.171918 -237.11841) (xy 381.180082 -237.168644) (xy 381.180594 -237.19409) (xy 381.499122 -237.19409)
			(xy 381.503082 -237.145036) (xy 381.514859 -237.097252) (xy 381.53415 -237.051976) (xy 381.560453 -237.01038)
			(xy 381.593088 -236.973543) (xy 381.631209 -236.942418) (xy 381.67383 -236.917811) (xy 381.719846 -236.900359)
			(xy 381.768065 -236.890515) (xy 381.81724 -236.888534) (xy 381.866095 -236.894466) (xy 381.913366 -236.908158)
			(xy 381.957828 -236.929256) (xy 381.998331 -236.957212) (xy 382.033824 -236.991304) (xy 382.063389 -237.030648)
			(xy 382.08626 -237.074225) (xy 382.101844 -237.120906) (xy 382.109739 -237.169483) (xy 382.110234 -237.19409)
			(xy 382.438922 -237.19409) (xy 382.442882 -237.145036) (xy 382.454659 -237.097252) (xy 382.47395 -237.051976)
			(xy 382.500253 -237.01038) (xy 382.532888 -236.973543) (xy 382.571009 -236.942418) (xy 382.61363 -236.917811)
			(xy 382.659646 -236.900359) (xy 382.707865 -236.890515) (xy 382.75704 -236.888534) (xy 382.805895 -236.894466)
			(xy 382.853166 -236.908158) (xy 382.897628 -236.929256) (xy 382.938131 -236.957212) (xy 382.973624 -236.991304)
			(xy 383.003189 -237.030648) (xy 383.02606 -237.074225) (xy 383.041644 -237.120906) (xy 383.049539 -237.169483)
			(xy 383.050034 -237.19409) (xy 383.378976 -237.19409) (xy 383.382936 -237.145036) (xy 383.394713 -237.097252)
			(xy 383.414004 -237.051976) (xy 383.440307 -237.01038) (xy 383.472942 -236.973543) (xy 383.511063 -236.942418)
			(xy 383.553684 -236.917811) (xy 383.5997 -236.900359) (xy 383.647919 -236.890515) (xy 383.697094 -236.888534)
			(xy 383.745949 -236.894466) (xy 383.79322 -236.908158) (xy 383.837682 -236.929256) (xy 383.878185 -236.957212)
			(xy 383.913678 -236.991304) (xy 383.943243 -237.030648) (xy 383.966114 -237.074225) (xy 383.981698 -237.120906)
			(xy 383.989593 -237.169483) (xy 383.990088 -237.19409) (xy 383.989593 -237.218697) (xy 383.981698 -237.267274)
			(xy 383.966114 -237.313955) (xy 383.943243 -237.357532) (xy 383.913678 -237.396876) (xy 383.878185 -237.430968)
			(xy 383.837682 -237.458924) (xy 383.79322 -237.480022) (xy 383.745949 -237.493714) (xy 383.697094 -237.499646)
			(xy 383.647919 -237.497665) (xy 383.5997 -237.487821) (xy 383.553684 -237.470369) (xy 383.511063 -237.445762)
			(xy 383.472942 -237.414637) (xy 383.440307 -237.3778) (xy 383.414004 -237.336204) (xy 383.394713 -237.290928)
			(xy 383.382936 -237.243144) (xy 383.378976 -237.19409) (xy 383.050034 -237.19409) (xy 383.049539 -237.218697)
			(xy 383.041644 -237.267274) (xy 383.02606 -237.313955) (xy 383.003189 -237.357532) (xy 382.973624 -237.396876)
			(xy 382.938131 -237.430968) (xy 382.897628 -237.458924) (xy 382.853166 -237.480022) (xy 382.805895 -237.493714)
			(xy 382.75704 -237.499646) (xy 382.707865 -237.497665) (xy 382.659646 -237.487821) (xy 382.61363 -237.470369)
			(xy 382.571009 -237.445762) (xy 382.532888 -237.414637) (xy 382.500253 -237.3778) (xy 382.47395 -237.336204)
			(xy 382.454659 -237.290928) (xy 382.442882 -237.243144) (xy 382.438922 -237.19409) (xy 382.110234 -237.19409)
			(xy 382.109739 -237.218697) (xy 382.101844 -237.267274) (xy 382.08626 -237.313955) (xy 382.063389 -237.357532)
			(xy 382.033824 -237.396876) (xy 381.998331 -237.430968) (xy 381.957828 -237.458924) (xy 381.913366 -237.480022)
			(xy 381.866095 -237.493714) (xy 381.81724 -237.499646) (xy 381.768065 -237.497665) (xy 381.719846 -237.487821)
			(xy 381.67383 -237.470369) (xy 381.631209 -237.445762) (xy 381.593088 -237.414637) (xy 381.560453 -237.3778)
			(xy 381.53415 -237.336204) (xy 381.514859 -237.290928) (xy 381.503082 -237.243144) (xy 381.499122 -237.19409)
			(xy 381.180594 -237.19409) (xy 381.180082 -237.219536) (xy 381.171918 -237.26977) (xy 381.155802 -237.318044)
			(xy 381.132151 -237.363107) (xy 381.101578 -237.403793) (xy 381.064874 -237.439048) (xy 381.02299 -237.467958)
			(xy 380.977011 -237.489775) (xy 380.928127 -237.503935) (xy 380.877606 -237.510069) (xy 380.826754 -237.50802)
			(xy 380.77689 -237.49784) (xy 380.729304 -237.479793) (xy 380.68523 -237.454347) (xy 380.645808 -237.42216)
			(xy 380.61206 -237.384066) (xy 380.584859 -237.341052) (xy 380.564911 -237.294232) (xy 380.552732 -237.244818)
			(xy 380.548637 -237.19409) (xy 380.230126 -237.19409) (xy 380.229631 -237.218697) (xy 380.221736 -237.267274)
			(xy 380.206152 -237.313955) (xy 380.183281 -237.357532) (xy 380.153716 -237.396876) (xy 380.118223 -237.430968)
			(xy 380.07772 -237.458924) (xy 380.033258 -237.480022) (xy 379.985987 -237.493714) (xy 379.937132 -237.499646)
			(xy 379.887957 -237.497665) (xy 379.839738 -237.487821) (xy 379.793722 -237.470369) (xy 379.751101 -237.445762)
			(xy 379.71298 -237.414637) (xy 379.680345 -237.3778) (xy 379.654042 -237.336204) (xy 379.634751 -237.290928)
			(xy 379.622974 -237.243144) (xy 379.619014 -237.19409) (xy 379.300486 -237.19409) (xy 379.299974 -237.219536)
			(xy 379.29181 -237.26977) (xy 379.275694 -237.318044) (xy 379.252043 -237.363107) (xy 379.22147 -237.403793)
			(xy 379.184766 -237.439048) (xy 379.142882 -237.467958) (xy 379.096903 -237.489775) (xy 379.048019 -237.503935)
			(xy 378.997498 -237.510069) (xy 378.946646 -237.50802) (xy 378.896782 -237.49784) (xy 378.849196 -237.479793)
			(xy 378.805122 -237.454347) (xy 378.7657 -237.42216) (xy 378.731952 -237.384066) (xy 378.704751 -237.341052)
			(xy 378.684803 -237.294232) (xy 378.672624 -237.244818) (xy 378.668529 -237.19409) (xy 377.420632 -237.19409)
			(xy 377.42012 -237.219536) (xy 377.411956 -237.26977) (xy 377.39584 -237.318044) (xy 377.372189 -237.363107)
			(xy 377.341616 -237.403793) (xy 377.304912 -237.439048) (xy 377.263028 -237.467958) (xy 377.217049 -237.489775)
			(xy 377.168165 -237.503935) (xy 377.117644 -237.510069) (xy 377.066792 -237.50802) (xy 377.016928 -237.49784)
			(xy 376.969342 -237.479793) (xy 376.925268 -237.454347) (xy 376.885846 -237.42216) (xy 376.852098 -237.384066)
			(xy 376.824897 -237.341052) (xy 376.804949 -237.294232) (xy 376.79277 -237.244818) (xy 376.788675 -237.19409)
			(xy 376.48017 -237.19409) (xy 376.48017 -237.218915) (xy 376.472406 -237.267932) (xy 376.457069 -237.315132)
			(xy 376.434536 -237.359351) (xy 376.405362 -237.3995) (xy 376.370267 -237.434591) (xy 376.330113 -237.463759)
			(xy 376.285891 -237.486285) (xy 376.23869 -237.501616) (xy 376.189671 -237.509374) (xy 376.164856 -237.509812)
			(xy 376.137942 -237.509263) (xy 376.084896 -237.50012) (xy 376.034171 -237.482106) (xy 376.010424 -237.469426)
			(xy 375.999756 -237.46333) (xy 375.975372 -237.462314) (xy 375.903998 -237.495588) (xy 375.893616 -237.501147)
			(xy 375.878953 -237.519544) (xy 375.875804 -237.530894) (xy 375.875804 -237.531402) (xy 375.867821 -237.568093)
			(xy 375.848889 -237.640767) (xy 375.837958 -237.67669) (xy 375.835148 -237.687595) (xy 375.838223 -237.709875)
			(xy 375.850545 -237.728691) (xy 375.859802 -237.73511) (xy 375.880702 -237.748456) (xy 375.91841 -237.780656)
			(xy 375.950617 -237.81836) (xy 375.976528 -237.860638) (xy 375.995505 -237.906449) (xy 376.007082 -237.954665)
			(xy 376.010973 -238.004096) (xy 376.328952 -238.004096) (xy 376.332912 -237.955042) (xy 376.344689 -237.907258)
			(xy 376.36398 -237.861982) (xy 376.390283 -237.820386) (xy 376.422918 -237.783549) (xy 376.461039 -237.752424)
			(xy 376.50366 -237.727817) (xy 376.549676 -237.710365) (xy 376.597895 -237.700521) (xy 376.64707 -237.69854)
			(xy 376.695925 -237.704472) (xy 376.743196 -237.718164) (xy 376.787658 -237.739262) (xy 376.828161 -237.767218)
			(xy 376.863654 -237.80131) (xy 376.893219 -237.840654) (xy 376.91609 -237.884231) (xy 376.931674 -237.930912)
			(xy 376.939569 -237.979489) (xy 376.940064 -238.004096) (xy 377.258575 -238.004096) (xy 377.26267 -237.953368)
			(xy 377.274849 -237.903954) (xy 377.294797 -237.857134) (xy 377.321998 -237.81412) (xy 377.355746 -237.776026)
			(xy 377.395168 -237.743839) (xy 377.439242 -237.718393) (xy 377.486828 -237.700346) (xy 377.536692 -237.690166)
			(xy 377.587544 -237.688117) (xy 377.638065 -237.694251) (xy 377.686949 -237.708411) (xy 377.732928 -237.730228)
			(xy 377.774812 -237.759138) (xy 377.811516 -237.794393) (xy 377.842089 -237.835079) (xy 377.86574 -237.880142)
			(xy 377.881856 -237.928416) (xy 377.89002 -237.97865) (xy 377.890532 -238.004096) (xy 378.20906 -238.004096)
			(xy 378.21302 -237.955042) (xy 378.224797 -237.907258) (xy 378.244088 -237.861982) (xy 378.270391 -237.820386)
			(xy 378.303026 -237.783549) (xy 378.341147 -237.752424) (xy 378.383768 -237.727817) (xy 378.429784 -237.710365)
			(xy 378.478003 -237.700521) (xy 378.527178 -237.69854) (xy 378.576033 -237.704472) (xy 378.623304 -237.718164)
			(xy 378.667766 -237.739262) (xy 378.708269 -237.767218) (xy 378.743762 -237.80131) (xy 378.773327 -237.840654)
			(xy 378.796198 -237.884231) (xy 378.811782 -237.930912) (xy 378.819677 -237.979489) (xy 378.820172 -238.004096)
			(xy 379.138683 -238.004096) (xy 379.142778 -237.953368) (xy 379.154957 -237.903954) (xy 379.174905 -237.857134)
			(xy 379.202106 -237.81412) (xy 379.235854 -237.776026) (xy 379.275276 -237.743839) (xy 379.31935 -237.718393)
			(xy 379.366936 -237.700346) (xy 379.4168 -237.690166) (xy 379.467652 -237.688117) (xy 379.518173 -237.694251)
			(xy 379.567057 -237.708411) (xy 379.613036 -237.730228) (xy 379.65492 -237.759138) (xy 379.691624 -237.794393)
			(xy 379.722197 -237.835079) (xy 379.745848 -237.880142) (xy 379.761964 -237.928416) (xy 379.770128 -237.97865)
			(xy 379.77064 -238.004096) (xy 380.078483 -238.004096) (xy 380.082578 -237.953368) (xy 380.094757 -237.903954)
			(xy 380.114705 -237.857134) (xy 380.141906 -237.81412) (xy 380.175654 -237.776026) (xy 380.215076 -237.743839)
			(xy 380.25915 -237.718393) (xy 380.306736 -237.700346) (xy 380.3566 -237.690166) (xy 380.407452 -237.688117)
			(xy 380.457973 -237.694251) (xy 380.506857 -237.708411) (xy 380.552836 -237.730228) (xy 380.59472 -237.759138)
			(xy 380.631424 -237.794393) (xy 380.661997 -237.835079) (xy 380.685648 -237.880142) (xy 380.701764 -237.928416)
			(xy 380.709928 -237.97865) (xy 380.71044 -238.004096) (xy 381.028968 -238.004096) (xy 381.032928 -237.955042)
			(xy 381.044705 -237.907258) (xy 381.063996 -237.861982) (xy 381.090299 -237.820386) (xy 381.122934 -237.783549)
			(xy 381.161055 -237.752424) (xy 381.203676 -237.727817) (xy 381.249692 -237.710365) (xy 381.297911 -237.700521)
			(xy 381.347086 -237.69854) (xy 381.395941 -237.704472) (xy 381.443212 -237.718164) (xy 381.487674 -237.739262)
			(xy 381.528177 -237.767218) (xy 381.56367 -237.80131) (xy 381.593235 -237.840654) (xy 381.616106 -237.884231)
			(xy 381.63169 -237.930912) (xy 381.639585 -237.979489) (xy 381.64008 -238.004096) (xy 381.969022 -238.004096)
			(xy 381.972982 -237.955042) (xy 381.984759 -237.907258) (xy 382.00405 -237.861982) (xy 382.030353 -237.820386)
			(xy 382.062988 -237.783549) (xy 382.101109 -237.752424) (xy 382.14373 -237.727817) (xy 382.189746 -237.710365)
			(xy 382.237965 -237.700521) (xy 382.28714 -237.69854) (xy 382.335995 -237.704472) (xy 382.383266 -237.718164)
			(xy 382.427728 -237.739262) (xy 382.468231 -237.767218) (xy 382.503724 -237.80131) (xy 382.533289 -237.840654)
			(xy 382.55616 -237.884231) (xy 382.571744 -237.930912) (xy 382.579639 -237.979489) (xy 382.580134 -238.004096)
			(xy 382.909076 -238.004096) (xy 382.913036 -237.955042) (xy 382.924813 -237.907258) (xy 382.944104 -237.861982)
			(xy 382.970407 -237.820386) (xy 383.003042 -237.783549) (xy 383.041163 -237.752424) (xy 383.083784 -237.727817)
			(xy 383.1298 -237.710365) (xy 383.178019 -237.700521) (xy 383.227194 -237.69854) (xy 383.276049 -237.704472)
			(xy 383.32332 -237.718164) (xy 383.367782 -237.739262) (xy 383.408285 -237.767218) (xy 383.443778 -237.80131)
			(xy 383.473343 -237.840654) (xy 383.496214 -237.884231) (xy 383.511798 -237.930912) (xy 383.519693 -237.979489)
			(xy 383.520188 -238.004096) (xy 383.84913 -238.004096) (xy 383.85309 -237.955042) (xy 383.864867 -237.907258)
			(xy 383.884158 -237.861982) (xy 383.910461 -237.820386) (xy 383.943096 -237.783549) (xy 383.981217 -237.752424)
			(xy 384.023838 -237.727817) (xy 384.069854 -237.710365) (xy 384.118073 -237.700521) (xy 384.167248 -237.69854)
			(xy 384.216103 -237.704472) (xy 384.263374 -237.718164) (xy 384.307836 -237.739262) (xy 384.348339 -237.767218)
			(xy 384.383832 -237.80131) (xy 384.413397 -237.840654) (xy 384.436268 -237.884231) (xy 384.451852 -237.930912)
			(xy 384.459747 -237.979489) (xy 384.460242 -238.004096) (xy 384.459747 -238.028703) (xy 384.451852 -238.07728)
			(xy 384.436268 -238.123961) (xy 384.413397 -238.167538) (xy 384.383832 -238.206882) (xy 384.348339 -238.240974)
			(xy 384.307836 -238.26893) (xy 384.263374 -238.290028) (xy 384.216103 -238.30372) (xy 384.167248 -238.309652)
			(xy 384.118073 -238.307671) (xy 384.069854 -238.297827) (xy 384.023838 -238.280375) (xy 383.981217 -238.255768)
			(xy 383.943096 -238.224643) (xy 383.910461 -238.187806) (xy 383.884158 -238.14621) (xy 383.864867 -238.100934)
			(xy 383.85309 -238.05315) (xy 383.84913 -238.004096) (xy 383.520188 -238.004096) (xy 383.519693 -238.028703)
			(xy 383.511798 -238.07728) (xy 383.496214 -238.123961) (xy 383.473343 -238.167538) (xy 383.443778 -238.206882)
			(xy 383.408285 -238.240974) (xy 383.367782 -238.26893) (xy 383.32332 -238.290028) (xy 383.276049 -238.30372)
			(xy 383.227194 -238.309652) (xy 383.178019 -238.307671) (xy 383.1298 -238.297827) (xy 383.083784 -238.280375)
			(xy 383.041163 -238.255768) (xy 383.003042 -238.224643) (xy 382.970407 -238.187806) (xy 382.944104 -238.14621)
			(xy 382.924813 -238.100934) (xy 382.913036 -238.05315) (xy 382.909076 -238.004096) (xy 382.580134 -238.004096)
			(xy 382.579639 -238.028703) (xy 382.571744 -238.07728) (xy 382.55616 -238.123961) (xy 382.533289 -238.167538)
			(xy 382.503724 -238.206882) (xy 382.468231 -238.240974) (xy 382.427728 -238.26893) (xy 382.383266 -238.290028)
			(xy 382.335995 -238.30372) (xy 382.28714 -238.309652) (xy 382.237965 -238.307671) (xy 382.189746 -238.297827)
			(xy 382.14373 -238.280375) (xy 382.101109 -238.255768) (xy 382.062988 -238.224643) (xy 382.030353 -238.187806)
			(xy 382.00405 -238.14621) (xy 381.984759 -238.100934) (xy 381.972982 -238.05315) (xy 381.969022 -238.004096)
			(xy 381.64008 -238.004096) (xy 381.639585 -238.028703) (xy 381.63169 -238.07728) (xy 381.616106 -238.123961)
			(xy 381.593235 -238.167538) (xy 381.56367 -238.206882) (xy 381.528177 -238.240974) (xy 381.487674 -238.26893)
			(xy 381.443212 -238.290028) (xy 381.395941 -238.30372) (xy 381.347086 -238.309652) (xy 381.297911 -238.307671)
			(xy 381.249692 -238.297827) (xy 381.203676 -238.280375) (xy 381.161055 -238.255768) (xy 381.122934 -238.224643)
			(xy 381.090299 -238.187806) (xy 381.063996 -238.14621) (xy 381.044705 -238.100934) (xy 381.032928 -238.05315)
			(xy 381.028968 -238.004096) (xy 380.71044 -238.004096) (xy 380.709928 -238.029542) (xy 380.701764 -238.079776)
			(xy 380.685648 -238.12805) (xy 380.661997 -238.173113) (xy 380.631424 -238.213799) (xy 380.59472 -238.249054)
			(xy 380.552836 -238.277964) (xy 380.506857 -238.299781) (xy 380.457973 -238.313941) (xy 380.407452 -238.320075)
			(xy 380.3566 -238.318026) (xy 380.306736 -238.307846) (xy 380.25915 -238.289799) (xy 380.215076 -238.264353)
			(xy 380.175654 -238.232166) (xy 380.141906 -238.194072) (xy 380.114705 -238.151058) (xy 380.094757 -238.104238)
			(xy 380.082578 -238.054824) (xy 380.078483 -238.004096) (xy 379.77064 -238.004096) (xy 379.770128 -238.029542)
			(xy 379.761964 -238.079776) (xy 379.745848 -238.12805) (xy 379.722197 -238.173113) (xy 379.691624 -238.213799)
			(xy 379.65492 -238.249054) (xy 379.613036 -238.277964) (xy 379.567057 -238.299781) (xy 379.518173 -238.313941)
			(xy 379.467652 -238.320075) (xy 379.4168 -238.318026) (xy 379.366936 -238.307846) (xy 379.31935 -238.289799)
			(xy 379.275276 -238.264353) (xy 379.235854 -238.232166) (xy 379.202106 -238.194072) (xy 379.174905 -238.151058)
			(xy 379.154957 -238.104238) (xy 379.142778 -238.054824) (xy 379.138683 -238.004096) (xy 378.820172 -238.004096)
			(xy 378.819677 -238.028703) (xy 378.811782 -238.07728) (xy 378.796198 -238.123961) (xy 378.773327 -238.167538)
			(xy 378.743762 -238.206882) (xy 378.708269 -238.240974) (xy 378.667766 -238.26893) (xy 378.623304 -238.290028)
			(xy 378.576033 -238.30372) (xy 378.527178 -238.309652) (xy 378.478003 -238.307671) (xy 378.429784 -238.297827)
			(xy 378.383768 -238.280375) (xy 378.341147 -238.255768) (xy 378.303026 -238.224643) (xy 378.270391 -238.187806)
			(xy 378.244088 -238.14621) (xy 378.224797 -238.100934) (xy 378.21302 -238.05315) (xy 378.20906 -238.004096)
			(xy 377.890532 -238.004096) (xy 377.89002 -238.029542) (xy 377.881856 -238.079776) (xy 377.86574 -238.12805)
			(xy 377.842089 -238.173113) (xy 377.811516 -238.213799) (xy 377.774812 -238.249054) (xy 377.732928 -238.277964)
			(xy 377.686949 -238.299781) (xy 377.638065 -238.313941) (xy 377.587544 -238.320075) (xy 377.536692 -238.318026)
			(xy 377.486828 -238.307846) (xy 377.439242 -238.289799) (xy 377.395168 -238.264353) (xy 377.355746 -238.232166)
			(xy 377.321998 -238.194072) (xy 377.294797 -238.151058) (xy 377.274849 -238.104238) (xy 377.26267 -238.054824)
			(xy 377.258575 -238.004096) (xy 376.940064 -238.004096) (xy 376.939569 -238.028703) (xy 376.931674 -238.07728)
			(xy 376.91609 -238.123961) (xy 376.893219 -238.167538) (xy 376.863654 -238.206882) (xy 376.828161 -238.240974)
			(xy 376.787658 -238.26893) (xy 376.743196 -238.290028) (xy 376.695925 -238.30372) (xy 376.64707 -238.309652)
			(xy 376.597895 -238.307671) (xy 376.549676 -238.297827) (xy 376.50366 -238.280375) (xy 376.461039 -238.255768)
			(xy 376.422918 -238.224643) (xy 376.390283 -238.187806) (xy 376.36398 -238.14621) (xy 376.344689 -238.100934)
			(xy 376.332912 -238.05315) (xy 376.328952 -238.004096) (xy 376.010973 -238.004096) (xy 376.010973 -238.004098)
			(xy 376.007083 -238.053531) (xy 375.995507 -238.101747) (xy 375.97653 -238.147559) (xy 375.950619 -238.189837)
			(xy 375.918413 -238.227541) (xy 375.880705 -238.259742) (xy 375.859802 -238.273082) (xy 375.850565 -238.279501)
			(xy 375.838317 -238.298336) (xy 375.835225 -238.320589) (xy 375.837958 -238.331502) (xy 375.84888 -238.367428)
			(xy 375.867812 -238.440101) (xy 375.875804 -238.47679) (xy 375.875804 -238.477298) (xy 375.878853 -238.488695)
			(xy 375.893561 -238.507102) (xy 375.903998 -238.512604) (xy 375.975372 -238.545878) (xy 375.999756 -238.544862)
			(xy 376.010424 -238.538766) (xy 376.034161 -238.526064) (xy 376.084891 -238.508056) (xy 376.13794 -238.498915)
			(xy 376.164856 -238.49838) (xy 376.18967 -238.498838) (xy 376.238687 -238.506595) (xy 376.285887 -238.521926)
			(xy 376.330107 -238.544452) (xy 376.370259 -238.573618) (xy 376.405353 -238.608708) (xy 376.434525 -238.648855)
			(xy 376.457057 -238.693072) (xy 376.472394 -238.74027) (xy 376.480158 -238.789286) (xy 376.480158 -238.814102)
			(xy 376.788675 -238.814102) (xy 376.79277 -238.763374) (xy 376.804949 -238.71396) (xy 376.824897 -238.66714)
			(xy 376.852098 -238.624126) (xy 376.885846 -238.586032) (xy 376.925268 -238.553845) (xy 376.969342 -238.528399)
			(xy 377.016928 -238.510352) (xy 377.066792 -238.500172) (xy 377.117644 -238.498123) (xy 377.168165 -238.504257)
			(xy 377.217049 -238.518417) (xy 377.263028 -238.540234) (xy 377.304912 -238.569144) (xy 377.341616 -238.604399)
			(xy 377.372189 -238.645085) (xy 377.39584 -238.690148) (xy 377.411956 -238.738422) (xy 377.42012 -238.788656)
			(xy 377.420632 -238.814102) (xy 377.738906 -238.814102) (xy 377.742866 -238.765048) (xy 377.754643 -238.717264)
			(xy 377.773934 -238.671988) (xy 377.800237 -238.630392) (xy 377.832872 -238.593555) (xy 377.870993 -238.56243)
			(xy 377.913614 -238.537823) (xy 377.95963 -238.520371) (xy 378.007849 -238.510527) (xy 378.057024 -238.508546)
			(xy 378.105879 -238.514478) (xy 378.15315 -238.52817) (xy 378.197612 -238.549268) (xy 378.238115 -238.577224)
			(xy 378.273608 -238.611316) (xy 378.303173 -238.65066) (xy 378.326044 -238.694237) (xy 378.341628 -238.740918)
			(xy 378.349523 -238.789495) (xy 378.350018 -238.814102) (xy 378.668529 -238.814102) (xy 378.672624 -238.763374)
			(xy 378.684803 -238.71396) (xy 378.704751 -238.66714) (xy 378.731952 -238.624126) (xy 378.7657 -238.586032)
			(xy 378.805122 -238.553845) (xy 378.849196 -238.528399) (xy 378.896782 -238.510352) (xy 378.946646 -238.500172)
			(xy 378.997498 -238.498123) (xy 379.048019 -238.504257) (xy 379.096903 -238.518417) (xy 379.142882 -238.540234)
			(xy 379.184766 -238.569144) (xy 379.22147 -238.604399) (xy 379.252043 -238.645085) (xy 379.275694 -238.690148)
			(xy 379.29181 -238.738422) (xy 379.299974 -238.788656) (xy 379.300486 -238.814102) (xy 379.619014 -238.814102)
			(xy 379.622974 -238.765048) (xy 379.634751 -238.717264) (xy 379.654042 -238.671988) (xy 379.680345 -238.630392)
			(xy 379.71298 -238.593555) (xy 379.751101 -238.56243) (xy 379.793722 -238.537823) (xy 379.839738 -238.520371)
			(xy 379.887957 -238.510527) (xy 379.937132 -238.508546) (xy 379.985987 -238.514478) (xy 380.033258 -238.52817)
			(xy 380.07772 -238.549268) (xy 380.118223 -238.577224) (xy 380.153716 -238.611316) (xy 380.183281 -238.65066)
			(xy 380.206152 -238.694237) (xy 380.221736 -238.740918) (xy 380.229631 -238.789495) (xy 380.230126 -238.814102)
			(xy 380.548637 -238.814102) (xy 380.552732 -238.763374) (xy 380.564911 -238.71396) (xy 380.584859 -238.66714)
			(xy 380.61206 -238.624126) (xy 380.645808 -238.586032) (xy 380.68523 -238.553845) (xy 380.729304 -238.528399)
			(xy 380.77689 -238.510352) (xy 380.826754 -238.500172) (xy 380.877606 -238.498123) (xy 380.928127 -238.504257)
			(xy 380.977011 -238.518417) (xy 381.02299 -238.540234) (xy 381.064874 -238.569144) (xy 381.101578 -238.604399)
			(xy 381.132151 -238.645085) (xy 381.155802 -238.690148) (xy 381.171918 -238.738422) (xy 381.180082 -238.788656)
			(xy 381.180594 -238.814102) (xy 381.499122 -238.814102) (xy 381.503082 -238.765048) (xy 381.514859 -238.717264)
			(xy 381.53415 -238.671988) (xy 381.560453 -238.630392) (xy 381.593088 -238.593555) (xy 381.631209 -238.56243)
			(xy 381.67383 -238.537823) (xy 381.719846 -238.520371) (xy 381.768065 -238.510527) (xy 381.81724 -238.508546)
			(xy 381.866095 -238.514478) (xy 381.913366 -238.52817) (xy 381.957828 -238.549268) (xy 381.998331 -238.577224)
			(xy 382.033824 -238.611316) (xy 382.063389 -238.65066) (xy 382.08626 -238.694237) (xy 382.101844 -238.740918)
			(xy 382.109739 -238.789495) (xy 382.110234 -238.814102) (xy 382.438922 -238.814102) (xy 382.442882 -238.765048)
			(xy 382.454659 -238.717264) (xy 382.47395 -238.671988) (xy 382.500253 -238.630392) (xy 382.532888 -238.593555)
			(xy 382.571009 -238.56243) (xy 382.61363 -238.537823) (xy 382.659646 -238.520371) (xy 382.707865 -238.510527)
			(xy 382.75704 -238.508546) (xy 382.805895 -238.514478) (xy 382.853166 -238.52817) (xy 382.897628 -238.549268)
			(xy 382.938131 -238.577224) (xy 382.973624 -238.611316) (xy 383.003189 -238.65066) (xy 383.02606 -238.694237)
			(xy 383.041644 -238.740918) (xy 383.049539 -238.789495) (xy 383.050034 -238.814102) (xy 383.378976 -238.814102)
			(xy 383.382936 -238.765048) (xy 383.394713 -238.717264) (xy 383.414004 -238.671988) (xy 383.440307 -238.630392)
			(xy 383.472942 -238.593555) (xy 383.511063 -238.56243) (xy 383.553684 -238.537823) (xy 383.5997 -238.520371)
			(xy 383.647919 -238.510527) (xy 383.697094 -238.508546) (xy 383.745949 -238.514478) (xy 383.79322 -238.52817)
			(xy 383.837682 -238.549268) (xy 383.878185 -238.577224) (xy 383.913678 -238.611316) (xy 383.943243 -238.65066)
			(xy 383.966114 -238.694237) (xy 383.981698 -238.740918) (xy 383.989593 -238.789495) (xy 383.990088 -238.814102)
			(xy 383.989593 -238.838709) (xy 383.981698 -238.887286) (xy 383.966114 -238.933967) (xy 383.943243 -238.977544)
			(xy 383.913678 -239.016888) (xy 383.878185 -239.05098) (xy 383.837682 -239.078936) (xy 383.79322 -239.100034)
			(xy 383.745949 -239.113726) (xy 383.697094 -239.119658) (xy 383.647919 -239.117677) (xy 383.5997 -239.107833)
			(xy 383.553684 -239.090381) (xy 383.511063 -239.065774) (xy 383.472942 -239.034649) (xy 383.440307 -238.997812)
			(xy 383.414004 -238.956216) (xy 383.394713 -238.91094) (xy 383.382936 -238.863156) (xy 383.378976 -238.814102)
			(xy 383.050034 -238.814102) (xy 383.049539 -238.838709) (xy 383.041644 -238.887286) (xy 383.02606 -238.933967)
			(xy 383.003189 -238.977544) (xy 382.973624 -239.016888) (xy 382.938131 -239.05098) (xy 382.897628 -239.078936)
			(xy 382.853166 -239.100034) (xy 382.805895 -239.113726) (xy 382.75704 -239.119658) (xy 382.707865 -239.117677)
			(xy 382.659646 -239.107833) (xy 382.61363 -239.090381) (xy 382.571009 -239.065774) (xy 382.532888 -239.034649)
			(xy 382.500253 -238.997812) (xy 382.47395 -238.956216) (xy 382.454659 -238.91094) (xy 382.442882 -238.863156)
			(xy 382.438922 -238.814102) (xy 382.110234 -238.814102) (xy 382.109739 -238.838709) (xy 382.101844 -238.887286)
			(xy 382.08626 -238.933967) (xy 382.063389 -238.977544) (xy 382.033824 -239.016888) (xy 381.998331 -239.05098)
			(xy 381.957828 -239.078936) (xy 381.913366 -239.100034) (xy 381.866095 -239.113726) (xy 381.81724 -239.119658)
			(xy 381.768065 -239.117677) (xy 381.719846 -239.107833) (xy 381.67383 -239.090381) (xy 381.631209 -239.065774)
			(xy 381.593088 -239.034649) (xy 381.560453 -238.997812) (xy 381.53415 -238.956216) (xy 381.514859 -238.91094)
			(xy 381.503082 -238.863156) (xy 381.499122 -238.814102) (xy 381.180594 -238.814102) (xy 381.180082 -238.839548)
			(xy 381.171918 -238.889782) (xy 381.155802 -238.938056) (xy 381.132151 -238.983119) (xy 381.101578 -239.023805)
			(xy 381.064874 -239.05906) (xy 381.02299 -239.08797) (xy 380.977011 -239.109787) (xy 380.928127 -239.123947)
			(xy 380.877606 -239.130081) (xy 380.826754 -239.128032) (xy 380.77689 -239.117852) (xy 380.729304 -239.099805)
			(xy 380.68523 -239.074359) (xy 380.645808 -239.042172) (xy 380.61206 -239.004078) (xy 380.584859 -238.961064)
			(xy 380.564911 -238.914244) (xy 380.552732 -238.86483) (xy 380.548637 -238.814102) (xy 380.230126 -238.814102)
			(xy 380.229631 -238.838709) (xy 380.221736 -238.887286) (xy 380.206152 -238.933967) (xy 380.183281 -238.977544)
			(xy 380.153716 -239.016888) (xy 380.118223 -239.05098) (xy 380.07772 -239.078936) (xy 380.033258 -239.100034)
			(xy 379.985987 -239.113726) (xy 379.937132 -239.119658) (xy 379.887957 -239.117677) (xy 379.839738 -239.107833)
			(xy 379.793722 -239.090381) (xy 379.751101 -239.065774) (xy 379.71298 -239.034649) (xy 379.680345 -238.997812)
			(xy 379.654042 -238.956216) (xy 379.634751 -238.91094) (xy 379.622974 -238.863156) (xy 379.619014 -238.814102)
			(xy 379.300486 -238.814102) (xy 379.299974 -238.839548) (xy 379.29181 -238.889782) (xy 379.275694 -238.938056)
			(xy 379.252043 -238.983119) (xy 379.22147 -239.023805) (xy 379.184766 -239.05906) (xy 379.142882 -239.08797)
			(xy 379.096903 -239.109787) (xy 379.048019 -239.123947) (xy 378.997498 -239.130081) (xy 378.946646 -239.128032)
			(xy 378.896782 -239.117852) (xy 378.849196 -239.099805) (xy 378.805122 -239.074359) (xy 378.7657 -239.042172)
			(xy 378.731952 -239.004078) (xy 378.704751 -238.961064) (xy 378.684803 -238.914244) (xy 378.672624 -238.86483)
			(xy 378.668529 -238.814102) (xy 378.350018 -238.814102) (xy 378.349523 -238.838709) (xy 378.341628 -238.887286)
			(xy 378.326044 -238.933967) (xy 378.303173 -238.977544) (xy 378.273608 -239.016888) (xy 378.238115 -239.05098)
			(xy 378.197612 -239.078936) (xy 378.15315 -239.100034) (xy 378.105879 -239.113726) (xy 378.057024 -239.119658)
			(xy 378.007849 -239.117677) (xy 377.95963 -239.107833) (xy 377.913614 -239.090381) (xy 377.870993 -239.065774)
			(xy 377.832872 -239.034649) (xy 377.800237 -238.997812) (xy 377.773934 -238.956216) (xy 377.754643 -238.91094)
			(xy 377.742866 -238.863156) (xy 377.738906 -238.814102) (xy 377.420632 -238.814102) (xy 377.42012 -238.839548)
			(xy 377.411956 -238.889782) (xy 377.39584 -238.938056) (xy 377.372189 -238.983119) (xy 377.341616 -239.023805)
			(xy 377.304912 -239.05906) (xy 377.263028 -239.08797) (xy 377.217049 -239.109787) (xy 377.168165 -239.123947)
			(xy 377.117644 -239.130081) (xy 377.066792 -239.128032) (xy 377.016928 -239.117852) (xy 376.969342 -239.099805)
			(xy 376.925268 -239.074359) (xy 376.885846 -239.042172) (xy 376.852098 -239.004078) (xy 376.824897 -238.961064)
			(xy 376.804949 -238.914244) (xy 376.79277 -238.86483) (xy 376.788675 -238.814102) (xy 376.480158 -238.814102)
			(xy 376.480158 -238.838914) (xy 376.472394 -238.88793) (xy 376.457057 -238.935128) (xy 376.434525 -238.979345)
			(xy 376.405353 -239.019492) (xy 376.370259 -239.054582) (xy 376.330107 -239.083748) (xy 376.285887 -239.106274)
			(xy 376.238687 -239.121605) (xy 376.18967 -239.129362) (xy 376.164856 -239.129824) (xy 376.137942 -239.129275)
			(xy 376.084895 -239.120132) (xy 376.03417 -239.102119) (xy 376.010424 -239.089438) (xy 375.999756 -239.083342)
			(xy 375.975372 -239.082326) (xy 375.903998 -239.1156) (xy 375.893605 -239.121152) (xy 375.878912 -239.139541)
			(xy 375.875804 -239.150906) (xy 375.875804 -239.151414) (xy 375.86782 -239.188105) (xy 375.848889 -239.260778)
			(xy 375.837958 -239.296702) (xy 375.83515 -239.307606) (xy 375.83823 -239.329883) (xy 375.850553 -239.348694)
			(xy 375.859802 -239.355122) (xy 375.880701 -239.368468) (xy 375.918407 -239.400668) (xy 375.950612 -239.438371)
			(xy 375.976521 -239.480648) (xy 375.995498 -239.526458) (xy 376.007073 -239.574672) (xy 376.010963 -239.624104)
			(xy 376.010963 -239.624108) (xy 376.328952 -239.624108) (xy 376.332912 -239.575054) (xy 376.344689 -239.52727)
			(xy 376.36398 -239.481994) (xy 376.390283 -239.440398) (xy 376.422918 -239.403561) (xy 376.461039 -239.372436)
			(xy 376.50366 -239.347829) (xy 376.549676 -239.330377) (xy 376.597895 -239.320533) (xy 376.64707 -239.318552)
			(xy 376.695925 -239.324484) (xy 376.743196 -239.338176) (xy 376.787658 -239.359274) (xy 376.828161 -239.38723)
			(xy 376.863654 -239.421322) (xy 376.893219 -239.460666) (xy 376.91609 -239.504243) (xy 376.931674 -239.550924)
			(xy 376.939569 -239.599501) (xy 376.940064 -239.624108) (xy 377.258575 -239.624108) (xy 377.26267 -239.57338)
			(xy 377.274849 -239.523966) (xy 377.294797 -239.477146) (xy 377.321998 -239.434132) (xy 377.355746 -239.396038)
			(xy 377.395168 -239.363851) (xy 377.439242 -239.338405) (xy 377.486828 -239.320358) (xy 377.536692 -239.310178)
			(xy 377.587544 -239.308129) (xy 377.638065 -239.314263) (xy 377.686949 -239.328423) (xy 377.732928 -239.35024)
			(xy 377.774812 -239.37915) (xy 377.811516 -239.414405) (xy 377.842089 -239.455091) (xy 377.86574 -239.500154)
			(xy 377.881856 -239.548428) (xy 377.89002 -239.598662) (xy 377.890532 -239.624108) (xy 379.138683 -239.624108)
			(xy 379.142778 -239.57338) (xy 379.154957 -239.523966) (xy 379.174905 -239.477146) (xy 379.202106 -239.434132)
			(xy 379.235854 -239.396038) (xy 379.275276 -239.363851) (xy 379.31935 -239.338405) (xy 379.366936 -239.320358)
			(xy 379.4168 -239.310178) (xy 379.467652 -239.308129) (xy 379.518173 -239.314263) (xy 379.567057 -239.328423)
			(xy 379.613036 -239.35024) (xy 379.65492 -239.37915) (xy 379.691624 -239.414405) (xy 379.722197 -239.455091)
			(xy 379.745848 -239.500154) (xy 379.761964 -239.548428) (xy 379.770128 -239.598662) (xy 379.77064 -239.624108)
			(xy 380.078483 -239.624108) (xy 380.082578 -239.57338) (xy 380.094757 -239.523966) (xy 380.114705 -239.477146)
			(xy 380.141906 -239.434132) (xy 380.175654 -239.396038) (xy 380.215076 -239.363851) (xy 380.25915 -239.338405)
			(xy 380.306736 -239.320358) (xy 380.3566 -239.310178) (xy 380.407452 -239.308129) (xy 380.457973 -239.314263)
			(xy 380.506857 -239.328423) (xy 380.552836 -239.35024) (xy 380.59472 -239.37915) (xy 380.631424 -239.414405)
			(xy 380.661997 -239.455091) (xy 380.685648 -239.500154) (xy 380.701764 -239.548428) (xy 380.709928 -239.598662)
			(xy 380.71044 -239.624108) (xy 381.028968 -239.624108) (xy 381.032928 -239.575054) (xy 381.044705 -239.52727)
			(xy 381.063996 -239.481994) (xy 381.090299 -239.440398) (xy 381.122934 -239.403561) (xy 381.161055 -239.372436)
			(xy 381.203676 -239.347829) (xy 381.249692 -239.330377) (xy 381.297911 -239.320533) (xy 381.347086 -239.318552)
			(xy 381.395941 -239.324484) (xy 381.443212 -239.338176) (xy 381.487674 -239.359274) (xy 381.528177 -239.38723)
			(xy 381.56367 -239.421322) (xy 381.593235 -239.460666) (xy 381.616106 -239.504243) (xy 381.63169 -239.550924)
			(xy 381.639585 -239.599501) (xy 381.64008 -239.624108) (xy 381.969022 -239.624108) (xy 381.972982 -239.575054)
			(xy 381.984759 -239.52727) (xy 382.00405 -239.481994) (xy 382.030353 -239.440398) (xy 382.062988 -239.403561)
			(xy 382.101109 -239.372436) (xy 382.14373 -239.347829) (xy 382.189746 -239.330377) (xy 382.237965 -239.320533)
			(xy 382.28714 -239.318552) (xy 382.335995 -239.324484) (xy 382.383266 -239.338176) (xy 382.427728 -239.359274)
			(xy 382.468231 -239.38723) (xy 382.503724 -239.421322) (xy 382.533289 -239.460666) (xy 382.55616 -239.504243)
			(xy 382.571744 -239.550924) (xy 382.579639 -239.599501) (xy 382.580134 -239.624108) (xy 382.909076 -239.624108)
			(xy 382.913036 -239.575054) (xy 382.924813 -239.52727) (xy 382.944104 -239.481994) (xy 382.970407 -239.440398)
			(xy 383.003042 -239.403561) (xy 383.041163 -239.372436) (xy 383.083784 -239.347829) (xy 383.1298 -239.330377)
			(xy 383.178019 -239.320533) (xy 383.227194 -239.318552) (xy 383.276049 -239.324484) (xy 383.32332 -239.338176)
			(xy 383.367782 -239.359274) (xy 383.408285 -239.38723) (xy 383.443778 -239.421322) (xy 383.473343 -239.460666)
			(xy 383.496214 -239.504243) (xy 383.511798 -239.550924) (xy 383.519693 -239.599501) (xy 383.520188 -239.624108)
			(xy 383.84913 -239.624108) (xy 383.85309 -239.575054) (xy 383.864867 -239.52727) (xy 383.884158 -239.481994)
			(xy 383.910461 -239.440398) (xy 383.943096 -239.403561) (xy 383.981217 -239.372436) (xy 384.023838 -239.347829)
			(xy 384.069854 -239.330377) (xy 384.118073 -239.320533) (xy 384.167248 -239.318552) (xy 384.216103 -239.324484)
			(xy 384.263374 -239.338176) (xy 384.307836 -239.359274) (xy 384.348339 -239.38723) (xy 384.383832 -239.421322)
			(xy 384.413397 -239.460666) (xy 384.436268 -239.504243) (xy 384.451852 -239.550924) (xy 384.459747 -239.599501)
			(xy 384.460242 -239.624108) (xy 384.459747 -239.648715) (xy 384.451852 -239.697292) (xy 384.436268 -239.743973)
			(xy 384.413397 -239.78755) (xy 384.383832 -239.826894) (xy 384.348339 -239.860986) (xy 384.307836 -239.888942)
			(xy 384.263374 -239.91004) (xy 384.216103 -239.923732) (xy 384.167248 -239.929664) (xy 384.118073 -239.927683)
			(xy 384.069854 -239.917839) (xy 384.023838 -239.900387) (xy 383.981217 -239.87578) (xy 383.943096 -239.844655)
			(xy 383.910461 -239.807818) (xy 383.884158 -239.766222) (xy 383.864867 -239.720946) (xy 383.85309 -239.673162)
			(xy 383.84913 -239.624108) (xy 383.520188 -239.624108) (xy 383.519693 -239.648715) (xy 383.511798 -239.697292)
			(xy 383.496214 -239.743973) (xy 383.473343 -239.78755) (xy 383.443778 -239.826894) (xy 383.408285 -239.860986)
			(xy 383.367782 -239.888942) (xy 383.32332 -239.91004) (xy 383.276049 -239.923732) (xy 383.227194 -239.929664)
			(xy 383.178019 -239.927683) (xy 383.1298 -239.917839) (xy 383.083784 -239.900387) (xy 383.041163 -239.87578)
			(xy 383.003042 -239.844655) (xy 382.970407 -239.807818) (xy 382.944104 -239.766222) (xy 382.924813 -239.720946)
			(xy 382.913036 -239.673162) (xy 382.909076 -239.624108) (xy 382.580134 -239.624108) (xy 382.579639 -239.648715)
			(xy 382.571744 -239.697292) (xy 382.55616 -239.743973) (xy 382.533289 -239.78755) (xy 382.503724 -239.826894)
			(xy 382.468231 -239.860986) (xy 382.427728 -239.888942) (xy 382.383266 -239.91004) (xy 382.335995 -239.923732)
			(xy 382.28714 -239.929664) (xy 382.237965 -239.927683) (xy 382.189746 -239.917839) (xy 382.14373 -239.900387)
			(xy 382.101109 -239.87578) (xy 382.062988 -239.844655) (xy 382.030353 -239.807818) (xy 382.00405 -239.766222)
			(xy 381.984759 -239.720946) (xy 381.972982 -239.673162) (xy 381.969022 -239.624108) (xy 381.64008 -239.624108)
			(xy 381.639585 -239.648715) (xy 381.63169 -239.697292) (xy 381.616106 -239.743973) (xy 381.593235 -239.78755)
			(xy 381.56367 -239.826894) (xy 381.528177 -239.860986) (xy 381.487674 -239.888942) (xy 381.443212 -239.91004)
			(xy 381.395941 -239.923732) (xy 381.347086 -239.929664) (xy 381.297911 -239.927683) (xy 381.249692 -239.917839)
			(xy 381.203676 -239.900387) (xy 381.161055 -239.87578) (xy 381.122934 -239.844655) (xy 381.090299 -239.807818)
			(xy 381.063996 -239.766222) (xy 381.044705 -239.720946) (xy 381.032928 -239.673162) (xy 381.028968 -239.624108)
			(xy 380.71044 -239.624108) (xy 380.709928 -239.649554) (xy 380.701764 -239.699788) (xy 380.685648 -239.748062)
			(xy 380.661997 -239.793125) (xy 380.631424 -239.833811) (xy 380.59472 -239.869066) (xy 380.552836 -239.897976)
			(xy 380.506857 -239.919793) (xy 380.457973 -239.933953) (xy 380.407452 -239.940087) (xy 380.3566 -239.938038)
			(xy 380.306736 -239.927858) (xy 380.25915 -239.909811) (xy 380.215076 -239.884365) (xy 380.175654 -239.852178)
			(xy 380.141906 -239.814084) (xy 380.114705 -239.77107) (xy 380.094757 -239.72425) (xy 380.082578 -239.674836)
			(xy 380.078483 -239.624108) (xy 379.77064 -239.624108) (xy 379.770128 -239.649554) (xy 379.761964 -239.699788)
			(xy 379.745848 -239.748062) (xy 379.722197 -239.793125) (xy 379.691624 -239.833811) (xy 379.65492 -239.869066)
			(xy 379.613036 -239.897976) (xy 379.567057 -239.919793) (xy 379.518173 -239.933953) (xy 379.467652 -239.940087)
			(xy 379.4168 -239.938038) (xy 379.366936 -239.927858) (xy 379.31935 -239.909811) (xy 379.275276 -239.884365)
			(xy 379.235854 -239.852178) (xy 379.202106 -239.814084) (xy 379.174905 -239.77107) (xy 379.154957 -239.72425)
			(xy 379.142778 -239.674836) (xy 379.138683 -239.624108) (xy 377.890532 -239.624108) (xy 377.89002 -239.649554)
			(xy 377.881856 -239.699788) (xy 377.86574 -239.748062) (xy 377.842089 -239.793125) (xy 377.811516 -239.833811)
			(xy 377.774812 -239.869066) (xy 377.732928 -239.897976) (xy 377.686949 -239.919793) (xy 377.638065 -239.933953)
			(xy 377.587544 -239.940087) (xy 377.536692 -239.938038) (xy 377.486828 -239.927858) (xy 377.439242 -239.909811)
			(xy 377.395168 -239.884365) (xy 377.355746 -239.852178) (xy 377.321998 -239.814084) (xy 377.294797 -239.77107)
			(xy 377.274849 -239.72425) (xy 377.26267 -239.674836) (xy 377.258575 -239.624108) (xy 376.940064 -239.624108)
			(xy 376.939569 -239.648715) (xy 376.931674 -239.697292) (xy 376.91609 -239.743973) (xy 376.893219 -239.78755)
			(xy 376.863654 -239.826894) (xy 376.828161 -239.860986) (xy 376.787658 -239.888942) (xy 376.743196 -239.91004)
			(xy 376.695925 -239.923732) (xy 376.64707 -239.929664) (xy 376.597895 -239.927683) (xy 376.549676 -239.917839)
			(xy 376.50366 -239.900387) (xy 376.461039 -239.87578) (xy 376.422918 -239.844655) (xy 376.390283 -239.807818)
			(xy 376.36398 -239.766222) (xy 376.344689 -239.720946) (xy 376.332912 -239.673162) (xy 376.328952 -239.624108)
			(xy 376.010963 -239.624108) (xy 376.007072 -239.673536) (xy 375.995495 -239.72175) (xy 375.976518 -239.76756)
			(xy 375.950607 -239.809836) (xy 375.918402 -239.847538) (xy 375.880694 -239.879737) (xy 375.859802 -239.893094)
			(xy 375.850567 -239.899514) (xy 375.838323 -239.918348) (xy 375.835236 -239.940598) (xy 375.837958 -239.951514)
			(xy 375.84888 -239.98744) (xy 375.867811 -240.060113) (xy 375.875804 -240.096802) (xy 375.875804 -240.09731)
			(xy 375.878855 -240.108705) (xy 375.893565 -240.127108) (xy 375.903998 -240.132616) (xy 375.975372 -240.16589)
			(xy 375.999756 -240.164874) (xy 376.010424 -240.158778) (xy 376.03416 -240.146076) (xy 376.08489 -240.128067)
			(xy 376.13794 -240.118926) (xy 376.164856 -240.118392) (xy 376.189669 -240.11885) (xy 376.238684 -240.126607)
			(xy 376.285882 -240.141937) (xy 376.330101 -240.164462) (xy 376.370251 -240.193628) (xy 376.405344 -240.228715)
			(xy 376.434515 -240.268862) (xy 376.457046 -240.313077) (xy 376.472383 -240.360273) (xy 376.480147 -240.409287)
			(xy 376.480147 -240.434114) (xy 376.788675 -240.434114) (xy 376.79277 -240.383386) (xy 376.804949 -240.333972)
			(xy 376.824897 -240.287152) (xy 376.852098 -240.244138) (xy 376.885846 -240.206044) (xy 376.925268 -240.173857)
			(xy 376.969342 -240.148411) (xy 377.016928 -240.130364) (xy 377.066792 -240.120184) (xy 377.117644 -240.118135)
			(xy 377.168165 -240.124269) (xy 377.217049 -240.138429) (xy 377.263028 -240.160246) (xy 377.304912 -240.189156)
			(xy 377.341616 -240.224411) (xy 377.372189 -240.265097) (xy 377.39584 -240.31016) (xy 377.411956 -240.358434)
			(xy 377.42012 -240.408668) (xy 377.420632 -240.434114) (xy 377.738906 -240.434114) (xy 377.742866 -240.38506)
			(xy 377.754643 -240.337276) (xy 377.773934 -240.292) (xy 377.800237 -240.250404) (xy 377.832872 -240.213567)
			(xy 377.870993 -240.182442) (xy 377.913614 -240.157835) (xy 377.95963 -240.140383) (xy 378.007849 -240.130539)
			(xy 378.057024 -240.128558) (xy 378.105879 -240.13449) (xy 378.15315 -240.148182) (xy 378.197612 -240.16928)
			(xy 378.238115 -240.197236) (xy 378.273608 -240.231328) (xy 378.303173 -240.270672) (xy 378.326044 -240.314249)
			(xy 378.341628 -240.36093) (xy 378.349523 -240.409507) (xy 378.350018 -240.434114) (xy 378.668529 -240.434114)
			(xy 378.672624 -240.383386) (xy 378.684803 -240.333972) (xy 378.704751 -240.287152) (xy 378.731952 -240.244138)
			(xy 378.7657 -240.206044) (xy 378.805122 -240.173857) (xy 378.849196 -240.148411) (xy 378.896782 -240.130364)
			(xy 378.946646 -240.120184) (xy 378.997498 -240.118135) (xy 379.048019 -240.124269) (xy 379.096903 -240.138429)
			(xy 379.142882 -240.160246) (xy 379.184766 -240.189156) (xy 379.22147 -240.224411) (xy 379.252043 -240.265097)
			(xy 379.275694 -240.31016) (xy 379.29181 -240.358434) (xy 379.299974 -240.408668) (xy 379.300486 -240.434114)
			(xy 379.619014 -240.434114) (xy 379.622974 -240.38506) (xy 379.634751 -240.337276) (xy 379.654042 -240.292)
			(xy 379.680345 -240.250404) (xy 379.71298 -240.213567) (xy 379.751101 -240.182442) (xy 379.793722 -240.157835)
			(xy 379.839738 -240.140383) (xy 379.887957 -240.130539) (xy 379.937132 -240.128558) (xy 379.985987 -240.13449)
			(xy 380.033258 -240.148182) (xy 380.07772 -240.16928) (xy 380.118223 -240.197236) (xy 380.153716 -240.231328)
			(xy 380.183281 -240.270672) (xy 380.206152 -240.314249) (xy 380.221736 -240.36093) (xy 380.229631 -240.409507)
			(xy 380.230126 -240.434114) (xy 380.548637 -240.434114) (xy 380.552732 -240.383386) (xy 380.564911 -240.333972)
			(xy 380.584859 -240.287152) (xy 380.61206 -240.244138) (xy 380.645808 -240.206044) (xy 380.68523 -240.173857)
			(xy 380.729304 -240.148411) (xy 380.77689 -240.130364) (xy 380.826754 -240.120184) (xy 380.877606 -240.118135)
			(xy 380.928127 -240.124269) (xy 380.977011 -240.138429) (xy 381.02299 -240.160246) (xy 381.064874 -240.189156)
			(xy 381.101578 -240.224411) (xy 381.132151 -240.265097) (xy 381.155802 -240.31016) (xy 381.171918 -240.358434)
			(xy 381.180082 -240.408668) (xy 381.180594 -240.434114) (xy 381.499122 -240.434114) (xy 381.503082 -240.38506)
			(xy 381.514859 -240.337276) (xy 381.53415 -240.292) (xy 381.560453 -240.250404) (xy 381.593088 -240.213567)
			(xy 381.631209 -240.182442) (xy 381.67383 -240.157835) (xy 381.719846 -240.140383) (xy 381.768065 -240.130539)
			(xy 381.81724 -240.128558) (xy 381.866095 -240.13449) (xy 381.913366 -240.148182) (xy 381.957828 -240.16928)
			(xy 381.998331 -240.197236) (xy 382.033824 -240.231328) (xy 382.063389 -240.270672) (xy 382.08626 -240.314249)
			(xy 382.101844 -240.36093) (xy 382.109739 -240.409507) (xy 382.110234 -240.434114) (xy 382.438922 -240.434114)
			(xy 382.442882 -240.38506) (xy 382.454659 -240.337276) (xy 382.47395 -240.292) (xy 382.500253 -240.250404)
			(xy 382.532888 -240.213567) (xy 382.571009 -240.182442) (xy 382.61363 -240.157835) (xy 382.659646 -240.140383)
			(xy 382.707865 -240.130539) (xy 382.75704 -240.128558) (xy 382.805895 -240.13449) (xy 382.853166 -240.148182)
			(xy 382.897628 -240.16928) (xy 382.938131 -240.197236) (xy 382.973624 -240.231328) (xy 383.003189 -240.270672)
			(xy 383.02606 -240.314249) (xy 383.041644 -240.36093) (xy 383.049539 -240.409507) (xy 383.050034 -240.434114)
			(xy 383.378976 -240.434114) (xy 383.382936 -240.38506) (xy 383.394713 -240.337276) (xy 383.414004 -240.292)
			(xy 383.440307 -240.250404) (xy 383.472942 -240.213567) (xy 383.511063 -240.182442) (xy 383.553684 -240.157835)
			(xy 383.5997 -240.140383) (xy 383.647919 -240.130539) (xy 383.697094 -240.128558) (xy 383.745949 -240.13449)
			(xy 383.79322 -240.148182) (xy 383.837682 -240.16928) (xy 383.878185 -240.197236) (xy 383.913678 -240.231328)
			(xy 383.943243 -240.270672) (xy 383.966114 -240.314249) (xy 383.981698 -240.36093) (xy 383.989593 -240.409507)
			(xy 383.990088 -240.434114) (xy 383.989593 -240.458721) (xy 383.981698 -240.507298) (xy 383.966114 -240.553979)
			(xy 383.943243 -240.597556) (xy 383.913678 -240.6369) (xy 383.878185 -240.670992) (xy 383.837682 -240.698948)
			(xy 383.79322 -240.720046) (xy 383.745949 -240.733738) (xy 383.697094 -240.73967) (xy 383.647919 -240.737689)
			(xy 383.5997 -240.727845) (xy 383.553684 -240.710393) (xy 383.511063 -240.685786) (xy 383.472942 -240.654661)
			(xy 383.440307 -240.617824) (xy 383.414004 -240.576228) (xy 383.394713 -240.530952) (xy 383.382936 -240.483168)
			(xy 383.378976 -240.434114) (xy 383.050034 -240.434114) (xy 383.049539 -240.458721) (xy 383.041644 -240.507298)
			(xy 383.02606 -240.553979) (xy 383.003189 -240.597556) (xy 382.973624 -240.6369) (xy 382.938131 -240.670992)
			(xy 382.897628 -240.698948) (xy 382.853166 -240.720046) (xy 382.805895 -240.733738) (xy 382.75704 -240.73967)
			(xy 382.707865 -240.737689) (xy 382.659646 -240.727845) (xy 382.61363 -240.710393) (xy 382.571009 -240.685786)
			(xy 382.532888 -240.654661) (xy 382.500253 -240.617824) (xy 382.47395 -240.576228) (xy 382.454659 -240.530952)
			(xy 382.442882 -240.483168) (xy 382.438922 -240.434114) (xy 382.110234 -240.434114) (xy 382.109739 -240.458721)
			(xy 382.101844 -240.507298) (xy 382.08626 -240.553979) (xy 382.063389 -240.597556) (xy 382.033824 -240.6369)
			(xy 381.998331 -240.670992) (xy 381.957828 -240.698948) (xy 381.913366 -240.720046) (xy 381.866095 -240.733738)
			(xy 381.81724 -240.73967) (xy 381.768065 -240.737689) (xy 381.719846 -240.727845) (xy 381.67383 -240.710393)
			(xy 381.631209 -240.685786) (xy 381.593088 -240.654661) (xy 381.560453 -240.617824) (xy 381.53415 -240.576228)
			(xy 381.514859 -240.530952) (xy 381.503082 -240.483168) (xy 381.499122 -240.434114) (xy 381.180594 -240.434114)
			(xy 381.180082 -240.45956) (xy 381.171918 -240.509794) (xy 381.155802 -240.558068) (xy 381.132151 -240.603131)
			(xy 381.101578 -240.643817) (xy 381.064874 -240.679072) (xy 381.02299 -240.707982) (xy 380.977011 -240.729799)
			(xy 380.928127 -240.743959) (xy 380.877606 -240.750093) (xy 380.826754 -240.748044) (xy 380.77689 -240.737864)
			(xy 380.729304 -240.719817) (xy 380.68523 -240.694371) (xy 380.645808 -240.662184) (xy 380.61206 -240.62409)
			(xy 380.584859 -240.581076) (xy 380.564911 -240.534256) (xy 380.552732 -240.484842) (xy 380.548637 -240.434114)
			(xy 380.230126 -240.434114) (xy 380.229631 -240.458721) (xy 380.221736 -240.507298) (xy 380.206152 -240.553979)
			(xy 380.183281 -240.597556) (xy 380.153716 -240.6369) (xy 380.118223 -240.670992) (xy 380.07772 -240.698948)
			(xy 380.033258 -240.720046) (xy 379.985987 -240.733738) (xy 379.937132 -240.73967) (xy 379.887957 -240.737689)
			(xy 379.839738 -240.727845) (xy 379.793722 -240.710393) (xy 379.751101 -240.685786) (xy 379.71298 -240.654661)
			(xy 379.680345 -240.617824) (xy 379.654042 -240.576228) (xy 379.634751 -240.530952) (xy 379.622974 -240.483168)
			(xy 379.619014 -240.434114) (xy 379.300486 -240.434114) (xy 379.299974 -240.45956) (xy 379.29181 -240.509794)
			(xy 379.275694 -240.558068) (xy 379.252043 -240.603131) (xy 379.22147 -240.643817) (xy 379.184766 -240.679072)
			(xy 379.142882 -240.707982) (xy 379.096903 -240.729799) (xy 379.048019 -240.743959) (xy 378.997498 -240.750093)
			(xy 378.946646 -240.748044) (xy 378.896782 -240.737864) (xy 378.849196 -240.719817) (xy 378.805122 -240.694371)
			(xy 378.7657 -240.662184) (xy 378.731952 -240.62409) (xy 378.704751 -240.581076) (xy 378.684803 -240.534256)
			(xy 378.672624 -240.484842) (xy 378.668529 -240.434114) (xy 378.350018 -240.434114) (xy 378.349523 -240.458721)
			(xy 378.341628 -240.507298) (xy 378.326044 -240.553979) (xy 378.303173 -240.597556) (xy 378.273608 -240.6369)
			(xy 378.238115 -240.670992) (xy 378.197612 -240.698948) (xy 378.15315 -240.720046) (xy 378.105879 -240.733738)
			(xy 378.057024 -240.73967) (xy 378.007849 -240.737689) (xy 377.95963 -240.727845) (xy 377.913614 -240.710393)
			(xy 377.870993 -240.685786) (xy 377.832872 -240.654661) (xy 377.800237 -240.617824) (xy 377.773934 -240.576228)
			(xy 377.754643 -240.530952) (xy 377.742866 -240.483168) (xy 377.738906 -240.434114) (xy 377.420632 -240.434114)
			(xy 377.42012 -240.45956) (xy 377.411956 -240.509794) (xy 377.39584 -240.558068) (xy 377.372189 -240.603131)
			(xy 377.341616 -240.643817) (xy 377.304912 -240.679072) (xy 377.263028 -240.707982) (xy 377.217049 -240.729799)
			(xy 377.168165 -240.743959) (xy 377.117644 -240.750093) (xy 377.066792 -240.748044) (xy 377.016928 -240.737864)
			(xy 376.969342 -240.719817) (xy 376.925268 -240.694371) (xy 376.885846 -240.662184) (xy 376.852098 -240.62409)
			(xy 376.824897 -240.581076) (xy 376.804949 -240.534256) (xy 376.79277 -240.484842) (xy 376.788675 -240.434114)
			(xy 376.480147 -240.434114) (xy 376.480147 -240.458913) (xy 376.472383 -240.507927) (xy 376.457046 -240.555123)
			(xy 376.434515 -240.599338) (xy 376.405344 -240.639485) (xy 376.370251 -240.674572) (xy 376.330101 -240.703738)
			(xy 376.285882 -240.726263) (xy 376.238684 -240.741593) (xy 376.189669 -240.74935) (xy 376.164856 -240.749836)
			(xy 376.137942 -240.749287) (xy 376.084895 -240.740144) (xy 376.03417 -240.722132) (xy 376.010424 -240.70945)
			(xy 375.999756 -240.703354) (xy 375.975372 -240.702338) (xy 375.903998 -240.735612) (xy 375.893607 -240.741165)
			(xy 375.878918 -240.759555) (xy 375.875804 -240.770918) (xy 375.875804 -240.771426) (xy 375.86782 -240.808117)
			(xy 375.848888 -240.88079) (xy 375.837958 -240.916714) (xy 375.835131 -240.927626) (xy 375.838182 -240.94993)
			(xy 375.850496 -240.968776) (xy 375.859802 -240.975134) (xy 375.8807 -240.98848) (xy 375.918405 -241.02068)
			(xy 375.950607 -241.058382) (xy 375.976515 -241.100658) (xy 375.99549 -241.146467) (xy 376.007064 -241.19468)
			(xy 376.010953 -241.24411) (xy 376.010952 -241.24412) (xy 376.328952 -241.24412) (xy 376.332912 -241.195066)
			(xy 376.344689 -241.147282) (xy 376.36398 -241.102006) (xy 376.390283 -241.06041) (xy 376.422918 -241.023573)
			(xy 376.461039 -240.992448) (xy 376.50366 -240.967841) (xy 376.549676 -240.950389) (xy 376.597895 -240.940545)
			(xy 376.64707 -240.938564) (xy 376.695925 -240.944496) (xy 376.743196 -240.958188) (xy 376.787658 -240.979286)
			(xy 376.828161 -241.007242) (xy 376.863654 -241.041334) (xy 376.893219 -241.080678) (xy 376.91609 -241.124255)
			(xy 376.931674 -241.170936) (xy 376.939569 -241.219513) (xy 376.940064 -241.24412) (xy 377.258575 -241.24412)
			(xy 377.26267 -241.193392) (xy 377.274849 -241.143978) (xy 377.294797 -241.097158) (xy 377.321998 -241.054144)
			(xy 377.355746 -241.01605) (xy 377.395168 -240.983863) (xy 377.439242 -240.958417) (xy 377.486828 -240.94037)
			(xy 377.536692 -240.93019) (xy 377.587544 -240.928141) (xy 377.638065 -240.934275) (xy 377.686949 -240.948435)
			(xy 377.732928 -240.970252) (xy 377.774812 -240.999162) (xy 377.811516 -241.034417) (xy 377.842089 -241.075103)
			(xy 377.86574 -241.120166) (xy 377.881856 -241.16844) (xy 377.89002 -241.218674) (xy 377.890532 -241.24412)
			(xy 378.20906 -241.24412) (xy 378.21302 -241.195066) (xy 378.224797 -241.147282) (xy 378.244088 -241.102006)
			(xy 378.270391 -241.06041) (xy 378.303026 -241.023573) (xy 378.341147 -240.992448) (xy 378.383768 -240.967841)
			(xy 378.429784 -240.950389) (xy 378.478003 -240.940545) (xy 378.527178 -240.938564) (xy 378.576033 -240.944496)
			(xy 378.623304 -240.958188) (xy 378.667766 -240.979286) (xy 378.708269 -241.007242) (xy 378.743762 -241.041334)
			(xy 378.773327 -241.080678) (xy 378.796198 -241.124255) (xy 378.811782 -241.170936) (xy 378.819677 -241.219513)
			(xy 378.820172 -241.24412) (xy 379.138683 -241.24412) (xy 379.142778 -241.193392) (xy 379.154957 -241.143978)
			(xy 379.174905 -241.097158) (xy 379.202106 -241.054144) (xy 379.235854 -241.01605) (xy 379.275276 -240.983863)
			(xy 379.31935 -240.958417) (xy 379.366936 -240.94037) (xy 379.4168 -240.93019) (xy 379.467652 -240.928141)
			(xy 379.518173 -240.934275) (xy 379.567057 -240.948435) (xy 379.613036 -240.970252) (xy 379.65492 -240.999162)
			(xy 379.691624 -241.034417) (xy 379.722197 -241.075103) (xy 379.745848 -241.120166) (xy 379.761964 -241.16844)
			(xy 379.770128 -241.218674) (xy 379.77064 -241.24412) (xy 380.078483 -241.24412) (xy 380.082578 -241.193392)
			(xy 380.094757 -241.143978) (xy 380.114705 -241.097158) (xy 380.141906 -241.054144) (xy 380.175654 -241.01605)
			(xy 380.215076 -240.983863) (xy 380.25915 -240.958417) (xy 380.306736 -240.94037) (xy 380.3566 -240.93019)
			(xy 380.407452 -240.928141) (xy 380.457973 -240.934275) (xy 380.506857 -240.948435) (xy 380.552836 -240.970252)
			(xy 380.59472 -240.999162) (xy 380.631424 -241.034417) (xy 380.661997 -241.075103) (xy 380.685648 -241.120166)
			(xy 380.701764 -241.16844) (xy 380.709928 -241.218674) (xy 380.71044 -241.24412) (xy 381.028968 -241.24412)
			(xy 381.032928 -241.195066) (xy 381.044705 -241.147282) (xy 381.063996 -241.102006) (xy 381.090299 -241.06041)
			(xy 381.122934 -241.023573) (xy 381.161055 -240.992448) (xy 381.203676 -240.967841) (xy 381.249692 -240.950389)
			(xy 381.297911 -240.940545) (xy 381.347086 -240.938564) (xy 381.395941 -240.944496) (xy 381.443212 -240.958188)
			(xy 381.487674 -240.979286) (xy 381.528177 -241.007242) (xy 381.56367 -241.041334) (xy 381.593235 -241.080678)
			(xy 381.616106 -241.124255) (xy 381.63169 -241.170936) (xy 381.639585 -241.219513) (xy 381.64008 -241.24412)
			(xy 381.969022 -241.24412) (xy 381.972982 -241.195066) (xy 381.984759 -241.147282) (xy 382.00405 -241.102006)
			(xy 382.030353 -241.06041) (xy 382.062988 -241.023573) (xy 382.101109 -240.992448) (xy 382.14373 -240.967841)
			(xy 382.189746 -240.950389) (xy 382.237965 -240.940545) (xy 382.28714 -240.938564) (xy 382.335995 -240.944496)
			(xy 382.383266 -240.958188) (xy 382.427728 -240.979286) (xy 382.468231 -241.007242) (xy 382.503724 -241.041334)
			(xy 382.533289 -241.080678) (xy 382.55616 -241.124255) (xy 382.571744 -241.170936) (xy 382.579639 -241.219513)
			(xy 382.580134 -241.24412) (xy 382.909076 -241.24412) (xy 382.913036 -241.195066) (xy 382.924813 -241.147282)
			(xy 382.944104 -241.102006) (xy 382.970407 -241.06041) (xy 383.003042 -241.023573) (xy 383.041163 -240.992448)
			(xy 383.083784 -240.967841) (xy 383.1298 -240.950389) (xy 383.178019 -240.940545) (xy 383.227194 -240.938564)
			(xy 383.276049 -240.944496) (xy 383.32332 -240.958188) (xy 383.367782 -240.979286) (xy 383.408285 -241.007242)
			(xy 383.443778 -241.041334) (xy 383.473343 -241.080678) (xy 383.496214 -241.124255) (xy 383.511798 -241.170936)
			(xy 383.519693 -241.219513) (xy 383.520188 -241.24412) (xy 383.84913 -241.24412) (xy 383.85309 -241.195066)
			(xy 383.864867 -241.147282) (xy 383.884158 -241.102006) (xy 383.910461 -241.06041) (xy 383.943096 -241.023573)
			(xy 383.981217 -240.992448) (xy 384.023838 -240.967841) (xy 384.069854 -240.950389) (xy 384.118073 -240.940545)
			(xy 384.167248 -240.938564) (xy 384.216103 -240.944496) (xy 384.263374 -240.958188) (xy 384.307836 -240.979286)
			(xy 384.348339 -241.007242) (xy 384.383832 -241.041334) (xy 384.413397 -241.080678) (xy 384.436268 -241.124255)
			(xy 384.451852 -241.170936) (xy 384.459747 -241.219513) (xy 384.460242 -241.24412) (xy 384.459747 -241.268727)
			(xy 384.451852 -241.317304) (xy 384.436268 -241.363985) (xy 384.413397 -241.407562) (xy 384.383832 -241.446906)
			(xy 384.348339 -241.480998) (xy 384.307836 -241.508954) (xy 384.263374 -241.530052) (xy 384.216103 -241.543744)
			(xy 384.167248 -241.549676) (xy 384.118073 -241.547695) (xy 384.069854 -241.537851) (xy 384.023838 -241.520399)
			(xy 383.981217 -241.495792) (xy 383.943096 -241.464667) (xy 383.910461 -241.42783) (xy 383.884158 -241.386234)
			(xy 383.864867 -241.340958) (xy 383.85309 -241.293174) (xy 383.84913 -241.24412) (xy 383.520188 -241.24412)
			(xy 383.519693 -241.268727) (xy 383.511798 -241.317304) (xy 383.496214 -241.363985) (xy 383.473343 -241.407562)
			(xy 383.443778 -241.446906) (xy 383.408285 -241.480998) (xy 383.367782 -241.508954) (xy 383.32332 -241.530052)
			(xy 383.276049 -241.543744) (xy 383.227194 -241.549676) (xy 383.178019 -241.547695) (xy 383.1298 -241.537851)
			(xy 383.083784 -241.520399) (xy 383.041163 -241.495792) (xy 383.003042 -241.464667) (xy 382.970407 -241.42783)
			(xy 382.944104 -241.386234) (xy 382.924813 -241.340958) (xy 382.913036 -241.293174) (xy 382.909076 -241.24412)
			(xy 382.580134 -241.24412) (xy 382.579639 -241.268727) (xy 382.571744 -241.317304) (xy 382.55616 -241.363985)
			(xy 382.533289 -241.407562) (xy 382.503724 -241.446906) (xy 382.468231 -241.480998) (xy 382.427728 -241.508954)
			(xy 382.383266 -241.530052) (xy 382.335995 -241.543744) (xy 382.28714 -241.549676) (xy 382.237965 -241.547695)
			(xy 382.189746 -241.537851) (xy 382.14373 -241.520399) (xy 382.101109 -241.495792) (xy 382.062988 -241.464667)
			(xy 382.030353 -241.42783) (xy 382.00405 -241.386234) (xy 381.984759 -241.340958) (xy 381.972982 -241.293174)
			(xy 381.969022 -241.24412) (xy 381.64008 -241.24412) (xy 381.639585 -241.268727) (xy 381.63169 -241.317304)
			(xy 381.616106 -241.363985) (xy 381.593235 -241.407562) (xy 381.56367 -241.446906) (xy 381.528177 -241.480998)
			(xy 381.487674 -241.508954) (xy 381.443212 -241.530052) (xy 381.395941 -241.543744) (xy 381.347086 -241.549676)
			(xy 381.297911 -241.547695) (xy 381.249692 -241.537851) (xy 381.203676 -241.520399) (xy 381.161055 -241.495792)
			(xy 381.122934 -241.464667) (xy 381.090299 -241.42783) (xy 381.063996 -241.386234) (xy 381.044705 -241.340958)
			(xy 381.032928 -241.293174) (xy 381.028968 -241.24412) (xy 380.71044 -241.24412) (xy 380.709928 -241.269566)
			(xy 380.701764 -241.3198) (xy 380.685648 -241.368074) (xy 380.661997 -241.413137) (xy 380.631424 -241.453823)
			(xy 380.59472 -241.489078) (xy 380.552836 -241.517988) (xy 380.506857 -241.539805) (xy 380.457973 -241.553965)
			(xy 380.407452 -241.560099) (xy 380.3566 -241.55805) (xy 380.306736 -241.54787) (xy 380.25915 -241.529823)
			(xy 380.215076 -241.504377) (xy 380.175654 -241.47219) (xy 380.141906 -241.434096) (xy 380.114705 -241.391082)
			(xy 380.094757 -241.344262) (xy 380.082578 -241.294848) (xy 380.078483 -241.24412) (xy 379.77064 -241.24412)
			(xy 379.770128 -241.269566) (xy 379.761964 -241.3198) (xy 379.745848 -241.368074) (xy 379.722197 -241.413137)
			(xy 379.691624 -241.453823) (xy 379.65492 -241.489078) (xy 379.613036 -241.517988) (xy 379.567057 -241.539805)
			(xy 379.518173 -241.553965) (xy 379.467652 -241.560099) (xy 379.4168 -241.55805) (xy 379.366936 -241.54787)
			(xy 379.31935 -241.529823) (xy 379.275276 -241.504377) (xy 379.235854 -241.47219) (xy 379.202106 -241.434096)
			(xy 379.174905 -241.391082) (xy 379.154957 -241.344262) (xy 379.142778 -241.294848) (xy 379.138683 -241.24412)
			(xy 378.820172 -241.24412) (xy 378.819677 -241.268727) (xy 378.811782 -241.317304) (xy 378.796198 -241.363985)
			(xy 378.773327 -241.407562) (xy 378.743762 -241.446906) (xy 378.708269 -241.480998) (xy 378.667766 -241.508954)
			(xy 378.623304 -241.530052) (xy 378.576033 -241.543744) (xy 378.527178 -241.549676) (xy 378.478003 -241.547695)
			(xy 378.429784 -241.537851) (xy 378.383768 -241.520399) (xy 378.341147 -241.495792) (xy 378.303026 -241.464667)
			(xy 378.270391 -241.42783) (xy 378.244088 -241.386234) (xy 378.224797 -241.340958) (xy 378.21302 -241.293174)
			(xy 378.20906 -241.24412) (xy 377.890532 -241.24412) (xy 377.89002 -241.269566) (xy 377.881856 -241.3198)
			(xy 377.86574 -241.368074) (xy 377.842089 -241.413137) (xy 377.811516 -241.453823) (xy 377.774812 -241.489078)
			(xy 377.732928 -241.517988) (xy 377.686949 -241.539805) (xy 377.638065 -241.553965) (xy 377.587544 -241.560099)
			(xy 377.536692 -241.55805) (xy 377.486828 -241.54787) (xy 377.439242 -241.529823) (xy 377.395168 -241.504377)
			(xy 377.355746 -241.47219) (xy 377.321998 -241.434096) (xy 377.294797 -241.391082) (xy 377.274849 -241.344262)
			(xy 377.26267 -241.294848) (xy 377.258575 -241.24412) (xy 376.940064 -241.24412) (xy 376.939569 -241.268727)
			(xy 376.931674 -241.317304) (xy 376.91609 -241.363985) (xy 376.893219 -241.407562) (xy 376.863654 -241.446906)
			(xy 376.828161 -241.480998) (xy 376.787658 -241.508954) (xy 376.743196 -241.530052) (xy 376.695925 -241.543744)
			(xy 376.64707 -241.549676) (xy 376.597895 -241.547695) (xy 376.549676 -241.537851) (xy 376.50366 -241.520399)
			(xy 376.461039 -241.495792) (xy 376.422918 -241.464667) (xy 376.390283 -241.42783) (xy 376.36398 -241.386234)
			(xy 376.344689 -241.340958) (xy 376.332912 -241.293174) (xy 376.328952 -241.24412) (xy 376.010952 -241.24412)
			(xy 376.007061 -241.293541) (xy 375.995483 -241.341753) (xy 375.976506 -241.387561) (xy 375.950595 -241.429835)
			(xy 375.91839 -241.467535) (xy 375.880683 -241.499733) (xy 375.859802 -241.513106) (xy 375.850569 -241.519526)
			(xy 375.83833 -241.53836) (xy 375.835247 -241.560608) (xy 375.837958 -241.571526) (xy 375.84888 -241.607452)
			(xy 375.867811 -241.680125) (xy 375.875804 -241.716814) (xy 375.875804 -241.717322) (xy 375.878857 -241.728715)
			(xy 375.893569 -241.747114) (xy 375.903998 -241.752628) (xy 375.975372 -241.785902) (xy 375.999756 -241.784886)
			(xy 376.010424 -241.77879) (xy 376.03416 -241.766088) (xy 376.08489 -241.748078) (xy 376.13794 -241.738936)
			(xy 376.164856 -241.738404) (xy 376.189668 -241.738862) (xy 376.238681 -241.746619) (xy 376.285878 -241.761948)
			(xy 376.330095 -241.784472) (xy 376.370243 -241.813637) (xy 376.405335 -241.848723) (xy 376.434505 -241.888868)
			(xy 376.457035 -241.933082) (xy 376.472371 -241.980276) (xy 376.480135 -242.029288) (xy 376.480135 -242.054126)
			(xy 376.788675 -242.054126) (xy 376.79277 -242.003398) (xy 376.804949 -241.953984) (xy 376.824897 -241.907164)
			(xy 376.852098 -241.86415) (xy 376.885846 -241.826056) (xy 376.925268 -241.793869) (xy 376.969342 -241.768423)
			(xy 377.016928 -241.750376) (xy 377.066792 -241.740196) (xy 377.117644 -241.738147) (xy 377.168165 -241.744281)
			(xy 377.217049 -241.758441) (xy 377.263028 -241.780258) (xy 377.304912 -241.809168) (xy 377.341616 -241.844423)
			(xy 377.372189 -241.885109) (xy 377.39584 -241.930172) (xy 377.411956 -241.978446) (xy 377.42012 -242.02868)
			(xy 377.420632 -242.054126) (xy 378.668529 -242.054126) (xy 378.672624 -242.003398) (xy 378.684803 -241.953984)
			(xy 378.704751 -241.907164) (xy 378.731952 -241.86415) (xy 378.7657 -241.826056) (xy 378.805122 -241.793869)
			(xy 378.849196 -241.768423) (xy 378.896782 -241.750376) (xy 378.946646 -241.740196) (xy 378.997498 -241.738147)
			(xy 379.048019 -241.744281) (xy 379.096903 -241.758441) (xy 379.142882 -241.780258) (xy 379.184766 -241.809168)
			(xy 379.22147 -241.844423) (xy 379.252043 -241.885109) (xy 379.275694 -241.930172) (xy 379.29181 -241.978446)
			(xy 379.299974 -242.02868) (xy 379.300486 -242.054126) (xy 379.619014 -242.054126) (xy 379.622974 -242.005072)
			(xy 379.634751 -241.957288) (xy 379.654042 -241.912012) (xy 379.680345 -241.870416) (xy 379.71298 -241.833579)
			(xy 379.751101 -241.802454) (xy 379.793722 -241.777847) (xy 379.839738 -241.760395) (xy 379.887957 -241.750551)
			(xy 379.937132 -241.74857) (xy 379.985987 -241.754502) (xy 380.033258 -241.768194) (xy 380.07772 -241.789292)
			(xy 380.118223 -241.817248) (xy 380.153716 -241.85134) (xy 380.183281 -241.890684) (xy 380.206152 -241.934261)
			(xy 380.221736 -241.980942) (xy 380.229631 -242.029519) (xy 380.230126 -242.054126) (xy 380.548637 -242.054126)
			(xy 380.552732 -242.003398) (xy 380.564911 -241.953984) (xy 380.584859 -241.907164) (xy 380.61206 -241.86415)
			(xy 380.645808 -241.826056) (xy 380.68523 -241.793869) (xy 380.729304 -241.768423) (xy 380.77689 -241.750376)
			(xy 380.826754 -241.740196) (xy 380.877606 -241.738147) (xy 380.928127 -241.744281) (xy 380.977011 -241.758441)
			(xy 381.02299 -241.780258) (xy 381.064874 -241.809168) (xy 381.101578 -241.844423) (xy 381.132151 -241.885109)
			(xy 381.155802 -241.930172) (xy 381.171918 -241.978446) (xy 381.180082 -242.02868) (xy 381.180594 -242.054126)
			(xy 381.499122 -242.054126) (xy 381.503082 -242.005072) (xy 381.514859 -241.957288) (xy 381.53415 -241.912012)
			(xy 381.560453 -241.870416) (xy 381.593088 -241.833579) (xy 381.631209 -241.802454) (xy 381.67383 -241.777847)
			(xy 381.719846 -241.760395) (xy 381.768065 -241.750551) (xy 381.81724 -241.74857) (xy 381.866095 -241.754502)
			(xy 381.913366 -241.768194) (xy 381.957828 -241.789292) (xy 381.998331 -241.817248) (xy 382.033824 -241.85134)
			(xy 382.063389 -241.890684) (xy 382.08626 -241.934261) (xy 382.101844 -241.980942) (xy 382.109739 -242.029519)
			(xy 382.110234 -242.054126) (xy 382.438922 -242.054126) (xy 382.442882 -242.005072) (xy 382.454659 -241.957288)
			(xy 382.47395 -241.912012) (xy 382.500253 -241.870416) (xy 382.532888 -241.833579) (xy 382.571009 -241.802454)
			(xy 382.61363 -241.777847) (xy 382.659646 -241.760395) (xy 382.707865 -241.750551) (xy 382.75704 -241.74857)
			(xy 382.805895 -241.754502) (xy 382.853166 -241.768194) (xy 382.897628 -241.789292) (xy 382.938131 -241.817248)
			(xy 382.973624 -241.85134) (xy 383.003189 -241.890684) (xy 383.02606 -241.934261) (xy 383.041644 -241.980942)
			(xy 383.049539 -242.029519) (xy 383.050034 -242.054126) (xy 383.378976 -242.054126) (xy 383.382936 -242.005072)
			(xy 383.394713 -241.957288) (xy 383.414004 -241.912012) (xy 383.440307 -241.870416) (xy 383.472942 -241.833579)
			(xy 383.511063 -241.802454) (xy 383.553684 -241.777847) (xy 383.5997 -241.760395) (xy 383.647919 -241.750551)
			(xy 383.697094 -241.74857) (xy 383.745949 -241.754502) (xy 383.79322 -241.768194) (xy 383.837682 -241.789292)
			(xy 383.878185 -241.817248) (xy 383.913678 -241.85134) (xy 383.943243 -241.890684) (xy 383.966114 -241.934261)
			(xy 383.981698 -241.980942) (xy 383.989593 -242.029519) (xy 383.990088 -242.054126) (xy 383.989593 -242.078733)
			(xy 383.981698 -242.12731) (xy 383.966114 -242.173991) (xy 383.943243 -242.217568) (xy 383.913678 -242.256912)
			(xy 383.878185 -242.291004) (xy 383.837682 -242.31896) (xy 383.79322 -242.340058) (xy 383.745949 -242.35375)
			(xy 383.697094 -242.359682) (xy 383.647919 -242.357701) (xy 383.5997 -242.347857) (xy 383.553684 -242.330405)
			(xy 383.511063 -242.305798) (xy 383.472942 -242.274673) (xy 383.440307 -242.237836) (xy 383.414004 -242.19624)
			(xy 383.394713 -242.150964) (xy 383.382936 -242.10318) (xy 383.378976 -242.054126) (xy 383.050034 -242.054126)
			(xy 383.049539 -242.078733) (xy 383.041644 -242.12731) (xy 383.02606 -242.173991) (xy 383.003189 -242.217568)
			(xy 382.973624 -242.256912) (xy 382.938131 -242.291004) (xy 382.897628 -242.31896) (xy 382.853166 -242.340058)
			(xy 382.805895 -242.35375) (xy 382.75704 -242.359682) (xy 382.707865 -242.357701) (xy 382.659646 -242.347857)
			(xy 382.61363 -242.330405) (xy 382.571009 -242.305798) (xy 382.532888 -242.274673) (xy 382.500253 -242.237836)
			(xy 382.47395 -242.19624) (xy 382.454659 -242.150964) (xy 382.442882 -242.10318) (xy 382.438922 -242.054126)
			(xy 382.110234 -242.054126) (xy 382.109739 -242.078733) (xy 382.101844 -242.12731) (xy 382.08626 -242.173991)
			(xy 382.063389 -242.217568) (xy 382.033824 -242.256912) (xy 381.998331 -242.291004) (xy 381.957828 -242.31896)
			(xy 381.913366 -242.340058) (xy 381.866095 -242.35375) (xy 381.81724 -242.359682) (xy 381.768065 -242.357701)
			(xy 381.719846 -242.347857) (xy 381.67383 -242.330405) (xy 381.631209 -242.305798) (xy 381.593088 -242.274673)
			(xy 381.560453 -242.237836) (xy 381.53415 -242.19624) (xy 381.514859 -242.150964) (xy 381.503082 -242.10318)
			(xy 381.499122 -242.054126) (xy 381.180594 -242.054126) (xy 381.180082 -242.079572) (xy 381.171918 -242.129806)
			(xy 381.155802 -242.17808) (xy 381.132151 -242.223143) (xy 381.101578 -242.263829) (xy 381.064874 -242.299084)
			(xy 381.02299 -242.327994) (xy 380.977011 -242.349811) (xy 380.928127 -242.363971) (xy 380.877606 -242.370105)
			(xy 380.826754 -242.368056) (xy 380.77689 -242.357876) (xy 380.729304 -242.339829) (xy 380.68523 -242.314383)
			(xy 380.645808 -242.282196) (xy 380.61206 -242.244102) (xy 380.584859 -242.201088) (xy 380.564911 -242.154268)
			(xy 380.552732 -242.104854) (xy 380.548637 -242.054126) (xy 380.230126 -242.054126) (xy 380.229631 -242.078733)
			(xy 380.221736 -242.12731) (xy 380.206152 -242.173991) (xy 380.183281 -242.217568) (xy 380.153716 -242.256912)
			(xy 380.118223 -242.291004) (xy 380.07772 -242.31896) (xy 380.033258 -242.340058) (xy 379.985987 -242.35375)
			(xy 379.937132 -242.359682) (xy 379.887957 -242.357701) (xy 379.839738 -242.347857) (xy 379.793722 -242.330405)
			(xy 379.751101 -242.305798) (xy 379.71298 -242.274673) (xy 379.680345 -242.237836) (xy 379.654042 -242.19624)
			(xy 379.634751 -242.150964) (xy 379.622974 -242.10318) (xy 379.619014 -242.054126) (xy 379.300486 -242.054126)
			(xy 379.299974 -242.079572) (xy 379.29181 -242.129806) (xy 379.275694 -242.17808) (xy 379.252043 -242.223143)
			(xy 379.22147 -242.263829) (xy 379.184766 -242.299084) (xy 379.142882 -242.327994) (xy 379.096903 -242.349811)
			(xy 379.048019 -242.363971) (xy 378.997498 -242.370105) (xy 378.946646 -242.368056) (xy 378.896782 -242.357876)
			(xy 378.849196 -242.339829) (xy 378.805122 -242.314383) (xy 378.7657 -242.282196) (xy 378.731952 -242.244102)
			(xy 378.704751 -242.201088) (xy 378.684803 -242.154268) (xy 378.672624 -242.104854) (xy 378.668529 -242.054126)
			(xy 377.420632 -242.054126) (xy 377.42012 -242.079572) (xy 377.411956 -242.129806) (xy 377.39584 -242.17808)
			(xy 377.372189 -242.223143) (xy 377.341616 -242.263829) (xy 377.304912 -242.299084) (xy 377.263028 -242.327994)
			(xy 377.217049 -242.349811) (xy 377.168165 -242.363971) (xy 377.117644 -242.370105) (xy 377.066792 -242.368056)
			(xy 377.016928 -242.357876) (xy 376.969342 -242.339829) (xy 376.925268 -242.314383) (xy 376.885846 -242.282196)
			(xy 376.852098 -242.244102) (xy 376.824897 -242.201088) (xy 376.804949 -242.154268) (xy 376.79277 -242.104854)
			(xy 376.788675 -242.054126) (xy 376.480135 -242.054126) (xy 376.480135 -242.078912) (xy 376.472371 -242.127924)
			(xy 376.457035 -242.175118) (xy 376.434505 -242.219332) (xy 376.405335 -242.259477) (xy 376.370243 -242.294563)
			(xy 376.330095 -242.323728) (xy 376.285878 -242.346252) (xy 376.238681 -242.361581) (xy 376.189668 -242.369338)
			(xy 376.164856 -242.369848) (xy 376.137942 -242.369299) (xy 376.084895 -242.360157) (xy 376.034169 -242.342145)
			(xy 376.010424 -242.329462) (xy 375.999756 -242.323366) (xy 375.975372 -242.32235) (xy 375.903998 -242.355624)
			(xy 375.893608 -242.361178) (xy 375.878924 -242.379569) (xy 375.875804 -242.39093) (xy 375.875804 -242.391438)
			(xy 375.86782 -242.428129) (xy 375.848887 -242.500802) (xy 375.837958 -242.536726) (xy 375.835133 -242.547637)
			(xy 375.838189 -242.569937) (xy 375.850504 -242.588778) (xy 375.859802 -242.595146) (xy 375.880699 -242.608492)
			(xy 375.918402 -242.640691) (xy 375.950603 -242.678393) (xy 375.976509 -242.720668) (xy 375.995482 -242.766476)
			(xy 376.007055 -242.814688) (xy 376.010943 -242.864117) (xy 376.010942 -242.864132) (xy 376.328952 -242.864132)
			(xy 376.332912 -242.815078) (xy 376.344689 -242.767294) (xy 376.36398 -242.722018) (xy 376.390283 -242.680422)
			(xy 376.422918 -242.643585) (xy 376.461039 -242.61246) (xy 376.50366 -242.587853) (xy 376.549676 -242.570401)
			(xy 376.597895 -242.560557) (xy 376.64707 -242.558576) (xy 376.695925 -242.564508) (xy 376.743196 -242.5782)
			(xy 376.787658 -242.599298) (xy 376.828161 -242.627254) (xy 376.863654 -242.661346) (xy 376.893219 -242.70069)
			(xy 376.91609 -242.744267) (xy 376.931674 -242.790948) (xy 376.939569 -242.839525) (xy 376.940064 -242.864132)
			(xy 377.258575 -242.864132) (xy 377.26267 -242.813404) (xy 377.274849 -242.76399) (xy 377.294797 -242.71717)
			(xy 377.321998 -242.674156) (xy 377.355746 -242.636062) (xy 377.395168 -242.603875) (xy 377.439242 -242.578429)
			(xy 377.486828 -242.560382) (xy 377.536692 -242.550202) (xy 377.587544 -242.548153) (xy 377.638065 -242.554287)
			(xy 377.686949 -242.568447) (xy 377.732928 -242.590264) (xy 377.774812 -242.619174) (xy 377.811516 -242.654429)
			(xy 377.842089 -242.695115) (xy 377.86574 -242.740178) (xy 377.881856 -242.788452) (xy 377.89002 -242.838686)
			(xy 377.890532 -242.864132) (xy 378.20906 -242.864132) (xy 378.21302 -242.815078) (xy 378.224797 -242.767294)
			(xy 378.244088 -242.722018) (xy 378.270391 -242.680422) (xy 378.303026 -242.643585) (xy 378.341147 -242.61246)
			(xy 378.383768 -242.587853) (xy 378.429784 -242.570401) (xy 378.478003 -242.560557) (xy 378.527178 -242.558576)
			(xy 378.576033 -242.564508) (xy 378.623304 -242.5782) (xy 378.667766 -242.599298) (xy 378.708269 -242.627254)
			(xy 378.743762 -242.661346) (xy 378.773327 -242.70069) (xy 378.796198 -242.744267) (xy 378.811782 -242.790948)
			(xy 378.819677 -242.839525) (xy 378.820172 -242.864132) (xy 379.138683 -242.864132) (xy 379.142778 -242.813404)
			(xy 379.154957 -242.76399) (xy 379.174905 -242.71717) (xy 379.202106 -242.674156) (xy 379.235854 -242.636062)
			(xy 379.275276 -242.603875) (xy 379.31935 -242.578429) (xy 379.366936 -242.560382) (xy 379.4168 -242.550202)
			(xy 379.467652 -242.548153) (xy 379.518173 -242.554287) (xy 379.567057 -242.568447) (xy 379.613036 -242.590264)
			(xy 379.65492 -242.619174) (xy 379.691624 -242.654429) (xy 379.722197 -242.695115) (xy 379.745848 -242.740178)
			(xy 379.761964 -242.788452) (xy 379.770128 -242.838686) (xy 379.77064 -242.864132) (xy 380.078483 -242.864132)
			(xy 380.082578 -242.813404) (xy 380.094757 -242.76399) (xy 380.114705 -242.71717) (xy 380.141906 -242.674156)
			(xy 380.175654 -242.636062) (xy 380.215076 -242.603875) (xy 380.25915 -242.578429) (xy 380.306736 -242.560382)
			(xy 380.3566 -242.550202) (xy 380.407452 -242.548153) (xy 380.457973 -242.554287) (xy 380.506857 -242.568447)
			(xy 380.552836 -242.590264) (xy 380.59472 -242.619174) (xy 380.631424 -242.654429) (xy 380.661997 -242.695115)
			(xy 380.685648 -242.740178) (xy 380.701764 -242.788452) (xy 380.709928 -242.838686) (xy 380.71044 -242.864132)
			(xy 381.028968 -242.864132) (xy 381.032928 -242.815078) (xy 381.044705 -242.767294) (xy 381.063996 -242.722018)
			(xy 381.090299 -242.680422) (xy 381.122934 -242.643585) (xy 381.161055 -242.61246) (xy 381.203676 -242.587853)
			(xy 381.249692 -242.570401) (xy 381.297911 -242.560557) (xy 381.347086 -242.558576) (xy 381.395941 -242.564508)
			(xy 381.443212 -242.5782) (xy 381.487674 -242.599298) (xy 381.528177 -242.627254) (xy 381.56367 -242.661346)
			(xy 381.593235 -242.70069) (xy 381.616106 -242.744267) (xy 381.63169 -242.790948) (xy 381.639585 -242.839525)
			(xy 381.64008 -242.864132) (xy 381.969022 -242.864132) (xy 381.972982 -242.815078) (xy 381.984759 -242.767294)
			(xy 382.00405 -242.722018) (xy 382.030353 -242.680422) (xy 382.062988 -242.643585) (xy 382.101109 -242.61246)
			(xy 382.14373 -242.587853) (xy 382.189746 -242.570401) (xy 382.237965 -242.560557) (xy 382.28714 -242.558576)
			(xy 382.335995 -242.564508) (xy 382.383266 -242.5782) (xy 382.427728 -242.599298) (xy 382.468231 -242.627254)
			(xy 382.503724 -242.661346) (xy 382.533289 -242.70069) (xy 382.55616 -242.744267) (xy 382.571744 -242.790948)
			(xy 382.579639 -242.839525) (xy 382.580134 -242.864132) (xy 382.909076 -242.864132) (xy 382.913036 -242.815078)
			(xy 382.924813 -242.767294) (xy 382.944104 -242.722018) (xy 382.970407 -242.680422) (xy 383.003042 -242.643585)
			(xy 383.041163 -242.61246) (xy 383.083784 -242.587853) (xy 383.1298 -242.570401) (xy 383.178019 -242.560557)
			(xy 383.227194 -242.558576) (xy 383.276049 -242.564508) (xy 383.32332 -242.5782) (xy 383.367782 -242.599298)
			(xy 383.408285 -242.627254) (xy 383.443778 -242.661346) (xy 383.473343 -242.70069) (xy 383.496214 -242.744267)
			(xy 383.511798 -242.790948) (xy 383.519693 -242.839525) (xy 383.520188 -242.864132) (xy 383.84913 -242.864132)
			(xy 383.85309 -242.815078) (xy 383.864867 -242.767294) (xy 383.884158 -242.722018) (xy 383.910461 -242.680422)
			(xy 383.943096 -242.643585) (xy 383.981217 -242.61246) (xy 384.023838 -242.587853) (xy 384.069854 -242.570401)
			(xy 384.118073 -242.560557) (xy 384.167248 -242.558576) (xy 384.216103 -242.564508) (xy 384.263374 -242.5782)
			(xy 384.307836 -242.599298) (xy 384.348339 -242.627254) (xy 384.383832 -242.661346) (xy 384.413397 -242.70069)
			(xy 384.436268 -242.744267) (xy 384.451852 -242.790948) (xy 384.459747 -242.839525) (xy 384.460242 -242.864132)
			(xy 384.459747 -242.888739) (xy 384.451852 -242.937316) (xy 384.436268 -242.983997) (xy 384.413397 -243.027574)
			(xy 384.383832 -243.066918) (xy 384.348339 -243.10101) (xy 384.307836 -243.128966) (xy 384.263374 -243.150064)
			(xy 384.216103 -243.163756) (xy 384.167248 -243.169688) (xy 384.118073 -243.167707) (xy 384.069854 -243.157863)
			(xy 384.023838 -243.140411) (xy 383.981217 -243.115804) (xy 383.943096 -243.084679) (xy 383.910461 -243.047842)
			(xy 383.884158 -243.006246) (xy 383.864867 -242.96097) (xy 383.85309 -242.913186) (xy 383.84913 -242.864132)
			(xy 383.520188 -242.864132) (xy 383.519693 -242.888739) (xy 383.511798 -242.937316) (xy 383.496214 -242.983997)
			(xy 383.473343 -243.027574) (xy 383.443778 -243.066918) (xy 383.408285 -243.10101) (xy 383.367782 -243.128966)
			(xy 383.32332 -243.150064) (xy 383.276049 -243.163756) (xy 383.227194 -243.169688) (xy 383.178019 -243.167707)
			(xy 383.1298 -243.157863) (xy 383.083784 -243.140411) (xy 383.041163 -243.115804) (xy 383.003042 -243.084679)
			(xy 382.970407 -243.047842) (xy 382.944104 -243.006246) (xy 382.924813 -242.96097) (xy 382.913036 -242.913186)
			(xy 382.909076 -242.864132) (xy 382.580134 -242.864132) (xy 382.579639 -242.888739) (xy 382.571744 -242.937316)
			(xy 382.55616 -242.983997) (xy 382.533289 -243.027574) (xy 382.503724 -243.066918) (xy 382.468231 -243.10101)
			(xy 382.427728 -243.128966) (xy 382.383266 -243.150064) (xy 382.335995 -243.163756) (xy 382.28714 -243.169688)
			(xy 382.237965 -243.167707) (xy 382.189746 -243.157863) (xy 382.14373 -243.140411) (xy 382.101109 -243.115804)
			(xy 382.062988 -243.084679) (xy 382.030353 -243.047842) (xy 382.00405 -243.006246) (xy 381.984759 -242.96097)
			(xy 381.972982 -242.913186) (xy 381.969022 -242.864132) (xy 381.64008 -242.864132) (xy 381.639585 -242.888739)
			(xy 381.63169 -242.937316) (xy 381.616106 -242.983997) (xy 381.593235 -243.027574) (xy 381.56367 -243.066918)
			(xy 381.528177 -243.10101) (xy 381.487674 -243.128966) (xy 381.443212 -243.150064) (xy 381.395941 -243.163756)
			(xy 381.347086 -243.169688) (xy 381.297911 -243.167707) (xy 381.249692 -243.157863) (xy 381.203676 -243.140411)
			(xy 381.161055 -243.115804) (xy 381.122934 -243.084679) (xy 381.090299 -243.047842) (xy 381.063996 -243.006246)
			(xy 381.044705 -242.96097) (xy 381.032928 -242.913186) (xy 381.028968 -242.864132) (xy 380.71044 -242.864132)
			(xy 380.709928 -242.889578) (xy 380.701764 -242.939812) (xy 380.685648 -242.988086) (xy 380.661997 -243.033149)
			(xy 380.631424 -243.073835) (xy 380.59472 -243.10909) (xy 380.552836 -243.138) (xy 380.506857 -243.159817)
			(xy 380.457973 -243.173977) (xy 380.407452 -243.180111) (xy 380.3566 -243.178062) (xy 380.306736 -243.167882)
			(xy 380.25915 -243.149835) (xy 380.215076 -243.124389) (xy 380.175654 -243.092202) (xy 380.141906 -243.054108)
			(xy 380.114705 -243.011094) (xy 380.094757 -242.964274) (xy 380.082578 -242.91486) (xy 380.078483 -242.864132)
			(xy 379.77064 -242.864132) (xy 379.770128 -242.889578) (xy 379.761964 -242.939812) (xy 379.745848 -242.988086)
			(xy 379.722197 -243.033149) (xy 379.691624 -243.073835) (xy 379.65492 -243.10909) (xy 379.613036 -243.138)
			(xy 379.567057 -243.159817) (xy 379.518173 -243.173977) (xy 379.467652 -243.180111) (xy 379.4168 -243.178062)
			(xy 379.366936 -243.167882) (xy 379.31935 -243.149835) (xy 379.275276 -243.124389) (xy 379.235854 -243.092202)
			(xy 379.202106 -243.054108) (xy 379.174905 -243.011094) (xy 379.154957 -242.964274) (xy 379.142778 -242.91486)
			(xy 379.138683 -242.864132) (xy 378.820172 -242.864132) (xy 378.819677 -242.888739) (xy 378.811782 -242.937316)
			(xy 378.796198 -242.983997) (xy 378.773327 -243.027574) (xy 378.743762 -243.066918) (xy 378.708269 -243.10101)
			(xy 378.667766 -243.128966) (xy 378.623304 -243.150064) (xy 378.576033 -243.163756) (xy 378.527178 -243.169688)
			(xy 378.478003 -243.167707) (xy 378.429784 -243.157863) (xy 378.383768 -243.140411) (xy 378.341147 -243.115804)
			(xy 378.303026 -243.084679) (xy 378.270391 -243.047842) (xy 378.244088 -243.006246) (xy 378.224797 -242.96097)
			(xy 378.21302 -242.913186) (xy 378.20906 -242.864132) (xy 377.890532 -242.864132) (xy 377.89002 -242.889578)
			(xy 377.881856 -242.939812) (xy 377.86574 -242.988086) (xy 377.842089 -243.033149) (xy 377.811516 -243.073835)
			(xy 377.774812 -243.10909) (xy 377.732928 -243.138) (xy 377.686949 -243.159817) (xy 377.638065 -243.173977)
			(xy 377.587544 -243.180111) (xy 377.536692 -243.178062) (xy 377.486828 -243.167882) (xy 377.439242 -243.149835)
			(xy 377.395168 -243.124389) (xy 377.355746 -243.092202) (xy 377.321998 -243.054108) (xy 377.294797 -243.011094)
			(xy 377.274849 -242.964274) (xy 377.26267 -242.91486) (xy 377.258575 -242.864132) (xy 376.940064 -242.864132)
			(xy 376.939569 -242.888739) (xy 376.931674 -242.937316) (xy 376.91609 -242.983997) (xy 376.893219 -243.027574)
			(xy 376.863654 -243.066918) (xy 376.828161 -243.10101) (xy 376.787658 -243.128966) (xy 376.743196 -243.150064)
			(xy 376.695925 -243.163756) (xy 376.64707 -243.169688) (xy 376.597895 -243.167707) (xy 376.549676 -243.157863)
			(xy 376.50366 -243.140411) (xy 376.461039 -243.115804) (xy 376.422918 -243.084679) (xy 376.390283 -243.047842)
			(xy 376.36398 -243.006246) (xy 376.344689 -242.96097) (xy 376.332912 -242.913186) (xy 376.328952 -242.864132)
			(xy 376.010942 -242.864132) (xy 376.00705 -242.913545) (xy 375.995472 -242.961756) (xy 375.976494 -243.007561)
			(xy 375.950583 -243.049834) (xy 375.918378 -243.087532) (xy 375.880672 -243.119728) (xy 375.859802 -243.133118)
			(xy 375.850554 -243.139535) (xy 375.838282 -243.158371) (xy 375.835165 -243.180636) (xy 375.837958 -243.191538)
			(xy 375.84888 -243.227464) (xy 375.86781 -243.300137) (xy 375.875804 -243.336826) (xy 375.875804 -243.337334)
			(xy 375.878859 -243.348726) (xy 375.893573 -243.36712) (xy 375.903998 -243.37264) (xy 375.975372 -243.405914)
			(xy 375.999756 -243.404898) (xy 376.010424 -243.398802) (xy 376.03416 -243.386099) (xy 376.08489 -243.368089)
			(xy 376.13794 -243.358947) (xy 376.164856 -243.358416) (xy 376.189667 -243.358874) (xy 376.238678 -243.36663)
			(xy 376.285873 -243.381959) (xy 376.330088 -243.404482) (xy 376.370235 -243.433646) (xy 376.405326 -243.468731)
			(xy 376.434495 -243.508874) (xy 376.457024 -243.553086) (xy 376.472359 -243.600279) (xy 376.480123 -243.649289)
			(xy 376.480123 -243.674138) (xy 376.788675 -243.674138) (xy 376.79277 -243.62341) (xy 376.804949 -243.573996)
			(xy 376.824897 -243.527176) (xy 376.852098 -243.484162) (xy 376.885846 -243.446068) (xy 376.925268 -243.413881)
			(xy 376.969342 -243.388435) (xy 377.016928 -243.370388) (xy 377.066792 -243.360208) (xy 377.117644 -243.358159)
			(xy 377.168165 -243.364293) (xy 377.217049 -243.378453) (xy 377.263028 -243.40027) (xy 377.304912 -243.42918)
			(xy 377.341616 -243.464435) (xy 377.372189 -243.505121) (xy 377.39584 -243.550184) (xy 377.411956 -243.598458)
			(xy 377.42012 -243.648692) (xy 377.420632 -243.674138) (xy 377.738906 -243.674138) (xy 377.742866 -243.625084)
			(xy 377.754643 -243.5773) (xy 377.773934 -243.532024) (xy 377.800237 -243.490428) (xy 377.832872 -243.453591)
			(xy 377.870993 -243.422466) (xy 377.913614 -243.397859) (xy 377.95963 -243.380407) (xy 378.007849 -243.370563)
			(xy 378.057024 -243.368582) (xy 378.105879 -243.374514) (xy 378.15315 -243.388206) (xy 378.197612 -243.409304)
			(xy 378.238115 -243.43726) (xy 378.273608 -243.471352) (xy 378.303173 -243.510696) (xy 378.326044 -243.554273)
			(xy 378.341628 -243.600954) (xy 378.349523 -243.649531) (xy 378.350018 -243.674138) (xy 378.668529 -243.674138)
			(xy 378.672624 -243.62341) (xy 378.684803 -243.573996) (xy 378.704751 -243.527176) (xy 378.731952 -243.484162)
			(xy 378.7657 -243.446068) (xy 378.805122 -243.413881) (xy 378.849196 -243.388435) (xy 378.896782 -243.370388)
			(xy 378.946646 -243.360208) (xy 378.997498 -243.358159) (xy 379.048019 -243.364293) (xy 379.096903 -243.378453)
			(xy 379.142882 -243.40027) (xy 379.184766 -243.42918) (xy 379.22147 -243.464435) (xy 379.252043 -243.505121)
			(xy 379.275694 -243.550184) (xy 379.29181 -243.598458) (xy 379.299974 -243.648692) (xy 379.300486 -243.674138)
			(xy 379.619014 -243.674138) (xy 379.622974 -243.625084) (xy 379.634751 -243.5773) (xy 379.654042 -243.532024)
			(xy 379.680345 -243.490428) (xy 379.71298 -243.453591) (xy 379.751101 -243.422466) (xy 379.793722 -243.397859)
			(xy 379.839738 -243.380407) (xy 379.887957 -243.370563) (xy 379.937132 -243.368582) (xy 379.985987 -243.374514)
			(xy 380.033258 -243.388206) (xy 380.07772 -243.409304) (xy 380.118223 -243.43726) (xy 380.153716 -243.471352)
			(xy 380.183281 -243.510696) (xy 380.206152 -243.554273) (xy 380.221736 -243.600954) (xy 380.229631 -243.649531)
			(xy 380.230126 -243.674138) (xy 380.548637 -243.674138) (xy 380.552732 -243.62341) (xy 380.564911 -243.573996)
			(xy 380.584859 -243.527176) (xy 380.61206 -243.484162) (xy 380.645808 -243.446068) (xy 380.68523 -243.413881)
			(xy 380.729304 -243.388435) (xy 380.77689 -243.370388) (xy 380.826754 -243.360208) (xy 380.877606 -243.358159)
			(xy 380.928127 -243.364293) (xy 380.977011 -243.378453) (xy 381.02299 -243.40027) (xy 381.064874 -243.42918)
			(xy 381.101578 -243.464435) (xy 381.132151 -243.505121) (xy 381.155802 -243.550184) (xy 381.171918 -243.598458)
			(xy 381.180082 -243.648692) (xy 381.180594 -243.674138) (xy 381.499122 -243.674138) (xy 381.503082 -243.625084)
			(xy 381.514859 -243.5773) (xy 381.53415 -243.532024) (xy 381.560453 -243.490428) (xy 381.593088 -243.453591)
			(xy 381.631209 -243.422466) (xy 381.67383 -243.397859) (xy 381.719846 -243.380407) (xy 381.768065 -243.370563)
			(xy 381.81724 -243.368582) (xy 381.866095 -243.374514) (xy 381.913366 -243.388206) (xy 381.957828 -243.409304)
			(xy 381.998331 -243.43726) (xy 382.033824 -243.471352) (xy 382.063389 -243.510696) (xy 382.08626 -243.554273)
			(xy 382.101844 -243.600954) (xy 382.109739 -243.649531) (xy 382.110234 -243.674138) (xy 382.438922 -243.674138)
			(xy 382.442882 -243.625084) (xy 382.454659 -243.5773) (xy 382.47395 -243.532024) (xy 382.500253 -243.490428)
			(xy 382.532888 -243.453591) (xy 382.571009 -243.422466) (xy 382.61363 -243.397859) (xy 382.659646 -243.380407)
			(xy 382.707865 -243.370563) (xy 382.75704 -243.368582) (xy 382.805895 -243.374514) (xy 382.853166 -243.388206)
			(xy 382.897628 -243.409304) (xy 382.938131 -243.43726) (xy 382.973624 -243.471352) (xy 383.003189 -243.510696)
			(xy 383.02606 -243.554273) (xy 383.041644 -243.600954) (xy 383.049539 -243.649531) (xy 383.050034 -243.674138)
			(xy 383.378976 -243.674138) (xy 383.382936 -243.625084) (xy 383.394713 -243.5773) (xy 383.414004 -243.532024)
			(xy 383.440307 -243.490428) (xy 383.472942 -243.453591) (xy 383.511063 -243.422466) (xy 383.553684 -243.397859)
			(xy 383.5997 -243.380407) (xy 383.647919 -243.370563) (xy 383.697094 -243.368582) (xy 383.745949 -243.374514)
			(xy 383.79322 -243.388206) (xy 383.837682 -243.409304) (xy 383.878185 -243.43726) (xy 383.913678 -243.471352)
			(xy 383.943243 -243.510696) (xy 383.966114 -243.554273) (xy 383.981698 -243.600954) (xy 383.989593 -243.649531)
			(xy 383.990088 -243.674138) (xy 383.989593 -243.698745) (xy 383.981698 -243.747322) (xy 383.966114 -243.794003)
			(xy 383.943243 -243.83758) (xy 383.913678 -243.876924) (xy 383.878185 -243.911016) (xy 383.837682 -243.938972)
			(xy 383.79322 -243.96007) (xy 383.745949 -243.973762) (xy 383.697094 -243.979694) (xy 383.647919 -243.977713)
			(xy 383.5997 -243.967869) (xy 383.553684 -243.950417) (xy 383.511063 -243.92581) (xy 383.472942 -243.894685)
			(xy 383.440307 -243.857848) (xy 383.414004 -243.816252) (xy 383.394713 -243.770976) (xy 383.382936 -243.723192)
			(xy 383.378976 -243.674138) (xy 383.050034 -243.674138) (xy 383.049539 -243.698745) (xy 383.041644 -243.747322)
			(xy 383.02606 -243.794003) (xy 383.003189 -243.83758) (xy 382.973624 -243.876924) (xy 382.938131 -243.911016)
			(xy 382.897628 -243.938972) (xy 382.853166 -243.96007) (xy 382.805895 -243.973762) (xy 382.75704 -243.979694)
			(xy 382.707865 -243.977713) (xy 382.659646 -243.967869) (xy 382.61363 -243.950417) (xy 382.571009 -243.92581)
			(xy 382.532888 -243.894685) (xy 382.500253 -243.857848) (xy 382.47395 -243.816252) (xy 382.454659 -243.770976)
			(xy 382.442882 -243.723192) (xy 382.438922 -243.674138) (xy 382.110234 -243.674138) (xy 382.109739 -243.698745)
			(xy 382.101844 -243.747322) (xy 382.08626 -243.794003) (xy 382.063389 -243.83758) (xy 382.033824 -243.876924)
			(xy 381.998331 -243.911016) (xy 381.957828 -243.938972) (xy 381.913366 -243.96007) (xy 381.866095 -243.973762)
			(xy 381.81724 -243.979694) (xy 381.768065 -243.977713) (xy 381.719846 -243.967869) (xy 381.67383 -243.950417)
			(xy 381.631209 -243.92581) (xy 381.593088 -243.894685) (xy 381.560453 -243.857848) (xy 381.53415 -243.816252)
			(xy 381.514859 -243.770976) (xy 381.503082 -243.723192) (xy 381.499122 -243.674138) (xy 381.180594 -243.674138)
			(xy 381.180082 -243.699584) (xy 381.171918 -243.749818) (xy 381.155802 -243.798092) (xy 381.132151 -243.843155)
			(xy 381.101578 -243.883841) (xy 381.064874 -243.919096) (xy 381.02299 -243.948006) (xy 380.977011 -243.969823)
			(xy 380.928127 -243.983983) (xy 380.877606 -243.990117) (xy 380.826754 -243.988068) (xy 380.77689 -243.977888)
			(xy 380.729304 -243.959841) (xy 380.68523 -243.934395) (xy 380.645808 -243.902208) (xy 380.61206 -243.864114)
			(xy 380.584859 -243.8211) (xy 380.564911 -243.77428) (xy 380.552732 -243.724866) (xy 380.548637 -243.674138)
			(xy 380.230126 -243.674138) (xy 380.229631 -243.698745) (xy 380.221736 -243.747322) (xy 380.206152 -243.794003)
			(xy 380.183281 -243.83758) (xy 380.153716 -243.876924) (xy 380.118223 -243.911016) (xy 380.07772 -243.938972)
			(xy 380.033258 -243.96007) (xy 379.985987 -243.973762) (xy 379.937132 -243.979694) (xy 379.887957 -243.977713)
			(xy 379.839738 -243.967869) (xy 379.793722 -243.950417) (xy 379.751101 -243.92581) (xy 379.71298 -243.894685)
			(xy 379.680345 -243.857848) (xy 379.654042 -243.816252) (xy 379.634751 -243.770976) (xy 379.622974 -243.723192)
			(xy 379.619014 -243.674138) (xy 379.300486 -243.674138) (xy 379.299974 -243.699584) (xy 379.29181 -243.749818)
			(xy 379.275694 -243.798092) (xy 379.252043 -243.843155) (xy 379.22147 -243.883841) (xy 379.184766 -243.919096)
			(xy 379.142882 -243.948006) (xy 379.096903 -243.969823) (xy 379.048019 -243.983983) (xy 378.997498 -243.990117)
			(xy 378.946646 -243.988068) (xy 378.896782 -243.977888) (xy 378.849196 -243.959841) (xy 378.805122 -243.934395)
			(xy 378.7657 -243.902208) (xy 378.731952 -243.864114) (xy 378.704751 -243.8211) (xy 378.684803 -243.77428)
			(xy 378.672624 -243.724866) (xy 378.668529 -243.674138) (xy 378.350018 -243.674138) (xy 378.349523 -243.698745)
			(xy 378.341628 -243.747322) (xy 378.326044 -243.794003) (xy 378.303173 -243.83758) (xy 378.273608 -243.876924)
			(xy 378.238115 -243.911016) (xy 378.197612 -243.938972) (xy 378.15315 -243.96007) (xy 378.105879 -243.973762)
			(xy 378.057024 -243.979694) (xy 378.007849 -243.977713) (xy 377.95963 -243.967869) (xy 377.913614 -243.950417)
			(xy 377.870993 -243.92581) (xy 377.832872 -243.894685) (xy 377.800237 -243.857848) (xy 377.773934 -243.816252)
			(xy 377.754643 -243.770976) (xy 377.742866 -243.723192) (xy 377.738906 -243.674138) (xy 377.420632 -243.674138)
			(xy 377.42012 -243.699584) (xy 377.411956 -243.749818) (xy 377.39584 -243.798092) (xy 377.372189 -243.843155)
			(xy 377.341616 -243.883841) (xy 377.304912 -243.919096) (xy 377.263028 -243.948006) (xy 377.217049 -243.969823)
			(xy 377.168165 -243.983983) (xy 377.117644 -243.990117) (xy 377.066792 -243.988068) (xy 377.016928 -243.977888)
			(xy 376.969342 -243.959841) (xy 376.925268 -243.934395) (xy 376.885846 -243.902208) (xy 376.852098 -243.864114)
			(xy 376.824897 -243.8211) (xy 376.804949 -243.77428) (xy 376.79277 -243.724866) (xy 376.788675 -243.674138)
			(xy 376.480123 -243.674138) (xy 376.480123 -243.698911) (xy 376.472359 -243.747921) (xy 376.457024 -243.795114)
			(xy 376.434495 -243.839326) (xy 376.405326 -243.879469) (xy 376.370235 -243.914554) (xy 376.330088 -243.943718)
			(xy 376.285873 -243.966241) (xy 376.238678 -243.98157) (xy 376.189667 -243.989326) (xy 376.164856 -243.98986)
			(xy 376.137942 -243.989311) (xy 376.084895 -243.980169) (xy 376.034169 -243.962158) (xy 376.010424 -243.949474)
			(xy 375.999756 -243.943378) (xy 375.975372 -243.942362) (xy 375.903998 -243.975636) (xy 375.893609 -243.981191)
			(xy 375.878929 -243.999583) (xy 375.875804 -244.010942) (xy 375.875804 -244.01145) (xy 375.867822 -244.048142)
			(xy 375.848893 -244.120815) (xy 375.837958 -244.156738) (xy 375.835136 -244.167648) (xy 375.838195 -244.189945)
			(xy 375.850512 -244.208781) (xy 375.859802 -244.215158) (xy 375.882422 -244.229653) (xy 375.922811 -244.265074)
			(xy 375.956617 -244.306824) (xy 375.982863 -244.353697) (xy 376.000791 -244.404338) (xy 376.009882 -244.457284)
			(xy 376.010424 -244.484144) (xy 376.328952 -244.484144) (xy 376.332912 -244.43509) (xy 376.344689 -244.387306)
			(xy 376.36398 -244.34203) (xy 376.390283 -244.300434) (xy 376.422918 -244.263597) (xy 376.461039 -244.232472)
			(xy 376.50366 -244.207865) (xy 376.549676 -244.190413) (xy 376.597895 -244.180569) (xy 376.64707 -244.178588)
			(xy 376.695925 -244.18452) (xy 376.743196 -244.198212) (xy 376.787658 -244.21931) (xy 376.828161 -244.247266)
			(xy 376.863654 -244.281358) (xy 376.893219 -244.320702) (xy 376.91609 -244.364279) (xy 376.931674 -244.41096)
			(xy 376.939569 -244.459537) (xy 376.940064 -244.484144) (xy 377.258575 -244.484144) (xy 377.26267 -244.433416)
			(xy 377.274849 -244.384002) (xy 377.294797 -244.337182) (xy 377.321998 -244.294168) (xy 377.355746 -244.256074)
			(xy 377.395168 -244.223887) (xy 377.439242 -244.198441) (xy 377.486828 -244.180394) (xy 377.536692 -244.170214)
			(xy 377.587544 -244.168165) (xy 377.638065 -244.174299) (xy 377.686949 -244.188459) (xy 377.732928 -244.210276)
			(xy 377.774812 -244.239186) (xy 377.811516 -244.274441) (xy 377.842089 -244.315127) (xy 377.86574 -244.36019)
			(xy 377.881856 -244.408464) (xy 377.89002 -244.458698) (xy 377.890532 -244.484144) (xy 379.138683 -244.484144)
			(xy 379.142778 -244.433416) (xy 379.154957 -244.384002) (xy 379.174905 -244.337182) (xy 379.202106 -244.294168)
			(xy 379.235854 -244.256074) (xy 379.275276 -244.223887) (xy 379.31935 -244.198441) (xy 379.366936 -244.180394)
			(xy 379.4168 -244.170214) (xy 379.467652 -244.168165) (xy 379.518173 -244.174299) (xy 379.567057 -244.188459)
			(xy 379.613036 -244.210276) (xy 379.65492 -244.239186) (xy 379.691624 -244.274441) (xy 379.722197 -244.315127)
			(xy 379.745848 -244.36019) (xy 379.761964 -244.408464) (xy 379.770128 -244.458698) (xy 379.77064 -244.484144)
			(xy 380.078483 -244.484144) (xy 380.082578 -244.433416) (xy 380.094757 -244.384002) (xy 380.114705 -244.337182)
			(xy 380.141906 -244.294168) (xy 380.175654 -244.256074) (xy 380.215076 -244.223887) (xy 380.25915 -244.198441)
			(xy 380.306736 -244.180394) (xy 380.3566 -244.170214) (xy 380.407452 -244.168165) (xy 380.457973 -244.174299)
			(xy 380.506857 -244.188459) (xy 380.552836 -244.210276) (xy 380.59472 -244.239186) (xy 380.631424 -244.274441)
			(xy 380.661997 -244.315127) (xy 380.685648 -244.36019) (xy 380.701764 -244.408464) (xy 380.709928 -244.458698)
			(xy 380.71044 -244.484144) (xy 381.028968 -244.484144) (xy 381.032928 -244.43509) (xy 381.044705 -244.387306)
			(xy 381.063996 -244.34203) (xy 381.090299 -244.300434) (xy 381.122934 -244.263597) (xy 381.161055 -244.232472)
			(xy 381.203676 -244.207865) (xy 381.249692 -244.190413) (xy 381.297911 -244.180569) (xy 381.347086 -244.178588)
			(xy 381.395941 -244.18452) (xy 381.443212 -244.198212) (xy 381.487674 -244.21931) (xy 381.528177 -244.247266)
			(xy 381.56367 -244.281358) (xy 381.593235 -244.320702) (xy 381.616106 -244.364279) (xy 381.63169 -244.41096)
			(xy 381.639585 -244.459537) (xy 381.64008 -244.484144) (xy 381.969022 -244.484144) (xy 381.972982 -244.43509)
			(xy 381.984759 -244.387306) (xy 382.00405 -244.34203) (xy 382.030353 -244.300434) (xy 382.062988 -244.263597)
			(xy 382.101109 -244.232472) (xy 382.14373 -244.207865) (xy 382.189746 -244.190413) (xy 382.237965 -244.180569)
			(xy 382.28714 -244.178588) (xy 382.335995 -244.18452) (xy 382.383266 -244.198212) (xy 382.427728 -244.21931)
			(xy 382.468231 -244.247266) (xy 382.503724 -244.281358) (xy 382.533289 -244.320702) (xy 382.55616 -244.364279)
			(xy 382.571744 -244.41096) (xy 382.579639 -244.459537) (xy 382.580134 -244.484144) (xy 382.909076 -244.484144)
			(xy 382.913036 -244.43509) (xy 382.924813 -244.387306) (xy 382.944104 -244.34203) (xy 382.970407 -244.300434)
			(xy 383.003042 -244.263597) (xy 383.041163 -244.232472) (xy 383.083784 -244.207865) (xy 383.1298 -244.190413)
			(xy 383.178019 -244.180569) (xy 383.227194 -244.178588) (xy 383.276049 -244.18452) (xy 383.32332 -244.198212)
			(xy 383.367782 -244.21931) (xy 383.408285 -244.247266) (xy 383.443778 -244.281358) (xy 383.473343 -244.320702)
			(xy 383.496214 -244.364279) (xy 383.511798 -244.41096) (xy 383.519693 -244.459537) (xy 383.520188 -244.484144)
			(xy 383.84913 -244.484144) (xy 383.85309 -244.43509) (xy 383.864867 -244.387306) (xy 383.884158 -244.34203)
			(xy 383.910461 -244.300434) (xy 383.943096 -244.263597) (xy 383.981217 -244.232472) (xy 384.023838 -244.207865)
			(xy 384.069854 -244.190413) (xy 384.118073 -244.180569) (xy 384.167248 -244.178588) (xy 384.216103 -244.18452)
			(xy 384.263374 -244.198212) (xy 384.307836 -244.21931) (xy 384.348339 -244.247266) (xy 384.383832 -244.281358)
			(xy 384.413397 -244.320702) (xy 384.436268 -244.364279) (xy 384.451852 -244.41096) (xy 384.459747 -244.459537)
			(xy 384.460242 -244.484144) (xy 384.459747 -244.508751) (xy 384.451852 -244.557328) (xy 384.436268 -244.604009)
			(xy 384.413397 -244.647586) (xy 384.383832 -244.68693) (xy 384.348339 -244.721022) (xy 384.307836 -244.748978)
			(xy 384.263374 -244.770076) (xy 384.216103 -244.783768) (xy 384.167248 -244.7897) (xy 384.118073 -244.787719)
			(xy 384.069854 -244.777875) (xy 384.023838 -244.760423) (xy 383.981217 -244.735816) (xy 383.943096 -244.704691)
			(xy 383.910461 -244.667854) (xy 383.884158 -244.626258) (xy 383.864867 -244.580982) (xy 383.85309 -244.533198)
			(xy 383.84913 -244.484144) (xy 383.520188 -244.484144) (xy 383.519693 -244.508751) (xy 383.511798 -244.557328)
			(xy 383.496214 -244.604009) (xy 383.473343 -244.647586) (xy 383.443778 -244.68693) (xy 383.408285 -244.721022)
			(xy 383.367782 -244.748978) (xy 383.32332 -244.770076) (xy 383.276049 -244.783768) (xy 383.227194 -244.7897)
			(xy 383.178019 -244.787719) (xy 383.1298 -244.777875) (xy 383.083784 -244.760423) (xy 383.041163 -244.735816)
			(xy 383.003042 -244.704691) (xy 382.970407 -244.667854) (xy 382.944104 -244.626258) (xy 382.924813 -244.580982)
			(xy 382.913036 -244.533198) (xy 382.909076 -244.484144) (xy 382.580134 -244.484144) (xy 382.579639 -244.508751)
			(xy 382.571744 -244.557328) (xy 382.55616 -244.604009) (xy 382.533289 -244.647586) (xy 382.503724 -244.68693)
			(xy 382.468231 -244.721022) (xy 382.427728 -244.748978) (xy 382.383266 -244.770076) (xy 382.335995 -244.783768)
			(xy 382.28714 -244.7897) (xy 382.237965 -244.787719) (xy 382.189746 -244.777875) (xy 382.14373 -244.760423)
			(xy 382.101109 -244.735816) (xy 382.062988 -244.704691) (xy 382.030353 -244.667854) (xy 382.00405 -244.626258)
			(xy 381.984759 -244.580982) (xy 381.972982 -244.533198) (xy 381.969022 -244.484144) (xy 381.64008 -244.484144)
			(xy 381.639585 -244.508751) (xy 381.63169 -244.557328) (xy 381.616106 -244.604009) (xy 381.593235 -244.647586)
			(xy 381.56367 -244.68693) (xy 381.528177 -244.721022) (xy 381.487674 -244.748978) (xy 381.443212 -244.770076)
			(xy 381.395941 -244.783768) (xy 381.347086 -244.7897) (xy 381.297911 -244.787719) (xy 381.249692 -244.777875)
			(xy 381.203676 -244.760423) (xy 381.161055 -244.735816) (xy 381.122934 -244.704691) (xy 381.090299 -244.667854)
			(xy 381.063996 -244.626258) (xy 381.044705 -244.580982) (xy 381.032928 -244.533198) (xy 381.028968 -244.484144)
			(xy 380.71044 -244.484144) (xy 380.709928 -244.50959) (xy 380.701764 -244.559824) (xy 380.685648 -244.608098)
			(xy 380.661997 -244.653161) (xy 380.631424 -244.693847) (xy 380.59472 -244.729102) (xy 380.552836 -244.758012)
			(xy 380.506857 -244.779829) (xy 380.457973 -244.793989) (xy 380.407452 -244.800123) (xy 380.3566 -244.798074)
			(xy 380.306736 -244.787894) (xy 380.25915 -244.769847) (xy 380.215076 -244.744401) (xy 380.175654 -244.712214)
			(xy 380.141906 -244.67412) (xy 380.114705 -244.631106) (xy 380.094757 -244.584286) (xy 380.082578 -244.534872)
			(xy 380.078483 -244.484144) (xy 379.77064 -244.484144) (xy 379.770128 -244.50959) (xy 379.761964 -244.559824)
			(xy 379.745848 -244.608098) (xy 379.722197 -244.653161) (xy 379.691624 -244.693847) (xy 379.65492 -244.729102)
			(xy 379.613036 -244.758012) (xy 379.567057 -244.779829) (xy 379.518173 -244.793989) (xy 379.467652 -244.800123)
			(xy 379.4168 -244.798074) (xy 379.366936 -244.787894) (xy 379.31935 -244.769847) (xy 379.275276 -244.744401)
			(xy 379.235854 -244.712214) (xy 379.202106 -244.67412) (xy 379.174905 -244.631106) (xy 379.154957 -244.584286)
			(xy 379.142778 -244.534872) (xy 379.138683 -244.484144) (xy 377.890532 -244.484144) (xy 377.89002 -244.50959)
			(xy 377.881856 -244.559824) (xy 377.86574 -244.608098) (xy 377.842089 -244.653161) (xy 377.811516 -244.693847)
			(xy 377.774812 -244.729102) (xy 377.732928 -244.758012) (xy 377.686949 -244.779829) (xy 377.638065 -244.793989)
			(xy 377.587544 -244.800123) (xy 377.536692 -244.798074) (xy 377.486828 -244.787894) (xy 377.439242 -244.769847)
			(xy 377.395168 -244.744401) (xy 377.355746 -244.712214) (xy 377.321998 -244.67412) (xy 377.294797 -244.631106)
			(xy 377.274849 -244.584286) (xy 377.26267 -244.534872) (xy 377.258575 -244.484144) (xy 376.940064 -244.484144)
			(xy 376.939569 -244.508751) (xy 376.931674 -244.557328) (xy 376.91609 -244.604009) (xy 376.893219 -244.647586)
			(xy 376.863654 -244.68693) (xy 376.828161 -244.721022) (xy 376.787658 -244.748978) (xy 376.743196 -244.770076)
			(xy 376.695925 -244.783768) (xy 376.64707 -244.7897) (xy 376.597895 -244.787719) (xy 376.549676 -244.777875)
			(xy 376.50366 -244.760423) (xy 376.461039 -244.735816) (xy 376.422918 -244.704691) (xy 376.390283 -244.667854)
			(xy 376.36398 -244.626258) (xy 376.344689 -244.580982) (xy 376.332912 -244.533198) (xy 376.328952 -244.484144)
			(xy 376.010424 -244.484144) (xy 376.009959 -244.508945) (xy 376.002188 -244.557934) (xy 375.986847 -244.605103)
			(xy 375.964311 -244.64929) (xy 375.935137 -244.689405) (xy 375.900045 -244.72446) (xy 375.859898 -244.75359)
			(xy 375.815687 -244.776078) (xy 375.768501 -244.791368) (xy 375.719503 -244.799085) (xy 375.694702 -244.799612)
			(xy 375.668767 -244.799126) (xy 375.617584 -244.790716) (xy 375.568469 -244.77404) (xy 375.54535 -244.762274)
			(xy 375.535177 -244.75745) (xy 375.512722 -244.756257) (xy 375.491925 -244.764805) (xy 375.483882 -244.772688)
			(xy 375.466666 -244.791331) (xy 375.431227 -244.82766) (xy 375.413016 -244.845332) (xy 375.407936 -244.850158)
			(xy 375.393458 -244.874796) (xy 375.39168 -244.881908) (xy 375.386114 -244.903833) (xy 375.373921 -244.947401)
			(xy 375.367296 -244.96903) (xy 375.367042 -244.970046) (xy 375.366788 -244.971062) (xy 375.364677 -244.98058)
			(xy 375.367041 -244.999912) (xy 375.37136 -245.008654) (xy 375.379488 -245.023386) (xy 375.386854 -245.033546)
			(xy 375.390664 -245.03761) (xy 375.395744 -245.041166) (xy 375.395998 -245.04142) (xy 375.416277 -245.055751)
			(xy 375.452334 -245.089891) (xy 375.482394 -245.129413) (xy 375.505667 -245.173276) (xy 375.52154 -245.220326)
			(xy 375.529595 -245.269323) (xy 375.53011 -245.29415) (xy 375.848621 -245.29415) (xy 375.852716 -245.243422)
			(xy 375.864895 -245.194008) (xy 375.884843 -245.147188) (xy 375.912044 -245.104174) (xy 375.945792 -245.06608)
			(xy 375.985214 -245.033893) (xy 376.029288 -245.008447) (xy 376.076874 -244.9904) (xy 376.126738 -244.98022)
			(xy 376.17759 -244.978171) (xy 376.228111 -244.984305) (xy 376.276995 -244.998465) (xy 376.322974 -245.020282)
			(xy 376.364858 -245.049192) (xy 376.401562 -245.084447) (xy 376.432135 -245.125133) (xy 376.455786 -245.170196)
			(xy 376.471902 -245.21847) (xy 376.480066 -245.268704) (xy 376.480578 -245.29415) (xy 376.788675 -245.29415)
			(xy 376.79277 -245.243422) (xy 376.804949 -245.194008) (xy 376.824897 -245.147188) (xy 376.852098 -245.104174)
			(xy 376.885846 -245.06608) (xy 376.925268 -245.033893) (xy 376.969342 -245.008447) (xy 377.016928 -244.9904)
			(xy 377.066792 -244.98022) (xy 377.117644 -244.978171) (xy 377.168165 -244.984305) (xy 377.217049 -244.998465)
			(xy 377.263028 -245.020282) (xy 377.304912 -245.049192) (xy 377.341616 -245.084447) (xy 377.372189 -245.125133)
			(xy 377.39584 -245.170196) (xy 377.411956 -245.21847) (xy 377.42012 -245.268704) (xy 377.420632 -245.29415)
			(xy 377.738906 -245.29415) (xy 377.742866 -245.245096) (xy 377.754643 -245.197312) (xy 377.773934 -245.152036)
			(xy 377.800237 -245.11044) (xy 377.832872 -245.073603) (xy 377.870993 -245.042478) (xy 377.913614 -245.017871)
			(xy 377.95963 -245.000419) (xy 378.007849 -244.990575) (xy 378.057024 -244.988594) (xy 378.105879 -244.994526)
			(xy 378.15315 -245.008218) (xy 378.197612 -245.029316) (xy 378.238115 -245.057272) (xy 378.273608 -245.091364)
			(xy 378.303173 -245.130708) (xy 378.326044 -245.174285) (xy 378.341628 -245.220966) (xy 378.349523 -245.269543)
			(xy 378.350018 -245.29415) (xy 378.668529 -245.29415) (xy 378.672624 -245.243422) (xy 378.684803 -245.194008)
			(xy 378.704751 -245.147188) (xy 378.731952 -245.104174) (xy 378.7657 -245.06608) (xy 378.805122 -245.033893)
			(xy 378.849196 -245.008447) (xy 378.896782 -244.9904) (xy 378.946646 -244.98022) (xy 378.997498 -244.978171)
			(xy 379.048019 -244.984305) (xy 379.096903 -244.998465) (xy 379.142882 -245.020282) (xy 379.184766 -245.049192)
			(xy 379.22147 -245.084447) (xy 379.252043 -245.125133) (xy 379.275694 -245.170196) (xy 379.29181 -245.21847)
			(xy 379.299974 -245.268704) (xy 379.300486 -245.29415) (xy 379.619014 -245.29415) (xy 379.622974 -245.245096)
			(xy 379.634751 -245.197312) (xy 379.654042 -245.152036) (xy 379.680345 -245.11044) (xy 379.71298 -245.073603)
			(xy 379.751101 -245.042478) (xy 379.793722 -245.017871) (xy 379.839738 -245.000419) (xy 379.887957 -244.990575)
			(xy 379.937132 -244.988594) (xy 379.985987 -244.994526) (xy 380.033258 -245.008218) (xy 380.07772 -245.029316)
			(xy 380.118223 -245.057272) (xy 380.153716 -245.091364) (xy 380.183281 -245.130708) (xy 380.206152 -245.174285)
			(xy 380.221736 -245.220966) (xy 380.229631 -245.269543) (xy 380.230126 -245.29415) (xy 380.548637 -245.29415)
			(xy 380.552732 -245.243422) (xy 380.564911 -245.194008) (xy 380.584859 -245.147188) (xy 380.61206 -245.104174)
			(xy 380.645808 -245.06608) (xy 380.68523 -245.033893) (xy 380.729304 -245.008447) (xy 380.77689 -244.9904)
			(xy 380.826754 -244.98022) (xy 380.877606 -244.978171) (xy 380.928127 -244.984305) (xy 380.977011 -244.998465)
			(xy 381.02299 -245.020282) (xy 381.064874 -245.049192) (xy 381.101578 -245.084447) (xy 381.132151 -245.125133)
			(xy 381.155802 -245.170196) (xy 381.171918 -245.21847) (xy 381.180082 -245.268704) (xy 381.180594 -245.29415)
			(xy 381.499122 -245.29415) (xy 381.503082 -245.245096) (xy 381.514859 -245.197312) (xy 381.53415 -245.152036)
			(xy 381.560453 -245.11044) (xy 381.593088 -245.073603) (xy 381.631209 -245.042478) (xy 381.67383 -245.017871)
			(xy 381.719846 -245.000419) (xy 381.768065 -244.990575) (xy 381.81724 -244.988594) (xy 381.866095 -244.994526)
			(xy 381.913366 -245.008218) (xy 381.957828 -245.029316) (xy 381.998331 -245.057272) (xy 382.033824 -245.091364)
			(xy 382.063389 -245.130708) (xy 382.08626 -245.174285) (xy 382.101844 -245.220966) (xy 382.109739 -245.269543)
			(xy 382.110234 -245.29415) (xy 382.438922 -245.29415) (xy 382.442882 -245.245096) (xy 382.454659 -245.197312)
			(xy 382.47395 -245.152036) (xy 382.500253 -245.11044) (xy 382.532888 -245.073603) (xy 382.571009 -245.042478)
			(xy 382.61363 -245.017871) (xy 382.659646 -245.000419) (xy 382.707865 -244.990575) (xy 382.75704 -244.988594)
			(xy 382.805895 -244.994526) (xy 382.853166 -245.008218) (xy 382.897628 -245.029316) (xy 382.938131 -245.057272)
			(xy 382.973624 -245.091364) (xy 383.003189 -245.130708) (xy 383.02606 -245.174285) (xy 383.041644 -245.220966)
			(xy 383.049539 -245.269543) (xy 383.050034 -245.29415) (xy 383.378976 -245.29415) (xy 383.382936 -245.245096)
			(xy 383.394713 -245.197312) (xy 383.414004 -245.152036) (xy 383.440307 -245.11044) (xy 383.472942 -245.073603)
			(xy 383.511063 -245.042478) (xy 383.553684 -245.017871) (xy 383.5997 -245.000419) (xy 383.647919 -244.990575)
			(xy 383.697094 -244.988594) (xy 383.745949 -244.994526) (xy 383.79322 -245.008218) (xy 383.837682 -245.029316)
			(xy 383.878185 -245.057272) (xy 383.913678 -245.091364) (xy 383.943243 -245.130708) (xy 383.966114 -245.174285)
			(xy 383.981698 -245.220966) (xy 383.989593 -245.269543) (xy 383.990088 -245.29415) (xy 383.989593 -245.318757)
			(xy 383.981698 -245.367334) (xy 383.966114 -245.414015) (xy 383.943243 -245.457592) (xy 383.913678 -245.496936)
			(xy 383.878185 -245.531028) (xy 383.837682 -245.558984) (xy 383.79322 -245.580082) (xy 383.745949 -245.593774)
			(xy 383.697094 -245.599706) (xy 383.647919 -245.597725) (xy 383.5997 -245.587881) (xy 383.553684 -245.570429)
			(xy 383.511063 -245.545822) (xy 383.472942 -245.514697) (xy 383.440307 -245.47786) (xy 383.414004 -245.436264)
			(xy 383.394713 -245.390988) (xy 383.382936 -245.343204) (xy 383.378976 -245.29415) (xy 383.050034 -245.29415)
			(xy 383.049539 -245.318757) (xy 383.041644 -245.367334) (xy 383.02606 -245.414015) (xy 383.003189 -245.457592)
			(xy 382.973624 -245.496936) (xy 382.938131 -245.531028) (xy 382.897628 -245.558984) (xy 382.853166 -245.580082)
			(xy 382.805895 -245.593774) (xy 382.75704 -245.599706) (xy 382.707865 -245.597725) (xy 382.659646 -245.587881)
			(xy 382.61363 -245.570429) (xy 382.571009 -245.545822) (xy 382.532888 -245.514697) (xy 382.500253 -245.47786)
			(xy 382.47395 -245.436264) (xy 382.454659 -245.390988) (xy 382.442882 -245.343204) (xy 382.438922 -245.29415)
			(xy 382.110234 -245.29415) (xy 382.109739 -245.318757) (xy 382.101844 -245.367334) (xy 382.08626 -245.414015)
			(xy 382.063389 -245.457592) (xy 382.033824 -245.496936) (xy 381.998331 -245.531028) (xy 381.957828 -245.558984)
			(xy 381.913366 -245.580082) (xy 381.866095 -245.593774) (xy 381.81724 -245.599706) (xy 381.768065 -245.597725)
			(xy 381.719846 -245.587881) (xy 381.67383 -245.570429) (xy 381.631209 -245.545822) (xy 381.593088 -245.514697)
			(xy 381.560453 -245.47786) (xy 381.53415 -245.436264) (xy 381.514859 -245.390988) (xy 381.503082 -245.343204)
			(xy 381.499122 -245.29415) (xy 381.180594 -245.29415) (xy 381.180082 -245.319596) (xy 381.171918 -245.36983)
			(xy 381.155802 -245.418104) (xy 381.132151 -245.463167) (xy 381.101578 -245.503853) (xy 381.064874 -245.539108)
			(xy 381.02299 -245.568018) (xy 380.977011 -245.589835) (xy 380.928127 -245.603995) (xy 380.877606 -245.610129)
			(xy 380.826754 -245.60808) (xy 380.77689 -245.5979) (xy 380.729304 -245.579853) (xy 380.68523 -245.554407)
			(xy 380.645808 -245.52222) (xy 380.61206 -245.484126) (xy 380.584859 -245.441112) (xy 380.564911 -245.394292)
			(xy 380.552732 -245.344878) (xy 380.548637 -245.29415) (xy 380.230126 -245.29415) (xy 380.229631 -245.318757)
			(xy 380.221736 -245.367334) (xy 380.206152 -245.414015) (xy 380.183281 -245.457592) (xy 380.153716 -245.496936)
			(xy 380.118223 -245.531028) (xy 380.07772 -245.558984) (xy 380.033258 -245.580082) (xy 379.985987 -245.593774)
			(xy 379.937132 -245.599706) (xy 379.887957 -245.597725) (xy 379.839738 -245.587881) (xy 379.793722 -245.570429)
			(xy 379.751101 -245.545822) (xy 379.71298 -245.514697) (xy 379.680345 -245.47786) (xy 379.654042 -245.436264)
			(xy 379.634751 -245.390988) (xy 379.622974 -245.343204) (xy 379.619014 -245.29415) (xy 379.300486 -245.29415)
			(xy 379.299974 -245.319596) (xy 379.29181 -245.36983) (xy 379.275694 -245.418104) (xy 379.252043 -245.463167)
			(xy 379.22147 -245.503853) (xy 379.184766 -245.539108) (xy 379.142882 -245.568018) (xy 379.096903 -245.589835)
			(xy 379.048019 -245.603995) (xy 378.997498 -245.610129) (xy 378.946646 -245.60808) (xy 378.896782 -245.5979)
			(xy 378.849196 -245.579853) (xy 378.805122 -245.554407) (xy 378.7657 -245.52222) (xy 378.731952 -245.484126)
			(xy 378.704751 -245.441112) (xy 378.684803 -245.394292) (xy 378.672624 -245.344878) (xy 378.668529 -245.29415)
			(xy 378.350018 -245.29415) (xy 378.349523 -245.318757) (xy 378.341628 -245.367334) (xy 378.326044 -245.414015)
			(xy 378.303173 -245.457592) (xy 378.273608 -245.496936) (xy 378.238115 -245.531028) (xy 378.197612 -245.558984)
			(xy 378.15315 -245.580082) (xy 378.105879 -245.593774) (xy 378.057024 -245.599706) (xy 378.007849 -245.597725)
			(xy 377.95963 -245.587881) (xy 377.913614 -245.570429) (xy 377.870993 -245.545822) (xy 377.832872 -245.514697)
			(xy 377.800237 -245.47786) (xy 377.773934 -245.436264) (xy 377.754643 -245.390988) (xy 377.742866 -245.343204)
			(xy 377.738906 -245.29415) (xy 377.420632 -245.29415) (xy 377.42012 -245.319596) (xy 377.411956 -245.36983)
			(xy 377.39584 -245.418104) (xy 377.372189 -245.463167) (xy 377.341616 -245.503853) (xy 377.304912 -245.539108)
			(xy 377.263028 -245.568018) (xy 377.217049 -245.589835) (xy 377.168165 -245.603995) (xy 377.117644 -245.610129)
			(xy 377.066792 -245.60808) (xy 377.016928 -245.5979) (xy 376.969342 -245.579853) (xy 376.925268 -245.554407)
			(xy 376.885846 -245.52222) (xy 376.852098 -245.484126) (xy 376.824897 -245.441112) (xy 376.804949 -245.394292)
			(xy 376.79277 -245.344878) (xy 376.788675 -245.29415) (xy 376.480578 -245.29415) (xy 376.480066 -245.319596)
			(xy 376.471902 -245.36983) (xy 376.455786 -245.418104) (xy 376.432135 -245.463167) (xy 376.401562 -245.503853)
			(xy 376.364858 -245.539108) (xy 376.322974 -245.568018) (xy 376.276995 -245.589835) (xy 376.228111 -245.603995)
			(xy 376.17759 -245.610129) (xy 376.126738 -245.60808) (xy 376.076874 -245.5979) (xy 376.029288 -245.579853)
			(xy 375.985214 -245.554407) (xy 375.945792 -245.52222) (xy 375.912044 -245.484126) (xy 375.884843 -245.441112)
			(xy 375.864895 -245.394292) (xy 375.852716 -245.344878) (xy 375.848621 -245.29415) (xy 375.53011 -245.29415)
			(xy 375.529641 -245.318386) (xy 375.521977 -245.36625) (xy 375.506848 -245.412301) (xy 375.484635 -245.455385)
			(xy 375.455896 -245.494419) (xy 375.421351 -245.528423) (xy 375.381869 -245.556544) (xy 375.33844 -245.578076)
			(xy 375.292156 -245.592477) (xy 375.268236 -245.59641) (xy 375.254774 -245.598188) (xy 375.224802 -245.599712)
			(xy 375.200798 -245.599242) (xy 375.153381 -245.591739) (xy 375.107719 -245.576915) (xy 375.086118 -245.566438)
			(xy 375.075704 -245.561104) (xy 375.053098 -245.560596) (xy 375.021602 -245.574566) (xy 375.014236 -245.58244)
			(xy 374.996838 -245.601281) (xy 374.961017 -245.637991) (xy 374.942608 -245.655846) (xy 374.937274 -245.660926)
			(xy 374.923304 -245.68531) (xy 374.921526 -245.692168) (xy 374.921526 -245.692422) (xy 374.915952 -245.714093)
			(xy 374.903759 -245.757152) (xy 374.897142 -245.778528) (xy 374.897142 -245.778782) (xy 374.896888 -245.77929)
			(xy 374.894428 -245.789145) (xy 374.896671 -245.809316) (xy 374.901206 -245.818406) (xy 374.909588 -245.833392)
			(xy 374.916954 -245.843552) (xy 374.921018 -245.848124) (xy 374.925844 -245.851172) (xy 374.946173 -245.865494)
			(xy 374.982323 -245.899639) (xy 375.012459 -245.939192) (xy 375.035786 -245.983108) (xy 375.051685 -246.030223)
			(xy 375.059737 -246.079293) (xy 375.06021 -246.104156) (xy 375.378467 -246.104156) (xy 375.382562 -246.053428)
			(xy 375.394741 -246.004014) (xy 375.414689 -245.957194) (xy 375.44189 -245.91418) (xy 375.475638 -245.876086)
			(xy 375.51506 -245.843899) (xy 375.559134 -245.818453) (xy 375.60672 -245.800406) (xy 375.656584 -245.790226)
			(xy 375.707436 -245.788177) (xy 375.757957 -245.794311) (xy 375.806841 -245.808471) (xy 375.85282 -245.830288)
			(xy 375.894704 -245.859198) (xy 375.931408 -245.894453) (xy 375.961981 -245.935139) (xy 375.985632 -245.980202)
			(xy 376.001748 -246.028476) (xy 376.009912 -246.07871) (xy 376.010424 -246.104156) (xy 376.328952 -246.104156)
			(xy 376.332912 -246.055102) (xy 376.344689 -246.007318) (xy 376.36398 -245.962042) (xy 376.390283 -245.920446)
			(xy 376.422918 -245.883609) (xy 376.461039 -245.852484) (xy 376.50366 -245.827877) (xy 376.549676 -245.810425)
			(xy 376.597895 -245.800581) (xy 376.64707 -245.7986) (xy 376.695925 -245.804532) (xy 376.743196 -245.818224)
			(xy 376.787658 -245.839322) (xy 376.828161 -245.867278) (xy 376.863654 -245.90137) (xy 376.893219 -245.940714)
			(xy 376.91609 -245.984291) (xy 376.931674 -246.030972) (xy 376.939569 -246.079549) (xy 376.940064 -246.104156)
			(xy 377.258575 -246.104156) (xy 377.26267 -246.053428) (xy 377.274849 -246.004014) (xy 377.294797 -245.957194)
			(xy 377.321998 -245.91418) (xy 377.355746 -245.876086) (xy 377.395168 -245.843899) (xy 377.439242 -245.818453)
			(xy 377.486828 -245.800406) (xy 377.536692 -245.790226) (xy 377.587544 -245.788177) (xy 377.638065 -245.794311)
			(xy 377.686949 -245.808471) (xy 377.732928 -245.830288) (xy 377.774812 -245.859198) (xy 377.811516 -245.894453)
			(xy 377.842089 -245.935139) (xy 377.86574 -245.980202) (xy 377.881856 -246.028476) (xy 377.89002 -246.07871)
			(xy 377.890532 -246.104156) (xy 378.20906 -246.104156) (xy 378.21302 -246.055102) (xy 378.224797 -246.007318)
			(xy 378.244088 -245.962042) (xy 378.270391 -245.920446) (xy 378.303026 -245.883609) (xy 378.341147 -245.852484)
			(xy 378.383768 -245.827877) (xy 378.429784 -245.810425) (xy 378.478003 -245.800581) (xy 378.527178 -245.7986)
			(xy 378.576033 -245.804532) (xy 378.623304 -245.818224) (xy 378.667766 -245.839322) (xy 378.708269 -245.867278)
			(xy 378.743762 -245.90137) (xy 378.773327 -245.940714) (xy 378.796198 -245.984291) (xy 378.811782 -246.030972)
			(xy 378.819677 -246.079549) (xy 378.820172 -246.104156) (xy 379.138683 -246.104156) (xy 379.142778 -246.053428)
			(xy 379.154957 -246.004014) (xy 379.174905 -245.957194) (xy 379.202106 -245.91418) (xy 379.235854 -245.876086)
			(xy 379.275276 -245.843899) (xy 379.31935 -245.818453) (xy 379.366936 -245.800406) (xy 379.4168 -245.790226)
			(xy 379.467652 -245.788177) (xy 379.518173 -245.794311) (xy 379.567057 -245.808471) (xy 379.613036 -245.830288)
			(xy 379.65492 -245.859198) (xy 379.691624 -245.894453) (xy 379.722197 -245.935139) (xy 379.745848 -245.980202)
			(xy 379.761964 -246.028476) (xy 379.770128 -246.07871) (xy 379.77064 -246.104156) (xy 380.078483 -246.104156)
			(xy 380.082578 -246.053428) (xy 380.094757 -246.004014) (xy 380.114705 -245.957194) (xy 380.141906 -245.91418)
			(xy 380.175654 -245.876086) (xy 380.215076 -245.843899) (xy 380.25915 -245.818453) (xy 380.306736 -245.800406)
			(xy 380.3566 -245.790226) (xy 380.407452 -245.788177) (xy 380.457973 -245.794311) (xy 380.506857 -245.808471)
			(xy 380.552836 -245.830288) (xy 380.59472 -245.859198) (xy 380.631424 -245.894453) (xy 380.661997 -245.935139)
			(xy 380.685648 -245.980202) (xy 380.701764 -246.028476) (xy 380.709928 -246.07871) (xy 380.71044 -246.104156)
			(xy 381.028968 -246.104156) (xy 381.032928 -246.055102) (xy 381.044705 -246.007318) (xy 381.063996 -245.962042)
			(xy 381.090299 -245.920446) (xy 381.122934 -245.883609) (xy 381.161055 -245.852484) (xy 381.203676 -245.827877)
			(xy 381.249692 -245.810425) (xy 381.297911 -245.800581) (xy 381.347086 -245.7986) (xy 381.395941 -245.804532)
			(xy 381.443212 -245.818224) (xy 381.487674 -245.839322) (xy 381.528177 -245.867278) (xy 381.56367 -245.90137)
			(xy 381.593235 -245.940714) (xy 381.616106 -245.984291) (xy 381.63169 -246.030972) (xy 381.639585 -246.079549)
			(xy 381.64008 -246.104156) (xy 381.969022 -246.104156) (xy 381.972982 -246.055102) (xy 381.984759 -246.007318)
			(xy 382.00405 -245.962042) (xy 382.030353 -245.920446) (xy 382.062988 -245.883609) (xy 382.101109 -245.852484)
			(xy 382.14373 -245.827877) (xy 382.189746 -245.810425) (xy 382.237965 -245.800581) (xy 382.28714 -245.7986)
			(xy 382.335995 -245.804532) (xy 382.383266 -245.818224) (xy 382.427728 -245.839322) (xy 382.468231 -245.867278)
			(xy 382.503724 -245.90137) (xy 382.533289 -245.940714) (xy 382.55616 -245.984291) (xy 382.571744 -246.030972)
			(xy 382.579639 -246.079549) (xy 382.580134 -246.104156) (xy 382.909076 -246.104156) (xy 382.913036 -246.055102)
			(xy 382.924813 -246.007318) (xy 382.944104 -245.962042) (xy 382.970407 -245.920446) (xy 383.003042 -245.883609)
			(xy 383.041163 -245.852484) (xy 383.083784 -245.827877) (xy 383.1298 -245.810425) (xy 383.178019 -245.800581)
			(xy 383.227194 -245.7986) (xy 383.276049 -245.804532) (xy 383.32332 -245.818224) (xy 383.367782 -245.839322)
			(xy 383.408285 -245.867278) (xy 383.443778 -245.90137) (xy 383.473343 -245.940714) (xy 383.496214 -245.984291)
			(xy 383.511798 -246.030972) (xy 383.519693 -246.079549) (xy 383.520188 -246.104156) (xy 383.84913 -246.104156)
			(xy 383.85309 -246.055102) (xy 383.864867 -246.007318) (xy 383.884158 -245.962042) (xy 383.910461 -245.920446)
			(xy 383.943096 -245.883609) (xy 383.981217 -245.852484) (xy 384.023838 -245.827877) (xy 384.069854 -245.810425)
			(xy 384.118073 -245.800581) (xy 384.167248 -245.7986) (xy 384.216103 -245.804532) (xy 384.263374 -245.818224)
			(xy 384.307836 -245.839322) (xy 384.348339 -245.867278) (xy 384.383832 -245.90137) (xy 384.413397 -245.940714)
			(xy 384.436268 -245.984291) (xy 384.451852 -246.030972) (xy 384.459747 -246.079549) (xy 384.460242 -246.104156)
			(xy 384.459747 -246.128763) (xy 384.451852 -246.17734) (xy 384.436268 -246.224021) (xy 384.413397 -246.267598)
			(xy 384.383832 -246.306942) (xy 384.348339 -246.341034) (xy 384.307836 -246.36899) (xy 384.263374 -246.390088)
			(xy 384.216103 -246.40378) (xy 384.167248 -246.409712) (xy 384.118073 -246.407731) (xy 384.069854 -246.397887)
			(xy 384.023838 -246.380435) (xy 383.981217 -246.355828) (xy 383.943096 -246.324703) (xy 383.910461 -246.287866)
			(xy 383.884158 -246.24627) (xy 383.864867 -246.200994) (xy 383.85309 -246.15321) (xy 383.84913 -246.104156)
			(xy 383.520188 -246.104156) (xy 383.519693 -246.128763) (xy 383.511798 -246.17734) (xy 383.496214 -246.224021)
			(xy 383.473343 -246.267598) (xy 383.443778 -246.306942) (xy 383.408285 -246.341034) (xy 383.367782 -246.36899)
			(xy 383.32332 -246.390088) (xy 383.276049 -246.40378) (xy 383.227194 -246.409712) (xy 383.178019 -246.407731)
			(xy 383.1298 -246.397887) (xy 383.083784 -246.380435) (xy 383.041163 -246.355828) (xy 383.003042 -246.324703)
			(xy 382.970407 -246.287866) (xy 382.944104 -246.24627) (xy 382.924813 -246.200994) (xy 382.913036 -246.15321)
			(xy 382.909076 -246.104156) (xy 382.580134 -246.104156) (xy 382.579639 -246.128763) (xy 382.571744 -246.17734)
			(xy 382.55616 -246.224021) (xy 382.533289 -246.267598) (xy 382.503724 -246.306942) (xy 382.468231 -246.341034)
			(xy 382.427728 -246.36899) (xy 382.383266 -246.390088) (xy 382.335995 -246.40378) (xy 382.28714 -246.409712)
			(xy 382.237965 -246.407731) (xy 382.189746 -246.397887) (xy 382.14373 -246.380435) (xy 382.101109 -246.355828)
			(xy 382.062988 -246.324703) (xy 382.030353 -246.287866) (xy 382.00405 -246.24627) (xy 381.984759 -246.200994)
			(xy 381.972982 -246.15321) (xy 381.969022 -246.104156) (xy 381.64008 -246.104156) (xy 381.639585 -246.128763)
			(xy 381.63169 -246.17734) (xy 381.616106 -246.224021) (xy 381.593235 -246.267598) (xy 381.56367 -246.306942)
			(xy 381.528177 -246.341034) (xy 381.487674 -246.36899) (xy 381.443212 -246.390088) (xy 381.395941 -246.40378)
			(xy 381.347086 -246.409712) (xy 381.297911 -246.407731) (xy 381.249692 -246.397887) (xy 381.203676 -246.380435)
			(xy 381.161055 -246.355828) (xy 381.122934 -246.324703) (xy 381.090299 -246.287866) (xy 381.063996 -246.24627)
			(xy 381.044705 -246.200994) (xy 381.032928 -246.15321) (xy 381.028968 -246.104156) (xy 380.71044 -246.104156)
			(xy 380.709928 -246.129602) (xy 380.701764 -246.179836) (xy 380.685648 -246.22811) (xy 380.661997 -246.273173)
			(xy 380.631424 -246.313859) (xy 380.59472 -246.349114) (xy 380.552836 -246.378024) (xy 380.506857 -246.399841)
			(xy 380.457973 -246.414001) (xy 380.407452 -246.420135) (xy 380.3566 -246.418086) (xy 380.306736 -246.407906)
			(xy 380.25915 -246.389859) (xy 380.215076 -246.364413) (xy 380.175654 -246.332226) (xy 380.141906 -246.294132)
			(xy 380.114705 -246.251118) (xy 380.094757 -246.204298) (xy 380.082578 -246.154884) (xy 380.078483 -246.104156)
			(xy 379.77064 -246.104156) (xy 379.770128 -246.129602) (xy 379.761964 -246.179836) (xy 379.745848 -246.22811)
			(xy 379.722197 -246.273173) (xy 379.691624 -246.313859) (xy 379.65492 -246.349114) (xy 379.613036 -246.378024)
			(xy 379.567057 -246.399841) (xy 379.518173 -246.414001) (xy 379.467652 -246.420135) (xy 379.4168 -246.418086)
			(xy 379.366936 -246.407906) (xy 379.31935 -246.389859) (xy 379.275276 -246.364413) (xy 379.235854 -246.332226)
			(xy 379.202106 -246.294132) (xy 379.174905 -246.251118) (xy 379.154957 -246.204298) (xy 379.142778 -246.154884)
			(xy 379.138683 -246.104156) (xy 378.820172 -246.104156) (xy 378.819677 -246.128763) (xy 378.811782 -246.17734)
			(xy 378.796198 -246.224021) (xy 378.773327 -246.267598) (xy 378.743762 -246.306942) (xy 378.708269 -246.341034)
			(xy 378.667766 -246.36899) (xy 378.623304 -246.390088) (xy 378.576033 -246.40378) (xy 378.527178 -246.409712)
			(xy 378.478003 -246.407731) (xy 378.429784 -246.397887) (xy 378.383768 -246.380435) (xy 378.341147 -246.355828)
			(xy 378.303026 -246.324703) (xy 378.270391 -246.287866) (xy 378.244088 -246.24627) (xy 378.224797 -246.200994)
			(xy 378.21302 -246.15321) (xy 378.20906 -246.104156) (xy 377.890532 -246.104156) (xy 377.89002 -246.129602)
			(xy 377.881856 -246.179836) (xy 377.86574 -246.22811) (xy 377.842089 -246.273173) (xy 377.811516 -246.313859)
			(xy 377.774812 -246.349114) (xy 377.732928 -246.378024) (xy 377.686949 -246.399841) (xy 377.638065 -246.414001)
			(xy 377.587544 -246.420135) (xy 377.536692 -246.418086) (xy 377.486828 -246.407906) (xy 377.439242 -246.389859)
			(xy 377.395168 -246.364413) (xy 377.355746 -246.332226) (xy 377.321998 -246.294132) (xy 377.294797 -246.251118)
			(xy 377.274849 -246.204298) (xy 377.26267 -246.154884) (xy 377.258575 -246.104156) (xy 376.940064 -246.104156)
			(xy 376.939569 -246.128763) (xy 376.931674 -246.17734) (xy 376.91609 -246.224021) (xy 376.893219 -246.267598)
			(xy 376.863654 -246.306942) (xy 376.828161 -246.341034) (xy 376.787658 -246.36899) (xy 376.743196 -246.390088)
			(xy 376.695925 -246.40378) (xy 376.64707 -246.409712) (xy 376.597895 -246.407731) (xy 376.549676 -246.397887)
			(xy 376.50366 -246.380435) (xy 376.461039 -246.355828) (xy 376.422918 -246.324703) (xy 376.390283 -246.287866)
			(xy 376.36398 -246.24627) (xy 376.344689 -246.200994) (xy 376.332912 -246.15321) (xy 376.328952 -246.104156)
			(xy 376.010424 -246.104156) (xy 376.009912 -246.129602) (xy 376.001748 -246.179836) (xy 375.985632 -246.22811)
			(xy 375.961981 -246.273173) (xy 375.931408 -246.313859) (xy 375.894704 -246.349114) (xy 375.85282 -246.378024)
			(xy 375.806841 -246.399841) (xy 375.757957 -246.414001) (xy 375.707436 -246.420135) (xy 375.656584 -246.418086)
			(xy 375.60672 -246.407906) (xy 375.559134 -246.389859) (xy 375.51506 -246.364413) (xy 375.475638 -246.332226)
			(xy 375.44189 -246.294132) (xy 375.414689 -246.251118) (xy 375.394741 -246.204298) (xy 375.382562 -246.154884)
			(xy 375.378467 -246.104156) (xy 375.06021 -246.104156) (xy 375.059675 -246.129968) (xy 375.051003 -246.180859)
			(xy 375.033898 -246.229567) (xy 375.008848 -246.274707) (xy 374.976565 -246.314992) (xy 374.937968 -246.349276)
			(xy 374.894157 -246.376583) (xy 374.870472 -246.386858) (xy 374.860312 -246.390922) (xy 374.830086 -246.422672)
			(xy 374.82653 -246.433594) (xy 374.812295 -246.475841) (xy 374.77769 -246.558007) (xy 374.73633 -246.636989)
			(xy 374.688505 -246.712232) (xy 374.634549 -246.783208) (xy 374.605042 -246.816626) (xy 374.598692 -246.823484)
			(xy 374.58523 -246.858282) (xy 374.586754 -246.869204) (xy 374.5883 -246.880379) (xy 374.58995 -246.902881)
			(xy 374.590056 -246.914162) (xy 375.848621 -246.914162) (xy 375.852716 -246.863434) (xy 375.864895 -246.81402)
			(xy 375.884843 -246.7672) (xy 375.912044 -246.724186) (xy 375.945792 -246.686092) (xy 375.985214 -246.653905)
			(xy 376.029288 -246.628459) (xy 376.076874 -246.610412) (xy 376.126738 -246.600232) (xy 376.17759 -246.598183)
			(xy 376.228111 -246.604317) (xy 376.276995 -246.618477) (xy 376.322974 -246.640294) (xy 376.364858 -246.669204)
			(xy 376.401562 -246.704459) (xy 376.432135 -246.745145) (xy 376.455786 -246.790208) (xy 376.471902 -246.838482)
			(xy 376.480066 -246.888716) (xy 376.480578 -246.914162) (xy 376.788675 -246.914162) (xy 376.79277 -246.863434)
			(xy 376.804949 -246.81402) (xy 376.824897 -246.7672) (xy 376.852098 -246.724186) (xy 376.885846 -246.686092)
			(xy 376.925268 -246.653905) (xy 376.969342 -246.628459) (xy 377.016928 -246.610412) (xy 377.066792 -246.600232)
			(xy 377.117644 -246.598183) (xy 377.168165 -246.604317) (xy 377.217049 -246.618477) (xy 377.263028 -246.640294)
			(xy 377.304912 -246.669204) (xy 377.341616 -246.704459) (xy 377.372189 -246.745145) (xy 377.39584 -246.790208)
			(xy 377.411956 -246.838482) (xy 377.42012 -246.888716) (xy 377.420632 -246.914162) (xy 378.668529 -246.914162)
			(xy 378.672624 -246.863434) (xy 378.684803 -246.81402) (xy 378.704751 -246.7672) (xy 378.731952 -246.724186)
			(xy 378.7657 -246.686092) (xy 378.805122 -246.653905) (xy 378.849196 -246.628459) (xy 378.896782 -246.610412)
			(xy 378.946646 -246.600232) (xy 378.997498 -246.598183) (xy 379.048019 -246.604317) (xy 379.096903 -246.618477)
			(xy 379.142882 -246.640294) (xy 379.184766 -246.669204) (xy 379.22147 -246.704459) (xy 379.252043 -246.745145)
			(xy 379.275694 -246.790208) (xy 379.29181 -246.838482) (xy 379.299974 -246.888716) (xy 379.300486 -246.914162)
			(xy 379.619014 -246.914162) (xy 379.622974 -246.865108) (xy 379.634751 -246.817324) (xy 379.654042 -246.772048)
			(xy 379.680345 -246.730452) (xy 379.71298 -246.693615) (xy 379.751101 -246.66249) (xy 379.793722 -246.637883)
			(xy 379.839738 -246.620431) (xy 379.887957 -246.610587) (xy 379.937132 -246.608606) (xy 379.985987 -246.614538)
			(xy 380.033258 -246.62823) (xy 380.07772 -246.649328) (xy 380.118223 -246.677284) (xy 380.153716 -246.711376)
			(xy 380.183281 -246.75072) (xy 380.206152 -246.794297) (xy 380.221736 -246.840978) (xy 380.229631 -246.889555)
			(xy 380.230126 -246.914162) (xy 380.548637 -246.914162) (xy 380.552732 -246.863434) (xy 380.564911 -246.81402)
			(xy 380.584859 -246.7672) (xy 380.61206 -246.724186) (xy 380.645808 -246.686092) (xy 380.68523 -246.653905)
			(xy 380.729304 -246.628459) (xy 380.77689 -246.610412) (xy 380.826754 -246.600232) (xy 380.877606 -246.598183)
			(xy 380.928127 -246.604317) (xy 380.977011 -246.618477) (xy 381.02299 -246.640294) (xy 381.064874 -246.669204)
			(xy 381.101578 -246.704459) (xy 381.132151 -246.745145) (xy 381.155802 -246.790208) (xy 381.171918 -246.838482)
			(xy 381.180082 -246.888716) (xy 381.180594 -246.914162) (xy 381.499122 -246.914162) (xy 381.503082 -246.865108)
			(xy 381.514859 -246.817324) (xy 381.53415 -246.772048) (xy 381.560453 -246.730452) (xy 381.593088 -246.693615)
			(xy 381.631209 -246.66249) (xy 381.67383 -246.637883) (xy 381.719846 -246.620431) (xy 381.768065 -246.610587)
			(xy 381.81724 -246.608606) (xy 381.866095 -246.614538) (xy 381.913366 -246.62823) (xy 381.957828 -246.649328)
			(xy 381.998331 -246.677284) (xy 382.033824 -246.711376) (xy 382.063389 -246.75072) (xy 382.08626 -246.794297)
			(xy 382.101844 -246.840978) (xy 382.109739 -246.889555) (xy 382.110234 -246.914162) (xy 382.438922 -246.914162)
			(xy 382.442882 -246.865108) (xy 382.454659 -246.817324) (xy 382.47395 -246.772048) (xy 382.500253 -246.730452)
			(xy 382.532888 -246.693615) (xy 382.571009 -246.66249) (xy 382.61363 -246.637883) (xy 382.659646 -246.620431)
			(xy 382.707865 -246.610587) (xy 382.75704 -246.608606) (xy 382.805895 -246.614538) (xy 382.853166 -246.62823)
			(xy 382.897628 -246.649328) (xy 382.938131 -246.677284) (xy 382.973624 -246.711376) (xy 383.003189 -246.75072)
			(xy 383.02606 -246.794297) (xy 383.041644 -246.840978) (xy 383.049539 -246.889555) (xy 383.050034 -246.914162)
			(xy 383.378976 -246.914162) (xy 383.382936 -246.865108) (xy 383.394713 -246.817324) (xy 383.414004 -246.772048)
			(xy 383.440307 -246.730452) (xy 383.472942 -246.693615) (xy 383.511063 -246.66249) (xy 383.553684 -246.637883)
			(xy 383.5997 -246.620431) (xy 383.647919 -246.610587) (xy 383.697094 -246.608606) (xy 383.745949 -246.614538)
			(xy 383.79322 -246.62823) (xy 383.837682 -246.649328) (xy 383.878185 -246.677284) (xy 383.913678 -246.711376)
			(xy 383.943243 -246.75072) (xy 383.966114 -246.794297) (xy 383.981698 -246.840978) (xy 383.989593 -246.889555)
			(xy 383.990088 -246.914162) (xy 383.989593 -246.938769) (xy 383.981698 -246.987346) (xy 383.966114 -247.034027)
			(xy 383.943243 -247.077604) (xy 383.913678 -247.116948) (xy 383.878185 -247.15104) (xy 383.837682 -247.178996)
			(xy 383.79322 -247.200094) (xy 383.745949 -247.213786) (xy 383.697094 -247.219718) (xy 383.647919 -247.217737)
			(xy 383.5997 -247.207893) (xy 383.553684 -247.190441) (xy 383.511063 -247.165834) (xy 383.472942 -247.134709)
			(xy 383.440307 -247.097872) (xy 383.414004 -247.056276) (xy 383.394713 -247.011) (xy 383.382936 -246.963216)
			(xy 383.378976 -246.914162) (xy 383.050034 -246.914162) (xy 383.049539 -246.938769) (xy 383.041644 -246.987346)
			(xy 383.02606 -247.034027) (xy 383.003189 -247.077604) (xy 382.973624 -247.116948) (xy 382.938131 -247.15104)
			(xy 382.897628 -247.178996) (xy 382.853166 -247.200094) (xy 382.805895 -247.213786) (xy 382.75704 -247.219718)
			(xy 382.707865 -247.217737) (xy 382.659646 -247.207893) (xy 382.61363 -247.190441) (xy 382.571009 -247.165834)
			(xy 382.532888 -247.134709) (xy 382.500253 -247.097872) (xy 382.47395 -247.056276) (xy 382.454659 -247.011)
			(xy 382.442882 -246.963216) (xy 382.438922 -246.914162) (xy 382.110234 -246.914162) (xy 382.109739 -246.938769)
			(xy 382.101844 -246.987346) (xy 382.08626 -247.034027) (xy 382.063389 -247.077604) (xy 382.033824 -247.116948)
			(xy 381.998331 -247.15104) (xy 381.957828 -247.178996) (xy 381.913366 -247.200094) (xy 381.866095 -247.213786)
			(xy 381.81724 -247.219718) (xy 381.768065 -247.217737) (xy 381.719846 -247.207893) (xy 381.67383 -247.190441)
			(xy 381.631209 -247.165834) (xy 381.593088 -247.134709) (xy 381.560453 -247.097872) (xy 381.53415 -247.056276)
			(xy 381.514859 -247.011) (xy 381.503082 -246.963216) (xy 381.499122 -246.914162) (xy 381.180594 -246.914162)
			(xy 381.180082 -246.939608) (xy 381.171918 -246.989842) (xy 381.155802 -247.038116) (xy 381.132151 -247.083179)
			(xy 381.101578 -247.123865) (xy 381.064874 -247.15912) (xy 381.02299 -247.18803) (xy 380.977011 -247.209847)
			(xy 380.928127 -247.224007) (xy 380.877606 -247.230141) (xy 380.826754 -247.228092) (xy 380.77689 -247.217912)
			(xy 380.729304 -247.199865) (xy 380.68523 -247.174419) (xy 380.645808 -247.142232) (xy 380.61206 -247.104138)
			(xy 380.584859 -247.061124) (xy 380.564911 -247.014304) (xy 380.552732 -246.96489) (xy 380.548637 -246.914162)
			(xy 380.230126 -246.914162) (xy 380.229631 -246.938769) (xy 380.221736 -246.987346) (xy 380.206152 -247.034027)
			(xy 380.183281 -247.077604) (xy 380.153716 -247.116948) (xy 380.118223 -247.15104) (xy 380.07772 -247.178996)
			(xy 380.033258 -247.200094) (xy 379.985987 -247.213786) (xy 379.937132 -247.219718) (xy 379.887957 -247.217737)
			(xy 379.839738 -247.207893) (xy 379.793722 -247.190441) (xy 379.751101 -247.165834) (xy 379.71298 -247.134709)
			(xy 379.680345 -247.097872) (xy 379.654042 -247.056276) (xy 379.634751 -247.011) (xy 379.622974 -246.963216)
			(xy 379.619014 -246.914162) (xy 379.300486 -246.914162) (xy 379.299974 -246.939608) (xy 379.29181 -246.989842)
			(xy 379.275694 -247.038116) (xy 379.252043 -247.083179) (xy 379.22147 -247.123865) (xy 379.184766 -247.15912)
			(xy 379.142882 -247.18803) (xy 379.096903 -247.209847) (xy 379.048019 -247.224007) (xy 378.997498 -247.230141)
			(xy 378.946646 -247.228092) (xy 378.896782 -247.217912) (xy 378.849196 -247.199865) (xy 378.805122 -247.174419)
			(xy 378.7657 -247.142232) (xy 378.731952 -247.104138) (xy 378.704751 -247.061124) (xy 378.684803 -247.014304)
			(xy 378.672624 -246.96489) (xy 378.668529 -246.914162) (xy 377.420632 -246.914162) (xy 377.42012 -246.939608)
			(xy 377.411956 -246.989842) (xy 377.39584 -247.038116) (xy 377.372189 -247.083179) (xy 377.341616 -247.123865)
			(xy 377.304912 -247.15912) (xy 377.263028 -247.18803) (xy 377.217049 -247.209847) (xy 377.168165 -247.224007)
			(xy 377.117644 -247.230141) (xy 377.066792 -247.228092) (xy 377.016928 -247.217912) (xy 376.969342 -247.199865)
			(xy 376.925268 -247.174419) (xy 376.885846 -247.142232) (xy 376.852098 -247.104138) (xy 376.824897 -247.061124)
			(xy 376.804949 -247.014304) (xy 376.79277 -246.96489) (xy 376.788675 -246.914162) (xy 376.480578 -246.914162)
			(xy 376.480066 -246.939608) (xy 376.471902 -246.989842) (xy 376.455786 -247.038116) (xy 376.432135 -247.083179)
			(xy 376.401562 -247.123865) (xy 376.364858 -247.15912) (xy 376.322974 -247.18803) (xy 376.276995 -247.209847)
			(xy 376.228111 -247.224007) (xy 376.17759 -247.230141) (xy 376.126738 -247.228092) (xy 376.076874 -247.217912)
			(xy 376.029288 -247.199865) (xy 375.985214 -247.174419) (xy 375.945792 -247.142232) (xy 375.912044 -247.104138)
			(xy 375.884843 -247.061124) (xy 375.864895 -247.014304) (xy 375.852716 -246.96489) (xy 375.848621 -246.914162)
			(xy 374.590056 -246.914162) (xy 374.589957 -246.924867) (xy 374.588431 -246.946223) (xy 374.587008 -246.956834)
			(xy 374.58523 -246.970042) (xy 374.598692 -247.00484) (xy 374.605042 -247.011698) (xy 374.634556 -247.04511)
			(xy 374.688507 -247.116089) (xy 374.73633 -247.191334) (xy 374.777688 -247.270317) (xy 374.812292 -247.352484)
			(xy 374.82653 -247.39473) (xy 374.830086 -247.405652) (xy 374.860312 -247.437402) (xy 374.870218 -247.441466)
			(xy 374.893924 -247.451722) (xy 374.937778 -247.479002) (xy 374.976416 -247.513273) (xy 375.008736 -247.553557)
			(xy 375.033816 -247.598706) (xy 375.05094 -247.647432) (xy 375.05962 -247.698344) (xy 375.06021 -247.724168)
			(xy 375.378467 -247.724168) (xy 375.382562 -247.67344) (xy 375.394741 -247.624026) (xy 375.414689 -247.577206)
			(xy 375.44189 -247.534192) (xy 375.475638 -247.496098) (xy 375.51506 -247.463911) (xy 375.559134 -247.438465)
			(xy 375.60672 -247.420418) (xy 375.656584 -247.410238) (xy 375.707436 -247.408189) (xy 375.757957 -247.414323)
			(xy 375.806841 -247.428483) (xy 375.85282 -247.4503) (xy 375.894704 -247.47921) (xy 375.931408 -247.514465)
			(xy 375.961981 -247.555151) (xy 375.985632 -247.600214) (xy 376.001748 -247.648488) (xy 376.009912 -247.698722)
			(xy 376.010424 -247.724168) (xy 376.328952 -247.724168) (xy 376.332912 -247.675114) (xy 376.344689 -247.62733)
			(xy 376.36398 -247.582054) (xy 376.390283 -247.540458) (xy 376.422918 -247.503621) (xy 376.461039 -247.472496)
			(xy 376.50366 -247.447889) (xy 376.549676 -247.430437) (xy 376.597895 -247.420593) (xy 376.64707 -247.418612)
			(xy 376.695925 -247.424544) (xy 376.743196 -247.438236) (xy 376.787658 -247.459334) (xy 376.828161 -247.48729)
			(xy 376.863654 -247.521382) (xy 376.893219 -247.560726) (xy 376.91609 -247.604303) (xy 376.931674 -247.650984)
			(xy 376.939569 -247.699561) (xy 376.940064 -247.724168) (xy 377.258575 -247.724168) (xy 377.26267 -247.67344)
			(xy 377.274849 -247.624026) (xy 377.294797 -247.577206) (xy 377.321998 -247.534192) (xy 377.355746 -247.496098)
			(xy 377.395168 -247.463911) (xy 377.439242 -247.438465) (xy 377.486828 -247.420418) (xy 377.536692 -247.410238)
			(xy 377.587544 -247.408189) (xy 377.638065 -247.414323) (xy 377.686949 -247.428483) (xy 377.732928 -247.4503)
			(xy 377.774812 -247.47921) (xy 377.811516 -247.514465) (xy 377.842089 -247.555151) (xy 377.86574 -247.600214)
			(xy 377.881856 -247.648488) (xy 377.89002 -247.698722) (xy 377.890532 -247.724168) (xy 378.20906 -247.724168)
			(xy 378.21302 -247.675114) (xy 378.224797 -247.62733) (xy 378.244088 -247.582054) (xy 378.270391 -247.540458)
			(xy 378.303026 -247.503621) (xy 378.341147 -247.472496) (xy 378.383768 -247.447889) (xy 378.429784 -247.430437)
			(xy 378.478003 -247.420593) (xy 378.527178 -247.418612) (xy 378.576033 -247.424544) (xy 378.623304 -247.438236)
			(xy 378.667766 -247.459334) (xy 378.708269 -247.48729) (xy 378.743762 -247.521382) (xy 378.773327 -247.560726)
			(xy 378.796198 -247.604303) (xy 378.811782 -247.650984) (xy 378.819677 -247.699561) (xy 378.820172 -247.724168)
			(xy 379.138683 -247.724168) (xy 379.142778 -247.67344) (xy 379.154957 -247.624026) (xy 379.174905 -247.577206)
			(xy 379.202106 -247.534192) (xy 379.235854 -247.496098) (xy 379.275276 -247.463911) (xy 379.31935 -247.438465)
			(xy 379.366936 -247.420418) (xy 379.4168 -247.410238) (xy 379.467652 -247.408189) (xy 379.518173 -247.414323)
			(xy 379.567057 -247.428483) (xy 379.613036 -247.4503) (xy 379.65492 -247.47921) (xy 379.691624 -247.514465)
			(xy 379.722197 -247.555151) (xy 379.745848 -247.600214) (xy 379.761964 -247.648488) (xy 379.770128 -247.698722)
			(xy 379.77064 -247.724168) (xy 380.078483 -247.724168) (xy 380.082578 -247.67344) (xy 380.094757 -247.624026)
			(xy 380.114705 -247.577206) (xy 380.141906 -247.534192) (xy 380.175654 -247.496098) (xy 380.215076 -247.463911)
			(xy 380.25915 -247.438465) (xy 380.306736 -247.420418) (xy 380.3566 -247.410238) (xy 380.407452 -247.408189)
			(xy 380.457973 -247.414323) (xy 380.506857 -247.428483) (xy 380.552836 -247.4503) (xy 380.59472 -247.47921)
			(xy 380.631424 -247.514465) (xy 380.661997 -247.555151) (xy 380.685648 -247.600214) (xy 380.701764 -247.648488)
			(xy 380.709928 -247.698722) (xy 380.71044 -247.724168) (xy 381.028968 -247.724168) (xy 381.032928 -247.675114)
			(xy 381.044705 -247.62733) (xy 381.063996 -247.582054) (xy 381.090299 -247.540458) (xy 381.122934 -247.503621)
			(xy 381.161055 -247.472496) (xy 381.203676 -247.447889) (xy 381.249692 -247.430437) (xy 381.297911 -247.420593)
			(xy 381.347086 -247.418612) (xy 381.395941 -247.424544) (xy 381.443212 -247.438236) (xy 381.487674 -247.459334)
			(xy 381.528177 -247.48729) (xy 381.56367 -247.521382) (xy 381.593235 -247.560726) (xy 381.616106 -247.604303)
			(xy 381.63169 -247.650984) (xy 381.639585 -247.699561) (xy 381.64008 -247.724168) (xy 381.969022 -247.724168)
			(xy 381.972982 -247.675114) (xy 381.984759 -247.62733) (xy 382.00405 -247.582054) (xy 382.030353 -247.540458)
			(xy 382.062988 -247.503621) (xy 382.101109 -247.472496) (xy 382.14373 -247.447889) (xy 382.189746 -247.430437)
			(xy 382.237965 -247.420593) (xy 382.28714 -247.418612) (xy 382.335995 -247.424544) (xy 382.383266 -247.438236)
			(xy 382.427728 -247.459334) (xy 382.468231 -247.48729) (xy 382.503724 -247.521382) (xy 382.533289 -247.560726)
			(xy 382.55616 -247.604303) (xy 382.571744 -247.650984) (xy 382.579639 -247.699561) (xy 382.580134 -247.724168)
			(xy 382.909076 -247.724168) (xy 382.913036 -247.675114) (xy 382.924813 -247.62733) (xy 382.944104 -247.582054)
			(xy 382.970407 -247.540458) (xy 383.003042 -247.503621) (xy 383.041163 -247.472496) (xy 383.083784 -247.447889)
			(xy 383.1298 -247.430437) (xy 383.178019 -247.420593) (xy 383.227194 -247.418612) (xy 383.276049 -247.424544)
			(xy 383.32332 -247.438236) (xy 383.367782 -247.459334) (xy 383.408285 -247.48729) (xy 383.443778 -247.521382)
			(xy 383.473343 -247.560726) (xy 383.496214 -247.604303) (xy 383.511798 -247.650984) (xy 383.519693 -247.699561)
			(xy 383.520188 -247.724168) (xy 383.84913 -247.724168) (xy 383.85309 -247.675114) (xy 383.864867 -247.62733)
			(xy 383.884158 -247.582054) (xy 383.910461 -247.540458) (xy 383.943096 -247.503621) (xy 383.981217 -247.472496)
			(xy 384.023838 -247.447889) (xy 384.069854 -247.430437) (xy 384.118073 -247.420593) (xy 384.167248 -247.418612)
			(xy 384.216103 -247.424544) (xy 384.263374 -247.438236) (xy 384.307836 -247.459334) (xy 384.348339 -247.48729)
			(xy 384.383832 -247.521382) (xy 384.413397 -247.560726) (xy 384.436268 -247.604303) (xy 384.451852 -247.650984)
			(xy 384.459747 -247.699561) (xy 384.460242 -247.724168) (xy 384.459747 -247.748775) (xy 384.451852 -247.797352)
			(xy 384.436268 -247.844033) (xy 384.413397 -247.88761) (xy 384.383832 -247.926954) (xy 384.348339 -247.961046)
			(xy 384.307836 -247.989002) (xy 384.263374 -248.0101) (xy 384.216103 -248.023792) (xy 384.167248 -248.029724)
			(xy 384.118073 -248.027743) (xy 384.069854 -248.017899) (xy 384.023838 -248.000447) (xy 383.981217 -247.97584)
			(xy 383.943096 -247.944715) (xy 383.910461 -247.907878) (xy 383.884158 -247.866282) (xy 383.864867 -247.821006)
			(xy 383.85309 -247.773222) (xy 383.84913 -247.724168) (xy 383.520188 -247.724168) (xy 383.519693 -247.748775)
			(xy 383.511798 -247.797352) (xy 383.496214 -247.844033) (xy 383.473343 -247.88761) (xy 383.443778 -247.926954)
			(xy 383.408285 -247.961046) (xy 383.367782 -247.989002) (xy 383.32332 -248.0101) (xy 383.276049 -248.023792)
			(xy 383.227194 -248.029724) (xy 383.178019 -248.027743) (xy 383.1298 -248.017899) (xy 383.083784 -248.000447)
			(xy 383.041163 -247.97584) (xy 383.003042 -247.944715) (xy 382.970407 -247.907878) (xy 382.944104 -247.866282)
			(xy 382.924813 -247.821006) (xy 382.913036 -247.773222) (xy 382.909076 -247.724168) (xy 382.580134 -247.724168)
			(xy 382.579639 -247.748775) (xy 382.571744 -247.797352) (xy 382.55616 -247.844033) (xy 382.533289 -247.88761)
			(xy 382.503724 -247.926954) (xy 382.468231 -247.961046) (xy 382.427728 -247.989002) (xy 382.383266 -248.0101)
			(xy 382.335995 -248.023792) (xy 382.28714 -248.029724) (xy 382.237965 -248.027743) (xy 382.189746 -248.017899)
			(xy 382.14373 -248.000447) (xy 382.101109 -247.97584) (xy 382.062988 -247.944715) (xy 382.030353 -247.907878)
			(xy 382.00405 -247.866282) (xy 381.984759 -247.821006) (xy 381.972982 -247.773222) (xy 381.969022 -247.724168)
			(xy 381.64008 -247.724168) (xy 381.639585 -247.748775) (xy 381.63169 -247.797352) (xy 381.616106 -247.844033)
			(xy 381.593235 -247.88761) (xy 381.56367 -247.926954) (xy 381.528177 -247.961046) (xy 381.487674 -247.989002)
			(xy 381.443212 -248.0101) (xy 381.395941 -248.023792) (xy 381.347086 -248.029724) (xy 381.297911 -248.027743)
			(xy 381.249692 -248.017899) (xy 381.203676 -248.000447) (xy 381.161055 -247.97584) (xy 381.122934 -247.944715)
			(xy 381.090299 -247.907878) (xy 381.063996 -247.866282) (xy 381.044705 -247.821006) (xy 381.032928 -247.773222)
			(xy 381.028968 -247.724168) (xy 380.71044 -247.724168) (xy 380.709928 -247.749614) (xy 380.701764 -247.799848)
			(xy 380.685648 -247.848122) (xy 380.661997 -247.893185) (xy 380.631424 -247.933871) (xy 380.59472 -247.969126)
			(xy 380.552836 -247.998036) (xy 380.506857 -248.019853) (xy 380.457973 -248.034013) (xy 380.407452 -248.040147)
			(xy 380.3566 -248.038098) (xy 380.306736 -248.027918) (xy 380.25915 -248.009871) (xy 380.215076 -247.984425)
			(xy 380.175654 -247.952238) (xy 380.141906 -247.914144) (xy 380.114705 -247.87113) (xy 380.094757 -247.82431)
			(xy 380.082578 -247.774896) (xy 380.078483 -247.724168) (xy 379.77064 -247.724168) (xy 379.770128 -247.749614)
			(xy 379.761964 -247.799848) (xy 379.745848 -247.848122) (xy 379.722197 -247.893185) (xy 379.691624 -247.933871)
			(xy 379.65492 -247.969126) (xy 379.613036 -247.998036) (xy 379.567057 -248.019853) (xy 379.518173 -248.034013)
			(xy 379.467652 -248.040147) (xy 379.4168 -248.038098) (xy 379.366936 -248.027918) (xy 379.31935 -248.009871)
			(xy 379.275276 -247.984425) (xy 379.235854 -247.952238) (xy 379.202106 -247.914144) (xy 379.174905 -247.87113)
			(xy 379.154957 -247.82431) (xy 379.142778 -247.774896) (xy 379.138683 -247.724168) (xy 378.820172 -247.724168)
			(xy 378.819677 -247.748775) (xy 378.811782 -247.797352) (xy 378.796198 -247.844033) (xy 378.773327 -247.88761)
			(xy 378.743762 -247.926954) (xy 378.708269 -247.961046) (xy 378.667766 -247.989002) (xy 378.623304 -248.0101)
			(xy 378.576033 -248.023792) (xy 378.527178 -248.029724) (xy 378.478003 -248.027743) (xy 378.429784 -248.017899)
			(xy 378.383768 -248.000447) (xy 378.341147 -247.97584) (xy 378.303026 -247.944715) (xy 378.270391 -247.907878)
			(xy 378.244088 -247.866282) (xy 378.224797 -247.821006) (xy 378.21302 -247.773222) (xy 378.20906 -247.724168)
			(xy 377.890532 -247.724168) (xy 377.89002 -247.749614) (xy 377.881856 -247.799848) (xy 377.86574 -247.848122)
			(xy 377.842089 -247.893185) (xy 377.811516 -247.933871) (xy 377.774812 -247.969126) (xy 377.732928 -247.998036)
			(xy 377.686949 -248.019853) (xy 377.638065 -248.034013) (xy 377.587544 -248.040147) (xy 377.536692 -248.038098)
			(xy 377.486828 -248.027918) (xy 377.439242 -248.009871) (xy 377.395168 -247.984425) (xy 377.355746 -247.952238)
			(xy 377.321998 -247.914144) (xy 377.294797 -247.87113) (xy 377.274849 -247.82431) (xy 377.26267 -247.774896)
			(xy 377.258575 -247.724168) (xy 376.940064 -247.724168) (xy 376.939569 -247.748775) (xy 376.931674 -247.797352)
			(xy 376.91609 -247.844033) (xy 376.893219 -247.88761) (xy 376.863654 -247.926954) (xy 376.828161 -247.961046)
			(xy 376.787658 -247.989002) (xy 376.743196 -248.0101) (xy 376.695925 -248.023792) (xy 376.64707 -248.029724)
			(xy 376.597895 -248.027743) (xy 376.549676 -248.017899) (xy 376.50366 -248.000447) (xy 376.461039 -247.97584)
			(xy 376.422918 -247.944715) (xy 376.390283 -247.907878) (xy 376.36398 -247.866282) (xy 376.344689 -247.821006)
			(xy 376.332912 -247.773222) (xy 376.328952 -247.724168) (xy 376.010424 -247.724168) (xy 376.009912 -247.749614)
			(xy 376.001748 -247.799848) (xy 375.985632 -247.848122) (xy 375.961981 -247.893185) (xy 375.931408 -247.933871)
			(xy 375.894704 -247.969126) (xy 375.85282 -247.998036) (xy 375.806841 -248.019853) (xy 375.757957 -248.034013)
			(xy 375.707436 -248.040147) (xy 375.656584 -248.038098) (xy 375.60672 -248.027918) (xy 375.559134 -248.009871)
			(xy 375.51506 -247.984425) (xy 375.475638 -247.952238) (xy 375.44189 -247.914144) (xy 375.414689 -247.87113)
			(xy 375.394741 -247.82431) (xy 375.382562 -247.774896) (xy 375.378467 -247.724168) (xy 375.06021 -247.724168)
			(xy 375.059731 -247.74852) (xy 375.051991 -247.796604) (xy 375.036717 -247.842851) (xy 375.014298 -247.886088)
			(xy 374.985301 -247.925218) (xy 374.950461 -247.959251) (xy 374.910662 -247.987323) (xy 374.889014 -247.998488)
			(xy 374.875806 -248.005092) (xy 374.860566 -248.029476) (xy 374.860566 -248.223278) (xy 374.860995 -248.232958)
			(xy 374.868154 -248.250947) (xy 374.881434 -248.265035) (xy 374.89003 -248.269506) (xy 374.987058 -248.314464)
			(xy 375.016522 -248.310654) (xy 375.027698 -248.301002) (xy 375.048527 -248.284123) (xy 375.094875 -248.257188)
			(xy 375.145215 -248.238758) (xy 375.197998 -248.229399) (xy 375.224802 -248.228866) (xy 375.250059 -248.229388)
			(xy 375.299885 -248.237703) (xy 375.347663 -248.254105) (xy 375.392089 -248.278147) (xy 375.431952 -248.309174)
			(xy 375.466165 -248.346339) (xy 375.493794 -248.388629) (xy 375.514085 -248.434889) (xy 375.526486 -248.483858)
			(xy 375.530655 -248.534174) (xy 375.848621 -248.534174) (xy 375.852716 -248.483446) (xy 375.864895 -248.434032)
			(xy 375.884843 -248.387212) (xy 375.912044 -248.344198) (xy 375.945792 -248.306104) (xy 375.985214 -248.273917)
			(xy 376.029288 -248.248471) (xy 376.076874 -248.230424) (xy 376.126738 -248.220244) (xy 376.17759 -248.218195)
			(xy 376.228111 -248.224329) (xy 376.276995 -248.238489) (xy 376.322974 -248.260306) (xy 376.364858 -248.289216)
			(xy 376.401562 -248.324471) (xy 376.432135 -248.365157) (xy 376.455786 -248.41022) (xy 376.471902 -248.458494)
			(xy 376.480066 -248.508728) (xy 376.480578 -248.534174) (xy 376.788675 -248.534174) (xy 376.79277 -248.483446)
			(xy 376.804949 -248.434032) (xy 376.824897 -248.387212) (xy 376.852098 -248.344198) (xy 376.885846 -248.306104)
			(xy 376.925268 -248.273917) (xy 376.969342 -248.248471) (xy 377.016928 -248.230424) (xy 377.066792 -248.220244)
			(xy 377.117644 -248.218195) (xy 377.168165 -248.224329) (xy 377.217049 -248.238489) (xy 377.263028 -248.260306)
			(xy 377.304912 -248.289216) (xy 377.341616 -248.324471) (xy 377.372189 -248.365157) (xy 377.39584 -248.41022)
			(xy 377.411956 -248.458494) (xy 377.42012 -248.508728) (xy 377.420632 -248.534174) (xy 377.738906 -248.534174)
			(xy 377.742866 -248.48512) (xy 377.754643 -248.437336) (xy 377.773934 -248.39206) (xy 377.800237 -248.350464)
			(xy 377.832872 -248.313627) (xy 377.870993 -248.282502) (xy 377.913614 -248.257895) (xy 377.95963 -248.240443)
			(xy 378.007849 -248.230599) (xy 378.057024 -248.228618) (xy 378.105879 -248.23455) (xy 378.15315 -248.248242)
			(xy 378.197612 -248.26934) (xy 378.238115 -248.297296) (xy 378.273608 -248.331388) (xy 378.303173 -248.370732)
			(xy 378.326044 -248.414309) (xy 378.341628 -248.46099) (xy 378.349523 -248.509567) (xy 378.350018 -248.534174)
			(xy 378.668529 -248.534174) (xy 378.672624 -248.483446) (xy 378.684803 -248.434032) (xy 378.704751 -248.387212)
			(xy 378.731952 -248.344198) (xy 378.7657 -248.306104) (xy 378.805122 -248.273917) (xy 378.849196 -248.248471)
			(xy 378.896782 -248.230424) (xy 378.946646 -248.220244) (xy 378.997498 -248.218195) (xy 379.048019 -248.224329)
			(xy 379.096903 -248.238489) (xy 379.142882 -248.260306) (xy 379.184766 -248.289216) (xy 379.22147 -248.324471)
			(xy 379.252043 -248.365157) (xy 379.275694 -248.41022) (xy 379.29181 -248.458494) (xy 379.299974 -248.508728)
			(xy 379.300486 -248.534174) (xy 379.619014 -248.534174) (xy 379.622974 -248.48512) (xy 379.634751 -248.437336)
			(xy 379.654042 -248.39206) (xy 379.680345 -248.350464) (xy 379.71298 -248.313627) (xy 379.751101 -248.282502)
			(xy 379.793722 -248.257895) (xy 379.839738 -248.240443) (xy 379.887957 -248.230599) (xy 379.937132 -248.228618)
			(xy 379.985987 -248.23455) (xy 380.033258 -248.248242) (xy 380.07772 -248.26934) (xy 380.118223 -248.297296)
			(xy 380.153716 -248.331388) (xy 380.183281 -248.370732) (xy 380.206152 -248.414309) (xy 380.221736 -248.46099)
			(xy 380.229631 -248.509567) (xy 380.230126 -248.534174) (xy 380.548637 -248.534174) (xy 380.552732 -248.483446)
			(xy 380.564911 -248.434032) (xy 380.584859 -248.387212) (xy 380.61206 -248.344198) (xy 380.645808 -248.306104)
			(xy 380.68523 -248.273917) (xy 380.729304 -248.248471) (xy 380.77689 -248.230424) (xy 380.826754 -248.220244)
			(xy 380.877606 -248.218195) (xy 380.928127 -248.224329) (xy 380.977011 -248.238489) (xy 381.02299 -248.260306)
			(xy 381.064874 -248.289216) (xy 381.101578 -248.324471) (xy 381.132151 -248.365157) (xy 381.155802 -248.41022)
			(xy 381.171918 -248.458494) (xy 381.180082 -248.508728) (xy 381.180594 -248.534174) (xy 381.499122 -248.534174)
			(xy 381.503082 -248.48512) (xy 381.514859 -248.437336) (xy 381.53415 -248.39206) (xy 381.560453 -248.350464)
			(xy 381.593088 -248.313627) (xy 381.631209 -248.282502) (xy 381.67383 -248.257895) (xy 381.719846 -248.240443)
			(xy 381.768065 -248.230599) (xy 381.81724 -248.228618) (xy 381.866095 -248.23455) (xy 381.913366 -248.248242)
			(xy 381.957828 -248.26934) (xy 381.998331 -248.297296) (xy 382.033824 -248.331388) (xy 382.063389 -248.370732)
			(xy 382.08626 -248.414309) (xy 382.101844 -248.46099) (xy 382.109739 -248.509567) (xy 382.110234 -248.534174)
			(xy 382.438922 -248.534174) (xy 382.442882 -248.48512) (xy 382.454659 -248.437336) (xy 382.47395 -248.39206)
			(xy 382.500253 -248.350464) (xy 382.532888 -248.313627) (xy 382.571009 -248.282502) (xy 382.61363 -248.257895)
			(xy 382.659646 -248.240443) (xy 382.707865 -248.230599) (xy 382.75704 -248.228618) (xy 382.805895 -248.23455)
			(xy 382.853166 -248.248242) (xy 382.897628 -248.26934) (xy 382.938131 -248.297296) (xy 382.973624 -248.331388)
			(xy 383.003189 -248.370732) (xy 383.02606 -248.414309) (xy 383.041644 -248.46099) (xy 383.049539 -248.509567)
			(xy 383.050034 -248.534174) (xy 383.378976 -248.534174) (xy 383.382936 -248.48512) (xy 383.394713 -248.437336)
			(xy 383.414004 -248.39206) (xy 383.440307 -248.350464) (xy 383.472942 -248.313627) (xy 383.511063 -248.282502)
			(xy 383.553684 -248.257895) (xy 383.5997 -248.240443) (xy 383.647919 -248.230599) (xy 383.697094 -248.228618)
			(xy 383.745949 -248.23455) (xy 383.79322 -248.248242) (xy 383.837682 -248.26934) (xy 383.878185 -248.297296)
			(xy 383.913678 -248.331388) (xy 383.943243 -248.370732) (xy 383.966114 -248.414309) (xy 383.981698 -248.46099)
			(xy 383.989593 -248.509567) (xy 383.990088 -248.534174) (xy 383.989593 -248.558781) (xy 383.981698 -248.607358)
			(xy 383.966114 -248.654039) (xy 383.943243 -248.697616) (xy 383.913678 -248.73696) (xy 383.878185 -248.771052)
			(xy 383.837682 -248.799008) (xy 383.79322 -248.820106) (xy 383.745949 -248.833798) (xy 383.697094 -248.83973)
			(xy 383.647919 -248.837749) (xy 383.5997 -248.827905) (xy 383.553684 -248.810453) (xy 383.511063 -248.785846)
			(xy 383.472942 -248.754721) (xy 383.440307 -248.717884) (xy 383.414004 -248.676288) (xy 383.394713 -248.631012)
			(xy 383.382936 -248.583228) (xy 383.378976 -248.534174) (xy 383.050034 -248.534174) (xy 383.049539 -248.558781)
			(xy 383.041644 -248.607358) (xy 383.02606 -248.654039) (xy 383.003189 -248.697616) (xy 382.973624 -248.73696)
			(xy 382.938131 -248.771052) (xy 382.897628 -248.799008) (xy 382.853166 -248.820106) (xy 382.805895 -248.833798)
			(xy 382.75704 -248.83973) (xy 382.707865 -248.837749) (xy 382.659646 -248.827905) (xy 382.61363 -248.810453)
			(xy 382.571009 -248.785846) (xy 382.532888 -248.754721) (xy 382.500253 -248.717884) (xy 382.47395 -248.676288)
			(xy 382.454659 -248.631012) (xy 382.442882 -248.583228) (xy 382.438922 -248.534174) (xy 382.110234 -248.534174)
			(xy 382.109739 -248.558781) (xy 382.101844 -248.607358) (xy 382.08626 -248.654039) (xy 382.063389 -248.697616)
			(xy 382.033824 -248.73696) (xy 381.998331 -248.771052) (xy 381.957828 -248.799008) (xy 381.913366 -248.820106)
			(xy 381.866095 -248.833798) (xy 381.81724 -248.83973) (xy 381.768065 -248.837749) (xy 381.719846 -248.827905)
			(xy 381.67383 -248.810453) (xy 381.631209 -248.785846) (xy 381.593088 -248.754721) (xy 381.560453 -248.717884)
			(xy 381.53415 -248.676288) (xy 381.514859 -248.631012) (xy 381.503082 -248.583228) (xy 381.499122 -248.534174)
			(xy 381.180594 -248.534174) (xy 381.180082 -248.55962) (xy 381.171918 -248.609854) (xy 381.155802 -248.658128)
			(xy 381.132151 -248.703191) (xy 381.101578 -248.743877) (xy 381.064874 -248.779132) (xy 381.02299 -248.808042)
			(xy 380.977011 -248.829859) (xy 380.928127 -248.844019) (xy 380.877606 -248.850153) (xy 380.826754 -248.848104)
			(xy 380.77689 -248.837924) (xy 380.729304 -248.819877) (xy 380.68523 -248.794431) (xy 380.645808 -248.762244)
			(xy 380.61206 -248.72415) (xy 380.584859 -248.681136) (xy 380.564911 -248.634316) (xy 380.552732 -248.584902)
			(xy 380.548637 -248.534174) (xy 380.230126 -248.534174) (xy 380.229631 -248.558781) (xy 380.221736 -248.607358)
			(xy 380.206152 -248.654039) (xy 380.183281 -248.697616) (xy 380.153716 -248.73696) (xy 380.118223 -248.771052)
			(xy 380.07772 -248.799008) (xy 380.033258 -248.820106) (xy 379.985987 -248.833798) (xy 379.937132 -248.83973)
			(xy 379.887957 -248.837749) (xy 379.839738 -248.827905) (xy 379.793722 -248.810453) (xy 379.751101 -248.785846)
			(xy 379.71298 -248.754721) (xy 379.680345 -248.717884) (xy 379.654042 -248.676288) (xy 379.634751 -248.631012)
			(xy 379.622974 -248.583228) (xy 379.619014 -248.534174) (xy 379.300486 -248.534174) (xy 379.299974 -248.55962)
			(xy 379.29181 -248.609854) (xy 379.275694 -248.658128) (xy 379.252043 -248.703191) (xy 379.22147 -248.743877)
			(xy 379.184766 -248.779132) (xy 379.142882 -248.808042) (xy 379.096903 -248.829859) (xy 379.048019 -248.844019)
			(xy 378.997498 -248.850153) (xy 378.946646 -248.848104) (xy 378.896782 -248.837924) (xy 378.849196 -248.819877)
			(xy 378.805122 -248.794431) (xy 378.7657 -248.762244) (xy 378.731952 -248.72415) (xy 378.704751 -248.681136)
			(xy 378.684803 -248.634316) (xy 378.672624 -248.584902) (xy 378.668529 -248.534174) (xy 378.350018 -248.534174)
			(xy 378.349523 -248.558781) (xy 378.341628 -248.607358) (xy 378.326044 -248.654039) (xy 378.303173 -248.697616)
			(xy 378.273608 -248.73696) (xy 378.238115 -248.771052) (xy 378.197612 -248.799008) (xy 378.15315 -248.820106)
			(xy 378.105879 -248.833798) (xy 378.057024 -248.83973) (xy 378.007849 -248.837749) (xy 377.95963 -248.827905)
			(xy 377.913614 -248.810453) (xy 377.870993 -248.785846) (xy 377.832872 -248.754721) (xy 377.800237 -248.717884)
			(xy 377.773934 -248.676288) (xy 377.754643 -248.631012) (xy 377.742866 -248.583228) (xy 377.738906 -248.534174)
			(xy 377.420632 -248.534174) (xy 377.42012 -248.55962) (xy 377.411956 -248.609854) (xy 377.39584 -248.658128)
			(xy 377.372189 -248.703191) (xy 377.341616 -248.743877) (xy 377.304912 -248.779132) (xy 377.263028 -248.808042)
			(xy 377.217049 -248.829859) (xy 377.168165 -248.844019) (xy 377.117644 -248.850153) (xy 377.066792 -248.848104)
			(xy 377.016928 -248.837924) (xy 376.969342 -248.819877) (xy 376.925268 -248.794431) (xy 376.885846 -248.762244)
			(xy 376.852098 -248.72415) (xy 376.824897 -248.681136) (xy 376.804949 -248.634316) (xy 376.79277 -248.584902)
			(xy 376.788675 -248.534174) (xy 376.480578 -248.534174) (xy 376.480066 -248.55962) (xy 376.471902 -248.609854)
			(xy 376.455786 -248.658128) (xy 376.432135 -248.703191) (xy 376.401562 -248.743877) (xy 376.364858 -248.779132)
			(xy 376.322974 -248.808042) (xy 376.276995 -248.829859) (xy 376.228111 -248.844019) (xy 376.17759 -248.850153)
			(xy 376.126738 -248.848104) (xy 376.076874 -248.837924) (xy 376.029288 -248.819877) (xy 375.985214 -248.794431)
			(xy 375.945792 -248.762244) (xy 375.912044 -248.72415) (xy 375.884843 -248.681136) (xy 375.864895 -248.634316)
			(xy 375.852716 -248.584902) (xy 375.848621 -248.534174) (xy 375.530655 -248.534174) (xy 375.530657 -248.5342)
			(xy 375.526486 -248.584542) (xy 375.514085 -248.633511) (xy 375.493794 -248.679771) (xy 375.466165 -248.722061)
			(xy 375.431952 -248.759226) (xy 375.392089 -248.790253) (xy 375.347663 -248.814295) (xy 375.299885 -248.830697)
			(xy 375.250059 -248.839012) (xy 375.224802 -248.839482) (xy 375.198 -248.838923) (xy 375.145218 -248.829569)
			(xy 375.094878 -248.811148) (xy 375.048525 -248.784225) (xy 375.027698 -248.767346) (xy 375.016522 -248.757694)
			(xy 374.987058 -248.753884) (xy 374.89003 -248.798842) (xy 374.881399 -248.803276) (xy 374.868058 -248.817345)
			(xy 374.860925 -248.835374) (xy 374.860566 -248.84507) (xy 374.860566 -249.038872) (xy 374.875806 -249.06351)
			(xy 374.889014 -249.06986) (xy 374.910689 -249.080981) (xy 374.950503 -249.109048) (xy 374.985353 -249.143083)
			(xy 375.014356 -249.18222) (xy 375.036775 -249.225468) (xy 375.05204 -249.271727) (xy 375.059764 -249.319824)
			(xy 375.06021 -249.34418) (xy 375.378467 -249.34418) (xy 375.382562 -249.293452) (xy 375.394741 -249.244038)
			(xy 375.414689 -249.197218) (xy 375.44189 -249.154204) (xy 375.475638 -249.11611) (xy 375.51506 -249.083923)
			(xy 375.559134 -249.058477) (xy 375.60672 -249.04043) (xy 375.656584 -249.03025) (xy 375.707436 -249.028201)
			(xy 375.757957 -249.034335) (xy 375.806841 -249.048495) (xy 375.85282 -249.070312) (xy 375.894704 -249.099222)
			(xy 375.931408 -249.134477) (xy 375.961981 -249.175163) (xy 375.985632 -249.220226) (xy 376.001748 -249.2685)
			(xy 376.009912 -249.318734) (xy 376.010424 -249.34418) (xy 376.328952 -249.34418) (xy 376.332912 -249.295126)
			(xy 376.344689 -249.247342) (xy 376.36398 -249.202066) (xy 376.390283 -249.16047) (xy 376.422918 -249.123633)
			(xy 376.461039 -249.092508) (xy 376.50366 -249.067901) (xy 376.549676 -249.050449) (xy 376.597895 -249.040605)
			(xy 376.64707 -249.038624) (xy 376.695925 -249.044556) (xy 376.743196 -249.058248) (xy 376.787658 -249.079346)
			(xy 376.828161 -249.107302) (xy 376.863654 -249.141394) (xy 376.893219 -249.180738) (xy 376.91609 -249.224315)
			(xy 376.931674 -249.270996) (xy 376.939569 -249.319573) (xy 376.940064 -249.34418) (xy 377.269006 -249.34418)
			(xy 377.272966 -249.295126) (xy 377.284743 -249.247342) (xy 377.304034 -249.202066) (xy 377.330337 -249.16047)
			(xy 377.362972 -249.123633) (xy 377.401093 -249.092508) (xy 377.443714 -249.067901) (xy 377.48973 -249.050449)
			(xy 377.537949 -249.040605) (xy 377.587124 -249.038624) (xy 377.635979 -249.044556) (xy 377.68325 -249.058248)
			(xy 377.727712 -249.079346) (xy 377.768215 -249.107302) (xy 377.803708 -249.141394) (xy 377.833273 -249.180738)
			(xy 377.856144 -249.224315) (xy 377.871728 -249.270996) (xy 377.879623 -249.319573) (xy 377.880118 -249.34418)
			(xy 379.138683 -249.34418) (xy 379.142778 -249.293452) (xy 379.154957 -249.244038) (xy 379.174905 -249.197218)
			(xy 379.202106 -249.154204) (xy 379.235854 -249.11611) (xy 379.275276 -249.083923) (xy 379.31935 -249.058477)
			(xy 379.366936 -249.04043) (xy 379.4168 -249.03025) (xy 379.467652 -249.028201) (xy 379.518173 -249.034335)
			(xy 379.567057 -249.048495) (xy 379.613036 -249.070312) (xy 379.65492 -249.099222) (xy 379.691624 -249.134477)
			(xy 379.722197 -249.175163) (xy 379.745848 -249.220226) (xy 379.761964 -249.2685) (xy 379.770128 -249.318734)
			(xy 379.77064 -249.34418) (xy 380.088914 -249.34418) (xy 380.092874 -249.295126) (xy 380.104651 -249.247342)
			(xy 380.123942 -249.202066) (xy 380.150245 -249.16047) (xy 380.18288 -249.123633) (xy 380.221001 -249.092508)
			(xy 380.263622 -249.067901) (xy 380.309638 -249.050449) (xy 380.357857 -249.040605) (xy 380.407032 -249.038624)
			(xy 380.455887 -249.044556) (xy 380.503158 -249.058248) (xy 380.54762 -249.079346) (xy 380.588123 -249.107302)
			(xy 380.623616 -249.141394) (xy 380.653181 -249.180738) (xy 380.676052 -249.224315) (xy 380.691636 -249.270996)
			(xy 380.699531 -249.319573) (xy 380.700026 -249.34418) (xy 381.028968 -249.34418) (xy 381.032928 -249.295126)
			(xy 381.044705 -249.247342) (xy 381.063996 -249.202066) (xy 381.090299 -249.16047) (xy 381.122934 -249.123633)
			(xy 381.161055 -249.092508) (xy 381.203676 -249.067901) (xy 381.249692 -249.050449) (xy 381.297911 -249.040605)
			(xy 381.347086 -249.038624) (xy 381.395941 -249.044556) (xy 381.443212 -249.058248) (xy 381.487674 -249.079346)
			(xy 381.528177 -249.107302) (xy 381.56367 -249.141394) (xy 381.593235 -249.180738) (xy 381.616106 -249.224315)
			(xy 381.63169 -249.270996) (xy 381.639585 -249.319573) (xy 381.64008 -249.34418) (xy 381.969022 -249.34418)
			(xy 381.972982 -249.295126) (xy 381.984759 -249.247342) (xy 382.00405 -249.202066) (xy 382.030353 -249.16047)
			(xy 382.062988 -249.123633) (xy 382.101109 -249.092508) (xy 382.14373 -249.067901) (xy 382.189746 -249.050449)
			(xy 382.237965 -249.040605) (xy 382.28714 -249.038624) (xy 382.335995 -249.044556) (xy 382.383266 -249.058248)
			(xy 382.427728 -249.079346) (xy 382.468231 -249.107302) (xy 382.503724 -249.141394) (xy 382.533289 -249.180738)
			(xy 382.55616 -249.224315) (xy 382.571744 -249.270996) (xy 382.579639 -249.319573) (xy 382.580134 -249.34418)
			(xy 382.909076 -249.34418) (xy 382.913036 -249.295126) (xy 382.924813 -249.247342) (xy 382.944104 -249.202066)
			(xy 382.970407 -249.16047) (xy 383.003042 -249.123633) (xy 383.041163 -249.092508) (xy 383.083784 -249.067901)
			(xy 383.1298 -249.050449) (xy 383.178019 -249.040605) (xy 383.227194 -249.038624) (xy 383.276049 -249.044556)
			(xy 383.32332 -249.058248) (xy 383.367782 -249.079346) (xy 383.408285 -249.107302) (xy 383.443778 -249.141394)
			(xy 383.473343 -249.180738) (xy 383.496214 -249.224315) (xy 383.511798 -249.270996) (xy 383.519693 -249.319573)
			(xy 383.520188 -249.34418) (xy 383.84913 -249.34418) (xy 383.85309 -249.295126) (xy 383.864867 -249.247342)
			(xy 383.884158 -249.202066) (xy 383.910461 -249.16047) (xy 383.943096 -249.123633) (xy 383.981217 -249.092508)
			(xy 384.023838 -249.067901) (xy 384.069854 -249.050449) (xy 384.118073 -249.040605) (xy 384.167248 -249.038624)
			(xy 384.216103 -249.044556) (xy 384.263374 -249.058248) (xy 384.307836 -249.079346) (xy 384.348339 -249.107302)
			(xy 384.383832 -249.141394) (xy 384.413397 -249.180738) (xy 384.436268 -249.224315) (xy 384.451852 -249.270996)
			(xy 384.459747 -249.319573) (xy 384.460242 -249.34418) (xy 384.459747 -249.368787) (xy 384.451852 -249.417364)
			(xy 384.436268 -249.464045) (xy 384.413397 -249.507622) (xy 384.383832 -249.546966) (xy 384.348339 -249.581058)
			(xy 384.307836 -249.609014) (xy 384.263374 -249.630112) (xy 384.216103 -249.643804) (xy 384.167248 -249.649736)
			(xy 384.118073 -249.647755) (xy 384.069854 -249.637911) (xy 384.023838 -249.620459) (xy 383.981217 -249.595852)
			(xy 383.943096 -249.564727) (xy 383.910461 -249.52789) (xy 383.884158 -249.486294) (xy 383.864867 -249.441018)
			(xy 383.85309 -249.393234) (xy 383.84913 -249.34418) (xy 383.520188 -249.34418) (xy 383.519693 -249.368787)
			(xy 383.511798 -249.417364) (xy 383.496214 -249.464045) (xy 383.473343 -249.507622) (xy 383.443778 -249.546966)
			(xy 383.408285 -249.581058) (xy 383.367782 -249.609014) (xy 383.32332 -249.630112) (xy 383.276049 -249.643804)
			(xy 383.227194 -249.649736) (xy 383.178019 -249.647755) (xy 383.1298 -249.637911) (xy 383.083784 -249.620459)
			(xy 383.041163 -249.595852) (xy 383.003042 -249.564727) (xy 382.970407 -249.52789) (xy 382.944104 -249.486294)
			(xy 382.924813 -249.441018) (xy 382.913036 -249.393234) (xy 382.909076 -249.34418) (xy 382.580134 -249.34418)
			(xy 382.579639 -249.368787) (xy 382.571744 -249.417364) (xy 382.55616 -249.464045) (xy 382.533289 -249.507622)
			(xy 382.503724 -249.546966) (xy 382.468231 -249.581058) (xy 382.427728 -249.609014) (xy 382.383266 -249.630112)
			(xy 382.335995 -249.643804) (xy 382.28714 -249.649736) (xy 382.237965 -249.647755) (xy 382.189746 -249.637911)
			(xy 382.14373 -249.620459) (xy 382.101109 -249.595852) (xy 382.062988 -249.564727) (xy 382.030353 -249.52789)
			(xy 382.00405 -249.486294) (xy 381.984759 -249.441018) (xy 381.972982 -249.393234) (xy 381.969022 -249.34418)
			(xy 381.64008 -249.34418) (xy 381.639585 -249.368787) (xy 381.63169 -249.417364) (xy 381.616106 -249.464045)
			(xy 381.593235 -249.507622) (xy 381.56367 -249.546966) (xy 381.528177 -249.581058) (xy 381.487674 -249.609014)
			(xy 381.443212 -249.630112) (xy 381.395941 -249.643804) (xy 381.347086 -249.649736) (xy 381.297911 -249.647755)
			(xy 381.249692 -249.637911) (xy 381.203676 -249.620459) (xy 381.161055 -249.595852) (xy 381.122934 -249.564727)
			(xy 381.090299 -249.52789) (xy 381.063996 -249.486294) (xy 381.044705 -249.441018) (xy 381.032928 -249.393234)
			(xy 381.028968 -249.34418) (xy 380.700026 -249.34418) (xy 380.699531 -249.368787) (xy 380.691636 -249.417364)
			(xy 380.676052 -249.464045) (xy 380.653181 -249.507622) (xy 380.623616 -249.546966) (xy 380.588123 -249.581058)
			(xy 380.54762 -249.609014) (xy 380.503158 -249.630112) (xy 380.455887 -249.643804) (xy 380.407032 -249.649736)
			(xy 380.357857 -249.647755) (xy 380.309638 -249.637911) (xy 380.263622 -249.620459) (xy 380.221001 -249.595852)
			(xy 380.18288 -249.564727) (xy 380.150245 -249.52789) (xy 380.123942 -249.486294) (xy 380.104651 -249.441018)
			(xy 380.092874 -249.393234) (xy 380.088914 -249.34418) (xy 379.77064 -249.34418) (xy 379.770128 -249.369626)
			(xy 379.761964 -249.41986) (xy 379.745848 -249.468134) (xy 379.722197 -249.513197) (xy 379.691624 -249.553883)
			(xy 379.65492 -249.589138) (xy 379.613036 -249.618048) (xy 379.567057 -249.639865) (xy 379.518173 -249.654025)
			(xy 379.467652 -249.660159) (xy 379.4168 -249.65811) (xy 379.366936 -249.64793) (xy 379.31935 -249.629883)
			(xy 379.275276 -249.604437) (xy 379.235854 -249.57225) (xy 379.202106 -249.534156) (xy 379.174905 -249.491142)
			(xy 379.154957 -249.444322) (xy 379.142778 -249.394908) (xy 379.138683 -249.34418) (xy 377.880118 -249.34418)
			(xy 377.879623 -249.368787) (xy 377.871728 -249.417364) (xy 377.856144 -249.464045) (xy 377.833273 -249.507622)
			(xy 377.803708 -249.546966) (xy 377.768215 -249.581058) (xy 377.727712 -249.609014) (xy 377.68325 -249.630112)
			(xy 377.635979 -249.643804) (xy 377.587124 -249.649736) (xy 377.537949 -249.647755) (xy 377.48973 -249.637911)
			(xy 377.443714 -249.620459) (xy 377.401093 -249.595852) (xy 377.362972 -249.564727) (xy 377.330337 -249.52789)
			(xy 377.304034 -249.486294) (xy 377.284743 -249.441018) (xy 377.272966 -249.393234) (xy 377.269006 -249.34418)
			(xy 376.940064 -249.34418) (xy 376.939569 -249.368787) (xy 376.931674 -249.417364) (xy 376.91609 -249.464045)
			(xy 376.893219 -249.507622) (xy 376.863654 -249.546966) (xy 376.828161 -249.581058) (xy 376.787658 -249.609014)
			(xy 376.743196 -249.630112) (xy 376.695925 -249.643804) (xy 376.64707 -249.649736) (xy 376.597895 -249.647755)
			(xy 376.549676 -249.637911) (xy 376.50366 -249.620459) (xy 376.461039 -249.595852) (xy 376.422918 -249.564727)
			(xy 376.390283 -249.52789) (xy 376.36398 -249.486294) (xy 376.344689 -249.441018) (xy 376.332912 -249.393234)
			(xy 376.328952 -249.34418) (xy 376.010424 -249.34418) (xy 376.009912 -249.369626) (xy 376.001748 -249.41986)
			(xy 375.985632 -249.468134) (xy 375.961981 -249.513197) (xy 375.931408 -249.553883) (xy 375.894704 -249.589138)
			(xy 375.85282 -249.618048) (xy 375.806841 -249.639865) (xy 375.757957 -249.654025) (xy 375.707436 -249.660159)
			(xy 375.656584 -249.65811) (xy 375.60672 -249.64793) (xy 375.559134 -249.629883) (xy 375.51506 -249.604437)
			(xy 375.475638 -249.57225) (xy 375.44189 -249.534156) (xy 375.414689 -249.491142) (xy 375.394741 -249.444322)
			(xy 375.382562 -249.394908) (xy 375.378467 -249.34418) (xy 375.06021 -249.34418) (xy 375.059765 -249.368174)
			(xy 375.052261 -249.415572) (xy 375.037434 -249.461213) (xy 375.01565 -249.503972) (xy 374.987445 -249.542796)
			(xy 374.953513 -249.576731) (xy 374.914691 -249.604939) (xy 374.871933 -249.626726) (xy 374.826294 -249.641556)
			(xy 374.778896 -249.649064) (xy 374.754902 -249.649488) (xy 374.736167 -249.649203) (xy 374.698977 -249.644619)
			(xy 374.680734 -249.640344) (xy 374.68048 -249.640344) (xy 374.671955 -249.638606) (xy 374.654654 -249.640319)
			(xy 374.638912 -249.6477) (xy 374.632474 -249.653552) (xy 374.496076 -249.78995) (xy 374.48871 -249.797316)
			(xy 374.48109 -249.815858) (xy 374.481852 -249.90933) (xy 374.489726 -249.927872) (xy 374.497092 -249.934984)
			(xy 374.514347 -249.952347) (xy 374.543646 -249.991557) (xy 374.566306 -250.034944) (xy 374.581745 -250.081393)
			(xy 374.589566 -250.129712) (xy 374.590056 -250.154186) (xy 375.848621 -250.154186) (xy 375.852716 -250.103458)
			(xy 375.864895 -250.054044) (xy 375.884843 -250.007224) (xy 375.912044 -249.96421) (xy 375.945792 -249.926116)
			(xy 375.985214 -249.893929) (xy 376.029288 -249.868483) (xy 376.076874 -249.850436) (xy 376.126738 -249.840256)
			(xy 376.17759 -249.838207) (xy 376.228111 -249.844341) (xy 376.276995 -249.858501) (xy 376.322974 -249.880318)
			(xy 376.364858 -249.909228) (xy 376.401562 -249.944483) (xy 376.432135 -249.985169) (xy 376.455786 -250.030232)
			(xy 376.471902 -250.078506) (xy 376.480066 -250.12874) (xy 376.480578 -250.154186) (xy 376.799106 -250.154186)
			(xy 376.803066 -250.105132) (xy 376.814843 -250.057348) (xy 376.834134 -250.012072) (xy 376.860437 -249.970476)
			(xy 376.893072 -249.933639) (xy 376.931193 -249.902514) (xy 376.973814 -249.877907) (xy 377.01983 -249.860455)
			(xy 377.068049 -249.850611) (xy 377.117224 -249.84863) (xy 377.166079 -249.854562) (xy 377.21335 -249.868254)
			(xy 377.257812 -249.889352) (xy 377.298315 -249.917308) (xy 377.333808 -249.9514) (xy 377.363373 -249.990744)
			(xy 377.386244 -250.034321) (xy 377.401828 -250.081002) (xy 377.409723 -250.129579) (xy 377.410218 -250.154186)
			(xy 377.738906 -250.154186) (xy 377.742866 -250.105132) (xy 377.754643 -250.057348) (xy 377.773934 -250.012072)
			(xy 377.800237 -249.970476) (xy 377.832872 -249.933639) (xy 377.870993 -249.902514) (xy 377.913614 -249.877907)
			(xy 377.95963 -249.860455) (xy 378.007849 -249.850611) (xy 378.057024 -249.84863) (xy 378.105879 -249.854562)
			(xy 378.15315 -249.868254) (xy 378.197612 -249.889352) (xy 378.238115 -249.917308) (xy 378.273608 -249.9514)
			(xy 378.303173 -249.990744) (xy 378.326044 -250.034321) (xy 378.341628 -250.081002) (xy 378.349523 -250.129579)
			(xy 378.350018 -250.154186) (xy 378.668529 -250.154186) (xy 378.672624 -250.103458) (xy 378.684803 -250.054044)
			(xy 378.704751 -250.007224) (xy 378.731952 -249.96421) (xy 378.7657 -249.926116) (xy 378.805122 -249.893929)
			(xy 378.849196 -249.868483) (xy 378.896782 -249.850436) (xy 378.946646 -249.840256) (xy 378.997498 -249.838207)
			(xy 379.048019 -249.844341) (xy 379.096903 -249.858501) (xy 379.142882 -249.880318) (xy 379.184766 -249.909228)
			(xy 379.22147 -249.944483) (xy 379.252043 -249.985169) (xy 379.275694 -250.030232) (xy 379.29181 -250.078506)
			(xy 379.299974 -250.12874) (xy 379.300486 -250.154186) (xy 379.619014 -250.154186) (xy 379.622974 -250.105132)
			(xy 379.634751 -250.057348) (xy 379.654042 -250.012072) (xy 379.680345 -249.970476) (xy 379.71298 -249.933639)
			(xy 379.751101 -249.902514) (xy 379.793722 -249.877907) (xy 379.839738 -249.860455) (xy 379.887957 -249.850611)
			(xy 379.937132 -249.84863) (xy 379.985987 -249.854562) (xy 380.033258 -249.868254) (xy 380.07772 -249.889352)
			(xy 380.118223 -249.917308) (xy 380.153716 -249.9514) (xy 380.183281 -249.990744) (xy 380.206152 -250.034321)
			(xy 380.221736 -250.081002) (xy 380.229631 -250.129579) (xy 380.230126 -250.154186) (xy 380.559068 -250.154186)
			(xy 380.563028 -250.105132) (xy 380.574805 -250.057348) (xy 380.594096 -250.012072) (xy 380.620399 -249.970476)
			(xy 380.653034 -249.933639) (xy 380.691155 -249.902514) (xy 380.733776 -249.877907) (xy 380.779792 -249.860455)
			(xy 380.828011 -249.850611) (xy 380.877186 -249.84863) (xy 380.926041 -249.854562) (xy 380.973312 -249.868254)
			(xy 381.017774 -249.889352) (xy 381.058277 -249.917308) (xy 381.09377 -249.9514) (xy 381.123335 -249.990744)
			(xy 381.146206 -250.034321) (xy 381.16179 -250.081002) (xy 381.169685 -250.129579) (xy 381.17018 -250.154186)
			(xy 381.499122 -250.154186) (xy 381.503082 -250.105132) (xy 381.514859 -250.057348) (xy 381.53415 -250.012072)
			(xy 381.560453 -249.970476) (xy 381.593088 -249.933639) (xy 381.631209 -249.902514) (xy 381.67383 -249.877907)
			(xy 381.719846 -249.860455) (xy 381.768065 -249.850611) (xy 381.81724 -249.84863) (xy 381.866095 -249.854562)
			(xy 381.913366 -249.868254) (xy 381.957828 -249.889352) (xy 381.998331 -249.917308) (xy 382.033824 -249.9514)
			(xy 382.063389 -249.990744) (xy 382.08626 -250.034321) (xy 382.101844 -250.081002) (xy 382.109739 -250.129579)
			(xy 382.110234 -250.154186) (xy 382.438922 -250.154186) (xy 382.442882 -250.105132) (xy 382.454659 -250.057348)
			(xy 382.47395 -250.012072) (xy 382.500253 -249.970476) (xy 382.532888 -249.933639) (xy 382.571009 -249.902514)
			(xy 382.61363 -249.877907) (xy 382.659646 -249.860455) (xy 382.707865 -249.850611) (xy 382.75704 -249.84863)
			(xy 382.805895 -249.854562) (xy 382.853166 -249.868254) (xy 382.897628 -249.889352) (xy 382.938131 -249.917308)
			(xy 382.973624 -249.9514) (xy 383.003189 -249.990744) (xy 383.02606 -250.034321) (xy 383.041644 -250.081002)
			(xy 383.049539 -250.129579) (xy 383.050034 -250.154186) (xy 383.378976 -250.154186) (xy 383.382936 -250.105132)
			(xy 383.394713 -250.057348) (xy 383.414004 -250.012072) (xy 383.440307 -249.970476) (xy 383.472942 -249.933639)
			(xy 383.511063 -249.902514) (xy 383.553684 -249.877907) (xy 383.5997 -249.860455) (xy 383.647919 -249.850611)
			(xy 383.697094 -249.84863) (xy 383.745949 -249.854562) (xy 383.79322 -249.868254) (xy 383.837682 -249.889352)
			(xy 383.878185 -249.917308) (xy 383.913678 -249.9514) (xy 383.943243 -249.990744) (xy 383.966114 -250.034321)
			(xy 383.981698 -250.081002) (xy 383.989593 -250.129579) (xy 383.990088 -250.154186) (xy 383.989593 -250.178793)
			(xy 383.981698 -250.22737) (xy 383.966114 -250.274051) (xy 383.943243 -250.317628) (xy 383.913678 -250.356972)
			(xy 383.878185 -250.391064) (xy 383.837682 -250.41902) (xy 383.79322 -250.440118) (xy 383.745949 -250.45381)
			(xy 383.697094 -250.459742) (xy 383.647919 -250.457761) (xy 383.5997 -250.447917) (xy 383.553684 -250.430465)
			(xy 383.511063 -250.405858) (xy 383.472942 -250.374733) (xy 383.440307 -250.337896) (xy 383.414004 -250.2963)
			(xy 383.394713 -250.251024) (xy 383.382936 -250.20324) (xy 383.378976 -250.154186) (xy 383.050034 -250.154186)
			(xy 383.049539 -250.178793) (xy 383.041644 -250.22737) (xy 383.02606 -250.274051) (xy 383.003189 -250.317628)
			(xy 382.973624 -250.356972) (xy 382.938131 -250.391064) (xy 382.897628 -250.41902) (xy 382.853166 -250.440118)
			(xy 382.805895 -250.45381) (xy 382.75704 -250.459742) (xy 382.707865 -250.457761) (xy 382.659646 -250.447917)
			(xy 382.61363 -250.430465) (xy 382.571009 -250.405858) (xy 382.532888 -250.374733) (xy 382.500253 -250.337896)
			(xy 382.47395 -250.2963) (xy 382.454659 -250.251024) (xy 382.442882 -250.20324) (xy 382.438922 -250.154186)
			(xy 382.110234 -250.154186) (xy 382.109739 -250.178793) (xy 382.101844 -250.22737) (xy 382.08626 -250.274051)
			(xy 382.063389 -250.317628) (xy 382.033824 -250.356972) (xy 381.998331 -250.391064) (xy 381.957828 -250.41902)
			(xy 381.913366 -250.440118) (xy 381.866095 -250.45381) (xy 381.81724 -250.459742) (xy 381.768065 -250.457761)
			(xy 381.719846 -250.447917) (xy 381.67383 -250.430465) (xy 381.631209 -250.405858) (xy 381.593088 -250.374733)
			(xy 381.560453 -250.337896) (xy 381.53415 -250.2963) (xy 381.514859 -250.251024) (xy 381.503082 -250.20324)
			(xy 381.499122 -250.154186) (xy 381.17018 -250.154186) (xy 381.169685 -250.178793) (xy 381.16179 -250.22737)
			(xy 381.146206 -250.274051) (xy 381.123335 -250.317628) (xy 381.09377 -250.356972) (xy 381.058277 -250.391064)
			(xy 381.017774 -250.41902) (xy 380.973312 -250.440118) (xy 380.926041 -250.45381) (xy 380.877186 -250.459742)
			(xy 380.828011 -250.457761) (xy 380.779792 -250.447917) (xy 380.733776 -250.430465) (xy 380.691155 -250.405858)
			(xy 380.653034 -250.374733) (xy 380.620399 -250.337896) (xy 380.594096 -250.2963) (xy 380.574805 -250.251024)
			(xy 380.563028 -250.20324) (xy 380.559068 -250.154186) (xy 380.230126 -250.154186) (xy 380.229631 -250.178793)
			(xy 380.221736 -250.22737) (xy 380.206152 -250.274051) (xy 380.183281 -250.317628) (xy 380.153716 -250.356972)
			(xy 380.118223 -250.391064) (xy 380.07772 -250.41902) (xy 380.033258 -250.440118) (xy 379.985987 -250.45381)
			(xy 379.937132 -250.459742) (xy 379.887957 -250.457761) (xy 379.839738 -250.447917) (xy 379.793722 -250.430465)
			(xy 379.751101 -250.405858) (xy 379.71298 -250.374733) (xy 379.680345 -250.337896) (xy 379.654042 -250.2963)
			(xy 379.634751 -250.251024) (xy 379.622974 -250.20324) (xy 379.619014 -250.154186) (xy 379.300486 -250.154186)
			(xy 379.299974 -250.179632) (xy 379.29181 -250.229866) (xy 379.275694 -250.27814) (xy 379.252043 -250.323203)
			(xy 379.22147 -250.363889) (xy 379.184766 -250.399144) (xy 379.142882 -250.428054) (xy 379.096903 -250.449871)
			(xy 379.048019 -250.464031) (xy 378.997498 -250.470165) (xy 378.946646 -250.468116) (xy 378.896782 -250.457936)
			(xy 378.849196 -250.439889) (xy 378.805122 -250.414443) (xy 378.7657 -250.382256) (xy 378.731952 -250.344162)
			(xy 378.704751 -250.301148) (xy 378.684803 -250.254328) (xy 378.672624 -250.204914) (xy 378.668529 -250.154186)
			(xy 378.350018 -250.154186) (xy 378.349523 -250.178793) (xy 378.341628 -250.22737) (xy 378.326044 -250.274051)
			(xy 378.303173 -250.317628) (xy 378.273608 -250.356972) (xy 378.238115 -250.391064) (xy 378.197612 -250.41902)
			(xy 378.15315 -250.440118) (xy 378.105879 -250.45381) (xy 378.057024 -250.459742) (xy 378.007849 -250.457761)
			(xy 377.95963 -250.447917) (xy 377.913614 -250.430465) (xy 377.870993 -250.405858) (xy 377.832872 -250.374733)
			(xy 377.800237 -250.337896) (xy 377.773934 -250.2963) (xy 377.754643 -250.251024) (xy 377.742866 -250.20324)
			(xy 377.738906 -250.154186) (xy 377.410218 -250.154186) (xy 377.409723 -250.178793) (xy 377.401828 -250.22737)
			(xy 377.386244 -250.274051) (xy 377.363373 -250.317628) (xy 377.333808 -250.356972) (xy 377.298315 -250.391064)
			(xy 377.257812 -250.41902) (xy 377.21335 -250.440118) (xy 377.166079 -250.45381) (xy 377.117224 -250.459742)
			(xy 377.068049 -250.457761) (xy 377.01983 -250.447917) (xy 376.973814 -250.430465) (xy 376.931193 -250.405858)
			(xy 376.893072 -250.374733) (xy 376.860437 -250.337896) (xy 376.834134 -250.2963) (xy 376.814843 -250.251024)
			(xy 376.803066 -250.20324) (xy 376.799106 -250.154186) (xy 376.480578 -250.154186) (xy 376.480066 -250.179632)
			(xy 376.471902 -250.229866) (xy 376.455786 -250.27814) (xy 376.432135 -250.323203) (xy 376.401562 -250.363889)
			(xy 376.364858 -250.399144) (xy 376.322974 -250.428054) (xy 376.276995 -250.449871) (xy 376.228111 -250.464031)
			(xy 376.17759 -250.470165) (xy 376.126738 -250.468116) (xy 376.076874 -250.457936) (xy 376.029288 -250.439889)
			(xy 375.985214 -250.414443) (xy 375.945792 -250.382256) (xy 375.912044 -250.344162) (xy 375.884843 -250.301148)
			(xy 375.864895 -250.254328) (xy 375.852716 -250.204914) (xy 375.848621 -250.154186) (xy 374.590056 -250.154186)
			(xy 374.589586 -250.178179) (xy 374.582082 -250.225576) (xy 374.567257 -250.271214) (xy 374.545475 -250.313973)
			(xy 374.517272 -250.352797) (xy 374.483344 -250.386732) (xy 374.444526 -250.414942) (xy 374.401772 -250.436733)
			(xy 374.356136 -250.451568) (xy 374.308741 -250.459082) (xy 374.284748 -250.459494) (xy 374.260278 -250.458983)
			(xy 374.211972 -250.45113) (xy 374.165534 -250.435681) (xy 374.122151 -250.413031) (xy 374.082931 -250.383758)
			(xy 374.065546 -250.36653) (xy 374.058434 -250.359164) (xy 374.039892 -250.35129) (xy 373.957088 -250.350528)
			(xy 373.94689 -250.350879) (xy 373.928021 -250.358605) (xy 373.920512 -250.365514) (xy 373.321834 -250.964192)
			(xy 374.449098 -250.964192) (xy 374.453058 -250.915138) (xy 374.464835 -250.867354) (xy 374.484126 -250.822078)
			(xy 374.510429 -250.780482) (xy 374.543064 -250.743645) (xy 374.581185 -250.71252) (xy 374.623806 -250.687913)
			(xy 374.669822 -250.670461) (xy 374.718041 -250.660617) (xy 374.767216 -250.658636) (xy 374.816071 -250.664568)
			(xy 374.863342 -250.67826) (xy 374.907804 -250.699358) (xy 374.948307 -250.727314) (xy 374.9838 -250.761406)
			(xy 375.013365 -250.80075) (xy 375.036236 -250.844327) (xy 375.05182 -250.891008) (xy 375.059715 -250.939585)
			(xy 375.06021 -250.964192) (xy 375.378467 -250.964192) (xy 375.382562 -250.913464) (xy 375.394741 -250.86405)
			(xy 375.414689 -250.81723) (xy 375.44189 -250.774216) (xy 375.475638 -250.736122) (xy 375.51506 -250.703935)
			(xy 375.559134 -250.678489) (xy 375.60672 -250.660442) (xy 375.656584 -250.650262) (xy 375.707436 -250.648213)
			(xy 375.757957 -250.654347) (xy 375.806841 -250.668507) (xy 375.85282 -250.690324) (xy 375.894704 -250.719234)
			(xy 375.931408 -250.754489) (xy 375.961981 -250.795175) (xy 375.985632 -250.840238) (xy 376.001748 -250.888512)
			(xy 376.009912 -250.938746) (xy 376.010424 -250.964192) (xy 376.328952 -250.964192) (xy 376.332912 -250.915138)
			(xy 376.344689 -250.867354) (xy 376.36398 -250.822078) (xy 376.390283 -250.780482) (xy 376.422918 -250.743645)
			(xy 376.461039 -250.71252) (xy 376.50366 -250.687913) (xy 376.549676 -250.670461) (xy 376.597895 -250.660617)
			(xy 376.64707 -250.658636) (xy 376.695925 -250.664568) (xy 376.743196 -250.67826) (xy 376.787658 -250.699358)
			(xy 376.828161 -250.727314) (xy 376.863654 -250.761406) (xy 376.893219 -250.80075) (xy 376.91609 -250.844327)
			(xy 376.931674 -250.891008) (xy 376.939569 -250.939585) (xy 376.940064 -250.964192) (xy 377.258575 -250.964192)
			(xy 377.26267 -250.913464) (xy 377.274849 -250.86405) (xy 377.294797 -250.81723) (xy 377.321998 -250.774216)
			(xy 377.355746 -250.736122) (xy 377.395168 -250.703935) (xy 377.439242 -250.678489) (xy 377.486828 -250.660442)
			(xy 377.536692 -250.650262) (xy 377.587544 -250.648213) (xy 377.638065 -250.654347) (xy 377.686949 -250.668507)
			(xy 377.732928 -250.690324) (xy 377.774812 -250.719234) (xy 377.811516 -250.754489) (xy 377.842089 -250.795175)
			(xy 377.86574 -250.840238) (xy 377.881856 -250.888512) (xy 377.89002 -250.938746) (xy 377.890532 -250.964192)
			(xy 378.20906 -250.964192) (xy 378.21302 -250.915138) (xy 378.224797 -250.867354) (xy 378.244088 -250.822078)
			(xy 378.270391 -250.780482) (xy 378.303026 -250.743645) (xy 378.341147 -250.71252) (xy 378.383768 -250.687913)
			(xy 378.429784 -250.670461) (xy 378.478003 -250.660617) (xy 378.527178 -250.658636) (xy 378.576033 -250.664568)
			(xy 378.623304 -250.67826) (xy 378.667766 -250.699358) (xy 378.708269 -250.727314) (xy 378.743762 -250.761406)
			(xy 378.773327 -250.80075) (xy 378.796198 -250.844327) (xy 378.811782 -250.891008) (xy 378.819677 -250.939585)
			(xy 378.820172 -250.964192) (xy 379.138683 -250.964192) (xy 379.142778 -250.913464) (xy 379.154957 -250.86405)
			(xy 379.174905 -250.81723) (xy 379.202106 -250.774216) (xy 379.235854 -250.736122) (xy 379.275276 -250.703935)
			(xy 379.31935 -250.678489) (xy 379.366936 -250.660442) (xy 379.4168 -250.650262) (xy 379.467652 -250.648213)
			(xy 379.518173 -250.654347) (xy 379.567057 -250.668507) (xy 379.613036 -250.690324) (xy 379.65492 -250.719234)
			(xy 379.691624 -250.754489) (xy 379.722197 -250.795175) (xy 379.745848 -250.840238) (xy 379.761964 -250.888512)
			(xy 379.770128 -250.938746) (xy 379.77064 -250.964192) (xy 380.078483 -250.964192) (xy 380.082578 -250.913464)
			(xy 380.094757 -250.86405) (xy 380.114705 -250.81723) (xy 380.141906 -250.774216) (xy 380.175654 -250.736122)
			(xy 380.215076 -250.703935) (xy 380.25915 -250.678489) (xy 380.306736 -250.660442) (xy 380.3566 -250.650262)
			(xy 380.407452 -250.648213) (xy 380.457973 -250.654347) (xy 380.506857 -250.668507) (xy 380.552836 -250.690324)
			(xy 380.59472 -250.719234) (xy 380.631424 -250.754489) (xy 380.661997 -250.795175) (xy 380.685648 -250.840238)
			(xy 380.701764 -250.888512) (xy 380.709928 -250.938746) (xy 380.71044 -250.964192) (xy 381.028968 -250.964192)
			(xy 381.032928 -250.915138) (xy 381.044705 -250.867354) (xy 381.063996 -250.822078) (xy 381.090299 -250.780482)
			(xy 381.122934 -250.743645) (xy 381.161055 -250.71252) (xy 381.203676 -250.687913) (xy 381.249692 -250.670461)
			(xy 381.297911 -250.660617) (xy 381.347086 -250.658636) (xy 381.395941 -250.664568) (xy 381.443212 -250.67826)
			(xy 381.487674 -250.699358) (xy 381.528177 -250.727314) (xy 381.56367 -250.761406) (xy 381.593235 -250.80075)
			(xy 381.616106 -250.844327) (xy 381.63169 -250.891008) (xy 381.639585 -250.939585) (xy 381.64008 -250.964192)
			(xy 381.969022 -250.964192) (xy 381.972982 -250.915138) (xy 381.984759 -250.867354) (xy 382.00405 -250.822078)
			(xy 382.030353 -250.780482) (xy 382.062988 -250.743645) (xy 382.101109 -250.71252) (xy 382.14373 -250.687913)
			(xy 382.189746 -250.670461) (xy 382.237965 -250.660617) (xy 382.28714 -250.658636) (xy 382.335995 -250.664568)
			(xy 382.383266 -250.67826) (xy 382.427728 -250.699358) (xy 382.468231 -250.727314) (xy 382.503724 -250.761406)
			(xy 382.533289 -250.80075) (xy 382.55616 -250.844327) (xy 382.571744 -250.891008) (xy 382.579639 -250.939585)
			(xy 382.580134 -250.964192) (xy 382.909076 -250.964192) (xy 382.913036 -250.915138) (xy 382.924813 -250.867354)
			(xy 382.944104 -250.822078) (xy 382.970407 -250.780482) (xy 383.003042 -250.743645) (xy 383.041163 -250.71252)
			(xy 383.083784 -250.687913) (xy 383.1298 -250.670461) (xy 383.178019 -250.660617) (xy 383.227194 -250.658636)
			(xy 383.276049 -250.664568) (xy 383.32332 -250.67826) (xy 383.367782 -250.699358) (xy 383.408285 -250.727314)
			(xy 383.443778 -250.761406) (xy 383.473343 -250.80075) (xy 383.496214 -250.844327) (xy 383.511798 -250.891008)
			(xy 383.519693 -250.939585) (xy 383.520188 -250.964192) (xy 383.84913 -250.964192) (xy 383.85309 -250.915138)
			(xy 383.864867 -250.867354) (xy 383.884158 -250.822078) (xy 383.910461 -250.780482) (xy 383.943096 -250.743645)
			(xy 383.981217 -250.71252) (xy 384.023838 -250.687913) (xy 384.069854 -250.670461) (xy 384.118073 -250.660617)
			(xy 384.167248 -250.658636) (xy 384.216103 -250.664568) (xy 384.263374 -250.67826) (xy 384.307836 -250.699358)
			(xy 384.348339 -250.727314) (xy 384.383832 -250.761406) (xy 384.413397 -250.80075) (xy 384.436268 -250.844327)
			(xy 384.451852 -250.891008) (xy 384.459747 -250.939585) (xy 384.460242 -250.964192) (xy 384.459747 -250.988799)
			(xy 384.451852 -251.037376) (xy 384.436268 -251.084057) (xy 384.413397 -251.127634) (xy 384.383832 -251.166978)
			(xy 384.348339 -251.20107) (xy 384.307836 -251.229026) (xy 384.263374 -251.250124) (xy 384.216103 -251.263816)
			(xy 384.167248 -251.269748) (xy 384.118073 -251.267767) (xy 384.069854 -251.257923) (xy 384.023838 -251.240471)
			(xy 383.981217 -251.215864) (xy 383.943096 -251.184739) (xy 383.910461 -251.147902) (xy 383.884158 -251.106306)
			(xy 383.864867 -251.06103) (xy 383.85309 -251.013246) (xy 383.84913 -250.964192) (xy 383.520188 -250.964192)
			(xy 383.519693 -250.988799) (xy 383.511798 -251.037376) (xy 383.496214 -251.084057) (xy 383.473343 -251.127634)
			(xy 383.443778 -251.166978) (xy 383.408285 -251.20107) (xy 383.367782 -251.229026) (xy 383.32332 -251.250124)
			(xy 383.276049 -251.263816) (xy 383.227194 -251.269748) (xy 383.178019 -251.267767) (xy 383.1298 -251.257923)
			(xy 383.083784 -251.240471) (xy 383.041163 -251.215864) (xy 383.003042 -251.184739) (xy 382.970407 -251.147902)
			(xy 382.944104 -251.106306) (xy 382.924813 -251.06103) (xy 382.913036 -251.013246) (xy 382.909076 -250.964192)
			(xy 382.580134 -250.964192) (xy 382.579639 -250.988799) (xy 382.571744 -251.037376) (xy 382.55616 -251.084057)
			(xy 382.533289 -251.127634) (xy 382.503724 -251.166978) (xy 382.468231 -251.20107) (xy 382.427728 -251.229026)
			(xy 382.383266 -251.250124) (xy 382.335995 -251.263816) (xy 382.28714 -251.269748) (xy 382.237965 -251.267767)
			(xy 382.189746 -251.257923) (xy 382.14373 -251.240471) (xy 382.101109 -251.215864) (xy 382.062988 -251.184739)
			(xy 382.030353 -251.147902) (xy 382.00405 -251.106306) (xy 381.984759 -251.06103) (xy 381.972982 -251.013246)
			(xy 381.969022 -250.964192) (xy 381.64008 -250.964192) (xy 381.639585 -250.988799) (xy 381.63169 -251.037376)
			(xy 381.616106 -251.084057) (xy 381.593235 -251.127634) (xy 381.56367 -251.166978) (xy 381.528177 -251.20107)
			(xy 381.487674 -251.229026) (xy 381.443212 -251.250124) (xy 381.395941 -251.263816) (xy 381.347086 -251.269748)
			(xy 381.297911 -251.267767) (xy 381.249692 -251.257923) (xy 381.203676 -251.240471) (xy 381.161055 -251.215864)
			(xy 381.122934 -251.184739) (xy 381.090299 -251.147902) (xy 381.063996 -251.106306) (xy 381.044705 -251.06103)
			(xy 381.032928 -251.013246) (xy 381.028968 -250.964192) (xy 380.71044 -250.964192) (xy 380.709928 -250.989638)
			(xy 380.701764 -251.039872) (xy 380.685648 -251.088146) (xy 380.661997 -251.133209) (xy 380.631424 -251.173895)
			(xy 380.59472 -251.20915) (xy 380.552836 -251.23806) (xy 380.506857 -251.259877) (xy 380.457973 -251.274037)
			(xy 380.407452 -251.280171) (xy 380.3566 -251.278122) (xy 380.306736 -251.267942) (xy 380.25915 -251.249895)
			(xy 380.215076 -251.224449) (xy 380.175654 -251.192262) (xy 380.141906 -251.154168) (xy 380.114705 -251.111154)
			(xy 380.094757 -251.064334) (xy 380.082578 -251.01492) (xy 380.078483 -250.964192) (xy 379.77064 -250.964192)
			(xy 379.770128 -250.989638) (xy 379.761964 -251.039872) (xy 379.745848 -251.088146) (xy 379.722197 -251.133209)
			(xy 379.691624 -251.173895) (xy 379.65492 -251.20915) (xy 379.613036 -251.23806) (xy 379.567057 -251.259877)
			(xy 379.518173 -251.274037) (xy 379.467652 -251.280171) (xy 379.4168 -251.278122) (xy 379.366936 -251.267942)
			(xy 379.31935 -251.249895) (xy 379.275276 -251.224449) (xy 379.235854 -251.192262) (xy 379.202106 -251.154168)
			(xy 379.174905 -251.111154) (xy 379.154957 -251.064334) (xy 379.142778 -251.01492) (xy 379.138683 -250.964192)
			(xy 378.820172 -250.964192) (xy 378.819677 -250.988799) (xy 378.811782 -251.037376) (xy 378.796198 -251.084057)
			(xy 378.773327 -251.127634) (xy 378.743762 -251.166978) (xy 378.708269 -251.20107) (xy 378.667766 -251.229026)
			(xy 378.623304 -251.250124) (xy 378.576033 -251.263816) (xy 378.527178 -251.269748) (xy 378.478003 -251.267767)
			(xy 378.429784 -251.257923) (xy 378.383768 -251.240471) (xy 378.341147 -251.215864) (xy 378.303026 -251.184739)
			(xy 378.270391 -251.147902) (xy 378.244088 -251.106306) (xy 378.224797 -251.06103) (xy 378.21302 -251.013246)
			(xy 378.20906 -250.964192) (xy 377.890532 -250.964192) (xy 377.89002 -250.989638) (xy 377.881856 -251.039872)
			(xy 377.86574 -251.088146) (xy 377.842089 -251.133209) (xy 377.811516 -251.173895) (xy 377.774812 -251.20915)
			(xy 377.732928 -251.23806) (xy 377.686949 -251.259877) (xy 377.638065 -251.274037) (xy 377.587544 -251.280171)
			(xy 377.536692 -251.278122) (xy 377.486828 -251.267942) (xy 377.439242 -251.249895) (xy 377.395168 -251.224449)
			(xy 377.355746 -251.192262) (xy 377.321998 -251.154168) (xy 377.294797 -251.111154) (xy 377.274849 -251.064334)
			(xy 377.26267 -251.01492) (xy 377.258575 -250.964192) (xy 376.940064 -250.964192) (xy 376.939569 -250.988799)
			(xy 376.931674 -251.037376) (xy 376.91609 -251.084057) (xy 376.893219 -251.127634) (xy 376.863654 -251.166978)
			(xy 376.828161 -251.20107) (xy 376.787658 -251.229026) (xy 376.743196 -251.250124) (xy 376.695925 -251.263816)
			(xy 376.64707 -251.269748) (xy 376.597895 -251.267767) (xy 376.549676 -251.257923) (xy 376.50366 -251.240471)
			(xy 376.461039 -251.215864) (xy 376.422918 -251.184739) (xy 376.390283 -251.147902) (xy 376.36398 -251.106306)
			(xy 376.344689 -251.06103) (xy 376.332912 -251.013246) (xy 376.328952 -250.964192) (xy 376.010424 -250.964192)
			(xy 376.009912 -250.989638) (xy 376.001748 -251.039872) (xy 375.985632 -251.088146) (xy 375.961981 -251.133209)
			(xy 375.931408 -251.173895) (xy 375.894704 -251.20915) (xy 375.85282 -251.23806) (xy 375.806841 -251.259877)
			(xy 375.757957 -251.274037) (xy 375.707436 -251.280171) (xy 375.656584 -251.278122) (xy 375.60672 -251.267942)
			(xy 375.559134 -251.249895) (xy 375.51506 -251.224449) (xy 375.475638 -251.192262) (xy 375.44189 -251.154168)
			(xy 375.414689 -251.111154) (xy 375.394741 -251.064334) (xy 375.382562 -251.01492) (xy 375.378467 -250.964192)
			(xy 375.06021 -250.964192) (xy 375.059715 -250.988799) (xy 375.05182 -251.037376) (xy 375.036236 -251.084057)
			(xy 375.013365 -251.127634) (xy 374.9838 -251.166978) (xy 374.948307 -251.20107) (xy 374.907804 -251.229026)
			(xy 374.863342 -251.250124) (xy 374.816071 -251.263816) (xy 374.767216 -251.269748) (xy 374.718041 -251.267767)
			(xy 374.669822 -251.257923) (xy 374.623806 -251.240471) (xy 374.581185 -251.215864) (xy 374.543064 -251.184739)
			(xy 374.510429 -251.147902) (xy 374.484126 -251.106306) (xy 374.464835 -251.06103) (xy 374.453058 -251.013246)
			(xy 374.449098 -250.964192) (xy 373.321834 -250.964192) (xy 372.754398 -251.531628) (xy 372.747003 -251.538482)
			(xy 372.728404 -251.546227) (xy 372.71833 -251.546614) (xy 372.714012 -251.546614) (xy 372.70399 -251.547032)
			(xy 372.685471 -251.5547) (xy 372.671299 -251.568873) (xy 372.663631 -251.587392) (xy 372.663212 -251.597414)
			(xy 372.663212 -251.610876) (xy 372.669816 -251.62256) (xy 372.682468 -251.645813) (xy 372.70045 -251.695597)
			(xy 372.709604 -251.747732) (xy 372.710202 -251.774198) (xy 373.978944 -251.774198) (xy 373.982904 -251.725144)
			(xy 373.994681 -251.67736) (xy 374.013972 -251.632084) (xy 374.040275 -251.590488) (xy 374.07291 -251.553651)
			(xy 374.111031 -251.522526) (xy 374.153652 -251.497919) (xy 374.199668 -251.480467) (xy 374.247887 -251.470623)
			(xy 374.297062 -251.468642) (xy 374.345917 -251.474574) (xy 374.393188 -251.488266) (xy 374.43765 -251.509364)
			(xy 374.478153 -251.53732) (xy 374.513646 -251.571412) (xy 374.543211 -251.610756) (xy 374.566082 -251.654333)
			(xy 374.581666 -251.701014) (xy 374.589561 -251.749591) (xy 374.590056 -251.774198) (xy 375.848621 -251.774198)
			(xy 375.852716 -251.72347) (xy 375.864895 -251.674056) (xy 375.884843 -251.627236) (xy 375.912044 -251.584222)
			(xy 375.945792 -251.546128) (xy 375.985214 -251.513941) (xy 376.029288 -251.488495) (xy 376.076874 -251.470448)
			(xy 376.126738 -251.460268) (xy 376.17759 -251.458219) (xy 376.228111 -251.464353) (xy 376.276995 -251.478513)
			(xy 376.322974 -251.50033) (xy 376.364858 -251.52924) (xy 376.401562 -251.564495) (xy 376.432135 -251.605181)
			(xy 376.455786 -251.650244) (xy 376.471902 -251.698518) (xy 376.480066 -251.748752) (xy 376.480578 -251.774198)
			(xy 376.799106 -251.774198) (xy 376.803066 -251.725144) (xy 376.814843 -251.67736) (xy 376.834134 -251.632084)
			(xy 376.860437 -251.590488) (xy 376.893072 -251.553651) (xy 376.931193 -251.522526) (xy 376.973814 -251.497919)
			(xy 377.01983 -251.480467) (xy 377.068049 -251.470623) (xy 377.117224 -251.468642) (xy 377.166079 -251.474574)
			(xy 377.21335 -251.488266) (xy 377.257812 -251.509364) (xy 377.298315 -251.53732) (xy 377.333808 -251.571412)
			(xy 377.363373 -251.610756) (xy 377.386244 -251.654333) (xy 377.401828 -251.701014) (xy 377.409723 -251.749591)
			(xy 377.410218 -251.774198) (xy 378.668529 -251.774198) (xy 378.672624 -251.72347) (xy 378.684803 -251.674056)
			(xy 378.704751 -251.627236) (xy 378.731952 -251.584222) (xy 378.7657 -251.546128) (xy 378.805122 -251.513941)
			(xy 378.849196 -251.488495) (xy 378.896782 -251.470448) (xy 378.946646 -251.460268) (xy 378.997498 -251.458219)
			(xy 379.048019 -251.464353) (xy 379.096903 -251.478513) (xy 379.142882 -251.50033) (xy 379.184766 -251.52924)
			(xy 379.22147 -251.564495) (xy 379.252043 -251.605181) (xy 379.275694 -251.650244) (xy 379.29181 -251.698518)
			(xy 379.299974 -251.748752) (xy 379.300486 -251.774198) (xy 379.619014 -251.774198) (xy 379.622974 -251.725144)
			(xy 379.634751 -251.67736) (xy 379.654042 -251.632084) (xy 379.680345 -251.590488) (xy 379.71298 -251.553651)
			(xy 379.751101 -251.522526) (xy 379.793722 -251.497919) (xy 379.839738 -251.480467) (xy 379.887957 -251.470623)
			(xy 379.937132 -251.468642) (xy 379.985987 -251.474574) (xy 380.033258 -251.488266) (xy 380.07772 -251.509364)
			(xy 380.118223 -251.53732) (xy 380.153716 -251.571412) (xy 380.183281 -251.610756) (xy 380.206152 -251.654333)
			(xy 380.221736 -251.701014) (xy 380.229631 -251.749591) (xy 380.230126 -251.774198) (xy 380.559068 -251.774198)
			(xy 380.563028 -251.725144) (xy 380.574805 -251.67736) (xy 380.594096 -251.632084) (xy 380.620399 -251.590488)
			(xy 380.653034 -251.553651) (xy 380.691155 -251.522526) (xy 380.733776 -251.497919) (xy 380.779792 -251.480467)
			(xy 380.828011 -251.470623) (xy 380.877186 -251.468642) (xy 380.926041 -251.474574) (xy 380.973312 -251.488266)
			(xy 381.017774 -251.509364) (xy 381.058277 -251.53732) (xy 381.09377 -251.571412) (xy 381.123335 -251.610756)
			(xy 381.146206 -251.654333) (xy 381.16179 -251.701014) (xy 381.169685 -251.749591) (xy 381.17018 -251.774198)
			(xy 381.499122 -251.774198) (xy 381.503082 -251.725144) (xy 381.514859 -251.67736) (xy 381.53415 -251.632084)
			(xy 381.560453 -251.590488) (xy 381.593088 -251.553651) (xy 381.631209 -251.522526) (xy 381.67383 -251.497919)
			(xy 381.719846 -251.480467) (xy 381.768065 -251.470623) (xy 381.81724 -251.468642) (xy 381.866095 -251.474574)
			(xy 381.913366 -251.488266) (xy 381.957828 -251.509364) (xy 381.998331 -251.53732) (xy 382.033824 -251.571412)
			(xy 382.063389 -251.610756) (xy 382.08626 -251.654333) (xy 382.101844 -251.701014) (xy 382.109739 -251.749591)
			(xy 382.110234 -251.774198) (xy 382.438922 -251.774198) (xy 382.442882 -251.725144) (xy 382.454659 -251.67736)
			(xy 382.47395 -251.632084) (xy 382.500253 -251.590488) (xy 382.532888 -251.553651) (xy 382.571009 -251.522526)
			(xy 382.61363 -251.497919) (xy 382.659646 -251.480467) (xy 382.707865 -251.470623) (xy 382.75704 -251.468642)
			(xy 382.805895 -251.474574) (xy 382.853166 -251.488266) (xy 382.897628 -251.509364) (xy 382.938131 -251.53732)
			(xy 382.973624 -251.571412) (xy 383.003189 -251.610756) (xy 383.02606 -251.654333) (xy 383.041644 -251.701014)
			(xy 383.049539 -251.749591) (xy 383.050034 -251.774198) (xy 383.378976 -251.774198) (xy 383.382936 -251.725144)
			(xy 383.394713 -251.67736) (xy 383.414004 -251.632084) (xy 383.440307 -251.590488) (xy 383.472942 -251.553651)
			(xy 383.511063 -251.522526) (xy 383.553684 -251.497919) (xy 383.5997 -251.480467) (xy 383.647919 -251.470623)
			(xy 383.697094 -251.468642) (xy 383.745949 -251.474574) (xy 383.79322 -251.488266) (xy 383.837682 -251.509364)
			(xy 383.878185 -251.53732) (xy 383.913678 -251.571412) (xy 383.943243 -251.610756) (xy 383.966114 -251.654333)
			(xy 383.981698 -251.701014) (xy 383.989593 -251.749591) (xy 383.990088 -251.774198) (xy 383.989593 -251.798805)
			(xy 383.981698 -251.847382) (xy 383.966114 -251.894063) (xy 383.943243 -251.93764) (xy 383.913678 -251.976984)
			(xy 383.878185 -252.011076) (xy 383.837682 -252.039032) (xy 383.79322 -252.06013) (xy 383.745949 -252.073822)
			(xy 383.697094 -252.079754) (xy 383.647919 -252.077773) (xy 383.5997 -252.067929) (xy 383.553684 -252.050477)
			(xy 383.511063 -252.02587) (xy 383.472942 -251.994745) (xy 383.440307 -251.957908) (xy 383.414004 -251.916312)
			(xy 383.394713 -251.871036) (xy 383.382936 -251.823252) (xy 383.378976 -251.774198) (xy 383.050034 -251.774198)
			(xy 383.049539 -251.798805) (xy 383.041644 -251.847382) (xy 383.02606 -251.894063) (xy 383.003189 -251.93764)
			(xy 382.973624 -251.976984) (xy 382.938131 -252.011076) (xy 382.897628 -252.039032) (xy 382.853166 -252.06013)
			(xy 382.805895 -252.073822) (xy 382.75704 -252.079754) (xy 382.707865 -252.077773) (xy 382.659646 -252.067929)
			(xy 382.61363 -252.050477) (xy 382.571009 -252.02587) (xy 382.532888 -251.994745) (xy 382.500253 -251.957908)
			(xy 382.47395 -251.916312) (xy 382.454659 -251.871036) (xy 382.442882 -251.823252) (xy 382.438922 -251.774198)
			(xy 382.110234 -251.774198) (xy 382.109739 -251.798805) (xy 382.101844 -251.847382) (xy 382.08626 -251.894063)
			(xy 382.063389 -251.93764) (xy 382.033824 -251.976984) (xy 381.998331 -252.011076) (xy 381.957828 -252.039032)
			(xy 381.913366 -252.06013) (xy 381.866095 -252.073822) (xy 381.81724 -252.079754) (xy 381.768065 -252.077773)
			(xy 381.719846 -252.067929) (xy 381.67383 -252.050477) (xy 381.631209 -252.02587) (xy 381.593088 -251.994745)
			(xy 381.560453 -251.957908) (xy 381.53415 -251.916312) (xy 381.514859 -251.871036) (xy 381.503082 -251.823252)
			(xy 381.499122 -251.774198) (xy 381.17018 -251.774198) (xy 381.169685 -251.798805) (xy 381.16179 -251.847382)
			(xy 381.146206 -251.894063) (xy 381.123335 -251.93764) (xy 381.09377 -251.976984) (xy 381.058277 -252.011076)
			(xy 381.017774 -252.039032) (xy 380.973312 -252.06013) (xy 380.926041 -252.073822) (xy 380.877186 -252.079754)
			(xy 380.828011 -252.077773) (xy 380.779792 -252.067929) (xy 380.733776 -252.050477) (xy 380.691155 -252.02587)
			(xy 380.653034 -251.994745) (xy 380.620399 -251.957908) (xy 380.594096 -251.916312) (xy 380.574805 -251.871036)
			(xy 380.563028 -251.823252) (xy 380.559068 -251.774198) (xy 380.230126 -251.774198) (xy 380.229631 -251.798805)
			(xy 380.221736 -251.847382) (xy 380.206152 -251.894063) (xy 380.183281 -251.93764) (xy 380.153716 -251.976984)
			(xy 380.118223 -252.011076) (xy 380.07772 -252.039032) (xy 380.033258 -252.06013) (xy 379.985987 -252.073822)
			(xy 379.937132 -252.079754) (xy 379.887957 -252.077773) (xy 379.839738 -252.067929) (xy 379.793722 -252.050477)
			(xy 379.751101 -252.02587) (xy 379.71298 -251.994745) (xy 379.680345 -251.957908) (xy 379.654042 -251.916312)
			(xy 379.634751 -251.871036) (xy 379.622974 -251.823252) (xy 379.619014 -251.774198) (xy 379.300486 -251.774198)
			(xy 379.299974 -251.799644) (xy 379.29181 -251.849878) (xy 379.275694 -251.898152) (xy 379.252043 -251.943215)
			(xy 379.22147 -251.983901) (xy 379.184766 -252.019156) (xy 379.142882 -252.048066) (xy 379.096903 -252.069883)
			(xy 379.048019 -252.084043) (xy 378.997498 -252.090177) (xy 378.946646 -252.088128) (xy 378.896782 -252.077948)
			(xy 378.849196 -252.059901) (xy 378.805122 -252.034455) (xy 378.7657 -252.002268) (xy 378.731952 -251.964174)
			(xy 378.704751 -251.92116) (xy 378.684803 -251.87434) (xy 378.672624 -251.824926) (xy 378.668529 -251.774198)
			(xy 377.410218 -251.774198) (xy 377.409723 -251.798805) (xy 377.401828 -251.847382) (xy 377.386244 -251.894063)
			(xy 377.363373 -251.93764) (xy 377.333808 -251.976984) (xy 377.298315 -252.011076) (xy 377.257812 -252.039032)
			(xy 377.21335 -252.06013) (xy 377.166079 -252.073822) (xy 377.117224 -252.079754) (xy 377.068049 -252.077773)
			(xy 377.01983 -252.067929) (xy 376.973814 -252.050477) (xy 376.931193 -252.02587) (xy 376.893072 -251.994745)
			(xy 376.860437 -251.957908) (xy 376.834134 -251.916312) (xy 376.814843 -251.871036) (xy 376.803066 -251.823252)
			(xy 376.799106 -251.774198) (xy 376.480578 -251.774198) (xy 376.480066 -251.799644) (xy 376.471902 -251.849878)
			(xy 376.455786 -251.898152) (xy 376.432135 -251.943215) (xy 376.401562 -251.983901) (xy 376.364858 -252.019156)
			(xy 376.322974 -252.048066) (xy 376.276995 -252.069883) (xy 376.228111 -252.084043) (xy 376.17759 -252.090177)
			(xy 376.126738 -252.088128) (xy 376.076874 -252.077948) (xy 376.029288 -252.059901) (xy 375.985214 -252.034455)
			(xy 375.945792 -252.002268) (xy 375.912044 -251.964174) (xy 375.884843 -251.92116) (xy 375.864895 -251.87434)
			(xy 375.852716 -251.824926) (xy 375.848621 -251.774198) (xy 374.590056 -251.774198) (xy 374.589561 -251.798805)
			(xy 374.581666 -251.847382) (xy 374.566082 -251.894063) (xy 374.543211 -251.93764) (xy 374.513646 -251.976984)
			(xy 374.478153 -252.011076) (xy 374.43765 -252.039032) (xy 374.393188 -252.06013) (xy 374.345917 -252.073822)
			(xy 374.297062 -252.079754) (xy 374.247887 -252.077773) (xy 374.199668 -252.067929) (xy 374.153652 -252.050477)
			(xy 374.111031 -252.02587) (xy 374.07291 -251.994745) (xy 374.040275 -251.957908) (xy 374.013972 -251.916312)
			(xy 373.994681 -251.871036) (xy 373.982904 -251.823252) (xy 373.978944 -251.774198) (xy 372.710202 -251.774198)
			(xy 372.70968 -251.799453) (xy 372.701367 -251.849275) (xy 372.684966 -251.897049) (xy 372.660925 -251.941472)
			(xy 372.629901 -251.981332) (xy 372.592739 -252.015542) (xy 372.550453 -252.043168) (xy 372.504197 -252.063458)
			(xy 372.455232 -252.075858) (xy 372.404894 -252.080029) (xy 372.354556 -252.075858) (xy 372.305591 -252.063458)
			(xy 372.259335 -252.043168) (xy 372.217049 -252.015542) (xy 372.179887 -251.981332) (xy 372.148863 -251.941472)
			(xy 372.124822 -251.897049) (xy 372.108421 -251.849275) (xy 372.100108 -251.799453) (xy 372.099586 -251.774198)
			(xy 372.100147 -251.747729) (xy 372.109284 -251.695585) (xy 372.1273 -251.645806) (xy 372.139972 -251.62256)
			(xy 372.143274 -251.616972) (xy 372.146576 -251.604018) (xy 372.146576 -251.597414) (xy 372.146158 -251.587393)
			(xy 372.13849 -251.568875) (xy 372.124316 -251.554704) (xy 372.105797 -251.54704) (xy 372.095776 -251.546614)
			(xy 372.08206 -251.546614) (xy 372.051834 -251.530612) (xy 372.046303 -251.527914) (xy 372.034363 -251.524955)
			(xy 372.028212 -251.52477) (xy 371.333776 -251.52477) (xy 371.323935 -251.524242) (xy 371.305765 -251.516663)
			(xy 371.29847 -251.510038) (xy 371.06225 -251.273818) (xy 371.04066 -251.266198) (xy 371.028976 -251.267468)
			(xy 370.994686 -251.2695) (xy 370.970696 -251.269028) (xy 370.923306 -251.26152) (xy 370.877675 -251.246692)
			(xy 370.834924 -251.224907) (xy 370.796108 -251.196704) (xy 370.762182 -251.162775) (xy 370.733981 -251.123957)
			(xy 370.7122 -251.081205) (xy 370.697374 -251.035572) (xy 370.68987 -250.988182) (xy 370.689378 -250.964192)
			(xy 370.69141 -250.929902) (xy 370.69268 -250.918218) (xy 370.68506 -250.896628) (xy 370.402358 -250.613926)
			(xy 370.395246 -250.60656) (xy 370.37645 -250.59894) (xy 369.460526 -250.59894) (xy 369.450688 -250.599475)
			(xy 369.432522 -250.607056) (xy 369.42522 -250.613672) (xy 369.359688 -250.679204) (xy 369.353261 -250.686246)
			(xy 369.345706 -250.703735) (xy 369.344956 -250.71324) (xy 369.344194 -250.734576) (xy 369.344112 -250.739359)
			(xy 369.345519 -250.74882) (xy 369.346988 -250.753372) (xy 369.354862 -250.775216) (xy 369.359688 -250.781312)
			(xy 369.373962 -250.801252) (xy 369.396641 -250.844729) (xy 369.412092 -250.891267) (xy 369.419918 -250.939674)
			(xy 369.420394 -250.964192) (xy 369.419886 -250.977908) (xy 369.419124 -250.988322) (xy 369.416621 -251.013515)
			(xy 369.404339 -251.062627) (xy 369.384126 -251.109041) (xy 369.356535 -251.151487) (xy 369.322323 -251.188802)
			(xy 369.282426 -251.219964) (xy 369.237936 -251.24412) (xy 369.190072 -251.260608) (xy 369.140144 -251.268978)
			(xy 369.114832 -251.2695) (xy 369.103228 -251.269382) (xy 369.080089 -251.267603) (xy 369.068604 -251.265944)
			(xy 369.064794 -251.265436) (xy 369.064032 -251.265436) (xy 369.036238 -251.260098) (xy 368.983137 -251.240536)
			(xy 368.934537 -251.211546) (xy 368.912902 -251.1933) (xy 368.897662 -251.179838) (xy 368.857784 -251.181108)
			(xy 368.715544 -251.323348) (xy 368.711338 -251.327819) (xy 368.705045 -251.338354) (xy 368.703098 -251.344176)
			(xy 368.701318 -251.3505) (xy 368.700667 -251.363618) (xy 368.701828 -251.370084) (xy 368.722402 -251.464064)
			(xy 368.73942 -251.483622) (xy 368.751612 -251.488194) (xy 368.776208 -251.497994) (xy 368.821854 -251.524811)
			(xy 368.862192 -251.559098) (xy 368.896012 -251.599828) (xy 368.922301 -251.64578) (xy 368.940272 -251.695577)
			(xy 368.949385 -251.747727) (xy 368.949986 -251.774198) (xy 370.218982 -251.774198) (xy 370.222942 -251.725144)
			(xy 370.234719 -251.67736) (xy 370.25401 -251.632084) (xy 370.280313 -251.590488) (xy 370.312948 -251.553651)
			(xy 370.351069 -251.522526) (xy 370.39369 -251.497919) (xy 370.439706 -251.480467) (xy 370.487925 -251.470623)
			(xy 370.5371 -251.468642) (xy 370.585955 -251.474574) (xy 370.633226 -251.488266) (xy 370.677688 -251.509364)
			(xy 370.718191 -251.53732) (xy 370.753684 -251.571412) (xy 370.783249 -251.610756) (xy 370.80612 -251.654333)
			(xy 370.821704 -251.701014) (xy 370.829599 -251.749591) (xy 370.830094 -251.774198) (xy 370.829599 -251.798805)
			(xy 370.821704 -251.847382) (xy 370.80612 -251.894063) (xy 370.783249 -251.93764) (xy 370.753684 -251.976984)
			(xy 370.718191 -252.011076) (xy 370.677688 -252.039032) (xy 370.633226 -252.06013) (xy 370.585955 -252.073822)
			(xy 370.5371 -252.079754) (xy 370.487925 -252.077773) (xy 370.439706 -252.067929) (xy 370.39369 -252.050477)
			(xy 370.351069 -252.02587) (xy 370.312948 -251.994745) (xy 370.280313 -251.957908) (xy 370.25401 -251.916312)
			(xy 370.234719 -251.871036) (xy 370.222942 -251.823252) (xy 370.218982 -251.774198) (xy 368.949986 -251.774198)
			(xy 368.949464 -251.799453) (xy 368.941151 -251.849275) (xy 368.92475 -251.897049) (xy 368.900709 -251.941472)
			(xy 368.869685 -251.981332) (xy 368.832523 -252.015542) (xy 368.790237 -252.043168) (xy 368.743981 -252.063458)
			(xy 368.695016 -252.075858) (xy 368.644678 -252.080029) (xy 368.59434 -252.075858) (xy 368.545375 -252.063458)
			(xy 368.499119 -252.043168) (xy 368.456833 -252.015542) (xy 368.419671 -251.981332) (xy 368.388647 -251.941472)
			(xy 368.364606 -251.897049) (xy 368.348205 -251.849275) (xy 368.339892 -251.799453) (xy 368.33937 -251.774198)
			(xy 368.339914 -251.747974) (xy 368.348876 -251.696297) (xy 368.366536 -251.646912) (xy 368.378994 -251.62383)
			(xy 368.382296 -251.617988) (xy 368.385598 -251.605542) (xy 368.385598 -251.598684) (xy 368.385434 -251.59195)
			(xy 368.381971 -251.578939) (xy 368.37874 -251.57303) (xy 368.33556 -251.499116) (xy 368.333274 -251.49556)
			(xy 368.326197 -251.486566) (xy 368.306281 -251.475353) (xy 368.29492 -251.47397) (xy 367.625376 -251.47397)
			(xy 367.615535 -251.473442) (xy 367.597365 -251.465863) (xy 367.59007 -251.459238) (xy 367.382806 -251.251974)
			(xy 367.354104 -251.245624) (xy 367.33988 -251.250704) (xy 367.314474 -251.259449) (xy 367.261586 -251.268903)
			(xy 367.234724 -251.2695) (xy 367.23066 -251.2695) (xy 367.207079 -251.268749) (xy 367.160564 -251.260876)
			(xy 367.115813 -251.245942) (xy 367.073892 -251.224303) (xy 367.035798 -251.196473) (xy 367.002438 -251.163115)
			(xy 366.974606 -251.125022) (xy 366.952964 -251.083102) (xy 366.938028 -251.038352) (xy 366.930153 -250.991837)
			(xy 366.929416 -250.968256) (xy 366.929416 -250.966224) (xy 366.929416 -250.964192) (xy 366.930003 -250.937329)
			(xy 366.939457 -250.88444) (xy 366.948212 -250.859036) (xy 366.953292 -250.844812) (xy 366.946942 -250.81611)
			(xy 366.744758 -250.613926) (xy 366.737646 -250.60656) (xy 366.71885 -250.59894) (xy 365.767366 -250.59894)
			(xy 365.757524 -250.599468) (xy 365.739348 -250.607039) (xy 365.73206 -250.613672) (xy 365.616744 -250.728988)
			(xy 365.615474 -250.730512) (xy 365.611911 -250.734534) (xy 365.606402 -250.743756) (xy 365.604552 -250.7488)
			(xy 365.602256 -250.756499) (xy 365.602136 -250.772557) (xy 365.604298 -250.780296) (xy 365.608616 -250.794012)
			(xy 365.612426 -250.800108) (xy 365.61268 -250.800362) (xy 365.627572 -250.825066) (xy 365.648794 -250.878694)
			(xy 365.659569 -250.935354) (xy 365.660178 -250.964192) (xy 365.660178 -250.970796) (xy 365.659222 -250.994445)
			(xy 365.650908 -251.041036) (xy 365.635503 -251.085787) (xy 365.613376 -251.127623) (xy 365.585057 -251.165543)
			(xy 365.551225 -251.198638) (xy 365.51269 -251.226115) (xy 365.470376 -251.247314) (xy 365.425298 -251.261729)
			(xy 365.378534 -251.269014) (xy 365.35487 -251.2695) (xy 365.326033 -251.26886) (xy 365.269375 -251.258095)
			(xy 365.215739 -251.236898) (xy 365.19104 -251.222002) (xy 365.190786 -251.221748) (xy 365.18469 -251.217938)
			(xy 365.170974 -251.21362) (xy 365.163228 -251.211519) (xy 365.147187 -251.211642) (xy 365.139478 -251.213874)
			(xy 365.134434 -251.215725) (xy 365.125212 -251.221234) (xy 365.12119 -251.224796) (xy 365.119666 -251.226066)
			(xy 365.00181 -251.343922) (xy 364.993868 -251.352827) (xy 364.986458 -251.375476) (xy 364.987586 -251.387356)
			(xy 365.001556 -251.478542) (xy 365.015526 -251.4981) (xy 365.026448 -251.503688) (xy 365.047257 -251.515127)
			(xy 365.085374 -251.543443) (xy 365.118654 -251.577312) (xy 365.146296 -251.61592) (xy 365.167635 -251.658339)
			(xy 365.182159 -251.703546) (xy 365.189517 -251.750456) (xy 365.190024 -251.774198) (xy 366.45902 -251.774198)
			(xy 366.46298 -251.725144) (xy 366.474757 -251.67736) (xy 366.494048 -251.632084) (xy 366.520351 -251.590488)
			(xy 366.552986 -251.553651) (xy 366.591107 -251.522526) (xy 366.633728 -251.497919) (xy 366.679744 -251.480467)
			(xy 366.727963 -251.470623) (xy 366.777138 -251.468642) (xy 366.825993 -251.474574) (xy 366.873264 -251.488266)
			(xy 366.917726 -251.509364) (xy 366.958229 -251.53732) (xy 366.993722 -251.571412) (xy 367.023287 -251.610756)
			(xy 367.046158 -251.654333) (xy 367.061742 -251.701014) (xy 367.069637 -251.749591) (xy 367.070132 -251.774198)
			(xy 367.069637 -251.798805) (xy 367.061742 -251.847382) (xy 367.046158 -251.894063) (xy 367.023287 -251.93764)
			(xy 366.993722 -251.976984) (xy 366.958229 -252.011076) (xy 366.917726 -252.039032) (xy 366.873264 -252.06013)
			(xy 366.825993 -252.073822) (xy 366.777138 -252.079754) (xy 366.727963 -252.077773) (xy 366.679744 -252.067929)
			(xy 366.633728 -252.050477) (xy 366.591107 -252.02587) (xy 366.552986 -251.994745) (xy 366.520351 -251.957908)
			(xy 366.494048 -251.916312) (xy 366.474757 -251.871036) (xy 366.46298 -251.823252) (xy 366.45902 -251.774198)
			(xy 365.190024 -251.774198) (xy 365.189502 -251.799453) (xy 365.181189 -251.849275) (xy 365.164788 -251.897049)
			(xy 365.140747 -251.941472) (xy 365.109723 -251.981332) (xy 365.072561 -252.015542) (xy 365.030275 -252.043168)
			(xy 364.984019 -252.063458) (xy 364.935054 -252.075858) (xy 364.884716 -252.080029) (xy 364.834378 -252.075858)
			(xy 364.785413 -252.063458) (xy 364.739157 -252.043168) (xy 364.696871 -252.015542) (xy 364.659709 -251.981332)
			(xy 364.628685 -251.941472) (xy 364.604644 -251.897049) (xy 364.588243 -251.849275) (xy 364.57993 -251.799453)
			(xy 364.579408 -251.774198) (xy 364.579952 -251.747974) (xy 364.588915 -251.696298) (xy 364.606577 -251.646914)
			(xy 364.619032 -251.62383) (xy 364.622334 -251.617988) (xy 364.625636 -251.605542) (xy 364.625636 -251.598684)
			(xy 364.625471 -251.591951) (xy 364.622005 -251.578941) (xy 364.618778 -251.57303) (xy 364.575598 -251.499116)
			(xy 364.573312 -251.49556) (xy 364.56623 -251.486576) (xy 364.546312 -251.475387) (xy 364.534958 -251.47397)
			(xy 364.137956 -251.47397) (xy 364.128117 -251.473438) (xy 364.109952 -251.465854) (xy 364.10265 -251.459238)
			(xy 363.828076 -251.184664) (xy 363.825073 -251.181781) (xy 363.818308 -251.17693) (xy 363.814614 -251.175012)
			(xy 363.809348 -251.172571) (xy 363.798063 -251.169872) (xy 363.792262 -251.169678) (xy 363.72292 -251.16917)
			(xy 363.713067 -251.169578) (xy 363.694774 -251.176893) (xy 363.68736 -251.183394) (xy 363.687106 -251.183648)
			(xy 363.669916 -251.199665) (xy 363.631536 -251.226763) (xy 363.58946 -251.247669) (xy 363.544681 -251.261889)
			(xy 363.498253 -251.269088) (xy 363.474762 -251.2695) (xy 363.450525 -251.269032) (xy 363.402661 -251.261369)
			(xy 363.356609 -251.246241) (xy 363.313524 -251.224029) (xy 363.274489 -251.195289) (xy 363.240484 -251.160744)
			(xy 363.212363 -251.121261) (xy 363.190832 -251.077832) (xy 363.176431 -251.031547) (xy 363.172502 -251.007626)
			(xy 363.170724 -250.994418) (xy 363.1692 -250.964192) (xy 363.169623 -250.941105) (xy 363.176571 -250.895458)
			(xy 363.190306 -250.851375) (xy 363.210517 -250.80986) (xy 363.236744 -250.771858) (xy 363.268389 -250.738234)
			(xy 363.286294 -250.723654) (xy 363.288834 -250.721622) (xy 363.29112 -250.719336) (xy 363.297813 -250.711926)
			(xy 363.305426 -250.693489) (xy 363.305432 -250.673542) (xy 363.297831 -250.6551) (xy 363.29112 -250.647708)
			(xy 363.257338 -250.613926) (xy 363.250226 -250.60656) (xy 363.23143 -250.59894) (xy 361.901994 -250.59894)
			(xy 361.89228 -250.59937) (xy 361.874242 -250.60659) (xy 361.860177 -250.619993) (xy 361.855766 -250.628658)
			(xy 361.812078 -250.724162) (xy 361.816142 -250.753372) (xy 361.826048 -250.764802) (xy 361.84336 -250.785764)
			(xy 361.871031 -250.832555) (xy 361.889974 -250.883508) (xy 361.89959 -250.937012) (xy 361.900216 -250.964192)
			(xy 361.899694 -250.989447) (xy 361.891381 -251.039269) (xy 361.87498 -251.087043) (xy 361.850939 -251.131466)
			(xy 361.819915 -251.171326) (xy 361.782753 -251.205536) (xy 361.740467 -251.233162) (xy 361.694211 -251.253452)
			(xy 361.645246 -251.265852) (xy 361.594908 -251.270023) (xy 361.54457 -251.265852) (xy 361.495605 -251.253452)
			(xy 361.449349 -251.233162) (xy 361.407063 -251.205536) (xy 361.369901 -251.171326) (xy 361.338877 -251.131466)
			(xy 361.314836 -251.087043) (xy 361.298435 -251.039269) (xy 361.290122 -250.989447) (xy 361.2896 -250.964192)
			(xy 361.290195 -250.937011) (xy 361.299825 -250.883508) (xy 361.318779 -250.832556) (xy 361.346458 -250.785767)
			(xy 361.363768 -250.764802) (xy 361.373674 -250.753372) (xy 361.377738 -250.724162) (xy 361.33405 -250.628658)
			(xy 361.329633 -250.61999) (xy 361.31558 -250.606562) (xy 361.29754 -250.599324) (xy 361.287822 -250.59894)
			(xy 359.858818 -250.59894) (xy 359.850944 -250.601734) (xy 359.824109 -250.610191) (xy 359.768585 -250.619262)
			(xy 359.740454 -250.619768) (xy 359.712322 -250.619269) (xy 359.656795 -250.610206) (xy 359.629964 -250.601734)
			(xy 359.62209 -250.59894) (xy 357.379016 -250.59894) (xy 357.369178 -250.599477) (xy 357.351015 -250.607061)
			(xy 357.34371 -250.613672) (xy 357.173784 -250.783598) (xy 357.16845 -250.815602) (xy 357.175562 -250.830334)
			(xy 357.185335 -250.851281) (xy 357.199144 -250.895391) (xy 357.20613 -250.941081) (xy 357.20655 -250.964192)
			(xy 357.20608 -250.988185) (xy 357.198575 -251.03558) (xy 357.183749 -251.081218) (xy 357.161967 -251.123975)
			(xy 357.133764 -251.162798) (xy 357.099836 -251.196732) (xy 357.061017 -251.22494) (xy 357.018264 -251.24673)
			(xy 356.972629 -251.261563) (xy 356.925235 -251.269076) (xy 356.901242 -251.2695) (xy 356.878134 -251.269051)
			(xy 356.832451 -251.26205) (xy 356.78834 -251.24826) (xy 356.767384 -251.238512) (xy 356.752652 -251.2314)
			(xy 356.720648 -251.236734) (xy 356.601776 -251.355606) (xy 356.594538 -251.362318) (xy 356.576332 -251.369909)
			(xy 356.56647 -251.370338) (xy 356.29215 -251.370338) (xy 356.29088 -251.370592) (xy 355.759766 -251.370592)
			(xy 355.749498 -251.371068) (xy 355.730607 -251.379124) (xy 355.716381 -251.393936) (xy 355.713599 -251.40031)
			(xy 359.872791 -251.40031) (xy 359.876821 -251.347812) (xy 359.888818 -251.296544) (xy 359.908501 -251.247709)
			(xy 359.935407 -251.20245) (xy 359.968907 -251.161829) (xy 360.008215 -251.126798) (xy 360.05241 -251.098178)
			(xy 360.100455 -251.076639) (xy 360.151226 -251.062687) (xy 360.203531 -251.056649) (xy 360.256145 -251.058666)
			(xy 360.307835 -251.06869) (xy 360.357388 -251.086488) (xy 360.403644 -251.111641) (xy 360.445518 -251.14356)
			(xy 360.48203 -251.181498) (xy 360.512322 -251.224564) (xy 360.535685 -251.271749) (xy 360.551571 -251.321948)
			(xy 360.559608 -251.373984) (xy 360.560112 -251.40031) (xy 360.559608 -251.426636) (xy 360.551571 -251.478672)
			(xy 360.535685 -251.528871) (xy 360.512322 -251.576056) (xy 360.48203 -251.619122) (xy 360.445518 -251.65706)
			(xy 360.403644 -251.688979) (xy 360.357388 -251.714132) (xy 360.307835 -251.73193) (xy 360.256145 -251.741954)
			(xy 360.203531 -251.743971) (xy 360.151226 -251.737933) (xy 360.100455 -251.723981) (xy 360.05241 -251.702442)
			(xy 360.008215 -251.673822) (xy 359.968907 -251.638791) (xy 359.935407 -251.59817) (xy 359.908501 -251.552911)
			(xy 359.888818 -251.504076) (xy 359.876821 -251.452808) (xy 359.872791 -251.40031) (xy 355.713599 -251.40031)
			(xy 355.712268 -251.403358) (xy 355.679756 -251.489718) (xy 355.676554 -251.499456) (xy 355.677367 -251.51992)
			(xy 355.686148 -251.538422) (xy 355.693472 -251.545598) (xy 355.712467 -251.563138) (xy 355.74485 -251.603438)
			(xy 355.76998 -251.648618) (xy 355.787138 -251.697386) (xy 355.795832 -251.748349) (xy 355.796342 -251.774198)
			(xy 357.065338 -251.774198) (xy 357.069298 -251.725144) (xy 357.081075 -251.67736) (xy 357.100366 -251.632084)
			(xy 357.126669 -251.590488) (xy 357.159304 -251.553651) (xy 357.197425 -251.522526) (xy 357.240046 -251.497919)
			(xy 357.286062 -251.480467) (xy 357.334281 -251.470623) (xy 357.383456 -251.468642) (xy 357.432311 -251.474574)
			(xy 357.479582 -251.488266) (xy 357.524044 -251.509364) (xy 357.564547 -251.53732) (xy 357.60004 -251.571412)
			(xy 357.629605 -251.610756) (xy 357.652476 -251.654333) (xy 357.66806 -251.701014) (xy 357.675955 -251.749591)
			(xy 357.67645 -251.774198) (xy 360.81895 -251.774198) (xy 360.82291 -251.725144) (xy 360.834687 -251.67736)
			(xy 360.853978 -251.632084) (xy 360.880281 -251.590488) (xy 360.912916 -251.553651) (xy 360.951037 -251.522526)
			(xy 360.993658 -251.497919) (xy 361.039674 -251.480467) (xy 361.087893 -251.470623) (xy 361.137068 -251.468642)
			(xy 361.185923 -251.474574) (xy 361.233194 -251.488266) (xy 361.277656 -251.509364) (xy 361.318159 -251.53732)
			(xy 361.353652 -251.571412) (xy 361.383217 -251.610756) (xy 361.406088 -251.654333) (xy 361.421672 -251.701014)
			(xy 361.429567 -251.749591) (xy 361.430062 -251.774198) (xy 362.699058 -251.774198) (xy 362.703018 -251.725144)
			(xy 362.714795 -251.67736) (xy 362.734086 -251.632084) (xy 362.760389 -251.590488) (xy 362.793024 -251.553651)
			(xy 362.831145 -251.522526) (xy 362.873766 -251.497919) (xy 362.919782 -251.480467) (xy 362.968001 -251.470623)
			(xy 363.017176 -251.468642) (xy 363.066031 -251.474574) (xy 363.113302 -251.488266) (xy 363.157764 -251.509364)
			(xy 363.198267 -251.53732) (xy 363.23376 -251.571412) (xy 363.263325 -251.610756) (xy 363.286196 -251.654333)
			(xy 363.30178 -251.701014) (xy 363.309675 -251.749591) (xy 363.31017 -251.774198) (xy 363.309675 -251.798805)
			(xy 363.30178 -251.847382) (xy 363.286196 -251.894063) (xy 363.263325 -251.93764) (xy 363.23376 -251.976984)
			(xy 363.198267 -252.011076) (xy 363.157764 -252.039032) (xy 363.113302 -252.06013) (xy 363.066031 -252.073822)
			(xy 363.017176 -252.079754) (xy 362.968001 -252.077773) (xy 362.919782 -252.067929) (xy 362.873766 -252.050477)
			(xy 362.831145 -252.02587) (xy 362.793024 -251.994745) (xy 362.760389 -251.957908) (xy 362.734086 -251.916312)
			(xy 362.714795 -251.871036) (xy 362.703018 -251.823252) (xy 362.699058 -251.774198) (xy 361.430062 -251.774198)
			(xy 361.429567 -251.798805) (xy 361.421672 -251.847382) (xy 361.406088 -251.894063) (xy 361.383217 -251.93764)
			(xy 361.353652 -251.976984) (xy 361.318159 -252.011076) (xy 361.277656 -252.039032) (xy 361.233194 -252.06013)
			(xy 361.185923 -252.073822) (xy 361.137068 -252.079754) (xy 361.087893 -252.077773) (xy 361.039674 -252.067929)
			(xy 360.993658 -252.050477) (xy 360.951037 -252.02587) (xy 360.912916 -251.994745) (xy 360.880281 -251.957908)
			(xy 360.853978 -251.916312) (xy 360.834687 -251.871036) (xy 360.82291 -251.823252) (xy 360.81895 -251.774198)
			(xy 357.67645 -251.774198) (xy 357.675955 -251.798805) (xy 357.66806 -251.847382) (xy 357.652476 -251.894063)
			(xy 357.629605 -251.93764) (xy 357.60004 -251.976984) (xy 357.564547 -252.011076) (xy 357.524044 -252.039032)
			(xy 357.479582 -252.06013) (xy 357.432311 -252.073822) (xy 357.383456 -252.079754) (xy 357.334281 -252.077773)
			(xy 357.286062 -252.067929) (xy 357.240046 -252.050477) (xy 357.197425 -252.02587) (xy 357.159304 -251.994745)
			(xy 357.126669 -251.957908) (xy 357.100366 -251.916312) (xy 357.081075 -251.871036) (xy 357.069298 -251.823252)
			(xy 357.065338 -251.774198) (xy 355.796342 -251.774198) (xy 355.79582 -251.799453) (xy 355.787507 -251.849275)
			(xy 355.771106 -251.897049) (xy 355.747065 -251.941472) (xy 355.716041 -251.981332) (xy 355.678879 -252.015542)
			(xy 355.636593 -252.043168) (xy 355.590337 -252.063458) (xy 355.541372 -252.075858) (xy 355.491034 -252.080029)
			(xy 355.440696 -252.075858) (xy 355.391731 -252.063458) (xy 355.345475 -252.043168) (xy 355.303189 -252.015542)
			(xy 355.266027 -251.981332) (xy 355.235003 -251.941472) (xy 355.210962 -251.897049) (xy 355.194561 -251.849275)
			(xy 355.186248 -251.799453) (xy 355.185726 -251.774198) (xy 355.185863 -251.761435) (xy 355.188022 -251.736)
			(xy 355.190044 -251.723398) (xy 355.18979 -251.723398) (xy 355.194669 -251.69792) (xy 355.211855 -251.648981)
			(xy 355.23706 -251.603646) (xy 355.269557 -251.563219) (xy 355.288596 -251.545598) (xy 355.295921 -251.53843)
			(xy 355.304663 -251.519914) (xy 355.305508 -251.499454) (xy 355.302312 -251.489718) (xy 355.2698 -251.403358)
			(xy 355.265735 -251.393885) (xy 355.251515 -251.378988) (xy 355.232597 -251.370848) (xy 355.222302 -251.370338)
			(xy 354.675694 -251.370338) (xy 354.670868 -251.370592) (xy 353.879912 -251.370592) (xy 353.869639 -251.37106)
			(xy 353.850733 -251.379107) (xy 353.836493 -251.393918) (xy 353.832414 -251.403358) (xy 353.799902 -251.489718)
			(xy 353.796702 -251.499457) (xy 353.797515 -251.519922) (xy 353.806289 -251.538428) (xy 353.813618 -251.545598)
			(xy 353.832616 -251.563137) (xy 353.865005 -251.603434) (xy 353.890139 -251.648614) (xy 353.9073 -251.697384)
			(xy 353.915996 -251.748348) (xy 353.916488 -251.774198) (xy 353.915966 -251.799453) (xy 353.907653 -251.849275)
			(xy 353.891252 -251.897049) (xy 353.867211 -251.941472) (xy 353.836187 -251.981332) (xy 353.799025 -252.015542)
			(xy 353.756739 -252.043168) (xy 353.710483 -252.063458) (xy 353.661518 -252.075858) (xy 353.61118 -252.080029)
			(xy 353.560842 -252.075858) (xy 353.511877 -252.063458) (xy 353.465621 -252.043168) (xy 353.423335 -252.015542)
			(xy 353.386173 -251.981332) (xy 353.355149 -251.941472) (xy 353.331108 -251.897049) (xy 353.314707 -251.849275)
			(xy 353.306394 -251.799453) (xy 353.305872 -251.774198) (xy 353.305991 -251.762594) (xy 353.307772 -251.739456)
			(xy 353.309428 -251.72797) (xy 353.309936 -251.72416) (xy 353.309936 -251.723398) (xy 353.314814 -251.697919)
			(xy 353.331998 -251.648978) (xy 353.357199 -251.60364) (xy 353.389693 -251.563208) (xy 353.408742 -251.545598)
			(xy 353.420426 -251.53493) (xy 353.428046 -251.50445) (xy 353.389946 -251.403358) (xy 353.385878 -251.393892)
			(xy 353.371656 -251.379009) (xy 353.352739 -251.370889) (xy 353.342448 -251.370338) (xy 352.795586 -251.370338)
			(xy 352.79076 -251.370592) (xy 351.999804 -251.370592) (xy 351.989531 -251.371061) (xy 351.970629 -251.37911)
			(xy 351.956391 -251.393921) (xy 351.952306 -251.403358) (xy 351.919794 -251.489718) (xy 351.916594 -251.499457)
			(xy 351.917407 -251.519922) (xy 351.92618 -251.538429) (xy 351.93351 -251.545598) (xy 351.952509 -251.563136)
			(xy 351.984898 -251.603434) (xy 352.010033 -251.648614) (xy 352.027194 -251.697383) (xy 352.035891 -251.748347)
			(xy 352.03638 -251.774198) (xy 352.035858 -251.799453) (xy 352.027545 -251.849275) (xy 352.011144 -251.897049)
			(xy 351.987103 -251.941472) (xy 351.956079 -251.981332) (xy 351.918917 -252.015542) (xy 351.876631 -252.043168)
			(xy 351.830375 -252.063458) (xy 351.78141 -252.075858) (xy 351.731072 -252.080029) (xy 351.680734 -252.075858)
			(xy 351.631769 -252.063458) (xy 351.585513 -252.043168) (xy 351.543227 -252.015542) (xy 351.506065 -251.981332)
			(xy 351.475041 -251.941472) (xy 351.451 -251.897049) (xy 351.434599 -251.849275) (xy 351.426286 -251.799453)
			(xy 351.425764 -251.774198) (xy 351.425901 -251.761435) (xy 351.42806 -251.736001) (xy 351.430082 -251.723398)
			(xy 351.429828 -251.723398) (xy 351.434706 -251.697919) (xy 351.45189 -251.648977) (xy 351.47709 -251.603639)
			(xy 351.509584 -251.563207) (xy 351.528634 -251.545598) (xy 351.535967 -251.538434) (xy 351.54472 -251.519916)
			(xy 351.545565 -251.49945) (xy 351.54235 -251.489718) (xy 351.509838 -251.403358) (xy 351.505775 -251.393881)
			(xy 351.491557 -251.378973) (xy 351.472638 -251.37082) (xy 351.46234 -251.370338) (xy 350.915732 -251.370338)
			(xy 350.910906 -251.370592) (xy 350.735392 -251.370592) (xy 350.726438 -251.371573) (xy 350.71004 -251.378996)
			(xy 350.703388 -251.38507) (xy 350.604074 -251.484638) (xy 350.597366 -251.491878) (xy 350.589784 -251.510083)
			(xy 350.589342 -251.519944) (xy 350.589342 -251.807218) (xy 350.589801 -251.817096) (xy 350.597238 -251.8354)
			(xy 350.60382 -251.842778) (xy 350.604074 -251.843032) (xy 351.177352 -252.41631) (xy 359.853741 -252.41631)
			(xy 359.857771 -252.363812) (xy 359.869768 -252.312544) (xy 359.889451 -252.263709) (xy 359.916357 -252.21845)
			(xy 359.949857 -252.177829) (xy 359.989165 -252.142798) (xy 360.03336 -252.114178) (xy 360.081405 -252.092639)
			(xy 360.132176 -252.078687) (xy 360.184481 -252.072649) (xy 360.237095 -252.074666) (xy 360.288785 -252.08469)
			(xy 360.338338 -252.102488) (xy 360.384594 -252.127641) (xy 360.426468 -252.15956) (xy 360.46298 -252.197498)
			(xy 360.493272 -252.240564) (xy 360.516635 -252.287749) (xy 360.532521 -252.337948) (xy 360.540558 -252.389984)
			(xy 360.541062 -252.41631) (xy 360.540558 -252.442636) (xy 360.532521 -252.494672) (xy 360.516635 -252.544871)
			(xy 360.49716 -252.584204) (xy 368.809028 -252.584204) (xy 368.812988 -252.53515) (xy 368.824765 -252.487366)
			(xy 368.844056 -252.44209) (xy 368.870359 -252.400494) (xy 368.902994 -252.363657) (xy 368.941115 -252.332532)
			(xy 368.983736 -252.307925) (xy 369.029752 -252.290473) (xy 369.077971 -252.280629) (xy 369.127146 -252.278648)
			(xy 369.176001 -252.28458) (xy 369.223272 -252.298272) (xy 369.267734 -252.31937) (xy 369.308237 -252.347326)
			(xy 369.34373 -252.381418) (xy 369.373295 -252.420762) (xy 369.396166 -252.464339) (xy 369.41175 -252.51102)
			(xy 369.419645 -252.559597) (xy 369.42014 -252.584204) (xy 370.688882 -252.584204) (xy 370.692842 -252.53515)
			(xy 370.704619 -252.487366) (xy 370.72391 -252.44209) (xy 370.750213 -252.400494) (xy 370.782848 -252.363657)
			(xy 370.820969 -252.332532) (xy 370.86359 -252.307925) (xy 370.909606 -252.290473) (xy 370.957825 -252.280629)
			(xy 371.007 -252.278648) (xy 371.055855 -252.28458) (xy 371.103126 -252.298272) (xy 371.147588 -252.31937)
			(xy 371.188091 -252.347326) (xy 371.223584 -252.381418) (xy 371.253149 -252.420762) (xy 371.27602 -252.464339)
			(xy 371.291604 -252.51102) (xy 371.299499 -252.559597) (xy 371.299994 -252.584204) (xy 372.56899 -252.584204)
			(xy 372.57295 -252.53515) (xy 372.584727 -252.487366) (xy 372.604018 -252.44209) (xy 372.630321 -252.400494)
			(xy 372.662956 -252.363657) (xy 372.701077 -252.332532) (xy 372.743698 -252.307925) (xy 372.789714 -252.290473)
			(xy 372.837933 -252.280629) (xy 372.887108 -252.278648) (xy 372.935963 -252.28458) (xy 372.983234 -252.298272)
			(xy 373.027696 -252.31937) (xy 373.068199 -252.347326) (xy 373.103692 -252.381418) (xy 373.133257 -252.420762)
			(xy 373.156128 -252.464339) (xy 373.171712 -252.51102) (xy 373.179607 -252.559597) (xy 373.180102 -252.584204)
			(xy 374.449098 -252.584204) (xy 374.453058 -252.53515) (xy 374.464835 -252.487366) (xy 374.484126 -252.44209)
			(xy 374.510429 -252.400494) (xy 374.543064 -252.363657) (xy 374.581185 -252.332532) (xy 374.623806 -252.307925)
			(xy 374.669822 -252.290473) (xy 374.718041 -252.280629) (xy 374.767216 -252.278648) (xy 374.816071 -252.28458)
			(xy 374.863342 -252.298272) (xy 374.907804 -252.31937) (xy 374.948307 -252.347326) (xy 374.9838 -252.381418)
			(xy 375.013365 -252.420762) (xy 375.036236 -252.464339) (xy 375.05182 -252.51102) (xy 375.059715 -252.559597)
			(xy 375.06021 -252.584204) (xy 375.388898 -252.584204) (xy 375.392858 -252.53515) (xy 375.404635 -252.487366)
			(xy 375.423926 -252.44209) (xy 375.450229 -252.400494) (xy 375.482864 -252.363657) (xy 375.520985 -252.332532)
			(xy 375.563606 -252.307925) (xy 375.609622 -252.290473) (xy 375.657841 -252.280629) (xy 375.707016 -252.278648)
			(xy 375.755871 -252.28458) (xy 375.803142 -252.298272) (xy 375.847604 -252.31937) (xy 375.888107 -252.347326)
			(xy 375.9236 -252.381418) (xy 375.953165 -252.420762) (xy 375.976036 -252.464339) (xy 375.99162 -252.51102)
			(xy 375.999515 -252.559597) (xy 376.00001 -252.584204) (xy 376.328952 -252.584204) (xy 376.332912 -252.53515)
			(xy 376.344689 -252.487366) (xy 376.36398 -252.44209) (xy 376.390283 -252.400494) (xy 376.422918 -252.363657)
			(xy 376.461039 -252.332532) (xy 376.50366 -252.307925) (xy 376.549676 -252.290473) (xy 376.597895 -252.280629)
			(xy 376.64707 -252.278648) (xy 376.695925 -252.28458) (xy 376.743196 -252.298272) (xy 376.787658 -252.31937)
			(xy 376.828161 -252.347326) (xy 376.863654 -252.381418) (xy 376.893219 -252.420762) (xy 376.91609 -252.464339)
			(xy 376.931674 -252.51102) (xy 376.939569 -252.559597) (xy 376.940064 -252.584204) (xy 377.258575 -252.584204)
			(xy 377.26267 -252.533476) (xy 377.274849 -252.484062) (xy 377.294797 -252.437242) (xy 377.321998 -252.394228)
			(xy 377.355746 -252.356134) (xy 377.395168 -252.323947) (xy 377.439242 -252.298501) (xy 377.486828 -252.280454)
			(xy 377.536692 -252.270274) (xy 377.587544 -252.268225) (xy 377.638065 -252.274359) (xy 377.686949 -252.288519)
			(xy 377.732928 -252.310336) (xy 377.774812 -252.339246) (xy 377.811516 -252.374501) (xy 377.842089 -252.415187)
			(xy 377.86574 -252.46025) (xy 377.881856 -252.508524) (xy 377.89002 -252.558758) (xy 377.890532 -252.584204)
			(xy 378.20906 -252.584204) (xy 378.21302 -252.53515) (xy 378.224797 -252.487366) (xy 378.244088 -252.44209)
			(xy 378.270391 -252.400494) (xy 378.303026 -252.363657) (xy 378.341147 -252.332532) (xy 378.383768 -252.307925)
			(xy 378.429784 -252.290473) (xy 378.478003 -252.280629) (xy 378.527178 -252.278648) (xy 378.576033 -252.28458)
			(xy 378.623304 -252.298272) (xy 378.667766 -252.31937) (xy 378.708269 -252.347326) (xy 378.743762 -252.381418)
			(xy 378.773327 -252.420762) (xy 378.796198 -252.464339) (xy 378.811782 -252.51102) (xy 378.819677 -252.559597)
			(xy 378.820172 -252.584204) (xy 379.149114 -252.584204) (xy 379.153074 -252.53515) (xy 379.164851 -252.487366)
			(xy 379.184142 -252.44209) (xy 379.210445 -252.400494) (xy 379.24308 -252.363657) (xy 379.281201 -252.332532)
			(xy 379.323822 -252.307925) (xy 379.369838 -252.290473) (xy 379.418057 -252.280629) (xy 379.467232 -252.278648)
			(xy 379.516087 -252.28458) (xy 379.563358 -252.298272) (xy 379.60782 -252.31937) (xy 379.648323 -252.347326)
			(xy 379.683816 -252.381418) (xy 379.713381 -252.420762) (xy 379.736252 -252.464339) (xy 379.751836 -252.51102)
			(xy 379.759731 -252.559597) (xy 379.760226 -252.584204) (xy 380.078483 -252.584204) (xy 380.082578 -252.533476)
			(xy 380.094757 -252.484062) (xy 380.114705 -252.437242) (xy 380.141906 -252.394228) (xy 380.175654 -252.356134)
			(xy 380.215076 -252.323947) (xy 380.25915 -252.298501) (xy 380.306736 -252.280454) (xy 380.3566 -252.270274)
			(xy 380.407452 -252.268225) (xy 380.457973 -252.274359) (xy 380.506857 -252.288519) (xy 380.552836 -252.310336)
			(xy 380.59472 -252.339246) (xy 380.631424 -252.374501) (xy 380.661997 -252.415187) (xy 380.685648 -252.46025)
			(xy 380.701764 -252.508524) (xy 380.709928 -252.558758) (xy 380.71044 -252.584204) (xy 381.028968 -252.584204)
			(xy 381.032928 -252.53515) (xy 381.044705 -252.487366) (xy 381.063996 -252.44209) (xy 381.090299 -252.400494)
			(xy 381.122934 -252.363657) (xy 381.161055 -252.332532) (xy 381.203676 -252.307925) (xy 381.249692 -252.290473)
			(xy 381.297911 -252.280629) (xy 381.347086 -252.278648) (xy 381.395941 -252.28458) (xy 381.443212 -252.298272)
			(xy 381.487674 -252.31937) (xy 381.528177 -252.347326) (xy 381.56367 -252.381418) (xy 381.593235 -252.420762)
			(xy 381.616106 -252.464339) (xy 381.63169 -252.51102) (xy 381.639585 -252.559597) (xy 381.64008 -252.584204)
			(xy 381.969022 -252.584204) (xy 381.972982 -252.53515) (xy 381.984759 -252.487366) (xy 382.00405 -252.44209)
			(xy 382.030353 -252.400494) (xy 382.062988 -252.363657) (xy 382.101109 -252.332532) (xy 382.14373 -252.307925)
			(xy 382.189746 -252.290473) (xy 382.237965 -252.280629) (xy 382.28714 -252.278648) (xy 382.335995 -252.28458)
			(xy 382.383266 -252.298272) (xy 382.427728 -252.31937) (xy 382.468231 -252.347326) (xy 382.503724 -252.381418)
			(xy 382.533289 -252.420762) (xy 382.55616 -252.464339) (xy 382.571744 -252.51102) (xy 382.579639 -252.559597)
			(xy 382.580134 -252.584204) (xy 382.909076 -252.584204) (xy 382.913036 -252.53515) (xy 382.924813 -252.487366)
			(xy 382.944104 -252.44209) (xy 382.970407 -252.400494) (xy 383.003042 -252.363657) (xy 383.041163 -252.332532)
			(xy 383.083784 -252.307925) (xy 383.1298 -252.290473) (xy 383.178019 -252.280629) (xy 383.227194 -252.278648)
			(xy 383.276049 -252.28458) (xy 383.32332 -252.298272) (xy 383.367782 -252.31937) (xy 383.408285 -252.347326)
			(xy 383.443778 -252.381418) (xy 383.473343 -252.420762) (xy 383.496214 -252.464339) (xy 383.511798 -252.51102)
			(xy 383.519693 -252.559597) (xy 383.520188 -252.584204) (xy 383.84913 -252.584204) (xy 383.85309 -252.53515)
			(xy 383.864867 -252.487366) (xy 383.884158 -252.44209) (xy 383.910461 -252.400494) (xy 383.943096 -252.363657)
			(xy 383.981217 -252.332532) (xy 384.023838 -252.307925) (xy 384.069854 -252.290473) (xy 384.118073 -252.280629)
			(xy 384.167248 -252.278648) (xy 384.216103 -252.28458) (xy 384.263374 -252.298272) (xy 384.307836 -252.31937)
			(xy 384.348339 -252.347326) (xy 384.383832 -252.381418) (xy 384.413397 -252.420762) (xy 384.436268 -252.464339)
			(xy 384.451852 -252.51102) (xy 384.459747 -252.559597) (xy 384.460242 -252.584204) (xy 384.459747 -252.608811)
			(xy 384.451852 -252.657388) (xy 384.436268 -252.704069) (xy 384.413397 -252.747646) (xy 384.383832 -252.78699)
			(xy 384.348339 -252.821082) (xy 384.307836 -252.849038) (xy 384.263374 -252.870136) (xy 384.216103 -252.883828)
			(xy 384.167248 -252.88976) (xy 384.118073 -252.887779) (xy 384.069854 -252.877935) (xy 384.023838 -252.860483)
			(xy 383.981217 -252.835876) (xy 383.943096 -252.804751) (xy 383.910461 -252.767914) (xy 383.884158 -252.726318)
			(xy 383.864867 -252.681042) (xy 383.85309 -252.633258) (xy 383.84913 -252.584204) (xy 383.520188 -252.584204)
			(xy 383.519693 -252.608811) (xy 383.511798 -252.657388) (xy 383.496214 -252.704069) (xy 383.473343 -252.747646)
			(xy 383.443778 -252.78699) (xy 383.408285 -252.821082) (xy 383.367782 -252.849038) (xy 383.32332 -252.870136)
			(xy 383.276049 -252.883828) (xy 383.227194 -252.88976) (xy 383.178019 -252.887779) (xy 383.1298 -252.877935)
			(xy 383.083784 -252.860483) (xy 383.041163 -252.835876) (xy 383.003042 -252.804751) (xy 382.970407 -252.767914)
			(xy 382.944104 -252.726318) (xy 382.924813 -252.681042) (xy 382.913036 -252.633258) (xy 382.909076 -252.584204)
			(xy 382.580134 -252.584204) (xy 382.579639 -252.608811) (xy 382.571744 -252.657388) (xy 382.55616 -252.704069)
			(xy 382.533289 -252.747646) (xy 382.503724 -252.78699) (xy 382.468231 -252.821082) (xy 382.427728 -252.849038)
			(xy 382.383266 -252.870136) (xy 382.335995 -252.883828) (xy 382.28714 -252.88976) (xy 382.237965 -252.887779)
			(xy 382.189746 -252.877935) (xy 382.14373 -252.860483) (xy 382.101109 -252.835876) (xy 382.062988 -252.804751)
			(xy 382.030353 -252.767914) (xy 382.00405 -252.726318) (xy 381.984759 -252.681042) (xy 381.972982 -252.633258)
			(xy 381.969022 -252.584204) (xy 381.64008 -252.584204) (xy 381.639585 -252.608811) (xy 381.63169 -252.657388)
			(xy 381.616106 -252.704069) (xy 381.593235 -252.747646) (xy 381.56367 -252.78699) (xy 381.528177 -252.821082)
			(xy 381.487674 -252.849038) (xy 381.443212 -252.870136) (xy 381.395941 -252.883828) (xy 381.347086 -252.88976)
			(xy 381.297911 -252.887779) (xy 381.249692 -252.877935) (xy 381.203676 -252.860483) (xy 381.161055 -252.835876)
			(xy 381.122934 -252.804751) (xy 381.090299 -252.767914) (xy 381.063996 -252.726318) (xy 381.044705 -252.681042)
			(xy 381.032928 -252.633258) (xy 381.028968 -252.584204) (xy 380.71044 -252.584204) (xy 380.709928 -252.60965)
			(xy 380.701764 -252.659884) (xy 380.685648 -252.708158) (xy 380.661997 -252.753221) (xy 380.631424 -252.793907)
			(xy 380.59472 -252.829162) (xy 380.552836 -252.858072) (xy 380.506857 -252.879889) (xy 380.457973 -252.894049)
			(xy 380.407452 -252.900183) (xy 380.3566 -252.898134) (xy 380.306736 -252.887954) (xy 380.25915 -252.869907)
			(xy 380.215076 -252.844461) (xy 380.175654 -252.812274) (xy 380.141906 -252.77418) (xy 380.114705 -252.731166)
			(xy 380.094757 -252.684346) (xy 380.082578 -252.634932) (xy 380.078483 -252.584204) (xy 379.760226 -252.584204)
			(xy 379.759731 -252.608811) (xy 379.751836 -252.657388) (xy 379.736252 -252.704069) (xy 379.713381 -252.747646)
			(xy 379.683816 -252.78699) (xy 379.648323 -252.821082) (xy 379.60782 -252.849038) (xy 379.563358 -252.870136)
			(xy 379.516087 -252.883828) (xy 379.467232 -252.88976) (xy 379.418057 -252.887779) (xy 379.369838 -252.877935)
			(xy 379.323822 -252.860483) (xy 379.281201 -252.835876) (xy 379.24308 -252.804751) (xy 379.210445 -252.767914)
			(xy 379.184142 -252.726318) (xy 379.164851 -252.681042) (xy 379.153074 -252.633258) (xy 379.149114 -252.584204)
			(xy 378.820172 -252.584204) (xy 378.819677 -252.608811) (xy 378.811782 -252.657388) (xy 378.796198 -252.704069)
			(xy 378.773327 -252.747646) (xy 378.743762 -252.78699) (xy 378.708269 -252.821082) (xy 378.667766 -252.849038)
			(xy 378.623304 -252.870136) (xy 378.576033 -252.883828) (xy 378.527178 -252.88976) (xy 378.478003 -252.887779)
			(xy 378.429784 -252.877935) (xy 378.383768 -252.860483) (xy 378.341147 -252.835876) (xy 378.303026 -252.804751)
			(xy 378.270391 -252.767914) (xy 378.244088 -252.726318) (xy 378.224797 -252.681042) (xy 378.21302 -252.633258)
			(xy 378.20906 -252.584204) (xy 377.890532 -252.584204) (xy 377.89002 -252.60965) (xy 377.881856 -252.659884)
			(xy 377.86574 -252.708158) (xy 377.842089 -252.753221) (xy 377.811516 -252.793907) (xy 377.774812 -252.829162)
			(xy 377.732928 -252.858072) (xy 377.686949 -252.879889) (xy 377.638065 -252.894049) (xy 377.587544 -252.900183)
			(xy 377.536692 -252.898134) (xy 377.486828 -252.887954) (xy 377.439242 -252.869907) (xy 377.395168 -252.844461)
			(xy 377.355746 -252.812274) (xy 377.321998 -252.77418) (xy 377.294797 -252.731166) (xy 377.274849 -252.684346)
			(xy 377.26267 -252.634932) (xy 377.258575 -252.584204) (xy 376.940064 -252.584204) (xy 376.939569 -252.608811)
			(xy 376.931674 -252.657388) (xy 376.91609 -252.704069) (xy 376.893219 -252.747646) (xy 376.863654 -252.78699)
			(xy 376.828161 -252.821082) (xy 376.787658 -252.849038) (xy 376.743196 -252.870136) (xy 376.695925 -252.883828)
			(xy 376.64707 -252.88976) (xy 376.597895 -252.887779) (xy 376.549676 -252.877935) (xy 376.50366 -252.860483)
			(xy 376.461039 -252.835876) (xy 376.422918 -252.804751) (xy 376.390283 -252.767914) (xy 376.36398 -252.726318)
			(xy 376.344689 -252.681042) (xy 376.332912 -252.633258) (xy 376.328952 -252.584204) (xy 376.00001 -252.584204)
			(xy 375.999515 -252.608811) (xy 375.99162 -252.657388) (xy 375.976036 -252.704069) (xy 375.953165 -252.747646)
			(xy 375.9236 -252.78699) (xy 375.888107 -252.821082) (xy 375.847604 -252.849038) (xy 375.803142 -252.870136)
			(xy 375.755871 -252.883828) (xy 375.707016 -252.88976) (xy 375.657841 -252.887779) (xy 375.609622 -252.877935)
			(xy 375.563606 -252.860483) (xy 375.520985 -252.835876) (xy 375.482864 -252.804751) (xy 375.450229 -252.767914)
			(xy 375.423926 -252.726318) (xy 375.404635 -252.681042) (xy 375.392858 -252.633258) (xy 375.388898 -252.584204)
			(xy 375.06021 -252.584204) (xy 375.059715 -252.608811) (xy 375.05182 -252.657388) (xy 375.036236 -252.704069)
			(xy 375.013365 -252.747646) (xy 374.9838 -252.78699) (xy 374.948307 -252.821082) (xy 374.907804 -252.849038)
			(xy 374.863342 -252.870136) (xy 374.816071 -252.883828) (xy 374.767216 -252.88976) (xy 374.718041 -252.887779)
			(xy 374.669822 -252.877935) (xy 374.623806 -252.860483) (xy 374.581185 -252.835876) (xy 374.543064 -252.804751)
			(xy 374.510429 -252.767914) (xy 374.484126 -252.726318) (xy 374.464835 -252.681042) (xy 374.453058 -252.633258)
			(xy 374.449098 -252.584204) (xy 373.180102 -252.584204) (xy 373.179607 -252.608811) (xy 373.171712 -252.657388)
			(xy 373.156128 -252.704069) (xy 373.133257 -252.747646) (xy 373.103692 -252.78699) (xy 373.068199 -252.821082)
			(xy 373.027696 -252.849038) (xy 372.983234 -252.870136) (xy 372.935963 -252.883828) (xy 372.887108 -252.88976)
			(xy 372.837933 -252.887779) (xy 372.789714 -252.877935) (xy 372.743698 -252.860483) (xy 372.701077 -252.835876)
			(xy 372.662956 -252.804751) (xy 372.630321 -252.767914) (xy 372.604018 -252.726318) (xy 372.584727 -252.681042)
			(xy 372.57295 -252.633258) (xy 372.56899 -252.584204) (xy 371.299994 -252.584204) (xy 371.299499 -252.608811)
			(xy 371.291604 -252.657388) (xy 371.27602 -252.704069) (xy 371.253149 -252.747646) (xy 371.223584 -252.78699)
			(xy 371.188091 -252.821082) (xy 371.147588 -252.849038) (xy 371.103126 -252.870136) (xy 371.055855 -252.883828)
			(xy 371.007 -252.88976) (xy 370.957825 -252.887779) (xy 370.909606 -252.877935) (xy 370.86359 -252.860483)
			(xy 370.820969 -252.835876) (xy 370.782848 -252.804751) (xy 370.750213 -252.767914) (xy 370.72391 -252.726318)
			(xy 370.704619 -252.681042) (xy 370.692842 -252.633258) (xy 370.688882 -252.584204) (xy 369.42014 -252.584204)
			(xy 369.419645 -252.608811) (xy 369.41175 -252.657388) (xy 369.396166 -252.704069) (xy 369.373295 -252.747646)
			(xy 369.34373 -252.78699) (xy 369.308237 -252.821082) (xy 369.267734 -252.849038) (xy 369.223272 -252.870136)
			(xy 369.176001 -252.883828) (xy 369.127146 -252.88976) (xy 369.077971 -252.887779) (xy 369.029752 -252.877935)
			(xy 368.983736 -252.860483) (xy 368.941115 -252.835876) (xy 368.902994 -252.804751) (xy 368.870359 -252.767914)
			(xy 368.844056 -252.726318) (xy 368.824765 -252.681042) (xy 368.812988 -252.633258) (xy 368.809028 -252.584204)
			(xy 360.49716 -252.584204) (xy 360.493272 -252.592056) (xy 360.46298 -252.635122) (xy 360.426468 -252.67306)
			(xy 360.384594 -252.704979) (xy 360.338338 -252.730132) (xy 360.288785 -252.74793) (xy 360.237095 -252.757954)
			(xy 360.184481 -252.759971) (xy 360.132176 -252.753933) (xy 360.081405 -252.739981) (xy 360.03336 -252.718442)
			(xy 359.989165 -252.689822) (xy 359.949857 -252.654791) (xy 359.916357 -252.61417) (xy 359.889451 -252.568911)
			(xy 359.869768 -252.520076) (xy 359.857771 -252.468808) (xy 359.853741 -252.41631) (xy 351.177352 -252.41631)
			(xy 351.902776 -253.141734) (xy 351.906078 -253.14402) (xy 351.926031 -253.158942) (xy 351.961259 -253.194172)
			(xy 351.976182 -253.214124) (xy 351.978468 -253.217426) (xy 352.408744 -253.647448) (xy 352.409252 -253.647956)
			(xy 352.416633 -253.654538) (xy 352.434932 -253.661988) (xy 352.444812 -253.662434) (xy 353.239578 -253.662434)
			(xy 353.246436 -253.661926) (xy 353.256701 -253.659952) (xy 353.274524 -253.649067) (xy 353.28098 -253.640844)
			(xy 353.28225 -253.639066) (xy 353.33432 -253.557786) (xy 353.336098 -253.531878) (xy 353.330764 -253.520194)
			(xy 353.321881 -253.500033) (xy 353.309341 -253.457799) (xy 353.302978 -253.414205) (xy 353.30257 -253.392178)
			(xy 353.30257 -253.387352) (xy 353.303466 -253.362358) (xy 353.312394 -253.313152) (xy 353.329221 -253.266058)
			(xy 353.353497 -253.222336) (xy 353.384574 -253.183154) (xy 353.42162 -253.149559) (xy 353.463645 -253.122451)
			(xy 353.509526 -253.102553) (xy 353.558036 -253.090397) (xy 353.607878 -253.086309) (xy 353.65772 -253.090397)
			(xy 353.70623 -253.102553) (xy 353.752111 -253.122451) (xy 353.794136 -253.149559) (xy 353.831182 -253.183154)
			(xy 353.862259 -253.222336) (xy 353.886535 -253.266058) (xy 353.903362 -253.313152) (xy 353.91229 -253.362358)
			(xy 353.913186 -253.387352) (xy 353.913186 -253.3904) (xy 353.913186 -253.392178) (xy 355.182182 -253.392178)
			(xy 355.186142 -253.343124) (xy 355.197919 -253.29534) (xy 355.21721 -253.250064) (xy 355.243513 -253.208468)
			(xy 355.276148 -253.171631) (xy 355.314269 -253.140506) (xy 355.35689 -253.115899) (xy 355.402906 -253.098447)
			(xy 355.451125 -253.088603) (xy 355.5003 -253.086622) (xy 355.549155 -253.092554) (xy 355.596426 -253.106246)
			(xy 355.640888 -253.127344) (xy 355.681391 -253.1553) (xy 355.716884 -253.189392) (xy 355.746449 -253.228736)
			(xy 355.76932 -253.272313) (xy 355.784904 -253.318994) (xy 355.792799 -253.367571) (xy 355.793294 -253.392178)
			(xy 357.06229 -253.392178) (xy 357.06625 -253.343124) (xy 357.078027 -253.29534) (xy 357.097318 -253.250064)
			(xy 357.123621 -253.208468) (xy 357.156256 -253.171631) (xy 357.194377 -253.140506) (xy 357.236998 -253.115899)
			(xy 357.283014 -253.098447) (xy 357.331233 -253.088603) (xy 357.380408 -253.086622) (xy 357.429263 -253.092554)
			(xy 357.476534 -253.106246) (xy 357.520996 -253.127344) (xy 357.561499 -253.1553) (xy 357.596992 -253.189392)
			(xy 357.626557 -253.228736) (xy 357.649428 -253.272313) (xy 357.665012 -253.318994) (xy 357.672907 -253.367571)
			(xy 357.673402 -253.392178) (xy 357.672907 -253.416785) (xy 357.670384 -253.43231) (xy 359.853741 -253.43231)
			(xy 359.857771 -253.379812) (xy 359.869768 -253.328544) (xy 359.889451 -253.279709) (xy 359.916357 -253.23445)
			(xy 359.949857 -253.193829) (xy 359.989165 -253.158798) (xy 360.03336 -253.130178) (xy 360.081405 -253.108639)
			(xy 360.132176 -253.094687) (xy 360.184481 -253.088649) (xy 360.237095 -253.090666) (xy 360.288785 -253.10069)
			(xy 360.338338 -253.118488) (xy 360.384594 -253.143641) (xy 360.426468 -253.17556) (xy 360.46298 -253.213498)
			(xy 360.493272 -253.256564) (xy 360.516635 -253.303749) (xy 360.532521 -253.353948) (xy 360.538426 -253.392178)
			(xy 360.822252 -253.392178) (xy 360.826212 -253.343124) (xy 360.837989 -253.29534) (xy 360.85728 -253.250064)
			(xy 360.883583 -253.208468) (xy 360.916218 -253.171631) (xy 360.954339 -253.140506) (xy 360.99696 -253.115899)
			(xy 361.042976 -253.098447) (xy 361.091195 -253.088603) (xy 361.14037 -253.086622) (xy 361.189225 -253.092554)
			(xy 361.236496 -253.106246) (xy 361.280958 -253.127344) (xy 361.321461 -253.1553) (xy 361.356954 -253.189392)
			(xy 361.386519 -253.228736) (xy 361.40939 -253.272313) (xy 361.424974 -253.318994) (xy 361.432869 -253.367571)
			(xy 361.433364 -253.392178) (xy 362.702106 -253.392178) (xy 362.706066 -253.343124) (xy 362.717843 -253.29534)
			(xy 362.737134 -253.250064) (xy 362.763437 -253.208468) (xy 362.796072 -253.171631) (xy 362.834193 -253.140506)
			(xy 362.876814 -253.115899) (xy 362.92283 -253.098447) (xy 362.971049 -253.088603) (xy 363.020224 -253.086622)
			(xy 363.069079 -253.092554) (xy 363.11635 -253.106246) (xy 363.160812 -253.127344) (xy 363.201315 -253.1553)
			(xy 363.236808 -253.189392) (xy 363.266373 -253.228736) (xy 363.289244 -253.272313) (xy 363.304828 -253.318994)
			(xy 363.312723 -253.367571) (xy 363.313218 -253.392178) (xy 364.582214 -253.392178) (xy 364.586174 -253.343124)
			(xy 364.597951 -253.29534) (xy 364.617242 -253.250064) (xy 364.643545 -253.208468) (xy 364.67618 -253.171631)
			(xy 364.714301 -253.140506) (xy 364.756922 -253.115899) (xy 364.802938 -253.098447) (xy 364.851157 -253.088603)
			(xy 364.900332 -253.086622) (xy 364.949187 -253.092554) (xy 364.996458 -253.106246) (xy 365.04092 -253.127344)
			(xy 365.081423 -253.1553) (xy 365.116916 -253.189392) (xy 365.146481 -253.228736) (xy 365.169352 -253.272313)
			(xy 365.184936 -253.318994) (xy 365.192831 -253.367571) (xy 365.193326 -253.392178) (xy 366.462068 -253.392178)
			(xy 366.466028 -253.343124) (xy 366.477805 -253.29534) (xy 366.497096 -253.250064) (xy 366.523399 -253.208468)
			(xy 366.556034 -253.171631) (xy 366.594155 -253.140506) (xy 366.636776 -253.115899) (xy 366.682792 -253.098447)
			(xy 366.731011 -253.088603) (xy 366.780186 -253.086622) (xy 366.829041 -253.092554) (xy 366.876312 -253.106246)
			(xy 366.920774 -253.127344) (xy 366.961277 -253.1553) (xy 366.99677 -253.189392) (xy 367.026335 -253.228736)
			(xy 367.049206 -253.272313) (xy 367.06479 -253.318994) (xy 367.072685 -253.367571) (xy 367.07318 -253.392178)
			(xy 367.073139 -253.39421) (xy 370.218982 -253.39421) (xy 370.222942 -253.345156) (xy 370.234719 -253.297372)
			(xy 370.25401 -253.252096) (xy 370.280313 -253.2105) (xy 370.312948 -253.173663) (xy 370.351069 -253.142538)
			(xy 370.39369 -253.117931) (xy 370.439706 -253.100479) (xy 370.487925 -253.090635) (xy 370.5371 -253.088654)
			(xy 370.585955 -253.094586) (xy 370.633226 -253.108278) (xy 370.677688 -253.129376) (xy 370.718191 -253.157332)
			(xy 370.753684 -253.191424) (xy 370.783249 -253.230768) (xy 370.80612 -253.274345) (xy 370.821704 -253.321026)
			(xy 370.829599 -253.369603) (xy 370.830094 -253.39421) (xy 372.09909 -253.39421) (xy 372.10305 -253.345156)
			(xy 372.114827 -253.297372) (xy 372.134118 -253.252096) (xy 372.160421 -253.2105) (xy 372.193056 -253.173663)
			(xy 372.231177 -253.142538) (xy 372.273798 -253.117931) (xy 372.319814 -253.100479) (xy 372.368033 -253.090635)
			(xy 372.417208 -253.088654) (xy 372.466063 -253.094586) (xy 372.513334 -253.108278) (xy 372.557796 -253.129376)
			(xy 372.598299 -253.157332) (xy 372.633792 -253.191424) (xy 372.663357 -253.230768) (xy 372.686228 -253.274345)
			(xy 372.701812 -253.321026) (xy 372.709707 -253.369603) (xy 372.710202 -253.39421) (xy 373.978944 -253.39421)
			(xy 373.982904 -253.345156) (xy 373.994681 -253.297372) (xy 374.013972 -253.252096) (xy 374.040275 -253.2105)
			(xy 374.07291 -253.173663) (xy 374.111031 -253.142538) (xy 374.153652 -253.117931) (xy 374.199668 -253.100479)
			(xy 374.247887 -253.090635) (xy 374.297062 -253.088654) (xy 374.345917 -253.094586) (xy 374.393188 -253.108278)
			(xy 374.43765 -253.129376) (xy 374.478153 -253.157332) (xy 374.513646 -253.191424) (xy 374.543211 -253.230768)
			(xy 374.566082 -253.274345) (xy 374.581666 -253.321026) (xy 374.589561 -253.369603) (xy 374.590056 -253.39421)
			(xy 375.848621 -253.39421) (xy 375.852716 -253.343482) (xy 375.864895 -253.294068) (xy 375.884843 -253.247248)
			(xy 375.912044 -253.204234) (xy 375.945792 -253.16614) (xy 375.985214 -253.133953) (xy 376.029288 -253.108507)
			(xy 376.076874 -253.09046) (xy 376.126738 -253.08028) (xy 376.17759 -253.078231) (xy 376.228111 -253.084365)
			(xy 376.276995 -253.098525) (xy 376.322974 -253.120342) (xy 376.364858 -253.149252) (xy 376.401562 -253.184507)
			(xy 376.432135 -253.225193) (xy 376.455786 -253.270256) (xy 376.471902 -253.31853) (xy 376.480066 -253.368764)
			(xy 376.480578 -253.39421) (xy 376.788675 -253.39421) (xy 376.79277 -253.343482) (xy 376.804949 -253.294068)
			(xy 376.824897 -253.247248) (xy 376.852098 -253.204234) (xy 376.885846 -253.16614) (xy 376.925268 -253.133953)
			(xy 376.969342 -253.108507) (xy 377.016928 -253.09046) (xy 377.066792 -253.08028) (xy 377.117644 -253.078231)
			(xy 377.168165 -253.084365) (xy 377.217049 -253.098525) (xy 377.263028 -253.120342) (xy 377.304912 -253.149252)
			(xy 377.341616 -253.184507) (xy 377.372189 -253.225193) (xy 377.39584 -253.270256) (xy 377.411956 -253.31853)
			(xy 377.42012 -253.368764) (xy 377.420632 -253.39421) (xy 377.738906 -253.39421) (xy 377.742866 -253.345156)
			(xy 377.754643 -253.297372) (xy 377.773934 -253.252096) (xy 377.800237 -253.2105) (xy 377.832872 -253.173663)
			(xy 377.870993 -253.142538) (xy 377.913614 -253.117931) (xy 377.95963 -253.100479) (xy 378.007849 -253.090635)
			(xy 378.057024 -253.088654) (xy 378.105879 -253.094586) (xy 378.15315 -253.108278) (xy 378.197612 -253.129376)
			(xy 378.238115 -253.157332) (xy 378.273608 -253.191424) (xy 378.303173 -253.230768) (xy 378.326044 -253.274345)
			(xy 378.341628 -253.321026) (xy 378.349523 -253.369603) (xy 378.350018 -253.39421) (xy 378.668529 -253.39421)
			(xy 378.672624 -253.343482) (xy 378.684803 -253.294068) (xy 378.704751 -253.247248) (xy 378.731952 -253.204234)
			(xy 378.7657 -253.16614) (xy 378.805122 -253.133953) (xy 378.849196 -253.108507) (xy 378.896782 -253.09046)
			(xy 378.946646 -253.08028) (xy 378.997498 -253.078231) (xy 379.048019 -253.084365) (xy 379.096903 -253.098525)
			(xy 379.142882 -253.120342) (xy 379.184766 -253.149252) (xy 379.22147 -253.184507) (xy 379.252043 -253.225193)
			(xy 379.275694 -253.270256) (xy 379.29181 -253.31853) (xy 379.299974 -253.368764) (xy 379.300486 -253.39421)
			(xy 379.619014 -253.39421) (xy 379.622974 -253.345156) (xy 379.634751 -253.297372) (xy 379.654042 -253.252096)
			(xy 379.680345 -253.2105) (xy 379.71298 -253.173663) (xy 379.751101 -253.142538) (xy 379.793722 -253.117931)
			(xy 379.839738 -253.100479) (xy 379.887957 -253.090635) (xy 379.937132 -253.088654) (xy 379.985987 -253.094586)
			(xy 380.033258 -253.108278) (xy 380.07772 -253.129376) (xy 380.118223 -253.157332) (xy 380.153716 -253.191424)
			(xy 380.183281 -253.230768) (xy 380.206152 -253.274345) (xy 380.221736 -253.321026) (xy 380.229631 -253.369603)
			(xy 380.230126 -253.39421) (xy 380.548637 -253.39421) (xy 380.552732 -253.343482) (xy 380.564911 -253.294068)
			(xy 380.584859 -253.247248) (xy 380.61206 -253.204234) (xy 380.645808 -253.16614) (xy 380.68523 -253.133953)
			(xy 380.729304 -253.108507) (xy 380.77689 -253.09046) (xy 380.826754 -253.08028) (xy 380.877606 -253.078231)
			(xy 380.928127 -253.084365) (xy 380.977011 -253.098525) (xy 381.02299 -253.120342) (xy 381.064874 -253.149252)
			(xy 381.101578 -253.184507) (xy 381.132151 -253.225193) (xy 381.155802 -253.270256) (xy 381.171918 -253.31853)
			(xy 381.180082 -253.368764) (xy 381.180594 -253.39421) (xy 381.499122 -253.39421) (xy 381.503082 -253.345156)
			(xy 381.514859 -253.297372) (xy 381.53415 -253.252096) (xy 381.560453 -253.2105) (xy 381.593088 -253.173663)
			(xy 381.631209 -253.142538) (xy 381.67383 -253.117931) (xy 381.719846 -253.100479) (xy 381.768065 -253.090635)
			(xy 381.81724 -253.088654) (xy 381.866095 -253.094586) (xy 381.913366 -253.108278) (xy 381.957828 -253.129376)
			(xy 381.998331 -253.157332) (xy 382.033824 -253.191424) (xy 382.063389 -253.230768) (xy 382.08626 -253.274345)
			(xy 382.101844 -253.321026) (xy 382.109739 -253.369603) (xy 382.110234 -253.39421) (xy 382.438922 -253.39421)
			(xy 382.442882 -253.345156) (xy 382.454659 -253.297372) (xy 382.47395 -253.252096) (xy 382.500253 -253.2105)
			(xy 382.532888 -253.173663) (xy 382.571009 -253.142538) (xy 382.61363 -253.117931) (xy 382.659646 -253.100479)
			(xy 382.707865 -253.090635) (xy 382.75704 -253.088654) (xy 382.805895 -253.094586) (xy 382.853166 -253.108278)
			(xy 382.897628 -253.129376) (xy 382.938131 -253.157332) (xy 382.973624 -253.191424) (xy 383.003189 -253.230768)
			(xy 383.02606 -253.274345) (xy 383.041644 -253.321026) (xy 383.049539 -253.369603) (xy 383.050034 -253.39421)
			(xy 383.378976 -253.39421) (xy 383.382936 -253.345156) (xy 383.394713 -253.297372) (xy 383.414004 -253.252096)
			(xy 383.440307 -253.2105) (xy 383.472942 -253.173663) (xy 383.511063 -253.142538) (xy 383.553684 -253.117931)
			(xy 383.5997 -253.100479) (xy 383.647919 -253.090635) (xy 383.697094 -253.088654) (xy 383.745949 -253.094586)
			(xy 383.79322 -253.108278) (xy 383.837682 -253.129376) (xy 383.878185 -253.157332) (xy 383.913678 -253.191424)
			(xy 383.943243 -253.230768) (xy 383.966114 -253.274345) (xy 383.981698 -253.321026) (xy 383.989593 -253.369603)
			(xy 383.990088 -253.39421) (xy 383.989593 -253.418817) (xy 383.981698 -253.467394) (xy 383.966114 -253.514075)
			(xy 383.943243 -253.557652) (xy 383.913678 -253.596996) (xy 383.878185 -253.631088) (xy 383.837682 -253.659044)
			(xy 383.79322 -253.680142) (xy 383.745949 -253.693834) (xy 383.697094 -253.699766) (xy 383.647919 -253.697785)
			(xy 383.5997 -253.687941) (xy 383.553684 -253.670489) (xy 383.511063 -253.645882) (xy 383.472942 -253.614757)
			(xy 383.440307 -253.57792) (xy 383.414004 -253.536324) (xy 383.394713 -253.491048) (xy 383.382936 -253.443264)
			(xy 383.378976 -253.39421) (xy 383.050034 -253.39421) (xy 383.049539 -253.418817) (xy 383.041644 -253.467394)
			(xy 383.02606 -253.514075) (xy 383.003189 -253.557652) (xy 382.973624 -253.596996) (xy 382.938131 -253.631088)
			(xy 382.897628 -253.659044) (xy 382.853166 -253.680142) (xy 382.805895 -253.693834) (xy 382.75704 -253.699766)
			(xy 382.707865 -253.697785) (xy 382.659646 -253.687941) (xy 382.61363 -253.670489) (xy 382.571009 -253.645882)
			(xy 382.532888 -253.614757) (xy 382.500253 -253.57792) (xy 382.47395 -253.536324) (xy 382.454659 -253.491048)
			(xy 382.442882 -253.443264) (xy 382.438922 -253.39421) (xy 382.110234 -253.39421) (xy 382.109739 -253.418817)
			(xy 382.101844 -253.467394) (xy 382.08626 -253.514075) (xy 382.063389 -253.557652) (xy 382.033824 -253.596996)
			(xy 381.998331 -253.631088) (xy 381.957828 -253.659044) (xy 381.913366 -253.680142) (xy 381.866095 -253.693834)
			(xy 381.81724 -253.699766) (xy 381.768065 -253.697785) (xy 381.719846 -253.687941) (xy 381.67383 -253.670489)
			(xy 381.631209 -253.645882) (xy 381.593088 -253.614757) (xy 381.560453 -253.57792) (xy 381.53415 -253.536324)
			(xy 381.514859 -253.491048) (xy 381.503082 -253.443264) (xy 381.499122 -253.39421) (xy 381.180594 -253.39421)
			(xy 381.180082 -253.419656) (xy 381.171918 -253.46989) (xy 381.155802 -253.518164) (xy 381.132151 -253.563227)
			(xy 381.101578 -253.603913) (xy 381.064874 -253.639168) (xy 381.02299 -253.668078) (xy 380.977011 -253.689895)
			(xy 380.928127 -253.704055) (xy 380.877606 -253.710189) (xy 380.826754 -253.70814) (xy 380.77689 -253.69796)
			(xy 380.729304 -253.679913) (xy 380.68523 -253.654467) (xy 380.645808 -253.62228) (xy 380.61206 -253.584186)
			(xy 380.584859 -253.541172) (xy 380.564911 -253.494352) (xy 380.552732 -253.444938) (xy 380.548637 -253.39421)
			(xy 380.230126 -253.39421) (xy 380.229631 -253.418817) (xy 380.221736 -253.467394) (xy 380.206152 -253.514075)
			(xy 380.183281 -253.557652) (xy 380.153716 -253.596996) (xy 380.118223 -253.631088) (xy 380.07772 -253.659044)
			(xy 380.033258 -253.680142) (xy 379.985987 -253.693834) (xy 379.937132 -253.699766) (xy 379.887957 -253.697785)
			(xy 379.839738 -253.687941) (xy 379.793722 -253.670489) (xy 379.751101 -253.645882) (xy 379.71298 -253.614757)
			(xy 379.680345 -253.57792) (xy 379.654042 -253.536324) (xy 379.634751 -253.491048) (xy 379.622974 -253.443264)
			(xy 379.619014 -253.39421) (xy 379.300486 -253.39421) (xy 379.299974 -253.419656) (xy 379.29181 -253.46989)
			(xy 379.275694 -253.518164) (xy 379.252043 -253.563227) (xy 379.22147 -253.603913) (xy 379.184766 -253.639168)
			(xy 379.142882 -253.668078) (xy 379.096903 -253.689895) (xy 379.048019 -253.704055) (xy 378.997498 -253.710189)
			(xy 378.946646 -253.70814) (xy 378.896782 -253.69796) (xy 378.849196 -253.679913) (xy 378.805122 -253.654467)
			(xy 378.7657 -253.62228) (xy 378.731952 -253.584186) (xy 378.704751 -253.541172) (xy 378.684803 -253.494352)
			(xy 378.672624 -253.444938) (xy 378.668529 -253.39421) (xy 378.350018 -253.39421) (xy 378.349523 -253.418817)
			(xy 378.341628 -253.467394) (xy 378.326044 -253.514075) (xy 378.303173 -253.557652) (xy 378.273608 -253.596996)
			(xy 378.238115 -253.631088) (xy 378.197612 -253.659044) (xy 378.15315 -253.680142) (xy 378.105879 -253.693834)
			(xy 378.057024 -253.699766) (xy 378.007849 -253.697785) (xy 377.95963 -253.687941) (xy 377.913614 -253.670489)
			(xy 377.870993 -253.645882) (xy 377.832872 -253.614757) (xy 377.800237 -253.57792) (xy 377.773934 -253.536324)
			(xy 377.754643 -253.491048) (xy 377.742866 -253.443264) (xy 377.738906 -253.39421) (xy 377.420632 -253.39421)
			(xy 377.42012 -253.419656) (xy 377.411956 -253.46989) (xy 377.39584 -253.518164) (xy 377.372189 -253.563227)
			(xy 377.341616 -253.603913) (xy 377.304912 -253.639168) (xy 377.263028 -253.668078) (xy 377.217049 -253.689895)
			(xy 377.168165 -253.704055) (xy 377.117644 -253.710189) (xy 377.066792 -253.70814) (xy 377.016928 -253.69796)
			(xy 376.969342 -253.679913) (xy 376.925268 -253.654467) (xy 376.885846 -253.62228) (xy 376.852098 -253.584186)
			(xy 376.824897 -253.541172) (xy 376.804949 -253.494352) (xy 376.79277 -253.444938) (xy 376.788675 -253.39421)
			(xy 376.480578 -253.39421) (xy 376.480066 -253.419656) (xy 376.471902 -253.46989) (xy 376.455786 -253.518164)
			(xy 376.432135 -253.563227) (xy 376.401562 -253.603913) (xy 376.364858 -253.639168) (xy 376.322974 -253.668078)
			(xy 376.276995 -253.689895) (xy 376.228111 -253.704055) (xy 376.17759 -253.710189) (xy 376.126738 -253.70814)
			(xy 376.076874 -253.69796) (xy 376.029288 -253.679913) (xy 375.985214 -253.654467) (xy 375.945792 -253.62228)
			(xy 375.912044 -253.584186) (xy 375.884843 -253.541172) (xy 375.864895 -253.494352) (xy 375.852716 -253.444938)
			(xy 375.848621 -253.39421) (xy 374.590056 -253.39421) (xy 374.589561 -253.418817) (xy 374.581666 -253.467394)
			(xy 374.566082 -253.514075) (xy 374.543211 -253.557652) (xy 374.513646 -253.596996) (xy 374.478153 -253.631088)
			(xy 374.43765 -253.659044) (xy 374.393188 -253.680142) (xy 374.345917 -253.693834) (xy 374.297062 -253.699766)
			(xy 374.247887 -253.697785) (xy 374.199668 -253.687941) (xy 374.153652 -253.670489) (xy 374.111031 -253.645882)
			(xy 374.07291 -253.614757) (xy 374.040275 -253.57792) (xy 374.013972 -253.536324) (xy 373.994681 -253.491048)
			(xy 373.982904 -253.443264) (xy 373.978944 -253.39421) (xy 372.710202 -253.39421) (xy 372.709707 -253.418817)
			(xy 372.701812 -253.467394) (xy 372.686228 -253.514075) (xy 372.663357 -253.557652) (xy 372.633792 -253.596996)
			(xy 372.598299 -253.631088) (xy 372.557796 -253.659044) (xy 372.513334 -253.680142) (xy 372.466063 -253.693834)
			(xy 372.417208 -253.699766) (xy 372.368033 -253.697785) (xy 372.319814 -253.687941) (xy 372.273798 -253.670489)
			(xy 372.231177 -253.645882) (xy 372.193056 -253.614757) (xy 372.160421 -253.57792) (xy 372.134118 -253.536324)
			(xy 372.114827 -253.491048) (xy 372.10305 -253.443264) (xy 372.09909 -253.39421) (xy 370.830094 -253.39421)
			(xy 370.829599 -253.418817) (xy 370.821704 -253.467394) (xy 370.80612 -253.514075) (xy 370.783249 -253.557652)
			(xy 370.753684 -253.596996) (xy 370.718191 -253.631088) (xy 370.677688 -253.659044) (xy 370.633226 -253.680142)
			(xy 370.585955 -253.693834) (xy 370.5371 -253.699766) (xy 370.487925 -253.697785) (xy 370.439706 -253.687941)
			(xy 370.39369 -253.670489) (xy 370.351069 -253.645882) (xy 370.312948 -253.614757) (xy 370.280313 -253.57792)
			(xy 370.25401 -253.536324) (xy 370.234719 -253.491048) (xy 370.222942 -253.443264) (xy 370.218982 -253.39421)
			(xy 367.073139 -253.39421) (xy 367.072685 -253.416785) (xy 367.06479 -253.465362) (xy 367.049206 -253.512043)
			(xy 367.026335 -253.55562) (xy 366.99677 -253.594964) (xy 366.961277 -253.629056) (xy 366.920774 -253.657012)
			(xy 366.876312 -253.67811) (xy 366.829041 -253.691802) (xy 366.780186 -253.697734) (xy 366.731011 -253.695753)
			(xy 366.682792 -253.685909) (xy 366.636776 -253.668457) (xy 366.594155 -253.64385) (xy 366.556034 -253.612725)
			(xy 366.523399 -253.575888) (xy 366.497096 -253.534292) (xy 366.477805 -253.489016) (xy 366.466028 -253.441232)
			(xy 366.462068 -253.392178) (xy 365.193326 -253.392178) (xy 365.192831 -253.416785) (xy 365.184936 -253.465362)
			(xy 365.169352 -253.512043) (xy 365.146481 -253.55562) (xy 365.116916 -253.594964) (xy 365.081423 -253.629056)
			(xy 365.04092 -253.657012) (xy 364.996458 -253.67811) (xy 364.949187 -253.691802) (xy 364.900332 -253.697734)
			(xy 364.851157 -253.695753) (xy 364.802938 -253.685909) (xy 364.756922 -253.668457) (xy 364.714301 -253.64385)
			(xy 364.67618 -253.612725) (xy 364.643545 -253.575888) (xy 364.617242 -253.534292) (xy 364.597951 -253.489016)
			(xy 364.586174 -253.441232) (xy 364.582214 -253.392178) (xy 363.313218 -253.392178) (xy 363.312723 -253.416785)
			(xy 363.304828 -253.465362) (xy 363.289244 -253.512043) (xy 363.266373 -253.55562) (xy 363.236808 -253.594964)
			(xy 363.201315 -253.629056) (xy 363.160812 -253.657012) (xy 363.11635 -253.67811) (xy 363.069079 -253.691802)
			(xy 363.020224 -253.697734) (xy 362.971049 -253.695753) (xy 362.92283 -253.685909) (xy 362.876814 -253.668457)
			(xy 362.834193 -253.64385) (xy 362.796072 -253.612725) (xy 362.763437 -253.575888) (xy 362.737134 -253.534292)
			(xy 362.717843 -253.489016) (xy 362.706066 -253.441232) (xy 362.702106 -253.392178) (xy 361.433364 -253.392178)
			(xy 361.432869 -253.416785) (xy 361.424974 -253.465362) (xy 361.40939 -253.512043) (xy 361.386519 -253.55562)
			(xy 361.356954 -253.594964) (xy 361.321461 -253.629056) (xy 361.280958 -253.657012) (xy 361.236496 -253.67811)
			(xy 361.189225 -253.691802) (xy 361.14037 -253.697734) (xy 361.091195 -253.695753) (xy 361.042976 -253.685909)
			(xy 360.99696 -253.668457) (xy 360.954339 -253.64385) (xy 360.916218 -253.612725) (xy 360.883583 -253.575888)
			(xy 360.85728 -253.534292) (xy 360.837989 -253.489016) (xy 360.826212 -253.441232) (xy 360.822252 -253.392178)
			(xy 360.538426 -253.392178) (xy 360.540558 -253.405984) (xy 360.541062 -253.43231) (xy 360.540558 -253.458636)
			(xy 360.532521 -253.510672) (xy 360.516635 -253.560871) (xy 360.493272 -253.608056) (xy 360.46298 -253.651122)
			(xy 360.426468 -253.68906) (xy 360.384594 -253.720979) (xy 360.338338 -253.746132) (xy 360.288785 -253.76393)
			(xy 360.237095 -253.773954) (xy 360.184481 -253.775971) (xy 360.132176 -253.769933) (xy 360.081405 -253.755981)
			(xy 360.03336 -253.734442) (xy 359.989165 -253.705822) (xy 359.949857 -253.670791) (xy 359.916357 -253.63017)
			(xy 359.889451 -253.584911) (xy 359.869768 -253.536076) (xy 359.857771 -253.484808) (xy 359.853741 -253.43231)
			(xy 357.670384 -253.43231) (xy 357.665012 -253.465362) (xy 357.649428 -253.512043) (xy 357.626557 -253.55562)
			(xy 357.596992 -253.594964) (xy 357.561499 -253.629056) (xy 357.520996 -253.657012) (xy 357.476534 -253.67811)
			(xy 357.429263 -253.691802) (xy 357.380408 -253.697734) (xy 357.331233 -253.695753) (xy 357.283014 -253.685909)
			(xy 357.236998 -253.668457) (xy 357.194377 -253.64385) (xy 357.156256 -253.612725) (xy 357.123621 -253.575888)
			(xy 357.097318 -253.534292) (xy 357.078027 -253.489016) (xy 357.06625 -253.441232) (xy 357.06229 -253.392178)
			(xy 355.793294 -253.392178) (xy 355.792799 -253.416785) (xy 355.784904 -253.465362) (xy 355.76932 -253.512043)
			(xy 355.746449 -253.55562) (xy 355.716884 -253.594964) (xy 355.681391 -253.629056) (xy 355.640888 -253.657012)
			(xy 355.596426 -253.67811) (xy 355.549155 -253.691802) (xy 355.5003 -253.697734) (xy 355.451125 -253.695753)
			(xy 355.402906 -253.685909) (xy 355.35689 -253.668457) (xy 355.314269 -253.64385) (xy 355.276148 -253.612725)
			(xy 355.243513 -253.575888) (xy 355.21721 -253.534292) (xy 355.197919 -253.489016) (xy 355.186142 -253.441232)
			(xy 355.182182 -253.392178) (xy 353.913186 -253.392178) (xy 353.912804 -253.414208) (xy 353.906465 -253.45781)
			(xy 353.893901 -253.500042) (xy 353.884992 -253.520194) (xy 353.879658 -253.531878) (xy 353.881436 -253.557786)
			(xy 353.933506 -253.639066) (xy 353.934776 -253.640844) (xy 353.941186 -253.649118) (xy 353.95903 -253.660014)
			(xy 353.96932 -253.661926) (xy 353.976178 -253.662434) (xy 354.285804 -253.662434) (xy 354.295648 -253.662956)
			(xy 354.313833 -253.670519) (xy 354.32111 -253.677166) (xy 355.092254 -254.44831) (xy 359.853741 -254.44831)
			(xy 359.857771 -254.395812) (xy 359.869768 -254.344544) (xy 359.889451 -254.295709) (xy 359.916357 -254.25045)
			(xy 359.949857 -254.209829) (xy 359.989165 -254.174798) (xy 360.03336 -254.146178) (xy 360.081405 -254.124639)
			(xy 360.132176 -254.110687) (xy 360.184481 -254.104649) (xy 360.237095 -254.106666) (xy 360.288785 -254.11669)
			(xy 360.338338 -254.134488) (xy 360.384594 -254.159641) (xy 360.426468 -254.19156) (xy 360.438648 -254.204216)
			(xy 368.809028 -254.204216) (xy 368.812988 -254.155162) (xy 368.824765 -254.107378) (xy 368.844056 -254.062102)
			(xy 368.870359 -254.020506) (xy 368.902994 -253.983669) (xy 368.941115 -253.952544) (xy 368.983736 -253.927937)
			(xy 369.029752 -253.910485) (xy 369.077971 -253.900641) (xy 369.127146 -253.89866) (xy 369.176001 -253.904592)
			(xy 369.223272 -253.918284) (xy 369.267734 -253.939382) (xy 369.308237 -253.967338) (xy 369.34373 -254.00143)
			(xy 369.373295 -254.040774) (xy 369.396166 -254.084351) (xy 369.41175 -254.131032) (xy 369.419645 -254.179609)
			(xy 369.42014 -254.204216) (xy 370.688882 -254.204216) (xy 370.692842 -254.155162) (xy 370.704619 -254.107378)
			(xy 370.72391 -254.062102) (xy 370.750213 -254.020506) (xy 370.782848 -253.983669) (xy 370.820969 -253.952544)
			(xy 370.86359 -253.927937) (xy 370.909606 -253.910485) (xy 370.957825 -253.900641) (xy 371.007 -253.89866)
			(xy 371.055855 -253.904592) (xy 371.103126 -253.918284) (xy 371.147588 -253.939382) (xy 371.188091 -253.967338)
			(xy 371.223584 -254.00143) (xy 371.253149 -254.040774) (xy 371.27602 -254.084351) (xy 371.291604 -254.131032)
			(xy 371.299499 -254.179609) (xy 371.299994 -254.204216) (xy 372.56899 -254.204216) (xy 372.57295 -254.155162)
			(xy 372.584727 -254.107378) (xy 372.604018 -254.062102) (xy 372.630321 -254.020506) (xy 372.662956 -253.983669)
			(xy 372.701077 -253.952544) (xy 372.743698 -253.927937) (xy 372.789714 -253.910485) (xy 372.837933 -253.900641)
			(xy 372.887108 -253.89866) (xy 372.935963 -253.904592) (xy 372.983234 -253.918284) (xy 373.027696 -253.939382)
			(xy 373.068199 -253.967338) (xy 373.103692 -254.00143) (xy 373.133257 -254.040774) (xy 373.156128 -254.084351)
			(xy 373.171712 -254.131032) (xy 373.179607 -254.179609) (xy 373.180102 -254.204216) (xy 374.449098 -254.204216)
			(xy 374.453058 -254.155162) (xy 374.464835 -254.107378) (xy 374.484126 -254.062102) (xy 374.510429 -254.020506)
			(xy 374.543064 -253.983669) (xy 374.581185 -253.952544) (xy 374.623806 -253.927937) (xy 374.669822 -253.910485)
			(xy 374.718041 -253.900641) (xy 374.767216 -253.89866) (xy 374.816071 -253.904592) (xy 374.863342 -253.918284)
			(xy 374.907804 -253.939382) (xy 374.948307 -253.967338) (xy 374.9838 -254.00143) (xy 375.013365 -254.040774)
			(xy 375.036236 -254.084351) (xy 375.05182 -254.131032) (xy 375.059715 -254.179609) (xy 375.06021 -254.204216)
			(xy 375.378467 -254.204216) (xy 375.382562 -254.153488) (xy 375.394741 -254.104074) (xy 375.414689 -254.057254)
			(xy 375.44189 -254.01424) (xy 375.475638 -253.976146) (xy 375.51506 -253.943959) (xy 375.559134 -253.918513)
			(xy 375.60672 -253.900466) (xy 375.656584 -253.890286) (xy 375.707436 -253.888237) (xy 375.757957 -253.894371)
			(xy 375.806841 -253.908531) (xy 375.85282 -253.930348) (xy 375.894704 -253.959258) (xy 375.931408 -253.994513)
			(xy 375.961981 -254.035199) (xy 375.985632 -254.080262) (xy 376.001748 -254.128536) (xy 376.009912 -254.17877)
			(xy 376.010424 -254.204216) (xy 376.328952 -254.204216) (xy 376.332912 -254.155162) (xy 376.344689 -254.107378)
			(xy 376.36398 -254.062102) (xy 376.390283 -254.020506) (xy 376.422918 -253.983669) (xy 376.461039 -253.952544)
			(xy 376.50366 -253.927937) (xy 376.549676 -253.910485) (xy 376.597895 -253.900641) (xy 376.64707 -253.89866)
			(xy 376.695925 -253.904592) (xy 376.743196 -253.918284) (xy 376.787658 -253.939382) (xy 376.828161 -253.967338)
			(xy 376.863654 -254.00143) (xy 376.893219 -254.040774) (xy 376.91609 -254.084351) (xy 376.931674 -254.131032)
			(xy 376.939569 -254.179609) (xy 376.940064 -254.204216) (xy 377.258575 -254.204216) (xy 377.26267 -254.153488)
			(xy 377.274849 -254.104074) (xy 377.294797 -254.057254) (xy 377.321998 -254.01424) (xy 377.355746 -253.976146)
			(xy 377.395168 -253.943959) (xy 377.439242 -253.918513) (xy 377.486828 -253.900466) (xy 377.536692 -253.890286)
			(xy 377.587544 -253.888237) (xy 377.638065 -253.894371) (xy 377.686949 -253.908531) (xy 377.732928 -253.930348)
			(xy 377.774812 -253.959258) (xy 377.811516 -253.994513) (xy 377.842089 -254.035199) (xy 377.86574 -254.080262)
			(xy 377.881856 -254.128536) (xy 377.89002 -254.17877) (xy 377.890532 -254.204216) (xy 379.138683 -254.204216)
			(xy 379.142778 -254.153488) (xy 379.154957 -254.104074) (xy 379.174905 -254.057254) (xy 379.202106 -254.01424)
			(xy 379.235854 -253.976146) (xy 379.275276 -253.943959) (xy 379.31935 -253.918513) (xy 379.366936 -253.900466)
			(xy 379.4168 -253.890286) (xy 379.467652 -253.888237) (xy 379.518173 -253.894371) (xy 379.567057 -253.908531)
			(xy 379.613036 -253.930348) (xy 379.65492 -253.959258) (xy 379.691624 -253.994513) (xy 379.722197 -254.035199)
			(xy 379.745848 -254.080262) (xy 379.761964 -254.128536) (xy 379.770128 -254.17877) (xy 379.77064 -254.204216)
			(xy 380.078483 -254.204216) (xy 380.082578 -254.153488) (xy 380.094757 -254.104074) (xy 380.114705 -254.057254)
			(xy 380.141906 -254.01424) (xy 380.175654 -253.976146) (xy 380.215076 -253.943959) (xy 380.25915 -253.918513)
			(xy 380.306736 -253.900466) (xy 380.3566 -253.890286) (xy 380.407452 -253.888237) (xy 380.457973 -253.894371)
			(xy 380.506857 -253.908531) (xy 380.552836 -253.930348) (xy 380.59472 -253.959258) (xy 380.631424 -253.994513)
			(xy 380.661997 -254.035199) (xy 380.685648 -254.080262) (xy 380.701764 -254.128536) (xy 380.709928 -254.17877)
			(xy 380.71044 -254.204216) (xy 381.028968 -254.204216) (xy 381.032928 -254.155162) (xy 381.044705 -254.107378)
			(xy 381.063996 -254.062102) (xy 381.090299 -254.020506) (xy 381.122934 -253.983669) (xy 381.161055 -253.952544)
			(xy 381.203676 -253.927937) (xy 381.249692 -253.910485) (xy 381.297911 -253.900641) (xy 381.347086 -253.89866)
			(xy 381.395941 -253.904592) (xy 381.443212 -253.918284) (xy 381.487674 -253.939382) (xy 381.528177 -253.967338)
			(xy 381.56367 -254.00143) (xy 381.593235 -254.040774) (xy 381.616106 -254.084351) (xy 381.63169 -254.131032)
			(xy 381.639585 -254.179609) (xy 381.64008 -254.204216) (xy 381.969022 -254.204216) (xy 381.972982 -254.155162)
			(xy 381.984759 -254.107378) (xy 382.00405 -254.062102) (xy 382.030353 -254.020506) (xy 382.062988 -253.983669)
			(xy 382.101109 -253.952544) (xy 382.14373 -253.927937) (xy 382.189746 -253.910485) (xy 382.237965 -253.900641)
			(xy 382.28714 -253.89866) (xy 382.335995 -253.904592) (xy 382.383266 -253.918284) (xy 382.427728 -253.939382)
			(xy 382.468231 -253.967338) (xy 382.503724 -254.00143) (xy 382.533289 -254.040774) (xy 382.55616 -254.084351)
			(xy 382.571744 -254.131032) (xy 382.579639 -254.179609) (xy 382.580134 -254.204216) (xy 382.909076 -254.204216)
			(xy 382.913036 -254.155162) (xy 382.924813 -254.107378) (xy 382.944104 -254.062102) (xy 382.970407 -254.020506)
			(xy 383.003042 -253.983669) (xy 383.041163 -253.952544) (xy 383.083784 -253.927937) (xy 383.1298 -253.910485)
			(xy 383.178019 -253.900641) (xy 383.227194 -253.89866) (xy 383.276049 -253.904592) (xy 383.32332 -253.918284)
			(xy 383.367782 -253.939382) (xy 383.408285 -253.967338) (xy 383.443778 -254.00143) (xy 383.473343 -254.040774)
			(xy 383.496214 -254.084351) (xy 383.511798 -254.131032) (xy 383.519693 -254.179609) (xy 383.520188 -254.204216)
			(xy 383.84913 -254.204216) (xy 383.85309 -254.155162) (xy 383.864867 -254.107378) (xy 383.884158 -254.062102)
			(xy 383.910461 -254.020506) (xy 383.943096 -253.983669) (xy 383.981217 -253.952544) (xy 384.023838 -253.927937)
			(xy 384.069854 -253.910485) (xy 384.118073 -253.900641) (xy 384.167248 -253.89866) (xy 384.216103 -253.904592)
			(xy 384.263374 -253.918284) (xy 384.307836 -253.939382) (xy 384.348339 -253.967338) (xy 384.383832 -254.00143)
			(xy 384.413397 -254.040774) (xy 384.436268 -254.084351) (xy 384.451852 -254.131032) (xy 384.459747 -254.179609)
			(xy 384.460242 -254.204216) (xy 384.459747 -254.228823) (xy 384.451852 -254.2774) (xy 384.436268 -254.324081)
			(xy 384.413397 -254.367658) (xy 384.383832 -254.407002) (xy 384.348339 -254.441094) (xy 384.307836 -254.46905)
			(xy 384.263374 -254.490148) (xy 384.216103 -254.50384) (xy 384.167248 -254.509772) (xy 384.118073 -254.507791)
			(xy 384.069854 -254.497947) (xy 384.023838 -254.480495) (xy 383.981217 -254.455888) (xy 383.943096 -254.424763)
			(xy 383.910461 -254.387926) (xy 383.884158 -254.34633) (xy 383.864867 -254.301054) (xy 383.85309 -254.25327)
			(xy 383.84913 -254.204216) (xy 383.520188 -254.204216) (xy 383.519693 -254.228823) (xy 383.511798 -254.2774)
			(xy 383.496214 -254.324081) (xy 383.473343 -254.367658) (xy 383.443778 -254.407002) (xy 383.408285 -254.441094)
			(xy 383.367782 -254.46905) (xy 383.32332 -254.490148) (xy 383.276049 -254.50384) (xy 383.227194 -254.509772)
			(xy 383.178019 -254.507791) (xy 383.1298 -254.497947) (xy 383.083784 -254.480495) (xy 383.041163 -254.455888)
			(xy 383.003042 -254.424763) (xy 382.970407 -254.387926) (xy 382.944104 -254.34633) (xy 382.924813 -254.301054)
			(xy 382.913036 -254.25327) (xy 382.909076 -254.204216) (xy 382.580134 -254.204216) (xy 382.579639 -254.228823)
			(xy 382.571744 -254.2774) (xy 382.55616 -254.324081) (xy 382.533289 -254.367658) (xy 382.503724 -254.407002)
			(xy 382.468231 -254.441094) (xy 382.427728 -254.46905) (xy 382.383266 -254.490148) (xy 382.335995 -254.50384)
			(xy 382.28714 -254.509772) (xy 382.237965 -254.507791) (xy 382.189746 -254.497947) (xy 382.14373 -254.480495)
			(xy 382.101109 -254.455888) (xy 382.062988 -254.424763) (xy 382.030353 -254.387926) (xy 382.00405 -254.34633)
			(xy 381.984759 -254.301054) (xy 381.972982 -254.25327) (xy 381.969022 -254.204216) (xy 381.64008 -254.204216)
			(xy 381.639585 -254.228823) (xy 381.63169 -254.2774) (xy 381.616106 -254.324081) (xy 381.593235 -254.367658)
			(xy 381.56367 -254.407002) (xy 381.528177 -254.441094) (xy 381.487674 -254.46905) (xy 381.443212 -254.490148)
			(xy 381.395941 -254.50384) (xy 381.347086 -254.509772) (xy 381.297911 -254.507791) (xy 381.249692 -254.497947)
			(xy 381.203676 -254.480495) (xy 381.161055 -254.455888) (xy 381.122934 -254.424763) (xy 381.090299 -254.387926)
			(xy 381.063996 -254.34633) (xy 381.044705 -254.301054) (xy 381.032928 -254.25327) (xy 381.028968 -254.204216)
			(xy 380.71044 -254.204216) (xy 380.709928 -254.229662) (xy 380.701764 -254.279896) (xy 380.685648 -254.32817)
			(xy 380.661997 -254.373233) (xy 380.631424 -254.413919) (xy 380.59472 -254.449174) (xy 380.552836 -254.478084)
			(xy 380.506857 -254.499901) (xy 380.457973 -254.514061) (xy 380.407452 -254.520195) (xy 380.3566 -254.518146)
			(xy 380.306736 -254.507966) (xy 380.25915 -254.489919) (xy 380.215076 -254.464473) (xy 380.175654 -254.432286)
			(xy 380.141906 -254.394192) (xy 380.114705 -254.351178) (xy 380.094757 -254.304358) (xy 380.082578 -254.254944)
			(xy 380.078483 -254.204216) (xy 379.77064 -254.204216) (xy 379.770128 -254.229662) (xy 379.761964 -254.279896)
			(xy 379.745848 -254.32817) (xy 379.722197 -254.373233) (xy 379.691624 -254.413919) (xy 379.65492 -254.449174)
			(xy 379.613036 -254.478084) (xy 379.567057 -254.499901) (xy 379.518173 -254.514061) (xy 379.467652 -254.520195)
			(xy 379.4168 -254.518146) (xy 379.366936 -254.507966) (xy 379.31935 -254.489919) (xy 379.275276 -254.464473)
			(xy 379.235854 -254.432286) (xy 379.202106 -254.394192) (xy 379.174905 -254.351178) (xy 379.154957 -254.304358)
			(xy 379.142778 -254.254944) (xy 379.138683 -254.204216) (xy 377.890532 -254.204216) (xy 377.89002 -254.229662)
			(xy 377.881856 -254.279896) (xy 377.86574 -254.32817) (xy 377.842089 -254.373233) (xy 377.811516 -254.413919)
			(xy 377.774812 -254.449174) (xy 377.732928 -254.478084) (xy 377.686949 -254.499901) (xy 377.638065 -254.514061)
			(xy 377.587544 -254.520195) (xy 377.536692 -254.518146) (xy 377.486828 -254.507966) (xy 377.439242 -254.489919)
			(xy 377.395168 -254.464473) (xy 377.355746 -254.432286) (xy 377.321998 -254.394192) (xy 377.294797 -254.351178)
			(xy 377.274849 -254.304358) (xy 377.26267 -254.254944) (xy 377.258575 -254.204216) (xy 376.940064 -254.204216)
			(xy 376.939569 -254.228823) (xy 376.931674 -254.2774) (xy 376.91609 -254.324081) (xy 376.893219 -254.367658)
			(xy 376.863654 -254.407002) (xy 376.828161 -254.441094) (xy 376.787658 -254.46905) (xy 376.743196 -254.490148)
			(xy 376.695925 -254.50384) (xy 376.64707 -254.509772) (xy 376.597895 -254.507791) (xy 376.549676 -254.497947)
			(xy 376.50366 -254.480495) (xy 376.461039 -254.455888) (xy 376.422918 -254.424763) (xy 376.390283 -254.387926)
			(xy 376.36398 -254.34633) (xy 376.344689 -254.301054) (xy 376.332912 -254.25327) (xy 376.328952 -254.204216)
			(xy 376.010424 -254.204216) (xy 376.009912 -254.229662) (xy 376.001748 -254.279896) (xy 375.985632 -254.32817)
			(xy 375.961981 -254.373233) (xy 375.931408 -254.413919) (xy 375.894704 -254.449174) (xy 375.85282 -254.478084)
			(xy 375.806841 -254.499901) (xy 375.757957 -254.514061) (xy 375.707436 -254.520195) (xy 375.656584 -254.518146)
			(xy 375.60672 -254.507966) (xy 375.559134 -254.489919) (xy 375.51506 -254.464473) (xy 375.475638 -254.432286)
			(xy 375.44189 -254.394192) (xy 375.414689 -254.351178) (xy 375.394741 -254.304358) (xy 375.382562 -254.254944)
			(xy 375.378467 -254.204216) (xy 375.06021 -254.204216) (xy 375.059715 -254.228823) (xy 375.05182 -254.2774)
			(xy 375.036236 -254.324081) (xy 375.013365 -254.367658) (xy 374.9838 -254.407002) (xy 374.948307 -254.441094)
			(xy 374.907804 -254.46905) (xy 374.863342 -254.490148) (xy 374.816071 -254.50384) (xy 374.767216 -254.509772)
			(xy 374.718041 -254.507791) (xy 374.669822 -254.497947) (xy 374.623806 -254.480495) (xy 374.581185 -254.455888)
			(xy 374.543064 -254.424763) (xy 374.510429 -254.387926) (xy 374.484126 -254.34633) (xy 374.464835 -254.301054)
			(xy 374.453058 -254.25327) (xy 374.449098 -254.204216) (xy 373.180102 -254.204216) (xy 373.179607 -254.228823)
			(xy 373.171712 -254.2774) (xy 373.156128 -254.324081) (xy 373.133257 -254.367658) (xy 373.103692 -254.407002)
			(xy 373.068199 -254.441094) (xy 373.027696 -254.46905) (xy 372.983234 -254.490148) (xy 372.935963 -254.50384)
			(xy 372.887108 -254.509772) (xy 372.837933 -254.507791) (xy 372.789714 -254.497947) (xy 372.743698 -254.480495)
			(xy 372.701077 -254.455888) (xy 372.662956 -254.424763) (xy 372.630321 -254.387926) (xy 372.604018 -254.34633)
			(xy 372.584727 -254.301054) (xy 372.57295 -254.25327) (xy 372.56899 -254.204216) (xy 371.299994 -254.204216)
			(xy 371.299499 -254.228823) (xy 371.291604 -254.2774) (xy 371.27602 -254.324081) (xy 371.253149 -254.367658)
			(xy 371.223584 -254.407002) (xy 371.188091 -254.441094) (xy 371.147588 -254.46905) (xy 371.103126 -254.490148)
			(xy 371.055855 -254.50384) (xy 371.007 -254.509772) (xy 370.957825 -254.507791) (xy 370.909606 -254.497947)
			(xy 370.86359 -254.480495) (xy 370.820969 -254.455888) (xy 370.782848 -254.424763) (xy 370.750213 -254.387926)
			(xy 370.72391 -254.34633) (xy 370.704619 -254.301054) (xy 370.692842 -254.25327) (xy 370.688882 -254.204216)
			(xy 369.42014 -254.204216) (xy 369.419645 -254.228823) (xy 369.41175 -254.2774) (xy 369.396166 -254.324081)
			(xy 369.373295 -254.367658) (xy 369.34373 -254.407002) (xy 369.308237 -254.441094) (xy 369.267734 -254.46905)
			(xy 369.223272 -254.490148) (xy 369.176001 -254.50384) (xy 369.127146 -254.509772) (xy 369.077971 -254.507791)
			(xy 369.029752 -254.497947) (xy 368.983736 -254.480495) (xy 368.941115 -254.455888) (xy 368.902994 -254.424763)
			(xy 368.870359 -254.387926) (xy 368.844056 -254.34633) (xy 368.824765 -254.301054) (xy 368.812988 -254.25327)
			(xy 368.809028 -254.204216) (xy 360.438648 -254.204216) (xy 360.46298 -254.229498) (xy 360.493272 -254.272564)
			(xy 360.516635 -254.319749) (xy 360.532521 -254.369948) (xy 360.540558 -254.421984) (xy 360.541062 -254.44831)
			(xy 360.540558 -254.474636) (xy 360.532521 -254.526672) (xy 360.516635 -254.576871) (xy 360.493272 -254.624056)
			(xy 360.46298 -254.667122) (xy 360.426468 -254.70506) (xy 360.384594 -254.736979) (xy 360.338338 -254.762132)
			(xy 360.288785 -254.77993) (xy 360.237095 -254.789954) (xy 360.184481 -254.791971) (xy 360.132176 -254.785933)
			(xy 360.081405 -254.771981) (xy 360.03336 -254.750442) (xy 359.989165 -254.721822) (xy 359.949857 -254.686791)
			(xy 359.916357 -254.64617) (xy 359.889451 -254.600911) (xy 359.869768 -254.552076) (xy 359.857771 -254.500808)
			(xy 359.853741 -254.44831) (xy 355.092254 -254.44831) (xy 355.356922 -254.712978) (xy 355.363639 -254.720215)
			(xy 355.371244 -254.738419) (xy 355.371654 -254.748284) (xy 355.371654 -255.014222) (xy 370.218982 -255.014222)
			(xy 370.222942 -254.965168) (xy 370.234719 -254.917384) (xy 370.25401 -254.872108) (xy 370.280313 -254.830512)
			(xy 370.312948 -254.793675) (xy 370.351069 -254.76255) (xy 370.39369 -254.737943) (xy 370.439706 -254.720491)
			(xy 370.487925 -254.710647) (xy 370.5371 -254.708666) (xy 370.585955 -254.714598) (xy 370.633226 -254.72829)
			(xy 370.677688 -254.749388) (xy 370.718191 -254.777344) (xy 370.753684 -254.811436) (xy 370.783249 -254.85078)
			(xy 370.80612 -254.894357) (xy 370.821704 -254.941038) (xy 370.829599 -254.989615) (xy 370.830094 -255.014222)
			(xy 372.09909 -255.014222) (xy 372.10305 -254.965168) (xy 372.114827 -254.917384) (xy 372.134118 -254.872108)
			(xy 372.160421 -254.830512) (xy 372.193056 -254.793675) (xy 372.231177 -254.76255) (xy 372.273798 -254.737943)
			(xy 372.319814 -254.720491) (xy 372.368033 -254.710647) (xy 372.417208 -254.708666) (xy 372.466063 -254.714598)
			(xy 372.513334 -254.72829) (xy 372.557796 -254.749388) (xy 372.598299 -254.777344) (xy 372.633792 -254.811436)
			(xy 372.663357 -254.85078) (xy 372.686228 -254.894357) (xy 372.701812 -254.941038) (xy 372.709707 -254.989615)
			(xy 372.710202 -255.014222) (xy 373.978944 -255.014222) (xy 373.982904 -254.965168) (xy 373.994681 -254.917384)
			(xy 374.013972 -254.872108) (xy 374.040275 -254.830512) (xy 374.07291 -254.793675) (xy 374.111031 -254.76255)
			(xy 374.153652 -254.737943) (xy 374.199668 -254.720491) (xy 374.247887 -254.710647) (xy 374.297062 -254.708666)
			(xy 374.345917 -254.714598) (xy 374.393188 -254.72829) (xy 374.43765 -254.749388) (xy 374.478153 -254.777344)
			(xy 374.513646 -254.811436) (xy 374.543211 -254.85078) (xy 374.566082 -254.894357) (xy 374.581666 -254.941038)
			(xy 374.589561 -254.989615) (xy 374.590056 -255.014222) (xy 375.848621 -255.014222) (xy 375.852716 -254.963494)
			(xy 375.864895 -254.91408) (xy 375.884843 -254.86726) (xy 375.912044 -254.824246) (xy 375.945792 -254.786152)
			(xy 375.985214 -254.753965) (xy 376.029288 -254.728519) (xy 376.076874 -254.710472) (xy 376.126738 -254.700292)
			(xy 376.17759 -254.698243) (xy 376.228111 -254.704377) (xy 376.276995 -254.718537) (xy 376.322974 -254.740354)
			(xy 376.364858 -254.769264) (xy 376.401562 -254.804519) (xy 376.432135 -254.845205) (xy 376.455786 -254.890268)
			(xy 376.471902 -254.938542) (xy 376.480066 -254.988776) (xy 376.480578 -255.014222) (xy 376.788675 -255.014222)
			(xy 376.79277 -254.963494) (xy 376.804949 -254.91408) (xy 376.824897 -254.86726) (xy 376.852098 -254.824246)
			(xy 376.885846 -254.786152) (xy 376.925268 -254.753965) (xy 376.969342 -254.728519) (xy 377.016928 -254.710472)
			(xy 377.066792 -254.700292) (xy 377.117644 -254.698243) (xy 377.168165 -254.704377) (xy 377.217049 -254.718537)
			(xy 377.263028 -254.740354) (xy 377.304912 -254.769264) (xy 377.341616 -254.804519) (xy 377.372189 -254.845205)
			(xy 377.39584 -254.890268) (xy 377.411956 -254.938542) (xy 377.42012 -254.988776) (xy 377.420632 -255.014222)
			(xy 377.738906 -255.014222) (xy 377.742866 -254.965168) (xy 377.754643 -254.917384) (xy 377.773934 -254.872108)
			(xy 377.800237 -254.830512) (xy 377.832872 -254.793675) (xy 377.870993 -254.76255) (xy 377.913614 -254.737943)
			(xy 377.95963 -254.720491) (xy 378.007849 -254.710647) (xy 378.057024 -254.708666) (xy 378.105879 -254.714598)
			(xy 378.15315 -254.72829) (xy 378.197612 -254.749388) (xy 378.238115 -254.777344) (xy 378.273608 -254.811436)
			(xy 378.303173 -254.85078) (xy 378.326044 -254.894357) (xy 378.341628 -254.941038) (xy 378.349523 -254.989615)
			(xy 378.350018 -255.014222) (xy 378.668529 -255.014222) (xy 378.672624 -254.963494) (xy 378.684803 -254.91408)
			(xy 378.704751 -254.86726) (xy 378.731952 -254.824246) (xy 378.7657 -254.786152) (xy 378.805122 -254.753965)
			(xy 378.849196 -254.728519) (xy 378.896782 -254.710472) (xy 378.946646 -254.700292) (xy 378.997498 -254.698243)
			(xy 379.048019 -254.704377) (xy 379.096903 -254.718537) (xy 379.142882 -254.740354) (xy 379.184766 -254.769264)
			(xy 379.22147 -254.804519) (xy 379.252043 -254.845205) (xy 379.275694 -254.890268) (xy 379.29181 -254.938542)
			(xy 379.299974 -254.988776) (xy 379.300486 -255.014222) (xy 379.619014 -255.014222) (xy 379.622974 -254.965168)
			(xy 379.634751 -254.917384) (xy 379.654042 -254.872108) (xy 379.680345 -254.830512) (xy 379.71298 -254.793675)
			(xy 379.751101 -254.76255) (xy 379.793722 -254.737943) (xy 379.839738 -254.720491) (xy 379.887957 -254.710647)
			(xy 379.937132 -254.708666) (xy 379.985987 -254.714598) (xy 380.033258 -254.72829) (xy 380.07772 -254.749388)
			(xy 380.118223 -254.777344) (xy 380.153716 -254.811436) (xy 380.183281 -254.85078) (xy 380.206152 -254.894357)
			(xy 380.221736 -254.941038) (xy 380.229631 -254.989615) (xy 380.230126 -255.014222) (xy 380.548637 -255.014222)
			(xy 380.552732 -254.963494) (xy 380.564911 -254.91408) (xy 380.584859 -254.86726) (xy 380.61206 -254.824246)
			(xy 380.645808 -254.786152) (xy 380.68523 -254.753965) (xy 380.729304 -254.728519) (xy 380.77689 -254.710472)
			(xy 380.826754 -254.700292) (xy 380.877606 -254.698243) (xy 380.928127 -254.704377) (xy 380.977011 -254.718537)
			(xy 381.02299 -254.740354) (xy 381.064874 -254.769264) (xy 381.101578 -254.804519) (xy 381.132151 -254.845205)
			(xy 381.155802 -254.890268) (xy 381.171918 -254.938542) (xy 381.180082 -254.988776) (xy 381.180594 -255.014222)
			(xy 381.499122 -255.014222) (xy 381.503082 -254.965168) (xy 381.514859 -254.917384) (xy 381.53415 -254.872108)
			(xy 381.560453 -254.830512) (xy 381.593088 -254.793675) (xy 381.631209 -254.76255) (xy 381.67383 -254.737943)
			(xy 381.719846 -254.720491) (xy 381.768065 -254.710647) (xy 381.81724 -254.708666) (xy 381.866095 -254.714598)
			(xy 381.913366 -254.72829) (xy 381.957828 -254.749388) (xy 381.998331 -254.777344) (xy 382.033824 -254.811436)
			(xy 382.063389 -254.85078) (xy 382.08626 -254.894357) (xy 382.101844 -254.941038) (xy 382.109739 -254.989615)
			(xy 382.110234 -255.014222) (xy 382.438922 -255.014222) (xy 382.442882 -254.965168) (xy 382.454659 -254.917384)
			(xy 382.47395 -254.872108) (xy 382.500253 -254.830512) (xy 382.532888 -254.793675) (xy 382.571009 -254.76255)
			(xy 382.61363 -254.737943) (xy 382.659646 -254.720491) (xy 382.707865 -254.710647) (xy 382.75704 -254.708666)
			(xy 382.805895 -254.714598) (xy 382.853166 -254.72829) (xy 382.897628 -254.749388) (xy 382.938131 -254.777344)
			(xy 382.973624 -254.811436) (xy 383.003189 -254.85078) (xy 383.02606 -254.894357) (xy 383.041644 -254.941038)
			(xy 383.049539 -254.989615) (xy 383.050034 -255.014222) (xy 383.378976 -255.014222) (xy 383.382936 -254.965168)
			(xy 383.394713 -254.917384) (xy 383.414004 -254.872108) (xy 383.440307 -254.830512) (xy 383.472942 -254.793675)
			(xy 383.511063 -254.76255) (xy 383.553684 -254.737943) (xy 383.5997 -254.720491) (xy 383.647919 -254.710647)
			(xy 383.697094 -254.708666) (xy 383.745949 -254.714598) (xy 383.79322 -254.72829) (xy 383.837682 -254.749388)
			(xy 383.878185 -254.777344) (xy 383.913678 -254.811436) (xy 383.943243 -254.85078) (xy 383.966114 -254.894357)
			(xy 383.981698 -254.941038) (xy 383.989593 -254.989615) (xy 383.990088 -255.014222) (xy 383.989593 -255.038829)
			(xy 383.981698 -255.087406) (xy 383.966114 -255.134087) (xy 383.943243 -255.177664) (xy 383.913678 -255.217008)
			(xy 383.878185 -255.2511) (xy 383.837682 -255.279056) (xy 383.79322 -255.300154) (xy 383.745949 -255.313846)
			(xy 383.697094 -255.319778) (xy 383.647919 -255.317797) (xy 383.5997 -255.307953) (xy 383.553684 -255.290501)
			(xy 383.511063 -255.265894) (xy 383.472942 -255.234769) (xy 383.440307 -255.197932) (xy 383.414004 -255.156336)
			(xy 383.394713 -255.11106) (xy 383.382936 -255.063276) (xy 383.378976 -255.014222) (xy 383.050034 -255.014222)
			(xy 383.049539 -255.038829) (xy 383.041644 -255.087406) (xy 383.02606 -255.134087) (xy 383.003189 -255.177664)
			(xy 382.973624 -255.217008) (xy 382.938131 -255.2511) (xy 382.897628 -255.279056) (xy 382.853166 -255.300154)
			(xy 382.805895 -255.313846) (xy 382.75704 -255.319778) (xy 382.707865 -255.317797) (xy 382.659646 -255.307953)
			(xy 382.61363 -255.290501) (xy 382.571009 -255.265894) (xy 382.532888 -255.234769) (xy 382.500253 -255.197932)
			(xy 382.47395 -255.156336) (xy 382.454659 -255.11106) (xy 382.442882 -255.063276) (xy 382.438922 -255.014222)
			(xy 382.110234 -255.014222) (xy 382.109739 -255.038829) (xy 382.101844 -255.087406) (xy 382.08626 -255.134087)
			(xy 382.063389 -255.177664) (xy 382.033824 -255.217008) (xy 381.998331 -255.2511) (xy 381.957828 -255.279056)
			(xy 381.913366 -255.300154) (xy 381.866095 -255.313846) (xy 381.81724 -255.319778) (xy 381.768065 -255.317797)
			(xy 381.719846 -255.307953) (xy 381.67383 -255.290501) (xy 381.631209 -255.265894) (xy 381.593088 -255.234769)
			(xy 381.560453 -255.197932) (xy 381.53415 -255.156336) (xy 381.514859 -255.11106) (xy 381.503082 -255.063276)
			(xy 381.499122 -255.014222) (xy 381.180594 -255.014222) (xy 381.180082 -255.039668) (xy 381.171918 -255.089902)
			(xy 381.155802 -255.138176) (xy 381.132151 -255.183239) (xy 381.101578 -255.223925) (xy 381.064874 -255.25918)
			(xy 381.02299 -255.28809) (xy 380.977011 -255.309907) (xy 380.928127 -255.324067) (xy 380.877606 -255.330201)
			(xy 380.826754 -255.328152) (xy 380.77689 -255.317972) (xy 380.729304 -255.299925) (xy 380.68523 -255.274479)
			(xy 380.645808 -255.242292) (xy 380.61206 -255.204198) (xy 380.584859 -255.161184) (xy 380.564911 -255.114364)
			(xy 380.552732 -255.06495) (xy 380.548637 -255.014222) (xy 380.230126 -255.014222) (xy 380.229631 -255.038829)
			(xy 380.221736 -255.087406) (xy 380.206152 -255.134087) (xy 380.183281 -255.177664) (xy 380.153716 -255.217008)
			(xy 380.118223 -255.2511) (xy 380.07772 -255.279056) (xy 380.033258 -255.300154) (xy 379.985987 -255.313846)
			(xy 379.937132 -255.319778) (xy 379.887957 -255.317797) (xy 379.839738 -255.307953) (xy 379.793722 -255.290501)
			(xy 379.751101 -255.265894) (xy 379.71298 -255.234769) (xy 379.680345 -255.197932) (xy 379.654042 -255.156336)
			(xy 379.634751 -255.11106) (xy 379.622974 -255.063276) (xy 379.619014 -255.014222) (xy 379.300486 -255.014222)
			(xy 379.299974 -255.039668) (xy 379.29181 -255.089902) (xy 379.275694 -255.138176) (xy 379.252043 -255.183239)
			(xy 379.22147 -255.223925) (xy 379.184766 -255.25918) (xy 379.142882 -255.28809) (xy 379.096903 -255.309907)
			(xy 379.048019 -255.324067) (xy 378.997498 -255.330201) (xy 378.946646 -255.328152) (xy 378.896782 -255.317972)
			(xy 378.849196 -255.299925) (xy 378.805122 -255.274479) (xy 378.7657 -255.242292) (xy 378.731952 -255.204198)
			(xy 378.704751 -255.161184) (xy 378.684803 -255.114364) (xy 378.672624 -255.06495) (xy 378.668529 -255.014222)
			(xy 378.350018 -255.014222) (xy 378.349523 -255.038829) (xy 378.341628 -255.087406) (xy 378.326044 -255.134087)
			(xy 378.303173 -255.177664) (xy 378.273608 -255.217008) (xy 378.238115 -255.2511) (xy 378.197612 -255.279056)
			(xy 378.15315 -255.300154) (xy 378.105879 -255.313846) (xy 378.057024 -255.319778) (xy 378.007849 -255.317797)
			(xy 377.95963 -255.307953) (xy 377.913614 -255.290501) (xy 377.870993 -255.265894) (xy 377.832872 -255.234769)
			(xy 377.800237 -255.197932) (xy 377.773934 -255.156336) (xy 377.754643 -255.11106) (xy 377.742866 -255.063276)
			(xy 377.738906 -255.014222) (xy 377.420632 -255.014222) (xy 377.42012 -255.039668) (xy 377.411956 -255.089902)
			(xy 377.39584 -255.138176) (xy 377.372189 -255.183239) (xy 377.341616 -255.223925) (xy 377.304912 -255.25918)
			(xy 377.263028 -255.28809) (xy 377.217049 -255.309907) (xy 377.168165 -255.324067) (xy 377.117644 -255.330201)
			(xy 377.066792 -255.328152) (xy 377.016928 -255.317972) (xy 376.969342 -255.299925) (xy 376.925268 -255.274479)
			(xy 376.885846 -255.242292) (xy 376.852098 -255.204198) (xy 376.824897 -255.161184) (xy 376.804949 -255.114364)
			(xy 376.79277 -255.06495) (xy 376.788675 -255.014222) (xy 376.480578 -255.014222) (xy 376.480066 -255.039668)
			(xy 376.471902 -255.089902) (xy 376.455786 -255.138176) (xy 376.432135 -255.183239) (xy 376.401562 -255.223925)
			(xy 376.364858 -255.25918) (xy 376.322974 -255.28809) (xy 376.276995 -255.309907) (xy 376.228111 -255.324067)
			(xy 376.17759 -255.330201) (xy 376.126738 -255.328152) (xy 376.076874 -255.317972) (xy 376.029288 -255.299925)
			(xy 375.985214 -255.274479) (xy 375.945792 -255.242292) (xy 375.912044 -255.204198) (xy 375.884843 -255.161184)
			(xy 375.864895 -255.114364) (xy 375.852716 -255.06495) (xy 375.848621 -255.014222) (xy 374.590056 -255.014222)
			(xy 374.589561 -255.038829) (xy 374.581666 -255.087406) (xy 374.566082 -255.134087) (xy 374.543211 -255.177664)
			(xy 374.513646 -255.217008) (xy 374.478153 -255.2511) (xy 374.43765 -255.279056) (xy 374.393188 -255.300154)
			(xy 374.345917 -255.313846) (xy 374.297062 -255.319778) (xy 374.247887 -255.317797) (xy 374.199668 -255.307953)
			(xy 374.153652 -255.290501) (xy 374.111031 -255.265894) (xy 374.07291 -255.234769) (xy 374.040275 -255.197932)
			(xy 374.013972 -255.156336) (xy 373.994681 -255.11106) (xy 373.982904 -255.063276) (xy 373.978944 -255.014222)
			(xy 372.710202 -255.014222) (xy 372.709707 -255.038829) (xy 372.701812 -255.087406) (xy 372.686228 -255.134087)
			(xy 372.663357 -255.177664) (xy 372.633792 -255.217008) (xy 372.598299 -255.2511) (xy 372.557796 -255.279056)
			(xy 372.513334 -255.300154) (xy 372.466063 -255.313846) (xy 372.417208 -255.319778) (xy 372.368033 -255.317797)
			(xy 372.319814 -255.307953) (xy 372.273798 -255.290501) (xy 372.231177 -255.265894) (xy 372.193056 -255.234769)
			(xy 372.160421 -255.197932) (xy 372.134118 -255.156336) (xy 372.114827 -255.11106) (xy 372.10305 -255.063276)
			(xy 372.09909 -255.014222) (xy 370.830094 -255.014222) (xy 370.829599 -255.038829) (xy 370.821704 -255.087406)
			(xy 370.80612 -255.134087) (xy 370.783249 -255.177664) (xy 370.753684 -255.217008) (xy 370.718191 -255.2511)
			(xy 370.677688 -255.279056) (xy 370.633226 -255.300154) (xy 370.585955 -255.313846) (xy 370.5371 -255.319778)
			(xy 370.487925 -255.317797) (xy 370.439706 -255.307953) (xy 370.39369 -255.290501) (xy 370.351069 -255.265894)
			(xy 370.312948 -255.234769) (xy 370.280313 -255.197932) (xy 370.25401 -255.156336) (xy 370.234719 -255.11106)
			(xy 370.222942 -255.063276) (xy 370.218982 -255.014222) (xy 355.371654 -255.014222) (xy 355.371654 -255.468628)
			(xy 355.372115 -255.478505) (xy 355.379555 -255.496805) (xy 355.386132 -255.504188) (xy 355.386386 -255.504442)
			(xy 355.41204 -255.530096) (xy 365.036865 -255.530096) (xy 365.040895 -255.477598) (xy 365.052892 -255.42633)
			(xy 365.072575 -255.377495) (xy 365.099481 -255.332236) (xy 365.132981 -255.291615) (xy 365.172289 -255.256584)
			(xy 365.216484 -255.227964) (xy 365.264529 -255.206425) (xy 365.3153 -255.192473) (xy 365.367605 -255.186435)
			(xy 365.420219 -255.188452) (xy 365.471909 -255.198476) (xy 365.521462 -255.216274) (xy 365.567718 -255.241427)
			(xy 365.609592 -255.273346) (xy 365.646104 -255.311284) (xy 365.676396 -255.35435) (xy 365.699759 -255.401535)
			(xy 365.715645 -255.451734) (xy 365.723682 -255.50377) (xy 365.724186 -255.530096) (xy 365.723682 -255.556422)
			(xy 365.715645 -255.608458) (xy 365.699759 -255.658657) (xy 365.676396 -255.705842) (xy 365.646104 -255.748908)
			(xy 365.609592 -255.786846) (xy 365.567718 -255.818765) (xy 365.557672 -255.824228) (xy 368.809028 -255.824228)
			(xy 368.812988 -255.775174) (xy 368.824765 -255.72739) (xy 368.844056 -255.682114) (xy 368.870359 -255.640518)
			(xy 368.902994 -255.603681) (xy 368.941115 -255.572556) (xy 368.983736 -255.547949) (xy 369.029752 -255.530497)
			(xy 369.077971 -255.520653) (xy 369.127146 -255.518672) (xy 369.176001 -255.524604) (xy 369.223272 -255.538296)
			(xy 369.267734 -255.559394) (xy 369.308237 -255.58735) (xy 369.34373 -255.621442) (xy 369.373295 -255.660786)
			(xy 369.396166 -255.704363) (xy 369.41175 -255.751044) (xy 369.419645 -255.799621) (xy 369.42014 -255.824228)
			(xy 370.688882 -255.824228) (xy 370.692842 -255.775174) (xy 370.704619 -255.72739) (xy 370.72391 -255.682114)
			(xy 370.750213 -255.640518) (xy 370.782848 -255.603681) (xy 370.820969 -255.572556) (xy 370.86359 -255.547949)
			(xy 370.909606 -255.530497) (xy 370.957825 -255.520653) (xy 371.007 -255.518672) (xy 371.055855 -255.524604)
			(xy 371.103126 -255.538296) (xy 371.147588 -255.559394) (xy 371.188091 -255.58735) (xy 371.223584 -255.621442)
			(xy 371.253149 -255.660786) (xy 371.27602 -255.704363) (xy 371.291604 -255.751044) (xy 371.299499 -255.799621)
			(xy 371.299994 -255.824228) (xy 372.56899 -255.824228) (xy 372.57295 -255.775174) (xy 372.584727 -255.72739)
			(xy 372.604018 -255.682114) (xy 372.630321 -255.640518) (xy 372.662956 -255.603681) (xy 372.701077 -255.572556)
			(xy 372.743698 -255.547949) (xy 372.789714 -255.530497) (xy 372.837933 -255.520653) (xy 372.887108 -255.518672)
			(xy 372.935963 -255.524604) (xy 372.983234 -255.538296) (xy 373.027696 -255.559394) (xy 373.068199 -255.58735)
			(xy 373.103692 -255.621442) (xy 373.133257 -255.660786) (xy 373.156128 -255.704363) (xy 373.171712 -255.751044)
			(xy 373.179607 -255.799621) (xy 373.180102 -255.824228) (xy 374.449098 -255.824228) (xy 374.453058 -255.775174)
			(xy 374.464835 -255.72739) (xy 374.484126 -255.682114) (xy 374.510429 -255.640518) (xy 374.543064 -255.603681)
			(xy 374.581185 -255.572556) (xy 374.623806 -255.547949) (xy 374.669822 -255.530497) (xy 374.718041 -255.520653)
			(xy 374.767216 -255.518672) (xy 374.816071 -255.524604) (xy 374.863342 -255.538296) (xy 374.907804 -255.559394)
			(xy 374.948307 -255.58735) (xy 374.9838 -255.621442) (xy 375.013365 -255.660786) (xy 375.036236 -255.704363)
			(xy 375.05182 -255.751044) (xy 375.059715 -255.799621) (xy 375.06021 -255.824228) (xy 375.378467 -255.824228)
			(xy 375.382562 -255.7735) (xy 375.394741 -255.724086) (xy 375.414689 -255.677266) (xy 375.44189 -255.634252)
			(xy 375.475638 -255.596158) (xy 375.51506 -255.563971) (xy 375.559134 -255.538525) (xy 375.60672 -255.520478)
			(xy 375.656584 -255.510298) (xy 375.707436 -255.508249) (xy 375.757957 -255.514383) (xy 375.806841 -255.528543)
			(xy 375.85282 -255.55036) (xy 375.894704 -255.57927) (xy 375.931408 -255.614525) (xy 375.961981 -255.655211)
			(xy 375.985632 -255.700274) (xy 376.001748 -255.748548) (xy 376.009912 -255.798782) (xy 376.010424 -255.824228)
			(xy 376.328952 -255.824228) (xy 376.332912 -255.775174) (xy 376.344689 -255.72739) (xy 376.36398 -255.682114)
			(xy 376.390283 -255.640518) (xy 376.422918 -255.603681) (xy 376.461039 -255.572556) (xy 376.50366 -255.547949)
			(xy 376.549676 -255.530497) (xy 376.597895 -255.520653) (xy 376.64707 -255.518672) (xy 376.695925 -255.524604)
			(xy 376.743196 -255.538296) (xy 376.787658 -255.559394) (xy 376.828161 -255.58735) (xy 376.863654 -255.621442)
			(xy 376.893219 -255.660786) (xy 376.91609 -255.704363) (xy 376.931674 -255.751044) (xy 376.939569 -255.799621)
			(xy 376.940064 -255.824228) (xy 377.258575 -255.824228) (xy 377.26267 -255.7735) (xy 377.274849 -255.724086)
			(xy 377.294797 -255.677266) (xy 377.321998 -255.634252) (xy 377.355746 -255.596158) (xy 377.395168 -255.563971)
			(xy 377.439242 -255.538525) (xy 377.486828 -255.520478) (xy 377.536692 -255.510298) (xy 377.587544 -255.508249)
			(xy 377.638065 -255.514383) (xy 377.686949 -255.528543) (xy 377.732928 -255.55036) (xy 377.774812 -255.57927)
			(xy 377.811516 -255.614525) (xy 377.842089 -255.655211) (xy 377.86574 -255.700274) (xy 377.881856 -255.748548)
			(xy 377.89002 -255.798782) (xy 377.890532 -255.824228) (xy 378.20906 -255.824228) (xy 378.21302 -255.775174)
			(xy 378.224797 -255.72739) (xy 378.244088 -255.682114) (xy 378.270391 -255.640518) (xy 378.303026 -255.603681)
			(xy 378.341147 -255.572556) (xy 378.383768 -255.547949) (xy 378.429784 -255.530497) (xy 378.478003 -255.520653)
			(xy 378.527178 -255.518672) (xy 378.576033 -255.524604) (xy 378.623304 -255.538296) (xy 378.667766 -255.559394)
			(xy 378.708269 -255.58735) (xy 378.743762 -255.621442) (xy 378.773327 -255.660786) (xy 378.796198 -255.704363)
			(xy 378.811782 -255.751044) (xy 378.819677 -255.799621) (xy 378.820172 -255.824228) (xy 379.138683 -255.824228)
			(xy 379.142778 -255.7735) (xy 379.154957 -255.724086) (xy 379.174905 -255.677266) (xy 379.202106 -255.634252)
			(xy 379.235854 -255.596158) (xy 379.275276 -255.563971) (xy 379.31935 -255.538525) (xy 379.366936 -255.520478)
			(xy 379.4168 -255.510298) (xy 379.467652 -255.508249) (xy 379.518173 -255.514383) (xy 379.567057 -255.528543)
			(xy 379.613036 -255.55036) (xy 379.65492 -255.57927) (xy 379.691624 -255.614525) (xy 379.722197 -255.655211)
			(xy 379.745848 -255.700274) (xy 379.761964 -255.748548) (xy 379.770128 -255.798782) (xy 379.77064 -255.824228)
			(xy 380.078483 -255.824228) (xy 380.082578 -255.7735) (xy 380.094757 -255.724086) (xy 380.114705 -255.677266)
			(xy 380.141906 -255.634252) (xy 380.175654 -255.596158) (xy 380.215076 -255.563971) (xy 380.25915 -255.538525)
			(xy 380.306736 -255.520478) (xy 380.3566 -255.510298) (xy 380.407452 -255.508249) (xy 380.457973 -255.514383)
			(xy 380.506857 -255.528543) (xy 380.552836 -255.55036) (xy 380.59472 -255.57927) (xy 380.631424 -255.614525)
			(xy 380.661997 -255.655211) (xy 380.685648 -255.700274) (xy 380.701764 -255.748548) (xy 380.709928 -255.798782)
			(xy 380.71044 -255.824228) (xy 381.028968 -255.824228) (xy 381.032928 -255.775174) (xy 381.044705 -255.72739)
			(xy 381.063996 -255.682114) (xy 381.090299 -255.640518) (xy 381.122934 -255.603681) (xy 381.161055 -255.572556)
			(xy 381.203676 -255.547949) (xy 381.249692 -255.530497) (xy 381.297911 -255.520653) (xy 381.347086 -255.518672)
			(xy 381.395941 -255.524604) (xy 381.443212 -255.538296) (xy 381.487674 -255.559394) (xy 381.528177 -255.58735)
			(xy 381.56367 -255.621442) (xy 381.593235 -255.660786) (xy 381.616106 -255.704363) (xy 381.63169 -255.751044)
			(xy 381.639585 -255.799621) (xy 381.64008 -255.824228) (xy 381.969022 -255.824228) (xy 381.972982 -255.775174)
			(xy 381.984759 -255.72739) (xy 382.00405 -255.682114) (xy 382.030353 -255.640518) (xy 382.062988 -255.603681)
			(xy 382.101109 -255.572556) (xy 382.14373 -255.547949) (xy 382.189746 -255.530497) (xy 382.237965 -255.520653)
			(xy 382.28714 -255.518672) (xy 382.335995 -255.524604) (xy 382.383266 -255.538296) (xy 382.427728 -255.559394)
			(xy 382.468231 -255.58735) (xy 382.503724 -255.621442) (xy 382.533289 -255.660786) (xy 382.55616 -255.704363)
			(xy 382.571744 -255.751044) (xy 382.579639 -255.799621) (xy 382.580134 -255.824228) (xy 382.909076 -255.824228)
			(xy 382.913036 -255.775174) (xy 382.924813 -255.72739) (xy 382.944104 -255.682114) (xy 382.970407 -255.640518)
			(xy 383.003042 -255.603681) (xy 383.041163 -255.572556) (xy 383.083784 -255.547949) (xy 383.1298 -255.530497)
			(xy 383.178019 -255.520653) (xy 383.227194 -255.518672) (xy 383.276049 -255.524604) (xy 383.32332 -255.538296)
			(xy 383.367782 -255.559394) (xy 383.408285 -255.58735) (xy 383.443778 -255.621442) (xy 383.473343 -255.660786)
			(xy 383.496214 -255.704363) (xy 383.511798 -255.751044) (xy 383.519693 -255.799621) (xy 383.520188 -255.824228)
			(xy 383.84913 -255.824228) (xy 383.85309 -255.775174) (xy 383.864867 -255.72739) (xy 383.884158 -255.682114)
			(xy 383.910461 -255.640518) (xy 383.943096 -255.603681) (xy 383.981217 -255.572556) (xy 384.023838 -255.547949)
			(xy 384.069854 -255.530497) (xy 384.118073 -255.520653) (xy 384.167248 -255.518672) (xy 384.216103 -255.524604)
			(xy 384.263374 -255.538296) (xy 384.307836 -255.559394) (xy 384.348339 -255.58735) (xy 384.383832 -255.621442)
			(xy 384.413397 -255.660786) (xy 384.436268 -255.704363) (xy 384.451852 -255.751044) (xy 384.459747 -255.799621)
			(xy 384.460242 -255.824228) (xy 384.459747 -255.848835) (xy 384.451852 -255.897412) (xy 384.436268 -255.944093)
			(xy 384.413397 -255.98767) (xy 384.383832 -256.027014) (xy 384.348339 -256.061106) (xy 384.307836 -256.089062)
			(xy 384.263374 -256.11016) (xy 384.216103 -256.123852) (xy 384.167248 -256.129784) (xy 384.118073 -256.127803)
			(xy 384.069854 -256.117959) (xy 384.023838 -256.100507) (xy 383.981217 -256.0759) (xy 383.943096 -256.044775)
			(xy 383.910461 -256.007938) (xy 383.884158 -255.966342) (xy 383.864867 -255.921066) (xy 383.85309 -255.873282)
			(xy 383.84913 -255.824228) (xy 383.520188 -255.824228) (xy 383.519693 -255.848835) (xy 383.511798 -255.897412)
			(xy 383.496214 -255.944093) (xy 383.473343 -255.98767) (xy 383.443778 -256.027014) (xy 383.408285 -256.061106)
			(xy 383.367782 -256.089062) (xy 383.32332 -256.11016) (xy 383.276049 -256.123852) (xy 383.227194 -256.129784)
			(xy 383.178019 -256.127803) (xy 383.1298 -256.117959) (xy 383.083784 -256.100507) (xy 383.041163 -256.0759)
			(xy 383.003042 -256.044775) (xy 382.970407 -256.007938) (xy 382.944104 -255.966342) (xy 382.924813 -255.921066)
			(xy 382.913036 -255.873282) (xy 382.909076 -255.824228) (xy 382.580134 -255.824228) (xy 382.579639 -255.848835)
			(xy 382.571744 -255.897412) (xy 382.55616 -255.944093) (xy 382.533289 -255.98767) (xy 382.503724 -256.027014)
			(xy 382.468231 -256.061106) (xy 382.427728 -256.089062) (xy 382.383266 -256.11016) (xy 382.335995 -256.123852)
			(xy 382.28714 -256.129784) (xy 382.237965 -256.127803) (xy 382.189746 -256.117959) (xy 382.14373 -256.100507)
			(xy 382.101109 -256.0759) (xy 382.062988 -256.044775) (xy 382.030353 -256.007938) (xy 382.00405 -255.966342)
			(xy 381.984759 -255.921066) (xy 381.972982 -255.873282) (xy 381.969022 -255.824228) (xy 381.64008 -255.824228)
			(xy 381.639585 -255.848835) (xy 381.63169 -255.897412) (xy 381.616106 -255.944093) (xy 381.593235 -255.98767)
			(xy 381.56367 -256.027014) (xy 381.528177 -256.061106) (xy 381.487674 -256.089062) (xy 381.443212 -256.11016)
			(xy 381.395941 -256.123852) (xy 381.347086 -256.129784) (xy 381.297911 -256.127803) (xy 381.249692 -256.117959)
			(xy 381.203676 -256.100507) (xy 381.161055 -256.0759) (xy 381.122934 -256.044775) (xy 381.090299 -256.007938)
			(xy 381.063996 -255.966342) (xy 381.044705 -255.921066) (xy 381.032928 -255.873282) (xy 381.028968 -255.824228)
			(xy 380.71044 -255.824228) (xy 380.709928 -255.849674) (xy 380.701764 -255.899908) (xy 380.685648 -255.948182)
			(xy 380.661997 -255.993245) (xy 380.631424 -256.033931) (xy 380.59472 -256.069186) (xy 380.552836 -256.098096)
			(xy 380.506857 -256.119913) (xy 380.457973 -256.134073) (xy 380.407452 -256.140207) (xy 380.3566 -256.138158)
			(xy 380.306736 -256.127978) (xy 380.25915 -256.109931) (xy 380.215076 -256.084485) (xy 380.175654 -256.052298)
			(xy 380.141906 -256.014204) (xy 380.114705 -255.97119) (xy 380.094757 -255.92437) (xy 380.082578 -255.874956)
			(xy 380.078483 -255.824228) (xy 379.77064 -255.824228) (xy 379.770128 -255.849674) (xy 379.761964 -255.899908)
			(xy 379.745848 -255.948182) (xy 379.722197 -255.993245) (xy 379.691624 -256.033931) (xy 379.65492 -256.069186)
			(xy 379.613036 -256.098096) (xy 379.567057 -256.119913) (xy 379.518173 -256.134073) (xy 379.467652 -256.140207)
			(xy 379.4168 -256.138158) (xy 379.366936 -256.127978) (xy 379.31935 -256.109931) (xy 379.275276 -256.084485)
			(xy 379.235854 -256.052298) (xy 379.202106 -256.014204) (xy 379.174905 -255.97119) (xy 379.154957 -255.92437)
			(xy 379.142778 -255.874956) (xy 379.138683 -255.824228) (xy 378.820172 -255.824228) (xy 378.819677 -255.848835)
			(xy 378.811782 -255.897412) (xy 378.796198 -255.944093) (xy 378.773327 -255.98767) (xy 378.743762 -256.027014)
			(xy 378.708269 -256.061106) (xy 378.667766 -256.089062) (xy 378.623304 -256.11016) (xy 378.576033 -256.123852)
			(xy 378.527178 -256.129784) (xy 378.478003 -256.127803) (xy 378.429784 -256.117959) (xy 378.383768 -256.100507)
			(xy 378.341147 -256.0759) (xy 378.303026 -256.044775) (xy 378.270391 -256.007938) (xy 378.244088 -255.966342)
			(xy 378.224797 -255.921066) (xy 378.21302 -255.873282) (xy 378.20906 -255.824228) (xy 377.890532 -255.824228)
			(xy 377.89002 -255.849674) (xy 377.881856 -255.899908) (xy 377.86574 -255.948182) (xy 377.842089 -255.993245)
			(xy 377.811516 -256.033931) (xy 377.774812 -256.069186) (xy 377.732928 -256.098096) (xy 377.686949 -256.119913)
			(xy 377.638065 -256.134073) (xy 377.587544 -256.140207) (xy 377.536692 -256.138158) (xy 377.486828 -256.127978)
			(xy 377.439242 -256.109931) (xy 377.395168 -256.084485) (xy 377.355746 -256.052298) (xy 377.321998 -256.014204)
			(xy 377.294797 -255.97119) (xy 377.274849 -255.92437) (xy 377.26267 -255.874956) (xy 377.258575 -255.824228)
			(xy 376.940064 -255.824228) (xy 376.939569 -255.848835) (xy 376.931674 -255.897412) (xy 376.91609 -255.944093)
			(xy 376.893219 -255.98767) (xy 376.863654 -256.027014) (xy 376.828161 -256.061106) (xy 376.787658 -256.089062)
			(xy 376.743196 -256.11016) (xy 376.695925 -256.123852) (xy 376.64707 -256.129784) (xy 376.597895 -256.127803)
			(xy 376.549676 -256.117959) (xy 376.50366 -256.100507) (xy 376.461039 -256.0759) (xy 376.422918 -256.044775)
			(xy 376.390283 -256.007938) (xy 376.36398 -255.966342) (xy 376.344689 -255.921066) (xy 376.332912 -255.873282)
			(xy 376.328952 -255.824228) (xy 376.010424 -255.824228) (xy 376.009912 -255.849674) (xy 376.001748 -255.899908)
			(xy 375.985632 -255.948182) (xy 375.961981 -255.993245) (xy 375.931408 -256.033931) (xy 375.894704 -256.069186)
			(xy 375.85282 -256.098096) (xy 375.806841 -256.119913) (xy 375.757957 -256.134073) (xy 375.707436 -256.140207)
			(xy 375.656584 -256.138158) (xy 375.60672 -256.127978) (xy 375.559134 -256.109931) (xy 375.51506 -256.084485)
			(xy 375.475638 -256.052298) (xy 375.44189 -256.014204) (xy 375.414689 -255.97119) (xy 375.394741 -255.92437)
			(xy 375.382562 -255.874956) (xy 375.378467 -255.824228) (xy 375.06021 -255.824228) (xy 375.059715 -255.848835)
			(xy 375.05182 -255.897412) (xy 375.036236 -255.944093) (xy 375.013365 -255.98767) (xy 374.9838 -256.027014)
			(xy 374.948307 -256.061106) (xy 374.907804 -256.089062) (xy 374.863342 -256.11016) (xy 374.816071 -256.123852)
			(xy 374.767216 -256.129784) (xy 374.718041 -256.127803) (xy 374.669822 -256.117959) (xy 374.623806 -256.100507)
			(xy 374.581185 -256.0759) (xy 374.543064 -256.044775) (xy 374.510429 -256.007938) (xy 374.484126 -255.966342)
			(xy 374.464835 -255.921066) (xy 374.453058 -255.873282) (xy 374.449098 -255.824228) (xy 373.180102 -255.824228)
			(xy 373.179607 -255.848835) (xy 373.171712 -255.897412) (xy 373.156128 -255.944093) (xy 373.133257 -255.98767)
			(xy 373.103692 -256.027014) (xy 373.068199 -256.061106) (xy 373.027696 -256.089062) (xy 372.983234 -256.11016)
			(xy 372.935963 -256.123852) (xy 372.887108 -256.129784) (xy 372.837933 -256.127803) (xy 372.789714 -256.117959)
			(xy 372.743698 -256.100507) (xy 372.701077 -256.0759) (xy 372.662956 -256.044775) (xy 372.630321 -256.007938)
			(xy 372.604018 -255.966342) (xy 372.584727 -255.921066) (xy 372.57295 -255.873282) (xy 372.56899 -255.824228)
			(xy 371.299994 -255.824228) (xy 371.299499 -255.848835) (xy 371.291604 -255.897412) (xy 371.27602 -255.944093)
			(xy 371.253149 -255.98767) (xy 371.223584 -256.027014) (xy 371.188091 -256.061106) (xy 371.147588 -256.089062)
			(xy 371.103126 -256.11016) (xy 371.055855 -256.123852) (xy 371.007 -256.129784) (xy 370.957825 -256.127803)
			(xy 370.909606 -256.117959) (xy 370.86359 -256.100507) (xy 370.820969 -256.0759) (xy 370.782848 -256.044775)
			(xy 370.750213 -256.007938) (xy 370.72391 -255.966342) (xy 370.704619 -255.921066) (xy 370.692842 -255.873282)
			(xy 370.688882 -255.824228) (xy 369.42014 -255.824228) (xy 369.419645 -255.848835) (xy 369.41175 -255.897412)
			(xy 369.396166 -255.944093) (xy 369.373295 -255.98767) (xy 369.34373 -256.027014) (xy 369.308237 -256.061106)
			(xy 369.267734 -256.089062) (xy 369.223272 -256.11016) (xy 369.176001 -256.123852) (xy 369.127146 -256.129784)
			(xy 369.077971 -256.127803) (xy 369.029752 -256.117959) (xy 368.983736 -256.100507) (xy 368.941115 -256.0759)
			(xy 368.902994 -256.044775) (xy 368.870359 -256.007938) (xy 368.844056 -255.966342) (xy 368.824765 -255.921066)
			(xy 368.812988 -255.873282) (xy 368.809028 -255.824228) (xy 365.557672 -255.824228) (xy 365.521462 -255.843918)
			(xy 365.471909 -255.861716) (xy 365.420219 -255.87174) (xy 365.367605 -255.873757) (xy 365.3153 -255.867719)
			(xy 365.264529 -255.853767) (xy 365.216484 -255.832228) (xy 365.172289 -255.803608) (xy 365.132981 -255.768577)
			(xy 365.099481 -255.727956) (xy 365.072575 -255.682697) (xy 365.052892 -255.633862) (xy 365.040895 -255.582594)
			(xy 365.036865 -255.530096) (xy 355.41204 -255.530096) (xy 355.534468 -255.652524) (xy 355.534976 -255.653032)
			(xy 355.542357 -255.659613) (xy 355.560657 -255.667058) (xy 355.570536 -255.66751) (xy 359.64368 -255.66751)
			(xy 359.653516 -255.668048) (xy 359.671674 -255.675639) (xy 359.678986 -255.682242) (xy 360.08691 -256.090166)
			(xy 360.093565 -256.096251) (xy 360.109952 -256.103752) (xy 360.127917 -256.105188) (xy 360.136694 -256.10312)
			(xy 360.151426 -256.098802) (xy 360.157268 -256.095246) (xy 360.177707 -256.083083) (xy 360.221225 -256.063894)
			(xy 360.266975 -256.050896) (xy 360.314081 -256.044338) (xy 360.337862 -256.043938) (xy 360.344466 -256.043938)
			(xy 360.37111 -256.044952) (xy 360.423618 -256.0542) (xy 360.474065 -256.071453) (xy 360.521238 -256.096298)
			(xy 360.564004 -256.128137) (xy 360.601334 -256.166204) (xy 360.63233 -256.209584) (xy 360.656248 -256.257234)
			(xy 360.672513 -256.308009) (xy 360.680732 -256.360688) (xy 360.68127 -256.387346) (xy 360.944163 -256.387346)
			(xy 360.948193 -256.334848) (xy 360.96019 -256.28358) (xy 360.979873 -256.234745) (xy 361.006779 -256.189486)
			(xy 361.040279 -256.148865) (xy 361.079587 -256.113834) (xy 361.123782 -256.085214) (xy 361.171827 -256.063675)
			(xy 361.222598 -256.049723) (xy 361.274903 -256.043685) (xy 361.327517 -256.045702) (xy 361.379207 -256.055726)
			(xy 361.42876 -256.073524) (xy 361.475016 -256.098677) (xy 361.51689 -256.130596) (xy 361.553402 -256.168534)
			(xy 361.583694 -256.2116) (xy 361.607057 -256.258785) (xy 361.622943 -256.308984) (xy 361.63098 -256.36102)
			(xy 361.631484 -256.387346) (xy 361.894123 -256.387346) (xy 361.898153 -256.334848) (xy 361.91015 -256.28358)
			(xy 361.929833 -256.234745) (xy 361.956739 -256.189486) (xy 361.990239 -256.148865) (xy 362.029547 -256.113834)
			(xy 362.073742 -256.085214) (xy 362.121787 -256.063675) (xy 362.172558 -256.049723) (xy 362.224863 -256.043685)
			(xy 362.277477 -256.045702) (xy 362.329167 -256.055726) (xy 362.37872 -256.073524) (xy 362.424976 -256.098677)
			(xy 362.46685 -256.130596) (xy 362.503362 -256.168534) (xy 362.533654 -256.2116) (xy 362.557017 -256.258785)
			(xy 362.572903 -256.308984) (xy 362.58094 -256.36102) (xy 362.581444 -256.387346) (xy 362.844083 -256.387346)
			(xy 362.848113 -256.334848) (xy 362.86011 -256.28358) (xy 362.879793 -256.234745) (xy 362.906699 -256.189486)
			(xy 362.940199 -256.148865) (xy 362.979507 -256.113834) (xy 363.023702 -256.085214) (xy 363.071747 -256.063675)
			(xy 363.122518 -256.049723) (xy 363.174823 -256.043685) (xy 363.227437 -256.045702) (xy 363.279127 -256.055726)
			(xy 363.32868 -256.073524) (xy 363.374936 -256.098677) (xy 363.41681 -256.130596) (xy 363.453322 -256.168534)
			(xy 363.483614 -256.2116) (xy 363.506977 -256.258785) (xy 363.522863 -256.308984) (xy 363.5309 -256.36102)
			(xy 363.531404 -256.387346) (xy 363.794043 -256.387346) (xy 363.798073 -256.334848) (xy 363.81007 -256.28358)
			(xy 363.829753 -256.234745) (xy 363.856659 -256.189486) (xy 363.890159 -256.148865) (xy 363.929467 -256.113834)
			(xy 363.973662 -256.085214) (xy 364.021707 -256.063675) (xy 364.072478 -256.049723) (xy 364.124783 -256.043685)
			(xy 364.177397 -256.045702) (xy 364.229087 -256.055726) (xy 364.27864 -256.073524) (xy 364.324896 -256.098677)
			(xy 364.36677 -256.130596) (xy 364.403282 -256.168534) (xy 364.433574 -256.2116) (xy 364.456937 -256.258785)
			(xy 364.472823 -256.308984) (xy 364.48086 -256.36102) (xy 364.481364 -256.387346) (xy 364.48086 -256.413672)
			(xy 364.472823 -256.465708) (xy 364.468282 -256.480056) (xy 365.036865 -256.480056) (xy 365.040895 -256.427558)
			(xy 365.052892 -256.37629) (xy 365.072575 -256.327455) (xy 365.099481 -256.282196) (xy 365.132981 -256.241575)
			(xy 365.172289 -256.206544) (xy 365.216484 -256.177924) (xy 365.264529 -256.156385) (xy 365.3153 -256.142433)
			(xy 365.367605 -256.136395) (xy 365.420219 -256.138412) (xy 365.471909 -256.148436) (xy 365.521462 -256.166234)
			(xy 365.567718 -256.191387) (xy 365.609592 -256.223306) (xy 365.646104 -256.261244) (xy 365.676396 -256.30431)
			(xy 365.699759 -256.351495) (xy 365.715645 -256.401694) (xy 365.723682 -256.45373) (xy 365.724186 -256.480056)
			(xy 365.723682 -256.506382) (xy 365.715645 -256.558418) (xy 365.699759 -256.608617) (xy 365.687075 -256.634234)
			(xy 370.218982 -256.634234) (xy 370.222942 -256.58518) (xy 370.234719 -256.537396) (xy 370.25401 -256.49212)
			(xy 370.280313 -256.450524) (xy 370.312948 -256.413687) (xy 370.351069 -256.382562) (xy 370.39369 -256.357955)
			(xy 370.439706 -256.340503) (xy 370.487925 -256.330659) (xy 370.5371 -256.328678) (xy 370.585955 -256.33461)
			(xy 370.633226 -256.348302) (xy 370.677688 -256.3694) (xy 370.718191 -256.397356) (xy 370.753684 -256.431448)
			(xy 370.783249 -256.470792) (xy 370.80612 -256.514369) (xy 370.821704 -256.56105) (xy 370.829599 -256.609627)
			(xy 370.830094 -256.634234) (xy 372.09909 -256.634234) (xy 372.10305 -256.58518) (xy 372.114827 -256.537396)
			(xy 372.134118 -256.49212) (xy 372.160421 -256.450524) (xy 372.193056 -256.413687) (xy 372.231177 -256.382562)
			(xy 372.273798 -256.357955) (xy 372.319814 -256.340503) (xy 372.368033 -256.330659) (xy 372.417208 -256.328678)
			(xy 372.466063 -256.33461) (xy 372.513334 -256.348302) (xy 372.557796 -256.3694) (xy 372.598299 -256.397356)
			(xy 372.633792 -256.431448) (xy 372.663357 -256.470792) (xy 372.686228 -256.514369) (xy 372.701812 -256.56105)
			(xy 372.709707 -256.609627) (xy 372.710202 -256.634234) (xy 373.978944 -256.634234) (xy 373.982904 -256.58518)
			(xy 373.994681 -256.537396) (xy 374.013972 -256.49212) (xy 374.040275 -256.450524) (xy 374.07291 -256.413687)
			(xy 374.111031 -256.382562) (xy 374.153652 -256.357955) (xy 374.199668 -256.340503) (xy 374.247887 -256.330659)
			(xy 374.297062 -256.328678) (xy 374.345917 -256.33461) (xy 374.393188 -256.348302) (xy 374.43765 -256.3694)
			(xy 374.478153 -256.397356) (xy 374.513646 -256.431448) (xy 374.543211 -256.470792) (xy 374.566082 -256.514369)
			(xy 374.581666 -256.56105) (xy 374.589561 -256.609627) (xy 374.590056 -256.634234) (xy 375.859052 -256.634234)
			(xy 375.863012 -256.58518) (xy 375.874789 -256.537396) (xy 375.89408 -256.49212) (xy 375.920383 -256.450524)
			(xy 375.953018 -256.413687) (xy 375.991139 -256.382562) (xy 376.03376 -256.357955) (xy 376.079776 -256.340503)
			(xy 376.127995 -256.330659) (xy 376.17717 -256.328678) (xy 376.226025 -256.33461) (xy 376.273296 -256.348302)
			(xy 376.317758 -256.3694) (xy 376.358261 -256.397356) (xy 376.393754 -256.431448) (xy 376.423319 -256.470792)
			(xy 376.44619 -256.514369) (xy 376.461774 -256.56105) (xy 376.469669 -256.609627) (xy 376.470164 -256.634234)
			(xy 376.788675 -256.634234) (xy 376.79277 -256.583506) (xy 376.804949 -256.534092) (xy 376.824897 -256.487272)
			(xy 376.852098 -256.444258) (xy 376.885846 -256.406164) (xy 376.925268 -256.373977) (xy 376.969342 -256.348531)
			(xy 377.016928 -256.330484) (xy 377.066792 -256.320304) (xy 377.117644 -256.318255) (xy 377.168165 -256.324389)
			(xy 377.217049 -256.338549) (xy 377.263028 -256.360366) (xy 377.304912 -256.389276) (xy 377.341616 -256.424531)
			(xy 377.372189 -256.465217) (xy 377.39584 -256.51028) (xy 377.411956 -256.558554) (xy 377.42012 -256.608788)
			(xy 377.420632 -256.634234) (xy 378.67896 -256.634234) (xy 378.68292 -256.58518) (xy 378.694697 -256.537396)
			(xy 378.713988 -256.49212) (xy 378.740291 -256.450524) (xy 378.772926 -256.413687) (xy 378.811047 -256.382562)
			(xy 378.853668 -256.357955) (xy 378.899684 -256.340503) (xy 378.947903 -256.330659) (xy 378.997078 -256.328678)
			(xy 379.045933 -256.33461) (xy 379.093204 -256.348302) (xy 379.137666 -256.3694) (xy 379.178169 -256.397356)
			(xy 379.213662 -256.431448) (xy 379.243227 -256.470792) (xy 379.266098 -256.514369) (xy 379.281682 -256.56105)
			(xy 379.289577 -256.609627) (xy 379.290072 -256.634234) (xy 379.619014 -256.634234) (xy 379.622974 -256.58518)
			(xy 379.634751 -256.537396) (xy 379.654042 -256.49212) (xy 379.680345 -256.450524) (xy 379.71298 -256.413687)
			(xy 379.751101 -256.382562) (xy 379.793722 -256.357955) (xy 379.839738 -256.340503) (xy 379.887957 -256.330659)
			(xy 379.937132 -256.328678) (xy 379.985987 -256.33461) (xy 380.033258 -256.348302) (xy 380.07772 -256.3694)
			(xy 380.118223 -256.397356) (xy 380.153716 -256.431448) (xy 380.183281 -256.470792) (xy 380.206152 -256.514369)
			(xy 380.221736 -256.56105) (xy 380.229631 -256.609627) (xy 380.230126 -256.634234) (xy 380.548637 -256.634234)
			(xy 380.552732 -256.583506) (xy 380.564911 -256.534092) (xy 380.584859 -256.487272) (xy 380.61206 -256.444258)
			(xy 380.645808 -256.406164) (xy 380.68523 -256.373977) (xy 380.729304 -256.348531) (xy 380.77689 -256.330484)
			(xy 380.826754 -256.320304) (xy 380.877606 -256.318255) (xy 380.928127 -256.324389) (xy 380.977011 -256.338549)
			(xy 381.02299 -256.360366) (xy 381.064874 -256.389276) (xy 381.101578 -256.424531) (xy 381.132151 -256.465217)
			(xy 381.155802 -256.51028) (xy 381.171918 -256.558554) (xy 381.180082 -256.608788) (xy 381.180594 -256.634234)
			(xy 381.499122 -256.634234) (xy 381.503082 -256.58518) (xy 381.514859 -256.537396) (xy 381.53415 -256.49212)
			(xy 381.560453 -256.450524) (xy 381.593088 -256.413687) (xy 381.631209 -256.382562) (xy 381.67383 -256.357955)
			(xy 381.719846 -256.340503) (xy 381.768065 -256.330659) (xy 381.81724 -256.328678) (xy 381.866095 -256.33461)
			(xy 381.913366 -256.348302) (xy 381.957828 -256.3694) (xy 381.998331 -256.397356) (xy 382.033824 -256.431448)
			(xy 382.063389 -256.470792) (xy 382.08626 -256.514369) (xy 382.101844 -256.56105) (xy 382.109739 -256.609627)
			(xy 382.110234 -256.634234) (xy 382.438922 -256.634234) (xy 382.442882 -256.58518) (xy 382.454659 -256.537396)
			(xy 382.47395 -256.49212) (xy 382.500253 -256.450524) (xy 382.532888 -256.413687) (xy 382.571009 -256.382562)
			(xy 382.61363 -256.357955) (xy 382.659646 -256.340503) (xy 382.707865 -256.330659) (xy 382.75704 -256.328678)
			(xy 382.805895 -256.33461) (xy 382.853166 -256.348302) (xy 382.897628 -256.3694) (xy 382.938131 -256.397356)
			(xy 382.973624 -256.431448) (xy 383.003189 -256.470792) (xy 383.02606 -256.514369) (xy 383.041644 -256.56105)
			(xy 383.049539 -256.609627) (xy 383.050034 -256.634234) (xy 383.378976 -256.634234) (xy 383.382936 -256.58518)
			(xy 383.394713 -256.537396) (xy 383.414004 -256.49212) (xy 383.440307 -256.450524) (xy 383.472942 -256.413687)
			(xy 383.511063 -256.382562) (xy 383.553684 -256.357955) (xy 383.5997 -256.340503) (xy 383.647919 -256.330659)
			(xy 383.697094 -256.328678) (xy 383.745949 -256.33461) (xy 383.79322 -256.348302) (xy 383.837682 -256.3694)
			(xy 383.878185 -256.397356) (xy 383.913678 -256.431448) (xy 383.943243 -256.470792) (xy 383.966114 -256.514369)
			(xy 383.981698 -256.56105) (xy 383.989593 -256.609627) (xy 383.990088 -256.634234) (xy 383.989593 -256.658841)
			(xy 383.981698 -256.707418) (xy 383.966114 -256.754099) (xy 383.943243 -256.797676) (xy 383.913678 -256.83702)
			(xy 383.878185 -256.871112) (xy 383.837682 -256.899068) (xy 383.79322 -256.920166) (xy 383.745949 -256.933858)
			(xy 383.697094 -256.93979) (xy 383.647919 -256.937809) (xy 383.5997 -256.927965) (xy 383.553684 -256.910513)
			(xy 383.511063 -256.885906) (xy 383.472942 -256.854781) (xy 383.440307 -256.817944) (xy 383.414004 -256.776348)
			(xy 383.394713 -256.731072) (xy 383.382936 -256.683288) (xy 383.378976 -256.634234) (xy 383.050034 -256.634234)
			(xy 383.049539 -256.658841) (xy 383.041644 -256.707418) (xy 383.02606 -256.754099) (xy 383.003189 -256.797676)
			(xy 382.973624 -256.83702) (xy 382.938131 -256.871112) (xy 382.897628 -256.899068) (xy 382.853166 -256.920166)
			(xy 382.805895 -256.933858) (xy 382.75704 -256.93979) (xy 382.707865 -256.937809) (xy 382.659646 -256.927965)
			(xy 382.61363 -256.910513) (xy 382.571009 -256.885906) (xy 382.532888 -256.854781) (xy 382.500253 -256.817944)
			(xy 382.47395 -256.776348) (xy 382.454659 -256.731072) (xy 382.442882 -256.683288) (xy 382.438922 -256.634234)
			(xy 382.110234 -256.634234) (xy 382.109739 -256.658841) (xy 382.101844 -256.707418) (xy 382.08626 -256.754099)
			(xy 382.063389 -256.797676) (xy 382.033824 -256.83702) (xy 381.998331 -256.871112) (xy 381.957828 -256.899068)
			(xy 381.913366 -256.920166) (xy 381.866095 -256.933858) (xy 381.81724 -256.93979) (xy 381.768065 -256.937809)
			(xy 381.719846 -256.927965) (xy 381.67383 -256.910513) (xy 381.631209 -256.885906) (xy 381.593088 -256.854781)
			(xy 381.560453 -256.817944) (xy 381.53415 -256.776348) (xy 381.514859 -256.731072) (xy 381.503082 -256.683288)
			(xy 381.499122 -256.634234) (xy 381.180594 -256.634234) (xy 381.180082 -256.65968) (xy 381.171918 -256.709914)
			(xy 381.155802 -256.758188) (xy 381.132151 -256.803251) (xy 381.101578 -256.843937) (xy 381.064874 -256.879192)
			(xy 381.02299 -256.908102) (xy 380.977011 -256.929919) (xy 380.928127 -256.944079) (xy 380.877606 -256.950213)
			(xy 380.826754 -256.948164) (xy 380.77689 -256.937984) (xy 380.729304 -256.919937) (xy 380.68523 -256.894491)
			(xy 380.645808 -256.862304) (xy 380.61206 -256.82421) (xy 380.584859 -256.781196) (xy 380.564911 -256.734376)
			(xy 380.552732 -256.684962) (xy 380.548637 -256.634234) (xy 380.230126 -256.634234) (xy 380.229631 -256.658841)
			(xy 380.221736 -256.707418) (xy 380.206152 -256.754099) (xy 380.183281 -256.797676) (xy 380.153716 -256.83702)
			(xy 380.118223 -256.871112) (xy 380.07772 -256.899068) (xy 380.033258 -256.920166) (xy 379.985987 -256.933858)
			(xy 379.937132 -256.93979) (xy 379.887957 -256.937809) (xy 379.839738 -256.927965) (xy 379.793722 -256.910513)
			(xy 379.751101 -256.885906) (xy 379.71298 -256.854781) (xy 379.680345 -256.817944) (xy 379.654042 -256.776348)
			(xy 379.634751 -256.731072) (xy 379.622974 -256.683288) (xy 379.619014 -256.634234) (xy 379.290072 -256.634234)
			(xy 379.289577 -256.658841) (xy 379.281682 -256.707418) (xy 379.266098 -256.754099) (xy 379.243227 -256.797676)
			(xy 379.213662 -256.83702) (xy 379.178169 -256.871112) (xy 379.137666 -256.899068) (xy 379.093204 -256.920166)
			(xy 379.045933 -256.933858) (xy 378.997078 -256.93979) (xy 378.947903 -256.937809) (xy 378.899684 -256.927965)
			(xy 378.853668 -256.910513) (xy 378.811047 -256.885906) (xy 378.772926 -256.854781) (xy 378.740291 -256.817944)
			(xy 378.713988 -256.776348) (xy 378.694697 -256.731072) (xy 378.68292 -256.683288) (xy 378.67896 -256.634234)
			(xy 377.420632 -256.634234) (xy 377.42012 -256.65968) (xy 377.411956 -256.709914) (xy 377.39584 -256.758188)
			(xy 377.372189 -256.803251) (xy 377.341616 -256.843937) (xy 377.304912 -256.879192) (xy 377.263028 -256.908102)
			(xy 377.217049 -256.929919) (xy 377.168165 -256.944079) (xy 377.117644 -256.950213) (xy 377.066792 -256.948164)
			(xy 377.016928 -256.937984) (xy 376.969342 -256.919937) (xy 376.925268 -256.894491) (xy 376.885846 -256.862304)
			(xy 376.852098 -256.82421) (xy 376.824897 -256.781196) (xy 376.804949 -256.734376) (xy 376.79277 -256.684962)
			(xy 376.788675 -256.634234) (xy 376.470164 -256.634234) (xy 376.469669 -256.658841) (xy 376.461774 -256.707418)
			(xy 376.44619 -256.754099) (xy 376.423319 -256.797676) (xy 376.393754 -256.83702) (xy 376.358261 -256.871112)
			(xy 376.317758 -256.899068) (xy 376.273296 -256.920166) (xy 376.226025 -256.933858) (xy 376.17717 -256.93979)
			(xy 376.127995 -256.937809) (xy 376.079776 -256.927965) (xy 376.03376 -256.910513) (xy 375.991139 -256.885906)
			(xy 375.953018 -256.854781) (xy 375.920383 -256.817944) (xy 375.89408 -256.776348) (xy 375.874789 -256.731072)
			(xy 375.863012 -256.683288) (xy 375.859052 -256.634234) (xy 374.590056 -256.634234) (xy 374.589561 -256.658841)
			(xy 374.581666 -256.707418) (xy 374.566082 -256.754099) (xy 374.543211 -256.797676) (xy 374.513646 -256.83702)
			(xy 374.478153 -256.871112) (xy 374.43765 -256.899068) (xy 374.393188 -256.920166) (xy 374.345917 -256.933858)
			(xy 374.297062 -256.93979) (xy 374.247887 -256.937809) (xy 374.199668 -256.927965) (xy 374.153652 -256.910513)
			(xy 374.111031 -256.885906) (xy 374.07291 -256.854781) (xy 374.040275 -256.817944) (xy 374.013972 -256.776348)
			(xy 373.994681 -256.731072) (xy 373.982904 -256.683288) (xy 373.978944 -256.634234) (xy 372.710202 -256.634234)
			(xy 372.709707 -256.658841) (xy 372.701812 -256.707418) (xy 372.686228 -256.754099) (xy 372.663357 -256.797676)
			(xy 372.633792 -256.83702) (xy 372.598299 -256.871112) (xy 372.557796 -256.899068) (xy 372.513334 -256.920166)
			(xy 372.466063 -256.933858) (xy 372.417208 -256.93979) (xy 372.368033 -256.937809) (xy 372.319814 -256.927965)
			(xy 372.273798 -256.910513) (xy 372.231177 -256.885906) (xy 372.193056 -256.854781) (xy 372.160421 -256.817944)
			(xy 372.134118 -256.776348) (xy 372.114827 -256.731072) (xy 372.10305 -256.683288) (xy 372.09909 -256.634234)
			(xy 370.830094 -256.634234) (xy 370.829599 -256.658841) (xy 370.821704 -256.707418) (xy 370.80612 -256.754099)
			(xy 370.783249 -256.797676) (xy 370.753684 -256.83702) (xy 370.718191 -256.871112) (xy 370.677688 -256.899068)
			(xy 370.633226 -256.920166) (xy 370.585955 -256.933858) (xy 370.5371 -256.93979) (xy 370.487925 -256.937809)
			(xy 370.439706 -256.927965) (xy 370.39369 -256.910513) (xy 370.351069 -256.885906) (xy 370.312948 -256.854781)
			(xy 370.280313 -256.817944) (xy 370.25401 -256.776348) (xy 370.234719 -256.731072) (xy 370.222942 -256.683288)
			(xy 370.218982 -256.634234) (xy 365.687075 -256.634234) (xy 365.676396 -256.655802) (xy 365.646104 -256.698868)
			(xy 365.609592 -256.736806) (xy 365.567718 -256.768725) (xy 365.521462 -256.793878) (xy 365.471909 -256.811676)
			(xy 365.420219 -256.8217) (xy 365.367605 -256.823717) (xy 365.3153 -256.817679) (xy 365.264529 -256.803727)
			(xy 365.216484 -256.782188) (xy 365.172289 -256.753568) (xy 365.132981 -256.718537) (xy 365.099481 -256.677916)
			(xy 365.072575 -256.632657) (xy 365.052892 -256.583822) (xy 365.040895 -256.532554) (xy 365.036865 -256.480056)
			(xy 364.468282 -256.480056) (xy 364.456937 -256.515907) (xy 364.433574 -256.563092) (xy 364.403282 -256.606158)
			(xy 364.36677 -256.644096) (xy 364.324896 -256.676015) (xy 364.27864 -256.701168) (xy 364.229087 -256.718966)
			(xy 364.177397 -256.72899) (xy 364.124783 -256.731007) (xy 364.072478 -256.724969) (xy 364.021707 -256.711017)
			(xy 363.973662 -256.689478) (xy 363.929467 -256.660858) (xy 363.890159 -256.625827) (xy 363.856659 -256.585206)
			(xy 363.829753 -256.539947) (xy 363.81007 -256.491112) (xy 363.798073 -256.439844) (xy 363.794043 -256.387346)
			(xy 363.531404 -256.387346) (xy 363.5309 -256.413672) (xy 363.522863 -256.465708) (xy 363.506977 -256.515907)
			(xy 363.483614 -256.563092) (xy 363.453322 -256.606158) (xy 363.41681 -256.644096) (xy 363.374936 -256.676015)
			(xy 363.32868 -256.701168) (xy 363.279127 -256.718966) (xy 363.227437 -256.72899) (xy 363.174823 -256.731007)
			(xy 363.122518 -256.724969) (xy 363.071747 -256.711017) (xy 363.023702 -256.689478) (xy 362.979507 -256.660858)
			(xy 362.940199 -256.625827) (xy 362.906699 -256.585206) (xy 362.879793 -256.539947) (xy 362.86011 -256.491112)
			(xy 362.848113 -256.439844) (xy 362.844083 -256.387346) (xy 362.581444 -256.387346) (xy 362.58094 -256.413672)
			(xy 362.572903 -256.465708) (xy 362.557017 -256.515907) (xy 362.533654 -256.563092) (xy 362.503362 -256.606158)
			(xy 362.46685 -256.644096) (xy 362.424976 -256.676015) (xy 362.37872 -256.701168) (xy 362.329167 -256.718966)
			(xy 362.277477 -256.72899) (xy 362.224863 -256.731007) (xy 362.172558 -256.724969) (xy 362.121787 -256.711017)
			(xy 362.073742 -256.689478) (xy 362.029547 -256.660858) (xy 361.990239 -256.625827) (xy 361.956739 -256.585206)
			(xy 361.929833 -256.539947) (xy 361.91015 -256.491112) (xy 361.898153 -256.439844) (xy 361.894123 -256.387346)
			(xy 361.631484 -256.387346) (xy 361.63098 -256.413672) (xy 361.622943 -256.465708) (xy 361.607057 -256.515907)
			(xy 361.583694 -256.563092) (xy 361.553402 -256.606158) (xy 361.51689 -256.644096) (xy 361.475016 -256.676015)
			(xy 361.42876 -256.701168) (xy 361.379207 -256.718966) (xy 361.327517 -256.72899) (xy 361.274903 -256.731007)
			(xy 361.222598 -256.724969) (xy 361.171827 -256.711017) (xy 361.123782 -256.689478) (xy 361.079587 -256.660858)
			(xy 361.040279 -256.625827) (xy 361.006779 -256.585206) (xy 360.979873 -256.539947) (xy 360.96019 -256.491112)
			(xy 360.948193 -256.439844) (xy 360.944163 -256.387346) (xy 360.68127 -256.387346) (xy 360.680755 -256.41411)
			(xy 360.672444 -256.466988) (xy 360.656031 -256.517936) (xy 360.631913 -256.565722) (xy 360.600674 -256.609188)
			(xy 360.56307 -256.647281) (xy 360.520012 -256.67908) (xy 360.472542 -256.703814) (xy 360.42181 -256.720885)
			(xy 360.39552 -256.725928) (xy 360.387646 -256.727198) (xy 360.365294 -256.738882) (xy 360.357166 -256.7432)
			(xy 360.337608 -256.76479) (xy 360.331699 -256.772034) (xy 360.325039 -256.789487) (xy 360.324654 -256.798826)
			(xy 360.324654 -257.744976) (xy 361.178351 -257.744976) (xy 361.182381 -257.692478) (xy 361.194378 -257.64121)
			(xy 361.214061 -257.592375) (xy 361.240967 -257.547116) (xy 361.274467 -257.506495) (xy 361.313775 -257.471464)
			(xy 361.35797 -257.442844) (xy 361.406015 -257.421305) (xy 361.456786 -257.407353) (xy 361.509091 -257.401315)
			(xy 361.561705 -257.403332) (xy 361.613395 -257.413356) (xy 361.662948 -257.431154) (xy 361.709204 -257.456307)
			(xy 361.751078 -257.488226) (xy 361.78759 -257.526164) (xy 361.817882 -257.56923) (xy 361.841245 -257.616415)
			(xy 361.857131 -257.666614) (xy 361.865168 -257.71865) (xy 361.865672 -257.744976) (xy 363.778295 -257.744976)
			(xy 363.782325 -257.692478) (xy 363.794322 -257.64121) (xy 363.814005 -257.592375) (xy 363.840911 -257.547116)
			(xy 363.874411 -257.506495) (xy 363.913719 -257.471464) (xy 363.957914 -257.442844) (xy 364.005959 -257.421305)
			(xy 364.05673 -257.407353) (xy 364.109035 -257.401315) (xy 364.161649 -257.403332) (xy 364.213339 -257.413356)
			(xy 364.259724 -257.430016) (xy 365.036865 -257.430016) (xy 365.040895 -257.377518) (xy 365.052892 -257.32625)
			(xy 365.072575 -257.277415) (xy 365.099481 -257.232156) (xy 365.132981 -257.191535) (xy 365.172289 -257.156504)
			(xy 365.216484 -257.127884) (xy 365.264529 -257.106345) (xy 365.3153 -257.092393) (xy 365.367605 -257.086355)
			(xy 365.420219 -257.088372) (xy 365.471909 -257.098396) (xy 365.521462 -257.116194) (xy 365.567718 -257.141347)
			(xy 365.609592 -257.173266) (xy 365.646104 -257.211204) (xy 365.676396 -257.25427) (xy 365.699759 -257.301455)
			(xy 365.715645 -257.351654) (xy 365.723682 -257.40369) (xy 365.724186 -257.430016) (xy 365.723682 -257.456342)
			(xy 365.715645 -257.508378) (xy 365.699759 -257.558577) (xy 365.676396 -257.605762) (xy 365.646104 -257.648828)
			(xy 365.609592 -257.686766) (xy 365.567718 -257.718685) (xy 365.521462 -257.743838) (xy 365.471909 -257.761636)
			(xy 365.420219 -257.77166) (xy 365.367605 -257.773677) (xy 365.3153 -257.767639) (xy 365.264529 -257.753687)
			(xy 365.216484 -257.732148) (xy 365.172289 -257.703528) (xy 365.132981 -257.668497) (xy 365.099481 -257.627876)
			(xy 365.072575 -257.582617) (xy 365.052892 -257.533782) (xy 365.040895 -257.482514) (xy 365.036865 -257.430016)
			(xy 364.259724 -257.430016) (xy 364.262892 -257.431154) (xy 364.309148 -257.456307) (xy 364.351022 -257.488226)
			(xy 364.387534 -257.526164) (xy 364.417826 -257.56923) (xy 364.441189 -257.616415) (xy 364.457075 -257.666614)
			(xy 364.465112 -257.71865) (xy 364.465616 -257.744976) (xy 364.465112 -257.771302) (xy 364.457075 -257.823338)
			(xy 364.441189 -257.873537) (xy 364.417826 -257.920722) (xy 364.4112 -257.930142) (xy 368.805717 -257.930142)
			(xy 368.809747 -257.877644) (xy 368.821744 -257.826376) (xy 368.841427 -257.777541) (xy 368.868333 -257.732282)
			(xy 368.901833 -257.691661) (xy 368.941141 -257.65663) (xy 368.985336 -257.62801) (xy 369.033381 -257.606471)
			(xy 369.084152 -257.592519) (xy 369.136457 -257.586481) (xy 369.189071 -257.588498) (xy 369.240761 -257.598522)
			(xy 369.290314 -257.61632) (xy 369.33657 -257.641473) (xy 369.378444 -257.673392) (xy 369.414956 -257.71133)
			(xy 369.445248 -257.754396) (xy 369.468611 -257.801581) (xy 369.484497 -257.85178) (xy 369.492534 -257.903816)
			(xy 369.493038 -257.930142) (xy 370.731291 -257.930142) (xy 370.735321 -257.877644) (xy 370.747318 -257.826376)
			(xy 370.767001 -257.777541) (xy 370.793907 -257.732282) (xy 370.827407 -257.691661) (xy 370.866715 -257.65663)
			(xy 370.91091 -257.62801) (xy 370.958955 -257.606471) (xy 371.009726 -257.592519) (xy 371.062031 -257.586481)
			(xy 371.114645 -257.588498) (xy 371.166335 -257.598522) (xy 371.215888 -257.61632) (xy 371.262144 -257.641473)
			(xy 371.304018 -257.673392) (xy 371.34053 -257.71133) (xy 371.370822 -257.754396) (xy 371.394185 -257.801581)
			(xy 371.410071 -257.85178) (xy 371.418108 -257.903816) (xy 371.418612 -257.930142) (xy 372.509291 -257.930142)
			(xy 372.513321 -257.877644) (xy 372.525318 -257.826376) (xy 372.545001 -257.777541) (xy 372.571907 -257.732282)
			(xy 372.605407 -257.691661) (xy 372.644715 -257.65663) (xy 372.68891 -257.62801) (xy 372.736955 -257.606471)
			(xy 372.787726 -257.592519) (xy 372.840031 -257.586481) (xy 372.892645 -257.588498) (xy 372.944335 -257.598522)
			(xy 372.993888 -257.61632) (xy 373.040144 -257.641473) (xy 373.082018 -257.673392) (xy 373.11853 -257.71133)
			(xy 373.148822 -257.754396) (xy 373.172185 -257.801581) (xy 373.188071 -257.85178) (xy 373.196108 -257.903816)
			(xy 373.196612 -257.930142) (xy 373.196108 -257.956468) (xy 373.188071 -258.008504) (xy 373.172185 -258.058703)
			(xy 373.148822 -258.105888) (xy 373.11853 -258.148954) (xy 373.082018 -258.186892) (xy 373.040144 -258.218811)
			(xy 372.993888 -258.243964) (xy 372.944335 -258.261762) (xy 372.892645 -258.271786) (xy 372.840031 -258.273803)
			(xy 372.787726 -258.267765) (xy 372.736955 -258.253813) (xy 372.68891 -258.232274) (xy 372.644715 -258.203654)
			(xy 372.605407 -258.168623) (xy 372.571907 -258.128002) (xy 372.545001 -258.082743) (xy 372.525318 -258.033908)
			(xy 372.513321 -257.98264) (xy 372.509291 -257.930142) (xy 371.418612 -257.930142) (xy 371.418108 -257.956468)
			(xy 371.410071 -258.008504) (xy 371.394185 -258.058703) (xy 371.370822 -258.105888) (xy 371.34053 -258.148954)
			(xy 371.304018 -258.186892) (xy 371.262144 -258.218811) (xy 371.215888 -258.243964) (xy 371.166335 -258.261762)
			(xy 371.114645 -258.271786) (xy 371.062031 -258.273803) (xy 371.009726 -258.267765) (xy 370.958955 -258.253813)
			(xy 370.91091 -258.232274) (xy 370.866715 -258.203654) (xy 370.827407 -258.168623) (xy 370.793907 -258.128002)
			(xy 370.767001 -258.082743) (xy 370.747318 -258.033908) (xy 370.735321 -257.98264) (xy 370.731291 -257.930142)
			(xy 369.493038 -257.930142) (xy 369.492534 -257.956468) (xy 369.484497 -258.008504) (xy 369.468611 -258.058703)
			(xy 369.445248 -258.105888) (xy 369.414956 -258.148954) (xy 369.378444 -258.186892) (xy 369.33657 -258.218811)
			(xy 369.290314 -258.243964) (xy 369.240761 -258.261762) (xy 369.189071 -258.271786) (xy 369.136457 -258.273803)
			(xy 369.084152 -258.267765) (xy 369.033381 -258.253813) (xy 368.985336 -258.232274) (xy 368.941141 -258.203654)
			(xy 368.901833 -258.168623) (xy 368.868333 -258.128002) (xy 368.841427 -258.082743) (xy 368.821744 -258.033908)
			(xy 368.809747 -257.98264) (xy 368.805717 -257.930142) (xy 364.4112 -257.930142) (xy 364.387534 -257.963788)
			(xy 364.351022 -258.001726) (xy 364.309148 -258.033645) (xy 364.262892 -258.058798) (xy 364.213339 -258.076596)
			(xy 364.161649 -258.08662) (xy 364.109035 -258.088637) (xy 364.05673 -258.082599) (xy 364.005959 -258.068647)
			(xy 363.957914 -258.047108) (xy 363.913719 -258.018488) (xy 363.874411 -257.983457) (xy 363.840911 -257.942836)
			(xy 363.814005 -257.897577) (xy 363.794322 -257.848742) (xy 363.782325 -257.797474) (xy 363.778295 -257.744976)
			(xy 361.865672 -257.744976) (xy 361.865168 -257.771302) (xy 361.857131 -257.823338) (xy 361.841245 -257.873537)
			(xy 361.817882 -257.920722) (xy 361.78759 -257.963788) (xy 361.751078 -258.001726) (xy 361.709204 -258.033645)
			(xy 361.662948 -258.058798) (xy 361.613395 -258.076596) (xy 361.561705 -258.08662) (xy 361.509091 -258.088637)
			(xy 361.456786 -258.082599) (xy 361.406015 -258.068647) (xy 361.35797 -258.047108) (xy 361.313775 -258.018488)
			(xy 361.274467 -257.983457) (xy 361.240967 -257.942836) (xy 361.214061 -257.897577) (xy 361.194378 -257.848742)
			(xy 361.182381 -257.797474) (xy 361.178351 -257.744976) (xy 360.324654 -257.744976) (xy 360.324654 -258.379976)
			(xy 365.036865 -258.379976) (xy 365.040895 -258.327478) (xy 365.052892 -258.27621) (xy 365.072575 -258.227375)
			(xy 365.099481 -258.182116) (xy 365.132981 -258.141495) (xy 365.172289 -258.106464) (xy 365.216484 -258.077844)
			(xy 365.264529 -258.056305) (xy 365.3153 -258.042353) (xy 365.367605 -258.036315) (xy 365.420219 -258.038332)
			(xy 365.471909 -258.048356) (xy 365.521462 -258.066154) (xy 365.567718 -258.091307) (xy 365.609592 -258.123226)
			(xy 365.646104 -258.161164) (xy 365.676396 -258.20423) (xy 365.699759 -258.251415) (xy 365.715645 -258.301614)
			(xy 365.723682 -258.35365) (xy 365.724186 -258.379976) (xy 365.723682 -258.406302) (xy 365.715645 -258.458338)
			(xy 365.699759 -258.508537) (xy 365.676396 -258.555722) (xy 365.646104 -258.598788) (xy 365.609592 -258.636726)
			(xy 365.567718 -258.668645) (xy 365.521462 -258.693798) (xy 365.471909 -258.711596) (xy 365.420219 -258.72162)
			(xy 365.367605 -258.723637) (xy 365.3153 -258.717599) (xy 365.264529 -258.703647) (xy 365.216484 -258.682108)
			(xy 365.172289 -258.653488) (xy 365.132981 -258.618457) (xy 365.099481 -258.577836) (xy 365.072575 -258.532577)
			(xy 365.052892 -258.483742) (xy 365.040895 -258.432474) (xy 365.036865 -258.379976) (xy 360.324654 -258.379976)
			(xy 360.324654 -258.846828) (xy 360.325115 -258.856705) (xy 360.332555 -258.875005) (xy 360.339132 -258.882388)
			(xy 360.339386 -258.882642) (xy 360.589068 -259.132324) (xy 360.589576 -259.132832) (xy 360.596957 -259.139413)
			(xy 360.615257 -259.146858) (xy 360.625136 -259.14731) (xy 361.156758 -259.14731) (xy 361.165962 -259.146916)
			(xy 361.183195 -259.140441) (xy 361.197062 -259.128334) (xy 361.201716 -259.120386) (xy 361.24261 -259.042662)
			(xy 361.2466 -259.034298) (xy 361.248894 -259.015924) (xy 361.244475 -258.997943) (xy 361.239562 -258.990084)
			(xy 361.225211 -258.968464) (xy 361.202495 -258.921809) (xy 361.187072 -258.872263) (xy 361.179293 -258.820958)
			(xy 361.178856 -258.795012) (xy 361.178856 -258.7879) (xy 361.179909 -258.761284) (xy 361.189221 -258.708841)
			(xy 361.206521 -258.658466) (xy 361.231393 -258.611366) (xy 361.263241 -258.568673) (xy 361.301301 -258.531411)
			(xy 361.344658 -258.500473) (xy 361.392273 -258.476603) (xy 361.443004 -258.460373) (xy 361.495632 -258.452172)
			(xy 361.522264 -258.451604) (xy 361.548906 -258.452111) (xy 361.60155 -258.460349) (xy 361.65229 -258.476617)
			(xy 361.699909 -258.500526) (xy 361.743265 -258.5315) (xy 361.781318 -258.568799) (xy 361.813155 -258.611526)
			(xy 361.838013 -258.658657) (xy 361.855294 -258.70906) (xy 361.864585 -258.761528) (xy 361.865672 -258.788154)
			(xy 361.865672 -258.792726) (xy 361.865672 -258.795012) (xy 361.865192 -258.820953) (xy 361.857386 -258.872246)
			(xy 361.841967 -258.921784) (xy 361.819284 -258.968447) (xy 361.804966 -258.990084) (xy 361.800078 -258.997946)
			(xy 361.795715 -259.015924) (xy 361.797977 -259.034284) (xy 361.801918 -259.042662) (xy 361.842812 -259.120386)
			(xy 361.847468 -259.128346) (xy 361.8613 -259.140518) (xy 361.878556 -259.146977) (xy 361.88777 -259.14731)
			(xy 363.756702 -259.14731) (xy 363.765902 -259.146909) (xy 363.783123 -259.140424) (xy 363.796977 -259.128314)
			(xy 363.80166 -259.120386) (xy 363.842554 -259.042662) (xy 363.846548 -259.034299) (xy 363.848845 -259.015924)
			(xy 363.844421 -258.997943) (xy 363.839506 -258.990084) (xy 363.825157 -258.968463) (xy 363.802445 -258.921807)
			(xy 363.787024 -258.872261) (xy 363.779247 -258.820957) (xy 363.7788 -258.795012) (xy 363.7788 -258.7879)
			(xy 363.779852 -258.761283) (xy 363.789164 -258.708836) (xy 363.806464 -258.658457) (xy 363.831335 -258.611353)
			(xy 363.863182 -258.568656) (xy 363.901241 -258.531388) (xy 363.944598 -258.500444) (xy 363.992213 -258.476567)
			(xy 364.042944 -258.460329) (xy 364.095575 -258.45212) (xy 364.122208 -258.451604) (xy 364.148853 -258.452107)
			(xy 364.201503 -258.460338) (xy 364.25225 -258.476601) (xy 364.299877 -258.500506) (xy 364.343241 -258.53148)
			(xy 364.381301 -258.568779) (xy 364.413145 -258.611508) (xy 364.438007 -258.658643) (xy 364.455292 -258.709051)
			(xy 364.464585 -258.761525) (xy 364.465616 -258.788154) (xy 364.465616 -258.792726) (xy 364.465616 -258.795012)
			(xy 364.465136 -258.820954) (xy 364.46375 -258.830064) (xy 368.805717 -258.830064) (xy 368.809747 -258.777566)
			(xy 368.821744 -258.726298) (xy 368.841427 -258.677463) (xy 368.868333 -258.632204) (xy 368.901833 -258.591583)
			(xy 368.941141 -258.556552) (xy 368.985336 -258.527932) (xy 369.033381 -258.506393) (xy 369.084152 -258.492441)
			(xy 369.136457 -258.486403) (xy 369.189071 -258.48842) (xy 369.240761 -258.498444) (xy 369.290314 -258.516242)
			(xy 369.33657 -258.541395) (xy 369.378444 -258.573314) (xy 369.414956 -258.611252) (xy 369.445248 -258.654318)
			(xy 369.468611 -258.701503) (xy 369.484497 -258.751702) (xy 369.492534 -258.803738) (xy 369.493038 -258.830064)
			(xy 370.731291 -258.830064) (xy 370.735321 -258.777566) (xy 370.747318 -258.726298) (xy 370.767001 -258.677463)
			(xy 370.793907 -258.632204) (xy 370.827407 -258.591583) (xy 370.866715 -258.556552) (xy 370.91091 -258.527932)
			(xy 370.958955 -258.506393) (xy 371.009726 -258.492441) (xy 371.062031 -258.486403) (xy 371.114645 -258.48842)
			(xy 371.166335 -258.498444) (xy 371.215888 -258.516242) (xy 371.262144 -258.541395) (xy 371.304018 -258.573314)
			(xy 371.34053 -258.611252) (xy 371.370822 -258.654318) (xy 371.394185 -258.701503) (xy 371.410071 -258.751702)
			(xy 371.418108 -258.803738) (xy 371.418612 -258.830064) (xy 372.509291 -258.830064) (xy 372.513321 -258.777566)
			(xy 372.525318 -258.726298) (xy 372.545001 -258.677463) (xy 372.571907 -258.632204) (xy 372.605407 -258.591583)
			(xy 372.644715 -258.556552) (xy 372.68891 -258.527932) (xy 372.736955 -258.506393) (xy 372.787726 -258.492441)
			(xy 372.840031 -258.486403) (xy 372.892645 -258.48842) (xy 372.944335 -258.498444) (xy 372.993888 -258.516242)
			(xy 373.040144 -258.541395) (xy 373.082018 -258.573314) (xy 373.11853 -258.611252) (xy 373.148822 -258.654318)
			(xy 373.172185 -258.701503) (xy 373.188071 -258.751702) (xy 373.196108 -258.803738) (xy 373.196612 -258.830064)
			(xy 373.196108 -258.85639) (xy 373.188071 -258.908426) (xy 373.172185 -258.958625) (xy 373.148822 -259.00581)
			(xy 373.11853 -259.048876) (xy 373.082018 -259.086814) (xy 373.040144 -259.118733) (xy 372.993888 -259.143886)
			(xy 372.944335 -259.161684) (xy 372.892645 -259.171708) (xy 372.840031 -259.173725) (xy 372.787726 -259.167687)
			(xy 372.736955 -259.153735) (xy 372.68891 -259.132196) (xy 372.644715 -259.103576) (xy 372.605407 -259.068545)
			(xy 372.571907 -259.027924) (xy 372.545001 -258.982665) (xy 372.525318 -258.93383) (xy 372.513321 -258.882562)
			(xy 372.509291 -258.830064) (xy 371.418612 -258.830064) (xy 371.418108 -258.85639) (xy 371.410071 -258.908426)
			(xy 371.394185 -258.958625) (xy 371.370822 -259.00581) (xy 371.34053 -259.048876) (xy 371.304018 -259.086814)
			(xy 371.262144 -259.118733) (xy 371.215888 -259.143886) (xy 371.166335 -259.161684) (xy 371.114645 -259.171708)
			(xy 371.062031 -259.173725) (xy 371.009726 -259.167687) (xy 370.958955 -259.153735) (xy 370.91091 -259.132196)
			(xy 370.866715 -259.103576) (xy 370.827407 -259.068545) (xy 370.793907 -259.027924) (xy 370.767001 -258.982665)
			(xy 370.747318 -258.93383) (xy 370.735321 -258.882562) (xy 370.731291 -258.830064) (xy 369.493038 -258.830064)
			(xy 369.492534 -258.85639) (xy 369.484497 -258.908426) (xy 369.468611 -258.958625) (xy 369.445248 -259.00581)
			(xy 369.414956 -259.048876) (xy 369.378444 -259.086814) (xy 369.33657 -259.118733) (xy 369.290314 -259.143886)
			(xy 369.240761 -259.161684) (xy 369.189071 -259.171708) (xy 369.136457 -259.173725) (xy 369.084152 -259.167687)
			(xy 369.033381 -259.153735) (xy 368.985336 -259.132196) (xy 368.941141 -259.103576) (xy 368.901833 -259.068545)
			(xy 368.868333 -259.027924) (xy 368.841427 -258.982665) (xy 368.821744 -258.93383) (xy 368.809747 -258.882562)
			(xy 368.805717 -258.830064) (xy 364.46375 -258.830064) (xy 364.457331 -258.872246) (xy 364.441913 -258.921786)
			(xy 364.419233 -258.96845) (xy 364.40491 -258.990084) (xy 364.400026 -258.997948) (xy 364.395669 -259.015924)
			(xy 364.397928 -259.034282) (xy 364.401862 -259.042662) (xy 364.442756 -259.120386) (xy 364.447413 -259.128341)
			(xy 364.461248 -259.140501) (xy 364.478502 -259.146946) (xy 364.487714 -259.14731) (xy 365.051594 -259.14731)
			(xy 365.05746 -259.147154) (xy 365.068877 -259.144447) (xy 365.0742 -259.141976) (xy 365.092996 -259.132578)
			(xy 365.103156 -259.12572) (xy 365.107474 -259.122418) (xy 365.110522 -259.118354) (xy 365.126898 -259.098231)
			(xy 365.16468 -259.062677) (xy 365.207378 -259.033209) (xy 365.254022 -259.010495) (xy 365.303551 -258.995054)
			(xy 365.354838 -258.987235) (xy 365.380778 -258.986782) (xy 365.407334 -258.987283) (xy 365.459812 -258.995467)
			(xy 365.510405 -259.011628) (xy 365.55791 -259.035382) (xy 365.601193 -259.066162) (xy 365.639225 -259.103236)
			(xy 365.6711 -259.14572) (xy 365.696058 -259.192603) (xy 365.713505 -259.242767) (xy 365.723026 -259.295019)
			(xy 365.724186 -259.321554) (xy 365.724186 -259.325364) (xy 365.724186 -259.33019) (xy 365.723722 -259.355663)
			(xy 365.716192 -259.406049) (xy 365.701296 -259.454769) (xy 365.679361 -259.500751) (xy 365.650869 -259.542985)
			(xy 365.634016 -259.562092) (xy 365.627412 -259.569458) (xy 365.620554 -259.587492) (xy 365.620808 -259.597652)
			(xy 365.621481 -259.607382) (xy 365.629177 -259.625286) (xy 365.635794 -259.63245) (xy 365.73333 -259.729986)
			(xy 368.805717 -259.729986) (xy 368.809747 -259.677488) (xy 368.821744 -259.62622) (xy 368.841427 -259.577385)
			(xy 368.868333 -259.532126) (xy 368.901833 -259.491505) (xy 368.941141 -259.456474) (xy 368.985336 -259.427854)
			(xy 369.033381 -259.406315) (xy 369.084152 -259.392363) (xy 369.136457 -259.386325) (xy 369.189071 -259.388342)
			(xy 369.240761 -259.398366) (xy 369.290314 -259.416164) (xy 369.33657 -259.441317) (xy 369.378444 -259.473236)
			(xy 369.414956 -259.511174) (xy 369.445248 -259.55424) (xy 369.468611 -259.601425) (xy 369.484497 -259.651624)
			(xy 369.492534 -259.70366) (xy 369.493038 -259.729986) (xy 370.731291 -259.729986) (xy 370.735321 -259.677488)
			(xy 370.747318 -259.62622) (xy 370.767001 -259.577385) (xy 370.793907 -259.532126) (xy 370.827407 -259.491505)
			(xy 370.866715 -259.456474) (xy 370.91091 -259.427854) (xy 370.958955 -259.406315) (xy 371.009726 -259.392363)
			(xy 371.062031 -259.386325) (xy 371.114645 -259.388342) (xy 371.166335 -259.398366) (xy 371.215888 -259.416164)
			(xy 371.262144 -259.441317) (xy 371.304018 -259.473236) (xy 371.34053 -259.511174) (xy 371.370822 -259.55424)
			(xy 371.394185 -259.601425) (xy 371.410071 -259.651624) (xy 371.418108 -259.70366) (xy 371.418612 -259.729986)
			(xy 372.509291 -259.729986) (xy 372.513321 -259.677488) (xy 372.525318 -259.62622) (xy 372.545001 -259.577385)
			(xy 372.571907 -259.532126) (xy 372.605407 -259.491505) (xy 372.644715 -259.456474) (xy 372.68891 -259.427854)
			(xy 372.736955 -259.406315) (xy 372.787726 -259.392363) (xy 372.840031 -259.386325) (xy 372.892645 -259.388342)
			(xy 372.944335 -259.398366) (xy 372.993888 -259.416164) (xy 373.040144 -259.441317) (xy 373.082018 -259.473236)
			(xy 373.11853 -259.511174) (xy 373.148822 -259.55424) (xy 373.172185 -259.601425) (xy 373.188071 -259.651624)
			(xy 373.196108 -259.70366) (xy 373.196612 -259.729986) (xy 373.196108 -259.756312) (xy 373.188071 -259.808348)
			(xy 373.172185 -259.858547) (xy 373.148822 -259.905732) (xy 373.11853 -259.948798) (xy 373.082018 -259.986736)
			(xy 373.040144 -260.018655) (xy 372.993888 -260.043808) (xy 372.944335 -260.061606) (xy 372.892645 -260.07163)
			(xy 372.840031 -260.073647) (xy 372.787726 -260.067609) (xy 372.736955 -260.053657) (xy 372.68891 -260.032118)
			(xy 372.644715 -260.003498) (xy 372.605407 -259.968467) (xy 372.571907 -259.927846) (xy 372.545001 -259.882587)
			(xy 372.525318 -259.833752) (xy 372.513321 -259.782484) (xy 372.509291 -259.729986) (xy 371.418612 -259.729986)
			(xy 371.418108 -259.756312) (xy 371.410071 -259.808348) (xy 371.394185 -259.858547) (xy 371.370822 -259.905732)
			(xy 371.34053 -259.948798) (xy 371.304018 -259.986736) (xy 371.262144 -260.018655) (xy 371.215888 -260.043808)
			(xy 371.166335 -260.061606) (xy 371.114645 -260.07163) (xy 371.062031 -260.073647) (xy 371.009726 -260.067609)
			(xy 370.958955 -260.053657) (xy 370.91091 -260.032118) (xy 370.866715 -260.003498) (xy 370.827407 -259.968467)
			(xy 370.793907 -259.927846) (xy 370.767001 -259.882587) (xy 370.747318 -259.833752) (xy 370.735321 -259.782484)
			(xy 370.731291 -259.729986) (xy 369.493038 -259.729986) (xy 369.492534 -259.756312) (xy 369.484497 -259.808348)
			(xy 369.468611 -259.858547) (xy 369.445248 -259.905732) (xy 369.414956 -259.948798) (xy 369.378444 -259.986736)
			(xy 369.33657 -260.018655) (xy 369.290314 -260.043808) (xy 369.240761 -260.061606) (xy 369.189071 -260.07163)
			(xy 369.136457 -260.073647) (xy 369.084152 -260.067609) (xy 369.033381 -260.053657) (xy 368.985336 -260.032118)
			(xy 368.941141 -260.003498) (xy 368.901833 -259.968467) (xy 368.868333 -259.927846) (xy 368.841427 -259.882587)
			(xy 368.821744 -259.833752) (xy 368.809747 -259.782484) (xy 368.805717 -259.729986) (xy 365.73333 -259.729986)
			(xy 366.024922 -260.021578) (xy 366.031639 -260.028815) (xy 366.039244 -260.047019) (xy 366.039654 -260.056884)
			(xy 366.039654 -260.269228) (xy 366.040115 -260.279105) (xy 366.047555 -260.297405) (xy 366.054132 -260.304788)
			(xy 366.054386 -260.305042) (xy 366.227868 -260.478524) (xy 366.228376 -260.479032) (xy 366.235757 -260.485613)
			(xy 366.254057 -260.493058) (xy 366.263936 -260.49351) (xy 369.647978 -260.49351) (xy 369.657815 -260.494048)
			(xy 369.675973 -260.501638) (xy 369.683284 -260.508242) (xy 370.035328 -260.860286) (xy 370.040916 -260.863588)
			(xy 370.062403 -260.876957) (xy 370.101023 -260.909654) (xy 370.133724 -260.94827) (xy 370.147088 -260.96976)
			(xy 370.15039 -260.975348) (xy 370.301012 -261.12597) (xy 371.45901 -261.12597) (xy 371.46297 -261.076916)
			(xy 371.474747 -261.029132) (xy 371.494038 -260.983856) (xy 371.520341 -260.94226) (xy 371.552976 -260.905423)
			(xy 371.591097 -260.874298) (xy 371.633718 -260.849691) (xy 371.679734 -260.832239) (xy 371.727953 -260.822395)
			(xy 371.777128 -260.820414) (xy 371.825983 -260.826346) (xy 371.873254 -260.840038) (xy 371.917716 -260.861136)
			(xy 371.958219 -260.889092) (xy 371.993712 -260.923184) (xy 372.023277 -260.962528) (xy 372.046148 -261.006105)
			(xy 372.061732 -261.052786) (xy 372.069627 -261.101363) (xy 372.070122 -261.12597) (xy 373.339118 -261.12597)
			(xy 373.343078 -261.076916) (xy 373.354855 -261.029132) (xy 373.374146 -260.983856) (xy 373.400449 -260.94226)
			(xy 373.433084 -260.905423) (xy 373.471205 -260.874298) (xy 373.513826 -260.849691) (xy 373.559842 -260.832239)
			(xy 373.608061 -260.822395) (xy 373.657236 -260.820414) (xy 373.706091 -260.826346) (xy 373.753362 -260.840038)
			(xy 373.797824 -260.861136) (xy 373.838327 -260.889092) (xy 373.87382 -260.923184) (xy 373.903385 -260.962528)
			(xy 373.926256 -261.006105) (xy 373.94184 -261.052786) (xy 373.949735 -261.101363) (xy 373.95023 -261.12597)
			(xy 375.218972 -261.12597) (xy 375.222932 -261.076916) (xy 375.234709 -261.029132) (xy 375.254 -260.983856)
			(xy 375.280303 -260.94226) (xy 375.312938 -260.905423) (xy 375.351059 -260.874298) (xy 375.39368 -260.849691)
			(xy 375.439696 -260.832239) (xy 375.487915 -260.822395) (xy 375.53709 -260.820414) (xy 375.585945 -260.826346)
			(xy 375.633216 -260.840038) (xy 375.677678 -260.861136) (xy 375.718181 -260.889092) (xy 375.753674 -260.923184)
			(xy 375.783239 -260.962528) (xy 375.80611 -261.006105) (xy 375.821694 -261.052786) (xy 375.829589 -261.101363)
			(xy 375.830084 -261.12597) (xy 376.159026 -261.12597) (xy 376.162986 -261.076916) (xy 376.174763 -261.029132)
			(xy 376.194054 -260.983856) (xy 376.220357 -260.94226) (xy 376.252992 -260.905423) (xy 376.291113 -260.874298)
			(xy 376.333734 -260.849691) (xy 376.37975 -260.832239) (xy 376.427969 -260.822395) (xy 376.477144 -260.820414)
			(xy 376.525999 -260.826346) (xy 376.57327 -260.840038) (xy 376.617732 -260.861136) (xy 376.658235 -260.889092)
			(xy 376.693728 -260.923184) (xy 376.723293 -260.962528) (xy 376.746164 -261.006105) (xy 376.761748 -261.052786)
			(xy 376.769643 -261.101363) (xy 376.770138 -261.12597) (xy 377.09908 -261.12597) (xy 377.10304 -261.076916)
			(xy 377.114817 -261.029132) (xy 377.134108 -260.983856) (xy 377.160411 -260.94226) (xy 377.193046 -260.905423)
			(xy 377.231167 -260.874298) (xy 377.273788 -260.849691) (xy 377.319804 -260.832239) (xy 377.368023 -260.822395)
			(xy 377.417198 -260.820414) (xy 377.466053 -260.826346) (xy 377.513324 -260.840038) (xy 377.557786 -260.861136)
			(xy 377.598289 -260.889092) (xy 377.633782 -260.923184) (xy 377.663347 -260.962528) (xy 377.686218 -261.006105)
			(xy 377.701802 -261.052786) (xy 377.709697 -261.101363) (xy 377.710192 -261.12597) (xy 378.039134 -261.12597)
			(xy 378.043094 -261.076916) (xy 378.054871 -261.029132) (xy 378.074162 -260.983856) (xy 378.100465 -260.94226)
			(xy 378.1331 -260.905423) (xy 378.171221 -260.874298) (xy 378.213842 -260.849691) (xy 378.259858 -260.832239)
			(xy 378.308077 -260.822395) (xy 378.357252 -260.820414) (xy 378.406107 -260.826346) (xy 378.453378 -260.840038)
			(xy 378.49784 -260.861136) (xy 378.538343 -260.889092) (xy 378.573836 -260.923184) (xy 378.603401 -260.962528)
			(xy 378.626272 -261.006105) (xy 378.641856 -261.052786) (xy 378.649751 -261.101363) (xy 378.650246 -261.12597)
			(xy 378.978934 -261.12597) (xy 378.982894 -261.076916) (xy 378.994671 -261.029132) (xy 379.013962 -260.983856)
			(xy 379.040265 -260.94226) (xy 379.0729 -260.905423) (xy 379.111021 -260.874298) (xy 379.153642 -260.849691)
			(xy 379.199658 -260.832239) (xy 379.247877 -260.822395) (xy 379.297052 -260.820414) (xy 379.345907 -260.826346)
			(xy 379.393178 -260.840038) (xy 379.43764 -260.861136) (xy 379.478143 -260.889092) (xy 379.513636 -260.923184)
			(xy 379.543201 -260.962528) (xy 379.566072 -261.006105) (xy 379.581656 -261.052786) (xy 379.589551 -261.101363)
			(xy 379.590046 -261.12597) (xy 379.918988 -261.12597) (xy 379.922948 -261.076916) (xy 379.934725 -261.029132)
			(xy 379.954016 -260.983856) (xy 379.980319 -260.94226) (xy 380.012954 -260.905423) (xy 380.051075 -260.874298)
			(xy 380.093696 -260.849691) (xy 380.139712 -260.832239) (xy 380.187931 -260.822395) (xy 380.237106 -260.820414)
			(xy 380.285961 -260.826346) (xy 380.333232 -260.840038) (xy 380.377694 -260.861136) (xy 380.418197 -260.889092)
			(xy 380.45369 -260.923184) (xy 380.483255 -260.962528) (xy 380.506126 -261.006105) (xy 380.52171 -261.052786)
			(xy 380.529605 -261.101363) (xy 380.5301 -261.12597) (xy 380.859042 -261.12597) (xy 380.863002 -261.076916)
			(xy 380.874779 -261.029132) (xy 380.89407 -260.983856) (xy 380.920373 -260.94226) (xy 380.953008 -260.905423)
			(xy 380.991129 -260.874298) (xy 381.03375 -260.849691) (xy 381.079766 -260.832239) (xy 381.127985 -260.822395)
			(xy 381.17716 -260.820414) (xy 381.226015 -260.826346) (xy 381.273286 -260.840038) (xy 381.317748 -260.861136)
			(xy 381.358251 -260.889092) (xy 381.393744 -260.923184) (xy 381.423309 -260.962528) (xy 381.44618 -261.006105)
			(xy 381.461764 -261.052786) (xy 381.469659 -261.101363) (xy 381.470154 -261.12597) (xy 381.799096 -261.12597)
			(xy 381.803056 -261.076916) (xy 381.814833 -261.029132) (xy 381.834124 -260.983856) (xy 381.860427 -260.94226)
			(xy 381.893062 -260.905423) (xy 381.931183 -260.874298) (xy 381.973804 -260.849691) (xy 382.01982 -260.832239)
			(xy 382.068039 -260.822395) (xy 382.117214 -260.820414) (xy 382.166069 -260.826346) (xy 382.21334 -260.840038)
			(xy 382.257802 -260.861136) (xy 382.298305 -260.889092) (xy 382.333798 -260.923184) (xy 382.363363 -260.962528)
			(xy 382.386234 -261.006105) (xy 382.401818 -261.052786) (xy 382.409713 -261.101363) (xy 382.410208 -261.12597)
			(xy 382.738896 -261.12597) (xy 382.742856 -261.076916) (xy 382.754633 -261.029132) (xy 382.773924 -260.983856)
			(xy 382.800227 -260.94226) (xy 382.832862 -260.905423) (xy 382.870983 -260.874298) (xy 382.913604 -260.849691)
			(xy 382.95962 -260.832239) (xy 383.007839 -260.822395) (xy 383.057014 -260.820414) (xy 383.105869 -260.826346)
			(xy 383.15314 -260.840038) (xy 383.197602 -260.861136) (xy 383.238105 -260.889092) (xy 383.273598 -260.923184)
			(xy 383.303163 -260.962528) (xy 383.326034 -261.006105) (xy 383.341618 -261.052786) (xy 383.349513 -261.101363)
			(xy 383.350008 -261.12597) (xy 383.67895 -261.12597) (xy 383.68291 -261.076916) (xy 383.694687 -261.029132)
			(xy 383.713978 -260.983856) (xy 383.740281 -260.94226) (xy 383.772916 -260.905423) (xy 383.811037 -260.874298)
			(xy 383.853658 -260.849691) (xy 383.899674 -260.832239) (xy 383.947893 -260.822395) (xy 383.997068 -260.820414)
			(xy 384.045923 -260.826346) (xy 384.093194 -260.840038) (xy 384.137656 -260.861136) (xy 384.178159 -260.889092)
			(xy 384.213652 -260.923184) (xy 384.243217 -260.962528) (xy 384.266088 -261.006105) (xy 384.281672 -261.052786)
			(xy 384.289567 -261.101363) (xy 384.290062 -261.12597) (xy 384.619004 -261.12597) (xy 384.622964 -261.076916)
			(xy 384.634741 -261.029132) (xy 384.654032 -260.983856) (xy 384.680335 -260.94226) (xy 384.71297 -260.905423)
			(xy 384.751091 -260.874298) (xy 384.793712 -260.849691) (xy 384.839728 -260.832239) (xy 384.887947 -260.822395)
			(xy 384.937122 -260.820414) (xy 384.985977 -260.826346) (xy 385.033248 -260.840038) (xy 385.07771 -260.861136)
			(xy 385.118213 -260.889092) (xy 385.153706 -260.923184) (xy 385.183271 -260.962528) (xy 385.206142 -261.006105)
			(xy 385.221726 -261.052786) (xy 385.229621 -261.101363) (xy 385.230116 -261.12597) (xy 385.229621 -261.150577)
			(xy 385.221726 -261.199154) (xy 385.206142 -261.245835) (xy 385.183271 -261.289412) (xy 385.153706 -261.328756)
			(xy 385.118213 -261.362848) (xy 385.07771 -261.390804) (xy 385.033248 -261.411902) (xy 384.985977 -261.425594)
			(xy 384.937122 -261.431526) (xy 384.887947 -261.429545) (xy 384.839728 -261.419701) (xy 384.793712 -261.402249)
			(xy 384.751091 -261.377642) (xy 384.71297 -261.346517) (xy 384.680335 -261.30968) (xy 384.654032 -261.268084)
			(xy 384.634741 -261.222808) (xy 384.622964 -261.175024) (xy 384.619004 -261.12597) (xy 384.290062 -261.12597)
			(xy 384.289567 -261.150577) (xy 384.281672 -261.199154) (xy 384.266088 -261.245835) (xy 384.243217 -261.289412)
			(xy 384.213652 -261.328756) (xy 384.178159 -261.362848) (xy 384.137656 -261.390804) (xy 384.093194 -261.411902)
			(xy 384.045923 -261.425594) (xy 383.997068 -261.431526) (xy 383.947893 -261.429545) (xy 383.899674 -261.419701)
			(xy 383.853658 -261.402249) (xy 383.811037 -261.377642) (xy 383.772916 -261.346517) (xy 383.740281 -261.30968)
			(xy 383.713978 -261.268084) (xy 383.694687 -261.222808) (xy 383.68291 -261.175024) (xy 383.67895 -261.12597)
			(xy 383.350008 -261.12597) (xy 383.349513 -261.150577) (xy 383.341618 -261.199154) (xy 383.326034 -261.245835)
			(xy 383.303163 -261.289412) (xy 383.273598 -261.328756) (xy 383.238105 -261.362848) (xy 383.197602 -261.390804)
			(xy 383.15314 -261.411902) (xy 383.105869 -261.425594) (xy 383.057014 -261.431526) (xy 383.007839 -261.429545)
			(xy 382.95962 -261.419701) (xy 382.913604 -261.402249) (xy 382.870983 -261.377642) (xy 382.832862 -261.346517)
			(xy 382.800227 -261.30968) (xy 382.773924 -261.268084) (xy 382.754633 -261.222808) (xy 382.742856 -261.175024)
			(xy 382.738896 -261.12597) (xy 382.410208 -261.12597) (xy 382.409713 -261.150577) (xy 382.401818 -261.199154)
			(xy 382.386234 -261.245835) (xy 382.363363 -261.289412) (xy 382.333798 -261.328756) (xy 382.298305 -261.362848)
			(xy 382.257802 -261.390804) (xy 382.21334 -261.411902) (xy 382.166069 -261.425594) (xy 382.117214 -261.431526)
			(xy 382.068039 -261.429545) (xy 382.01982 -261.419701) (xy 381.973804 -261.402249) (xy 381.931183 -261.377642)
			(xy 381.893062 -261.346517) (xy 381.860427 -261.30968) (xy 381.834124 -261.268084) (xy 381.814833 -261.222808)
			(xy 381.803056 -261.175024) (xy 381.799096 -261.12597) (xy 381.470154 -261.12597) (xy 381.469659 -261.150577)
			(xy 381.461764 -261.199154) (xy 381.44618 -261.245835) (xy 381.423309 -261.289412) (xy 381.393744 -261.328756)
			(xy 381.358251 -261.362848) (xy 381.317748 -261.390804) (xy 381.273286 -261.411902) (xy 381.226015 -261.425594)
			(xy 381.17716 -261.431526) (xy 381.127985 -261.429545) (xy 381.079766 -261.419701) (xy 381.03375 -261.402249)
			(xy 380.991129 -261.377642) (xy 380.953008 -261.346517) (xy 380.920373 -261.30968) (xy 380.89407 -261.268084)
			(xy 380.874779 -261.222808) (xy 380.863002 -261.175024) (xy 380.859042 -261.12597) (xy 380.5301 -261.12597)
			(xy 380.529605 -261.150577) (xy 380.52171 -261.199154) (xy 380.506126 -261.245835) (xy 380.483255 -261.289412)
			(xy 380.45369 -261.328756) (xy 380.418197 -261.362848) (xy 380.377694 -261.390804) (xy 380.333232 -261.411902)
			(xy 380.285961 -261.425594) (xy 380.237106 -261.431526) (xy 380.187931 -261.429545) (xy 380.139712 -261.419701)
			(xy 380.093696 -261.402249) (xy 380.051075 -261.377642) (xy 380.012954 -261.346517) (xy 379.980319 -261.30968)
			(xy 379.954016 -261.268084) (xy 379.934725 -261.222808) (xy 379.922948 -261.175024) (xy 379.918988 -261.12597)
			(xy 379.590046 -261.12597) (xy 379.589551 -261.150577) (xy 379.581656 -261.199154) (xy 379.566072 -261.245835)
			(xy 379.543201 -261.289412) (xy 379.513636 -261.328756) (xy 379.478143 -261.362848) (xy 379.43764 -261.390804)
			(xy 379.393178 -261.411902) (xy 379.345907 -261.425594) (xy 379.297052 -261.431526) (xy 379.247877 -261.429545)
			(xy 379.199658 -261.419701) (xy 379.153642 -261.402249) (xy 379.111021 -261.377642) (xy 379.0729 -261.346517)
			(xy 379.040265 -261.30968) (xy 379.013962 -261.268084) (xy 378.994671 -261.222808) (xy 378.982894 -261.175024)
			(xy 378.978934 -261.12597) (xy 378.650246 -261.12597) (xy 378.649751 -261.150577) (xy 378.641856 -261.199154)
			(xy 378.626272 -261.245835) (xy 378.603401 -261.289412) (xy 378.573836 -261.328756) (xy 378.538343 -261.362848)
			(xy 378.49784 -261.390804) (xy 378.453378 -261.411902) (xy 378.406107 -261.425594) (xy 378.357252 -261.431526)
			(xy 378.308077 -261.429545) (xy 378.259858 -261.419701) (xy 378.213842 -261.402249) (xy 378.171221 -261.377642)
			(xy 378.1331 -261.346517) (xy 378.100465 -261.30968) (xy 378.074162 -261.268084) (xy 378.054871 -261.222808)
			(xy 378.043094 -261.175024) (xy 378.039134 -261.12597) (xy 377.710192 -261.12597) (xy 377.709697 -261.150577)
			(xy 377.701802 -261.199154) (xy 377.686218 -261.245835) (xy 377.663347 -261.289412) (xy 377.633782 -261.328756)
			(xy 377.598289 -261.362848) (xy 377.557786 -261.390804) (xy 377.513324 -261.411902) (xy 377.466053 -261.425594)
			(xy 377.417198 -261.431526) (xy 377.368023 -261.429545) (xy 377.319804 -261.419701) (xy 377.273788 -261.402249)
			(xy 377.231167 -261.377642) (xy 377.193046 -261.346517) (xy 377.160411 -261.30968) (xy 377.134108 -261.268084)
			(xy 377.114817 -261.222808) (xy 377.10304 -261.175024) (xy 377.09908 -261.12597) (xy 376.770138 -261.12597)
			(xy 376.769643 -261.150577) (xy 376.761748 -261.199154) (xy 376.746164 -261.245835) (xy 376.723293 -261.289412)
			(xy 376.693728 -261.328756) (xy 376.658235 -261.362848) (xy 376.617732 -261.390804) (xy 376.57327 -261.411902)
			(xy 376.525999 -261.425594) (xy 376.477144 -261.431526) (xy 376.427969 -261.429545) (xy 376.37975 -261.419701)
			(xy 376.333734 -261.402249) (xy 376.291113 -261.377642) (xy 376.252992 -261.346517) (xy 376.220357 -261.30968)
			(xy 376.194054 -261.268084) (xy 376.174763 -261.222808) (xy 376.162986 -261.175024) (xy 376.159026 -261.12597)
			(xy 375.830084 -261.12597) (xy 375.829589 -261.150577) (xy 375.821694 -261.199154) (xy 375.80611 -261.245835)
			(xy 375.783239 -261.289412) (xy 375.753674 -261.328756) (xy 375.718181 -261.362848) (xy 375.677678 -261.390804)
			(xy 375.633216 -261.411902) (xy 375.585945 -261.425594) (xy 375.53709 -261.431526) (xy 375.487915 -261.429545)
			(xy 375.439696 -261.419701) (xy 375.39368 -261.402249) (xy 375.351059 -261.377642) (xy 375.312938 -261.346517)
			(xy 375.280303 -261.30968) (xy 375.254 -261.268084) (xy 375.234709 -261.222808) (xy 375.222932 -261.175024)
			(xy 375.218972 -261.12597) (xy 373.95023 -261.12597) (xy 373.949735 -261.150577) (xy 373.94184 -261.199154)
			(xy 373.926256 -261.245835) (xy 373.903385 -261.289412) (xy 373.87382 -261.328756) (xy 373.838327 -261.362848)
			(xy 373.797824 -261.390804) (xy 373.753362 -261.411902) (xy 373.706091 -261.425594) (xy 373.657236 -261.431526)
			(xy 373.608061 -261.429545) (xy 373.559842 -261.419701) (xy 373.513826 -261.402249) (xy 373.471205 -261.377642)
			(xy 373.433084 -261.346517) (xy 373.400449 -261.30968) (xy 373.374146 -261.268084) (xy 373.354855 -261.222808)
			(xy 373.343078 -261.175024) (xy 373.339118 -261.12597) (xy 372.070122 -261.12597) (xy 372.069627 -261.150577)
			(xy 372.061732 -261.199154) (xy 372.046148 -261.245835) (xy 372.023277 -261.289412) (xy 371.993712 -261.328756)
			(xy 371.958219 -261.362848) (xy 371.917716 -261.390804) (xy 371.873254 -261.411902) (xy 371.825983 -261.425594)
			(xy 371.777128 -261.431526) (xy 371.727953 -261.429545) (xy 371.679734 -261.419701) (xy 371.633718 -261.402249)
			(xy 371.591097 -261.377642) (xy 371.552976 -261.346517) (xy 371.520341 -261.30968) (xy 371.494038 -261.268084)
			(xy 371.474747 -261.222808) (xy 371.46297 -261.175024) (xy 371.45901 -261.12597) (xy 370.301012 -261.12597)
			(xy 371.111018 -261.935976) (xy 371.92891 -261.935976) (xy 371.93287 -261.886922) (xy 371.944647 -261.839138)
			(xy 371.963938 -261.793862) (xy 371.990241 -261.752266) (xy 372.022876 -261.715429) (xy 372.060997 -261.684304)
			(xy 372.103618 -261.659697) (xy 372.149634 -261.642245) (xy 372.197853 -261.632401) (xy 372.247028 -261.63042)
			(xy 372.295883 -261.636352) (xy 372.343154 -261.650044) (xy 372.387616 -261.671142) (xy 372.428119 -261.699098)
			(xy 372.463612 -261.73319) (xy 372.493177 -261.772534) (xy 372.516048 -261.816111) (xy 372.531632 -261.862792)
			(xy 372.539527 -261.911369) (xy 372.540022 -261.935976) (xy 373.809018 -261.935976) (xy 373.812978 -261.886922)
			(xy 373.824755 -261.839138) (xy 373.844046 -261.793862) (xy 373.870349 -261.752266) (xy 373.902984 -261.715429)
			(xy 373.941105 -261.684304) (xy 373.983726 -261.659697) (xy 374.029742 -261.642245) (xy 374.077961 -261.632401)
			(xy 374.127136 -261.63042) (xy 374.175991 -261.636352) (xy 374.223262 -261.650044) (xy 374.267724 -261.671142)
			(xy 374.308227 -261.699098) (xy 374.34372 -261.73319) (xy 374.373285 -261.772534) (xy 374.396156 -261.816111)
			(xy 374.41174 -261.862792) (xy 374.419635 -261.911369) (xy 374.42013 -261.935976) (xy 375.678695 -261.935976)
			(xy 375.68279 -261.885248) (xy 375.694969 -261.835834) (xy 375.714917 -261.789014) (xy 375.742118 -261.746)
			(xy 375.775866 -261.707906) (xy 375.815288 -261.675719) (xy 375.859362 -261.650273) (xy 375.906948 -261.632226)
			(xy 375.956812 -261.622046) (xy 376.007664 -261.619997) (xy 376.058185 -261.626131) (xy 376.107069 -261.640291)
			(xy 376.153048 -261.662108) (xy 376.194932 -261.691018) (xy 376.231636 -261.726273) (xy 376.262209 -261.766959)
			(xy 376.28586 -261.812022) (xy 376.301976 -261.860296) (xy 376.31014 -261.91053) (xy 376.310652 -261.935976)
			(xy 376.628926 -261.935976) (xy 376.632886 -261.886922) (xy 376.644663 -261.839138) (xy 376.663954 -261.793862)
			(xy 376.690257 -261.752266) (xy 376.722892 -261.715429) (xy 376.761013 -261.684304) (xy 376.803634 -261.659697)
			(xy 376.84965 -261.642245) (xy 376.897869 -261.632401) (xy 376.947044 -261.63042) (xy 376.995899 -261.636352)
			(xy 377.04317 -261.650044) (xy 377.087632 -261.671142) (xy 377.128135 -261.699098) (xy 377.163628 -261.73319)
			(xy 377.193193 -261.772534) (xy 377.216064 -261.816111) (xy 377.231648 -261.862792) (xy 377.239543 -261.911369)
			(xy 377.240038 -261.935976) (xy 377.56898 -261.935976) (xy 377.57294 -261.886922) (xy 377.584717 -261.839138)
			(xy 377.604008 -261.793862) (xy 377.630311 -261.752266) (xy 377.662946 -261.715429) (xy 377.701067 -261.684304)
			(xy 377.743688 -261.659697) (xy 377.789704 -261.642245) (xy 377.837923 -261.632401) (xy 377.887098 -261.63042)
			(xy 377.935953 -261.636352) (xy 377.983224 -261.650044) (xy 378.027686 -261.671142) (xy 378.068189 -261.699098)
			(xy 378.103682 -261.73319) (xy 378.133247 -261.772534) (xy 378.156118 -261.816111) (xy 378.171702 -261.862792)
			(xy 378.179597 -261.911369) (xy 378.180092 -261.935976) (xy 378.509034 -261.935976) (xy 378.512994 -261.886922)
			(xy 378.524771 -261.839138) (xy 378.544062 -261.793862) (xy 378.570365 -261.752266) (xy 378.603 -261.715429)
			(xy 378.641121 -261.684304) (xy 378.683742 -261.659697) (xy 378.729758 -261.642245) (xy 378.777977 -261.632401)
			(xy 378.827152 -261.63042) (xy 378.876007 -261.636352) (xy 378.923278 -261.650044) (xy 378.96774 -261.671142)
			(xy 379.008243 -261.699098) (xy 379.043736 -261.73319) (xy 379.073301 -261.772534) (xy 379.096172 -261.816111)
			(xy 379.111756 -261.862792) (xy 379.119651 -261.911369) (xy 379.120146 -261.935976) (xy 379.438657 -261.935976)
			(xy 379.442752 -261.885248) (xy 379.454931 -261.835834) (xy 379.474879 -261.789014) (xy 379.50208 -261.746)
			(xy 379.535828 -261.707906) (xy 379.57525 -261.675719) (xy 379.619324 -261.650273) (xy 379.66691 -261.632226)
			(xy 379.716774 -261.622046) (xy 379.767626 -261.619997) (xy 379.818147 -261.626131) (xy 379.867031 -261.640291)
			(xy 379.91301 -261.662108) (xy 379.954894 -261.691018) (xy 379.991598 -261.726273) (xy 380.022171 -261.766959)
			(xy 380.045822 -261.812022) (xy 380.061938 -261.860296) (xy 380.070102 -261.91053) (xy 380.070614 -261.935976)
			(xy 380.388888 -261.935976) (xy 380.392848 -261.886922) (xy 380.404625 -261.839138) (xy 380.423916 -261.793862)
			(xy 380.450219 -261.752266) (xy 380.482854 -261.715429) (xy 380.520975 -261.684304) (xy 380.563596 -261.659697)
			(xy 380.609612 -261.642245) (xy 380.657831 -261.632401) (xy 380.707006 -261.63042) (xy 380.755861 -261.636352)
			(xy 380.803132 -261.650044) (xy 380.847594 -261.671142) (xy 380.888097 -261.699098) (xy 380.92359 -261.73319)
			(xy 380.953155 -261.772534) (xy 380.976026 -261.816111) (xy 380.99161 -261.862792) (xy 380.999505 -261.911369)
			(xy 381 -261.935976) (xy 381.328942 -261.935976) (xy 381.332902 -261.886922) (xy 381.344679 -261.839138)
			(xy 381.36397 -261.793862) (xy 381.390273 -261.752266) (xy 381.422908 -261.715429) (xy 381.461029 -261.684304)
			(xy 381.50365 -261.659697) (xy 381.549666 -261.642245) (xy 381.597885 -261.632401) (xy 381.64706 -261.63042)
			(xy 381.695915 -261.636352) (xy 381.743186 -261.650044) (xy 381.787648 -261.671142) (xy 381.828151 -261.699098)
			(xy 381.863644 -261.73319) (xy 381.893209 -261.772534) (xy 381.91608 -261.816111) (xy 381.931664 -261.862792)
			(xy 381.939559 -261.911369) (xy 381.940054 -261.935976) (xy 382.268996 -261.935976) (xy 382.272956 -261.886922)
			(xy 382.284733 -261.839138) (xy 382.304024 -261.793862) (xy 382.330327 -261.752266) (xy 382.362962 -261.715429)
			(xy 382.401083 -261.684304) (xy 382.443704 -261.659697) (xy 382.48972 -261.642245) (xy 382.537939 -261.632401)
			(xy 382.587114 -261.63042) (xy 382.635969 -261.636352) (xy 382.68324 -261.650044) (xy 382.727702 -261.671142)
			(xy 382.768205 -261.699098) (xy 382.803698 -261.73319) (xy 382.833263 -261.772534) (xy 382.856134 -261.816111)
			(xy 382.871718 -261.862792) (xy 382.879613 -261.911369) (xy 382.880108 -261.935976) (xy 383.20905 -261.935976)
			(xy 383.21301 -261.886922) (xy 383.224787 -261.839138) (xy 383.244078 -261.793862) (xy 383.270381 -261.752266)
			(xy 383.303016 -261.715429) (xy 383.341137 -261.684304) (xy 383.383758 -261.659697) (xy 383.429774 -261.642245)
			(xy 383.477993 -261.632401) (xy 383.527168 -261.63042) (xy 383.576023 -261.636352) (xy 383.623294 -261.650044)
			(xy 383.667756 -261.671142) (xy 383.708259 -261.699098) (xy 383.743752 -261.73319) (xy 383.773317 -261.772534)
			(xy 383.796188 -261.816111) (xy 383.811772 -261.862792) (xy 383.819667 -261.911369) (xy 383.820162 -261.935976)
			(xy 384.149104 -261.935976) (xy 384.153064 -261.886922) (xy 384.164841 -261.839138) (xy 384.184132 -261.793862)
			(xy 384.210435 -261.752266) (xy 384.24307 -261.715429) (xy 384.281191 -261.684304) (xy 384.323812 -261.659697)
			(xy 384.369828 -261.642245) (xy 384.418047 -261.632401) (xy 384.467222 -261.63042) (xy 384.516077 -261.636352)
			(xy 384.563348 -261.650044) (xy 384.60781 -261.671142) (xy 384.648313 -261.699098) (xy 384.683806 -261.73319)
			(xy 384.713371 -261.772534) (xy 384.736242 -261.816111) (xy 384.751826 -261.862792) (xy 384.759721 -261.911369)
			(xy 384.760216 -261.935976) (xy 384.759721 -261.960583) (xy 384.751826 -262.00916) (xy 384.736242 -262.055841)
			(xy 384.713371 -262.099418) (xy 384.683806 -262.138762) (xy 384.648313 -262.172854) (xy 384.60781 -262.20081)
			(xy 384.563348 -262.221908) (xy 384.516077 -262.2356) (xy 384.467222 -262.241532) (xy 384.418047 -262.239551)
			(xy 384.369828 -262.229707) (xy 384.323812 -262.212255) (xy 384.281191 -262.187648) (xy 384.24307 -262.156523)
			(xy 384.210435 -262.119686) (xy 384.184132 -262.07809) (xy 384.164841 -262.032814) (xy 384.153064 -261.98503)
			(xy 384.149104 -261.935976) (xy 383.820162 -261.935976) (xy 383.819667 -261.960583) (xy 383.811772 -262.00916)
			(xy 383.796188 -262.055841) (xy 383.773317 -262.099418) (xy 383.743752 -262.138762) (xy 383.708259 -262.172854)
			(xy 383.667756 -262.20081) (xy 383.623294 -262.221908) (xy 383.576023 -262.2356) (xy 383.527168 -262.241532)
			(xy 383.477993 -262.239551) (xy 383.429774 -262.229707) (xy 383.383758 -262.212255) (xy 383.341137 -262.187648)
			(xy 383.303016 -262.156523) (xy 383.270381 -262.119686) (xy 383.244078 -262.07809) (xy 383.224787 -262.032814)
			(xy 383.21301 -261.98503) (xy 383.20905 -261.935976) (xy 382.880108 -261.935976) (xy 382.879613 -261.960583)
			(xy 382.871718 -262.00916) (xy 382.856134 -262.055841) (xy 382.833263 -262.099418) (xy 382.803698 -262.138762)
			(xy 382.768205 -262.172854) (xy 382.727702 -262.20081) (xy 382.68324 -262.221908) (xy 382.635969 -262.2356)
			(xy 382.587114 -262.241532) (xy 382.537939 -262.239551) (xy 382.48972 -262.229707) (xy 382.443704 -262.212255)
			(xy 382.401083 -262.187648) (xy 382.362962 -262.156523) (xy 382.330327 -262.119686) (xy 382.304024 -262.07809)
			(xy 382.284733 -262.032814) (xy 382.272956 -261.98503) (xy 382.268996 -261.935976) (xy 381.940054 -261.935976)
			(xy 381.939559 -261.960583) (xy 381.931664 -262.00916) (xy 381.91608 -262.055841) (xy 381.893209 -262.099418)
			(xy 381.863644 -262.138762) (xy 381.828151 -262.172854) (xy 381.787648 -262.20081) (xy 381.743186 -262.221908)
			(xy 381.695915 -262.2356) (xy 381.64706 -262.241532) (xy 381.597885 -262.239551) (xy 381.549666 -262.229707)
			(xy 381.50365 -262.212255) (xy 381.461029 -262.187648) (xy 381.422908 -262.156523) (xy 381.390273 -262.119686)
			(xy 381.36397 -262.07809) (xy 381.344679 -262.032814) (xy 381.332902 -261.98503) (xy 381.328942 -261.935976)
			(xy 381 -261.935976) (xy 380.999505 -261.960583) (xy 380.99161 -262.00916) (xy 380.976026 -262.055841)
			(xy 380.953155 -262.099418) (xy 380.92359 -262.138762) (xy 380.888097 -262.172854) (xy 380.847594 -262.20081)
			(xy 380.803132 -262.221908) (xy 380.755861 -262.2356) (xy 380.707006 -262.241532) (xy 380.657831 -262.239551)
			(xy 380.609612 -262.229707) (xy 380.563596 -262.212255) (xy 380.520975 -262.187648) (xy 380.482854 -262.156523)
			(xy 380.450219 -262.119686) (xy 380.423916 -262.07809) (xy 380.404625 -262.032814) (xy 380.392848 -261.98503)
			(xy 380.388888 -261.935976) (xy 380.070614 -261.935976) (xy 380.070102 -261.961422) (xy 380.061938 -262.011656)
			(xy 380.045822 -262.05993) (xy 380.022171 -262.104993) (xy 379.991598 -262.145679) (xy 379.954894 -262.180934)
			(xy 379.91301 -262.209844) (xy 379.867031 -262.231661) (xy 379.818147 -262.245821) (xy 379.767626 -262.251955)
			(xy 379.716774 -262.249906) (xy 379.66691 -262.239726) (xy 379.619324 -262.221679) (xy 379.57525 -262.196233)
			(xy 379.535828 -262.164046) (xy 379.50208 -262.125952) (xy 379.474879 -262.082938) (xy 379.454931 -262.036118)
			(xy 379.442752 -261.986704) (xy 379.438657 -261.935976) (xy 379.120146 -261.935976) (xy 379.119651 -261.960583)
			(xy 379.111756 -262.00916) (xy 379.096172 -262.055841) (xy 379.073301 -262.099418) (xy 379.043736 -262.138762)
			(xy 379.008243 -262.172854) (xy 378.96774 -262.20081) (xy 378.923278 -262.221908) (xy 378.876007 -262.2356)
			(xy 378.827152 -262.241532) (xy 378.777977 -262.239551) (xy 378.729758 -262.229707) (xy 378.683742 -262.212255)
			(xy 378.641121 -262.187648) (xy 378.603 -262.156523) (xy 378.570365 -262.119686) (xy 378.544062 -262.07809)
			(xy 378.524771 -262.032814) (xy 378.512994 -261.98503) (xy 378.509034 -261.935976) (xy 378.180092 -261.935976)
			(xy 378.179597 -261.960583) (xy 378.171702 -262.00916) (xy 378.156118 -262.055841) (xy 378.133247 -262.099418)
			(xy 378.103682 -262.138762) (xy 378.068189 -262.172854) (xy 378.027686 -262.20081) (xy 377.983224 -262.221908)
			(xy 377.935953 -262.2356) (xy 377.887098 -262.241532) (xy 377.837923 -262.239551) (xy 377.789704 -262.229707)
			(xy 377.743688 -262.212255) (xy 377.701067 -262.187648) (xy 377.662946 -262.156523) (xy 377.630311 -262.119686)
			(xy 377.604008 -262.07809) (xy 377.584717 -262.032814) (xy 377.57294 -261.98503) (xy 377.56898 -261.935976)
			(xy 377.240038 -261.935976) (xy 377.239543 -261.960583) (xy 377.231648 -262.00916) (xy 377.216064 -262.055841)
			(xy 377.193193 -262.099418) (xy 377.163628 -262.138762) (xy 377.128135 -262.172854) (xy 377.087632 -262.20081)
			(xy 377.04317 -262.221908) (xy 376.995899 -262.2356) (xy 376.947044 -262.241532) (xy 376.897869 -262.239551)
			(xy 376.84965 -262.229707) (xy 376.803634 -262.212255) (xy 376.761013 -262.187648) (xy 376.722892 -262.156523)
			(xy 376.690257 -262.119686) (xy 376.663954 -262.07809) (xy 376.644663 -262.032814) (xy 376.632886 -261.98503)
			(xy 376.628926 -261.935976) (xy 376.310652 -261.935976) (xy 376.31014 -261.961422) (xy 376.301976 -262.011656)
			(xy 376.28586 -262.05993) (xy 376.262209 -262.104993) (xy 376.231636 -262.145679) (xy 376.194932 -262.180934)
			(xy 376.153048 -262.209844) (xy 376.107069 -262.231661) (xy 376.058185 -262.245821) (xy 376.007664 -262.251955)
			(xy 375.956812 -262.249906) (xy 375.906948 -262.239726) (xy 375.859362 -262.221679) (xy 375.815288 -262.196233)
			(xy 375.775866 -262.164046) (xy 375.742118 -262.125952) (xy 375.714917 -262.082938) (xy 375.694969 -262.036118)
			(xy 375.68279 -261.986704) (xy 375.678695 -261.935976) (xy 374.42013 -261.935976) (xy 374.419635 -261.960583)
			(xy 374.41174 -262.00916) (xy 374.396156 -262.055841) (xy 374.373285 -262.099418) (xy 374.34372 -262.138762)
			(xy 374.308227 -262.172854) (xy 374.267724 -262.20081) (xy 374.223262 -262.221908) (xy 374.175991 -262.2356)
			(xy 374.127136 -262.241532) (xy 374.077961 -262.239551) (xy 374.029742 -262.229707) (xy 373.983726 -262.212255)
			(xy 373.941105 -262.187648) (xy 373.902984 -262.156523) (xy 373.870349 -262.119686) (xy 373.844046 -262.07809)
			(xy 373.824755 -262.032814) (xy 373.812978 -261.98503) (xy 373.809018 -261.935976) (xy 372.540022 -261.935976)
			(xy 372.539527 -261.960583) (xy 372.531632 -262.00916) (xy 372.516048 -262.055841) (xy 372.493177 -262.099418)
			(xy 372.463612 -262.138762) (xy 372.428119 -262.172854) (xy 372.387616 -262.20081) (xy 372.343154 -262.221908)
			(xy 372.295883 -262.2356) (xy 372.247028 -262.241532) (xy 372.197853 -262.239551) (xy 372.149634 -262.229707)
			(xy 372.103618 -262.212255) (xy 372.060997 -262.187648) (xy 372.022876 -262.156523) (xy 371.990241 -262.119686)
			(xy 371.963938 -262.07809) (xy 371.944647 -262.032814) (xy 371.93287 -261.98503) (xy 371.92891 -261.935976)
			(xy 371.111018 -261.935976) (xy 371.618256 -262.443214) (xy 371.625171 -262.449639) (xy 371.642403 -262.457311)
			(xy 371.661244 -262.458237) (xy 371.670326 -262.45566) (xy 371.692951 -262.448765) (xy 371.739644 -262.441241)
			(xy 371.76329 -262.440674) (xy 371.76837 -262.440674) (xy 371.792175 -262.441409) (xy 371.839132 -262.449355)
			(xy 371.884285 -262.464498) (xy 371.926539 -262.486469) (xy 371.964868 -262.514736) (xy 371.998341 -262.548612)
			(xy 372.026148 -262.587276) (xy 372.047612 -262.62979) (xy 372.062213 -262.675121) (xy 372.069596 -262.72217)
			(xy 372.070122 -262.745982) (xy 372.070122 -262.753348) (xy 372.069868 -262.763254) (xy 372.077234 -262.78205)
			(xy 372.13413 -262.84047) (xy 372.141556 -262.847415) (xy 372.160293 -262.855266) (xy 372.170452 -262.85571)
			(xy 373.239792 -262.85571) (xy 373.249717 -262.855152) (xy 373.26801 -262.847427) (xy 373.275352 -262.840724)
			(xy 373.325136 -262.789416) (xy 373.33168 -262.782088) (xy 373.33912 -262.763923) (xy 373.339614 -262.75411)
			(xy 373.339614 -262.745982) (xy 373.340136 -262.720727) (xy 373.348449 -262.670905) (xy 373.36485 -262.623131)
			(xy 373.388891 -262.578708) (xy 373.419915 -262.538848) (xy 373.457077 -262.504638) (xy 373.499363 -262.477012)
			(xy 373.545619 -262.456722) (xy 373.594584 -262.444322) (xy 373.644922 -262.440151) (xy 373.69526 -262.444322)
			(xy 373.744225 -262.456722) (xy 373.790481 -262.477012) (xy 373.832767 -262.504638) (xy 373.869929 -262.538848)
			(xy 373.900953 -262.578708) (xy 373.924994 -262.623131) (xy 373.941395 -262.670905) (xy 373.949708 -262.720727)
			(xy 373.95023 -262.745982) (xy 373.95023 -262.753348) (xy 373.949976 -262.763254) (xy 373.957342 -262.78205)
			(xy 374.014238 -262.84047) (xy 374.021664 -262.847414) (xy 374.040401 -262.855262) (xy 374.05056 -262.85571)
			(xy 375.119646 -262.85571) (xy 375.129574 -262.855161) (xy 375.14788 -262.847447) (xy 375.155206 -262.840724)
			(xy 375.20499 -262.789416) (xy 375.211528 -262.782085) (xy 375.21896 -262.763922) (xy 375.219468 -262.75411)
			(xy 375.219468 -262.745982) (xy 375.21999 -262.720727) (xy 375.228303 -262.670905) (xy 375.244704 -262.623131)
			(xy 375.268745 -262.578708) (xy 375.299769 -262.538848) (xy 375.336931 -262.504638) (xy 375.379217 -262.477012)
			(xy 375.425473 -262.456722) (xy 375.474438 -262.444322) (xy 375.524776 -262.440151) (xy 375.575114 -262.444322)
			(xy 375.624079 -262.456722) (xy 375.670335 -262.477012) (xy 375.712621 -262.504638) (xy 375.749783 -262.538848)
			(xy 375.780807 -262.578708) (xy 375.804848 -262.623131) (xy 375.821249 -262.670905) (xy 375.829562 -262.720727)
			(xy 375.830084 -262.745982) (xy 375.830084 -262.753348) (xy 375.82983 -262.763254) (xy 375.837196 -262.78205)
			(xy 375.894092 -262.84047) (xy 375.901516 -262.847421) (xy 375.920253 -262.855286) (xy 375.930414 -262.85571)
			(xy 376.0597 -262.85571) (xy 376.069624 -262.855151) (xy 376.087915 -262.847424) (xy 376.09526 -262.840724)
			(xy 376.142758 -262.791956) (xy 376.150124 -262.772398) (xy 376.149616 -262.76173) (xy 376.149108 -262.745982)
			(xy 376.149595 -262.721172) (xy 376.157357 -262.672164) (xy 376.17269 -262.624974) (xy 376.195217 -262.580763)
			(xy 376.224382 -262.54062) (xy 376.259468 -262.505534) (xy 376.299611 -262.476369) (xy 376.343822 -262.453842)
			(xy 376.391012 -262.438509) (xy 376.44002 -262.430747) (xy 376.48964 -262.430747) (xy 376.538648 -262.438509)
			(xy 376.585838 -262.453842) (xy 376.630049 -262.476369) (xy 376.670192 -262.505534) (xy 376.705278 -262.54062)
			(xy 376.734443 -262.580763) (xy 376.75697 -262.624974) (xy 376.772303 -262.672164) (xy 376.780065 -262.721172)
			(xy 376.780552 -262.745982) (xy 376.780044 -262.76173) (xy 376.779536 -262.772398) (xy 376.786902 -262.791956)
			(xy 376.834146 -262.84047) (xy 376.841567 -262.847429) (xy 376.860304 -262.855311) (xy 376.870468 -262.85571)
			(xy 376.999754 -262.85571) (xy 377.009682 -262.855159) (xy 377.027985 -262.847444) (xy 377.035314 -262.840724)
			(xy 377.082812 -262.791956) (xy 377.090178 -262.772398) (xy 377.08967 -262.76173) (xy 377.089416 -262.745982)
			(xy 377.089902 -262.721192) (xy 377.097658 -262.672224) (xy 377.112979 -262.625071) (xy 377.135488 -262.580896)
			(xy 377.16463 -262.540785) (xy 377.199687 -262.505728) (xy 377.239798 -262.476586) (xy 377.283973 -262.454077)
			(xy 377.331126 -262.438756) (xy 377.380094 -262.431) (xy 377.429674 -262.431) (xy 377.478642 -262.438756)
			(xy 377.525795 -262.454077) (xy 377.56997 -262.476586) (xy 377.610081 -262.505728) (xy 377.645138 -262.540785)
			(xy 377.67428 -262.580896) (xy 377.696789 -262.625071) (xy 377.71211 -262.672224) (xy 377.719866 -262.721192)
			(xy 377.720352 -262.745982) (xy 377.720098 -262.76173) (xy 377.71959 -262.772398) (xy 377.726956 -262.791956)
			(xy 377.7742 -262.84047) (xy 377.781624 -262.84742) (xy 377.800361 -262.855282) (xy 377.810522 -262.85571)
			(xy 377.939808 -262.85571) (xy 377.94974 -262.855168) (xy 377.968055 -262.847464) (xy 377.975368 -262.840724)
			(xy 378.025152 -262.789416) (xy 378.031694 -262.782087) (xy 378.039132 -262.763923) (xy 378.03963 -262.75411)
			(xy 378.03963 -262.745982) (xy 378.040152 -262.720727) (xy 378.048465 -262.670905) (xy 378.064866 -262.623131)
			(xy 378.088907 -262.578708) (xy 378.119931 -262.538848) (xy 378.157093 -262.504638) (xy 378.199379 -262.477012)
			(xy 378.245635 -262.456722) (xy 378.2946 -262.444322) (xy 378.344938 -262.440151) (xy 378.395276 -262.444322)
			(xy 378.444241 -262.456722) (xy 378.490497 -262.477012) (xy 378.532783 -262.504638) (xy 378.569945 -262.538848)
			(xy 378.600969 -262.578708) (xy 378.62501 -262.623131) (xy 378.641411 -262.670905) (xy 378.649724 -262.720727)
			(xy 378.650246 -262.745982) (xy 378.650246 -262.753348) (xy 378.649992 -262.763254) (xy 378.657358 -262.78205)
			(xy 378.714254 -262.84047) (xy 378.721676 -262.847427) (xy 378.740413 -262.855306) (xy 378.750576 -262.85571)
			(xy 378.879608 -262.85571) (xy 378.88954 -262.855168) (xy 378.907855 -262.847464) (xy 378.915168 -262.840724)
			(xy 378.962666 -262.791956) (xy 378.970032 -262.772398) (xy 378.969524 -262.76173) (xy 378.969016 -262.745982)
			(xy 378.969503 -262.721172) (xy 378.977265 -262.672164) (xy 378.992598 -262.624974) (xy 379.015125 -262.580763)
			(xy 379.04429 -262.54062) (xy 379.079376 -262.505534) (xy 379.119519 -262.476369) (xy 379.16373 -262.453842)
			(xy 379.21092 -262.438509) (xy 379.259928 -262.430747) (xy 379.309548 -262.430747) (xy 379.358556 -262.438509)
			(xy 379.405746 -262.453842) (xy 379.449957 -262.476369) (xy 379.4901 -262.505534) (xy 379.525186 -262.54062)
			(xy 379.554351 -262.580763) (xy 379.576878 -262.624974) (xy 379.592211 -262.672164) (xy 379.599973 -262.721172)
			(xy 379.60046 -262.745982) (xy 379.599952 -262.76173) (xy 379.599444 -262.772398) (xy 379.60681 -262.791956)
			(xy 379.654054 -262.84047) (xy 379.661476 -262.847427) (xy 379.680213 -262.855306) (xy 379.690376 -262.85571)
			(xy 379.819662 -262.85571) (xy 379.829589 -262.855158) (xy 379.84789 -262.84744) (xy 379.855222 -262.840724)
			(xy 379.905006 -262.789416) (xy 379.911553 -262.782089) (xy 379.918998 -262.763924) (xy 379.919484 -262.75411)
			(xy 379.919484 -262.745982) (xy 379.920006 -262.720727) (xy 379.928319 -262.670905) (xy 379.94472 -262.623131)
			(xy 379.968761 -262.578708) (xy 379.999785 -262.538848) (xy 380.036947 -262.504638) (xy 380.079233 -262.477012)
			(xy 380.125489 -262.456722) (xy 380.174454 -262.444322) (xy 380.224792 -262.440151) (xy 380.27513 -262.444322)
			(xy 380.324095 -262.456722) (xy 380.370351 -262.477012) (xy 380.412637 -262.504638) (xy 380.449799 -262.538848)
			(xy 380.480823 -262.578708) (xy 380.504864 -262.623131) (xy 380.521265 -262.670905) (xy 380.529578 -262.720727)
			(xy 380.5301 -262.745982) (xy 380.5301 -262.753348) (xy 380.529846 -262.763254) (xy 380.537212 -262.78205)
			(xy 380.594108 -262.84047) (xy 380.601533 -262.847419) (xy 380.62027 -262.855278) (xy 380.63043 -262.85571)
			(xy 380.759716 -262.85571) (xy 380.769647 -262.855166) (xy 380.78796 -262.84746) (xy 380.795276 -262.840724)
			(xy 380.842774 -262.791956) (xy 380.85014 -262.772398) (xy 380.849632 -262.76173) (xy 380.849124 -262.745982)
			(xy 380.849611 -262.721172) (xy 380.857373 -262.672164) (xy 380.872706 -262.624974) (xy 380.895233 -262.580763)
			(xy 380.924398 -262.54062) (xy 380.959484 -262.505534) (xy 380.999627 -262.476369) (xy 381.043838 -262.453842)
			(xy 381.091028 -262.438509) (xy 381.140036 -262.430747) (xy 381.189656 -262.430747) (xy 381.238664 -262.438509)
			(xy 381.285854 -262.453842) (xy 381.330065 -262.476369) (xy 381.370208 -262.505534) (xy 381.405294 -262.54062)
			(xy 381.434459 -262.580763) (xy 381.456986 -262.624974) (xy 381.472319 -262.672164) (xy 381.480081 -262.721172)
			(xy 381.480568 -262.745982) (xy 381.48006 -262.76173) (xy 381.479552 -262.772398) (xy 381.486918 -262.791956)
			(xy 381.534162 -262.84047) (xy 381.541584 -262.847426) (xy 381.560321 -262.855302) (xy 381.570484 -262.85571)
			(xy 381.69977 -262.85571) (xy 381.709697 -262.855156) (xy 381.727995 -262.847437) (xy 381.73533 -262.840724)
			(xy 381.785114 -262.789416) (xy 381.79166 -262.782089) (xy 381.799104 -262.763924) (xy 381.799592 -262.75411)
			(xy 381.799592 -262.745982) (xy 381.800114 -262.720727) (xy 381.808427 -262.670905) (xy 381.824828 -262.623131)
			(xy 381.848869 -262.578708) (xy 381.879893 -262.538848) (xy 381.917055 -262.504638) (xy 381.959341 -262.477012)
			(xy 382.005597 -262.456722) (xy 382.054562 -262.444322) (xy 382.1049 -262.440151) (xy 382.155238 -262.444322)
			(xy 382.204203 -262.456722) (xy 382.250459 -262.477012) (xy 382.292745 -262.504638) (xy 382.329907 -262.538848)
			(xy 382.360931 -262.578708) (xy 382.384972 -262.623131) (xy 382.401373 -262.670905) (xy 382.409686 -262.720727)
			(xy 382.410208 -262.745982) (xy 382.410208 -262.753348) (xy 382.409954 -262.763254) (xy 382.41732 -262.78205)
			(xy 382.474216 -262.84047) (xy 382.481641 -262.847417) (xy 382.500378 -262.855273) (xy 382.510538 -262.85571)
			(xy 382.63957 -262.85571) (xy 382.649497 -262.855156) (xy 382.667795 -262.847437) (xy 382.67513 -262.840724)
			(xy 382.724914 -262.789416) (xy 382.73146 -262.782089) (xy 382.738904 -262.763924) (xy 382.739392 -262.75411)
			(xy 382.739392 -262.745982) (xy 382.739864 -262.721992) (xy 382.747372 -262.674602) (xy 382.762201 -262.628971)
			(xy 382.783986 -262.58622) (xy 382.81219 -262.547404) (xy 382.846118 -262.513478) (xy 382.884936 -262.485276)
			(xy 382.927687 -262.463494) (xy 382.97332 -262.448668) (xy 383.02071 -262.441163) (xy 383.0447 -262.440674)
			(xy 383.068654 -262.441142) (xy 383.115973 -262.448624) (xy 383.161543 -262.463405) (xy 383.204246 -262.485122)
			(xy 383.243032 -262.513241) (xy 383.276951 -262.547074) (xy 383.30517 -262.585788) (xy 383.326996 -262.628435)
			(xy 383.341893 -262.673967) (xy 383.349496 -262.721268) (xy 383.350008 -262.74522) (xy 383.350008 -262.745982)
			(xy 383.67895 -262.745982) (xy 383.68291 -262.696928) (xy 383.694687 -262.649144) (xy 383.713978 -262.603868)
			(xy 383.740281 -262.562272) (xy 383.772916 -262.525435) (xy 383.811037 -262.49431) (xy 383.853658 -262.469703)
			(xy 383.899674 -262.452251) (xy 383.947893 -262.442407) (xy 383.997068 -262.440426) (xy 384.045923 -262.446358)
			(xy 384.093194 -262.46005) (xy 384.137656 -262.481148) (xy 384.178159 -262.509104) (xy 384.213652 -262.543196)
			(xy 384.243217 -262.58254) (xy 384.266088 -262.626117) (xy 384.281672 -262.672798) (xy 384.289567 -262.721375)
			(xy 384.290062 -262.745982) (xy 384.289567 -262.770589) (xy 384.281672 -262.819166) (xy 384.266088 -262.865847)
			(xy 384.243217 -262.909424) (xy 384.213652 -262.948768) (xy 384.178159 -262.98286) (xy 384.137656 -263.010816)
			(xy 384.093194 -263.031914) (xy 384.045923 -263.045606) (xy 383.997068 -263.051538) (xy 383.947893 -263.049557)
			(xy 383.899674 -263.039713) (xy 383.853658 -263.022261) (xy 383.811037 -262.997654) (xy 383.772916 -262.966529)
			(xy 383.740281 -262.929692) (xy 383.713978 -262.888096) (xy 383.694687 -262.84282) (xy 383.68291 -262.795036)
			(xy 383.67895 -262.745982) (xy 383.350008 -262.745982) (xy 383.350008 -262.746744) (xy 383.349652 -262.766011)
			(xy 383.34469 -262.804228) (xy 383.340102 -262.822944) (xy 383.340102 -262.823198) (xy 383.339848 -262.823706)
			(xy 383.338103 -262.832291) (xy 383.339865 -262.84971) (xy 383.347369 -262.865528) (xy 383.35331 -262.871966)
			(xy 383.994406 -263.513062) (xy 383.997708 -263.51611) (xy 383.997962 -263.516364) (xy 384.007693 -263.523574)
			(xy 384.031292 -263.528873) (xy 384.043174 -263.526524) (xy 384.138932 -263.501886) (xy 384.157982 -263.483598)
			(xy 384.161792 -263.47039) (xy 384.169148 -263.446943) (xy 384.190293 -263.402586) (xy 384.218271 -263.362191)
			(xy 384.25236 -263.326799) (xy 384.291678 -263.297326) (xy 384.33521 -263.274533) (xy 384.381832 -263.259008)
			(xy 384.430339 -263.251153) (xy 384.454908 -263.25068) (xy 384.478899 -263.251151) (xy 384.526291 -263.258658)
			(xy 384.571924 -263.273486) (xy 384.614677 -263.29527) (xy 384.653495 -263.323473) (xy 384.687424 -263.357402)
			(xy 384.715628 -263.39622) (xy 384.737412 -263.438972) (xy 384.752241 -263.484606) (xy 384.759748 -263.531997)
			(xy 384.760216 -263.555988) (xy 384.760132 -263.567846) (xy 384.758348 -263.591494) (xy 384.75666 -263.603232)
			(xy 384.75666 -263.603486) (xy 384.755479 -263.614469) (xy 384.761527 -263.63569) (xy 384.768344 -263.64438)
			(xy 384.817112 -263.70153) (xy 384.821938 -263.706356) (xy 384.829132 -263.712219) (xy 384.84645 -263.718853)
			(xy 384.85572 -263.71931)
		)
		(stroke
			(width 0)
			(type solid)
		)
		(fill yes)
		(layer "In11.Cu")
		(net "PVDDCR_SOC_P0")
	)
	(gr_poly
		(pts
			(xy 137.6426 -263.719564) (xy 137.647275 -263.719477) (xy 137.656475 -263.717809) (xy 137.660888 -263.716262)
			(xy 137.671048 -263.712198) (xy 137.677601 -263.709471) (xy 137.688959 -263.70097) (xy 137.6934 -263.695434)
			(xy 137.696702 -263.690354) (xy 137.702544 -263.680448) (xy 137.704322 -263.673336) (xy 137.714467 -263.636281)
			(xy 137.743533 -263.565164) (xy 137.762234 -263.531604) (xy 137.822178 -263.42848) (xy 137.827377 -263.418188)
			(xy 137.82911 -263.395226) (xy 137.82548 -263.384284) (xy 137.79246 -263.300972) (xy 137.775442 -263.285224)
			(xy 137.764266 -263.281922) (xy 137.734075 -263.272417) (xy 137.675883 -263.247515) (xy 137.620875 -263.216199)
			(xy 137.569758 -263.178869) (xy 137.523185 -263.136003) (xy 137.481753 -263.08815) (xy 137.445993 -263.035923)
			(xy 137.416361 -262.97999) (xy 137.404348 -262.950706) (xy 137.399268 -262.937752) (xy 137.377424 -262.920734)
			(xy 137.277856 -262.907526) (xy 137.270993 -262.906863) (xy 137.257347 -262.908806) (xy 137.250932 -262.911336)
			(xy 137.244582 -262.913876) (xy 137.234422 -262.922258) (xy 137.230104 -262.927846) (xy 137.215601 -262.946677)
			(xy 137.181747 -262.980035) (xy 137.143134 -263.007748) (xy 137.100696 -263.029145) (xy 137.055455 -263.043711)
			(xy 137.008504 -263.051094) (xy 136.98474 -263.051544) (xy 136.959477 -263.051054) (xy 136.90964 -263.042744)
			(xy 136.86185 -263.026343) (xy 136.817412 -263.0023) (xy 136.777538 -262.971269) (xy 136.743315 -262.934099)
			(xy 136.715679 -262.891802) (xy 136.695381 -262.845532) (xy 136.682977 -262.796553) (xy 136.678804 -262.7462)
			(xy 136.682977 -262.695847) (xy 136.695381 -262.646868) (xy 136.715679 -262.600598) (xy 136.743315 -262.558301)
			(xy 136.777538 -262.521131) (xy 136.817412 -262.4901) (xy 136.86185 -262.466057) (xy 136.90964 -262.449656)
			(xy 136.959477 -262.441346) (xy 136.98474 -262.440928) (xy 137.008506 -262.441377) (xy 137.055463 -262.44874)
			(xy 137.100711 -262.463296) (xy 137.143153 -262.484693) (xy 137.181764 -262.512414) (xy 137.215607 -262.545788)
			(xy 137.230104 -262.564626) (xy 137.234422 -262.570214) (xy 137.244582 -262.578596) (xy 137.250932 -262.581136)
			(xy 137.257341 -262.583682) (xy 137.270991 -262.585604) (xy 137.277856 -262.584946) (xy 137.377678 -262.571738)
			(xy 137.399268 -262.55472) (xy 137.404348 -262.541766) (xy 137.412269 -262.522059) (xy 137.430702 -262.483788)
			(xy 137.441178 -262.465312) (xy 137.485882 -262.38835) (xy 137.491661 -262.377137) (xy 137.492587 -262.351958)
			(xy 137.48766 -262.340344) (xy 137.451338 -262.266684) (xy 137.445273 -262.255743) (xy 137.425016 -262.241118)
			(xy 137.41273 -262.238744) (xy 137.388693 -262.234946) (xy 137.342157 -262.220722) (xy 137.298468 -262.199295)
			(xy 137.258731 -262.171208) (xy 137.223955 -262.137171) (xy 137.19502 -262.098048) (xy 137.172659 -262.054829)
			(xy 137.157438 -262.00861) (xy 137.149744 -261.960561) (xy 137.149332 -261.93623) (xy 137.149776 -261.912236)
			(xy 137.157279 -261.86484) (xy 137.172106 -261.819201) (xy 137.19389 -261.776443) (xy 137.222096 -261.737621)
			(xy 137.256028 -261.703689) (xy 137.294852 -261.675485) (xy 137.33761 -261.653702) (xy 137.383249 -261.638877)
			(xy 137.430646 -261.631375) (xy 137.45464 -261.630922) (xy 137.46618 -261.631051) (xy 137.489191 -261.632832)
			(xy 137.500614 -261.634478) (xy 137.504424 -261.634986) (xy 137.50544 -261.634986) (xy 137.527894 -261.63921)
			(xy 137.57131 -261.653439) (xy 137.612125 -261.67397) (xy 137.649432 -261.700344) (xy 137.682399 -261.731976)
			(xy 137.696702 -261.749794) (xy 137.696702 -261.750048) (xy 137.704922 -261.75955) (xy 137.727828 -261.769803)
			(xy 137.74039 -261.769606) (xy 137.822432 -261.764018) (xy 137.82862 -261.763404) (xy 137.840441 -261.759553)
			(xy 137.8458 -261.756398) (xy 137.846054 -261.756398) (xy 137.851204 -261.752904) (xy 137.859806 -261.743915)
			(xy 137.863072 -261.738618) (xy 137.883646 -261.70255) (xy 137.887964 -261.692898) (xy 137.89025 -261.68096)
			(xy 137.890504 -261.67715) (xy 137.890504 -261.454392) (xy 137.869168 -261.42696) (xy 137.851896 -261.422642)
			(xy 137.827365 -261.416091) (xy 137.780748 -261.395976) (xy 137.738102 -261.368427) (xy 137.7006 -261.334202)
			(xy 137.669278 -261.294244) (xy 137.644998 -261.249654) (xy 137.628429 -261.201663) (xy 137.620029 -261.151591)
			(xy 137.620028 -261.10082) (xy 137.628427 -261.050748) (xy 137.644993 -261.002756) (xy 137.669272 -260.958166)
			(xy 137.700592 -260.918207) (xy 137.738092 -260.88398) (xy 137.780738 -260.856429) (xy 137.827354 -260.836313)
			(xy 137.851896 -260.829806) (xy 137.869168 -260.825488) (xy 137.890504 -260.798056) (xy 137.890504 -257.00482)
			(xy 137.890504 -257.001772) (xy 137.889334 -256.990865) (xy 137.87908 -256.971499) (xy 137.870692 -256.964434)
			(xy 137.86739 -256.962148) (xy 137.786618 -256.909824) (xy 137.761218 -256.907792) (xy 137.74928 -256.913126)
			(xy 137.729618 -256.921533) (xy 137.688535 -256.933394) (xy 137.6462 -256.939419) (xy 137.62482 -256.939796)
			(xy 137.600826 -256.939351) (xy 137.553429 -256.931847) (xy 137.507789 -256.91702) (xy 137.465031 -256.895236)
			(xy 137.426208 -256.86703) (xy 137.392275 -256.833098) (xy 137.364069 -256.794275) (xy 137.342283 -256.751518)
			(xy 137.327455 -256.705879) (xy 137.319949 -256.658482) (xy 137.319512 -256.634488) (xy 137.319974 -256.609879)
			(xy 137.327858 -256.561298) (xy 137.343435 -256.514612) (xy 137.366302 -256.47103) (xy 137.395867 -256.431682)
			(xy 137.431362 -256.397588) (xy 137.471869 -256.369633) (xy 137.516336 -256.348539) (xy 137.563612 -256.334855)
			(xy 137.58799 -256.331466) (xy 137.60196 -256.329688) (xy 137.62355 -256.313178) (xy 137.667238 -256.208022)
			(xy 137.663428 -256.18059) (xy 137.654792 -256.169922) (xy 137.643733 -256.155589) (xy 137.62327 -256.125721)
			(xy 137.613898 -256.110232) (xy 137.613898 -256.109978) (xy 137.612374 -256.107438) (xy 137.605008 -256.097786)
			(xy 137.602468 -256.095246) (xy 137.52957 -256.022348) (xy 137.52195 -256.014728) (xy 137.502646 -256.007108)
			(xy 137.409428 -256.009902) (xy 137.390378 -256.018792) (xy 137.38352 -256.026666) (xy 137.37442 -256.036754)
			(xy 137.354707 -256.055452) (xy 137.34415 -256.064004) (xy 137.323757 -256.079497) (xy 137.278876 -256.104162)
			(xy 137.230512 -256.121) (xy 137.180018 -256.129539) (xy 137.154412 -256.130044) (xy 137.130419 -256.129574)
			(xy 137.083024 -256.12207) (xy 137.037386 -256.107244) (xy 136.994629 -256.085462) (xy 136.955806 -256.057259)
			(xy 136.921872 -256.023331) (xy 136.893663 -255.984512) (xy 136.871874 -255.941758) (xy 136.857041 -255.896123)
			(xy 136.849529 -255.848729) (xy 136.849104 -255.824736) (xy 136.849541 -255.801447) (xy 136.856618 -255.755411)
			(xy 136.870611 -255.710986) (xy 136.891197 -255.669205) (xy 136.917896 -255.63104) (xy 136.933686 -255.613916)
			(xy 136.938766 -255.608582) (xy 136.956526 -255.591501) (xy 136.996518 -255.562721) (xy 137.040611 -255.540731)
			(xy 137.087662 -255.526103) (xy 137.111994 -255.522222) (xy 137.112502 -255.522222) (xy 137.125456 -255.52019)
			(xy 137.135616 -255.512824) (xy 137.140522 -255.509029) (xy 137.148478 -255.499518) (xy 137.151364 -255.494028)
			(xy 137.187686 -255.420368) (xy 137.192635 -255.408758) (xy 137.191712 -255.383568) (xy 137.185908 -255.372362)
			(xy 137.141204 -255.2954) (xy 137.130732 -255.276921) (xy 137.112293 -255.238654) (xy 137.104374 -255.218946)
			(xy 137.099294 -255.205992) (xy 137.077704 -255.188974) (xy 136.977882 -255.175766) (xy 136.971018 -255.1751)
			(xy 136.957371 -255.177038) (xy 136.950958 -255.179576) (xy 136.944608 -255.182116) (xy 136.934448 -255.190498)
			(xy 136.93013 -255.196086) (xy 136.915626 -255.214916) (xy 136.881771 -255.248273) (xy 136.843159 -255.275985)
			(xy 136.80072 -255.297383) (xy 136.75548 -255.311951) (xy 136.70853 -255.319337) (xy 136.684766 -255.319784)
			(xy 136.659515 -255.31926) (xy 136.609701 -255.310942) (xy 136.561936 -255.29454) (xy 136.517521 -255.2705)
			(xy 136.477669 -255.239477) (xy 136.443466 -255.202319) (xy 136.415846 -255.160039) (xy 136.39556 -255.113789)
			(xy 136.383163 -255.064831) (xy 136.378993 -255.0145) (xy 136.383163 -254.964169) (xy 136.39556 -254.915211)
			(xy 136.415846 -254.868961) (xy 136.443467 -254.826681) (xy 136.477669 -254.789523) (xy 136.517521 -254.7585)
			(xy 136.561936 -254.73446) (xy 136.609701 -254.718058) (xy 136.659515 -254.70974) (xy 136.684766 -254.709168)
			(xy 136.708531 -254.709619) (xy 136.755488 -254.716984) (xy 136.800735 -254.731541) (xy 136.843177 -254.752937)
			(xy 136.881789 -254.780657) (xy 136.915635 -254.814027) (xy 136.93013 -254.832866) (xy 136.934448 -254.838454)
			(xy 136.944608 -254.846836) (xy 136.950958 -254.849376) (xy 136.957366 -254.851934) (xy 136.971018 -254.853878)
			(xy 136.977882 -254.853186) (xy 137.07745 -254.839978) (xy 137.099294 -254.82296) (xy 137.104374 -254.810006)
			(xy 137.116102 -254.781316) (xy 137.145015 -254.726487) (xy 137.179806 -254.675188) (xy 137.220049 -254.628044)
			(xy 137.265253 -254.585633) (xy 137.314864 -254.548474) (xy 137.341356 -254.532384) (xy 137.34161 -254.532384)
			(xy 137.347117 -254.528833) (xy 137.356256 -254.51945) (xy 137.359644 -254.513842) (xy 137.371328 -254.493776)
			(xy 137.374474 -254.4879) (xy 137.377954 -254.475037) (xy 137.378186 -254.468376) (xy 137.378186 -254.0762)
			(xy 137.378066 -254.071387) (xy 137.37628 -254.061927) (xy 137.37463 -254.057404) (xy 137.364724 -254.032512)
			(xy 137.358628 -254.025654) (xy 137.358628 -254.0254) (xy 137.339383 -254.003578) (xy 137.305021 -253.956621)
			(xy 137.290048 -253.931674) (xy 137.141204 -253.675388) (xy 137.130732 -253.656909) (xy 137.112294 -253.618642)
			(xy 137.104374 -253.598934) (xy 137.099294 -253.58598) (xy 137.077704 -253.568962) (xy 136.977882 -253.555754)
			(xy 136.971018 -253.555088) (xy 136.95737 -253.557026) (xy 136.950958 -253.559564) (xy 136.944608 -253.562104)
			(xy 136.934448 -253.570486) (xy 136.93013 -253.576074) (xy 136.915627 -253.594905) (xy 136.881772 -253.628263)
			(xy 136.84316 -253.655976) (xy 136.800721 -253.677375) (xy 136.755481 -253.691943) (xy 136.70853 -253.69933)
			(xy 136.684766 -253.699772) (xy 136.659515 -253.699248) (xy 136.609704 -253.690931) (xy 136.561941 -253.674529)
			(xy 136.517528 -253.65049) (xy 136.477677 -253.619469) (xy 136.443476 -253.582312) (xy 136.415856 -253.540033)
			(xy 136.395571 -253.493785) (xy 136.383175 -253.444829) (xy 136.379005 -253.3945) (xy 136.383175 -253.344171)
			(xy 136.395571 -253.295215) (xy 136.415856 -253.248967) (xy 136.443476 -253.206688) (xy 136.477677 -253.169531)
			(xy 136.517528 -253.13851) (xy 136.561941 -253.114471) (xy 136.609704 -253.098069) (xy 136.659516 -253.089752)
			(xy 136.684766 -253.089156) (xy 136.708532 -253.089607) (xy 136.755489 -253.096971) (xy 136.800736 -253.111528)
			(xy 136.843179 -253.132924) (xy 136.881791 -253.160643) (xy 136.915638 -253.194013) (xy 136.93013 -253.212854)
			(xy 136.934448 -253.218442) (xy 136.944608 -253.226824) (xy 136.950958 -253.229364) (xy 136.957365 -253.231922)
			(xy 136.971018 -253.233867) (xy 136.977882 -253.233174) (xy 137.077704 -253.219966) (xy 137.099294 -253.202948)
			(xy 137.104374 -253.189994) (xy 137.119921 -253.152321) (xy 137.16034 -253.081554) (xy 137.184892 -253.049024)
			(xy 137.190175 -253.041687) (xy 137.195698 -253.024483) (xy 137.194934 -253.006431) (xy 137.19175 -252.99797)
			(xy 137.153396 -252.905768) (xy 137.131806 -252.889512) (xy 137.11809 -252.887734) (xy 137.09379 -252.884308)
			(xy 137.046641 -252.870714) (xy 137.002272 -252.849756) (xy 136.961824 -252.821974) (xy 136.926338 -252.788082)
			(xy 136.896727 -252.748954) (xy 136.873753 -252.705594) (xy 136.858007 -252.659119) (xy 136.849893 -252.610725)
			(xy 136.849621 -252.561655) (xy 136.857198 -252.513174) (xy 136.872428 -252.466527) (xy 136.89492 -252.422916)
			(xy 136.909048 -252.402848) (xy 136.923895 -252.383551) (xy 136.958676 -252.349483) (xy 136.998428 -252.321373)
			(xy 137.04214 -252.299934) (xy 137.088702 -252.28571) (xy 137.112756 -252.281944) (xy 137.125036 -252.279568)
			(xy 137.145288 -252.264935) (xy 137.151364 -252.254004) (xy 137.187686 -252.180344) (xy 137.192629 -252.168734)
			(xy 137.191696 -252.14355) (xy 137.185908 -252.132338) (xy 137.141204 -252.055376) (xy 137.12328 -252.023306)
			(xy 137.095065 -251.955472) (xy 137.075974 -251.884527) (xy 137.066335 -251.811694) (xy 137.065766 -251.77496)
			(xy 137.065766 -251.773944) (xy 137.066177 -251.742956) (xy 137.073021 -251.681359) (xy 137.086641 -251.620898)
			(xy 137.106869 -251.562317) (xy 137.133457 -251.506334) (xy 137.166077 -251.453637) (xy 137.184892 -251.429012)
			(xy 137.193528 -251.417836) (xy 137.197338 -251.390912) (xy 137.153396 -251.285756) (xy 137.131806 -251.2695)
			(xy 137.11809 -251.267722) (xy 137.093791 -251.264296) (xy 137.046643 -251.250702) (xy 137.002275 -251.229744)
			(xy 136.961829 -251.201962) (xy 136.926344 -251.168071) (xy 136.896735 -251.128943) (xy 136.873762 -251.085584)
			(xy 136.858017 -251.03911) (xy 136.849904 -250.990717) (xy 136.849634 -250.941649) (xy 136.857211 -250.893169)
			(xy 136.872443 -250.846524) (xy 136.894935 -250.802914) (xy 136.909048 -250.782836) (xy 136.923895 -250.763539)
			(xy 136.958677 -250.729473) (xy 136.998429 -250.701364) (xy 137.042141 -250.679926) (xy 137.088703 -250.665703)
			(xy 137.112756 -250.661932) (xy 137.125035 -250.659555) (xy 137.145284 -250.64492) (xy 137.151364 -250.633992)
			(xy 137.187686 -250.560332) (xy 137.192626 -250.548723) (xy 137.191688 -250.523541) (xy 137.185908 -250.512326)
			(xy 137.141204 -250.435364) (xy 137.130733 -250.416885) (xy 137.112297 -250.378617) (xy 137.104374 -250.35891)
			(xy 137.099294 -250.345956) (xy 137.077704 -250.328938) (xy 136.977882 -250.31573) (xy 136.971018 -250.315064)
			(xy 136.95737 -250.317001) (xy 136.950958 -250.31954) (xy 136.944608 -250.32208) (xy 136.934448 -250.330462)
			(xy 136.93013 -250.33605) (xy 136.915628 -250.354882) (xy 136.881774 -250.388243) (xy 136.843162 -250.415958)
			(xy 136.800723 -250.437359) (xy 136.755482 -250.451928) (xy 136.70853 -250.459315) (xy 136.684766 -250.459748)
			(xy 136.659509 -250.459224) (xy 136.609685 -250.450904) (xy 136.56191 -250.434498) (xy 136.517486 -250.410453)
			(xy 136.477626 -250.379424) (xy 136.443416 -250.342259) (xy 136.415789 -250.299969) (xy 136.3955 -250.253709)
			(xy 136.3831 -250.204741) (xy 136.378929 -250.1544) (xy 136.3831 -250.104059) (xy 136.3955 -250.055091)
			(xy 136.415789 -250.008831) (xy 136.443416 -249.966541) (xy 136.477626 -249.929376) (xy 136.517486 -249.898347)
			(xy 136.56191 -249.874302) (xy 136.609685 -249.857896) (xy 136.659509 -249.849576) (xy 136.684766 -249.849132)
			(xy 136.708531 -249.849583) (xy 136.755486 -249.856949) (xy 136.80073 -249.871508) (xy 136.84317 -249.892908)
			(xy 136.881777 -249.920631) (xy 136.915617 -249.954005) (xy 136.93013 -249.97283) (xy 136.934448 -249.978418)
			(xy 136.944608 -249.9868) (xy 136.950958 -249.98934) (xy 136.957366 -249.991895) (xy 136.971018 -249.993838)
			(xy 136.977882 -249.99315) (xy 137.07745 -249.979942) (xy 137.099294 -249.962924) (xy 137.104374 -249.94997)
			(xy 137.11749 -249.917996) (xy 137.150498 -249.857278) (xy 137.190739 -249.801091) (xy 137.237599 -249.750294)
			(xy 137.290364 -249.705659) (xy 137.319004 -249.686318) (xy 137.324084 -249.682762) (xy 137.332466 -249.673872)
			(xy 137.346436 -249.648726) (xy 137.349396 -249.643002) (xy 137.352614 -249.630529) (xy 137.352786 -249.624088)
			(xy 137.352786 -249.186192) (xy 137.352702 -249.181781) (xy 137.351176 -249.173091) (xy 137.349738 -249.16892)
			(xy 137.34415 -249.153172) (xy 137.342624 -249.14935) (xy 137.338535 -249.142207) (xy 137.336022 -249.138948)
			(xy 137.323467 -249.12287) (xy 137.300459 -249.089181) (xy 137.290048 -249.071638) (xy 137.141204 -248.815352)
			(xy 137.130733 -248.796873) (xy 137.112298 -248.758604) (xy 137.104374 -248.738898) (xy 137.099294 -248.725944)
			(xy 137.077704 -248.708926) (xy 136.977882 -248.695718) (xy 136.971018 -248.695052) (xy 136.95737 -248.696988)
			(xy 136.950958 -248.699528) (xy 136.944608 -248.702068) (xy 136.934448 -248.71045) (xy 136.93013 -248.716038)
			(xy 136.915628 -248.734871) (xy 136.881775 -248.768233) (xy 136.843163 -248.795949) (xy 136.800724 -248.817351)
			(xy 136.755483 -248.831921) (xy 136.708531 -248.839308) (xy 136.684766 -248.839736) (xy 136.65951 -248.839212)
			(xy 136.609688 -248.830893) (xy 136.561915 -248.814487) (xy 136.517493 -248.790443) (xy 136.477634 -248.759416)
			(xy 136.443425 -248.722251) (xy 136.4158 -248.679963) (xy 136.395511 -248.633705) (xy 136.383112 -248.584739)
			(xy 136.378941 -248.5344) (xy 136.383112 -248.484061) (xy 136.395511 -248.435095) (xy 136.4158 -248.388837)
			(xy 136.443425 -248.346549) (xy 136.477634 -248.309384) (xy 136.517493 -248.278357) (xy 136.561915 -248.254313)
			(xy 136.609688 -248.237907) (xy 136.65951 -248.229588) (xy 136.684766 -248.22912) (xy 136.708531 -248.229571)
			(xy 136.755486 -248.236937) (xy 136.800731 -248.251496) (xy 136.843171 -248.272895) (xy 136.881779 -248.300617)
			(xy 136.91562 -248.333991) (xy 136.93013 -248.352818) (xy 136.934448 -248.358406) (xy 136.944608 -248.366788)
			(xy 136.950958 -248.369328) (xy 136.957366 -248.371884) (xy 136.971018 -248.373827) (xy 136.977882 -248.373138)
			(xy 137.077704 -248.35993) (xy 137.099294 -248.342912) (xy 137.104374 -248.329958) (xy 137.119924 -248.292286)
			(xy 137.160346 -248.221522) (xy 137.184892 -248.188988) (xy 137.190169 -248.18165) (xy 137.19568 -248.164449)
			(xy 137.194904 -248.146404) (xy 137.19175 -248.137934) (xy 137.153396 -248.045732) (xy 137.131806 -248.029476)
			(xy 137.11809 -248.027698) (xy 137.093787 -248.024272) (xy 137.046631 -248.010678) (xy 137.002254 -247.989719)
			(xy 136.961799 -247.961935) (xy 136.926306 -247.928042) (xy 136.896688 -247.88891) (xy 136.873706 -247.845546)
			(xy 136.857953 -247.799067) (xy 136.849833 -247.750666) (xy 136.849555 -247.70159) (xy 136.857126 -247.653101)
			(xy 136.872352 -247.606445) (xy 136.89484 -247.562824) (xy 136.909048 -247.542812) (xy 136.923896 -247.523517)
			(xy 136.958679 -247.489453) (xy 136.998432 -247.461346) (xy 137.042143 -247.43991) (xy 137.088704 -247.425688)
			(xy 137.112756 -247.421908) (xy 137.125034 -247.41953) (xy 137.145277 -247.404891) (xy 137.151364 -247.393968)
			(xy 137.187686 -247.320308) (xy 137.19262 -247.308699) (xy 137.191672 -247.283524) (xy 137.185908 -247.272302)
			(xy 137.141204 -247.19534) (xy 137.123282 -247.16327) (xy 137.095072 -247.095435) (xy 137.075985 -247.02449)
			(xy 137.066351 -246.951657) (xy 137.065766 -246.914924) (xy 137.065766 -246.913908) (xy 137.066179 -246.882921)
			(xy 137.073027 -246.821326) (xy 137.08665 -246.760867) (xy 137.106881 -246.702287) (xy 137.133471 -246.646307)
			(xy 137.166094 -246.593614) (xy 137.184892 -246.568976) (xy 137.193528 -246.5578) (xy 137.197338 -246.530876)
			(xy 137.153396 -246.42572) (xy 137.131806 -246.409464) (xy 137.11809 -246.407686) (xy 137.093788 -246.40426)
			(xy 137.046633 -246.390666) (xy 137.002257 -246.369707) (xy 136.961804 -246.341924) (xy 136.926312 -246.308031)
			(xy 136.896695 -246.268899) (xy 136.873715 -246.225537) (xy 136.857963 -246.179058) (xy 136.849844 -246.130658)
			(xy 136.849567 -246.081584) (xy 136.857139 -246.033096) (xy 136.872366 -245.986442) (xy 136.894855 -245.942823)
			(xy 136.909048 -245.9228) (xy 136.923896 -245.903505) (xy 136.95868 -245.869443) (xy 136.998433 -245.841337)
			(xy 137.042144 -245.819901) (xy 137.088705 -245.80568) (xy 137.112756 -245.801896) (xy 137.125033 -245.799517)
			(xy 137.145274 -245.784877) (xy 137.151364 -245.773956) (xy 137.187686 -245.700296) (xy 137.192617 -245.688687)
			(xy 137.191664 -245.663515) (xy 137.185908 -245.65229) (xy 137.141204 -245.575328) (xy 137.130734 -245.556848)
			(xy 137.1123 -245.518579) (xy 137.104374 -245.498874) (xy 137.099294 -245.48592) (xy 137.077704 -245.468902)
			(xy 136.977882 -245.455694) (xy 136.971018 -245.455028) (xy 136.95737 -245.456964) (xy 136.950958 -245.459504)
			(xy 136.944608 -245.462044) (xy 136.934448 -245.470426) (xy 136.93013 -245.476014) (xy 136.915625 -245.494843)
			(xy 136.881769 -245.528197) (xy 136.843156 -245.555906) (xy 136.800718 -245.577302) (xy 136.755478 -245.591868)
			(xy 136.708529 -245.599254) (xy 136.684766 -245.599712) (xy 136.659512 -245.599188) (xy 136.609694 -245.590869)
			(xy 136.561924 -245.574465) (xy 136.517506 -245.550423) (xy 136.47765 -245.519398) (xy 136.443444 -245.482236)
			(xy 136.415821 -245.439952) (xy 136.395534 -245.393698) (xy 136.383136 -245.344735) (xy 136.378965 -245.2944)
			(xy 136.383136 -245.244065) (xy 136.395534 -245.195102) (xy 136.415821 -245.148848) (xy 136.443444 -245.106564)
			(xy 136.47765 -245.069402) (xy 136.517506 -245.038377) (xy 136.561924 -245.014335) (xy 136.609694 -244.997931)
			(xy 136.659512 -244.989612) (xy 136.684766 -244.989096) (xy 136.708531 -244.989547) (xy 136.755487 -244.996913)
			(xy 136.800733 -245.011471) (xy 136.843174 -245.032869) (xy 136.881783 -245.060589) (xy 136.915627 -245.093962)
			(xy 136.93013 -245.112794) (xy 136.934448 -245.118382) (xy 136.944608 -245.126764) (xy 136.950958 -245.129304)
			(xy 136.957366 -245.131861) (xy 136.971018 -245.133804) (xy 136.977882 -245.133114) (xy 137.07745 -245.119906)
			(xy 137.099294 -245.102888) (xy 137.104374 -245.089934) (xy 137.117491 -245.057962) (xy 137.150503 -244.997246)
			(xy 137.190746 -244.941062) (xy 137.237608 -244.890268) (xy 137.290373 -244.845636) (xy 137.319004 -244.826282)
			(xy 137.324084 -244.822726) (xy 137.332466 -244.813836) (xy 137.346436 -244.78869) (xy 137.349392 -244.782966)
			(xy 137.352601 -244.770492) (xy 137.352786 -244.764052) (xy 137.352786 -244.326156) (xy 137.352699 -244.321745)
			(xy 137.351167 -244.313058) (xy 137.349738 -244.308884) (xy 137.34415 -244.293136) (xy 137.342628 -244.289311)
			(xy 137.338546 -244.282163) (xy 137.336022 -244.278912) (xy 137.323465 -244.262835) (xy 137.300454 -244.229148)
			(xy 137.290048 -244.211602) (xy 137.141204 -243.955316) (xy 137.130734 -243.936836) (xy 137.112301 -243.898567)
			(xy 137.104374 -243.878862) (xy 137.099294 -243.865908) (xy 137.077704 -243.84889) (xy 136.977882 -243.835682)
			(xy 136.971018 -243.835016) (xy 136.957369 -243.836951) (xy 136.950958 -243.839492) (xy 136.944608 -243.842032)
			(xy 136.934448 -243.850414) (xy 136.93013 -243.856002) (xy 136.915626 -243.874831) (xy 136.88177 -243.908187)
			(xy 136.843157 -243.935897) (xy 136.800719 -243.957294) (xy 136.755479 -243.971861) (xy 136.708529 -243.979246)
			(xy 136.684766 -243.9797) (xy 136.659513 -243.979176) (xy 136.609697 -243.970858) (xy 136.561929 -243.954454)
			(xy 136.517513 -243.930413) (xy 136.477659 -243.899389) (xy 136.443454 -243.862229) (xy 136.415832 -243.819946)
			(xy 136.395545 -243.773694) (xy 136.383147 -243.724733) (xy 136.378977 -243.6744) (xy 136.383147 -243.624067)
			(xy 136.395545 -243.575106) (xy 136.415832 -243.528854) (xy 136.443454 -243.486571) (xy 136.477659 -243.449411)
			(xy 136.517513 -243.418387) (xy 136.561929 -243.394346) (xy 136.609697 -243.377942) (xy 136.659513 -243.369624)
			(xy 136.684766 -243.369084) (xy 136.708531 -243.369535) (xy 136.755488 -243.376901) (xy 136.800734 -243.391458)
			(xy 136.843175 -243.412855) (xy 136.881785 -243.440575) (xy 136.91563 -243.473947) (xy 136.93013 -243.492782)
			(xy 136.934448 -243.49837) (xy 136.944608 -243.506752) (xy 136.950958 -243.509292) (xy 136.957366 -243.511849)
			(xy 136.971018 -243.513793) (xy 136.977882 -243.513102) (xy 137.077704 -243.499894) (xy 137.099294 -243.482876)
			(xy 137.104374 -243.469922) (xy 137.119926 -243.432252) (xy 137.160352 -243.36149) (xy 137.184892 -243.328952)
			(xy 137.190163 -243.321614) (xy 137.195662 -243.304416) (xy 137.194876 -243.286377) (xy 137.19175 -243.277898)
			(xy 137.153396 -243.185696) (xy 137.131806 -243.16944) (xy 137.11809 -243.167662) (xy 137.093789 -243.164236)
			(xy 137.046637 -243.150642) (xy 137.002264 -243.129683) (xy 136.961813 -243.101901) (xy 136.926324 -243.068008)
			(xy 136.89671 -243.028878) (xy 136.873733 -242.985517) (xy 136.857983 -242.93904) (xy 136.849867 -242.890643)
			(xy 136.849592 -242.841571) (xy 136.857166 -242.793086) (xy 136.872395 -242.746435) (xy 136.894885 -242.702819)
			(xy 136.909048 -242.682776) (xy 136.923897 -242.663482) (xy 136.958682 -242.629422) (xy 136.998435 -242.601319)
			(xy 137.042146 -242.579885) (xy 137.088707 -242.565665) (xy 137.112756 -242.561872) (xy 137.125031 -242.559492)
			(xy 137.145266 -242.544848) (xy 137.151364 -242.533932) (xy 137.187686 -242.460272) (xy 137.192636 -242.448662)
			(xy 137.191715 -242.423471) (xy 137.185908 -242.412266) (xy 137.141204 -242.335304) (xy 137.123284 -242.303233)
			(xy 137.095078 -242.235398) (xy 137.075996 -242.164453) (xy 137.066367 -242.091621) (xy 137.065766 -242.054888)
			(xy 137.065766 -242.053872) (xy 137.066181 -242.022885) (xy 137.073033 -241.961292) (xy 137.086659 -241.900835)
			(xy 137.106893 -241.842258) (xy 137.133485 -241.78628) (xy 137.16611 -241.73359) (xy 137.184892 -241.70894)
			(xy 137.193528 -241.697764) (xy 137.197338 -241.67084) (xy 137.153396 -241.565684) (xy 137.131806 -241.549428)
			(xy 137.11809 -241.54765) (xy 137.09379 -241.544224) (xy 137.046638 -241.53063) (xy 137.002267 -241.509672)
			(xy 136.961818 -241.481889) (xy 136.92633 -241.447997) (xy 136.896717 -241.408868) (xy 136.873741 -241.365507)
			(xy 136.857993 -241.319031) (xy 136.849878 -241.270635) (xy 136.849605 -241.221564) (xy 136.85718 -241.17308)
			(xy 136.872409 -241.126432) (xy 136.8949 -241.082818) (xy 136.909048 -241.062764) (xy 136.923897 -241.043471)
			(xy 136.958683 -241.009412) (xy 136.998436 -240.98131) (xy 137.042147 -240.959877) (xy 137.088708 -240.945657)
			(xy 137.112756 -240.94186) (xy 137.12503 -240.939479) (xy 137.145262 -240.924834) (xy 137.151364 -240.91392)
			(xy 137.187686 -240.84026) (xy 137.192633 -240.82865) (xy 137.191707 -240.803462) (xy 137.185908 -240.792254)
			(xy 137.141204 -240.715292) (xy 137.130732 -240.696813) (xy 137.112294 -240.658546) (xy 137.104374 -240.638838)
			(xy 137.099294 -240.625884) (xy 137.077704 -240.608866) (xy 136.977882 -240.595658) (xy 136.971018 -240.594992)
			(xy 136.957371 -240.59693) (xy 136.950958 -240.599468) (xy 136.944608 -240.602008) (xy 136.934448 -240.61039)
			(xy 136.93013 -240.615978) (xy 136.915627 -240.634809) (xy 136.881772 -240.668167) (xy 136.843159 -240.695879)
			(xy 136.800721 -240.717278) (xy 136.75548 -240.731846) (xy 136.70853 -240.739232) (xy 136.684766 -240.739676)
			(xy 136.659515 -240.739152) (xy 136.609703 -240.730835) (xy 136.561939 -240.714432) (xy 136.517526 -240.690393)
			(xy 136.477675 -240.659371) (xy 136.443473 -240.622214) (xy 136.415853 -240.579935) (xy 136.395568 -240.533686)
			(xy 136.383171 -240.484729) (xy 136.379001 -240.4344) (xy 136.383171 -240.384071) (xy 136.395568 -240.335114)
			(xy 136.415853 -240.288865) (xy 136.443473 -240.246586) (xy 136.477675 -240.209428) (xy 136.517526 -240.178407)
			(xy 136.561939 -240.154368) (xy 136.609703 -240.137965) (xy 136.659515 -240.129648) (xy 136.684766 -240.12906)
			(xy 136.708532 -240.129511) (xy 136.755489 -240.136876) (xy 136.800736 -240.151432) (xy 136.843178 -240.172829)
			(xy 136.88179 -240.200547) (xy 136.915637 -240.233918) (xy 136.93013 -240.252758) (xy 136.934448 -240.258346)
			(xy 136.944608 -240.266728) (xy 136.950958 -240.269268) (xy 136.957365 -240.271826) (xy 136.971018 -240.273771)
			(xy 136.977882 -240.273078) (xy 137.07745 -240.25987) (xy 137.099294 -240.242852) (xy 137.104374 -240.229898)
			(xy 137.117489 -240.197923) (xy 137.150495 -240.137203) (xy 137.190734 -240.081014) (xy 137.237593 -240.030214)
			(xy 137.290357 -239.985577) (xy 137.319004 -239.966246) (xy 137.324084 -239.96269) (xy 137.332466 -239.9538)
			(xy 137.346436 -239.928654) (xy 137.349399 -239.922931) (xy 137.352624 -239.910458) (xy 137.352786 -239.904016)
			(xy 137.352786 -239.46612) (xy 137.352696 -239.46171) (xy 137.351158 -239.453025) (xy 137.349738 -239.448848)
			(xy 137.34415 -239.4331) (xy 137.342626 -239.429277) (xy 137.33854 -239.422132) (xy 137.336022 -239.418876)
			(xy 137.323466 -239.402799) (xy 137.300456 -239.36911) (xy 137.290048 -239.351566) (xy 137.141204 -239.09528)
			(xy 137.130732 -239.076801) (xy 137.112295 -239.038533) (xy 137.104374 -239.018826) (xy 137.099294 -239.005872)
			(xy 137.077704 -238.988854) (xy 136.977882 -238.975646) (xy 136.971018 -238.97498) (xy 136.95737 -238.976917)
			(xy 136.950958 -238.979456) (xy 136.944608 -238.981996) (xy 136.934448 -238.990378) (xy 136.93013 -238.995966)
			(xy 136.915627 -239.014797) (xy 136.881773 -239.048157) (xy 136.84316 -239.07587) (xy 136.800722 -239.09727)
			(xy 136.755481 -239.111838) (xy 136.70853 -239.119225) (xy 136.684766 -239.119664) (xy 136.659516 -239.11914)
			(xy 136.609706 -239.110823) (xy 136.561944 -239.094421) (xy 136.517532 -239.070383) (xy 136.477683 -239.039363)
			(xy 136.443482 -239.002207) (xy 136.415863 -238.959929) (xy 136.395579 -238.913682) (xy 136.383183 -238.864727)
			(xy 136.379013 -238.8144) (xy 136.383183 -238.764073) (xy 136.395579 -238.715118) (xy 136.415863 -238.668871)
			(xy 136.443482 -238.626593) (xy 136.477683 -238.589437) (xy 136.517532 -238.558417) (xy 136.561944 -238.534378)
			(xy 136.609706 -238.517977) (xy 136.659516 -238.50966) (xy 136.684766 -238.509048) (xy 136.708531 -238.509499)
			(xy 136.755485 -238.516866) (xy 136.800729 -238.531425) (xy 136.843168 -238.552826) (xy 136.881774 -238.580549)
			(xy 136.915613 -238.613925) (xy 136.93013 -238.632746) (xy 136.934448 -238.638334) (xy 136.944608 -238.646716)
			(xy 136.950958 -238.649256) (xy 136.957365 -238.651815) (xy 136.971018 -238.65376) (xy 136.977882 -238.653066)
			(xy 137.077704 -238.639858) (xy 137.099294 -238.62284) (xy 137.104374 -238.609886) (xy 137.119922 -238.572213)
			(xy 137.160342 -238.501447) (xy 137.184892 -238.468916) (xy 137.190174 -238.461579) (xy 137.195694 -238.444376)
			(xy 137.194927 -238.426325) (xy 137.19175 -238.417862) (xy 137.153396 -238.32566) (xy 137.131806 -238.309404)
			(xy 137.11809 -238.307626) (xy 137.093791 -238.3042) (xy 137.046642 -238.290606) (xy 137.002274 -238.269648)
			(xy 136.961827 -238.241866) (xy 136.926342 -238.207975) (xy 136.896732 -238.168847) (xy 136.873759 -238.125488)
			(xy 136.858013 -238.079013) (xy 136.849901 -238.030619) (xy 136.849629 -237.981551) (xy 136.857207 -237.93307)
			(xy 136.872438 -237.886425) (xy 136.89493 -237.842814) (xy 136.909048 -237.82274) (xy 136.923895 -237.803443)
			(xy 136.958677 -237.769376) (xy 136.998429 -237.741267) (xy 137.04214 -237.719829) (xy 137.088702 -237.705605)
			(xy 137.112756 -237.701836) (xy 137.125036 -237.699459) (xy 137.145286 -237.684825) (xy 137.151364 -237.673896)
			(xy 137.187686 -237.600236) (xy 137.192627 -237.588627) (xy 137.191691 -237.563444) (xy 137.185908 -237.55223)
			(xy 137.141204 -237.475268) (xy 137.12328 -237.443198) (xy 137.095067 -237.375364) (xy 137.075977 -237.304419)
			(xy 137.066339 -237.231586) (xy 137.065766 -237.194852) (xy 137.065766 -237.193836) (xy 137.066178 -237.162848)
			(xy 137.073023 -237.101252) (xy 137.086643 -237.040791) (xy 137.106871 -236.98221) (xy 137.13346 -236.926228)
			(xy 137.166081 -236.873532) (xy 137.184892 -236.848904) (xy 137.193528 -236.837728) (xy 137.197338 -236.810804)
			(xy 137.153396 -236.705648) (xy 137.131806 -236.689392) (xy 137.11809 -236.687614) (xy 137.093786 -236.684188)
			(xy 137.046628 -236.670594) (xy 137.00225 -236.649635) (xy 136.961793 -236.621851) (xy 136.926298 -236.587957)
			(xy 136.896678 -236.548824) (xy 136.873695 -236.50546) (xy 136.85794 -236.458979) (xy 136.849818 -236.410577)
			(xy 136.849538 -236.361499) (xy 136.857108 -236.313008) (xy 136.872332 -236.26635) (xy 136.89482 -236.222726)
			(xy 136.909048 -236.202728) (xy 136.923895 -236.183432) (xy 136.958678 -236.149366) (xy 136.99843 -236.121258)
			(xy 137.042142 -236.09982) (xy 137.088703 -236.085598) (xy 137.112756 -236.081824) (xy 137.125035 -236.079447)
			(xy 137.145282 -236.064811) (xy 137.151364 -236.053884) (xy 137.187686 -235.980224) (xy 137.192624 -235.968615)
			(xy 137.191683 -235.943436) (xy 137.185908 -235.932218) (xy 137.141204 -235.855256) (xy 137.130733 -235.836777)
			(xy 137.112297 -235.798508) (xy 137.104374 -235.778802) (xy 137.099294 -235.765848) (xy 137.077704 -235.74883)
			(xy 136.977882 -235.735622) (xy 136.971018 -235.734956) (xy 136.95737 -235.736892) (xy 136.950958 -235.739432)
			(xy 136.944608 -235.741972) (xy 136.934448 -235.750354) (xy 136.93013 -235.755942) (xy 136.915628 -235.774774)
			(xy 136.881775 -235.808136) (xy 136.843163 -235.835852) (xy 136.800724 -235.857253) (xy 136.755483 -235.871823)
			(xy 136.708531 -235.87921) (xy 136.684766 -235.87964) (xy 136.65951 -235.879116) (xy 136.609687 -235.870797)
			(xy 136.561913 -235.854391) (xy 136.517491 -235.830346) (xy 136.477631 -235.799319) (xy 136.443422 -235.762154)
			(xy 136.415796 -235.719865) (xy 136.395507 -235.673607) (xy 136.383108 -235.62464) (xy 136.378937 -235.5743)
			(xy 136.383108 -235.52396) (xy 136.395507 -235.474993) (xy 136.415796 -235.428735) (xy 136.443422 -235.386446)
			(xy 136.477631 -235.349281) (xy 136.517491 -235.318254) (xy 136.561913 -235.294209) (xy 136.609687 -235.277803)
			(xy 136.65951 -235.269484) (xy 136.684766 -235.269024) (xy 136.708531 -235.269475) (xy 136.755486 -235.276841)
			(xy 136.800731 -235.2914) (xy 136.843171 -235.312799) (xy 136.881778 -235.340522) (xy 136.915619 -235.373896)
			(xy 136.93013 -235.392722) (xy 136.934448 -235.39831) (xy 136.944608 -235.406692) (xy 136.950958 -235.409232)
			(xy 136.957366 -235.411788) (xy 136.971018 -235.41373) (xy 136.977882 -235.413042) (xy 137.07745 -235.399834)
			(xy 137.099294 -235.382816) (xy 137.104374 -235.369862) (xy 137.11749 -235.337889) (xy 137.150499 -235.277171)
			(xy 137.190741 -235.220985) (xy 137.237601 -235.170188) (xy 137.290366 -235.125554) (xy 137.319004 -235.10621)
			(xy 137.324084 -235.102654) (xy 137.332466 -235.093764) (xy 137.346436 -235.068618) (xy 137.349395 -235.062894)
			(xy 137.352611 -235.050421) (xy 137.352786 -235.04398) (xy 137.352786 -234.606084) (xy 137.352701 -234.601673)
			(xy 137.351174 -234.592984) (xy 137.349738 -234.588812) (xy 137.34415 -234.573064) (xy 137.342624 -234.569242)
			(xy 137.338534 -234.5621) (xy 137.336022 -234.55884) (xy 137.323465 -234.542764) (xy 137.300452 -234.509077)
			(xy 137.290048 -234.49153) (xy 137.141204 -234.235244) (xy 137.130733 -234.216765) (xy 137.112298 -234.178496)
			(xy 137.104374 -234.15879) (xy 137.099294 -234.145836) (xy 137.077704 -234.128818) (xy 136.977882 -234.11561)
			(xy 136.971018 -234.114944) (xy 136.95737 -234.11688) (xy 136.950958 -234.11942) (xy 136.944608 -234.12196)
			(xy 136.934448 -234.130342) (xy 136.93013 -234.13593) (xy 136.915628 -234.154763) (xy 136.881776 -234.188126)
			(xy 136.843164 -234.215843) (xy 136.800725 -234.237245) (xy 136.755483 -234.251816) (xy 136.708531 -234.259203)
			(xy 136.684766 -234.259628) (xy 136.659511 -234.259104) (xy 136.60969 -234.250785) (xy 136.561918 -234.23438)
			(xy 136.517497 -234.210336) (xy 136.47764 -234.17931) (xy 136.443432 -234.142146) (xy 136.415807 -234.09986)
			(xy 136.395519 -234.053603) (xy 136.38312 -234.004638) (xy 136.378949 -233.9543) (xy 136.38312 -233.903962)
			(xy 136.395519 -233.854997) (xy 136.415807 -233.80874) (xy 136.443432 -233.766454) (xy 136.47764 -233.72929)
			(xy 136.517497 -233.698264) (xy 136.561918 -233.67422) (xy 136.60969 -233.657815) (xy 136.659511 -233.649496)
			(xy 136.684766 -233.649012) (xy 136.708531 -233.649463) (xy 136.755487 -233.656829) (xy 136.800732 -233.671387)
			(xy 136.843172 -233.692786) (xy 136.88178 -233.720508) (xy 136.915623 -233.753881) (xy 136.93013 -233.77271)
			(xy 136.934448 -233.778298) (xy 136.944608 -233.78668) (xy 136.950958 -233.78922) (xy 136.957366 -233.791776)
			(xy 136.971018 -233.793719) (xy 136.977882 -233.79303) (xy 137.077704 -233.779822) (xy 137.099294 -233.762804)
			(xy 137.104374 -233.74985) (xy 137.119924 -233.712179) (xy 137.160347 -233.641415) (xy 137.184892 -233.60888)
			(xy 137.190168 -233.601542) (xy 137.195676 -233.584342) (xy 137.194898 -233.566298) (xy 137.19175 -233.557826)
			(xy 137.153396 -233.465624) (xy 137.131806 -233.449368) (xy 137.11809 -233.44759) (xy 137.093787 -233.444164)
			(xy 137.046632 -233.43057) (xy 137.002256 -233.409611) (xy 136.961802 -233.381828) (xy 136.92631 -233.347934)
			(xy 136.896693 -233.308803) (xy 136.873712 -233.26544) (xy 136.85796 -233.218961) (xy 136.84984 -233.170561)
			(xy 136.849563 -233.121486) (xy 136.857135 -233.072997) (xy 136.872361 -233.026343) (xy 136.89485 -232.982723)
			(xy 136.909048 -232.962704) (xy 136.923896 -232.943409) (xy 136.95868 -232.909346) (xy 136.998432 -232.88124)
			(xy 137.042144 -232.859804) (xy 137.088705 -232.845583) (xy 137.112756 -232.8418) (xy 137.125033 -232.839421)
			(xy 137.145275 -232.824782) (xy 137.151364 -232.81386) (xy 137.187686 -232.7402) (xy 137.192618 -232.728591)
			(xy 137.191666 -232.703418) (xy 137.185908 -232.692194) (xy 137.141204 -232.615232) (xy 137.122268 -232.581271)
			(xy 137.092957 -232.509252) (xy 137.082784 -232.471722) (xy 137.081006 -232.465118) (xy 137.074402 -232.45318)
			(xy 136.935718 -232.314496) (xy 136.929 -232.30726) (xy 136.921398 -232.289055) (xy 136.920986 -232.27919)
			(xy 136.920986 -231.746806) (xy 136.920936 -231.742734) (xy 136.919666 -231.734689) (xy 136.918446 -231.730804)
			(xy 136.910826 -231.708452) (xy 136.906508 -231.702102) (xy 136.906254 -231.701848) (xy 136.892849 -231.682304)
			(xy 136.871595 -231.639947) (xy 136.857131 -231.594818) (xy 136.849803 -231.547997) (xy 136.849358 -231.524302)
			(xy 136.849799 -231.500677) (xy 136.857072 -231.45399) (xy 136.871446 -231.408979) (xy 136.881616 -231.38765)
			(xy 136.893808 -231.365806) (xy 136.906254 -231.346756) (xy 136.910826 -231.340406) (xy 136.918446 -231.3178)
			(xy 136.919627 -231.313905) (xy 136.920905 -231.305867) (xy 136.920986 -231.301798) (xy 136.920986 -231.09682)
			(xy 136.920267 -231.084568) (xy 136.908999 -231.062805) (xy 136.899396 -231.055164) (xy 136.833356 -231.008682)
			(xy 136.823 -231.002029) (xy 136.798637 -230.998704) (xy 136.786874 -231.002332) (xy 136.78662 -231.002332)
			(xy 136.761945 -231.010473) (xy 136.710743 -231.019278) (xy 136.684766 -231.019858) (xy 136.680956 -231.019858)
			(xy 136.657159 -231.01911) (xy 136.610221 -231.011143) (xy 136.565089 -230.995986) (xy 136.522856 -230.974006)
			(xy 136.484549 -230.945737) (xy 136.451093 -230.911863) (xy 136.423303 -230.873207) (xy 136.401849 -230.830705)
			(xy 136.387254 -230.785388) (xy 136.379871 -230.738355) (xy 136.379458 -230.71455) (xy 136.379932 -230.69056)
			(xy 136.387444 -230.643173) (xy 136.402276 -230.597543) (xy 136.424061 -230.554795) (xy 136.452265 -230.51598)
			(xy 136.486193 -230.482055) (xy 136.525009 -230.453853) (xy 136.567758 -230.43207) (xy 136.613388 -230.417241)
			(xy 136.660776 -230.409731) (xy 136.684766 -230.409242) (xy 136.697529 -230.409382) (xy 136.722962 -230.411546)
			(xy 136.735566 -230.41356) (xy 136.735566 -230.413306) (xy 136.758308 -230.417579) (xy 136.802253 -230.432069)
			(xy 136.843515 -230.453011) (xy 136.881154 -230.479927) (xy 136.914309 -230.512205) (xy 136.928606 -230.5304)
			(xy 136.93521 -230.53929) (xy 136.95426 -230.549704) (xy 137.040112 -230.5558) (xy 137.051014 -230.55605)
			(xy 137.071413 -230.548405) (xy 137.079482 -230.541068) (xy 137.09269 -230.52786) (xy 137.10031 -230.52024)
			(xy 137.10412 -230.510334) (xy 137.116683 -230.47961) (xy 137.148068 -230.421118) (xy 137.186154 -230.366751)
			(xy 137.230405 -230.317273) (xy 137.280199 -230.273377) (xy 137.334837 -230.235681) (xy 137.363962 -230.219758)
			(xy 137.370312 -230.216456) (xy 137.379964 -230.207566) (xy 137.395966 -230.18115) (xy 137.399424 -230.175094)
			(xy 137.403292 -230.161701) (xy 137.403586 -230.154734) (xy 137.403586 -229.806246) (xy 137.403153 -229.79618)
			(xy 137.395423 -229.777592) (xy 137.3886 -229.770178) (xy 136.963658 -229.345236) (xy 136.95667 -229.338841)
			(xy 136.939317 -229.331279) (xy 136.929876 -229.330504) (xy 136.900412 -229.329234) (xy 136.899904 -229.329234)
			(xy 136.881108 -229.328218) (xy 136.860303 -229.344928) (xy 136.814107 -229.371628) (xy 136.763981 -229.389913)
			(xy 136.711444 -229.399229) (xy 136.684766 -229.399846) (xy 136.659509 -229.399322) (xy 136.609686 -229.391002)
			(xy 136.561911 -229.374597) (xy 136.517488 -229.350552) (xy 136.477627 -229.319523) (xy 136.443418 -229.282357)
			(xy 136.415791 -229.240068) (xy 136.395501 -229.193809) (xy 136.383102 -229.144841) (xy 136.378931 -229.0945)
			(xy 136.383102 -229.044159) (xy 136.395501 -228.995191) (xy 136.415791 -228.948932) (xy 136.443418 -228.906643)
			(xy 136.477627 -228.869477) (xy 136.517487 -228.838448) (xy 136.561911 -228.814403) (xy 136.609686 -228.797998)
			(xy 136.659509 -228.789678) (xy 136.684766 -228.78923) (xy 136.70554 -228.789603) (xy 136.746699 -228.795274)
			(xy 136.786712 -228.806463) (xy 136.805924 -228.814376) (xy 136.817862 -228.819456) (xy 136.843262 -228.81717)
			(xy 136.923272 -228.764846) (xy 136.930202 -228.759983) (xy 136.940612 -228.746646) (xy 136.946081 -228.730635)
			(xy 136.946386 -228.722174) (xy 136.946386 -228.528118) (xy 136.932924 -228.49459) (xy 136.927082 -228.487986)
			(xy 136.910925 -228.469214) (xy 136.884286 -228.427461) (xy 136.864741 -228.381954) (xy 136.852804 -228.333887)
			(xy 136.848787 -228.284524) (xy 136.852796 -228.23516) (xy 136.864726 -228.187091) (xy 136.884264 -228.141581)
			(xy 136.910896 -228.099824) (xy 136.927082 -228.081078) (xy 136.932924 -228.074474) (xy 136.946386 -228.040946)
			(xy 136.946386 -226.908106) (xy 136.932924 -226.874578) (xy 136.927082 -226.867974) (xy 136.910926 -226.849202)
			(xy 136.884289 -226.807449) (xy 136.864746 -226.761943) (xy 136.85281 -226.713877) (xy 136.848795 -226.664515)
			(xy 136.852805 -226.615152) (xy 136.864737 -226.567085) (xy 136.884275 -226.521577) (xy 136.910908 -226.479822)
			(xy 136.927082 -226.461066) (xy 136.932924 -226.454462) (xy 136.946386 -226.420934) (xy 136.946386 -226.226878)
			(xy 136.945696 -226.214138) (xy 136.933578 -226.191723) (xy 136.923272 -226.184206) (xy 136.843262 -226.131882)
			(xy 136.817862 -226.129596) (xy 136.805924 -226.134676) (xy 136.786723 -226.14262) (xy 136.746708 -226.15382)
			(xy 136.705542 -226.159477) (xy 136.684766 -226.159822) (xy 136.659511 -226.159298) (xy 136.609692 -226.150979)
			(xy 136.56192 -226.134575) (xy 136.517501 -226.110531) (xy 136.477644 -226.079505) (xy 136.443437 -226.042343)
			(xy 136.415812 -226.000057) (xy 136.395524 -225.953801) (xy 136.383126 -225.904837) (xy 136.378955 -225.8545)
			(xy 136.383126 -225.804163) (xy 136.395524 -225.755199) (xy 136.415812 -225.708943) (xy 136.443437 -225.666657)
			(xy 136.477644 -225.629495) (xy 136.517501 -225.598469) (xy 136.56192 -225.574425) (xy 136.609692 -225.558021)
			(xy 136.659511 -225.549702) (xy 136.684766 -225.549206) (xy 136.697529 -225.549346) (xy 136.722962 -225.551511)
			(xy 136.735566 -225.553524) (xy 136.761716 -225.558532) (xy 136.811877 -225.576372) (xy 136.858188 -225.602632)
			(xy 136.89925 -225.636518) (xy 136.93382 -225.677005) (xy 136.960853 -225.722869) (xy 136.97077 -225.74758)
			(xy 136.97458 -225.757994) (xy 136.982454 -225.765614) (xy 136.98982 -225.772454) (xy 137.008353 -225.780196)
			(xy 137.028437 -225.780196) (xy 137.04697 -225.772454) (xy 137.054336 -225.765614) (xy 137.071354 -225.748596)
			(xy 137.078212 -225.736404) (xy 137.079736 -225.729292) (xy 137.088039 -225.695507) (xy 137.111906 -225.630157)
			(xy 137.143693 -225.568271) (xy 137.182912 -225.510806) (xy 137.228955 -225.45865) (xy 137.281112 -225.412607)
			(xy 137.338577 -225.37339) (xy 137.400463 -225.341603) (xy 137.465814 -225.317737) (xy 137.499598 -225.30943)
			(xy 137.50671 -225.307906) (xy 137.518902 -225.301048) (xy 137.776204 -225.043746) (xy 137.779294 -225.040546)
			(xy 137.784398 -225.03326) (xy 137.786364 -225.029268) (xy 137.78992 -225.021648) (xy 137.790936 -225.013012)
			(xy 137.790936 -225.012758) (xy 137.794167 -224.98691) (xy 137.808288 -224.936772) (xy 137.830709 -224.889756)
			(xy 137.860779 -224.847224) (xy 137.897627 -224.810408) (xy 137.940186 -224.780375) (xy 137.987221 -224.757995)
			(xy 138.037371 -224.743917) (xy 138.063224 -224.740724) (xy 138.07186 -224.739708) (xy 138.07948 -224.736152)
			(xy 138.083459 -224.734168) (xy 138.090732 -224.729053) (xy 138.093958 -224.725992) (xy 138.33856 -224.48139)
			(xy 138.340592 -224.442528) (xy 138.328146 -224.427288) (xy 138.312079 -224.406713) (xy 138.28648 -224.361222)
			(xy 138.268989 -224.312041) (xy 138.260114 -224.260602) (xy 138.259566 -224.234502) (xy 138.259566 -224.226628)
			(xy 138.260773 -224.200817) (xy 138.270778 -224.150129) (xy 138.289172 -224.101848) (xy 138.315429 -224.057352)
			(xy 138.348801 -224.017909) (xy 138.388335 -223.984646) (xy 138.432903 -223.95851) (xy 138.481234 -223.940249)
			(xy 138.531949 -223.930382) (xy 138.557762 -223.929194) (xy 138.563096 -223.929194) (xy 138.564874 -223.929194)
			(xy 138.587984 -223.929595) (xy 138.633683 -223.936518) (xy 138.677814 -223.950254) (xy 138.719369 -223.97049)
			(xy 138.73861 -223.983296) (xy 138.744452 -223.987614) (xy 138.765026 -223.994218) (xy 138.769467 -223.995582)
			(xy 138.778669 -223.996863) (xy 138.783314 -223.996758) (xy 138.805412 -223.995742) (xy 138.814794 -223.994956)
			(xy 138.832025 -223.987399) (xy 138.83894 -223.98101) (xy 138.949938 -223.870012) (xy 138.956288 -223.862392)
			(xy 138.961456 -223.853745) (xy 138.96537 -223.834006) (xy 138.963908 -223.824038) (xy 138.945112 -223.730566)
			(xy 138.92911 -223.711008) (xy 138.917426 -223.706182) (xy 138.893934 -223.695847) (xy 138.850509 -223.668499)
			(xy 138.812273 -223.634269) (xy 138.780304 -223.594124) (xy 138.755504 -223.549196) (xy 138.738572 -223.500751)
			(xy 138.729985 -223.450155) (xy 138.729466 -223.424496) (xy 138.729937 -223.400504) (xy 138.737443 -223.353111)
			(xy 138.752271 -223.307476) (xy 138.774054 -223.264722) (xy 138.802257 -223.225902) (xy 138.836185 -223.191971)
			(xy 138.875004 -223.163766) (xy 138.917756 -223.141979) (xy 138.96339 -223.127148) (xy 139.010782 -223.119639)
			(xy 139.034774 -223.119188) (xy 139.060433 -223.119714) (xy 139.111029 -223.128298) (xy 139.159474 -223.145228)
			(xy 139.204403 -223.170027) (xy 139.244548 -223.201996) (xy 139.278777 -223.240232) (xy 139.306124 -223.283657)
			(xy 139.31646 -223.307148) (xy 139.321286 -223.318832) (xy 139.340844 -223.334834) (xy 139.434316 -223.35363)
			(xy 139.444286 -223.355233) (xy 139.464077 -223.351313) (xy 139.47267 -223.34601) (xy 139.476734 -223.343216)
			(xy 139.624054 -223.195896) (xy 139.630764 -223.188656) (xy 139.638354 -223.170452) (xy 139.638786 -223.16059)
			(xy 139.638786 -223.018858) (xy 139.638235 -223.008259) (xy 139.629697 -222.988854) (xy 139.622276 -222.981266)
			(xy 139.568682 -222.93199) (xy 139.560675 -222.925316) (xy 139.541001 -222.918493) (xy 139.530582 -222.918782)
			(xy 139.52982 -222.918782) (xy 139.504674 -222.919798) (xy 139.479421 -222.919274) (xy 139.429604 -222.910958)
			(xy 139.381836 -222.894555) (xy 139.337418 -222.870514) (xy 139.297563 -222.839491) (xy 139.263358 -222.80233)
			(xy 139.235735 -222.760047) (xy 139.215447 -222.713795) (xy 139.20305 -222.664834) (xy 139.198879 -222.6145)
			(xy 139.20305 -222.564166) (xy 139.215447 -222.515205) (xy 139.235735 -222.468953) (xy 139.263358 -222.42667)
			(xy 139.297563 -222.389509) (xy 139.337418 -222.358486) (xy 139.381836 -222.334445) (xy 139.429604 -222.318042)
			(xy 139.479421 -222.309726) (xy 139.504674 -222.309182) (xy 139.52982 -222.310198) (xy 139.530582 -222.310198)
			(xy 139.541002 -222.310482) (xy 139.560679 -222.303668) (xy 139.568682 -222.29699) (xy 139.62253 -222.24746)
			(xy 139.629832 -222.240044) (xy 139.638225 -222.221023) (xy 139.638786 -222.21063) (xy 139.638786 -221.046802)
			(xy 139.638306 -221.036941) (xy 139.630764 -221.018717) (xy 139.616825 -221.004764) (xy 139.598609 -220.997204)
			(xy 139.588748 -220.996764) (xy 128.99136 -220.996764) (xy 128.981519 -220.997294) (xy 128.963347 -221.004869)
			(xy 128.956054 -221.011496) (xy 128.163066 -221.804484) (xy 131.209046 -221.804484) (xy 131.213006 -221.75543)
			(xy 131.224783 -221.707646) (xy 131.244074 -221.66237) (xy 131.270377 -221.620774) (xy 131.303012 -221.583937)
			(xy 131.341133 -221.552812) (xy 131.383754 -221.528205) (xy 131.42977 -221.510753) (xy 131.477989 -221.500909)
			(xy 131.527164 -221.498928) (xy 131.576019 -221.50486) (xy 131.62329 -221.518552) (xy 131.667752 -221.53965)
			(xy 131.708255 -221.567606) (xy 131.743748 -221.601698) (xy 131.773313 -221.641042) (xy 131.796184 -221.684619)
			(xy 131.811768 -221.7313) (xy 131.819663 -221.779877) (xy 131.820158 -221.804484) (xy 132.148846 -221.804484)
			(xy 132.152806 -221.75543) (xy 132.164583 -221.707646) (xy 132.183874 -221.66237) (xy 132.210177 -221.620774)
			(xy 132.242812 -221.583937) (xy 132.280933 -221.552812) (xy 132.323554 -221.528205) (xy 132.36957 -221.510753)
			(xy 132.417789 -221.500909) (xy 132.466964 -221.498928) (xy 132.515819 -221.50486) (xy 132.56309 -221.518552)
			(xy 132.607552 -221.53965) (xy 132.648055 -221.567606) (xy 132.683548 -221.601698) (xy 132.713113 -221.641042)
			(xy 132.735984 -221.684619) (xy 132.751568 -221.7313) (xy 132.759463 -221.779877) (xy 132.759958 -221.804484)
			(xy 133.0889 -221.804484) (xy 133.09286 -221.75543) (xy 133.104637 -221.707646) (xy 133.123928 -221.66237)
			(xy 133.150231 -221.620774) (xy 133.182866 -221.583937) (xy 133.220987 -221.552812) (xy 133.263608 -221.528205)
			(xy 133.309624 -221.510753) (xy 133.357843 -221.500909) (xy 133.407018 -221.498928) (xy 133.455873 -221.50486)
			(xy 133.503144 -221.518552) (xy 133.547606 -221.53965) (xy 133.588109 -221.567606) (xy 133.623602 -221.601698)
			(xy 133.653167 -221.641042) (xy 133.676038 -221.684619) (xy 133.691622 -221.7313) (xy 133.699517 -221.779877)
			(xy 133.700012 -221.804484) (xy 134.969008 -221.804484) (xy 134.972968 -221.75543) (xy 134.984745 -221.707646)
			(xy 135.004036 -221.66237) (xy 135.030339 -221.620774) (xy 135.062974 -221.583937) (xy 135.101095 -221.552812)
			(xy 135.143716 -221.528205) (xy 135.189732 -221.510753) (xy 135.237951 -221.500909) (xy 135.287126 -221.498928)
			(xy 135.335981 -221.50486) (xy 135.352311 -221.50959) (xy 138.262118 -221.50959) (xy 138.266078 -221.460536)
			(xy 138.277855 -221.412752) (xy 138.297146 -221.367476) (xy 138.323449 -221.32588) (xy 138.356084 -221.289043)
			(xy 138.394205 -221.257918) (xy 138.436826 -221.233311) (xy 138.482842 -221.215859) (xy 138.531061 -221.206015)
			(xy 138.580236 -221.204034) (xy 138.629091 -221.209966) (xy 138.676362 -221.223658) (xy 138.720824 -221.244756)
			(xy 138.761327 -221.272712) (xy 138.79682 -221.306804) (xy 138.826385 -221.346148) (xy 138.849256 -221.389725)
			(xy 138.86484 -221.436406) (xy 138.872735 -221.484983) (xy 138.87323 -221.50959) (xy 138.872735 -221.534197)
			(xy 138.86484 -221.582774) (xy 138.849256 -221.629455) (xy 138.826385 -221.673032) (xy 138.79682 -221.712376)
			(xy 138.761327 -221.746468) (xy 138.720824 -221.774424) (xy 138.676362 -221.795522) (xy 138.629091 -221.809214)
			(xy 138.580236 -221.815146) (xy 138.531061 -221.813165) (xy 138.482842 -221.803321) (xy 138.436826 -221.785869)
			(xy 138.394205 -221.761262) (xy 138.356084 -221.730137) (xy 138.323449 -221.6933) (xy 138.297146 -221.651704)
			(xy 138.277855 -221.606428) (xy 138.266078 -221.558644) (xy 138.262118 -221.50959) (xy 135.352311 -221.50959)
			(xy 135.383252 -221.518552) (xy 135.427714 -221.53965) (xy 135.468217 -221.567606) (xy 135.50371 -221.601698)
			(xy 135.533275 -221.641042) (xy 135.556146 -221.684619) (xy 135.57173 -221.7313) (xy 135.579625 -221.779877)
			(xy 135.58012 -221.804484) (xy 135.579625 -221.829091) (xy 135.57173 -221.877668) (xy 135.556146 -221.924349)
			(xy 135.533275 -221.967926) (xy 135.50371 -222.00727) (xy 135.468217 -222.041362) (xy 135.427714 -222.069318)
			(xy 135.383252 -222.090416) (xy 135.335981 -222.104108) (xy 135.287126 -222.11004) (xy 135.237951 -222.108059)
			(xy 135.189732 -222.098215) (xy 135.143716 -222.080763) (xy 135.101095 -222.056156) (xy 135.062974 -222.025031)
			(xy 135.030339 -221.988194) (xy 135.004036 -221.946598) (xy 134.984745 -221.901322) (xy 134.972968 -221.853538)
			(xy 134.969008 -221.804484) (xy 133.700012 -221.804484) (xy 133.699517 -221.829091) (xy 133.691622 -221.877668)
			(xy 133.676038 -221.924349) (xy 133.653167 -221.967926) (xy 133.623602 -222.00727) (xy 133.588109 -222.041362)
			(xy 133.547606 -222.069318) (xy 133.503144 -222.090416) (xy 133.455873 -222.104108) (xy 133.407018 -222.11004)
			(xy 133.357843 -222.108059) (xy 133.309624 -222.098215) (xy 133.263608 -222.080763) (xy 133.220987 -222.056156)
			(xy 133.182866 -222.025031) (xy 133.150231 -221.988194) (xy 133.123928 -221.946598) (xy 133.104637 -221.901322)
			(xy 133.09286 -221.853538) (xy 133.0889 -221.804484) (xy 132.759958 -221.804484) (xy 132.759463 -221.829091)
			(xy 132.751568 -221.877668) (xy 132.735984 -221.924349) (xy 132.713113 -221.967926) (xy 132.683548 -222.00727)
			(xy 132.648055 -222.041362) (xy 132.607552 -222.069318) (xy 132.56309 -222.090416) (xy 132.515819 -222.104108)
			(xy 132.466964 -222.11004) (xy 132.417789 -222.108059) (xy 132.36957 -222.098215) (xy 132.323554 -222.080763)
			(xy 132.280933 -222.056156) (xy 132.242812 -222.025031) (xy 132.210177 -221.988194) (xy 132.183874 -221.946598)
			(xy 132.164583 -221.901322) (xy 132.152806 -221.853538) (xy 132.148846 -221.804484) (xy 131.820158 -221.804484)
			(xy 131.819663 -221.829091) (xy 131.811768 -221.877668) (xy 131.796184 -221.924349) (xy 131.773313 -221.967926)
			(xy 131.743748 -222.00727) (xy 131.708255 -222.041362) (xy 131.667752 -222.069318) (xy 131.62329 -222.090416)
			(xy 131.576019 -222.104108) (xy 131.527164 -222.11004) (xy 131.477989 -222.108059) (xy 131.42977 -222.098215)
			(xy 131.383754 -222.080763) (xy 131.341133 -222.056156) (xy 131.303012 -222.025031) (xy 131.270377 -221.988194)
			(xy 131.244074 -221.946598) (xy 131.224783 -221.901322) (xy 131.213006 -221.853538) (xy 131.209046 -221.804484)
			(xy 128.163066 -221.804484) (xy 127.904494 -222.063056) (xy 127.899796 -222.068067) (xy 127.893095 -222.080052)
			(xy 127.891286 -222.086678) (xy 127.889254 -222.094298) (xy 127.889762 -222.10776) (xy 127.892048 -222.114872)
			(xy 127.908693 -222.167895) (xy 127.935567 -222.27574) (xy 127.955018 -222.385168) (xy 127.966954 -222.495669)
			(xy 127.971321 -222.606727) (xy 127.971096 -222.61449) (xy 128.859038 -222.61449) (xy 128.862998 -222.565436)
			(xy 128.874775 -222.517652) (xy 128.894066 -222.472376) (xy 128.920369 -222.43078) (xy 128.953004 -222.393943)
			(xy 128.991125 -222.362818) (xy 129.033746 -222.338211) (xy 129.079762 -222.320759) (xy 129.127981 -222.310915)
			(xy 129.177156 -222.308934) (xy 129.226011 -222.314866) (xy 129.273282 -222.328558) (xy 129.317744 -222.349656)
			(xy 129.358247 -222.377612) (xy 129.39374 -222.411704) (xy 129.423305 -222.451048) (xy 129.446176 -222.494625)
			(xy 129.46176 -222.541306) (xy 129.469655 -222.589883) (xy 129.47015 -222.61449) (xy 129.798838 -222.61449)
			(xy 129.802798 -222.565436) (xy 129.814575 -222.517652) (xy 129.833866 -222.472376) (xy 129.860169 -222.43078)
			(xy 129.892804 -222.393943) (xy 129.930925 -222.362818) (xy 129.973546 -222.338211) (xy 130.019562 -222.320759)
			(xy 130.067781 -222.310915) (xy 130.116956 -222.308934) (xy 130.165811 -222.314866) (xy 130.213082 -222.328558)
			(xy 130.257544 -222.349656) (xy 130.298047 -222.377612) (xy 130.33354 -222.411704) (xy 130.363105 -222.451048)
			(xy 130.385976 -222.494625) (xy 130.40156 -222.541306) (xy 130.409455 -222.589883) (xy 130.40995 -222.61449)
			(xy 130.738892 -222.61449) (xy 130.742852 -222.565436) (xy 130.754629 -222.517652) (xy 130.77392 -222.472376)
			(xy 130.800223 -222.43078) (xy 130.832858 -222.393943) (xy 130.870979 -222.362818) (xy 130.9136 -222.338211)
			(xy 130.959616 -222.320759) (xy 131.007835 -222.310915) (xy 131.05701 -222.308934) (xy 131.105865 -222.314866)
			(xy 131.153136 -222.328558) (xy 131.197598 -222.349656) (xy 131.238101 -222.377612) (xy 131.273594 -222.411704)
			(xy 131.303159 -222.451048) (xy 131.32603 -222.494625) (xy 131.341614 -222.541306) (xy 131.349509 -222.589883)
			(xy 131.350004 -222.61449) (xy 131.678946 -222.61449) (xy 131.682906 -222.565436) (xy 131.694683 -222.517652)
			(xy 131.713974 -222.472376) (xy 131.740277 -222.43078) (xy 131.772912 -222.393943) (xy 131.811033 -222.362818)
			(xy 131.853654 -222.338211) (xy 131.89967 -222.320759) (xy 131.947889 -222.310915) (xy 131.997064 -222.308934)
			(xy 132.045919 -222.314866) (xy 132.09319 -222.328558) (xy 132.137652 -222.349656) (xy 132.178155 -222.377612)
			(xy 132.213648 -222.411704) (xy 132.243213 -222.451048) (xy 132.266084 -222.494625) (xy 132.281668 -222.541306)
			(xy 132.289563 -222.589883) (xy 132.290058 -222.61449) (xy 133.559054 -222.61449) (xy 133.563014 -222.565436)
			(xy 133.574791 -222.517652) (xy 133.594082 -222.472376) (xy 133.620385 -222.43078) (xy 133.65302 -222.393943)
			(xy 133.691141 -222.362818) (xy 133.733762 -222.338211) (xy 133.779778 -222.320759) (xy 133.827997 -222.310915)
			(xy 133.877172 -222.308934) (xy 133.926027 -222.314866) (xy 133.973298 -222.328558) (xy 134.01776 -222.349656)
			(xy 134.058263 -222.377612) (xy 134.093756 -222.411704) (xy 134.123321 -222.451048) (xy 134.146192 -222.494625)
			(xy 134.161776 -222.541306) (xy 134.169671 -222.589883) (xy 134.170166 -222.61449) (xy 134.498854 -222.61449)
			(xy 134.502814 -222.565436) (xy 134.514591 -222.517652) (xy 134.533882 -222.472376) (xy 134.560185 -222.43078)
			(xy 134.59282 -222.393943) (xy 134.630941 -222.362818) (xy 134.673562 -222.338211) (xy 134.719578 -222.320759)
			(xy 134.767797 -222.310915) (xy 134.816972 -222.308934) (xy 134.865827 -222.314866) (xy 134.913098 -222.328558)
			(xy 134.95756 -222.349656) (xy 134.998063 -222.377612) (xy 135.033556 -222.411704) (xy 135.063121 -222.451048)
			(xy 135.085992 -222.494625) (xy 135.101576 -222.541306) (xy 135.109471 -222.589883) (xy 135.109966 -222.61449)
			(xy 135.438908 -222.61449) (xy 135.442868 -222.565436) (xy 135.454645 -222.517652) (xy 135.473936 -222.472376)
			(xy 135.500239 -222.43078) (xy 135.532874 -222.393943) (xy 135.570995 -222.362818) (xy 135.613616 -222.338211)
			(xy 135.659632 -222.320759) (xy 135.707851 -222.310915) (xy 135.757026 -222.308934) (xy 135.805881 -222.314866)
			(xy 135.853152 -222.328558) (xy 135.897614 -222.349656) (xy 135.938117 -222.377612) (xy 135.97361 -222.411704)
			(xy 136.003175 -222.451048) (xy 136.026046 -222.494625) (xy 136.04163 -222.541306) (xy 136.049525 -222.589883)
			(xy 136.05002 -222.61449) (xy 137.319016 -222.61449) (xy 137.322976 -222.565436) (xy 137.334753 -222.517652)
			(xy 137.354044 -222.472376) (xy 137.380347 -222.43078) (xy 137.412982 -222.393943) (xy 137.451103 -222.362818)
			(xy 137.493724 -222.338211) (xy 137.53974 -222.320759) (xy 137.587959 -222.310915) (xy 137.637134 -222.308934)
			(xy 137.685989 -222.314866) (xy 137.73326 -222.328558) (xy 137.777722 -222.349656) (xy 137.818225 -222.377612)
			(xy 137.853718 -222.411704) (xy 137.883283 -222.451048) (xy 137.906154 -222.494625) (xy 137.921738 -222.541306)
			(xy 137.929633 -222.589883) (xy 137.930128 -222.61449) (xy 138.25907 -222.61449) (xy 138.26303 -222.565436)
			(xy 138.274807 -222.517652) (xy 138.294098 -222.472376) (xy 138.320401 -222.43078) (xy 138.353036 -222.393943)
			(xy 138.391157 -222.362818) (xy 138.433778 -222.338211) (xy 138.479794 -222.320759) (xy 138.528013 -222.310915)
			(xy 138.577188 -222.308934) (xy 138.626043 -222.314866) (xy 138.673314 -222.328558) (xy 138.717776 -222.349656)
			(xy 138.758279 -222.377612) (xy 138.793772 -222.411704) (xy 138.823337 -222.451048) (xy 138.846208 -222.494625)
			(xy 138.861792 -222.541306) (xy 138.869687 -222.589883) (xy 138.870182 -222.61449) (xy 138.869687 -222.639097)
			(xy 138.861792 -222.687674) (xy 138.846208 -222.734355) (xy 138.823337 -222.777932) (xy 138.793772 -222.817276)
			(xy 138.758279 -222.851368) (xy 138.717776 -222.879324) (xy 138.673314 -222.900422) (xy 138.626043 -222.914114)
			(xy 138.577188 -222.920046) (xy 138.528013 -222.918065) (xy 138.479794 -222.908221) (xy 138.433778 -222.890769)
			(xy 138.391157 -222.866162) (xy 138.353036 -222.835037) (xy 138.320401 -222.7982) (xy 138.294098 -222.756604)
			(xy 138.274807 -222.711328) (xy 138.26303 -222.663544) (xy 138.25907 -222.61449) (xy 137.930128 -222.61449)
			(xy 137.929633 -222.639097) (xy 137.921738 -222.687674) (xy 137.906154 -222.734355) (xy 137.883283 -222.777932)
			(xy 137.853718 -222.817276) (xy 137.818225 -222.851368) (xy 137.777722 -222.879324) (xy 137.73326 -222.900422)
			(xy 137.685989 -222.914114) (xy 137.637134 -222.920046) (xy 137.587959 -222.918065) (xy 137.53974 -222.908221)
			(xy 137.493724 -222.890769) (xy 137.451103 -222.866162) (xy 137.412982 -222.835037) (xy 137.380347 -222.7982)
			(xy 137.354044 -222.756604) (xy 137.334753 -222.711328) (xy 137.322976 -222.663544) (xy 137.319016 -222.61449)
			(xy 136.05002 -222.61449) (xy 136.049525 -222.639097) (xy 136.04163 -222.687674) (xy 136.026046 -222.734355)
			(xy 136.003175 -222.777932) (xy 135.97361 -222.817276) (xy 135.938117 -222.851368) (xy 135.897614 -222.879324)
			(xy 135.853152 -222.900422) (xy 135.805881 -222.914114) (xy 135.757026 -222.920046) (xy 135.707851 -222.918065)
			(xy 135.659632 -222.908221) (xy 135.613616 -222.890769) (xy 135.570995 -222.866162) (xy 135.532874 -222.835037)
			(xy 135.500239 -222.7982) (xy 135.473936 -222.756604) (xy 135.454645 -222.711328) (xy 135.442868 -222.663544)
			(xy 135.438908 -222.61449) (xy 135.109966 -222.61449) (xy 135.109471 -222.639097) (xy 135.101576 -222.687674)
			(xy 135.085992 -222.734355) (xy 135.063121 -222.777932) (xy 135.033556 -222.817276) (xy 134.998063 -222.851368)
			(xy 134.95756 -222.879324) (xy 134.913098 -222.900422) (xy 134.865827 -222.914114) (xy 134.816972 -222.920046)
			(xy 134.767797 -222.918065) (xy 134.719578 -222.908221) (xy 134.673562 -222.890769) (xy 134.630941 -222.866162)
			(xy 134.59282 -222.835037) (xy 134.560185 -222.7982) (xy 134.533882 -222.756604) (xy 134.514591 -222.711328)
			(xy 134.502814 -222.663544) (xy 134.498854 -222.61449) (xy 134.170166 -222.61449) (xy 134.169671 -222.639097)
			(xy 134.161776 -222.687674) (xy 134.146192 -222.734355) (xy 134.123321 -222.777932) (xy 134.093756 -222.817276)
			(xy 134.058263 -222.851368) (xy 134.01776 -222.879324) (xy 133.973298 -222.900422) (xy 133.926027 -222.914114)
			(xy 133.877172 -222.920046) (xy 133.827997 -222.918065) (xy 133.779778 -222.908221) (xy 133.733762 -222.890769)
			(xy 133.691141 -222.866162) (xy 133.65302 -222.835037) (xy 133.620385 -222.7982) (xy 133.594082 -222.756604)
			(xy 133.574791 -222.711328) (xy 133.563014 -222.663544) (xy 133.559054 -222.61449) (xy 132.290058 -222.61449)
			(xy 132.289563 -222.639097) (xy 132.281668 -222.687674) (xy 132.266084 -222.734355) (xy 132.243213 -222.777932)
			(xy 132.213648 -222.817276) (xy 132.178155 -222.851368) (xy 132.137652 -222.879324) (xy 132.09319 -222.900422)
			(xy 132.045919 -222.914114) (xy 131.997064 -222.920046) (xy 131.947889 -222.918065) (xy 131.89967 -222.908221)
			(xy 131.853654 -222.890769) (xy 131.811033 -222.866162) (xy 131.772912 -222.835037) (xy 131.740277 -222.7982)
			(xy 131.713974 -222.756604) (xy 131.694683 -222.711328) (xy 131.682906 -222.663544) (xy 131.678946 -222.61449)
			(xy 131.350004 -222.61449) (xy 131.349509 -222.639097) (xy 131.341614 -222.687674) (xy 131.32603 -222.734355)
			(xy 131.303159 -222.777932) (xy 131.273594 -222.817276) (xy 131.238101 -222.851368) (xy 131.197598 -222.879324)
			(xy 131.153136 -222.900422) (xy 131.105865 -222.914114) (xy 131.05701 -222.920046) (xy 131.007835 -222.918065)
			(xy 130.959616 -222.908221) (xy 130.9136 -222.890769) (xy 130.870979 -222.866162) (xy 130.832858 -222.835037)
			(xy 130.800223 -222.7982) (xy 130.77392 -222.756604) (xy 130.754629 -222.711328) (xy 130.742852 -222.663544)
			(xy 130.738892 -222.61449) (xy 130.40995 -222.61449) (xy 130.409455 -222.639097) (xy 130.40156 -222.687674)
			(xy 130.385976 -222.734355) (xy 130.363105 -222.777932) (xy 130.33354 -222.817276) (xy 130.298047 -222.851368)
			(xy 130.257544 -222.879324) (xy 130.213082 -222.900422) (xy 130.165811 -222.914114) (xy 130.116956 -222.920046)
			(xy 130.067781 -222.918065) (xy 130.019562 -222.908221) (xy 129.973546 -222.890769) (xy 129.930925 -222.866162)
			(xy 129.892804 -222.835037) (xy 129.860169 -222.7982) (xy 129.833866 -222.756604) (xy 129.814575 -222.711328)
			(xy 129.802798 -222.663544) (xy 129.798838 -222.61449) (xy 129.47015 -222.61449) (xy 129.469655 -222.639097)
			(xy 129.46176 -222.687674) (xy 129.446176 -222.734355) (xy 129.423305 -222.777932) (xy 129.39374 -222.817276)
			(xy 129.358247 -222.851368) (xy 129.317744 -222.879324) (xy 129.273282 -222.900422) (xy 129.226011 -222.914114)
			(xy 129.177156 -222.920046) (xy 129.127981 -222.918065) (xy 129.079762 -222.908221) (xy 129.033746 -222.890769)
			(xy 128.991125 -222.866162) (xy 128.953004 -222.835037) (xy 128.920369 -222.7982) (xy 128.894066 -222.756604)
			(xy 128.874775 -222.711328) (xy 128.862998 -222.663544) (xy 128.859038 -222.61449) (xy 127.971096 -222.61449)
			(xy 127.968097 -222.717824) (xy 127.957298 -222.828441) (xy 127.938975 -222.938064) (xy 127.913211 -223.04618)
			(xy 127.897128 -223.099376) (xy 127.89662 -223.1009) (xy 127.896112 -223.102678) (xy 127.894314 -223.111932)
			(xy 127.896938 -223.130586) (xy 127.901192 -223.139) (xy 127.90932 -223.153732) (xy 127.916686 -223.163892)
			(xy 127.920496 -223.167956) (xy 127.925576 -223.171512) (xy 127.92583 -223.171766) (xy 127.946111 -223.186094)
			(xy 127.982169 -223.220231) (xy 128.012228 -223.259753) (xy 128.035494 -223.303619) (xy 128.051354 -223.350671)
			(xy 128.059391 -223.399671) (xy 128.059391 -223.424496) (xy 128.388884 -223.424496) (xy 128.392844 -223.375442)
			(xy 128.404621 -223.327658) (xy 128.423912 -223.282382) (xy 128.450215 -223.240786) (xy 128.48285 -223.203949)
			(xy 128.520971 -223.172824) (xy 128.563592 -223.148217) (xy 128.609608 -223.130765) (xy 128.657827 -223.120921)
			(xy 128.707002 -223.11894) (xy 128.755857 -223.124872) (xy 128.803128 -223.138564) (xy 128.84759 -223.159662)
			(xy 128.888093 -223.187618) (xy 128.923586 -223.22171) (xy 128.953151 -223.261054) (xy 128.976022 -223.304631)
			(xy 128.991606 -223.351312) (xy 128.999501 -223.399889) (xy 128.999996 -223.424496) (xy 129.328938 -223.424496)
			(xy 129.332898 -223.375442) (xy 129.344675 -223.327658) (xy 129.363966 -223.282382) (xy 129.390269 -223.240786)
			(xy 129.422904 -223.203949) (xy 129.461025 -223.172824) (xy 129.503646 -223.148217) (xy 129.549662 -223.130765)
			(xy 129.597881 -223.120921) (xy 129.647056 -223.11894) (xy 129.695911 -223.124872) (xy 129.743182 -223.138564)
			(xy 129.787644 -223.159662) (xy 129.828147 -223.187618) (xy 129.86364 -223.22171) (xy 129.893205 -223.261054)
			(xy 129.916076 -223.304631) (xy 129.93166 -223.351312) (xy 129.939555 -223.399889) (xy 129.94005 -223.424496)
			(xy 130.268992 -223.424496) (xy 130.272952 -223.375442) (xy 130.284729 -223.327658) (xy 130.30402 -223.282382)
			(xy 130.330323 -223.240786) (xy 130.362958 -223.203949) (xy 130.401079 -223.172824) (xy 130.4437 -223.148217)
			(xy 130.489716 -223.130765) (xy 130.537935 -223.120921) (xy 130.58711 -223.11894) (xy 130.635965 -223.124872)
			(xy 130.683236 -223.138564) (xy 130.727698 -223.159662) (xy 130.768201 -223.187618) (xy 130.803694 -223.22171)
			(xy 130.833259 -223.261054) (xy 130.85613 -223.304631) (xy 130.871714 -223.351312) (xy 130.879609 -223.399889)
			(xy 130.880104 -223.424496) (xy 131.209046 -223.424496) (xy 131.213006 -223.375442) (xy 131.224783 -223.327658)
			(xy 131.244074 -223.282382) (xy 131.270377 -223.240786) (xy 131.303012 -223.203949) (xy 131.341133 -223.172824)
			(xy 131.383754 -223.148217) (xy 131.42977 -223.130765) (xy 131.477989 -223.120921) (xy 131.527164 -223.11894)
			(xy 131.576019 -223.124872) (xy 131.62329 -223.138564) (xy 131.667752 -223.159662) (xy 131.708255 -223.187618)
			(xy 131.743748 -223.22171) (xy 131.773313 -223.261054) (xy 131.796184 -223.304631) (xy 131.811768 -223.351312)
			(xy 131.819663 -223.399889) (xy 131.820158 -223.424496) (xy 132.148846 -223.424496) (xy 132.152806 -223.375442)
			(xy 132.164583 -223.327658) (xy 132.183874 -223.282382) (xy 132.210177 -223.240786) (xy 132.242812 -223.203949)
			(xy 132.280933 -223.172824) (xy 132.323554 -223.148217) (xy 132.36957 -223.130765) (xy 132.417789 -223.120921)
			(xy 132.466964 -223.11894) (xy 132.515819 -223.124872) (xy 132.56309 -223.138564) (xy 132.607552 -223.159662)
			(xy 132.648055 -223.187618) (xy 132.683548 -223.22171) (xy 132.713113 -223.261054) (xy 132.735984 -223.304631)
			(xy 132.751568 -223.351312) (xy 132.759463 -223.399889) (xy 132.759958 -223.424496) (xy 133.0889 -223.424496)
			(xy 133.09286 -223.375442) (xy 133.104637 -223.327658) (xy 133.123928 -223.282382) (xy 133.150231 -223.240786)
			(xy 133.182866 -223.203949) (xy 133.220987 -223.172824) (xy 133.263608 -223.148217) (xy 133.309624 -223.130765)
			(xy 133.357843 -223.120921) (xy 133.407018 -223.11894) (xy 133.455873 -223.124872) (xy 133.503144 -223.138564)
			(xy 133.547606 -223.159662) (xy 133.588109 -223.187618) (xy 133.623602 -223.22171) (xy 133.653167 -223.261054)
			(xy 133.676038 -223.304631) (xy 133.691622 -223.351312) (xy 133.699517 -223.399889) (xy 133.700012 -223.424496)
			(xy 134.028954 -223.424496) (xy 134.032914 -223.375442) (xy 134.044691 -223.327658) (xy 134.063982 -223.282382)
			(xy 134.090285 -223.240786) (xy 134.12292 -223.203949) (xy 134.161041 -223.172824) (xy 134.203662 -223.148217)
			(xy 134.249678 -223.130765) (xy 134.297897 -223.120921) (xy 134.347072 -223.11894) (xy 134.395927 -223.124872)
			(xy 134.443198 -223.138564) (xy 134.48766 -223.159662) (xy 134.528163 -223.187618) (xy 134.563656 -223.22171)
			(xy 134.593221 -223.261054) (xy 134.616092 -223.304631) (xy 134.631676 -223.351312) (xy 134.639571 -223.399889)
			(xy 134.640066 -223.424496) (xy 134.969008 -223.424496) (xy 134.972968 -223.375442) (xy 134.984745 -223.327658)
			(xy 135.004036 -223.282382) (xy 135.030339 -223.240786) (xy 135.062974 -223.203949) (xy 135.101095 -223.172824)
			(xy 135.143716 -223.148217) (xy 135.189732 -223.130765) (xy 135.237951 -223.120921) (xy 135.287126 -223.11894)
			(xy 135.335981 -223.124872) (xy 135.383252 -223.138564) (xy 135.427714 -223.159662) (xy 135.468217 -223.187618)
			(xy 135.50371 -223.22171) (xy 135.533275 -223.261054) (xy 135.556146 -223.304631) (xy 135.57173 -223.351312)
			(xy 135.579625 -223.399889) (xy 135.58012 -223.424496) (xy 136.848862 -223.424496) (xy 136.852822 -223.375442)
			(xy 136.864599 -223.327658) (xy 136.88389 -223.282382) (xy 136.910193 -223.240786) (xy 136.942828 -223.203949)
			(xy 136.980949 -223.172824) (xy 137.02357 -223.148217) (xy 137.069586 -223.130765) (xy 137.117805 -223.120921)
			(xy 137.16698 -223.11894) (xy 137.215835 -223.124872) (xy 137.263106 -223.138564) (xy 137.307568 -223.159662)
			(xy 137.348071 -223.187618) (xy 137.383564 -223.22171) (xy 137.413129 -223.261054) (xy 137.436 -223.304631)
			(xy 137.451584 -223.351312) (xy 137.459479 -223.399889) (xy 137.459974 -223.424496) (xy 137.788916 -223.424496)
			(xy 137.792876 -223.375442) (xy 137.804653 -223.327658) (xy 137.823944 -223.282382) (xy 137.850247 -223.240786)
			(xy 137.882882 -223.203949) (xy 137.921003 -223.172824) (xy 137.963624 -223.148217) (xy 138.00964 -223.130765)
			(xy 138.057859 -223.120921) (xy 138.107034 -223.11894) (xy 138.155889 -223.124872) (xy 138.20316 -223.138564)
			(xy 138.247622 -223.159662) (xy 138.288125 -223.187618) (xy 138.323618 -223.22171) (xy 138.353183 -223.261054)
			(xy 138.376054 -223.304631) (xy 138.391638 -223.351312) (xy 138.399533 -223.399889) (xy 138.400028 -223.424496)
			(xy 138.399533 -223.449103) (xy 138.391638 -223.49768) (xy 138.376054 -223.544361) (xy 138.353183 -223.587938)
			(xy 138.323618 -223.627282) (xy 138.288125 -223.661374) (xy 138.247622 -223.68933) (xy 138.20316 -223.710428)
			(xy 138.155889 -223.72412) (xy 138.107034 -223.730052) (xy 138.057859 -223.728071) (xy 138.00964 -223.718227)
			(xy 137.963624 -223.700775) (xy 137.921003 -223.676168) (xy 137.882882 -223.645043) (xy 137.850247 -223.608206)
			(xy 137.823944 -223.56661) (xy 137.804653 -223.521334) (xy 137.792876 -223.47355) (xy 137.788916 -223.424496)
			(xy 137.459974 -223.424496) (xy 137.459479 -223.449103) (xy 137.451584 -223.49768) (xy 137.436 -223.544361)
			(xy 137.413129 -223.587938) (xy 137.383564 -223.627282) (xy 137.348071 -223.661374) (xy 137.307568 -223.68933)
			(xy 137.263106 -223.710428) (xy 137.215835 -223.72412) (xy 137.16698 -223.730052) (xy 137.117805 -223.728071)
			(xy 137.069586 -223.718227) (xy 137.02357 -223.700775) (xy 136.980949 -223.676168) (xy 136.942828 -223.645043)
			(xy 136.910193 -223.608206) (xy 136.88389 -223.56661) (xy 136.864599 -223.521334) (xy 136.852822 -223.47355)
			(xy 136.848862 -223.424496) (xy 135.58012 -223.424496) (xy 135.579625 -223.449103) (xy 135.57173 -223.49768)
			(xy 135.556146 -223.544361) (xy 135.533275 -223.587938) (xy 135.50371 -223.627282) (xy 135.468217 -223.661374)
			(xy 135.427714 -223.68933) (xy 135.383252 -223.710428) (xy 135.335981 -223.72412) (xy 135.287126 -223.730052)
			(xy 135.237951 -223.728071) (xy 135.189732 -223.718227) (xy 135.143716 -223.700775) (xy 135.101095 -223.676168)
			(xy 135.062974 -223.645043) (xy 135.030339 -223.608206) (xy 135.004036 -223.56661) (xy 134.984745 -223.521334)
			(xy 134.972968 -223.47355) (xy 134.969008 -223.424496) (xy 134.640066 -223.424496) (xy 134.639571 -223.449103)
			(xy 134.631676 -223.49768) (xy 134.616092 -223.544361) (xy 134.593221 -223.587938) (xy 134.563656 -223.627282)
			(xy 134.528163 -223.661374) (xy 134.48766 -223.68933) (xy 134.443198 -223.710428) (xy 134.395927 -223.72412)
			(xy 134.347072 -223.730052) (xy 134.297897 -223.728071) (xy 134.249678 -223.718227) (xy 134.203662 -223.700775)
			(xy 134.161041 -223.676168) (xy 134.12292 -223.645043) (xy 134.090285 -223.608206) (xy 134.063982 -223.56661)
			(xy 134.044691 -223.521334) (xy 134.032914 -223.47355) (xy 134.028954 -223.424496) (xy 133.700012 -223.424496)
			(xy 133.699517 -223.449103) (xy 133.691622 -223.49768) (xy 133.676038 -223.544361) (xy 133.653167 -223.587938)
			(xy 133.623602 -223.627282) (xy 133.588109 -223.661374) (xy 133.547606 -223.68933) (xy 133.503144 -223.710428)
			(xy 133.455873 -223.72412) (xy 133.407018 -223.730052) (xy 133.357843 -223.728071) (xy 133.309624 -223.718227)
			(xy 133.263608 -223.700775) (xy 133.220987 -223.676168) (xy 133.182866 -223.645043) (xy 133.150231 -223.608206)
			(xy 133.123928 -223.56661) (xy 133.104637 -223.521334) (xy 133.09286 -223.47355) (xy 133.0889 -223.424496)
			(xy 132.759958 -223.424496) (xy 132.759463 -223.449103) (xy 132.751568 -223.49768) (xy 132.735984 -223.544361)
			(xy 132.713113 -223.587938) (xy 132.683548 -223.627282) (xy 132.648055 -223.661374) (xy 132.607552 -223.68933)
			(xy 132.56309 -223.710428) (xy 132.515819 -223.72412) (xy 132.466964 -223.730052) (xy 132.417789 -223.728071)
			(xy 132.36957 -223.718227) (xy 132.323554 -223.700775) (xy 132.280933 -223.676168) (xy 132.242812 -223.645043)
			(xy 132.210177 -223.608206) (xy 132.183874 -223.56661) (xy 132.164583 -223.521334) (xy 132.152806 -223.47355)
			(xy 132.148846 -223.424496) (xy 131.820158 -223.424496) (xy 131.819663 -223.449103) (xy 131.811768 -223.49768)
			(xy 131.796184 -223.544361) (xy 131.773313 -223.587938) (xy 131.743748 -223.627282) (xy 131.708255 -223.661374)
			(xy 131.667752 -223.68933) (xy 131.62329 -223.710428) (xy 131.576019 -223.72412) (xy 131.527164 -223.730052)
			(xy 131.477989 -223.728071) (xy 131.42977 -223.718227) (xy 131.383754 -223.700775) (xy 131.341133 -223.676168)
			(xy 131.303012 -223.645043) (xy 131.270377 -223.608206) (xy 131.244074 -223.56661) (xy 131.224783 -223.521334)
			(xy 131.213006 -223.47355) (xy 131.209046 -223.424496) (xy 130.880104 -223.424496) (xy 130.879609 -223.449103)
			(xy 130.871714 -223.49768) (xy 130.85613 -223.544361) (xy 130.833259 -223.587938) (xy 130.803694 -223.627282)
			(xy 130.768201 -223.661374) (xy 130.727698 -223.68933) (xy 130.683236 -223.710428) (xy 130.635965 -223.72412)
			(xy 130.58711 -223.730052) (xy 130.537935 -223.728071) (xy 130.489716 -223.718227) (xy 130.4437 -223.700775)
			(xy 130.401079 -223.676168) (xy 130.362958 -223.645043) (xy 130.330323 -223.608206) (xy 130.30402 -223.56661)
			(xy 130.284729 -223.521334) (xy 130.272952 -223.47355) (xy 130.268992 -223.424496) (xy 129.94005 -223.424496)
			(xy 129.939555 -223.449103) (xy 129.93166 -223.49768) (xy 129.916076 -223.544361) (xy 129.893205 -223.587938)
			(xy 129.86364 -223.627282) (xy 129.828147 -223.661374) (xy 129.787644 -223.68933) (xy 129.743182 -223.710428)
			(xy 129.695911 -223.72412) (xy 129.647056 -223.730052) (xy 129.597881 -223.728071) (xy 129.549662 -223.718227)
			(xy 129.503646 -223.700775) (xy 129.461025 -223.676168) (xy 129.422904 -223.645043) (xy 129.390269 -223.608206)
			(xy 129.363966 -223.56661) (xy 129.344675 -223.521334) (xy 129.332898 -223.47355) (xy 129.328938 -223.424496)
			(xy 128.999996 -223.424496) (xy 128.999501 -223.449103) (xy 128.991606 -223.49768) (xy 128.976022 -223.544361)
			(xy 128.953151 -223.587938) (xy 128.923586 -223.627282) (xy 128.888093 -223.661374) (xy 128.84759 -223.68933)
			(xy 128.803128 -223.710428) (xy 128.755857 -223.72412) (xy 128.707002 -223.730052) (xy 128.657827 -223.728071)
			(xy 128.609608 -223.718227) (xy 128.563592 -223.700775) (xy 128.520971 -223.676168) (xy 128.48285 -223.645043)
			(xy 128.450215 -223.608206) (xy 128.423912 -223.56661) (xy 128.404621 -223.521334) (xy 128.392844 -223.47355)
			(xy 128.388884 -223.424496) (xy 128.059391 -223.424496) (xy 128.059391 -223.449325) (xy 128.051355 -223.498324)
			(xy 128.035496 -223.545377) (xy 128.01223 -223.589243) (xy 127.982172 -223.628766) (xy 127.946114 -223.662903)
			(xy 127.92583 -223.677226) (xy 127.925576 -223.67748) (xy 127.920496 -223.681036) (xy 127.916686 -223.6851)
			(xy 127.90932 -223.69526) (xy 127.901192 -223.709992) (xy 127.897009 -223.718427) (xy 127.8944 -223.737056)
			(xy 127.896112 -223.746314) (xy 127.89662 -223.748092) (xy 127.897128 -223.749616) (xy 127.908289 -223.786099)
			(xy 127.927602 -223.859916) (xy 127.935736 -223.89719) (xy 127.935736 -223.897698) (xy 127.93878 -223.9091)
			(xy 127.95348 -223.927524) (xy 127.96393 -223.933004) (xy 128.04648 -223.971358) (xy 128.070102 -223.970596)
			(xy 128.08077 -223.965008) (xy 128.103063 -223.953661) (xy 128.150428 -223.937583) (xy 128.199778 -223.929435)
			(xy 128.224788 -223.92894) (xy 128.234694 -223.92894) (xy 128.24841 -223.93021) (xy 128.273634 -223.932675)
			(xy 128.322817 -223.944895) (xy 128.369309 -223.965067) (xy 128.411833 -223.992636) (xy 128.449223 -224.026846)
			(xy 128.480453 -224.066758) (xy 128.504666 -224.111279) (xy 128.521198 -224.159185) (xy 128.529596 -224.209163)
			(xy 128.530096 -224.234502) (xy 128.859038 -224.234502) (xy 128.862998 -224.185448) (xy 128.874775 -224.137664)
			(xy 128.894066 -224.092388) (xy 128.920369 -224.050792) (xy 128.953004 -224.013955) (xy 128.991125 -223.98283)
			(xy 129.033746 -223.958223) (xy 129.079762 -223.940771) (xy 129.127981 -223.930927) (xy 129.177156 -223.928946)
			(xy 129.226011 -223.934878) (xy 129.273282 -223.94857) (xy 129.317744 -223.969668) (xy 129.358247 -223.997624)
			(xy 129.39374 -224.031716) (xy 129.423305 -224.07106) (xy 129.446176 -224.114637) (xy 129.46176 -224.161318)
			(xy 129.469655 -224.209895) (xy 129.47015 -224.234502) (xy 129.798838 -224.234502) (xy 129.802798 -224.185448)
			(xy 129.814575 -224.137664) (xy 129.833866 -224.092388) (xy 129.860169 -224.050792) (xy 129.892804 -224.013955)
			(xy 129.930925 -223.98283) (xy 129.973546 -223.958223) (xy 130.019562 -223.940771) (xy 130.067781 -223.930927)
			(xy 130.116956 -223.928946) (xy 130.165811 -223.934878) (xy 130.213082 -223.94857) (xy 130.257544 -223.969668)
			(xy 130.298047 -223.997624) (xy 130.33354 -224.031716) (xy 130.363105 -224.07106) (xy 130.385976 -224.114637)
			(xy 130.40156 -224.161318) (xy 130.409455 -224.209895) (xy 130.40995 -224.234502) (xy 130.738892 -224.234502)
			(xy 130.742852 -224.185448) (xy 130.754629 -224.137664) (xy 130.77392 -224.092388) (xy 130.800223 -224.050792)
			(xy 130.832858 -224.013955) (xy 130.870979 -223.98283) (xy 130.9136 -223.958223) (xy 130.959616 -223.940771)
			(xy 131.007835 -223.930927) (xy 131.05701 -223.928946) (xy 131.105865 -223.934878) (xy 131.153136 -223.94857)
			(xy 131.197598 -223.969668) (xy 131.238101 -223.997624) (xy 131.273594 -224.031716) (xy 131.303159 -224.07106)
			(xy 131.32603 -224.114637) (xy 131.341614 -224.161318) (xy 131.349509 -224.209895) (xy 131.350004 -224.234502)
			(xy 131.678946 -224.234502) (xy 131.682906 -224.185448) (xy 131.694683 -224.137664) (xy 131.713974 -224.092388)
			(xy 131.740277 -224.050792) (xy 131.772912 -224.013955) (xy 131.811033 -223.98283) (xy 131.853654 -223.958223)
			(xy 131.89967 -223.940771) (xy 131.947889 -223.930927) (xy 131.997064 -223.928946) (xy 132.045919 -223.934878)
			(xy 132.09319 -223.94857) (xy 132.137652 -223.969668) (xy 132.178155 -223.997624) (xy 132.213648 -224.031716)
			(xy 132.243213 -224.07106) (xy 132.266084 -224.114637) (xy 132.281668 -224.161318) (xy 132.289563 -224.209895)
			(xy 132.290058 -224.234502) (xy 132.619 -224.234502) (xy 132.62296 -224.185448) (xy 132.634737 -224.137664)
			(xy 132.654028 -224.092388) (xy 132.680331 -224.050792) (xy 132.712966 -224.013955) (xy 132.751087 -223.98283)
			(xy 132.793708 -223.958223) (xy 132.839724 -223.940771) (xy 132.887943 -223.930927) (xy 132.937118 -223.928946)
			(xy 132.985973 -223.934878) (xy 133.033244 -223.94857) (xy 133.077706 -223.969668) (xy 133.118209 -223.997624)
			(xy 133.153702 -224.031716) (xy 133.183267 -224.07106) (xy 133.206138 -224.114637) (xy 133.221722 -224.161318)
			(xy 133.229617 -224.209895) (xy 133.230112 -224.234502) (xy 133.559054 -224.234502) (xy 133.563014 -224.185448)
			(xy 133.574791 -224.137664) (xy 133.594082 -224.092388) (xy 133.620385 -224.050792) (xy 133.65302 -224.013955)
			(xy 133.691141 -223.98283) (xy 133.733762 -223.958223) (xy 133.779778 -223.940771) (xy 133.827997 -223.930927)
			(xy 133.877172 -223.928946) (xy 133.926027 -223.934878) (xy 133.973298 -223.94857) (xy 134.01776 -223.969668)
			(xy 134.058263 -223.997624) (xy 134.093756 -224.031716) (xy 134.123321 -224.07106) (xy 134.146192 -224.114637)
			(xy 134.161776 -224.161318) (xy 134.169671 -224.209895) (xy 134.170166 -224.234502) (xy 134.498854 -224.234502)
			(xy 134.502814 -224.185448) (xy 134.514591 -224.137664) (xy 134.533882 -224.092388) (xy 134.560185 -224.050792)
			(xy 134.59282 -224.013955) (xy 134.630941 -223.98283) (xy 134.673562 -223.958223) (xy 134.719578 -223.940771)
			(xy 134.767797 -223.930927) (xy 134.816972 -223.928946) (xy 134.865827 -223.934878) (xy 134.913098 -223.94857)
			(xy 134.95756 -223.969668) (xy 134.998063 -223.997624) (xy 135.033556 -224.031716) (xy 135.063121 -224.07106)
			(xy 135.085992 -224.114637) (xy 135.101576 -224.161318) (xy 135.109471 -224.209895) (xy 135.109966 -224.234502)
			(xy 135.438908 -224.234502) (xy 135.442868 -224.185448) (xy 135.454645 -224.137664) (xy 135.473936 -224.092388)
			(xy 135.500239 -224.050792) (xy 135.532874 -224.013955) (xy 135.570995 -223.98283) (xy 135.613616 -223.958223)
			(xy 135.659632 -223.940771) (xy 135.707851 -223.930927) (xy 135.757026 -223.928946) (xy 135.805881 -223.934878)
			(xy 135.853152 -223.94857) (xy 135.897614 -223.969668) (xy 135.938117 -223.997624) (xy 135.97361 -224.031716)
			(xy 136.003175 -224.07106) (xy 136.026046 -224.114637) (xy 136.04163 -224.161318) (xy 136.049525 -224.209895)
			(xy 136.05002 -224.234502) (xy 136.378962 -224.234502) (xy 136.382922 -224.185448) (xy 136.394699 -224.137664)
			(xy 136.41399 -224.092388) (xy 136.440293 -224.050792) (xy 136.472928 -224.013955) (xy 136.511049 -223.98283)
			(xy 136.55367 -223.958223) (xy 136.599686 -223.940771) (xy 136.647905 -223.930927) (xy 136.69708 -223.928946)
			(xy 136.745935 -223.934878) (xy 136.793206 -223.94857) (xy 136.837668 -223.969668) (xy 136.878171 -223.997624)
			(xy 136.913664 -224.031716) (xy 136.943229 -224.07106) (xy 136.9661 -224.114637) (xy 136.981684 -224.161318)
			(xy 136.989579 -224.209895) (xy 136.990074 -224.234502) (xy 137.319016 -224.234502) (xy 137.322976 -224.185448)
			(xy 137.334753 -224.137664) (xy 137.354044 -224.092388) (xy 137.380347 -224.050792) (xy 137.412982 -224.013955)
			(xy 137.451103 -223.98283) (xy 137.493724 -223.958223) (xy 137.53974 -223.940771) (xy 137.587959 -223.930927)
			(xy 137.637134 -223.928946) (xy 137.685989 -223.934878) (xy 137.73326 -223.94857) (xy 137.777722 -223.969668)
			(xy 137.818225 -223.997624) (xy 137.853718 -224.031716) (xy 137.883283 -224.07106) (xy 137.906154 -224.114637)
			(xy 137.921738 -224.161318) (xy 137.929633 -224.209895) (xy 137.930128 -224.234502) (xy 137.929633 -224.259109)
			(xy 137.921738 -224.307686) (xy 137.906154 -224.354367) (xy 137.883283 -224.397944) (xy 137.853718 -224.437288)
			(xy 137.818225 -224.47138) (xy 137.777722 -224.499336) (xy 137.73326 -224.520434) (xy 137.685989 -224.534126)
			(xy 137.637134 -224.540058) (xy 137.587959 -224.538077) (xy 137.53974 -224.528233) (xy 137.493724 -224.510781)
			(xy 137.451103 -224.486174) (xy 137.412982 -224.455049) (xy 137.380347 -224.418212) (xy 137.354044 -224.376616)
			(xy 137.334753 -224.33134) (xy 137.322976 -224.283556) (xy 137.319016 -224.234502) (xy 136.990074 -224.234502)
			(xy 136.989579 -224.259109) (xy 136.981684 -224.307686) (xy 136.9661 -224.354367) (xy 136.943229 -224.397944)
			(xy 136.913664 -224.437288) (xy 136.878171 -224.47138) (xy 136.837668 -224.499336) (xy 136.793206 -224.520434)
			(xy 136.745935 -224.534126) (xy 136.69708 -224.540058) (xy 136.647905 -224.538077) (xy 136.599686 -224.528233)
			(xy 136.55367 -224.510781) (xy 136.511049 -224.486174) (xy 136.472928 -224.455049) (xy 136.440293 -224.418212)
			(xy 136.41399 -224.376616) (xy 136.394699 -224.33134) (xy 136.382922 -224.283556) (xy 136.378962 -224.234502)
			(xy 136.05002 -224.234502) (xy 136.049525 -224.259109) (xy 136.04163 -224.307686) (xy 136.026046 -224.354367)
			(xy 136.003175 -224.397944) (xy 135.97361 -224.437288) (xy 135.938117 -224.47138) (xy 135.897614 -224.499336)
			(xy 135.853152 -224.520434) (xy 135.805881 -224.534126) (xy 135.757026 -224.540058) (xy 135.707851 -224.538077)
			(xy 135.659632 -224.528233) (xy 135.613616 -224.510781) (xy 135.570995 -224.486174) (xy 135.532874 -224.455049)
			(xy 135.500239 -224.418212) (xy 135.473936 -224.376616) (xy 135.454645 -224.33134) (xy 135.442868 -224.283556)
			(xy 135.438908 -224.234502) (xy 135.109966 -224.234502) (xy 135.109471 -224.259109) (xy 135.101576 -224.307686)
			(xy 135.085992 -224.354367) (xy 135.063121 -224.397944) (xy 135.033556 -224.437288) (xy 134.998063 -224.47138)
			(xy 134.95756 -224.499336) (xy 134.913098 -224.520434) (xy 134.865827 -224.534126) (xy 134.816972 -224.540058)
			(xy 134.767797 -224.538077) (xy 134.719578 -224.528233) (xy 134.673562 -224.510781) (xy 134.630941 -224.486174)
			(xy 134.59282 -224.455049) (xy 134.560185 -224.418212) (xy 134.533882 -224.376616) (xy 134.514591 -224.33134)
			(xy 134.502814 -224.283556) (xy 134.498854 -224.234502) (xy 134.170166 -224.234502) (xy 134.169671 -224.259109)
			(xy 134.161776 -224.307686) (xy 134.146192 -224.354367) (xy 134.123321 -224.397944) (xy 134.093756 -224.437288)
			(xy 134.058263 -224.47138) (xy 134.01776 -224.499336) (xy 133.973298 -224.520434) (xy 133.926027 -224.534126)
			(xy 133.877172 -224.540058) (xy 133.827997 -224.538077) (xy 133.779778 -224.528233) (xy 133.733762 -224.510781)
			(xy 133.691141 -224.486174) (xy 133.65302 -224.455049) (xy 133.620385 -224.418212) (xy 133.594082 -224.376616)
			(xy 133.574791 -224.33134) (xy 133.563014 -224.283556) (xy 133.559054 -224.234502) (xy 133.230112 -224.234502)
			(xy 133.229617 -224.259109) (xy 133.221722 -224.307686) (xy 133.206138 -224.354367) (xy 133.183267 -224.397944)
			(xy 133.153702 -224.437288) (xy 133.118209 -224.47138) (xy 133.077706 -224.499336) (xy 133.033244 -224.520434)
			(xy 132.985973 -224.534126) (xy 132.937118 -224.540058) (xy 132.887943 -224.538077) (xy 132.839724 -224.528233)
			(xy 132.793708 -224.510781) (xy 132.751087 -224.486174) (xy 132.712966 -224.455049) (xy 132.680331 -224.418212)
			(xy 132.654028 -224.376616) (xy 132.634737 -224.33134) (xy 132.62296 -224.283556) (xy 132.619 -224.234502)
			(xy 132.290058 -224.234502) (xy 132.289563 -224.259109) (xy 132.281668 -224.307686) (xy 132.266084 -224.354367)
			(xy 132.243213 -224.397944) (xy 132.213648 -224.437288) (xy 132.178155 -224.47138) (xy 132.137652 -224.499336)
			(xy 132.09319 -224.520434) (xy 132.045919 -224.534126) (xy 131.997064 -224.540058) (xy 131.947889 -224.538077)
			(xy 131.89967 -224.528233) (xy 131.853654 -224.510781) (xy 131.811033 -224.486174) (xy 131.772912 -224.455049)
			(xy 131.740277 -224.418212) (xy 131.713974 -224.376616) (xy 131.694683 -224.33134) (xy 131.682906 -224.283556)
			(xy 131.678946 -224.234502) (xy 131.350004 -224.234502) (xy 131.349509 -224.259109) (xy 131.341614 -224.307686)
			(xy 131.32603 -224.354367) (xy 131.303159 -224.397944) (xy 131.273594 -224.437288) (xy 131.238101 -224.47138)
			(xy 131.197598 -224.499336) (xy 131.153136 -224.520434) (xy 131.105865 -224.534126) (xy 131.05701 -224.540058)
			(xy 131.007835 -224.538077) (xy 130.959616 -224.528233) (xy 130.9136 -224.510781) (xy 130.870979 -224.486174)
			(xy 130.832858 -224.455049) (xy 130.800223 -224.418212) (xy 130.77392 -224.376616) (xy 130.754629 -224.33134)
			(xy 130.742852 -224.283556) (xy 130.738892 -224.234502) (xy 130.40995 -224.234502) (xy 130.409455 -224.259109)
			(xy 130.40156 -224.307686) (xy 130.385976 -224.354367) (xy 130.363105 -224.397944) (xy 130.33354 -224.437288)
			(xy 130.298047 -224.47138) (xy 130.257544 -224.499336) (xy 130.213082 -224.520434) (xy 130.165811 -224.534126)
			(xy 130.116956 -224.540058) (xy 130.067781 -224.538077) (xy 130.019562 -224.528233) (xy 129.973546 -224.510781)
			(xy 129.930925 -224.486174) (xy 129.892804 -224.455049) (xy 129.860169 -224.418212) (xy 129.833866 -224.376616)
			(xy 129.814575 -224.33134) (xy 129.802798 -224.283556) (xy 129.798838 -224.234502) (xy 129.47015 -224.234502)
			(xy 129.469655 -224.259109) (xy 129.46176 -224.307686) (xy 129.446176 -224.354367) (xy 129.423305 -224.397944)
			(xy 129.39374 -224.437288) (xy 129.358247 -224.47138) (xy 129.317744 -224.499336) (xy 129.273282 -224.520434)
			(xy 129.226011 -224.534126) (xy 129.177156 -224.540058) (xy 129.127981 -224.538077) (xy 129.079762 -224.528233)
			(xy 129.033746 -224.510781) (xy 128.991125 -224.486174) (xy 128.953004 -224.455049) (xy 128.920369 -224.418212)
			(xy 128.894066 -224.376616) (xy 128.874775 -224.33134) (xy 128.862998 -224.283556) (xy 128.859038 -224.234502)
			(xy 128.530096 -224.234502) (xy 128.529631 -224.25874) (xy 128.521972 -224.306608) (xy 128.506848 -224.352666)
			(xy 128.484637 -224.395755) (xy 128.455898 -224.434794) (xy 128.421353 -224.468803) (xy 128.381869 -224.496928)
			(xy 128.338437 -224.518462) (xy 128.292149 -224.532864) (xy 128.268222 -224.536762) (xy 128.25603 -224.53854)
			(xy 128.224788 -224.540064) (xy 128.19982 -224.53955) (xy 128.150555 -224.531396) (xy 128.103271 -224.515341)
			(xy 128.081024 -224.503996) (xy 128.080516 -224.503996) (xy 128.080516 -224.503742) (xy 128.069864 -224.498801)
			(xy 128.046418 -224.498262) (xy 128.035558 -224.502726) (xy 127.96393 -224.536) (xy 127.953533 -224.541549)
			(xy 127.938831 -224.559936) (xy 127.935736 -224.571306) (xy 127.935736 -224.571814) (xy 127.927607 -224.60909)
			(xy 127.908293 -224.682907) (xy 127.897128 -224.719388) (xy 127.89662 -224.720912) (xy 127.896112 -224.72269)
			(xy 127.894298 -224.731947) (xy 127.896893 -224.750617) (xy 127.901192 -224.759012) (xy 127.90932 -224.773744)
			(xy 127.916686 -224.783904) (xy 127.920496 -224.787968) (xy 127.925576 -224.791524) (xy 127.92583 -224.791778)
			(xy 127.94611 -224.806106) (xy 127.982167 -224.840242) (xy 128.012223 -224.879764) (xy 128.035488 -224.923629)
			(xy 128.051346 -224.97068) (xy 128.059381 -225.019678) (xy 128.05938 -225.044508) (xy 128.388884 -225.044508)
			(xy 128.392844 -224.995454) (xy 128.404621 -224.94767) (xy 128.423912 -224.902394) (xy 128.450215 -224.860798)
			(xy 128.48285 -224.823961) (xy 128.520971 -224.792836) (xy 128.563592 -224.768229) (xy 128.609608 -224.750777)
			(xy 128.657827 -224.740933) (xy 128.707002 -224.738952) (xy 128.755857 -224.744884) (xy 128.803128 -224.758576)
			(xy 128.84759 -224.779674) (xy 128.888093 -224.80763) (xy 128.923586 -224.841722) (xy 128.953151 -224.881066)
			(xy 128.976022 -224.924643) (xy 128.991606 -224.971324) (xy 128.999501 -225.019901) (xy 128.999996 -225.044508)
			(xy 129.318507 -225.044508) (xy 129.322602 -224.99378) (xy 129.334781 -224.944366) (xy 129.354729 -224.897546)
			(xy 129.38193 -224.854532) (xy 129.415678 -224.816438) (xy 129.4551 -224.784251) (xy 129.499174 -224.758805)
			(xy 129.54676 -224.740758) (xy 129.596624 -224.730578) (xy 129.647476 -224.728529) (xy 129.697997 -224.734663)
			(xy 129.746881 -224.748823) (xy 129.79286 -224.77064) (xy 129.834744 -224.79955) (xy 129.871448 -224.834805)
			(xy 129.902021 -224.875491) (xy 129.925672 -224.920554) (xy 129.941788 -224.968828) (xy 129.949952 -225.019062)
			(xy 129.950464 -225.044508) (xy 130.268992 -225.044508) (xy 130.272952 -224.995454) (xy 130.284729 -224.94767)
			(xy 130.30402 -224.902394) (xy 130.330323 -224.860798) (xy 130.362958 -224.823961) (xy 130.401079 -224.792836)
			(xy 130.4437 -224.768229) (xy 130.489716 -224.750777) (xy 130.537935 -224.740933) (xy 130.58711 -224.738952)
			(xy 130.635965 -224.744884) (xy 130.683236 -224.758576) (xy 130.727698 -224.779674) (xy 130.768201 -224.80763)
			(xy 130.803694 -224.841722) (xy 130.833259 -224.881066) (xy 130.85613 -224.924643) (xy 130.871714 -224.971324)
			(xy 130.879609 -225.019901) (xy 130.880104 -225.044508) (xy 131.209046 -225.044508) (xy 131.213006 -224.995454)
			(xy 131.224783 -224.94767) (xy 131.244074 -224.902394) (xy 131.270377 -224.860798) (xy 131.303012 -224.823961)
			(xy 131.341133 -224.792836) (xy 131.383754 -224.768229) (xy 131.42977 -224.750777) (xy 131.477989 -224.740933)
			(xy 131.527164 -224.738952) (xy 131.576019 -224.744884) (xy 131.62329 -224.758576) (xy 131.667752 -224.779674)
			(xy 131.708255 -224.80763) (xy 131.743748 -224.841722) (xy 131.773313 -224.881066) (xy 131.796184 -224.924643)
			(xy 131.811768 -224.971324) (xy 131.819663 -225.019901) (xy 131.820158 -225.044508) (xy 132.138415 -225.044508)
			(xy 132.14251 -224.99378) (xy 132.154689 -224.944366) (xy 132.174637 -224.897546) (xy 132.201838 -224.854532)
			(xy 132.235586 -224.816438) (xy 132.275008 -224.784251) (xy 132.319082 -224.758805) (xy 132.366668 -224.740758)
			(xy 132.416532 -224.730578) (xy 132.467384 -224.728529) (xy 132.517905 -224.734663) (xy 132.566789 -224.748823)
			(xy 132.612768 -224.77064) (xy 132.654652 -224.79955) (xy 132.691356 -224.834805) (xy 132.721929 -224.875491)
			(xy 132.74558 -224.920554) (xy 132.761696 -224.968828) (xy 132.76986 -225.019062) (xy 132.770372 -225.044508)
			(xy 133.0889 -225.044508) (xy 133.09286 -224.995454) (xy 133.104637 -224.94767) (xy 133.123928 -224.902394)
			(xy 133.150231 -224.860798) (xy 133.182866 -224.823961) (xy 133.220987 -224.792836) (xy 133.263608 -224.768229)
			(xy 133.309624 -224.750777) (xy 133.357843 -224.740933) (xy 133.407018 -224.738952) (xy 133.455873 -224.744884)
			(xy 133.503144 -224.758576) (xy 133.547606 -224.779674) (xy 133.588109 -224.80763) (xy 133.623602 -224.841722)
			(xy 133.653167 -224.881066) (xy 133.676038 -224.924643) (xy 133.691622 -224.971324) (xy 133.699517 -225.019901)
			(xy 133.700012 -225.044508) (xy 134.028954 -225.044508) (xy 134.032914 -224.995454) (xy 134.044691 -224.94767)
			(xy 134.063982 -224.902394) (xy 134.090285 -224.860798) (xy 134.12292 -224.823961) (xy 134.161041 -224.792836)
			(xy 134.203662 -224.768229) (xy 134.249678 -224.750777) (xy 134.297897 -224.740933) (xy 134.347072 -224.738952)
			(xy 134.395927 -224.744884) (xy 134.443198 -224.758576) (xy 134.48766 -224.779674) (xy 134.528163 -224.80763)
			(xy 134.563656 -224.841722) (xy 134.593221 -224.881066) (xy 134.616092 -224.924643) (xy 134.631676 -224.971324)
			(xy 134.639571 -225.019901) (xy 134.640066 -225.044508) (xy 134.969008 -225.044508) (xy 134.972968 -224.995454)
			(xy 134.984745 -224.94767) (xy 135.004036 -224.902394) (xy 135.030339 -224.860798) (xy 135.062974 -224.823961)
			(xy 135.101095 -224.792836) (xy 135.143716 -224.768229) (xy 135.189732 -224.750777) (xy 135.237951 -224.740933)
			(xy 135.287126 -224.738952) (xy 135.335981 -224.744884) (xy 135.383252 -224.758576) (xy 135.427714 -224.779674)
			(xy 135.468217 -224.80763) (xy 135.50371 -224.841722) (xy 135.533275 -224.881066) (xy 135.556146 -224.924643)
			(xy 135.57173 -224.971324) (xy 135.579625 -225.019901) (xy 135.58012 -225.044508) (xy 135.909062 -225.044508)
			(xy 135.913022 -224.995454) (xy 135.924799 -224.94767) (xy 135.94409 -224.902394) (xy 135.970393 -224.860798)
			(xy 136.003028 -224.823961) (xy 136.041149 -224.792836) (xy 136.08377 -224.768229) (xy 136.129786 -224.750777)
			(xy 136.178005 -224.740933) (xy 136.22718 -224.738952) (xy 136.276035 -224.744884) (xy 136.323306 -224.758576)
			(xy 136.367768 -224.779674) (xy 136.408271 -224.80763) (xy 136.443764 -224.841722) (xy 136.473329 -224.881066)
			(xy 136.4962 -224.924643) (xy 136.511784 -224.971324) (xy 136.519679 -225.019901) (xy 136.520174 -225.044508)
			(xy 136.519679 -225.069115) (xy 136.511784 -225.117692) (xy 136.4962 -225.164373) (xy 136.473329 -225.20795)
			(xy 136.443764 -225.247294) (xy 136.408271 -225.281386) (xy 136.367768 -225.309342) (xy 136.323306 -225.33044)
			(xy 136.276035 -225.344132) (xy 136.22718 -225.350064) (xy 136.178005 -225.348083) (xy 136.129786 -225.338239)
			(xy 136.08377 -225.320787) (xy 136.041149 -225.29618) (xy 136.003028 -225.265055) (xy 135.970393 -225.228218)
			(xy 135.94409 -225.186622) (xy 135.924799 -225.141346) (xy 135.913022 -225.093562) (xy 135.909062 -225.044508)
			(xy 135.58012 -225.044508) (xy 135.579625 -225.069115) (xy 135.57173 -225.117692) (xy 135.556146 -225.164373)
			(xy 135.533275 -225.20795) (xy 135.50371 -225.247294) (xy 135.468217 -225.281386) (xy 135.427714 -225.309342)
			(xy 135.383252 -225.33044) (xy 135.335981 -225.344132) (xy 135.287126 -225.350064) (xy 135.237951 -225.348083)
			(xy 135.189732 -225.338239) (xy 135.143716 -225.320787) (xy 135.101095 -225.29618) (xy 135.062974 -225.265055)
			(xy 135.030339 -225.228218) (xy 135.004036 -225.186622) (xy 134.984745 -225.141346) (xy 134.972968 -225.093562)
			(xy 134.969008 -225.044508) (xy 134.640066 -225.044508) (xy 134.639571 -225.069115) (xy 134.631676 -225.117692)
			(xy 134.616092 -225.164373) (xy 134.593221 -225.20795) (xy 134.563656 -225.247294) (xy 134.528163 -225.281386)
			(xy 134.48766 -225.309342) (xy 134.443198 -225.33044) (xy 134.395927 -225.344132) (xy 134.347072 -225.350064)
			(xy 134.297897 -225.348083) (xy 134.249678 -225.338239) (xy 134.203662 -225.320787) (xy 134.161041 -225.29618)
			(xy 134.12292 -225.265055) (xy 134.090285 -225.228218) (xy 134.063982 -225.186622) (xy 134.044691 -225.141346)
			(xy 134.032914 -225.093562) (xy 134.028954 -225.044508) (xy 133.700012 -225.044508) (xy 133.699517 -225.069115)
			(xy 133.691622 -225.117692) (xy 133.676038 -225.164373) (xy 133.653167 -225.20795) (xy 133.623602 -225.247294)
			(xy 133.588109 -225.281386) (xy 133.547606 -225.309342) (xy 133.503144 -225.33044) (xy 133.455873 -225.344132)
			(xy 133.407018 -225.350064) (xy 133.357843 -225.348083) (xy 133.309624 -225.338239) (xy 133.263608 -225.320787)
			(xy 133.220987 -225.29618) (xy 133.182866 -225.265055) (xy 133.150231 -225.228218) (xy 133.123928 -225.186622)
			(xy 133.104637 -225.141346) (xy 133.09286 -225.093562) (xy 133.0889 -225.044508) (xy 132.770372 -225.044508)
			(xy 132.76986 -225.069954) (xy 132.761696 -225.120188) (xy 132.74558 -225.168462) (xy 132.721929 -225.213525)
			(xy 132.691356 -225.254211) (xy 132.654652 -225.289466) (xy 132.612768 -225.318376) (xy 132.566789 -225.340193)
			(xy 132.517905 -225.354353) (xy 132.467384 -225.360487) (xy 132.416532 -225.358438) (xy 132.366668 -225.348258)
			(xy 132.319082 -225.330211) (xy 132.275008 -225.304765) (xy 132.235586 -225.272578) (xy 132.201838 -225.234484)
			(xy 132.174637 -225.19147) (xy 132.154689 -225.14465) (xy 132.14251 -225.095236) (xy 132.138415 -225.044508)
			(xy 131.820158 -225.044508) (xy 131.819663 -225.069115) (xy 131.811768 -225.117692) (xy 131.796184 -225.164373)
			(xy 131.773313 -225.20795) (xy 131.743748 -225.247294) (xy 131.708255 -225.281386) (xy 131.667752 -225.309342)
			(xy 131.62329 -225.33044) (xy 131.576019 -225.344132) (xy 131.527164 -225.350064) (xy 131.477989 -225.348083)
			(xy 131.42977 -225.338239) (xy 131.383754 -225.320787) (xy 131.341133 -225.29618) (xy 131.303012 -225.265055)
			(xy 131.270377 -225.228218) (xy 131.244074 -225.186622) (xy 131.224783 -225.141346) (xy 131.213006 -225.093562)
			(xy 131.209046 -225.044508) (xy 130.880104 -225.044508) (xy 130.879609 -225.069115) (xy 130.871714 -225.117692)
			(xy 130.85613 -225.164373) (xy 130.833259 -225.20795) (xy 130.803694 -225.247294) (xy 130.768201 -225.281386)
			(xy 130.727698 -225.309342) (xy 130.683236 -225.33044) (xy 130.635965 -225.344132) (xy 130.58711 -225.350064)
			(xy 130.537935 -225.348083) (xy 130.489716 -225.338239) (xy 130.4437 -225.320787) (xy 130.401079 -225.29618)
			(xy 130.362958 -225.265055) (xy 130.330323 -225.228218) (xy 130.30402 -225.186622) (xy 130.284729 -225.141346)
			(xy 130.272952 -225.093562) (xy 130.268992 -225.044508) (xy 129.950464 -225.044508) (xy 129.949952 -225.069954)
			(xy 129.941788 -225.120188) (xy 129.925672 -225.168462) (xy 129.902021 -225.213525) (xy 129.871448 -225.254211)
			(xy 129.834744 -225.289466) (xy 129.79286 -225.318376) (xy 129.746881 -225.340193) (xy 129.697997 -225.354353)
			(xy 129.647476 -225.360487) (xy 129.596624 -225.358438) (xy 129.54676 -225.348258) (xy 129.499174 -225.330211)
			(xy 129.4551 -225.304765) (xy 129.415678 -225.272578) (xy 129.38193 -225.234484) (xy 129.354729 -225.19147)
			(xy 129.334781 -225.14465) (xy 129.322602 -225.095236) (xy 129.318507 -225.044508) (xy 128.999996 -225.044508)
			(xy 128.999501 -225.069115) (xy 128.991606 -225.117692) (xy 128.976022 -225.164373) (xy 128.953151 -225.20795)
			(xy 128.923586 -225.247294) (xy 128.888093 -225.281386) (xy 128.84759 -225.309342) (xy 128.803128 -225.33044)
			(xy 128.755857 -225.344132) (xy 128.707002 -225.350064) (xy 128.657827 -225.348083) (xy 128.609608 -225.338239)
			(xy 128.563592 -225.320787) (xy 128.520971 -225.29618) (xy 128.48285 -225.265055) (xy 128.450215 -225.228218)
			(xy 128.423912 -225.186622) (xy 128.404621 -225.141346) (xy 128.392844 -225.093562) (xy 128.388884 -225.044508)
			(xy 128.05938 -225.044508) (xy 128.05938 -225.069331) (xy 128.051344 -225.118328) (xy 128.035484 -225.16538)
			(xy 128.012218 -225.209244) (xy 127.982161 -225.248764) (xy 127.946103 -225.282899) (xy 127.92583 -225.297238)
			(xy 127.925576 -225.297492) (xy 127.920496 -225.301048) (xy 127.916686 -225.305112) (xy 127.90932 -225.315272)
			(xy 127.901192 -225.330004) (xy 127.897011 -225.338439) (xy 127.894406 -225.357068) (xy 127.896112 -225.366326)
			(xy 127.89662 -225.368104) (xy 127.897128 -225.369628) (xy 127.908288 -225.406111) (xy 127.927601 -225.479928)
			(xy 127.935736 -225.517202) (xy 127.935736 -225.51771) (xy 127.938782 -225.52911) (xy 127.953483 -225.54753)
			(xy 127.96393 -225.553016) (xy 128.035304 -225.58629) (xy 128.059688 -225.585274) (xy 128.070356 -225.579178)
			(xy 128.094093 -225.566478) (xy 128.144823 -225.548474) (xy 128.197873 -225.539339) (xy 128.224788 -225.538792)
			(xy 128.249599 -225.539252) (xy 128.298611 -225.547013) (xy 128.345804 -225.562346) (xy 128.390019 -225.584873)
			(xy 128.430164 -225.614039) (xy 128.465253 -225.649126) (xy 128.494421 -225.689271) (xy 128.516949 -225.733484)
			(xy 128.532284 -225.780678) (xy 128.540047 -225.829689) (xy 128.540047 -225.854514) (xy 128.848607 -225.854514)
			(xy 128.852702 -225.803786) (xy 128.864881 -225.754372) (xy 128.884829 -225.707552) (xy 128.91203 -225.664538)
			(xy 128.945778 -225.626444) (xy 128.9852 -225.594257) (xy 129.029274 -225.568811) (xy 129.07686 -225.550764)
			(xy 129.126724 -225.540584) (xy 129.177576 -225.538535) (xy 129.228097 -225.544669) (xy 129.276981 -225.558829)
			(xy 129.32296 -225.580646) (xy 129.364844 -225.609556) (xy 129.401548 -225.644811) (xy 129.432121 -225.685497)
			(xy 129.455772 -225.73056) (xy 129.471888 -225.778834) (xy 129.480052 -225.829068) (xy 129.480564 -225.854514)
			(xy 129.798838 -225.854514) (xy 129.802798 -225.80546) (xy 129.814575 -225.757676) (xy 129.833866 -225.7124)
			(xy 129.860169 -225.670804) (xy 129.892804 -225.633967) (xy 129.930925 -225.602842) (xy 129.973546 -225.578235)
			(xy 130.019562 -225.560783) (xy 130.067781 -225.550939) (xy 130.116956 -225.548958) (xy 130.165811 -225.55489)
			(xy 130.213082 -225.568582) (xy 130.257544 -225.58968) (xy 130.298047 -225.617636) (xy 130.33354 -225.651728)
			(xy 130.363105 -225.691072) (xy 130.385976 -225.734649) (xy 130.40156 -225.78133) (xy 130.409455 -225.829907)
			(xy 130.40995 -225.854514) (xy 130.728461 -225.854514) (xy 130.732556 -225.803786) (xy 130.744735 -225.754372)
			(xy 130.764683 -225.707552) (xy 130.791884 -225.664538) (xy 130.825632 -225.626444) (xy 130.865054 -225.594257)
			(xy 130.909128 -225.568811) (xy 130.956714 -225.550764) (xy 131.006578 -225.540584) (xy 131.05743 -225.538535)
			(xy 131.107951 -225.544669) (xy 131.156835 -225.558829) (xy 131.202814 -225.580646) (xy 131.244698 -225.609556)
			(xy 131.281402 -225.644811) (xy 131.311975 -225.685497) (xy 131.335626 -225.73056) (xy 131.351742 -225.778834)
			(xy 131.359906 -225.829068) (xy 131.360418 -225.854514) (xy 131.678946 -225.854514) (xy 131.682906 -225.80546)
			(xy 131.694683 -225.757676) (xy 131.713974 -225.7124) (xy 131.740277 -225.670804) (xy 131.772912 -225.633967)
			(xy 131.811033 -225.602842) (xy 131.853654 -225.578235) (xy 131.89967 -225.560783) (xy 131.947889 -225.550939)
			(xy 131.997064 -225.548958) (xy 132.045919 -225.55489) (xy 132.09319 -225.568582) (xy 132.137652 -225.58968)
			(xy 132.178155 -225.617636) (xy 132.213648 -225.651728) (xy 132.243213 -225.691072) (xy 132.266084 -225.734649)
			(xy 132.281668 -225.78133) (xy 132.289563 -225.829907) (xy 132.290058 -225.854514) (xy 132.608569 -225.854514)
			(xy 132.612664 -225.803786) (xy 132.624843 -225.754372) (xy 132.644791 -225.707552) (xy 132.671992 -225.664538)
			(xy 132.70574 -225.626444) (xy 132.745162 -225.594257) (xy 132.789236 -225.568811) (xy 132.836822 -225.550764)
			(xy 132.886686 -225.540584) (xy 132.937538 -225.538535) (xy 132.988059 -225.544669) (xy 133.036943 -225.558829)
			(xy 133.082922 -225.580646) (xy 133.124806 -225.609556) (xy 133.16151 -225.644811) (xy 133.192083 -225.685497)
			(xy 133.215734 -225.73056) (xy 133.23185 -225.778834) (xy 133.240014 -225.829068) (xy 133.240526 -225.854514)
			(xy 133.559054 -225.854514) (xy 133.563014 -225.80546) (xy 133.574791 -225.757676) (xy 133.594082 -225.7124)
			(xy 133.620385 -225.670804) (xy 133.65302 -225.633967) (xy 133.691141 -225.602842) (xy 133.733762 -225.578235)
			(xy 133.779778 -225.560783) (xy 133.827997 -225.550939) (xy 133.877172 -225.548958) (xy 133.926027 -225.55489)
			(xy 133.973298 -225.568582) (xy 134.01776 -225.58968) (xy 134.058263 -225.617636) (xy 134.093756 -225.651728)
			(xy 134.123321 -225.691072) (xy 134.146192 -225.734649) (xy 134.161776 -225.78133) (xy 134.169671 -225.829907)
			(xy 134.170166 -225.854514) (xy 134.498854 -225.854514) (xy 134.502814 -225.80546) (xy 134.514591 -225.757676)
			(xy 134.533882 -225.7124) (xy 134.560185 -225.670804) (xy 134.59282 -225.633967) (xy 134.630941 -225.602842)
			(xy 134.673562 -225.578235) (xy 134.719578 -225.560783) (xy 134.767797 -225.550939) (xy 134.816972 -225.548958)
			(xy 134.865827 -225.55489) (xy 134.913098 -225.568582) (xy 134.95756 -225.58968) (xy 134.998063 -225.617636)
			(xy 135.033556 -225.651728) (xy 135.063121 -225.691072) (xy 135.085992 -225.734649) (xy 135.101576 -225.78133)
			(xy 135.109471 -225.829907) (xy 135.109966 -225.854514) (xy 135.438908 -225.854514) (xy 135.442868 -225.80546)
			(xy 135.454645 -225.757676) (xy 135.473936 -225.7124) (xy 135.500239 -225.670804) (xy 135.532874 -225.633967)
			(xy 135.570995 -225.602842) (xy 135.613616 -225.578235) (xy 135.659632 -225.560783) (xy 135.707851 -225.550939)
			(xy 135.757026 -225.548958) (xy 135.805881 -225.55489) (xy 135.853152 -225.568582) (xy 135.897614 -225.58968)
			(xy 135.938117 -225.617636) (xy 135.97361 -225.651728) (xy 136.003175 -225.691072) (xy 136.026046 -225.734649)
			(xy 136.04163 -225.78133) (xy 136.049525 -225.829907) (xy 136.05002 -225.854514) (xy 136.049525 -225.879121)
			(xy 136.04163 -225.927698) (xy 136.026046 -225.974379) (xy 136.003175 -226.017956) (xy 135.97361 -226.0573)
			(xy 135.938117 -226.091392) (xy 135.897614 -226.119348) (xy 135.853152 -226.140446) (xy 135.805881 -226.154138)
			(xy 135.757026 -226.16007) (xy 135.707851 -226.158089) (xy 135.659632 -226.148245) (xy 135.613616 -226.130793)
			(xy 135.570995 -226.106186) (xy 135.532874 -226.075061) (xy 135.500239 -226.038224) (xy 135.473936 -225.996628)
			(xy 135.454645 -225.951352) (xy 135.442868 -225.903568) (xy 135.438908 -225.854514) (xy 135.109966 -225.854514)
			(xy 135.109471 -225.879121) (xy 135.101576 -225.927698) (xy 135.085992 -225.974379) (xy 135.063121 -226.017956)
			(xy 135.033556 -226.0573) (xy 134.998063 -226.091392) (xy 134.95756 -226.119348) (xy 134.913098 -226.140446)
			(xy 134.865827 -226.154138) (xy 134.816972 -226.16007) (xy 134.767797 -226.158089) (xy 134.719578 -226.148245)
			(xy 134.673562 -226.130793) (xy 134.630941 -226.106186) (xy 134.59282 -226.075061) (xy 134.560185 -226.038224)
			(xy 134.533882 -225.996628) (xy 134.514591 -225.951352) (xy 134.502814 -225.903568) (xy 134.498854 -225.854514)
			(xy 134.170166 -225.854514) (xy 134.169671 -225.879121) (xy 134.161776 -225.927698) (xy 134.146192 -225.974379)
			(xy 134.123321 -226.017956) (xy 134.093756 -226.0573) (xy 134.058263 -226.091392) (xy 134.01776 -226.119348)
			(xy 133.973298 -226.140446) (xy 133.926027 -226.154138) (xy 133.877172 -226.16007) (xy 133.827997 -226.158089)
			(xy 133.779778 -226.148245) (xy 133.733762 -226.130793) (xy 133.691141 -226.106186) (xy 133.65302 -226.075061)
			(xy 133.620385 -226.038224) (xy 133.594082 -225.996628) (xy 133.574791 -225.951352) (xy 133.563014 -225.903568)
			(xy 133.559054 -225.854514) (xy 133.240526 -225.854514) (xy 133.240014 -225.87996) (xy 133.23185 -225.930194)
			(xy 133.215734 -225.978468) (xy 133.192083 -226.023531) (xy 133.16151 -226.064217) (xy 133.124806 -226.099472)
			(xy 133.082922 -226.128382) (xy 133.036943 -226.150199) (xy 132.988059 -226.164359) (xy 132.937538 -226.170493)
			(xy 132.886686 -226.168444) (xy 132.836822 -226.158264) (xy 132.789236 -226.140217) (xy 132.745162 -226.114771)
			(xy 132.70574 -226.082584) (xy 132.671992 -226.04449) (xy 132.644791 -226.001476) (xy 132.624843 -225.954656)
			(xy 132.612664 -225.905242) (xy 132.608569 -225.854514) (xy 132.290058 -225.854514) (xy 132.289563 -225.879121)
			(xy 132.281668 -225.927698) (xy 132.266084 -225.974379) (xy 132.243213 -226.017956) (xy 132.213648 -226.0573)
			(xy 132.178155 -226.091392) (xy 132.137652 -226.119348) (xy 132.09319 -226.140446) (xy 132.045919 -226.154138)
			(xy 131.997064 -226.16007) (xy 131.947889 -226.158089) (xy 131.89967 -226.148245) (xy 131.853654 -226.130793)
			(xy 131.811033 -226.106186) (xy 131.772912 -226.075061) (xy 131.740277 -226.038224) (xy 131.713974 -225.996628)
			(xy 131.694683 -225.951352) (xy 131.682906 -225.903568) (xy 131.678946 -225.854514) (xy 131.360418 -225.854514)
			(xy 131.359906 -225.87996) (xy 131.351742 -225.930194) (xy 131.335626 -225.978468) (xy 131.311975 -226.023531)
			(xy 131.281402 -226.064217) (xy 131.244698 -226.099472) (xy 131.202814 -226.128382) (xy 131.156835 -226.150199)
			(xy 131.107951 -226.164359) (xy 131.05743 -226.170493) (xy 131.006578 -226.168444) (xy 130.956714 -226.158264)
			(xy 130.909128 -226.140217) (xy 130.865054 -226.114771) (xy 130.825632 -226.082584) (xy 130.791884 -226.04449)
			(xy 130.764683 -226.001476) (xy 130.744735 -225.954656) (xy 130.732556 -225.905242) (xy 130.728461 -225.854514)
			(xy 130.40995 -225.854514) (xy 130.409455 -225.879121) (xy 130.40156 -225.927698) (xy 130.385976 -225.974379)
			(xy 130.363105 -226.017956) (xy 130.33354 -226.0573) (xy 130.298047 -226.091392) (xy 130.257544 -226.119348)
			(xy 130.213082 -226.140446) (xy 130.165811 -226.154138) (xy 130.116956 -226.16007) (xy 130.067781 -226.158089)
			(xy 130.019562 -226.148245) (xy 129.973546 -226.130793) (xy 129.930925 -226.106186) (xy 129.892804 -226.075061)
			(xy 129.860169 -226.038224) (xy 129.833866 -225.996628) (xy 129.814575 -225.951352) (xy 129.802798 -225.903568)
			(xy 129.798838 -225.854514) (xy 129.480564 -225.854514) (xy 129.480052 -225.87996) (xy 129.471888 -225.930194)
			(xy 129.455772 -225.978468) (xy 129.432121 -226.023531) (xy 129.401548 -226.064217) (xy 129.364844 -226.099472)
			(xy 129.32296 -226.128382) (xy 129.276981 -226.150199) (xy 129.228097 -226.164359) (xy 129.177576 -226.170493)
			(xy 129.126724 -226.168444) (xy 129.07686 -226.158264) (xy 129.029274 -226.140217) (xy 128.9852 -226.114771)
			(xy 128.945778 -226.082584) (xy 128.91203 -226.04449) (xy 128.884829 -226.001476) (xy 128.864881 -225.954656)
			(xy 128.852702 -225.905242) (xy 128.848607 -225.854514) (xy 128.540047 -225.854514) (xy 128.540047 -225.879311)
			(xy 128.532284 -225.928322) (xy 128.516949 -225.975516) (xy 128.494421 -226.019729) (xy 128.465253 -226.059874)
			(xy 128.430164 -226.094961) (xy 128.390019 -226.124127) (xy 128.345804 -226.146654) (xy 128.298611 -226.161987)
			(xy 128.249599 -226.169748) (xy 128.224788 -226.170236) (xy 128.197873 -226.169689) (xy 128.144824 -226.160552)
			(xy 128.094096 -226.142544) (xy 128.070356 -226.12985) (xy 128.059688 -226.123754) (xy 128.035304 -226.122738)
			(xy 127.96393 -226.156012) (xy 127.953534 -226.161561) (xy 127.938836 -226.17995) (xy 127.935736 -226.191318)
			(xy 127.935736 -226.191826) (xy 127.927752 -226.228517) (xy 127.90882 -226.30119) (xy 127.89789 -226.337114)
			(xy 127.895064 -226.348028) (xy 127.898114 -226.370335) (xy 127.910418 -226.389191) (xy 127.919734 -226.395534)
			(xy 127.94063 -226.408881) (xy 127.978331 -226.441083) (xy 128.010531 -226.478786) (xy 128.036436 -226.521062)
			(xy 128.055408 -226.56687) (xy 128.066981 -226.615082) (xy 128.07087 -226.66451) (xy 128.070869 -226.66452)
			(xy 128.388884 -226.66452) (xy 128.392844 -226.615466) (xy 128.404621 -226.567682) (xy 128.423912 -226.522406)
			(xy 128.450215 -226.48081) (xy 128.48285 -226.443973) (xy 128.520971 -226.412848) (xy 128.563592 -226.388241)
			(xy 128.609608 -226.370789) (xy 128.657827 -226.360945) (xy 128.707002 -226.358964) (xy 128.755857 -226.364896)
			(xy 128.803128 -226.378588) (xy 128.84759 -226.399686) (xy 128.888093 -226.427642) (xy 128.923586 -226.461734)
			(xy 128.953151 -226.501078) (xy 128.976022 -226.544655) (xy 128.991606 -226.591336) (xy 128.999501 -226.639913)
			(xy 128.999996 -226.66452) (xy 129.318507 -226.66452) (xy 129.322602 -226.613792) (xy 129.334781 -226.564378)
			(xy 129.354729 -226.517558) (xy 129.38193 -226.474544) (xy 129.415678 -226.43645) (xy 129.4551 -226.404263)
			(xy 129.499174 -226.378817) (xy 129.54676 -226.36077) (xy 129.596624 -226.35059) (xy 129.647476 -226.348541)
			(xy 129.697997 -226.354675) (xy 129.746881 -226.368835) (xy 129.79286 -226.390652) (xy 129.834744 -226.419562)
			(xy 129.871448 -226.454817) (xy 129.902021 -226.495503) (xy 129.925672 -226.540566) (xy 129.941788 -226.58884)
			(xy 129.949952 -226.639074) (xy 129.950464 -226.66452) (xy 130.268992 -226.66452) (xy 130.272952 -226.615466)
			(xy 130.284729 -226.567682) (xy 130.30402 -226.522406) (xy 130.330323 -226.48081) (xy 130.362958 -226.443973)
			(xy 130.401079 -226.412848) (xy 130.4437 -226.388241) (xy 130.489716 -226.370789) (xy 130.537935 -226.360945)
			(xy 130.58711 -226.358964) (xy 130.635965 -226.364896) (xy 130.683236 -226.378588) (xy 130.727698 -226.399686)
			(xy 130.768201 -226.427642) (xy 130.803694 -226.461734) (xy 130.833259 -226.501078) (xy 130.85613 -226.544655)
			(xy 130.871714 -226.591336) (xy 130.879609 -226.639913) (xy 130.880104 -226.66452) (xy 131.198615 -226.66452)
			(xy 131.20271 -226.613792) (xy 131.214889 -226.564378) (xy 131.234837 -226.517558) (xy 131.262038 -226.474544)
			(xy 131.295786 -226.43645) (xy 131.335208 -226.404263) (xy 131.379282 -226.378817) (xy 131.426868 -226.36077)
			(xy 131.476732 -226.35059) (xy 131.527584 -226.348541) (xy 131.578105 -226.354675) (xy 131.626989 -226.368835)
			(xy 131.672968 -226.390652) (xy 131.714852 -226.419562) (xy 131.751556 -226.454817) (xy 131.782129 -226.495503)
			(xy 131.80578 -226.540566) (xy 131.821896 -226.58884) (xy 131.83006 -226.639074) (xy 131.830572 -226.66452)
			(xy 132.138415 -226.66452) (xy 132.14251 -226.613792) (xy 132.154689 -226.564378) (xy 132.174637 -226.517558)
			(xy 132.201838 -226.474544) (xy 132.235586 -226.43645) (xy 132.275008 -226.404263) (xy 132.319082 -226.378817)
			(xy 132.366668 -226.36077) (xy 132.416532 -226.35059) (xy 132.467384 -226.348541) (xy 132.517905 -226.354675)
			(xy 132.566789 -226.368835) (xy 132.612768 -226.390652) (xy 132.654652 -226.419562) (xy 132.691356 -226.454817)
			(xy 132.721929 -226.495503) (xy 132.74558 -226.540566) (xy 132.761696 -226.58884) (xy 132.76986 -226.639074)
			(xy 132.770372 -226.66452) (xy 133.0889 -226.66452) (xy 133.09286 -226.615466) (xy 133.104637 -226.567682)
			(xy 133.123928 -226.522406) (xy 133.150231 -226.48081) (xy 133.182866 -226.443973) (xy 133.220987 -226.412848)
			(xy 133.263608 -226.388241) (xy 133.309624 -226.370789) (xy 133.357843 -226.360945) (xy 133.407018 -226.358964)
			(xy 133.455873 -226.364896) (xy 133.503144 -226.378588) (xy 133.547606 -226.399686) (xy 133.588109 -226.427642)
			(xy 133.623602 -226.461734) (xy 133.653167 -226.501078) (xy 133.676038 -226.544655) (xy 133.691622 -226.591336)
			(xy 133.699517 -226.639913) (xy 133.700012 -226.66452) (xy 134.028954 -226.66452) (xy 134.032914 -226.615466)
			(xy 134.044691 -226.567682) (xy 134.063982 -226.522406) (xy 134.090285 -226.48081) (xy 134.12292 -226.443973)
			(xy 134.161041 -226.412848) (xy 134.203662 -226.388241) (xy 134.249678 -226.370789) (xy 134.297897 -226.360945)
			(xy 134.347072 -226.358964) (xy 134.395927 -226.364896) (xy 134.443198 -226.378588) (xy 134.48766 -226.399686)
			(xy 134.528163 -226.427642) (xy 134.563656 -226.461734) (xy 134.593221 -226.501078) (xy 134.616092 -226.544655)
			(xy 134.631676 -226.591336) (xy 134.639571 -226.639913) (xy 134.640066 -226.66452) (xy 134.969008 -226.66452)
			(xy 134.972968 -226.615466) (xy 134.984745 -226.567682) (xy 135.004036 -226.522406) (xy 135.030339 -226.48081)
			(xy 135.062974 -226.443973) (xy 135.101095 -226.412848) (xy 135.143716 -226.388241) (xy 135.189732 -226.370789)
			(xy 135.237951 -226.360945) (xy 135.287126 -226.358964) (xy 135.335981 -226.364896) (xy 135.383252 -226.378588)
			(xy 135.427714 -226.399686) (xy 135.468217 -226.427642) (xy 135.50371 -226.461734) (xy 135.533275 -226.501078)
			(xy 135.556146 -226.544655) (xy 135.57173 -226.591336) (xy 135.579625 -226.639913) (xy 135.58012 -226.66452)
			(xy 135.909062 -226.66452) (xy 135.913022 -226.615466) (xy 135.924799 -226.567682) (xy 135.94409 -226.522406)
			(xy 135.970393 -226.48081) (xy 136.003028 -226.443973) (xy 136.041149 -226.412848) (xy 136.08377 -226.388241)
			(xy 136.129786 -226.370789) (xy 136.178005 -226.360945) (xy 136.22718 -226.358964) (xy 136.276035 -226.364896)
			(xy 136.323306 -226.378588) (xy 136.367768 -226.399686) (xy 136.408271 -226.427642) (xy 136.443764 -226.461734)
			(xy 136.473329 -226.501078) (xy 136.4962 -226.544655) (xy 136.511784 -226.591336) (xy 136.519679 -226.639913)
			(xy 136.520174 -226.66452) (xy 136.519679 -226.689127) (xy 136.511784 -226.737704) (xy 136.4962 -226.784385)
			(xy 136.473329 -226.827962) (xy 136.443764 -226.867306) (xy 136.408271 -226.901398) (xy 136.367768 -226.929354)
			(xy 136.323306 -226.950452) (xy 136.276035 -226.964144) (xy 136.22718 -226.970076) (xy 136.178005 -226.968095)
			(xy 136.129786 -226.958251) (xy 136.08377 -226.940799) (xy 136.041149 -226.916192) (xy 136.003028 -226.885067)
			(xy 135.970393 -226.84823) (xy 135.94409 -226.806634) (xy 135.924799 -226.761358) (xy 135.913022 -226.713574)
			(xy 135.909062 -226.66452) (xy 135.58012 -226.66452) (xy 135.579625 -226.689127) (xy 135.57173 -226.737704)
			(xy 135.556146 -226.784385) (xy 135.533275 -226.827962) (xy 135.50371 -226.867306) (xy 135.468217 -226.901398)
			(xy 135.427714 -226.929354) (xy 135.383252 -226.950452) (xy 135.335981 -226.964144) (xy 135.287126 -226.970076)
			(xy 135.237951 -226.968095) (xy 135.189732 -226.958251) (xy 135.143716 -226.940799) (xy 135.101095 -226.916192)
			(xy 135.062974 -226.885067) (xy 135.030339 -226.84823) (xy 135.004036 -226.806634) (xy 134.984745 -226.761358)
			(xy 134.972968 -226.713574) (xy 134.969008 -226.66452) (xy 134.640066 -226.66452) (xy 134.639571 -226.689127)
			(xy 134.631676 -226.737704) (xy 134.616092 -226.784385) (xy 134.593221 -226.827962) (xy 134.563656 -226.867306)
			(xy 134.528163 -226.901398) (xy 134.48766 -226.929354) (xy 134.443198 -226.950452) (xy 134.395927 -226.964144)
			(xy 134.347072 -226.970076) (xy 134.297897 -226.968095) (xy 134.249678 -226.958251) (xy 134.203662 -226.940799)
			(xy 134.161041 -226.916192) (xy 134.12292 -226.885067) (xy 134.090285 -226.84823) (xy 134.063982 -226.806634)
			(xy 134.044691 -226.761358) (xy 134.032914 -226.713574) (xy 134.028954 -226.66452) (xy 133.700012 -226.66452)
			(xy 133.699517 -226.689127) (xy 133.691622 -226.737704) (xy 133.676038 -226.784385) (xy 133.653167 -226.827962)
			(xy 133.623602 -226.867306) (xy 133.588109 -226.901398) (xy 133.547606 -226.929354) (xy 133.503144 -226.950452)
			(xy 133.455873 -226.964144) (xy 133.407018 -226.970076) (xy 133.357843 -226.968095) (xy 133.309624 -226.958251)
			(xy 133.263608 -226.940799) (xy 133.220987 -226.916192) (xy 133.182866 -226.885067) (xy 133.150231 -226.84823)
			(xy 133.123928 -226.806634) (xy 133.104637 -226.761358) (xy 133.09286 -226.713574) (xy 133.0889 -226.66452)
			(xy 132.770372 -226.66452) (xy 132.76986 -226.689966) (xy 132.761696 -226.7402) (xy 132.74558 -226.788474)
			(xy 132.721929 -226.833537) (xy 132.691356 -226.874223) (xy 132.654652 -226.909478) (xy 132.612768 -226.938388)
			(xy 132.566789 -226.960205) (xy 132.517905 -226.974365) (xy 132.467384 -226.980499) (xy 132.416532 -226.97845)
			(xy 132.366668 -226.96827) (xy 132.319082 -226.950223) (xy 132.275008 -226.924777) (xy 132.235586 -226.89259)
			(xy 132.201838 -226.854496) (xy 132.174637 -226.811482) (xy 132.154689 -226.764662) (xy 132.14251 -226.715248)
			(xy 132.138415 -226.66452) (xy 131.830572 -226.66452) (xy 131.83006 -226.689966) (xy 131.821896 -226.7402)
			(xy 131.80578 -226.788474) (xy 131.782129 -226.833537) (xy 131.751556 -226.874223) (xy 131.714852 -226.909478)
			(xy 131.672968 -226.938388) (xy 131.626989 -226.960205) (xy 131.578105 -226.974365) (xy 131.527584 -226.980499)
			(xy 131.476732 -226.97845) (xy 131.426868 -226.96827) (xy 131.379282 -226.950223) (xy 131.335208 -226.924777)
			(xy 131.295786 -226.89259) (xy 131.262038 -226.854496) (xy 131.234837 -226.811482) (xy 131.214889 -226.764662)
			(xy 131.20271 -226.715248) (xy 131.198615 -226.66452) (xy 130.880104 -226.66452) (xy 130.879609 -226.689127)
			(xy 130.871714 -226.737704) (xy 130.85613 -226.784385) (xy 130.833259 -226.827962) (xy 130.803694 -226.867306)
			(xy 130.768201 -226.901398) (xy 130.727698 -226.929354) (xy 130.683236 -226.950452) (xy 130.635965 -226.964144)
			(xy 130.58711 -226.970076) (xy 130.537935 -226.968095) (xy 130.489716 -226.958251) (xy 130.4437 -226.940799)
			(xy 130.401079 -226.916192) (xy 130.362958 -226.885067) (xy 130.330323 -226.84823) (xy 130.30402 -226.806634)
			(xy 130.284729 -226.761358) (xy 130.272952 -226.713574) (xy 130.268992 -226.66452) (xy 129.950464 -226.66452)
			(xy 129.949952 -226.689966) (xy 129.941788 -226.7402) (xy 129.925672 -226.788474) (xy 129.902021 -226.833537)
			(xy 129.871448 -226.874223) (xy 129.834744 -226.909478) (xy 129.79286 -226.938388) (xy 129.746881 -226.960205)
			(xy 129.697997 -226.974365) (xy 129.647476 -226.980499) (xy 129.596624 -226.97845) (xy 129.54676 -226.96827)
			(xy 129.499174 -226.950223) (xy 129.4551 -226.924777) (xy 129.415678 -226.89259) (xy 129.38193 -226.854496)
			(xy 129.354729 -226.811482) (xy 129.334781 -226.764662) (xy 129.322602 -226.715248) (xy 129.318507 -226.66452)
			(xy 128.999996 -226.66452) (xy 128.999501 -226.689127) (xy 128.991606 -226.737704) (xy 128.976022 -226.784385)
			(xy 128.953151 -226.827962) (xy 128.923586 -226.867306) (xy 128.888093 -226.901398) (xy 128.84759 -226.929354)
			(xy 128.803128 -226.950452) (xy 128.755857 -226.964144) (xy 128.707002 -226.970076) (xy 128.657827 -226.968095)
			(xy 128.609608 -226.958251) (xy 128.563592 -226.940799) (xy 128.520971 -226.916192) (xy 128.48285 -226.885067)
			(xy 128.450215 -226.84823) (xy 128.423912 -226.806634) (xy 128.404621 -226.761358) (xy 128.392844 -226.713574)
			(xy 128.388884 -226.66452) (xy 128.070869 -226.66452) (xy 128.066978 -226.713939) (xy 128.055402 -226.76215)
			(xy 128.036426 -226.807957) (xy 128.010518 -226.850231) (xy 127.978317 -226.887932) (xy 127.940613 -226.920131)
			(xy 127.919734 -226.933506) (xy 127.910497 -226.939924) (xy 127.898249 -226.958757) (xy 127.895165 -226.98101)
			(xy 127.89789 -226.991926) (xy 127.908812 -227.027852) (xy 127.927742 -227.100525) (xy 127.935736 -227.137214)
			(xy 127.935736 -227.137722) (xy 127.938784 -227.14912) (xy 127.953487 -227.167536) (xy 127.96393 -227.173028)
			(xy 128.035304 -227.206302) (xy 128.059688 -227.205286) (xy 128.070356 -227.19919) (xy 128.094093 -227.18649)
			(xy 128.144823 -227.168485) (xy 128.197873 -227.159349) (xy 128.224788 -227.158804) (xy 128.249598 -227.159264)
			(xy 128.298608 -227.167025) (xy 128.3458 -227.182357) (xy 128.390012 -227.204883) (xy 128.430157 -227.234048)
			(xy 128.465244 -227.269134) (xy 128.494411 -227.309277) (xy 128.516938 -227.353489) (xy 128.532272 -227.400681)
			(xy 128.540035 -227.44969) (xy 128.540035 -227.474526) (xy 128.848607 -227.474526) (xy 128.852702 -227.423798)
			(xy 128.864881 -227.374384) (xy 128.884829 -227.327564) (xy 128.91203 -227.28455) (xy 128.945778 -227.246456)
			(xy 128.9852 -227.214269) (xy 129.029274 -227.188823) (xy 129.07686 -227.170776) (xy 129.126724 -227.160596)
			(xy 129.177576 -227.158547) (xy 129.228097 -227.164681) (xy 129.276981 -227.178841) (xy 129.32296 -227.200658)
			(xy 129.364844 -227.229568) (xy 129.401548 -227.264823) (xy 129.432121 -227.305509) (xy 129.455772 -227.350572)
			(xy 129.471888 -227.398846) (xy 129.480052 -227.44908) (xy 129.480564 -227.474526) (xy 130.728461 -227.474526)
			(xy 130.732556 -227.423798) (xy 130.744735 -227.374384) (xy 130.764683 -227.327564) (xy 130.791884 -227.28455)
			(xy 130.825632 -227.246456) (xy 130.865054 -227.214269) (xy 130.909128 -227.188823) (xy 130.956714 -227.170776)
			(xy 131.006578 -227.160596) (xy 131.05743 -227.158547) (xy 131.107951 -227.164681) (xy 131.156835 -227.178841)
			(xy 131.202814 -227.200658) (xy 131.244698 -227.229568) (xy 131.281402 -227.264823) (xy 131.311975 -227.305509)
			(xy 131.335626 -227.350572) (xy 131.351742 -227.398846) (xy 131.359906 -227.44908) (xy 131.360418 -227.474526)
			(xy 131.678946 -227.474526) (xy 131.682906 -227.425472) (xy 131.694683 -227.377688) (xy 131.713974 -227.332412)
			(xy 131.740277 -227.290816) (xy 131.772912 -227.253979) (xy 131.811033 -227.222854) (xy 131.853654 -227.198247)
			(xy 131.89967 -227.180795) (xy 131.947889 -227.170951) (xy 131.997064 -227.16897) (xy 132.045919 -227.174902)
			(xy 132.09319 -227.188594) (xy 132.137652 -227.209692) (xy 132.178155 -227.237648) (xy 132.213648 -227.27174)
			(xy 132.243213 -227.311084) (xy 132.266084 -227.354661) (xy 132.281668 -227.401342) (xy 132.289563 -227.449919)
			(xy 132.290058 -227.474526) (xy 132.608569 -227.474526) (xy 132.612664 -227.423798) (xy 132.624843 -227.374384)
			(xy 132.644791 -227.327564) (xy 132.671992 -227.28455) (xy 132.70574 -227.246456) (xy 132.745162 -227.214269)
			(xy 132.789236 -227.188823) (xy 132.836822 -227.170776) (xy 132.886686 -227.160596) (xy 132.937538 -227.158547)
			(xy 132.988059 -227.164681) (xy 133.036943 -227.178841) (xy 133.082922 -227.200658) (xy 133.124806 -227.229568)
			(xy 133.16151 -227.264823) (xy 133.192083 -227.305509) (xy 133.215734 -227.350572) (xy 133.23185 -227.398846)
			(xy 133.240014 -227.44908) (xy 133.240526 -227.474526) (xy 133.559054 -227.474526) (xy 133.563014 -227.425472)
			(xy 133.574791 -227.377688) (xy 133.594082 -227.332412) (xy 133.620385 -227.290816) (xy 133.65302 -227.253979)
			(xy 133.691141 -227.222854) (xy 133.733762 -227.198247) (xy 133.779778 -227.180795) (xy 133.827997 -227.170951)
			(xy 133.877172 -227.16897) (xy 133.926027 -227.174902) (xy 133.973298 -227.188594) (xy 134.01776 -227.209692)
			(xy 134.058263 -227.237648) (xy 134.093756 -227.27174) (xy 134.123321 -227.311084) (xy 134.146192 -227.354661)
			(xy 134.161776 -227.401342) (xy 134.169671 -227.449919) (xy 134.170166 -227.474526) (xy 134.498854 -227.474526)
			(xy 134.502814 -227.425472) (xy 134.514591 -227.377688) (xy 134.533882 -227.332412) (xy 134.560185 -227.290816)
			(xy 134.59282 -227.253979) (xy 134.630941 -227.222854) (xy 134.673562 -227.198247) (xy 134.719578 -227.180795)
			(xy 134.767797 -227.170951) (xy 134.816972 -227.16897) (xy 134.865827 -227.174902) (xy 134.913098 -227.188594)
			(xy 134.95756 -227.209692) (xy 134.998063 -227.237648) (xy 135.033556 -227.27174) (xy 135.063121 -227.311084)
			(xy 135.085992 -227.354661) (xy 135.101576 -227.401342) (xy 135.109471 -227.449919) (xy 135.109966 -227.474526)
			(xy 135.438908 -227.474526) (xy 135.442868 -227.425472) (xy 135.454645 -227.377688) (xy 135.473936 -227.332412)
			(xy 135.500239 -227.290816) (xy 135.532874 -227.253979) (xy 135.570995 -227.222854) (xy 135.613616 -227.198247)
			(xy 135.659632 -227.180795) (xy 135.707851 -227.170951) (xy 135.757026 -227.16897) (xy 135.805881 -227.174902)
			(xy 135.853152 -227.188594) (xy 135.897614 -227.209692) (xy 135.938117 -227.237648) (xy 135.97361 -227.27174)
			(xy 136.003175 -227.311084) (xy 136.026046 -227.354661) (xy 136.04163 -227.401342) (xy 136.049525 -227.449919)
			(xy 136.05002 -227.474526) (xy 136.049525 -227.499133) (xy 136.04163 -227.54771) (xy 136.026046 -227.594391)
			(xy 136.003175 -227.637968) (xy 135.97361 -227.677312) (xy 135.938117 -227.711404) (xy 135.897614 -227.73936)
			(xy 135.853152 -227.760458) (xy 135.805881 -227.77415) (xy 135.757026 -227.780082) (xy 135.707851 -227.778101)
			(xy 135.659632 -227.768257) (xy 135.613616 -227.750805) (xy 135.570995 -227.726198) (xy 135.532874 -227.695073)
			(xy 135.500239 -227.658236) (xy 135.473936 -227.61664) (xy 135.454645 -227.571364) (xy 135.442868 -227.52358)
			(xy 135.438908 -227.474526) (xy 135.109966 -227.474526) (xy 135.109471 -227.499133) (xy 135.101576 -227.54771)
			(xy 135.085992 -227.594391) (xy 135.063121 -227.637968) (xy 135.033556 -227.677312) (xy 134.998063 -227.711404)
			(xy 134.95756 -227.73936) (xy 134.913098 -227.760458) (xy 134.865827 -227.77415) (xy 134.816972 -227.780082)
			(xy 134.767797 -227.778101) (xy 134.719578 -227.768257) (xy 134.673562 -227.750805) (xy 134.630941 -227.726198)
			(xy 134.59282 -227.695073) (xy 134.560185 -227.658236) (xy 134.533882 -227.61664) (xy 134.514591 -227.571364)
			(xy 134.502814 -227.52358) (xy 134.498854 -227.474526) (xy 134.170166 -227.474526) (xy 134.169671 -227.499133)
			(xy 134.161776 -227.54771) (xy 134.146192 -227.594391) (xy 134.123321 -227.637968) (xy 134.093756 -227.677312)
			(xy 134.058263 -227.711404) (xy 134.01776 -227.73936) (xy 133.973298 -227.760458) (xy 133.926027 -227.77415)
			(xy 133.877172 -227.780082) (xy 133.827997 -227.778101) (xy 133.779778 -227.768257) (xy 133.733762 -227.750805)
			(xy 133.691141 -227.726198) (xy 133.65302 -227.695073) (xy 133.620385 -227.658236) (xy 133.594082 -227.61664)
			(xy 133.574791 -227.571364) (xy 133.563014 -227.52358) (xy 133.559054 -227.474526) (xy 133.240526 -227.474526)
			(xy 133.240014 -227.499972) (xy 133.23185 -227.550206) (xy 133.215734 -227.59848) (xy 133.192083 -227.643543)
			(xy 133.16151 -227.684229) (xy 133.124806 -227.719484) (xy 133.082922 -227.748394) (xy 133.036943 -227.770211)
			(xy 132.988059 -227.784371) (xy 132.937538 -227.790505) (xy 132.886686 -227.788456) (xy 132.836822 -227.778276)
			(xy 132.789236 -227.760229) (xy 132.745162 -227.734783) (xy 132.70574 -227.702596) (xy 132.671992 -227.664502)
			(xy 132.644791 -227.621488) (xy 132.624843 -227.574668) (xy 132.612664 -227.525254) (xy 132.608569 -227.474526)
			(xy 132.290058 -227.474526) (xy 132.289563 -227.499133) (xy 132.281668 -227.54771) (xy 132.266084 -227.594391)
			(xy 132.243213 -227.637968) (xy 132.213648 -227.677312) (xy 132.178155 -227.711404) (xy 132.137652 -227.73936)
			(xy 132.09319 -227.760458) (xy 132.045919 -227.77415) (xy 131.997064 -227.780082) (xy 131.947889 -227.778101)
			(xy 131.89967 -227.768257) (xy 131.853654 -227.750805) (xy 131.811033 -227.726198) (xy 131.772912 -227.695073)
			(xy 131.740277 -227.658236) (xy 131.713974 -227.61664) (xy 131.694683 -227.571364) (xy 131.682906 -227.52358)
			(xy 131.678946 -227.474526) (xy 131.360418 -227.474526) (xy 131.359906 -227.499972) (xy 131.351742 -227.550206)
			(xy 131.335626 -227.59848) (xy 131.311975 -227.643543) (xy 131.281402 -227.684229) (xy 131.244698 -227.719484)
			(xy 131.202814 -227.748394) (xy 131.156835 -227.770211) (xy 131.107951 -227.784371) (xy 131.05743 -227.790505)
			(xy 131.006578 -227.788456) (xy 130.956714 -227.778276) (xy 130.909128 -227.760229) (xy 130.865054 -227.734783)
			(xy 130.825632 -227.702596) (xy 130.791884 -227.664502) (xy 130.764683 -227.621488) (xy 130.744735 -227.574668)
			(xy 130.732556 -227.525254) (xy 130.728461 -227.474526) (xy 129.480564 -227.474526) (xy 129.480052 -227.499972)
			(xy 129.471888 -227.550206) (xy 129.455772 -227.59848) (xy 129.432121 -227.643543) (xy 129.401548 -227.684229)
			(xy 129.364844 -227.719484) (xy 129.32296 -227.748394) (xy 129.276981 -227.770211) (xy 129.228097 -227.784371)
			(xy 129.177576 -227.790505) (xy 129.126724 -227.788456) (xy 129.07686 -227.778276) (xy 129.029274 -227.760229)
			(xy 128.9852 -227.734783) (xy 128.945778 -227.702596) (xy 128.91203 -227.664502) (xy 128.884829 -227.621488)
			(xy 128.864881 -227.574668) (xy 128.852702 -227.525254) (xy 128.848607 -227.474526) (xy 128.540035 -227.474526)
			(xy 128.540035 -227.49931) (xy 128.532272 -227.548319) (xy 128.516938 -227.595511) (xy 128.494411 -227.639723)
			(xy 128.465244 -227.679866) (xy 128.430157 -227.714952) (xy 128.390012 -227.744117) (xy 128.3458 -227.766643)
			(xy 128.298608 -227.781975) (xy 128.249598 -227.789736) (xy 128.224788 -227.790248) (xy 128.197873 -227.789701)
			(xy 128.144824 -227.780564) (xy 128.094095 -227.762557) (xy 128.070356 -227.749862) (xy 128.059688 -227.743766)
			(xy 128.035304 -227.74275) (xy 127.96393 -227.776024) (xy 127.953535 -227.781574) (xy 127.938841 -227.799964)
			(xy 127.935736 -227.81133) (xy 127.935736 -227.811838) (xy 127.927752 -227.848529) (xy 127.90882 -227.921202)
			(xy 127.89789 -227.957126) (xy 127.895067 -227.968039) (xy 127.89812 -227.990343) (xy 127.910426 -228.009194)
			(xy 127.919734 -228.015546) (xy 127.940629 -228.028893) (xy 127.978329 -228.061094) (xy 128.010526 -228.098797)
			(xy 128.036429 -228.141072) (xy 128.0554 -228.186879) (xy 128.066972 -228.235089) (xy 128.07086 -228.284517)
			(xy 128.070859 -228.284532) (xy 128.388884 -228.284532) (xy 128.392844 -228.235478) (xy 128.404621 -228.187694)
			(xy 128.423912 -228.142418) (xy 128.450215 -228.100822) (xy 128.48285 -228.063985) (xy 128.520971 -228.03286)
			(xy 128.563592 -228.008253) (xy 128.609608 -227.990801) (xy 128.657827 -227.980957) (xy 128.707002 -227.978976)
			(xy 128.755857 -227.984908) (xy 128.803128 -227.9986) (xy 128.84759 -228.019698) (xy 128.888093 -228.047654)
			(xy 128.923586 -228.081746) (xy 128.953151 -228.12109) (xy 128.976022 -228.164667) (xy 128.991606 -228.211348)
			(xy 128.999501 -228.259925) (xy 128.999996 -228.284532) (xy 129.318507 -228.284532) (xy 129.322602 -228.233804)
			(xy 129.334781 -228.18439) (xy 129.354729 -228.13757) (xy 129.38193 -228.094556) (xy 129.415678 -228.056462)
			(xy 129.4551 -228.024275) (xy 129.499174 -227.998829) (xy 129.54676 -227.980782) (xy 129.596624 -227.970602)
			(xy 129.647476 -227.968553) (xy 129.697997 -227.974687) (xy 129.746881 -227.988847) (xy 129.79286 -228.010664)
			(xy 129.834744 -228.039574) (xy 129.871448 -228.074829) (xy 129.902021 -228.115515) (xy 129.925672 -228.160578)
			(xy 129.941788 -228.208852) (xy 129.949952 -228.259086) (xy 129.950464 -228.284532) (xy 130.268992 -228.284532)
			(xy 130.272952 -228.235478) (xy 130.284729 -228.187694) (xy 130.30402 -228.142418) (xy 130.330323 -228.100822)
			(xy 130.362958 -228.063985) (xy 130.401079 -228.03286) (xy 130.4437 -228.008253) (xy 130.489716 -227.990801)
			(xy 130.537935 -227.980957) (xy 130.58711 -227.978976) (xy 130.635965 -227.984908) (xy 130.683236 -227.9986)
			(xy 130.727698 -228.019698) (xy 130.768201 -228.047654) (xy 130.803694 -228.081746) (xy 130.833259 -228.12109)
			(xy 130.85613 -228.164667) (xy 130.871714 -228.211348) (xy 130.879609 -228.259925) (xy 130.880104 -228.284532)
			(xy 131.198615 -228.284532) (xy 131.20271 -228.233804) (xy 131.214889 -228.18439) (xy 131.234837 -228.13757)
			(xy 131.262038 -228.094556) (xy 131.295786 -228.056462) (xy 131.335208 -228.024275) (xy 131.379282 -227.998829)
			(xy 131.426868 -227.980782) (xy 131.476732 -227.970602) (xy 131.527584 -227.968553) (xy 131.578105 -227.974687)
			(xy 131.626989 -227.988847) (xy 131.672968 -228.010664) (xy 131.714852 -228.039574) (xy 131.751556 -228.074829)
			(xy 131.782129 -228.115515) (xy 131.80578 -228.160578) (xy 131.821896 -228.208852) (xy 131.83006 -228.259086)
			(xy 131.830572 -228.284532) (xy 132.138415 -228.284532) (xy 132.14251 -228.233804) (xy 132.154689 -228.18439)
			(xy 132.174637 -228.13757) (xy 132.201838 -228.094556) (xy 132.235586 -228.056462) (xy 132.275008 -228.024275)
			(xy 132.319082 -227.998829) (xy 132.366668 -227.980782) (xy 132.416532 -227.970602) (xy 132.467384 -227.968553)
			(xy 132.517905 -227.974687) (xy 132.566789 -227.988847) (xy 132.612768 -228.010664) (xy 132.654652 -228.039574)
			(xy 132.691356 -228.074829) (xy 132.721929 -228.115515) (xy 132.74558 -228.160578) (xy 132.761696 -228.208852)
			(xy 132.76986 -228.259086) (xy 132.770372 -228.284532) (xy 133.0889 -228.284532) (xy 133.09286 -228.235478)
			(xy 133.104637 -228.187694) (xy 133.123928 -228.142418) (xy 133.150231 -228.100822) (xy 133.182866 -228.063985)
			(xy 133.220987 -228.03286) (xy 133.263608 -228.008253) (xy 133.309624 -227.990801) (xy 133.357843 -227.980957)
			(xy 133.407018 -227.978976) (xy 133.455873 -227.984908) (xy 133.503144 -227.9986) (xy 133.547606 -228.019698)
			(xy 133.588109 -228.047654) (xy 133.623602 -228.081746) (xy 133.653167 -228.12109) (xy 133.676038 -228.164667)
			(xy 133.691622 -228.211348) (xy 133.699517 -228.259925) (xy 133.700012 -228.284532) (xy 134.028954 -228.284532)
			(xy 134.032914 -228.235478) (xy 134.044691 -228.187694) (xy 134.063982 -228.142418) (xy 134.090285 -228.100822)
			(xy 134.12292 -228.063985) (xy 134.161041 -228.03286) (xy 134.203662 -228.008253) (xy 134.249678 -227.990801)
			(xy 134.297897 -227.980957) (xy 134.347072 -227.978976) (xy 134.395927 -227.984908) (xy 134.443198 -227.9986)
			(xy 134.48766 -228.019698) (xy 134.528163 -228.047654) (xy 134.563656 -228.081746) (xy 134.593221 -228.12109)
			(xy 134.616092 -228.164667) (xy 134.631676 -228.211348) (xy 134.639571 -228.259925) (xy 134.640066 -228.284532)
			(xy 134.969008 -228.284532) (xy 134.972968 -228.235478) (xy 134.984745 -228.187694) (xy 135.004036 -228.142418)
			(xy 135.030339 -228.100822) (xy 135.062974 -228.063985) (xy 135.101095 -228.03286) (xy 135.143716 -228.008253)
			(xy 135.189732 -227.990801) (xy 135.237951 -227.980957) (xy 135.287126 -227.978976) (xy 135.335981 -227.984908)
			(xy 135.383252 -227.9986) (xy 135.427714 -228.019698) (xy 135.468217 -228.047654) (xy 135.50371 -228.081746)
			(xy 135.533275 -228.12109) (xy 135.556146 -228.164667) (xy 135.57173 -228.211348) (xy 135.579625 -228.259925)
			(xy 135.58012 -228.284532) (xy 135.909062 -228.284532) (xy 135.913022 -228.235478) (xy 135.924799 -228.187694)
			(xy 135.94409 -228.142418) (xy 135.970393 -228.100822) (xy 136.003028 -228.063985) (xy 136.041149 -228.03286)
			(xy 136.08377 -228.008253) (xy 136.129786 -227.990801) (xy 136.178005 -227.980957) (xy 136.22718 -227.978976)
			(xy 136.276035 -227.984908) (xy 136.323306 -227.9986) (xy 136.367768 -228.019698) (xy 136.408271 -228.047654)
			(xy 136.443764 -228.081746) (xy 136.473329 -228.12109) (xy 136.4962 -228.164667) (xy 136.511784 -228.211348)
			(xy 136.519679 -228.259925) (xy 136.520174 -228.284532) (xy 136.519679 -228.309139) (xy 136.511784 -228.357716)
			(xy 136.4962 -228.404397) (xy 136.473329 -228.447974) (xy 136.443764 -228.487318) (xy 136.408271 -228.52141)
			(xy 136.367768 -228.549366) (xy 136.323306 -228.570464) (xy 136.276035 -228.584156) (xy 136.22718 -228.590088)
			(xy 136.178005 -228.588107) (xy 136.129786 -228.578263) (xy 136.08377 -228.560811) (xy 136.041149 -228.536204)
			(xy 136.003028 -228.505079) (xy 135.970393 -228.468242) (xy 135.94409 -228.426646) (xy 135.924799 -228.38137)
			(xy 135.913022 -228.333586) (xy 135.909062 -228.284532) (xy 135.58012 -228.284532) (xy 135.579625 -228.309139)
			(xy 135.57173 -228.357716) (xy 135.556146 -228.404397) (xy 135.533275 -228.447974) (xy 135.50371 -228.487318)
			(xy 135.468217 -228.52141) (xy 135.427714 -228.549366) (xy 135.383252 -228.570464) (xy 135.335981 -228.584156)
			(xy 135.287126 -228.590088) (xy 135.237951 -228.588107) (xy 135.189732 -228.578263) (xy 135.143716 -228.560811)
			(xy 135.101095 -228.536204) (xy 135.062974 -228.505079) (xy 135.030339 -228.468242) (xy 135.004036 -228.426646)
			(xy 134.984745 -228.38137) (xy 134.972968 -228.333586) (xy 134.969008 -228.284532) (xy 134.640066 -228.284532)
			(xy 134.639571 -228.309139) (xy 134.631676 -228.357716) (xy 134.616092 -228.404397) (xy 134.593221 -228.447974)
			(xy 134.563656 -228.487318) (xy 134.528163 -228.52141) (xy 134.48766 -228.549366) (xy 134.443198 -228.570464)
			(xy 134.395927 -228.584156) (xy 134.347072 -228.590088) (xy 134.297897 -228.588107) (xy 134.249678 -228.578263)
			(xy 134.203662 -228.560811) (xy 134.161041 -228.536204) (xy 134.12292 -228.505079) (xy 134.090285 -228.468242)
			(xy 134.063982 -228.426646) (xy 134.044691 -228.38137) (xy 134.032914 -228.333586) (xy 134.028954 -228.284532)
			(xy 133.700012 -228.284532) (xy 133.699517 -228.309139) (xy 133.691622 -228.357716) (xy 133.676038 -228.404397)
			(xy 133.653167 -228.447974) (xy 133.623602 -228.487318) (xy 133.588109 -228.52141) (xy 133.547606 -228.549366)
			(xy 133.503144 -228.570464) (xy 133.455873 -228.584156) (xy 133.407018 -228.590088) (xy 133.357843 -228.588107)
			(xy 133.309624 -228.578263) (xy 133.263608 -228.560811) (xy 133.220987 -228.536204) (xy 133.182866 -228.505079)
			(xy 133.150231 -228.468242) (xy 133.123928 -228.426646) (xy 133.104637 -228.38137) (xy 133.09286 -228.333586)
			(xy 133.0889 -228.284532) (xy 132.770372 -228.284532) (xy 132.76986 -228.309978) (xy 132.761696 -228.360212)
			(xy 132.74558 -228.408486) (xy 132.721929 -228.453549) (xy 132.691356 -228.494235) (xy 132.654652 -228.52949)
			(xy 132.612768 -228.5584) (xy 132.566789 -228.580217) (xy 132.517905 -228.594377) (xy 132.467384 -228.600511)
			(xy 132.416532 -228.598462) (xy 132.366668 -228.588282) (xy 132.319082 -228.570235) (xy 132.275008 -228.544789)
			(xy 132.235586 -228.512602) (xy 132.201838 -228.474508) (xy 132.174637 -228.431494) (xy 132.154689 -228.384674)
			(xy 132.14251 -228.33526) (xy 132.138415 -228.284532) (xy 131.830572 -228.284532) (xy 131.83006 -228.309978)
			(xy 131.821896 -228.360212) (xy 131.80578 -228.408486) (xy 131.782129 -228.453549) (xy 131.751556 -228.494235)
			(xy 131.714852 -228.52949) (xy 131.672968 -228.5584) (xy 131.626989 -228.580217) (xy 131.578105 -228.594377)
			(xy 131.527584 -228.600511) (xy 131.476732 -228.598462) (xy 131.426868 -228.588282) (xy 131.379282 -228.570235)
			(xy 131.335208 -228.544789) (xy 131.295786 -228.512602) (xy 131.262038 -228.474508) (xy 131.234837 -228.431494)
			(xy 131.214889 -228.384674) (xy 131.20271 -228.33526) (xy 131.198615 -228.284532) (xy 130.880104 -228.284532)
			(xy 130.879609 -228.309139) (xy 130.871714 -228.357716) (xy 130.85613 -228.404397) (xy 130.833259 -228.447974)
			(xy 130.803694 -228.487318) (xy 130.768201 -228.52141) (xy 130.727698 -228.549366) (xy 130.683236 -228.570464)
			(xy 130.635965 -228.584156) (xy 130.58711 -228.590088) (xy 130.537935 -228.588107) (xy 130.489716 -228.578263)
			(xy 130.4437 -228.560811) (xy 130.401079 -228.536204) (xy 130.362958 -228.505079) (xy 130.330323 -228.468242)
			(xy 130.30402 -228.426646) (xy 130.284729 -228.38137) (xy 130.272952 -228.333586) (xy 130.268992 -228.284532)
			(xy 129.950464 -228.284532) (xy 129.949952 -228.309978) (xy 129.941788 -228.360212) (xy 129.925672 -228.408486)
			(xy 129.902021 -228.453549) (xy 129.871448 -228.494235) (xy 129.834744 -228.52949) (xy 129.79286 -228.5584)
			(xy 129.746881 -228.580217) (xy 129.697997 -228.594377) (xy 129.647476 -228.600511) (xy 129.596624 -228.598462)
			(xy 129.54676 -228.588282) (xy 129.499174 -228.570235) (xy 129.4551 -228.544789) (xy 129.415678 -228.512602)
			(xy 129.38193 -228.474508) (xy 129.354729 -228.431494) (xy 129.334781 -228.384674) (xy 129.322602 -228.33526)
			(xy 129.318507 -228.284532) (xy 128.999996 -228.284532) (xy 128.999501 -228.309139) (xy 128.991606 -228.357716)
			(xy 128.976022 -228.404397) (xy 128.953151 -228.447974) (xy 128.923586 -228.487318) (xy 128.888093 -228.52141)
			(xy 128.84759 -228.549366) (xy 128.803128 -228.570464) (xy 128.755857 -228.584156) (xy 128.707002 -228.590088)
			(xy 128.657827 -228.588107) (xy 128.609608 -228.578263) (xy 128.563592 -228.560811) (xy 128.520971 -228.536204)
			(xy 128.48285 -228.505079) (xy 128.450215 -228.468242) (xy 128.423912 -228.426646) (xy 128.404621 -228.38137)
			(xy 128.392844 -228.333586) (xy 128.388884 -228.284532) (xy 128.070859 -228.284532) (xy 128.066967 -228.333944)
			(xy 128.05539 -228.382153) (xy 128.036414 -228.427958) (xy 128.010507 -228.47023) (xy 127.978305 -228.507929)
			(xy 127.940602 -228.540127) (xy 127.919734 -228.553518) (xy 127.910482 -228.559932) (xy 127.898201 -228.578769)
			(xy 127.895083 -228.601038) (xy 127.89789 -228.611938) (xy 127.908811 -228.647864) (xy 127.927741 -228.720537)
			(xy 127.935736 -228.757226) (xy 127.935736 -228.757734) (xy 127.938787 -228.769131) (xy 127.953491 -228.787542)
			(xy 127.96393 -228.79304) (xy 128.035304 -228.826314) (xy 128.059688 -228.825298) (xy 128.070356 -228.819202)
			(xy 128.094093 -228.806501) (xy 128.144823 -228.788496) (xy 128.197873 -228.77936) (xy 128.224788 -228.778816)
			(xy 128.249597 -228.779276) (xy 128.298605 -228.787037) (xy 128.345795 -228.802368) (xy 128.390006 -228.824893)
			(xy 128.430149 -228.854057) (xy 128.465235 -228.889142) (xy 128.4944 -228.929284) (xy 128.516927 -228.973494)
			(xy 128.532261 -229.020683) (xy 128.540023 -229.069691) (xy 128.540023 -229.094538) (xy 128.848607 -229.094538)
			(xy 128.852702 -229.04381) (xy 128.864881 -228.994396) (xy 128.884829 -228.947576) (xy 128.91203 -228.904562)
			(xy 128.945778 -228.866468) (xy 128.9852 -228.834281) (xy 129.029274 -228.808835) (xy 129.07686 -228.790788)
			(xy 129.126724 -228.780608) (xy 129.177576 -228.778559) (xy 129.228097 -228.784693) (xy 129.276981 -228.798853)
			(xy 129.32296 -228.82067) (xy 129.364844 -228.84958) (xy 129.401548 -228.884835) (xy 129.432121 -228.925521)
			(xy 129.455772 -228.970584) (xy 129.471888 -229.018858) (xy 129.480052 -229.069092) (xy 129.480564 -229.094538)
			(xy 129.798838 -229.094538) (xy 129.802798 -229.045484) (xy 129.814575 -228.9977) (xy 129.833866 -228.952424)
			(xy 129.860169 -228.910828) (xy 129.892804 -228.873991) (xy 129.930925 -228.842866) (xy 129.973546 -228.818259)
			(xy 130.019562 -228.800807) (xy 130.067781 -228.790963) (xy 130.116956 -228.788982) (xy 130.165811 -228.794914)
			(xy 130.213082 -228.808606) (xy 130.257544 -228.829704) (xy 130.298047 -228.85766) (xy 130.33354 -228.891752)
			(xy 130.363105 -228.931096) (xy 130.385976 -228.974673) (xy 130.40156 -229.021354) (xy 130.409455 -229.069931)
			(xy 130.40995 -229.094538) (xy 130.728461 -229.094538) (xy 130.732556 -229.04381) (xy 130.744735 -228.994396)
			(xy 130.764683 -228.947576) (xy 130.791884 -228.904562) (xy 130.825632 -228.866468) (xy 130.865054 -228.834281)
			(xy 130.909128 -228.808835) (xy 130.956714 -228.790788) (xy 131.006578 -228.780608) (xy 131.05743 -228.778559)
			(xy 131.107951 -228.784693) (xy 131.156835 -228.798853) (xy 131.202814 -228.82067) (xy 131.244698 -228.84958)
			(xy 131.281402 -228.884835) (xy 131.311975 -228.925521) (xy 131.335626 -228.970584) (xy 131.351742 -229.018858)
			(xy 131.359906 -229.069092) (xy 131.360418 -229.094538) (xy 131.678946 -229.094538) (xy 131.682906 -229.045484)
			(xy 131.694683 -228.9977) (xy 131.713974 -228.952424) (xy 131.740277 -228.910828) (xy 131.772912 -228.873991)
			(xy 131.811033 -228.842866) (xy 131.853654 -228.818259) (xy 131.89967 -228.800807) (xy 131.947889 -228.790963)
			(xy 131.997064 -228.788982) (xy 132.045919 -228.794914) (xy 132.09319 -228.808606) (xy 132.137652 -228.829704)
			(xy 132.178155 -228.85766) (xy 132.213648 -228.891752) (xy 132.243213 -228.931096) (xy 132.266084 -228.974673)
			(xy 132.281668 -229.021354) (xy 132.289563 -229.069931) (xy 132.290058 -229.094538) (xy 132.608569 -229.094538)
			(xy 132.612664 -229.04381) (xy 132.624843 -228.994396) (xy 132.644791 -228.947576) (xy 132.671992 -228.904562)
			(xy 132.70574 -228.866468) (xy 132.745162 -228.834281) (xy 132.789236 -228.808835) (xy 132.836822 -228.790788)
			(xy 132.886686 -228.780608) (xy 132.937538 -228.778559) (xy 132.988059 -228.784693) (xy 133.036943 -228.798853)
			(xy 133.082922 -228.82067) (xy 133.124806 -228.84958) (xy 133.16151 -228.884835) (xy 133.192083 -228.925521)
			(xy 133.215734 -228.970584) (xy 133.23185 -229.018858) (xy 133.240014 -229.069092) (xy 133.240526 -229.094538)
			(xy 133.559054 -229.094538) (xy 133.563014 -229.045484) (xy 133.574791 -228.9977) (xy 133.594082 -228.952424)
			(xy 133.620385 -228.910828) (xy 133.65302 -228.873991) (xy 133.691141 -228.842866) (xy 133.733762 -228.818259)
			(xy 133.779778 -228.800807) (xy 133.827997 -228.790963) (xy 133.877172 -228.788982) (xy 133.926027 -228.794914)
			(xy 133.973298 -228.808606) (xy 134.01776 -228.829704) (xy 134.058263 -228.85766) (xy 134.093756 -228.891752)
			(xy 134.123321 -228.931096) (xy 134.146192 -228.974673) (xy 134.161776 -229.021354) (xy 134.169671 -229.069931)
			(xy 134.170166 -229.094538) (xy 134.498854 -229.094538) (xy 134.502814 -229.045484) (xy 134.514591 -228.9977)
			(xy 134.533882 -228.952424) (xy 134.560185 -228.910828) (xy 134.59282 -228.873991) (xy 134.630941 -228.842866)
			(xy 134.673562 -228.818259) (xy 134.719578 -228.800807) (xy 134.767797 -228.790963) (xy 134.816972 -228.788982)
			(xy 134.865827 -228.794914) (xy 134.913098 -228.808606) (xy 134.95756 -228.829704) (xy 134.998063 -228.85766)
			(xy 135.033556 -228.891752) (xy 135.063121 -228.931096) (xy 135.085992 -228.974673) (xy 135.101576 -229.021354)
			(xy 135.109471 -229.069931) (xy 135.109966 -229.094538) (xy 135.438908 -229.094538) (xy 135.442868 -229.045484)
			(xy 135.454645 -228.9977) (xy 135.473936 -228.952424) (xy 135.500239 -228.910828) (xy 135.532874 -228.873991)
			(xy 135.570995 -228.842866) (xy 135.613616 -228.818259) (xy 135.659632 -228.800807) (xy 135.707851 -228.790963)
			(xy 135.757026 -228.788982) (xy 135.805881 -228.794914) (xy 135.853152 -228.808606) (xy 135.897614 -228.829704)
			(xy 135.938117 -228.85766) (xy 135.97361 -228.891752) (xy 136.003175 -228.931096) (xy 136.026046 -228.974673)
			(xy 136.04163 -229.021354) (xy 136.049525 -229.069931) (xy 136.05002 -229.094538) (xy 136.049525 -229.119145)
			(xy 136.04163 -229.167722) (xy 136.026046 -229.214403) (xy 136.003175 -229.25798) (xy 135.97361 -229.297324)
			(xy 135.938117 -229.331416) (xy 135.897614 -229.359372) (xy 135.853152 -229.38047) (xy 135.805881 -229.394162)
			(xy 135.757026 -229.400094) (xy 135.707851 -229.398113) (xy 135.659632 -229.388269) (xy 135.613616 -229.370817)
			(xy 135.570995 -229.34621) (xy 135.532874 -229.315085) (xy 135.500239 -229.278248) (xy 135.473936 -229.236652)
			(xy 135.454645 -229.191376) (xy 135.442868 -229.143592) (xy 135.438908 -229.094538) (xy 135.109966 -229.094538)
			(xy 135.109471 -229.119145) (xy 135.101576 -229.167722) (xy 135.085992 -229.214403) (xy 135.063121 -229.25798)
			(xy 135.033556 -229.297324) (xy 134.998063 -229.331416) (xy 134.95756 -229.359372) (xy 134.913098 -229.38047)
			(xy 134.865827 -229.394162) (xy 134.816972 -229.400094) (xy 134.767797 -229.398113) (xy 134.719578 -229.388269)
			(xy 134.673562 -229.370817) (xy 134.630941 -229.34621) (xy 134.59282 -229.315085) (xy 134.560185 -229.278248)
			(xy 134.533882 -229.236652) (xy 134.514591 -229.191376) (xy 134.502814 -229.143592) (xy 134.498854 -229.094538)
			(xy 134.170166 -229.094538) (xy 134.169671 -229.119145) (xy 134.161776 -229.167722) (xy 134.146192 -229.214403)
			(xy 134.123321 -229.25798) (xy 134.093756 -229.297324) (xy 134.058263 -229.331416) (xy 134.01776 -229.359372)
			(xy 133.973298 -229.38047) (xy 133.926027 -229.394162) (xy 133.877172 -229.400094) (xy 133.827997 -229.398113)
			(xy 133.779778 -229.388269) (xy 133.733762 -229.370817) (xy 133.691141 -229.34621) (xy 133.65302 -229.315085)
			(xy 133.620385 -229.278248) (xy 133.594082 -229.236652) (xy 133.574791 -229.191376) (xy 133.563014 -229.143592)
			(xy 133.559054 -229.094538) (xy 133.240526 -229.094538) (xy 133.240014 -229.119984) (xy 133.23185 -229.170218)
			(xy 133.215734 -229.218492) (xy 133.192083 -229.263555) (xy 133.16151 -229.304241) (xy 133.124806 -229.339496)
			(xy 133.082922 -229.368406) (xy 133.036943 -229.390223) (xy 132.988059 -229.404383) (xy 132.937538 -229.410517)
			(xy 132.886686 -229.408468) (xy 132.836822 -229.398288) (xy 132.789236 -229.380241) (xy 132.745162 -229.354795)
			(xy 132.70574 -229.322608) (xy 132.671992 -229.284514) (xy 132.644791 -229.2415) (xy 132.624843 -229.19468)
			(xy 132.612664 -229.145266) (xy 132.608569 -229.094538) (xy 132.290058 -229.094538) (xy 132.289563 -229.119145)
			(xy 132.281668 -229.167722) (xy 132.266084 -229.214403) (xy 132.243213 -229.25798) (xy 132.213648 -229.297324)
			(xy 132.178155 -229.331416) (xy 132.137652 -229.359372) (xy 132.09319 -229.38047) (xy 132.045919 -229.394162)
			(xy 131.997064 -229.400094) (xy 131.947889 -229.398113) (xy 131.89967 -229.388269) (xy 131.853654 -229.370817)
			(xy 131.811033 -229.34621) (xy 131.772912 -229.315085) (xy 131.740277 -229.278248) (xy 131.713974 -229.236652)
			(xy 131.694683 -229.191376) (xy 131.682906 -229.143592) (xy 131.678946 -229.094538) (xy 131.360418 -229.094538)
			(xy 131.359906 -229.119984) (xy 131.351742 -229.170218) (xy 131.335626 -229.218492) (xy 131.311975 -229.263555)
			(xy 131.281402 -229.304241) (xy 131.244698 -229.339496) (xy 131.202814 -229.368406) (xy 131.156835 -229.390223)
			(xy 131.107951 -229.404383) (xy 131.05743 -229.410517) (xy 131.006578 -229.408468) (xy 130.956714 -229.398288)
			(xy 130.909128 -229.380241) (xy 130.865054 -229.354795) (xy 130.825632 -229.322608) (xy 130.791884 -229.284514)
			(xy 130.764683 -229.2415) (xy 130.744735 -229.19468) (xy 130.732556 -229.145266) (xy 130.728461 -229.094538)
			(xy 130.40995 -229.094538) (xy 130.409455 -229.119145) (xy 130.40156 -229.167722) (xy 130.385976 -229.214403)
			(xy 130.363105 -229.25798) (xy 130.33354 -229.297324) (xy 130.298047 -229.331416) (xy 130.257544 -229.359372)
			(xy 130.213082 -229.38047) (xy 130.165811 -229.394162) (xy 130.116956 -229.400094) (xy 130.067781 -229.398113)
			(xy 130.019562 -229.388269) (xy 129.973546 -229.370817) (xy 129.930925 -229.34621) (xy 129.892804 -229.315085)
			(xy 129.860169 -229.278248) (xy 129.833866 -229.236652) (xy 129.814575 -229.191376) (xy 129.802798 -229.143592)
			(xy 129.798838 -229.094538) (xy 129.480564 -229.094538) (xy 129.480052 -229.119984) (xy 129.471888 -229.170218)
			(xy 129.455772 -229.218492) (xy 129.432121 -229.263555) (xy 129.401548 -229.304241) (xy 129.364844 -229.339496)
			(xy 129.32296 -229.368406) (xy 129.276981 -229.390223) (xy 129.228097 -229.404383) (xy 129.177576 -229.410517)
			(xy 129.126724 -229.408468) (xy 129.07686 -229.398288) (xy 129.029274 -229.380241) (xy 128.9852 -229.354795)
			(xy 128.945778 -229.322608) (xy 128.91203 -229.284514) (xy 128.884829 -229.2415) (xy 128.864881 -229.19468)
			(xy 128.852702 -229.145266) (xy 128.848607 -229.094538) (xy 128.540023 -229.094538) (xy 128.540023 -229.119309)
			(xy 128.532261 -229.168317) (xy 128.516927 -229.215506) (xy 128.4944 -229.259716) (xy 128.465235 -229.299858)
			(xy 128.430149 -229.334943) (xy 128.390006 -229.364107) (xy 128.345795 -229.386632) (xy 128.298605 -229.401963)
			(xy 128.249597 -229.409724) (xy 128.224788 -229.41026) (xy 128.197873 -229.409713) (xy 128.144824 -229.400577)
			(xy 128.094095 -229.38257) (xy 128.070356 -229.369874) (xy 128.059688 -229.363778) (xy 128.035304 -229.363016)
			(xy 127.953008 -229.40137) (xy 127.938276 -229.419912) (xy 127.935736 -229.43185) (xy 127.927684 -229.46848)
			(xy 127.908624 -229.541025) (xy 127.897636 -229.576884) (xy 127.894878 -229.587821) (xy 127.898044 -229.610126)
			(xy 127.910414 -229.628954) (xy 127.919734 -229.635304) (xy 127.942355 -229.6498) (xy 127.982746 -229.685221)
			(xy 128.016556 -229.72697) (xy 128.042807 -229.773842) (xy 128.060741 -229.824483) (xy 128.069841 -229.877429)
			(xy 128.070356 -229.90429) (xy 128.388884 -229.90429) (xy 128.392844 -229.855236) (xy 128.404621 -229.807452)
			(xy 128.423912 -229.762176) (xy 128.450215 -229.72058) (xy 128.48285 -229.683743) (xy 128.520971 -229.652618)
			(xy 128.563592 -229.628011) (xy 128.609608 -229.610559) (xy 128.657827 -229.600715) (xy 128.707002 -229.598734)
			(xy 128.755857 -229.604666) (xy 128.803128 -229.618358) (xy 128.84759 -229.639456) (xy 128.888093 -229.667412)
			(xy 128.923586 -229.701504) (xy 128.953151 -229.740848) (xy 128.976022 -229.784425) (xy 128.991606 -229.831106)
			(xy 128.999501 -229.879683) (xy 128.999996 -229.90429) (xy 129.318507 -229.90429) (xy 129.322602 -229.853562)
			(xy 129.334781 -229.804148) (xy 129.354729 -229.757328) (xy 129.38193 -229.714314) (xy 129.415678 -229.67622)
			(xy 129.4551 -229.644033) (xy 129.499174 -229.618587) (xy 129.54676 -229.60054) (xy 129.596624 -229.59036)
			(xy 129.647476 -229.588311) (xy 129.697997 -229.594445) (xy 129.746881 -229.608605) (xy 129.79286 -229.630422)
			(xy 129.834744 -229.659332) (xy 129.871448 -229.694587) (xy 129.902021 -229.735273) (xy 129.925672 -229.780336)
			(xy 129.941788 -229.82861) (xy 129.949952 -229.878844) (xy 129.950464 -229.90429) (xy 131.198615 -229.90429)
			(xy 131.20271 -229.853562) (xy 131.214889 -229.804148) (xy 131.234837 -229.757328) (xy 131.262038 -229.714314)
			(xy 131.295786 -229.67622) (xy 131.335208 -229.644033) (xy 131.379282 -229.618587) (xy 131.426868 -229.60054)
			(xy 131.476732 -229.59036) (xy 131.527584 -229.588311) (xy 131.578105 -229.594445) (xy 131.626989 -229.608605)
			(xy 131.672968 -229.630422) (xy 131.714852 -229.659332) (xy 131.751556 -229.694587) (xy 131.782129 -229.735273)
			(xy 131.80578 -229.780336) (xy 131.821896 -229.82861) (xy 131.83006 -229.878844) (xy 131.830572 -229.90429)
			(xy 132.138415 -229.90429) (xy 132.14251 -229.853562) (xy 132.154689 -229.804148) (xy 132.174637 -229.757328)
			(xy 132.201838 -229.714314) (xy 132.235586 -229.67622) (xy 132.275008 -229.644033) (xy 132.319082 -229.618587)
			(xy 132.366668 -229.60054) (xy 132.416532 -229.59036) (xy 132.467384 -229.588311) (xy 132.517905 -229.594445)
			(xy 132.566789 -229.608605) (xy 132.612768 -229.630422) (xy 132.654652 -229.659332) (xy 132.691356 -229.694587)
			(xy 132.721929 -229.735273) (xy 132.74558 -229.780336) (xy 132.761696 -229.82861) (xy 132.76986 -229.878844)
			(xy 132.770372 -229.90429) (xy 133.0889 -229.90429) (xy 133.09286 -229.855236) (xy 133.104637 -229.807452)
			(xy 133.123928 -229.762176) (xy 133.150231 -229.72058) (xy 133.182866 -229.683743) (xy 133.220987 -229.652618)
			(xy 133.263608 -229.628011) (xy 133.309624 -229.610559) (xy 133.357843 -229.600715) (xy 133.407018 -229.598734)
			(xy 133.455873 -229.604666) (xy 133.503144 -229.618358) (xy 133.547606 -229.639456) (xy 133.588109 -229.667412)
			(xy 133.623602 -229.701504) (xy 133.653167 -229.740848) (xy 133.676038 -229.784425) (xy 133.691622 -229.831106)
			(xy 133.699517 -229.879683) (xy 133.700012 -229.90429) (xy 134.028954 -229.90429) (xy 134.032914 -229.855236)
			(xy 134.044691 -229.807452) (xy 134.063982 -229.762176) (xy 134.090285 -229.72058) (xy 134.12292 -229.683743)
			(xy 134.161041 -229.652618) (xy 134.203662 -229.628011) (xy 134.249678 -229.610559) (xy 134.297897 -229.600715)
			(xy 134.347072 -229.598734) (xy 134.395927 -229.604666) (xy 134.443198 -229.618358) (xy 134.48766 -229.639456)
			(xy 134.528163 -229.667412) (xy 134.563656 -229.701504) (xy 134.593221 -229.740848) (xy 134.616092 -229.784425)
			(xy 134.631676 -229.831106) (xy 134.639571 -229.879683) (xy 134.640066 -229.90429) (xy 134.969008 -229.90429)
			(xy 134.972968 -229.855236) (xy 134.984745 -229.807452) (xy 135.004036 -229.762176) (xy 135.030339 -229.72058)
			(xy 135.062974 -229.683743) (xy 135.101095 -229.652618) (xy 135.143716 -229.628011) (xy 135.189732 -229.610559)
			(xy 135.237951 -229.600715) (xy 135.287126 -229.598734) (xy 135.335981 -229.604666) (xy 135.383252 -229.618358)
			(xy 135.427714 -229.639456) (xy 135.468217 -229.667412) (xy 135.50371 -229.701504) (xy 135.533275 -229.740848)
			(xy 135.556146 -229.784425) (xy 135.57173 -229.831106) (xy 135.579625 -229.879683) (xy 135.58012 -229.90429)
			(xy 135.909062 -229.90429) (xy 135.913022 -229.855236) (xy 135.924799 -229.807452) (xy 135.94409 -229.762176)
			(xy 135.970393 -229.72058) (xy 136.003028 -229.683743) (xy 136.041149 -229.652618) (xy 136.08377 -229.628011)
			(xy 136.129786 -229.610559) (xy 136.178005 -229.600715) (xy 136.22718 -229.598734) (xy 136.276035 -229.604666)
			(xy 136.323306 -229.618358) (xy 136.367768 -229.639456) (xy 136.408271 -229.667412) (xy 136.443764 -229.701504)
			(xy 136.473329 -229.740848) (xy 136.4962 -229.784425) (xy 136.511784 -229.831106) (xy 136.519679 -229.879683)
			(xy 136.520174 -229.90429) (xy 136.519679 -229.928897) (xy 136.511784 -229.977474) (xy 136.4962 -230.024155)
			(xy 136.473329 -230.067732) (xy 136.443764 -230.107076) (xy 136.408271 -230.141168) (xy 136.367768 -230.169124)
			(xy 136.323306 -230.190222) (xy 136.276035 -230.203914) (xy 136.22718 -230.209846) (xy 136.178005 -230.207865)
			(xy 136.129786 -230.198021) (xy 136.08377 -230.180569) (xy 136.041149 -230.155962) (xy 136.003028 -230.124837)
			(xy 135.970393 -230.088) (xy 135.94409 -230.046404) (xy 135.924799 -230.001128) (xy 135.913022 -229.953344)
			(xy 135.909062 -229.90429) (xy 135.58012 -229.90429) (xy 135.579625 -229.928897) (xy 135.57173 -229.977474)
			(xy 135.556146 -230.024155) (xy 135.533275 -230.067732) (xy 135.50371 -230.107076) (xy 135.468217 -230.141168)
			(xy 135.427714 -230.169124) (xy 135.383252 -230.190222) (xy 135.335981 -230.203914) (xy 135.287126 -230.209846)
			(xy 135.237951 -230.207865) (xy 135.189732 -230.198021) (xy 135.143716 -230.180569) (xy 135.101095 -230.155962)
			(xy 135.062974 -230.124837) (xy 135.030339 -230.088) (xy 135.004036 -230.046404) (xy 134.984745 -230.001128)
			(xy 134.972968 -229.953344) (xy 134.969008 -229.90429) (xy 134.640066 -229.90429) (xy 134.639571 -229.928897)
			(xy 134.631676 -229.977474) (xy 134.616092 -230.024155) (xy 134.593221 -230.067732) (xy 134.563656 -230.107076)
			(xy 134.528163 -230.141168) (xy 134.48766 -230.169124) (xy 134.443198 -230.190222) (xy 134.395927 -230.203914)
			(xy 134.347072 -230.209846) (xy 134.297897 -230.207865) (xy 134.249678 -230.198021) (xy 134.203662 -230.180569)
			(xy 134.161041 -230.155962) (xy 134.12292 -230.124837) (xy 134.090285 -230.088) (xy 134.063982 -230.046404)
			(xy 134.044691 -230.001128) (xy 134.032914 -229.953344) (xy 134.028954 -229.90429) (xy 133.700012 -229.90429)
			(xy 133.699517 -229.928897) (xy 133.691622 -229.977474) (xy 133.676038 -230.024155) (xy 133.653167 -230.067732)
			(xy 133.623602 -230.107076) (xy 133.588109 -230.141168) (xy 133.547606 -230.169124) (xy 133.503144 -230.190222)
			(xy 133.455873 -230.203914) (xy 133.407018 -230.209846) (xy 133.357843 -230.207865) (xy 133.309624 -230.198021)
			(xy 133.263608 -230.180569) (xy 133.220987 -230.155962) (xy 133.182866 -230.124837) (xy 133.150231 -230.088)
			(xy 133.123928 -230.046404) (xy 133.104637 -230.001128) (xy 133.09286 -229.953344) (xy 133.0889 -229.90429)
			(xy 132.770372 -229.90429) (xy 132.76986 -229.929736) (xy 132.761696 -229.97997) (xy 132.74558 -230.028244)
			(xy 132.721929 -230.073307) (xy 132.691356 -230.113993) (xy 132.654652 -230.149248) (xy 132.612768 -230.178158)
			(xy 132.566789 -230.199975) (xy 132.517905 -230.214135) (xy 132.467384 -230.220269) (xy 132.416532 -230.21822)
			(xy 132.366668 -230.20804) (xy 132.319082 -230.189993) (xy 132.275008 -230.164547) (xy 132.235586 -230.13236)
			(xy 132.201838 -230.094266) (xy 132.174637 -230.051252) (xy 132.154689 -230.004432) (xy 132.14251 -229.955018)
			(xy 132.138415 -229.90429) (xy 131.830572 -229.90429) (xy 131.83006 -229.929736) (xy 131.821896 -229.97997)
			(xy 131.80578 -230.028244) (xy 131.782129 -230.073307) (xy 131.751556 -230.113993) (xy 131.714852 -230.149248)
			(xy 131.672968 -230.178158) (xy 131.626989 -230.199975) (xy 131.578105 -230.214135) (xy 131.527584 -230.220269)
			(xy 131.476732 -230.21822) (xy 131.426868 -230.20804) (xy 131.379282 -230.189993) (xy 131.335208 -230.164547)
			(xy 131.295786 -230.13236) (xy 131.262038 -230.094266) (xy 131.234837 -230.051252) (xy 131.214889 -230.004432)
			(xy 131.20271 -229.955018) (xy 131.198615 -229.90429) (xy 129.950464 -229.90429) (xy 129.949952 -229.929736)
			(xy 129.941788 -229.97997) (xy 129.925672 -230.028244) (xy 129.902021 -230.073307) (xy 129.871448 -230.113993)
			(xy 129.834744 -230.149248) (xy 129.79286 -230.178158) (xy 129.746881 -230.199975) (xy 129.697997 -230.214135)
			(xy 129.647476 -230.220269) (xy 129.596624 -230.21822) (xy 129.54676 -230.20804) (xy 129.499174 -230.189993)
			(xy 129.4551 -230.164547) (xy 129.415678 -230.13236) (xy 129.38193 -230.094266) (xy 129.354729 -230.051252)
			(xy 129.334781 -230.004432) (xy 129.322602 -229.955018) (xy 129.318507 -229.90429) (xy 128.999996 -229.90429)
			(xy 128.999501 -229.928897) (xy 128.991606 -229.977474) (xy 128.976022 -230.024155) (xy 128.953151 -230.067732)
			(xy 128.923586 -230.107076) (xy 128.888093 -230.141168) (xy 128.84759 -230.169124) (xy 128.803128 -230.190222)
			(xy 128.755857 -230.203914) (xy 128.707002 -230.209846) (xy 128.657827 -230.207865) (xy 128.609608 -230.198021)
			(xy 128.563592 -230.180569) (xy 128.520971 -230.155962) (xy 128.48285 -230.124837) (xy 128.450215 -230.088)
			(xy 128.423912 -230.046404) (xy 128.404621 -230.001128) (xy 128.392844 -229.953344) (xy 128.388884 -229.90429)
			(xy 128.070356 -229.90429) (xy 128.069799 -229.931162) (xy 128.060667 -229.984126) (xy 128.042698 -230.034779)
			(xy 128.016412 -230.081658) (xy 127.982567 -230.123409) (xy 127.942142 -230.158826) (xy 127.91948 -230.173276)
			(xy 127.910214 -230.17973) (xy 127.897943 -230.198654) (xy 127.894877 -230.220998) (xy 127.897636 -230.23195)
			(xy 127.908627 -230.267936) (xy 127.927684 -230.340736) (xy 127.935736 -230.377492) (xy 127.938276 -230.389176)
			(xy 127.953008 -230.407718) (xy 128.035304 -230.446326) (xy 128.059688 -230.44531) (xy 128.070356 -230.439214)
			(xy 128.094093 -230.426513) (xy 128.144823 -230.408507) (xy 128.197873 -230.39937) (xy 128.224788 -230.398828)
			(xy 128.249596 -230.399288) (xy 128.298602 -230.407048) (xy 128.345791 -230.422379) (xy 128.39 -230.444903)
			(xy 128.430141 -230.474066) (xy 128.465226 -230.50915) (xy 128.49439 -230.54929) (xy 128.516916 -230.593498)
			(xy 128.532249 -230.640686) (xy 128.540011 -230.689692) (xy 128.540011 -230.71455) (xy 128.848607 -230.71455)
			(xy 128.852702 -230.663822) (xy 128.864881 -230.614408) (xy 128.884829 -230.567588) (xy 128.91203 -230.524574)
			(xy 128.945778 -230.48648) (xy 128.9852 -230.454293) (xy 129.029274 -230.428847) (xy 129.07686 -230.4108)
			(xy 129.126724 -230.40062) (xy 129.177576 -230.398571) (xy 129.228097 -230.404705) (xy 129.276981 -230.418865)
			(xy 129.32296 -230.440682) (xy 129.364844 -230.469592) (xy 129.401548 -230.504847) (xy 129.432121 -230.545533)
			(xy 129.455772 -230.590596) (xy 129.471888 -230.63887) (xy 129.480052 -230.689104) (xy 129.480564 -230.71455)
			(xy 129.798838 -230.71455) (xy 129.802798 -230.665496) (xy 129.814575 -230.617712) (xy 129.833866 -230.572436)
			(xy 129.860169 -230.53084) (xy 129.892804 -230.494003) (xy 129.930925 -230.462878) (xy 129.973546 -230.438271)
			(xy 130.019562 -230.420819) (xy 130.067781 -230.410975) (xy 130.116956 -230.408994) (xy 130.165811 -230.414926)
			(xy 130.213082 -230.428618) (xy 130.257544 -230.449716) (xy 130.298047 -230.477672) (xy 130.33354 -230.511764)
			(xy 130.363105 -230.551108) (xy 130.385976 -230.594685) (xy 130.40156 -230.641366) (xy 130.409455 -230.689943)
			(xy 130.40995 -230.71455) (xy 130.728461 -230.71455) (xy 130.732556 -230.663822) (xy 130.744735 -230.614408)
			(xy 130.764683 -230.567588) (xy 130.791884 -230.524574) (xy 130.825632 -230.48648) (xy 130.865054 -230.454293)
			(xy 130.909128 -230.428847) (xy 130.956714 -230.4108) (xy 131.006578 -230.40062) (xy 131.05743 -230.398571)
			(xy 131.107951 -230.404705) (xy 131.156835 -230.418865) (xy 131.202814 -230.440682) (xy 131.244698 -230.469592)
			(xy 131.281402 -230.504847) (xy 131.311975 -230.545533) (xy 131.335626 -230.590596) (xy 131.351742 -230.63887)
			(xy 131.359906 -230.689104) (xy 131.360418 -230.71455) (xy 131.678946 -230.71455) (xy 131.682906 -230.665496)
			(xy 131.694683 -230.617712) (xy 131.713974 -230.572436) (xy 131.740277 -230.53084) (xy 131.772912 -230.494003)
			(xy 131.811033 -230.462878) (xy 131.853654 -230.438271) (xy 131.89967 -230.420819) (xy 131.947889 -230.410975)
			(xy 131.997064 -230.408994) (xy 132.045919 -230.414926) (xy 132.09319 -230.428618) (xy 132.137652 -230.449716)
			(xy 132.178155 -230.477672) (xy 132.213648 -230.511764) (xy 132.243213 -230.551108) (xy 132.266084 -230.594685)
			(xy 132.281668 -230.641366) (xy 132.289563 -230.689943) (xy 132.290058 -230.71455) (xy 132.608569 -230.71455)
			(xy 132.612664 -230.663822) (xy 132.624843 -230.614408) (xy 132.644791 -230.567588) (xy 132.671992 -230.524574)
			(xy 132.70574 -230.48648) (xy 132.745162 -230.454293) (xy 132.789236 -230.428847) (xy 132.836822 -230.4108)
			(xy 132.886686 -230.40062) (xy 132.937538 -230.398571) (xy 132.988059 -230.404705) (xy 133.036943 -230.418865)
			(xy 133.082922 -230.440682) (xy 133.124806 -230.469592) (xy 133.16151 -230.504847) (xy 133.192083 -230.545533)
			(xy 133.215734 -230.590596) (xy 133.23185 -230.63887) (xy 133.240014 -230.689104) (xy 133.240521 -230.714296)
			(xy 133.559054 -230.714296) (xy 133.563014 -230.665242) (xy 133.574791 -230.617458) (xy 133.594082 -230.572182)
			(xy 133.620385 -230.530586) (xy 133.65302 -230.493749) (xy 133.691141 -230.462624) (xy 133.733762 -230.438017)
			(xy 133.779778 -230.420565) (xy 133.827997 -230.410721) (xy 133.877172 -230.40874) (xy 133.926027 -230.414672)
			(xy 133.973298 -230.428364) (xy 134.01776 -230.449462) (xy 134.058263 -230.477418) (xy 134.093756 -230.51151)
			(xy 134.123321 -230.550854) (xy 134.146192 -230.594431) (xy 134.161776 -230.641112) (xy 134.169671 -230.689689)
			(xy 134.170166 -230.714296) (xy 134.170161 -230.71455) (xy 134.498854 -230.71455) (xy 134.502814 -230.665496)
			(xy 134.514591 -230.617712) (xy 134.533882 -230.572436) (xy 134.560185 -230.53084) (xy 134.59282 -230.494003)
			(xy 134.630941 -230.462878) (xy 134.673562 -230.438271) (xy 134.719578 -230.420819) (xy 134.767797 -230.410975)
			(xy 134.816972 -230.408994) (xy 134.865827 -230.414926) (xy 134.913098 -230.428618) (xy 134.95756 -230.449716)
			(xy 134.998063 -230.477672) (xy 135.033556 -230.511764) (xy 135.063121 -230.551108) (xy 135.085992 -230.594685)
			(xy 135.101576 -230.641366) (xy 135.109471 -230.689943) (xy 135.109966 -230.71455) (xy 135.438908 -230.71455)
			(xy 135.442868 -230.665496) (xy 135.454645 -230.617712) (xy 135.473936 -230.572436) (xy 135.500239 -230.53084)
			(xy 135.532874 -230.494003) (xy 135.570995 -230.462878) (xy 135.613616 -230.438271) (xy 135.659632 -230.420819)
			(xy 135.707851 -230.410975) (xy 135.757026 -230.408994) (xy 135.805881 -230.414926) (xy 135.853152 -230.428618)
			(xy 135.897614 -230.449716) (xy 135.938117 -230.477672) (xy 135.97361 -230.511764) (xy 136.003175 -230.551108)
			(xy 136.026046 -230.594685) (xy 136.04163 -230.641366) (xy 136.049525 -230.689943) (xy 136.05002 -230.71455)
			(xy 136.049525 -230.739157) (xy 136.04163 -230.787734) (xy 136.026046 -230.834415) (xy 136.003175 -230.877992)
			(xy 135.97361 -230.917336) (xy 135.938117 -230.951428) (xy 135.897614 -230.979384) (xy 135.853152 -231.000482)
			(xy 135.805881 -231.014174) (xy 135.757026 -231.020106) (xy 135.707851 -231.018125) (xy 135.659632 -231.008281)
			(xy 135.613616 -230.990829) (xy 135.570995 -230.966222) (xy 135.532874 -230.935097) (xy 135.500239 -230.89826)
			(xy 135.473936 -230.856664) (xy 135.454645 -230.811388) (xy 135.442868 -230.763604) (xy 135.438908 -230.71455)
			(xy 135.109966 -230.71455) (xy 135.109471 -230.739157) (xy 135.101576 -230.787734) (xy 135.085992 -230.834415)
			(xy 135.063121 -230.877992) (xy 135.033556 -230.917336) (xy 134.998063 -230.951428) (xy 134.95756 -230.979384)
			(xy 134.913098 -231.000482) (xy 134.865827 -231.014174) (xy 134.816972 -231.020106) (xy 134.767797 -231.018125)
			(xy 134.719578 -231.008281) (xy 134.673562 -230.990829) (xy 134.630941 -230.966222) (xy 134.59282 -230.935097)
			(xy 134.560185 -230.89826) (xy 134.533882 -230.856664) (xy 134.514591 -230.811388) (xy 134.502814 -230.763604)
			(xy 134.498854 -230.71455) (xy 134.170161 -230.71455) (xy 134.169671 -230.738903) (xy 134.161776 -230.78748)
			(xy 134.146192 -230.834161) (xy 134.123321 -230.877738) (xy 134.093756 -230.917082) (xy 134.058263 -230.951174)
			(xy 134.01776 -230.97913) (xy 133.973298 -231.000228) (xy 133.926027 -231.01392) (xy 133.877172 -231.019852)
			(xy 133.827997 -231.017871) (xy 133.779778 -231.008027) (xy 133.733762 -230.990575) (xy 133.691141 -230.965968)
			(xy 133.65302 -230.934843) (xy 133.620385 -230.898006) (xy 133.594082 -230.85641) (xy 133.574791 -230.811134)
			(xy 133.563014 -230.76335) (xy 133.559054 -230.714296) (xy 133.240521 -230.714296) (xy 133.240526 -230.71455)
			(xy 133.240014 -230.739996) (xy 133.23185 -230.79023) (xy 133.215734 -230.838504) (xy 133.192083 -230.883567)
			(xy 133.16151 -230.924253) (xy 133.124806 -230.959508) (xy 133.082922 -230.988418) (xy 133.036943 -231.010235)
			(xy 132.988059 -231.024395) (xy 132.937538 -231.030529) (xy 132.886686 -231.02848) (xy 132.836822 -231.0183)
			(xy 132.789236 -231.000253) (xy 132.745162 -230.974807) (xy 132.70574 -230.94262) (xy 132.671992 -230.904526)
			(xy 132.644791 -230.861512) (xy 132.624843 -230.814692) (xy 132.612664 -230.765278) (xy 132.608569 -230.71455)
			(xy 132.290058 -230.71455) (xy 132.289563 -230.739157) (xy 132.281668 -230.787734) (xy 132.266084 -230.834415)
			(xy 132.243213 -230.877992) (xy 132.213648 -230.917336) (xy 132.178155 -230.951428) (xy 132.137652 -230.979384)
			(xy 132.09319 -231.000482) (xy 132.045919 -231.014174) (xy 131.997064 -231.020106) (xy 131.947889 -231.018125)
			(xy 131.89967 -231.008281) (xy 131.853654 -230.990829) (xy 131.811033 -230.966222) (xy 131.772912 -230.935097)
			(xy 131.740277 -230.89826) (xy 131.713974 -230.856664) (xy 131.694683 -230.811388) (xy 131.682906 -230.763604)
			(xy 131.678946 -230.71455) (xy 131.360418 -230.71455) (xy 131.359906 -230.739996) (xy 131.351742 -230.79023)
			(xy 131.335626 -230.838504) (xy 131.311975 -230.883567) (xy 131.281402 -230.924253) (xy 131.244698 -230.959508)
			(xy 131.202814 -230.988418) (xy 131.156835 -231.010235) (xy 131.107951 -231.024395) (xy 131.05743 -231.030529)
			(xy 131.006578 -231.02848) (xy 130.956714 -231.0183) (xy 130.909128 -231.000253) (xy 130.865054 -230.974807)
			(xy 130.825632 -230.94262) (xy 130.791884 -230.904526) (xy 130.764683 -230.861512) (xy 130.744735 -230.814692)
			(xy 130.732556 -230.765278) (xy 130.728461 -230.71455) (xy 130.40995 -230.71455) (xy 130.409455 -230.739157)
			(xy 130.40156 -230.787734) (xy 130.385976 -230.834415) (xy 130.363105 -230.877992) (xy 130.33354 -230.917336)
			(xy 130.298047 -230.951428) (xy 130.257544 -230.979384) (xy 130.213082 -231.000482) (xy 130.165811 -231.014174)
			(xy 130.116956 -231.020106) (xy 130.067781 -231.018125) (xy 130.019562 -231.008281) (xy 129.973546 -230.990829)
			(xy 129.930925 -230.966222) (xy 129.892804 -230.935097) (xy 129.860169 -230.89826) (xy 129.833866 -230.856664)
			(xy 129.814575 -230.811388) (xy 129.802798 -230.763604) (xy 129.798838 -230.71455) (xy 129.480564 -230.71455)
			(xy 129.480052 -230.739996) (xy 129.471888 -230.79023) (xy 129.455772 -230.838504) (xy 129.432121 -230.883567)
			(xy 129.401548 -230.924253) (xy 129.364844 -230.959508) (xy 129.32296 -230.988418) (xy 129.276981 -231.010235)
			(xy 129.228097 -231.024395) (xy 129.177576 -231.030529) (xy 129.126724 -231.02848) (xy 129.07686 -231.0183)
			(xy 129.029274 -231.000253) (xy 128.9852 -230.974807) (xy 128.945778 -230.94262) (xy 128.91203 -230.904526)
			(xy 128.884829 -230.861512) (xy 128.864881 -230.814692) (xy 128.852702 -230.765278) (xy 128.848607 -230.71455)
			(xy 128.540011 -230.71455) (xy 128.540011 -230.739308) (xy 128.532249 -230.788314) (xy 128.516916 -230.835502)
			(xy 128.49439 -230.87971) (xy 128.465226 -230.91985) (xy 128.430141 -230.954934) (xy 128.39 -230.984097)
			(xy 128.345791 -231.006621) (xy 128.298602 -231.021952) (xy 128.249596 -231.029712) (xy 128.224788 -231.030272)
			(xy 128.212995 -231.030154) (xy 128.189475 -231.028376) (xy 128.177798 -231.026716) (xy 128.17729 -231.02697)
			(xy 128.171736 -231.029502) (xy 128.161975 -231.036827) (xy 128.157986 -231.041448) (xy 128.09728 -231.116124)
			(xy 128.092454 -231.140254) (xy 128.09601 -231.152446) (xy 128.10765 -231.193862) (xy 128.126209 -231.277874)
			(xy 128.133094 -231.32034) (xy 128.140365 -231.370825) (xy 128.148122 -231.472536) (xy 128.148588 -231.52354)
			(xy 128.148588 -231.524302) (xy 128.388884 -231.524302) (xy 128.392844 -231.475248) (xy 128.404621 -231.427464)
			(xy 128.423912 -231.382188) (xy 128.450215 -231.340592) (xy 128.48285 -231.303755) (xy 128.520971 -231.27263)
			(xy 128.563592 -231.248023) (xy 128.609608 -231.230571) (xy 128.657827 -231.220727) (xy 128.707002 -231.218746)
			(xy 128.755857 -231.224678) (xy 128.803128 -231.23837) (xy 128.84759 -231.259468) (xy 128.888093 -231.287424)
			(xy 128.923586 -231.321516) (xy 128.953151 -231.36086) (xy 128.976022 -231.404437) (xy 128.991606 -231.451118)
			(xy 128.999501 -231.499695) (xy 128.999996 -231.524302) (xy 129.318507 -231.524302) (xy 129.322602 -231.473574)
			(xy 129.334781 -231.42416) (xy 129.354729 -231.37734) (xy 129.38193 -231.334326) (xy 129.415678 -231.296232)
			(xy 129.4551 -231.264045) (xy 129.499174 -231.238599) (xy 129.54676 -231.220552) (xy 129.596624 -231.210372)
			(xy 129.647476 -231.208323) (xy 129.697997 -231.214457) (xy 129.746881 -231.228617) (xy 129.79286 -231.250434)
			(xy 129.834744 -231.279344) (xy 129.871448 -231.314599) (xy 129.902021 -231.355285) (xy 129.925672 -231.400348)
			(xy 129.941788 -231.448622) (xy 129.949952 -231.498856) (xy 129.950464 -231.524302) (xy 130.268992 -231.524302)
			(xy 130.272952 -231.475248) (xy 130.284729 -231.427464) (xy 130.30402 -231.382188) (xy 130.330323 -231.340592)
			(xy 130.362958 -231.303755) (xy 130.401079 -231.27263) (xy 130.4437 -231.248023) (xy 130.489716 -231.230571)
			(xy 130.537935 -231.220727) (xy 130.58711 -231.218746) (xy 130.635965 -231.224678) (xy 130.683236 -231.23837)
			(xy 130.727698 -231.259468) (xy 130.768201 -231.287424) (xy 130.803694 -231.321516) (xy 130.833259 -231.36086)
			(xy 130.85613 -231.404437) (xy 130.871714 -231.451118) (xy 130.879609 -231.499695) (xy 130.880104 -231.524302)
			(xy 131.198615 -231.524302) (xy 131.20271 -231.473574) (xy 131.214889 -231.42416) (xy 131.234837 -231.37734)
			(xy 131.262038 -231.334326) (xy 131.295786 -231.296232) (xy 131.335208 -231.264045) (xy 131.379282 -231.238599)
			(xy 131.426868 -231.220552) (xy 131.476732 -231.210372) (xy 131.527584 -231.208323) (xy 131.578105 -231.214457)
			(xy 131.626989 -231.228617) (xy 131.672968 -231.250434) (xy 131.714852 -231.279344) (xy 131.751556 -231.314599)
			(xy 131.782129 -231.355285) (xy 131.80578 -231.400348) (xy 131.821896 -231.448622) (xy 131.83006 -231.498856)
			(xy 131.830572 -231.524302) (xy 132.138415 -231.524302) (xy 132.14251 -231.473574) (xy 132.154689 -231.42416)
			(xy 132.174637 -231.37734) (xy 132.201838 -231.334326) (xy 132.235586 -231.296232) (xy 132.275008 -231.264045)
			(xy 132.319082 -231.238599) (xy 132.366668 -231.220552) (xy 132.416532 -231.210372) (xy 132.467384 -231.208323)
			(xy 132.517905 -231.214457) (xy 132.566789 -231.228617) (xy 132.612768 -231.250434) (xy 132.654652 -231.279344)
			(xy 132.691356 -231.314599) (xy 132.721929 -231.355285) (xy 132.74558 -231.400348) (xy 132.761696 -231.448622)
			(xy 132.76986 -231.498856) (xy 132.770372 -231.524302) (xy 133.0889 -231.524302) (xy 133.09286 -231.475248)
			(xy 133.104637 -231.427464) (xy 133.123928 -231.382188) (xy 133.150231 -231.340592) (xy 133.182866 -231.303755)
			(xy 133.220987 -231.27263) (xy 133.263608 -231.248023) (xy 133.309624 -231.230571) (xy 133.357843 -231.220727)
			(xy 133.407018 -231.218746) (xy 133.455873 -231.224678) (xy 133.503144 -231.23837) (xy 133.547606 -231.259468)
			(xy 133.588109 -231.287424) (xy 133.623602 -231.321516) (xy 133.653167 -231.36086) (xy 133.676038 -231.404437)
			(xy 133.691622 -231.451118) (xy 133.699517 -231.499695) (xy 133.700012 -231.524302) (xy 134.028954 -231.524302)
			(xy 134.032914 -231.475248) (xy 134.044691 -231.427464) (xy 134.063982 -231.382188) (xy 134.090285 -231.340592)
			(xy 134.12292 -231.303755) (xy 134.161041 -231.27263) (xy 134.203662 -231.248023) (xy 134.249678 -231.230571)
			(xy 134.297897 -231.220727) (xy 134.347072 -231.218746) (xy 134.395927 -231.224678) (xy 134.443198 -231.23837)
			(xy 134.48766 -231.259468) (xy 134.528163 -231.287424) (xy 134.563656 -231.321516) (xy 134.593221 -231.36086)
			(xy 134.616092 -231.404437) (xy 134.631676 -231.451118) (xy 134.639571 -231.499695) (xy 134.640066 -231.524302)
			(xy 134.969008 -231.524302) (xy 134.972968 -231.475248) (xy 134.984745 -231.427464) (xy 135.004036 -231.382188)
			(xy 135.030339 -231.340592) (xy 135.062974 -231.303755) (xy 135.101095 -231.27263) (xy 135.143716 -231.248023)
			(xy 135.189732 -231.230571) (xy 135.237951 -231.220727) (xy 135.287126 -231.218746) (xy 135.335981 -231.224678)
			(xy 135.383252 -231.23837) (xy 135.427714 -231.259468) (xy 135.468217 -231.287424) (xy 135.50371 -231.321516)
			(xy 135.533275 -231.36086) (xy 135.556146 -231.404437) (xy 135.57173 -231.451118) (xy 135.579625 -231.499695)
			(xy 135.58012 -231.524302) (xy 135.909062 -231.524302) (xy 135.913022 -231.475248) (xy 135.924799 -231.427464)
			(xy 135.94409 -231.382188) (xy 135.970393 -231.340592) (xy 136.003028 -231.303755) (xy 136.041149 -231.27263)
			(xy 136.08377 -231.248023) (xy 136.129786 -231.230571) (xy 136.178005 -231.220727) (xy 136.22718 -231.218746)
			(xy 136.276035 -231.224678) (xy 136.323306 -231.23837) (xy 136.367768 -231.259468) (xy 136.408271 -231.287424)
			(xy 136.443764 -231.321516) (xy 136.473329 -231.36086) (xy 136.4962 -231.404437) (xy 136.511784 -231.451118)
			(xy 136.519679 -231.499695) (xy 136.520174 -231.524302) (xy 136.519679 -231.548909) (xy 136.511784 -231.597486)
			(xy 136.4962 -231.644167) (xy 136.473329 -231.687744) (xy 136.443764 -231.727088) (xy 136.408271 -231.76118)
			(xy 136.367768 -231.789136) (xy 136.323306 -231.810234) (xy 136.276035 -231.823926) (xy 136.22718 -231.829858)
			(xy 136.178005 -231.827877) (xy 136.129786 -231.818033) (xy 136.08377 -231.800581) (xy 136.041149 -231.775974)
			(xy 136.003028 -231.744849) (xy 135.970393 -231.708012) (xy 135.94409 -231.666416) (xy 135.924799 -231.62114)
			(xy 135.913022 -231.573356) (xy 135.909062 -231.524302) (xy 135.58012 -231.524302) (xy 135.579625 -231.548909)
			(xy 135.57173 -231.597486) (xy 135.556146 -231.644167) (xy 135.533275 -231.687744) (xy 135.50371 -231.727088)
			(xy 135.468217 -231.76118) (xy 135.427714 -231.789136) (xy 135.383252 -231.810234) (xy 135.335981 -231.823926)
			(xy 135.287126 -231.829858) (xy 135.237951 -231.827877) (xy 135.189732 -231.818033) (xy 135.143716 -231.800581)
			(xy 135.101095 -231.775974) (xy 135.062974 -231.744849) (xy 135.030339 -231.708012) (xy 135.004036 -231.666416)
			(xy 134.984745 -231.62114) (xy 134.972968 -231.573356) (xy 134.969008 -231.524302) (xy 134.640066 -231.524302)
			(xy 134.639571 -231.548909) (xy 134.631676 -231.597486) (xy 134.616092 -231.644167) (xy 134.593221 -231.687744)
			(xy 134.563656 -231.727088) (xy 134.528163 -231.76118) (xy 134.48766 -231.789136) (xy 134.443198 -231.810234)
			(xy 134.395927 -231.823926) (xy 134.347072 -231.829858) (xy 134.297897 -231.827877) (xy 134.249678 -231.818033)
			(xy 134.203662 -231.800581) (xy 134.161041 -231.775974) (xy 134.12292 -231.744849) (xy 134.090285 -231.708012)
			(xy 134.063982 -231.666416) (xy 134.044691 -231.62114) (xy 134.032914 -231.573356) (xy 134.028954 -231.524302)
			(xy 133.700012 -231.524302) (xy 133.699517 -231.548909) (xy 133.691622 -231.597486) (xy 133.676038 -231.644167)
			(xy 133.653167 -231.687744) (xy 133.623602 -231.727088) (xy 133.588109 -231.76118) (xy 133.547606 -231.789136)
			(xy 133.503144 -231.810234) (xy 133.455873 -231.823926) (xy 133.407018 -231.829858) (xy 133.357843 -231.827877)
			(xy 133.309624 -231.818033) (xy 133.263608 -231.800581) (xy 133.220987 -231.775974) (xy 133.182866 -231.744849)
			(xy 133.150231 -231.708012) (xy 133.123928 -231.666416) (xy 133.104637 -231.62114) (xy 133.09286 -231.573356)
			(xy 133.0889 -231.524302) (xy 132.770372 -231.524302) (xy 132.76986 -231.549748) (xy 132.761696 -231.599982)
			(xy 132.74558 -231.648256) (xy 132.721929 -231.693319) (xy 132.691356 -231.734005) (xy 132.654652 -231.76926)
			(xy 132.612768 -231.79817) (xy 132.566789 -231.819987) (xy 132.517905 -231.834147) (xy 132.467384 -231.840281)
			(xy 132.416532 -231.838232) (xy 132.366668 -231.828052) (xy 132.319082 -231.810005) (xy 132.275008 -231.784559)
			(xy 132.235586 -231.752372) (xy 132.201838 -231.714278) (xy 132.174637 -231.671264) (xy 132.154689 -231.624444)
			(xy 132.14251 -231.57503) (xy 132.138415 -231.524302) (xy 131.830572 -231.524302) (xy 131.83006 -231.549748)
			(xy 131.821896 -231.599982) (xy 131.80578 -231.648256) (xy 131.782129 -231.693319) (xy 131.751556 -231.734005)
			(xy 131.714852 -231.76926) (xy 131.672968 -231.79817) (xy 131.626989 -231.819987) (xy 131.578105 -231.834147)
			(xy 131.527584 -231.840281) (xy 131.476732 -231.838232) (xy 131.426868 -231.828052) (xy 131.379282 -231.810005)
			(xy 131.335208 -231.784559) (xy 131.295786 -231.752372) (xy 131.262038 -231.714278) (xy 131.234837 -231.671264)
			(xy 131.214889 -231.624444) (xy 131.20271 -231.57503) (xy 131.198615 -231.524302) (xy 130.880104 -231.524302)
			(xy 130.879609 -231.548909) (xy 130.871714 -231.597486) (xy 130.85613 -231.644167) (xy 130.833259 -231.687744)
			(xy 130.803694 -231.727088) (xy 130.768201 -231.76118) (xy 130.727698 -231.789136) (xy 130.683236 -231.810234)
			(xy 130.635965 -231.823926) (xy 130.58711 -231.829858) (xy 130.537935 -231.827877) (xy 130.489716 -231.818033)
			(xy 130.4437 -231.800581) (xy 130.401079 -231.775974) (xy 130.362958 -231.744849) (xy 130.330323 -231.708012)
			(xy 130.30402 -231.666416) (xy 130.284729 -231.62114) (xy 130.272952 -231.573356) (xy 130.268992 -231.524302)
			(xy 129.950464 -231.524302) (xy 129.949952 -231.549748) (xy 129.941788 -231.599982) (xy 129.925672 -231.648256)
			(xy 129.902021 -231.693319) (xy 129.871448 -231.734005) (xy 129.834744 -231.76926) (xy 129.79286 -231.79817)
			(xy 129.746881 -231.819987) (xy 129.697997 -231.834147) (xy 129.647476 -231.840281) (xy 129.596624 -231.838232)
			(xy 129.54676 -231.828052) (xy 129.499174 -231.810005) (xy 129.4551 -231.784559) (xy 129.415678 -231.752372)
			(xy 129.38193 -231.714278) (xy 129.354729 -231.671264) (xy 129.334781 -231.624444) (xy 129.322602 -231.57503)
			(xy 129.318507 -231.524302) (xy 128.999996 -231.524302) (xy 128.999501 -231.548909) (xy 128.991606 -231.597486)
			(xy 128.976022 -231.644167) (xy 128.953151 -231.687744) (xy 128.923586 -231.727088) (xy 128.888093 -231.76118)
			(xy 128.84759 -231.789136) (xy 128.803128 -231.810234) (xy 128.755857 -231.823926) (xy 128.707002 -231.829858)
			(xy 128.657827 -231.827877) (xy 128.609608 -231.818033) (xy 128.563592 -231.800581) (xy 128.520971 -231.775974)
			(xy 128.48285 -231.744849) (xy 128.450215 -231.708012) (xy 128.423912 -231.666416) (xy 128.404621 -231.62114)
			(xy 128.392844 -231.573356) (xy 128.388884 -231.524302) (xy 128.148588 -231.524302) (xy 128.148588 -231.524556)
			(xy 128.14806 -231.578343) (xy 128.139392 -231.685567) (xy 128.122109 -231.791743) (xy 128.109726 -231.844088)
			(xy 128.095756 -231.896412) (xy 128.0922 -231.908604) (xy 128.097026 -231.932988) (xy 128.15824 -232.007664)
			(xy 128.162167 -232.01214) (xy 128.171664 -232.019318) (xy 128.177036 -232.021888) (xy 128.177798 -232.022142)
			(xy 128.18948 -232.020553) (xy 128.212999 -232.018901) (xy 128.224788 -232.01884) (xy 128.24958 -232.0193)
			(xy 128.298552 -232.027055) (xy 128.345709 -232.042376) (xy 128.389889 -232.064885) (xy 128.430003 -232.094028)
			(xy 128.465064 -232.129088) (xy 128.494209 -232.169201) (xy 128.51672 -232.21338) (xy 128.532042 -232.260536)
			(xy 128.539799 -232.309508) (xy 128.539799 -232.334308) (xy 128.848607 -232.334308) (xy 128.852702 -232.28358)
			(xy 128.864881 -232.234166) (xy 128.884829 -232.187346) (xy 128.91203 -232.144332) (xy 128.945778 -232.106238)
			(xy 128.9852 -232.074051) (xy 129.029274 -232.048605) (xy 129.07686 -232.030558) (xy 129.126724 -232.020378)
			(xy 129.177576 -232.018329) (xy 129.228097 -232.024463) (xy 129.276981 -232.038623) (xy 129.32296 -232.06044)
			(xy 129.364844 -232.08935) (xy 129.401548 -232.124605) (xy 129.432121 -232.165291) (xy 129.455772 -232.210354)
			(xy 129.471888 -232.258628) (xy 129.480052 -232.308862) (xy 129.480564 -232.334308) (xy 130.728461 -232.334308)
			(xy 130.732556 -232.28358) (xy 130.744735 -232.234166) (xy 130.764683 -232.187346) (xy 130.791884 -232.144332)
			(xy 130.825632 -232.106238) (xy 130.865054 -232.074051) (xy 130.909128 -232.048605) (xy 130.956714 -232.030558)
			(xy 131.006578 -232.020378) (xy 131.05743 -232.018329) (xy 131.107951 -232.024463) (xy 131.156835 -232.038623)
			(xy 131.202814 -232.06044) (xy 131.244698 -232.08935) (xy 131.281402 -232.124605) (xy 131.311975 -232.165291)
			(xy 131.335626 -232.210354) (xy 131.351742 -232.258628) (xy 131.359906 -232.308862) (xy 131.360418 -232.334308)
			(xy 131.678946 -232.334308) (xy 131.682906 -232.285254) (xy 131.694683 -232.23747) (xy 131.713974 -232.192194)
			(xy 131.740277 -232.150598) (xy 131.772912 -232.113761) (xy 131.811033 -232.082636) (xy 131.853654 -232.058029)
			(xy 131.89967 -232.040577) (xy 131.947889 -232.030733) (xy 131.997064 -232.028752) (xy 132.045919 -232.034684)
			(xy 132.09319 -232.048376) (xy 132.137652 -232.069474) (xy 132.178155 -232.09743) (xy 132.213648 -232.131522)
			(xy 132.243213 -232.170866) (xy 132.266084 -232.214443) (xy 132.281668 -232.261124) (xy 132.289563 -232.309701)
			(xy 132.290058 -232.334308) (xy 132.608569 -232.334308) (xy 132.612664 -232.28358) (xy 132.624843 -232.234166)
			(xy 132.644791 -232.187346) (xy 132.671992 -232.144332) (xy 132.70574 -232.106238) (xy 132.745162 -232.074051)
			(xy 132.789236 -232.048605) (xy 132.836822 -232.030558) (xy 132.886686 -232.020378) (xy 132.937538 -232.018329)
			(xy 132.988059 -232.024463) (xy 133.036943 -232.038623) (xy 133.082922 -232.06044) (xy 133.124806 -232.08935)
			(xy 133.16151 -232.124605) (xy 133.192083 -232.165291) (xy 133.215734 -232.210354) (xy 133.23185 -232.258628)
			(xy 133.240014 -232.308862) (xy 133.240526 -232.334308) (xy 133.559054 -232.334308) (xy 133.563014 -232.285254)
			(xy 133.574791 -232.23747) (xy 133.594082 -232.192194) (xy 133.620385 -232.150598) (xy 133.65302 -232.113761)
			(xy 133.691141 -232.082636) (xy 133.733762 -232.058029) (xy 133.779778 -232.040577) (xy 133.827997 -232.030733)
			(xy 133.877172 -232.028752) (xy 133.926027 -232.034684) (xy 133.973298 -232.048376) (xy 134.01776 -232.069474)
			(xy 134.058263 -232.09743) (xy 134.093756 -232.131522) (xy 134.123321 -232.170866) (xy 134.146192 -232.214443)
			(xy 134.161776 -232.261124) (xy 134.169671 -232.309701) (xy 134.170166 -232.334308) (xy 134.498854 -232.334308)
			(xy 134.502814 -232.285254) (xy 134.514591 -232.23747) (xy 134.533882 -232.192194) (xy 134.560185 -232.150598)
			(xy 134.59282 -232.113761) (xy 134.630941 -232.082636) (xy 134.673562 -232.058029) (xy 134.719578 -232.040577)
			(xy 134.767797 -232.030733) (xy 134.816972 -232.028752) (xy 134.865827 -232.034684) (xy 134.913098 -232.048376)
			(xy 134.95756 -232.069474) (xy 134.998063 -232.09743) (xy 135.033556 -232.131522) (xy 135.063121 -232.170866)
			(xy 135.085992 -232.214443) (xy 135.101576 -232.261124) (xy 135.109471 -232.309701) (xy 135.109966 -232.334308)
			(xy 135.438908 -232.334308) (xy 135.442868 -232.285254) (xy 135.454645 -232.23747) (xy 135.473936 -232.192194)
			(xy 135.500239 -232.150598) (xy 135.532874 -232.113761) (xy 135.570995 -232.082636) (xy 135.613616 -232.058029)
			(xy 135.659632 -232.040577) (xy 135.707851 -232.030733) (xy 135.757026 -232.028752) (xy 135.805881 -232.034684)
			(xy 135.853152 -232.048376) (xy 135.897614 -232.069474) (xy 135.938117 -232.09743) (xy 135.97361 -232.131522)
			(xy 136.003175 -232.170866) (xy 136.026046 -232.214443) (xy 136.04163 -232.261124) (xy 136.049525 -232.309701)
			(xy 136.05002 -232.334308) (xy 136.049525 -232.358915) (xy 136.04163 -232.407492) (xy 136.026046 -232.454173)
			(xy 136.003175 -232.49775) (xy 135.97361 -232.537094) (xy 135.938117 -232.571186) (xy 135.897614 -232.599142)
			(xy 135.853152 -232.62024) (xy 135.805881 -232.633932) (xy 135.757026 -232.639864) (xy 135.707851 -232.637883)
			(xy 135.659632 -232.628039) (xy 135.613616 -232.610587) (xy 135.570995 -232.58598) (xy 135.532874 -232.554855)
			(xy 135.500239 -232.518018) (xy 135.473936 -232.476422) (xy 135.454645 -232.431146) (xy 135.442868 -232.383362)
			(xy 135.438908 -232.334308) (xy 135.109966 -232.334308) (xy 135.109471 -232.358915) (xy 135.101576 -232.407492)
			(xy 135.085992 -232.454173) (xy 135.063121 -232.49775) (xy 135.033556 -232.537094) (xy 134.998063 -232.571186)
			(xy 134.95756 -232.599142) (xy 134.913098 -232.62024) (xy 134.865827 -232.633932) (xy 134.816972 -232.639864)
			(xy 134.767797 -232.637883) (xy 134.719578 -232.628039) (xy 134.673562 -232.610587) (xy 134.630941 -232.58598)
			(xy 134.59282 -232.554855) (xy 134.560185 -232.518018) (xy 134.533882 -232.476422) (xy 134.514591 -232.431146)
			(xy 134.502814 -232.383362) (xy 134.498854 -232.334308) (xy 134.170166 -232.334308) (xy 134.169671 -232.358915)
			(xy 134.161776 -232.407492) (xy 134.146192 -232.454173) (xy 134.123321 -232.49775) (xy 134.093756 -232.537094)
			(xy 134.058263 -232.571186) (xy 134.01776 -232.599142) (xy 133.973298 -232.62024) (xy 133.926027 -232.633932)
			(xy 133.877172 -232.639864) (xy 133.827997 -232.637883) (xy 133.779778 -232.628039) (xy 133.733762 -232.610587)
			(xy 133.691141 -232.58598) (xy 133.65302 -232.554855) (xy 133.620385 -232.518018) (xy 133.594082 -232.476422)
			(xy 133.574791 -232.431146) (xy 133.563014 -232.383362) (xy 133.559054 -232.334308) (xy 133.240526 -232.334308)
			(xy 133.240014 -232.359754) (xy 133.23185 -232.409988) (xy 133.215734 -232.458262) (xy 133.192083 -232.503325)
			(xy 133.16151 -232.544011) (xy 133.124806 -232.579266) (xy 133.082922 -232.608176) (xy 133.036943 -232.629993)
			(xy 132.988059 -232.644153) (xy 132.937538 -232.650287) (xy 132.886686 -232.648238) (xy 132.836822 -232.638058)
			(xy 132.789236 -232.620011) (xy 132.745162 -232.594565) (xy 132.70574 -232.562378) (xy 132.671992 -232.524284)
			(xy 132.644791 -232.48127) (xy 132.624843 -232.43445) (xy 132.612664 -232.385036) (xy 132.608569 -232.334308)
			(xy 132.290058 -232.334308) (xy 132.289563 -232.358915) (xy 132.281668 -232.407492) (xy 132.266084 -232.454173)
			(xy 132.243213 -232.49775) (xy 132.213648 -232.537094) (xy 132.178155 -232.571186) (xy 132.137652 -232.599142)
			(xy 132.09319 -232.62024) (xy 132.045919 -232.633932) (xy 131.997064 -232.639864) (xy 131.947889 -232.637883)
			(xy 131.89967 -232.628039) (xy 131.853654 -232.610587) (xy 131.811033 -232.58598) (xy 131.772912 -232.554855)
			(xy 131.740277 -232.518018) (xy 131.713974 -232.476422) (xy 131.694683 -232.431146) (xy 131.682906 -232.383362)
			(xy 131.678946 -232.334308) (xy 131.360418 -232.334308) (xy 131.359906 -232.359754) (xy 131.351742 -232.409988)
			(xy 131.335626 -232.458262) (xy 131.311975 -232.503325) (xy 131.281402 -232.544011) (xy 131.244698 -232.579266)
			(xy 131.202814 -232.608176) (xy 131.156835 -232.629993) (xy 131.107951 -232.644153) (xy 131.05743 -232.650287)
			(xy 131.006578 -232.648238) (xy 130.956714 -232.638058) (xy 130.909128 -232.620011) (xy 130.865054 -232.594565)
			(xy 130.825632 -232.562378) (xy 130.791884 -232.524284) (xy 130.764683 -232.48127) (xy 130.744735 -232.43445)
			(xy 130.732556 -232.385036) (xy 130.728461 -232.334308) (xy 129.480564 -232.334308) (xy 129.480052 -232.359754)
			(xy 129.471888 -232.409988) (xy 129.455772 -232.458262) (xy 129.432121 -232.503325) (xy 129.401548 -232.544011)
			(xy 129.364844 -232.579266) (xy 129.32296 -232.608176) (xy 129.276981 -232.629993) (xy 129.228097 -232.644153)
			(xy 129.177576 -232.650287) (xy 129.126724 -232.648238) (xy 129.07686 -232.638058) (xy 129.029274 -232.620011)
			(xy 128.9852 -232.594565) (xy 128.945778 -232.562378) (xy 128.91203 -232.524284) (xy 128.884829 -232.48127)
			(xy 128.864881 -232.43445) (xy 128.852702 -232.385036) (xy 128.848607 -232.334308) (xy 128.539799 -232.334308)
			(xy 128.539799 -232.359092) (xy 128.532042 -232.408064) (xy 128.51672 -232.45522) (xy 128.494209 -232.499399)
			(xy 128.465064 -232.539512) (xy 128.430003 -232.574572) (xy 128.389889 -232.603715) (xy 128.345709 -232.626224)
			(xy 128.298552 -232.641545) (xy 128.24958 -232.6493) (xy 128.224788 -232.649776) (xy 128.197882 -232.649279)
			(xy 128.144836 -232.640236) (xy 128.094099 -232.622312) (xy 128.070356 -232.609644) (xy 128.059688 -232.603548)
			(xy 128.035304 -232.602532) (xy 127.96393 -232.635806) (xy 127.953533 -232.641355) (xy 127.938833 -232.659743)
			(xy 127.935736 -232.671112) (xy 127.935736 -232.67162) (xy 127.927752 -232.708311) (xy 127.908821 -232.780984)
			(xy 127.89789 -232.816908) (xy 127.895063 -232.827822) (xy 127.898111 -232.850132) (xy 127.910414 -232.86899)
			(xy 127.919734 -232.875328) (xy 127.942353 -232.889824) (xy 127.982742 -232.925246) (xy 128.016548 -232.966996)
			(xy 128.042796 -233.013868) (xy 128.060727 -233.064508) (xy 128.069822 -233.117454) (xy 128.070356 -233.144314)
			(xy 128.388884 -233.144314) (xy 128.392844 -233.09526) (xy 128.404621 -233.047476) (xy 128.423912 -233.0022)
			(xy 128.450215 -232.960604) (xy 128.48285 -232.923767) (xy 128.520971 -232.892642) (xy 128.563592 -232.868035)
			(xy 128.609608 -232.850583) (xy 128.657827 -232.840739) (xy 128.707002 -232.838758) (xy 128.755857 -232.84469)
			(xy 128.803128 -232.858382) (xy 128.84759 -232.87948) (xy 128.888093 -232.907436) (xy 128.923586 -232.941528)
			(xy 128.953151 -232.980872) (xy 128.976022 -233.024449) (xy 128.991606 -233.07113) (xy 128.999501 -233.119707)
			(xy 128.999996 -233.144314) (xy 129.318507 -233.144314) (xy 129.322602 -233.093586) (xy 129.334781 -233.044172)
			(xy 129.354729 -232.997352) (xy 129.38193 -232.954338) (xy 129.415678 -232.916244) (xy 129.4551 -232.884057)
			(xy 129.499174 -232.858611) (xy 129.54676 -232.840564) (xy 129.596624 -232.830384) (xy 129.647476 -232.828335)
			(xy 129.697997 -232.834469) (xy 129.746881 -232.848629) (xy 129.79286 -232.870446) (xy 129.834744 -232.899356)
			(xy 129.871448 -232.934611) (xy 129.902021 -232.975297) (xy 129.925672 -233.02036) (xy 129.941788 -233.068634)
			(xy 129.949952 -233.118868) (xy 129.950464 -233.144314) (xy 130.268992 -233.144314) (xy 130.272952 -233.09526)
			(xy 130.284729 -233.047476) (xy 130.30402 -233.0022) (xy 130.330323 -232.960604) (xy 130.362958 -232.923767)
			(xy 130.401079 -232.892642) (xy 130.4437 -232.868035) (xy 130.489716 -232.850583) (xy 130.537935 -232.840739)
			(xy 130.58711 -232.838758) (xy 130.635965 -232.84469) (xy 130.683236 -232.858382) (xy 130.727698 -232.87948)
			(xy 130.768201 -232.907436) (xy 130.803694 -232.941528) (xy 130.833259 -232.980872) (xy 130.85613 -233.024449)
			(xy 130.871714 -233.07113) (xy 130.879609 -233.119707) (xy 130.880104 -233.144314) (xy 131.198615 -233.144314)
			(xy 131.20271 -233.093586) (xy 131.214889 -233.044172) (xy 131.234837 -232.997352) (xy 131.262038 -232.954338)
			(xy 131.295786 -232.916244) (xy 131.335208 -232.884057) (xy 131.379282 -232.858611) (xy 131.426868 -232.840564)
			(xy 131.476732 -232.830384) (xy 131.527584 -232.828335) (xy 131.578105 -232.834469) (xy 131.626989 -232.848629)
			(xy 131.672968 -232.870446) (xy 131.714852 -232.899356) (xy 131.751556 -232.934611) (xy 131.782129 -232.975297)
			(xy 131.80578 -233.02036) (xy 131.821896 -233.068634) (xy 131.83006 -233.118868) (xy 131.830572 -233.144314)
			(xy 132.138415 -233.144314) (xy 132.14251 -233.093586) (xy 132.154689 -233.044172) (xy 132.174637 -232.997352)
			(xy 132.201838 -232.954338) (xy 132.235586 -232.916244) (xy 132.275008 -232.884057) (xy 132.319082 -232.858611)
			(xy 132.366668 -232.840564) (xy 132.416532 -232.830384) (xy 132.467384 -232.828335) (xy 132.517905 -232.834469)
			(xy 132.566789 -232.848629) (xy 132.612768 -232.870446) (xy 132.654652 -232.899356) (xy 132.691356 -232.934611)
			(xy 132.721929 -232.975297) (xy 132.74558 -233.02036) (xy 132.761696 -233.068634) (xy 132.76986 -233.118868)
			(xy 132.770372 -233.144314) (xy 133.0889 -233.144314) (xy 133.09286 -233.09526) (xy 133.104637 -233.047476)
			(xy 133.123928 -233.0022) (xy 133.150231 -232.960604) (xy 133.182866 -232.923767) (xy 133.220987 -232.892642)
			(xy 133.263608 -232.868035) (xy 133.309624 -232.850583) (xy 133.357843 -232.840739) (xy 133.407018 -232.838758)
			(xy 133.455873 -232.84469) (xy 133.503144 -232.858382) (xy 133.547606 -232.87948) (xy 133.588109 -232.907436)
			(xy 133.623602 -232.941528) (xy 133.653167 -232.980872) (xy 133.676038 -233.024449) (xy 133.691622 -233.07113)
			(xy 133.699517 -233.119707) (xy 133.700012 -233.144314) (xy 134.028954 -233.144314) (xy 134.032914 -233.09526)
			(xy 134.044691 -233.047476) (xy 134.063982 -233.0022) (xy 134.090285 -232.960604) (xy 134.12292 -232.923767)
			(xy 134.161041 -232.892642) (xy 134.203662 -232.868035) (xy 134.249678 -232.850583) (xy 134.297897 -232.840739)
			(xy 134.347072 -232.838758) (xy 134.395927 -232.84469) (xy 134.443198 -232.858382) (xy 134.48766 -232.87948)
			(xy 134.528163 -232.907436) (xy 134.563656 -232.941528) (xy 134.593221 -232.980872) (xy 134.616092 -233.024449)
			(xy 134.631676 -233.07113) (xy 134.639571 -233.119707) (xy 134.640066 -233.144314) (xy 134.969008 -233.144314)
			(xy 134.972968 -233.09526) (xy 134.984745 -233.047476) (xy 135.004036 -233.0022) (xy 135.030339 -232.960604)
			(xy 135.062974 -232.923767) (xy 135.101095 -232.892642) (xy 135.143716 -232.868035) (xy 135.189732 -232.850583)
			(xy 135.237951 -232.840739) (xy 135.287126 -232.838758) (xy 135.335981 -232.84469) (xy 135.383252 -232.858382)
			(xy 135.427714 -232.87948) (xy 135.468217 -232.907436) (xy 135.50371 -232.941528) (xy 135.533275 -232.980872)
			(xy 135.556146 -233.024449) (xy 135.57173 -233.07113) (xy 135.579625 -233.119707) (xy 135.58012 -233.144314)
			(xy 135.909062 -233.144314) (xy 135.913022 -233.09526) (xy 135.924799 -233.047476) (xy 135.94409 -233.0022)
			(xy 135.970393 -232.960604) (xy 136.003028 -232.923767) (xy 136.041149 -232.892642) (xy 136.08377 -232.868035)
			(xy 136.129786 -232.850583) (xy 136.178005 -232.840739) (xy 136.22718 -232.838758) (xy 136.276035 -232.84469)
			(xy 136.323306 -232.858382) (xy 136.367768 -232.87948) (xy 136.408271 -232.907436) (xy 136.443764 -232.941528)
			(xy 136.473329 -232.980872) (xy 136.4962 -233.024449) (xy 136.511784 -233.07113) (xy 136.519679 -233.119707)
			(xy 136.520174 -233.144314) (xy 136.519679 -233.168921) (xy 136.511784 -233.217498) (xy 136.4962 -233.264179)
			(xy 136.473329 -233.307756) (xy 136.443764 -233.3471) (xy 136.408271 -233.381192) (xy 136.367768 -233.409148)
			(xy 136.323306 -233.430246) (xy 136.276035 -233.443938) (xy 136.22718 -233.44987) (xy 136.178005 -233.447889)
			(xy 136.129786 -233.438045) (xy 136.08377 -233.420593) (xy 136.041149 -233.395986) (xy 136.003028 -233.364861)
			(xy 135.970393 -233.328024) (xy 135.94409 -233.286428) (xy 135.924799 -233.241152) (xy 135.913022 -233.193368)
			(xy 135.909062 -233.144314) (xy 135.58012 -233.144314) (xy 135.579625 -233.168921) (xy 135.57173 -233.217498)
			(xy 135.556146 -233.264179) (xy 135.533275 -233.307756) (xy 135.50371 -233.3471) (xy 135.468217 -233.381192)
			(xy 135.427714 -233.409148) (xy 135.383252 -233.430246) (xy 135.335981 -233.443938) (xy 135.287126 -233.44987)
			(xy 135.237951 -233.447889) (xy 135.189732 -233.438045) (xy 135.143716 -233.420593) (xy 135.101095 -233.395986)
			(xy 135.062974 -233.364861) (xy 135.030339 -233.328024) (xy 135.004036 -233.286428) (xy 134.984745 -233.241152)
			(xy 134.972968 -233.193368) (xy 134.969008 -233.144314) (xy 134.640066 -233.144314) (xy 134.639571 -233.168921)
			(xy 134.631676 -233.217498) (xy 134.616092 -233.264179) (xy 134.593221 -233.307756) (xy 134.563656 -233.3471)
			(xy 134.528163 -233.381192) (xy 134.48766 -233.409148) (xy 134.443198 -233.430246) (xy 134.395927 -233.443938)
			(xy 134.347072 -233.44987) (xy 134.297897 -233.447889) (xy 134.249678 -233.438045) (xy 134.203662 -233.420593)
			(xy 134.161041 -233.395986) (xy 134.12292 -233.364861) (xy 134.090285 -233.328024) (xy 134.063982 -233.286428)
			(xy 134.044691 -233.241152) (xy 134.032914 -233.193368) (xy 134.028954 -233.144314) (xy 133.700012 -233.144314)
			(xy 133.699517 -233.168921) (xy 133.691622 -233.217498) (xy 133.676038 -233.264179) (xy 133.653167 -233.307756)
			(xy 133.623602 -233.3471) (xy 133.588109 -233.381192) (xy 133.547606 -233.409148) (xy 133.503144 -233.430246)
			(xy 133.455873 -233.443938) (xy 133.407018 -233.44987) (xy 133.357843 -233.447889) (xy 133.309624 -233.438045)
			(xy 133.263608 -233.420593) (xy 133.220987 -233.395986) (xy 133.182866 -233.364861) (xy 133.150231 -233.328024)
			(xy 133.123928 -233.286428) (xy 133.104637 -233.241152) (xy 133.09286 -233.193368) (xy 133.0889 -233.144314)
			(xy 132.770372 -233.144314) (xy 132.76986 -233.16976) (xy 132.761696 -233.219994) (xy 132.74558 -233.268268)
			(xy 132.721929 -233.313331) (xy 132.691356 -233.354017) (xy 132.654652 -233.389272) (xy 132.612768 -233.418182)
			(xy 132.566789 -233.439999) (xy 132.517905 -233.454159) (xy 132.467384 -233.460293) (xy 132.416532 -233.458244)
			(xy 132.366668 -233.448064) (xy 132.319082 -233.430017) (xy 132.275008 -233.404571) (xy 132.235586 -233.372384)
			(xy 132.201838 -233.33429) (xy 132.174637 -233.291276) (xy 132.154689 -233.244456) (xy 132.14251 -233.195042)
			(xy 132.138415 -233.144314) (xy 131.830572 -233.144314) (xy 131.83006 -233.16976) (xy 131.821896 -233.219994)
			(xy 131.80578 -233.268268) (xy 131.782129 -233.313331) (xy 131.751556 -233.354017) (xy 131.714852 -233.389272)
			(xy 131.672968 -233.418182) (xy 131.626989 -233.439999) (xy 131.578105 -233.454159) (xy 131.527584 -233.460293)
			(xy 131.476732 -233.458244) (xy 131.426868 -233.448064) (xy 131.379282 -233.430017) (xy 131.335208 -233.404571)
			(xy 131.295786 -233.372384) (xy 131.262038 -233.33429) (xy 131.234837 -233.291276) (xy 131.214889 -233.244456)
			(xy 131.20271 -233.195042) (xy 131.198615 -233.144314) (xy 130.880104 -233.144314) (xy 130.879609 -233.168921)
			(xy 130.871714 -233.217498) (xy 130.85613 -233.264179) (xy 130.833259 -233.307756) (xy 130.803694 -233.3471)
			(xy 130.768201 -233.381192) (xy 130.727698 -233.409148) (xy 130.683236 -233.430246) (xy 130.635965 -233.443938)
			(xy 130.58711 -233.44987) (xy 130.537935 -233.447889) (xy 130.489716 -233.438045) (xy 130.4437 -233.420593)
			(xy 130.401079 -233.395986) (xy 130.362958 -233.364861) (xy 130.330323 -233.328024) (xy 130.30402 -233.286428)
			(xy 130.284729 -233.241152) (xy 130.272952 -233.193368) (xy 130.268992 -233.144314) (xy 129.950464 -233.144314)
			(xy 129.949952 -233.16976) (xy 129.941788 -233.219994) (xy 129.925672 -233.268268) (xy 129.902021 -233.313331)
			(xy 129.871448 -233.354017) (xy 129.834744 -233.389272) (xy 129.79286 -233.418182) (xy 129.746881 -233.439999)
			(xy 129.697997 -233.454159) (xy 129.647476 -233.460293) (xy 129.596624 -233.458244) (xy 129.54676 -233.448064)
			(xy 129.499174 -233.430017) (xy 129.4551 -233.404571) (xy 129.415678 -233.372384) (xy 129.38193 -233.33429)
			(xy 129.354729 -233.291276) (xy 129.334781 -233.244456) (xy 129.322602 -233.195042) (xy 129.318507 -233.144314)
			(xy 128.999996 -233.144314) (xy 128.999501 -233.168921) (xy 128.991606 -233.217498) (xy 128.976022 -233.264179)
			(xy 128.953151 -233.307756) (xy 128.923586 -233.3471) (xy 128.888093 -233.381192) (xy 128.84759 -233.409148)
			(xy 128.803128 -233.430246) (xy 128.755857 -233.443938) (xy 128.707002 -233.44987) (xy 128.657827 -233.447889)
			(xy 128.609608 -233.438045) (xy 128.563592 -233.420593) (xy 128.520971 -233.395986) (xy 128.48285 -233.364861)
			(xy 128.450215 -233.328024) (xy 128.423912 -233.286428) (xy 128.404621 -233.241152) (xy 128.392844 -233.193368)
			(xy 128.388884 -233.144314) (xy 128.070356 -233.144314) (xy 128.069868 -233.169124) (xy 128.062105 -233.218132)
			(xy 128.046771 -233.265323) (xy 128.024244 -233.309535) (xy 127.995079 -233.349678) (xy 127.959993 -233.384766)
			(xy 127.919852 -233.413933) (xy 127.875642 -233.436463) (xy 127.828452 -233.4518) (xy 127.779444 -233.459567)
			(xy 127.754634 -233.460036) (xy 127.732751 -233.459629) (xy 127.689414 -233.453513) (xy 127.668274 -233.447844)
			(xy 127.667004 -233.448098) (xy 127.661034 -233.450151) (xy 127.650253 -233.456711) (xy 127.645668 -233.461052)
			(xy 127.506222 -233.600498) (xy 127.503428 -233.603546) (xy 127.497939 -233.610543) (xy 127.491685 -233.627177)
			(xy 127.491236 -233.636058) (xy 127.490474 -233.706924) (xy 127.49089 -233.716773) (xy 127.498216 -233.735055)
			(xy 127.504698 -233.742484) (xy 127.504952 -233.742738) (xy 127.520826 -233.759914) (xy 127.547695 -233.798193)
			(xy 127.568415 -233.84012) (xy 127.582503 -233.884715) (xy 127.589629 -233.930936) (xy 127.590042 -233.95432)
			(xy 127.908553 -233.95432) (xy 127.912648 -233.903592) (xy 127.924827 -233.854178) (xy 127.944775 -233.807358)
			(xy 127.971976 -233.764344) (xy 128.005724 -233.72625) (xy 128.045146 -233.694063) (xy 128.08922 -233.668617)
			(xy 128.136806 -233.65057) (xy 128.18667 -233.64039) (xy 128.237522 -233.638341) (xy 128.288043 -233.644475)
			(xy 128.336927 -233.658635) (xy 128.382906 -233.680452) (xy 128.42479 -233.709362) (xy 128.461494 -233.744617)
			(xy 128.492067 -233.785303) (xy 128.515718 -233.830366) (xy 128.531834 -233.87864) (xy 128.539998 -233.928874)
			(xy 128.54051 -233.95432) (xy 128.848607 -233.95432) (xy 128.852702 -233.903592) (xy 128.864881 -233.854178)
			(xy 128.884829 -233.807358) (xy 128.91203 -233.764344) (xy 128.945778 -233.72625) (xy 128.9852 -233.694063)
			(xy 129.029274 -233.668617) (xy 129.07686 -233.65057) (xy 129.126724 -233.64039) (xy 129.177576 -233.638341)
			(xy 129.228097 -233.644475) (xy 129.276981 -233.658635) (xy 129.32296 -233.680452) (xy 129.364844 -233.709362)
			(xy 129.401548 -233.744617) (xy 129.432121 -233.785303) (xy 129.455772 -233.830366) (xy 129.471888 -233.87864)
			(xy 129.480052 -233.928874) (xy 129.480564 -233.95432) (xy 129.798838 -233.95432) (xy 129.802798 -233.905266)
			(xy 129.814575 -233.857482) (xy 129.833866 -233.812206) (xy 129.860169 -233.77061) (xy 129.892804 -233.733773)
			(xy 129.930925 -233.702648) (xy 129.973546 -233.678041) (xy 130.019562 -233.660589) (xy 130.067781 -233.650745)
			(xy 130.116956 -233.648764) (xy 130.165811 -233.654696) (xy 130.213082 -233.668388) (xy 130.257544 -233.689486)
			(xy 130.298047 -233.717442) (xy 130.33354 -233.751534) (xy 130.363105 -233.790878) (xy 130.385976 -233.834455)
			(xy 130.40156 -233.881136) (xy 130.409455 -233.929713) (xy 130.40995 -233.95432) (xy 130.728461 -233.95432)
			(xy 130.732556 -233.903592) (xy 130.744735 -233.854178) (xy 130.764683 -233.807358) (xy 130.791884 -233.764344)
			(xy 130.825632 -233.72625) (xy 130.865054 -233.694063) (xy 130.909128 -233.668617) (xy 130.956714 -233.65057)
			(xy 131.006578 -233.64039) (xy 131.05743 -233.638341) (xy 131.107951 -233.644475) (xy 131.156835 -233.658635)
			(xy 131.202814 -233.680452) (xy 131.244698 -233.709362) (xy 131.281402 -233.744617) (xy 131.311975 -233.785303)
			(xy 131.335626 -233.830366) (xy 131.351742 -233.87864) (xy 131.359906 -233.928874) (xy 131.360418 -233.95432)
			(xy 131.678946 -233.95432) (xy 131.682906 -233.905266) (xy 131.694683 -233.857482) (xy 131.713974 -233.812206)
			(xy 131.740277 -233.77061) (xy 131.772912 -233.733773) (xy 131.811033 -233.702648) (xy 131.853654 -233.678041)
			(xy 131.89967 -233.660589) (xy 131.947889 -233.650745) (xy 131.997064 -233.648764) (xy 132.045919 -233.654696)
			(xy 132.09319 -233.668388) (xy 132.137652 -233.689486) (xy 132.178155 -233.717442) (xy 132.213648 -233.751534)
			(xy 132.243213 -233.790878) (xy 132.266084 -233.834455) (xy 132.281668 -233.881136) (xy 132.289563 -233.929713)
			(xy 132.290058 -233.95432) (xy 132.608569 -233.95432) (xy 132.612664 -233.903592) (xy 132.624843 -233.854178)
			(xy 132.644791 -233.807358) (xy 132.671992 -233.764344) (xy 132.70574 -233.72625) (xy 132.745162 -233.694063)
			(xy 132.789236 -233.668617) (xy 132.836822 -233.65057) (xy 132.886686 -233.64039) (xy 132.937538 -233.638341)
			(xy 132.988059 -233.644475) (xy 133.036943 -233.658635) (xy 133.082922 -233.680452) (xy 133.124806 -233.709362)
			(xy 133.16151 -233.744617) (xy 133.192083 -233.785303) (xy 133.215734 -233.830366) (xy 133.23185 -233.87864)
			(xy 133.240014 -233.928874) (xy 133.240526 -233.95432) (xy 133.559054 -233.95432) (xy 133.563014 -233.905266)
			(xy 133.574791 -233.857482) (xy 133.594082 -233.812206) (xy 133.620385 -233.77061) (xy 133.65302 -233.733773)
			(xy 133.691141 -233.702648) (xy 133.733762 -233.678041) (xy 133.779778 -233.660589) (xy 133.827997 -233.650745)
			(xy 133.877172 -233.648764) (xy 133.926027 -233.654696) (xy 133.973298 -233.668388) (xy 134.01776 -233.689486)
			(xy 134.058263 -233.717442) (xy 134.093756 -233.751534) (xy 134.123321 -233.790878) (xy 134.146192 -233.834455)
			(xy 134.161776 -233.881136) (xy 134.169671 -233.929713) (xy 134.170166 -233.95432) (xy 134.498854 -233.95432)
			(xy 134.502814 -233.905266) (xy 134.514591 -233.857482) (xy 134.533882 -233.812206) (xy 134.560185 -233.77061)
			(xy 134.59282 -233.733773) (xy 134.630941 -233.702648) (xy 134.673562 -233.678041) (xy 134.719578 -233.660589)
			(xy 134.767797 -233.650745) (xy 134.816972 -233.648764) (xy 134.865827 -233.654696) (xy 134.913098 -233.668388)
			(xy 134.95756 -233.689486) (xy 134.998063 -233.717442) (xy 135.033556 -233.751534) (xy 135.063121 -233.790878)
			(xy 135.085992 -233.834455) (xy 135.101576 -233.881136) (xy 135.109471 -233.929713) (xy 135.109966 -233.95432)
			(xy 135.438908 -233.95432) (xy 135.442868 -233.905266) (xy 135.454645 -233.857482) (xy 135.473936 -233.812206)
			(xy 135.500239 -233.77061) (xy 135.532874 -233.733773) (xy 135.570995 -233.702648) (xy 135.613616 -233.678041)
			(xy 135.659632 -233.660589) (xy 135.707851 -233.650745) (xy 135.757026 -233.648764) (xy 135.805881 -233.654696)
			(xy 135.853152 -233.668388) (xy 135.897614 -233.689486) (xy 135.938117 -233.717442) (xy 135.97361 -233.751534)
			(xy 136.003175 -233.790878) (xy 136.026046 -233.834455) (xy 136.04163 -233.881136) (xy 136.049525 -233.929713)
			(xy 136.05002 -233.95432) (xy 136.049525 -233.978927) (xy 136.04163 -234.027504) (xy 136.026046 -234.074185)
			(xy 136.003175 -234.117762) (xy 135.97361 -234.157106) (xy 135.938117 -234.191198) (xy 135.897614 -234.219154)
			(xy 135.853152 -234.240252) (xy 135.805881 -234.253944) (xy 135.757026 -234.259876) (xy 135.707851 -234.257895)
			(xy 135.659632 -234.248051) (xy 135.613616 -234.230599) (xy 135.570995 -234.205992) (xy 135.532874 -234.174867)
			(xy 135.500239 -234.13803) (xy 135.473936 -234.096434) (xy 135.454645 -234.051158) (xy 135.442868 -234.003374)
			(xy 135.438908 -233.95432) (xy 135.109966 -233.95432) (xy 135.109471 -233.978927) (xy 135.101576 -234.027504)
			(xy 135.085992 -234.074185) (xy 135.063121 -234.117762) (xy 135.033556 -234.157106) (xy 134.998063 -234.191198)
			(xy 134.95756 -234.219154) (xy 134.913098 -234.240252) (xy 134.865827 -234.253944) (xy 134.816972 -234.259876)
			(xy 134.767797 -234.257895) (xy 134.719578 -234.248051) (xy 134.673562 -234.230599) (xy 134.630941 -234.205992)
			(xy 134.59282 -234.174867) (xy 134.560185 -234.13803) (xy 134.533882 -234.096434) (xy 134.514591 -234.051158)
			(xy 134.502814 -234.003374) (xy 134.498854 -233.95432) (xy 134.170166 -233.95432) (xy 134.169671 -233.978927)
			(xy 134.161776 -234.027504) (xy 134.146192 -234.074185) (xy 134.123321 -234.117762) (xy 134.093756 -234.157106)
			(xy 134.058263 -234.191198) (xy 134.01776 -234.219154) (xy 133.973298 -234.240252) (xy 133.926027 -234.253944)
			(xy 133.877172 -234.259876) (xy 133.827997 -234.257895) (xy 133.779778 -234.248051) (xy 133.733762 -234.230599)
			(xy 133.691141 -234.205992) (xy 133.65302 -234.174867) (xy 133.620385 -234.13803) (xy 133.594082 -234.096434)
			(xy 133.574791 -234.051158) (xy 133.563014 -234.003374) (xy 133.559054 -233.95432) (xy 133.240526 -233.95432)
			(xy 133.240014 -233.979766) (xy 133.23185 -234.03) (xy 133.215734 -234.078274) (xy 133.192083 -234.123337)
			(xy 133.16151 -234.164023) (xy 133.124806 -234.199278) (xy 133.082922 -234.228188) (xy 133.036943 -234.250005)
			(xy 132.988059 -234.264165) (xy 132.937538 -234.270299) (xy 132.886686 -234.26825) (xy 132.836822 -234.25807)
			(xy 132.789236 -234.240023) (xy 132.745162 -234.214577) (xy 132.70574 -234.18239) (xy 132.671992 -234.144296)
			(xy 132.644791 -234.101282) (xy 132.624843 -234.054462) (xy 132.612664 -234.005048) (xy 132.608569 -233.95432)
			(xy 132.290058 -233.95432) (xy 132.289563 -233.978927) (xy 132.281668 -234.027504) (xy 132.266084 -234.074185)
			(xy 132.243213 -234.117762) (xy 132.213648 -234.157106) (xy 132.178155 -234.191198) (xy 132.137652 -234.219154)
			(xy 132.09319 -234.240252) (xy 132.045919 -234.253944) (xy 131.997064 -234.259876) (xy 131.947889 -234.257895)
			(xy 131.89967 -234.248051) (xy 131.853654 -234.230599) (xy 131.811033 -234.205992) (xy 131.772912 -234.174867)
			(xy 131.740277 -234.13803) (xy 131.713974 -234.096434) (xy 131.694683 -234.051158) (xy 131.682906 -234.003374)
			(xy 131.678946 -233.95432) (xy 131.360418 -233.95432) (xy 131.359906 -233.979766) (xy 131.351742 -234.03)
			(xy 131.335626 -234.078274) (xy 131.311975 -234.123337) (xy 131.281402 -234.164023) (xy 131.244698 -234.199278)
			(xy 131.202814 -234.228188) (xy 131.156835 -234.250005) (xy 131.107951 -234.264165) (xy 131.05743 -234.270299)
			(xy 131.006578 -234.26825) (xy 130.956714 -234.25807) (xy 130.909128 -234.240023) (xy 130.865054 -234.214577)
			(xy 130.825632 -234.18239) (xy 130.791884 -234.144296) (xy 130.764683 -234.101282) (xy 130.744735 -234.054462)
			(xy 130.732556 -234.005048) (xy 130.728461 -233.95432) (xy 130.40995 -233.95432) (xy 130.409455 -233.978927)
			(xy 130.40156 -234.027504) (xy 130.385976 -234.074185) (xy 130.363105 -234.117762) (xy 130.33354 -234.157106)
			(xy 130.298047 -234.191198) (xy 130.257544 -234.219154) (xy 130.213082 -234.240252) (xy 130.165811 -234.253944)
			(xy 130.116956 -234.259876) (xy 130.067781 -234.257895) (xy 130.019562 -234.248051) (xy 129.973546 -234.230599)
			(xy 129.930925 -234.205992) (xy 129.892804 -234.174867) (xy 129.860169 -234.13803) (xy 129.833866 -234.096434)
			(xy 129.814575 -234.051158) (xy 129.802798 -234.003374) (xy 129.798838 -233.95432) (xy 129.480564 -233.95432)
			(xy 129.480052 -233.979766) (xy 129.471888 -234.03) (xy 129.455772 -234.078274) (xy 129.432121 -234.123337)
			(xy 129.401548 -234.164023) (xy 129.364844 -234.199278) (xy 129.32296 -234.228188) (xy 129.276981 -234.250005)
			(xy 129.228097 -234.264165) (xy 129.177576 -234.270299) (xy 129.126724 -234.26825) (xy 129.07686 -234.25807)
			(xy 129.029274 -234.240023) (xy 128.9852 -234.214577) (xy 128.945778 -234.18239) (xy 128.91203 -234.144296)
			(xy 128.884829 -234.101282) (xy 128.864881 -234.054462) (xy 128.852702 -234.005048) (xy 128.848607 -233.95432)
			(xy 128.54051 -233.95432) (xy 128.539998 -233.979766) (xy 128.531834 -234.03) (xy 128.515718 -234.078274)
			(xy 128.492067 -234.123337) (xy 128.461494 -234.164023) (xy 128.42479 -234.199278) (xy 128.382906 -234.228188)
			(xy 128.336927 -234.250005) (xy 128.288043 -234.264165) (xy 128.237522 -234.270299) (xy 128.18667 -234.26825)
			(xy 128.136806 -234.25807) (xy 128.08922 -234.240023) (xy 128.045146 -234.214577) (xy 128.005724 -234.18239)
			(xy 127.971976 -234.144296) (xy 127.944775 -234.101282) (xy 127.924827 -234.054462) (xy 127.912648 -234.005048)
			(xy 127.908553 -233.95432) (xy 127.590042 -233.95432) (xy 127.58957 -233.978311) (xy 127.582062 -234.025702)
			(xy 127.567233 -234.071336) (xy 127.545449 -234.114088) (xy 127.517246 -234.152907) (xy 127.483318 -234.186836)
			(xy 127.4445 -234.215041) (xy 127.401749 -234.236827) (xy 127.356116 -234.251658) (xy 127.308725 -234.259169)
			(xy 127.284734 -234.259628) (xy 127.261354 -234.259178) (xy 127.21514 -234.252045) (xy 127.170553 -234.237956)
			(xy 127.128632 -234.217239) (xy 127.090355 -234.190378) (xy 127.073152 -234.174538) (xy 127.072898 -234.174284)
			(xy 127.065492 -234.167768) (xy 127.047195 -234.160447) (xy 127.037338 -234.16006) (xy 126.966472 -234.160822)
			(xy 126.957596 -234.161299) (xy 126.940968 -234.167544) (xy 126.93396 -234.173014) (xy 126.932436 -234.174284)
			(xy 126.814834 -234.291886) (xy 126.810262 -234.29722) (xy 126.810008 -234.297474) (xy 126.803306 -234.307572)
			(xy 126.799221 -234.331427) (xy 126.802134 -234.343194) (xy 126.829058 -234.429046) (xy 126.831387 -234.435576)
			(xy 126.838984 -234.447166) (xy 126.844044 -234.451906) (xy 126.849381 -234.456355) (xy 126.861884 -234.462406)
			(xy 126.868682 -234.463844) (xy 126.891879 -234.468453) (xy 126.936586 -234.483876) (xy 126.978381 -234.506007)
			(xy 127.016263 -234.534317) (xy 127.049328 -234.568129) (xy 127.076785 -234.606635) (xy 127.097976 -234.648914)
			(xy 127.112396 -234.693955) (xy 127.119698 -234.74068) (xy 127.120142 -234.764326) (xy 127.438399 -234.764326)
			(xy 127.442494 -234.713598) (xy 127.454673 -234.664184) (xy 127.474621 -234.617364) (xy 127.501822 -234.57435)
			(xy 127.53557 -234.536256) (xy 127.574992 -234.504069) (xy 127.619066 -234.478623) (xy 127.666652 -234.460576)
			(xy 127.716516 -234.450396) (xy 127.767368 -234.448347) (xy 127.817889 -234.454481) (xy 127.866773 -234.468641)
			(xy 127.912752 -234.490458) (xy 127.954636 -234.519368) (xy 127.99134 -234.554623) (xy 128.021913 -234.595309)
			(xy 128.045564 -234.640372) (xy 128.06168 -234.688646) (xy 128.069844 -234.73888) (xy 128.070356 -234.764326)
			(xy 128.388884 -234.764326) (xy 128.392844 -234.715272) (xy 128.404621 -234.667488) (xy 128.423912 -234.622212)
			(xy 128.450215 -234.580616) (xy 128.48285 -234.543779) (xy 128.520971 -234.512654) (xy 128.563592 -234.488047)
			(xy 128.609608 -234.470595) (xy 128.657827 -234.460751) (xy 128.707002 -234.45877) (xy 128.755857 -234.464702)
			(xy 128.803128 -234.478394) (xy 128.84759 -234.499492) (xy 128.888093 -234.527448) (xy 128.923586 -234.56154)
			(xy 128.953151 -234.600884) (xy 128.976022 -234.644461) (xy 128.991606 -234.691142) (xy 128.999501 -234.739719)
			(xy 128.999996 -234.764326) (xy 129.318507 -234.764326) (xy 129.322602 -234.713598) (xy 129.334781 -234.664184)
			(xy 129.354729 -234.617364) (xy 129.38193 -234.57435) (xy 129.415678 -234.536256) (xy 129.4551 -234.504069)
			(xy 129.499174 -234.478623) (xy 129.54676 -234.460576) (xy 129.596624 -234.450396) (xy 129.647476 -234.448347)
			(xy 129.697997 -234.454481) (xy 129.746881 -234.468641) (xy 129.79286 -234.490458) (xy 129.834744 -234.519368)
			(xy 129.871448 -234.554623) (xy 129.902021 -234.595309) (xy 129.925672 -234.640372) (xy 129.941788 -234.688646)
			(xy 129.949952 -234.73888) (xy 129.950464 -234.764326) (xy 131.198615 -234.764326) (xy 131.20271 -234.713598)
			(xy 131.214889 -234.664184) (xy 131.234837 -234.617364) (xy 131.262038 -234.57435) (xy 131.295786 -234.536256)
			(xy 131.335208 -234.504069) (xy 131.379282 -234.478623) (xy 131.426868 -234.460576) (xy 131.476732 -234.450396)
			(xy 131.527584 -234.448347) (xy 131.578105 -234.454481) (xy 131.626989 -234.468641) (xy 131.672968 -234.490458)
			(xy 131.714852 -234.519368) (xy 131.751556 -234.554623) (xy 131.782129 -234.595309) (xy 131.80578 -234.640372)
			(xy 131.821896 -234.688646) (xy 131.83006 -234.73888) (xy 131.830572 -234.764326) (xy 132.138415 -234.764326)
			(xy 132.14251 -234.713598) (xy 132.154689 -234.664184) (xy 132.174637 -234.617364) (xy 132.201838 -234.57435)
			(xy 132.235586 -234.536256) (xy 132.275008 -234.504069) (xy 132.319082 -234.478623) (xy 132.366668 -234.460576)
			(xy 132.416532 -234.450396) (xy 132.467384 -234.448347) (xy 132.517905 -234.454481) (xy 132.566789 -234.468641)
			(xy 132.612768 -234.490458) (xy 132.654652 -234.519368) (xy 132.691356 -234.554623) (xy 132.721929 -234.595309)
			(xy 132.74558 -234.640372) (xy 132.761696 -234.688646) (xy 132.76986 -234.73888) (xy 132.770372 -234.764326)
			(xy 133.0889 -234.764326) (xy 133.09286 -234.715272) (xy 133.104637 -234.667488) (xy 133.123928 -234.622212)
			(xy 133.150231 -234.580616) (xy 133.182866 -234.543779) (xy 133.220987 -234.512654) (xy 133.263608 -234.488047)
			(xy 133.309624 -234.470595) (xy 133.357843 -234.460751) (xy 133.407018 -234.45877) (xy 133.455873 -234.464702)
			(xy 133.503144 -234.478394) (xy 133.547606 -234.499492) (xy 133.588109 -234.527448) (xy 133.623602 -234.56154)
			(xy 133.653167 -234.600884) (xy 133.676038 -234.644461) (xy 133.691622 -234.691142) (xy 133.699517 -234.739719)
			(xy 133.700012 -234.764326) (xy 134.028954 -234.764326) (xy 134.032914 -234.715272) (xy 134.044691 -234.667488)
			(xy 134.063982 -234.622212) (xy 134.090285 -234.580616) (xy 134.12292 -234.543779) (xy 134.161041 -234.512654)
			(xy 134.203662 -234.488047) (xy 134.249678 -234.470595) (xy 134.297897 -234.460751) (xy 134.347072 -234.45877)
			(xy 134.395927 -234.464702) (xy 134.443198 -234.478394) (xy 134.48766 -234.499492) (xy 134.528163 -234.527448)
			(xy 134.563656 -234.56154) (xy 134.593221 -234.600884) (xy 134.616092 -234.644461) (xy 134.631676 -234.691142)
			(xy 134.639571 -234.739719) (xy 134.640066 -234.764326) (xy 134.969008 -234.764326) (xy 134.972968 -234.715272)
			(xy 134.984745 -234.667488) (xy 135.004036 -234.622212) (xy 135.030339 -234.580616) (xy 135.062974 -234.543779)
			(xy 135.101095 -234.512654) (xy 135.143716 -234.488047) (xy 135.189732 -234.470595) (xy 135.237951 -234.460751)
			(xy 135.287126 -234.45877) (xy 135.335981 -234.464702) (xy 135.383252 -234.478394) (xy 135.427714 -234.499492)
			(xy 135.468217 -234.527448) (xy 135.50371 -234.56154) (xy 135.533275 -234.600884) (xy 135.556146 -234.644461)
			(xy 135.57173 -234.691142) (xy 135.579625 -234.739719) (xy 135.58012 -234.764326) (xy 135.909062 -234.764326)
			(xy 135.913022 -234.715272) (xy 135.924799 -234.667488) (xy 135.94409 -234.622212) (xy 135.970393 -234.580616)
			(xy 136.003028 -234.543779) (xy 136.041149 -234.512654) (xy 136.08377 -234.488047) (xy 136.129786 -234.470595)
			(xy 136.178005 -234.460751) (xy 136.22718 -234.45877) (xy 136.276035 -234.464702) (xy 136.323306 -234.478394)
			(xy 136.367768 -234.499492) (xy 136.408271 -234.527448) (xy 136.443764 -234.56154) (xy 136.473329 -234.600884)
			(xy 136.4962 -234.644461) (xy 136.511784 -234.691142) (xy 136.519679 -234.739719) (xy 136.520174 -234.764326)
			(xy 136.519679 -234.788933) (xy 136.511784 -234.83751) (xy 136.4962 -234.884191) (xy 136.473329 -234.927768)
			(xy 136.443764 -234.967112) (xy 136.408271 -235.001204) (xy 136.367768 -235.02916) (xy 136.323306 -235.050258)
			(xy 136.276035 -235.06395) (xy 136.22718 -235.069882) (xy 136.178005 -235.067901) (xy 136.129786 -235.058057)
			(xy 136.08377 -235.040605) (xy 136.041149 -235.015998) (xy 136.003028 -234.984873) (xy 135.970393 -234.948036)
			(xy 135.94409 -234.90644) (xy 135.924799 -234.861164) (xy 135.913022 -234.81338) (xy 135.909062 -234.764326)
			(xy 135.58012 -234.764326) (xy 135.579625 -234.788933) (xy 135.57173 -234.83751) (xy 135.556146 -234.884191)
			(xy 135.533275 -234.927768) (xy 135.50371 -234.967112) (xy 135.468217 -235.001204) (xy 135.427714 -235.02916)
			(xy 135.383252 -235.050258) (xy 135.335981 -235.06395) (xy 135.287126 -235.069882) (xy 135.237951 -235.067901)
			(xy 135.189732 -235.058057) (xy 135.143716 -235.040605) (xy 135.101095 -235.015998) (xy 135.062974 -234.984873)
			(xy 135.030339 -234.948036) (xy 135.004036 -234.90644) (xy 134.984745 -234.861164) (xy 134.972968 -234.81338)
			(xy 134.969008 -234.764326) (xy 134.640066 -234.764326) (xy 134.639571 -234.788933) (xy 134.631676 -234.83751)
			(xy 134.616092 -234.884191) (xy 134.593221 -234.927768) (xy 134.563656 -234.967112) (xy 134.528163 -235.001204)
			(xy 134.48766 -235.02916) (xy 134.443198 -235.050258) (xy 134.395927 -235.06395) (xy 134.347072 -235.069882)
			(xy 134.297897 -235.067901) (xy 134.249678 -235.058057) (xy 134.203662 -235.040605) (xy 134.161041 -235.015998)
			(xy 134.12292 -234.984873) (xy 134.090285 -234.948036) (xy 134.063982 -234.90644) (xy 134.044691 -234.861164)
			(xy 134.032914 -234.81338) (xy 134.028954 -234.764326) (xy 133.700012 -234.764326) (xy 133.699517 -234.788933)
			(xy 133.691622 -234.83751) (xy 133.676038 -234.884191) (xy 133.653167 -234.927768) (xy 133.623602 -234.967112)
			(xy 133.588109 -235.001204) (xy 133.547606 -235.02916) (xy 133.503144 -235.050258) (xy 133.455873 -235.06395)
			(xy 133.407018 -235.069882) (xy 133.357843 -235.067901) (xy 133.309624 -235.058057) (xy 133.263608 -235.040605)
			(xy 133.220987 -235.015998) (xy 133.182866 -234.984873) (xy 133.150231 -234.948036) (xy 133.123928 -234.90644)
			(xy 133.104637 -234.861164) (xy 133.09286 -234.81338) (xy 133.0889 -234.764326) (xy 132.770372 -234.764326)
			(xy 132.76986 -234.789772) (xy 132.761696 -234.840006) (xy 132.74558 -234.88828) (xy 132.721929 -234.933343)
			(xy 132.691356 -234.974029) (xy 132.654652 -235.009284) (xy 132.612768 -235.038194) (xy 132.566789 -235.060011)
			(xy 132.517905 -235.074171) (xy 132.467384 -235.080305) (xy 132.416532 -235.078256) (xy 132.366668 -235.068076)
			(xy 132.319082 -235.050029) (xy 132.275008 -235.024583) (xy 132.235586 -234.992396) (xy 132.201838 -234.954302)
			(xy 132.174637 -234.911288) (xy 132.154689 -234.864468) (xy 132.14251 -234.815054) (xy 132.138415 -234.764326)
			(xy 131.830572 -234.764326) (xy 131.83006 -234.789772) (xy 131.821896 -234.840006) (xy 131.80578 -234.88828)
			(xy 131.782129 -234.933343) (xy 131.751556 -234.974029) (xy 131.714852 -235.009284) (xy 131.672968 -235.038194)
			(xy 131.626989 -235.060011) (xy 131.578105 -235.074171) (xy 131.527584 -235.080305) (xy 131.476732 -235.078256)
			(xy 131.426868 -235.068076) (xy 131.379282 -235.050029) (xy 131.335208 -235.024583) (xy 131.295786 -234.992396)
			(xy 131.262038 -234.954302) (xy 131.234837 -234.911288) (xy 131.214889 -234.864468) (xy 131.20271 -234.815054)
			(xy 131.198615 -234.764326) (xy 129.950464 -234.764326) (xy 129.949952 -234.789772) (xy 129.941788 -234.840006)
			(xy 129.925672 -234.88828) (xy 129.902021 -234.933343) (xy 129.871448 -234.974029) (xy 129.834744 -235.009284)
			(xy 129.79286 -235.038194) (xy 129.746881 -235.060011) (xy 129.697997 -235.074171) (xy 129.647476 -235.080305)
			(xy 129.596624 -235.078256) (xy 129.54676 -235.068076) (xy 129.499174 -235.050029) (xy 129.4551 -235.024583)
			(xy 129.415678 -234.992396) (xy 129.38193 -234.954302) (xy 129.354729 -234.911288) (xy 129.334781 -234.864468)
			(xy 129.322602 -234.815054) (xy 129.318507 -234.764326) (xy 128.999996 -234.764326) (xy 128.999501 -234.788933)
			(xy 128.991606 -234.83751) (xy 128.976022 -234.884191) (xy 128.953151 -234.927768) (xy 128.923586 -234.967112)
			(xy 128.888093 -235.001204) (xy 128.84759 -235.02916) (xy 128.803128 -235.050258) (xy 128.755857 -235.06395)
			(xy 128.707002 -235.069882) (xy 128.657827 -235.067901) (xy 128.609608 -235.058057) (xy 128.563592 -235.040605)
			(xy 128.520971 -235.015998) (xy 128.48285 -234.984873) (xy 128.450215 -234.948036) (xy 128.423912 -234.90644)
			(xy 128.404621 -234.861164) (xy 128.392844 -234.81338) (xy 128.388884 -234.764326) (xy 128.070356 -234.764326)
			(xy 128.069844 -234.789772) (xy 128.06168 -234.840006) (xy 128.045564 -234.88828) (xy 128.021913 -234.933343)
			(xy 127.99134 -234.974029) (xy 127.954636 -235.009284) (xy 127.912752 -235.038194) (xy 127.866773 -235.060011)
			(xy 127.817889 -235.074171) (xy 127.767368 -235.080305) (xy 127.716516 -235.078256) (xy 127.666652 -235.068076)
			(xy 127.619066 -235.050029) (xy 127.574992 -235.024583) (xy 127.53557 -234.992396) (xy 127.501822 -234.954302)
			(xy 127.474621 -234.911288) (xy 127.454673 -234.864468) (xy 127.442494 -234.815054) (xy 127.438399 -234.764326)
			(xy 127.120142 -234.764326) (xy 127.119669 -234.788317) (xy 127.11216 -234.835707) (xy 127.097331 -234.88134)
			(xy 127.075547 -234.924092) (xy 127.047343 -234.96291) (xy 127.013416 -234.996838) (xy 126.974598 -235.025042)
			(xy 126.931848 -235.046828) (xy 126.886215 -235.061658) (xy 126.838825 -235.069169) (xy 126.814834 -235.069634)
			(xy 126.784904 -235.068911) (xy 126.726186 -235.057279) (xy 126.698248 -235.04652) (xy 126.689104 -235.04271)
			(xy 126.6698 -235.042456) (xy 126.586488 -235.074714) (xy 126.572264 -235.087922) (xy 126.567946 -235.096558)
			(xy 126.560251 -235.112379) (xy 126.543606 -235.143378) (xy 126.534672 -235.158534) (xy 126.531116 -235.164376)
			(xy 126.52756 -235.177584) (xy 126.52756 -235.294424) (xy 126.527678 -235.299929) (xy 126.529977 -235.310694)
			(xy 126.532132 -235.31576) (xy 126.544832 -235.343446) (xy 126.552198 -235.350304) (xy 126.570294 -235.367791)
			(xy 126.601078 -235.407595) (xy 126.624924 -235.451905) (xy 126.641187 -235.499523) (xy 126.649429 -235.549162)
			(xy 126.649427 -235.574332) (xy 127.908553 -235.574332) (xy 127.912648 -235.523604) (xy 127.924827 -235.47419)
			(xy 127.944775 -235.42737) (xy 127.971976 -235.384356) (xy 128.005724 -235.346262) (xy 128.045146 -235.314075)
			(xy 128.08922 -235.288629) (xy 128.136806 -235.270582) (xy 128.18667 -235.260402) (xy 128.237522 -235.258353)
			(xy 128.288043 -235.264487) (xy 128.336927 -235.278647) (xy 128.382906 -235.300464) (xy 128.42479 -235.329374)
			(xy 128.461494 -235.364629) (xy 128.492067 -235.405315) (xy 128.515718 -235.450378) (xy 128.531834 -235.498652)
			(xy 128.539998 -235.548886) (xy 128.54051 -235.574332) (xy 128.848607 -235.574332) (xy 128.852702 -235.523604)
			(xy 128.864881 -235.47419) (xy 128.884829 -235.42737) (xy 128.91203 -235.384356) (xy 128.945778 -235.346262)
			(xy 128.9852 -235.314075) (xy 129.029274 -235.288629) (xy 129.07686 -235.270582) (xy 129.126724 -235.260402)
			(xy 129.177576 -235.258353) (xy 129.228097 -235.264487) (xy 129.276981 -235.278647) (xy 129.32296 -235.300464)
			(xy 129.364844 -235.329374) (xy 129.401548 -235.364629) (xy 129.432121 -235.405315) (xy 129.455772 -235.450378)
			(xy 129.471888 -235.498652) (xy 129.480052 -235.548886) (xy 129.480564 -235.574332) (xy 129.798838 -235.574332)
			(xy 129.802798 -235.525278) (xy 129.814575 -235.477494) (xy 129.833866 -235.432218) (xy 129.860169 -235.390622)
			(xy 129.892804 -235.353785) (xy 129.930925 -235.32266) (xy 129.973546 -235.298053) (xy 130.019562 -235.280601)
			(xy 130.067781 -235.270757) (xy 130.116956 -235.268776) (xy 130.165811 -235.274708) (xy 130.213082 -235.2884)
			(xy 130.257544 -235.309498) (xy 130.298047 -235.337454) (xy 130.33354 -235.371546) (xy 130.363105 -235.41089)
			(xy 130.385976 -235.454467) (xy 130.40156 -235.501148) (xy 130.409455 -235.549725) (xy 130.40995 -235.574332)
			(xy 130.728461 -235.574332) (xy 130.732556 -235.523604) (xy 130.744735 -235.47419) (xy 130.764683 -235.42737)
			(xy 130.791884 -235.384356) (xy 130.825632 -235.346262) (xy 130.865054 -235.314075) (xy 130.909128 -235.288629)
			(xy 130.956714 -235.270582) (xy 131.006578 -235.260402) (xy 131.05743 -235.258353) (xy 131.107951 -235.264487)
			(xy 131.156835 -235.278647) (xy 131.202814 -235.300464) (xy 131.244698 -235.329374) (xy 131.281402 -235.364629)
			(xy 131.311975 -235.405315) (xy 131.335626 -235.450378) (xy 131.351742 -235.498652) (xy 131.359906 -235.548886)
			(xy 131.360418 -235.574332) (xy 131.678946 -235.574332) (xy 131.682906 -235.525278) (xy 131.694683 -235.477494)
			(xy 131.713974 -235.432218) (xy 131.740277 -235.390622) (xy 131.772912 -235.353785) (xy 131.811033 -235.32266)
			(xy 131.853654 -235.298053) (xy 131.89967 -235.280601) (xy 131.947889 -235.270757) (xy 131.997064 -235.268776)
			(xy 132.045919 -235.274708) (xy 132.09319 -235.2884) (xy 132.137652 -235.309498) (xy 132.178155 -235.337454)
			(xy 132.213648 -235.371546) (xy 132.243213 -235.41089) (xy 132.266084 -235.454467) (xy 132.281668 -235.501148)
			(xy 132.289563 -235.549725) (xy 132.290058 -235.574332) (xy 132.608569 -235.574332) (xy 132.612664 -235.523604)
			(xy 132.624843 -235.47419) (xy 132.644791 -235.42737) (xy 132.671992 -235.384356) (xy 132.70574 -235.346262)
			(xy 132.745162 -235.314075) (xy 132.789236 -235.288629) (xy 132.836822 -235.270582) (xy 132.886686 -235.260402)
			(xy 132.937538 -235.258353) (xy 132.988059 -235.264487) (xy 133.036943 -235.278647) (xy 133.082922 -235.300464)
			(xy 133.124806 -235.329374) (xy 133.16151 -235.364629) (xy 133.192083 -235.405315) (xy 133.215734 -235.450378)
			(xy 133.23185 -235.498652) (xy 133.240014 -235.548886) (xy 133.240526 -235.574332) (xy 133.559054 -235.574332)
			(xy 133.563014 -235.525278) (xy 133.574791 -235.477494) (xy 133.594082 -235.432218) (xy 133.620385 -235.390622)
			(xy 133.65302 -235.353785) (xy 133.691141 -235.32266) (xy 133.733762 -235.298053) (xy 133.779778 -235.280601)
			(xy 133.827997 -235.270757) (xy 133.877172 -235.268776) (xy 133.926027 -235.274708) (xy 133.973298 -235.2884)
			(xy 134.01776 -235.309498) (xy 134.058263 -235.337454) (xy 134.093756 -235.371546) (xy 134.123321 -235.41089)
			(xy 134.146192 -235.454467) (xy 134.161776 -235.501148) (xy 134.169671 -235.549725) (xy 134.170166 -235.574332)
			(xy 134.498854 -235.574332) (xy 134.502814 -235.525278) (xy 134.514591 -235.477494) (xy 134.533882 -235.432218)
			(xy 134.560185 -235.390622) (xy 134.59282 -235.353785) (xy 134.630941 -235.32266) (xy 134.673562 -235.298053)
			(xy 134.719578 -235.280601) (xy 134.767797 -235.270757) (xy 134.816972 -235.268776) (xy 134.865827 -235.274708)
			(xy 134.913098 -235.2884) (xy 134.95756 -235.309498) (xy 134.998063 -235.337454) (xy 135.033556 -235.371546)
			(xy 135.063121 -235.41089) (xy 135.085992 -235.454467) (xy 135.101576 -235.501148) (xy 135.109471 -235.549725)
			(xy 135.109966 -235.574332) (xy 135.438908 -235.574332) (xy 135.442868 -235.525278) (xy 135.454645 -235.477494)
			(xy 135.473936 -235.432218) (xy 135.500239 -235.390622) (xy 135.532874 -235.353785) (xy 135.570995 -235.32266)
			(xy 135.613616 -235.298053) (xy 135.659632 -235.280601) (xy 135.707851 -235.270757) (xy 135.757026 -235.268776)
			(xy 135.805881 -235.274708) (xy 135.853152 -235.2884) (xy 135.897614 -235.309498) (xy 135.938117 -235.337454)
			(xy 135.97361 -235.371546) (xy 136.003175 -235.41089) (xy 136.026046 -235.454467) (xy 136.04163 -235.501148)
			(xy 136.049525 -235.549725) (xy 136.05002 -235.574332) (xy 136.049525 -235.598939) (xy 136.04163 -235.647516)
			(xy 136.026046 -235.694197) (xy 136.003175 -235.737774) (xy 135.97361 -235.777118) (xy 135.938117 -235.81121)
			(xy 135.897614 -235.839166) (xy 135.853152 -235.860264) (xy 135.805881 -235.873956) (xy 135.757026 -235.879888)
			(xy 135.707851 -235.877907) (xy 135.659632 -235.868063) (xy 135.613616 -235.850611) (xy 135.570995 -235.826004)
			(xy 135.532874 -235.794879) (xy 135.500239 -235.758042) (xy 135.473936 -235.716446) (xy 135.454645 -235.67117)
			(xy 135.442868 -235.623386) (xy 135.438908 -235.574332) (xy 135.109966 -235.574332) (xy 135.109471 -235.598939)
			(xy 135.101576 -235.647516) (xy 135.085992 -235.694197) (xy 135.063121 -235.737774) (xy 135.033556 -235.777118)
			(xy 134.998063 -235.81121) (xy 134.95756 -235.839166) (xy 134.913098 -235.860264) (xy 134.865827 -235.873956)
			(xy 134.816972 -235.879888) (xy 134.767797 -235.877907) (xy 134.719578 -235.868063) (xy 134.673562 -235.850611)
			(xy 134.630941 -235.826004) (xy 134.59282 -235.794879) (xy 134.560185 -235.758042) (xy 134.533882 -235.716446)
			(xy 134.514591 -235.67117) (xy 134.502814 -235.623386) (xy 134.498854 -235.574332) (xy 134.170166 -235.574332)
			(xy 134.169671 -235.598939) (xy 134.161776 -235.647516) (xy 134.146192 -235.694197) (xy 134.123321 -235.737774)
			(xy 134.093756 -235.777118) (xy 134.058263 -235.81121) (xy 134.01776 -235.839166) (xy 133.973298 -235.860264)
			(xy 133.926027 -235.873956) (xy 133.877172 -235.879888) (xy 133.827997 -235.877907) (xy 133.779778 -235.868063)
			(xy 133.733762 -235.850611) (xy 133.691141 -235.826004) (xy 133.65302 -235.794879) (xy 133.620385 -235.758042)
			(xy 133.594082 -235.716446) (xy 133.574791 -235.67117) (xy 133.563014 -235.623386) (xy 133.559054 -235.574332)
			(xy 133.240526 -235.574332) (xy 133.240014 -235.599778) (xy 133.23185 -235.650012) (xy 133.215734 -235.698286)
			(xy 133.192083 -235.743349) (xy 133.16151 -235.784035) (xy 133.124806 -235.81929) (xy 133.082922 -235.8482)
			(xy 133.036943 -235.870017) (xy 132.988059 -235.884177) (xy 132.937538 -235.890311) (xy 132.886686 -235.888262)
			(xy 132.836822 -235.878082) (xy 132.789236 -235.860035) (xy 132.745162 -235.834589) (xy 132.70574 -235.802402)
			(xy 132.671992 -235.764308) (xy 132.644791 -235.721294) (xy 132.624843 -235.674474) (xy 132.612664 -235.62506)
			(xy 132.608569 -235.574332) (xy 132.290058 -235.574332) (xy 132.289563 -235.598939) (xy 132.281668 -235.647516)
			(xy 132.266084 -235.694197) (xy 132.243213 -235.737774) (xy 132.213648 -235.777118) (xy 132.178155 -235.81121)
			(xy 132.137652 -235.839166) (xy 132.09319 -235.860264) (xy 132.045919 -235.873956) (xy 131.997064 -235.879888)
			(xy 131.947889 -235.877907) (xy 131.89967 -235.868063) (xy 131.853654 -235.850611) (xy 131.811033 -235.826004)
			(xy 131.772912 -235.794879) (xy 131.740277 -235.758042) (xy 131.713974 -235.716446) (xy 131.694683 -235.67117)
			(xy 131.682906 -235.623386) (xy 131.678946 -235.574332) (xy 131.360418 -235.574332) (xy 131.359906 -235.599778)
			(xy 131.351742 -235.650012) (xy 131.335626 -235.698286) (xy 131.311975 -235.743349) (xy 131.281402 -235.784035)
			(xy 131.244698 -235.81929) (xy 131.202814 -235.8482) (xy 131.156835 -235.870017) (xy 131.107951 -235.884177)
			(xy 131.05743 -235.890311) (xy 131.006578 -235.888262) (xy 130.956714 -235.878082) (xy 130.909128 -235.860035)
			(xy 130.865054 -235.834589) (xy 130.825632 -235.802402) (xy 130.791884 -235.764308) (xy 130.764683 -235.721294)
			(xy 130.744735 -235.674474) (xy 130.732556 -235.62506) (xy 130.728461 -235.574332) (xy 130.40995 -235.574332)
			(xy 130.409455 -235.598939) (xy 130.40156 -235.647516) (xy 130.385976 -235.694197) (xy 130.363105 -235.737774)
			(xy 130.33354 -235.777118) (xy 130.298047 -235.81121) (xy 130.257544 -235.839166) (xy 130.213082 -235.860264)
			(xy 130.165811 -235.873956) (xy 130.116956 -235.879888) (xy 130.067781 -235.877907) (xy 130.019562 -235.868063)
			(xy 129.973546 -235.850611) (xy 129.930925 -235.826004) (xy 129.892804 -235.794879) (xy 129.860169 -235.758042)
			(xy 129.833866 -235.716446) (xy 129.814575 -235.67117) (xy 129.802798 -235.623386) (xy 129.798838 -235.574332)
			(xy 129.480564 -235.574332) (xy 129.480052 -235.599778) (xy 129.471888 -235.650012) (xy 129.455772 -235.698286)
			(xy 129.432121 -235.743349) (xy 129.401548 -235.784035) (xy 129.364844 -235.81929) (xy 129.32296 -235.8482)
			(xy 129.276981 -235.870017) (xy 129.228097 -235.884177) (xy 129.177576 -235.890311) (xy 129.126724 -235.888262)
			(xy 129.07686 -235.878082) (xy 129.029274 -235.860035) (xy 128.9852 -235.834589) (xy 128.945778 -235.802402)
			(xy 128.91203 -235.764308) (xy 128.884829 -235.721294) (xy 128.864881 -235.674474) (xy 128.852702 -235.62506)
			(xy 128.848607 -235.574332) (xy 128.54051 -235.574332) (xy 128.539998 -235.599778) (xy 128.531834 -235.650012)
			(xy 128.515718 -235.698286) (xy 128.492067 -235.743349) (xy 128.461494 -235.784035) (xy 128.42479 -235.81929)
			(xy 128.382906 -235.8482) (xy 128.336927 -235.870017) (xy 128.288043 -235.884177) (xy 128.237522 -235.890311)
			(xy 128.18667 -235.888262) (xy 128.136806 -235.878082) (xy 128.08922 -235.860035) (xy 128.045146 -235.834589)
			(xy 128.005724 -235.802402) (xy 127.971976 -235.764308) (xy 127.944775 -235.721294) (xy 127.924827 -235.674474)
			(xy 127.912648 -235.62506) (xy 127.908553 -235.574332) (xy 126.649427 -235.574332) (xy 126.649425 -235.599481)
			(xy 126.641177 -235.649119) (xy 126.624907 -235.696735) (xy 126.601054 -235.741042) (xy 126.570265 -235.780842)
			(xy 126.552198 -235.79836) (xy 126.544832 -235.805218) (xy 126.532132 -235.832904) (xy 126.529976 -235.83797)
			(xy 126.527676 -235.848735) (xy 126.52756 -235.85424) (xy 126.52756 -235.97108) (xy 126.531116 -235.984288)
			(xy 126.534672 -235.99013) (xy 126.543607 -236.005285) (xy 126.56025 -236.036286) (xy 126.567946 -236.052106)
			(xy 126.572264 -236.060742) (xy 126.586488 -236.07395) (xy 126.6698 -236.106208) (xy 126.689104 -236.105954)
			(xy 126.698248 -236.102144) (xy 126.726191 -236.0914) (xy 126.784906 -236.079765) (xy 126.814834 -236.07903)
			(xy 126.840084 -236.079554) (xy 126.889896 -236.087871) (xy 126.937659 -236.104273) (xy 126.982071 -236.128312)
			(xy 127.021921 -236.159333) (xy 127.056122 -236.196489) (xy 127.083742 -236.238768) (xy 127.104027 -236.285016)
			(xy 127.116423 -236.333972) (xy 127.120593 -236.3843) (xy 127.12059 -236.384338) (xy 127.438399 -236.384338)
			(xy 127.442494 -236.33361) (xy 127.454673 -236.284196) (xy 127.474621 -236.237376) (xy 127.501822 -236.194362)
			(xy 127.53557 -236.156268) (xy 127.574992 -236.124081) (xy 127.619066 -236.098635) (xy 127.666652 -236.080588)
			(xy 127.716516 -236.070408) (xy 127.767368 -236.068359) (xy 127.817889 -236.074493) (xy 127.866773 -236.088653)
			(xy 127.912752 -236.11047) (xy 127.954636 -236.13938) (xy 127.99134 -236.174635) (xy 128.021913 -236.215321)
			(xy 128.045564 -236.260384) (xy 128.06168 -236.308658) (xy 128.069844 -236.358892) (xy 128.070356 -236.384338)
			(xy 128.388884 -236.384338) (xy 128.392844 -236.335284) (xy 128.404621 -236.2875) (xy 128.423912 -236.242224)
			(xy 128.450215 -236.200628) (xy 128.48285 -236.163791) (xy 128.520971 -236.132666) (xy 128.563592 -236.108059)
			(xy 128.609608 -236.090607) (xy 128.657827 -236.080763) (xy 128.707002 -236.078782) (xy 128.755857 -236.084714)
			(xy 128.803128 -236.098406) (xy 128.84759 -236.119504) (xy 128.888093 -236.14746) (xy 128.923586 -236.181552)
			(xy 128.953151 -236.220896) (xy 128.976022 -236.264473) (xy 128.991606 -236.311154) (xy 128.999501 -236.359731)
			(xy 128.999996 -236.384338) (xy 129.318507 -236.384338) (xy 129.322602 -236.33361) (xy 129.334781 -236.284196)
			(xy 129.354729 -236.237376) (xy 129.38193 -236.194362) (xy 129.415678 -236.156268) (xy 129.4551 -236.124081)
			(xy 129.499174 -236.098635) (xy 129.54676 -236.080588) (xy 129.596624 -236.070408) (xy 129.647476 -236.068359)
			(xy 129.697997 -236.074493) (xy 129.746881 -236.088653) (xy 129.79286 -236.11047) (xy 129.834744 -236.13938)
			(xy 129.871448 -236.174635) (xy 129.902021 -236.215321) (xy 129.925672 -236.260384) (xy 129.941788 -236.308658)
			(xy 129.949952 -236.358892) (xy 129.950464 -236.384338) (xy 130.268992 -236.384338) (xy 130.272952 -236.335284)
			(xy 130.284729 -236.2875) (xy 130.30402 -236.242224) (xy 130.330323 -236.200628) (xy 130.362958 -236.163791)
			(xy 130.401079 -236.132666) (xy 130.4437 -236.108059) (xy 130.489716 -236.090607) (xy 130.537935 -236.080763)
			(xy 130.58711 -236.078782) (xy 130.635965 -236.084714) (xy 130.683236 -236.098406) (xy 130.727698 -236.119504)
			(xy 130.768201 -236.14746) (xy 130.803694 -236.181552) (xy 130.833259 -236.220896) (xy 130.85613 -236.264473)
			(xy 130.871714 -236.311154) (xy 130.879609 -236.359731) (xy 130.880104 -236.384338) (xy 131.198615 -236.384338)
			(xy 131.20271 -236.33361) (xy 131.214889 -236.284196) (xy 131.234837 -236.237376) (xy 131.262038 -236.194362)
			(xy 131.295786 -236.156268) (xy 131.335208 -236.124081) (xy 131.379282 -236.098635) (xy 131.426868 -236.080588)
			(xy 131.476732 -236.070408) (xy 131.527584 -236.068359) (xy 131.578105 -236.074493) (xy 131.626989 -236.088653)
			(xy 131.672968 -236.11047) (xy 131.714852 -236.13938) (xy 131.751556 -236.174635) (xy 131.782129 -236.215321)
			(xy 131.80578 -236.260384) (xy 131.821896 -236.308658) (xy 131.83006 -236.358892) (xy 131.830572 -236.384338)
			(xy 132.138415 -236.384338) (xy 132.14251 -236.33361) (xy 132.154689 -236.284196) (xy 132.174637 -236.237376)
			(xy 132.201838 -236.194362) (xy 132.235586 -236.156268) (xy 132.275008 -236.124081) (xy 132.319082 -236.098635)
			(xy 132.366668 -236.080588) (xy 132.416532 -236.070408) (xy 132.467384 -236.068359) (xy 132.517905 -236.074493)
			(xy 132.566789 -236.088653) (xy 132.612768 -236.11047) (xy 132.654652 -236.13938) (xy 132.691356 -236.174635)
			(xy 132.721929 -236.215321) (xy 132.74558 -236.260384) (xy 132.761696 -236.308658) (xy 132.76986 -236.358892)
			(xy 132.770372 -236.384338) (xy 133.0889 -236.384338) (xy 133.09286 -236.335284) (xy 133.104637 -236.2875)
			(xy 133.123928 -236.242224) (xy 133.150231 -236.200628) (xy 133.182866 -236.163791) (xy 133.220987 -236.132666)
			(xy 133.263608 -236.108059) (xy 133.309624 -236.090607) (xy 133.357843 -236.080763) (xy 133.407018 -236.078782)
			(xy 133.455873 -236.084714) (xy 133.503144 -236.098406) (xy 133.547606 -236.119504) (xy 133.588109 -236.14746)
			(xy 133.623602 -236.181552) (xy 133.653167 -236.220896) (xy 133.676038 -236.264473) (xy 133.691622 -236.311154)
			(xy 133.699517 -236.359731) (xy 133.700012 -236.384338) (xy 134.028954 -236.384338) (xy 134.032914 -236.335284)
			(xy 134.044691 -236.2875) (xy 134.063982 -236.242224) (xy 134.090285 -236.200628) (xy 134.12292 -236.163791)
			(xy 134.161041 -236.132666) (xy 134.203662 -236.108059) (xy 134.249678 -236.090607) (xy 134.297897 -236.080763)
			(xy 134.347072 -236.078782) (xy 134.395927 -236.084714) (xy 134.443198 -236.098406) (xy 134.48766 -236.119504)
			(xy 134.528163 -236.14746) (xy 134.563656 -236.181552) (xy 134.593221 -236.220896) (xy 134.616092 -236.264473)
			(xy 134.631676 -236.311154) (xy 134.639571 -236.359731) (xy 134.640066 -236.384338) (xy 134.969008 -236.384338)
			(xy 134.972968 -236.335284) (xy 134.984745 -236.2875) (xy 135.004036 -236.242224) (xy 135.030339 -236.200628)
			(xy 135.062974 -236.163791) (xy 135.101095 -236.132666) (xy 135.143716 -236.108059) (xy 135.189732 -236.090607)
			(xy 135.237951 -236.080763) (xy 135.287126 -236.078782) (xy 135.335981 -236.084714) (xy 135.383252 -236.098406)
			(xy 135.427714 -236.119504) (xy 135.468217 -236.14746) (xy 135.50371 -236.181552) (xy 135.533275 -236.220896)
			(xy 135.556146 -236.264473) (xy 135.57173 -236.311154) (xy 135.579625 -236.359731) (xy 135.58012 -236.384338)
			(xy 135.909062 -236.384338) (xy 135.913022 -236.335284) (xy 135.924799 -236.2875) (xy 135.94409 -236.242224)
			(xy 135.970393 -236.200628) (xy 136.003028 -236.163791) (xy 136.041149 -236.132666) (xy 136.08377 -236.108059)
			(xy 136.129786 -236.090607) (xy 136.178005 -236.080763) (xy 136.22718 -236.078782) (xy 136.276035 -236.084714)
			(xy 136.323306 -236.098406) (xy 136.367768 -236.119504) (xy 136.408271 -236.14746) (xy 136.443764 -236.181552)
			(xy 136.473329 -236.220896) (xy 136.4962 -236.264473) (xy 136.511784 -236.311154) (xy 136.519679 -236.359731)
			(xy 136.520174 -236.384338) (xy 136.519679 -236.408945) (xy 136.511784 -236.457522) (xy 136.4962 -236.504203)
			(xy 136.473329 -236.54778) (xy 136.443764 -236.587124) (xy 136.408271 -236.621216) (xy 136.367768 -236.649172)
			(xy 136.323306 -236.67027) (xy 136.276035 -236.683962) (xy 136.22718 -236.689894) (xy 136.178005 -236.687913)
			(xy 136.129786 -236.678069) (xy 136.08377 -236.660617) (xy 136.041149 -236.63601) (xy 136.003028 -236.604885)
			(xy 135.970393 -236.568048) (xy 135.94409 -236.526452) (xy 135.924799 -236.481176) (xy 135.913022 -236.433392)
			(xy 135.909062 -236.384338) (xy 135.58012 -236.384338) (xy 135.579625 -236.408945) (xy 135.57173 -236.457522)
			(xy 135.556146 -236.504203) (xy 135.533275 -236.54778) (xy 135.50371 -236.587124) (xy 135.468217 -236.621216)
			(xy 135.427714 -236.649172) (xy 135.383252 -236.67027) (xy 135.335981 -236.683962) (xy 135.287126 -236.689894)
			(xy 135.237951 -236.687913) (xy 135.189732 -236.678069) (xy 135.143716 -236.660617) (xy 135.101095 -236.63601)
			(xy 135.062974 -236.604885) (xy 135.030339 -236.568048) (xy 135.004036 -236.526452) (xy 134.984745 -236.481176)
			(xy 134.972968 -236.433392) (xy 134.969008 -236.384338) (xy 134.640066 -236.384338) (xy 134.639571 -236.408945)
			(xy 134.631676 -236.457522) (xy 134.616092 -236.504203) (xy 134.593221 -236.54778) (xy 134.563656 -236.587124)
			(xy 134.528163 -236.621216) (xy 134.48766 -236.649172) (xy 134.443198 -236.67027) (xy 134.395927 -236.683962)
			(xy 134.347072 -236.689894) (xy 134.297897 -236.687913) (xy 134.249678 -236.678069) (xy 134.203662 -236.660617)
			(xy 134.161041 -236.63601) (xy 134.12292 -236.604885) (xy 134.090285 -236.568048) (xy 134.063982 -236.526452)
			(xy 134.044691 -236.481176) (xy 134.032914 -236.433392) (xy 134.028954 -236.384338) (xy 133.700012 -236.384338)
			(xy 133.699517 -236.408945) (xy 133.691622 -236.457522) (xy 133.676038 -236.504203) (xy 133.653167 -236.54778)
			(xy 133.623602 -236.587124) (xy 133.588109 -236.621216) (xy 133.547606 -236.649172) (xy 133.503144 -236.67027)
			(xy 133.455873 -236.683962) (xy 133.407018 -236.689894) (xy 133.357843 -236.687913) (xy 133.309624 -236.678069)
			(xy 133.263608 -236.660617) (xy 133.220987 -236.63601) (xy 133.182866 -236.604885) (xy 133.150231 -236.568048)
			(xy 133.123928 -236.526452) (xy 133.104637 -236.481176) (xy 133.09286 -236.433392) (xy 133.0889 -236.384338)
			(xy 132.770372 -236.384338) (xy 132.76986 -236.409784) (xy 132.761696 -236.460018) (xy 132.74558 -236.508292)
			(xy 132.721929 -236.553355) (xy 132.691356 -236.594041) (xy 132.654652 -236.629296) (xy 132.612768 -236.658206)
			(xy 132.566789 -236.680023) (xy 132.517905 -236.694183) (xy 132.467384 -236.700317) (xy 132.416532 -236.698268)
			(xy 132.366668 -236.688088) (xy 132.319082 -236.670041) (xy 132.275008 -236.644595) (xy 132.235586 -236.612408)
			(xy 132.201838 -236.574314) (xy 132.174637 -236.5313) (xy 132.154689 -236.48448) (xy 132.14251 -236.435066)
			(xy 132.138415 -236.384338) (xy 131.830572 -236.384338) (xy 131.83006 -236.409784) (xy 131.821896 -236.460018)
			(xy 131.80578 -236.508292) (xy 131.782129 -236.553355) (xy 131.751556 -236.594041) (xy 131.714852 -236.629296)
			(xy 131.672968 -236.658206) (xy 131.626989 -236.680023) (xy 131.578105 -236.694183) (xy 131.527584 -236.700317)
			(xy 131.476732 -236.698268) (xy 131.426868 -236.688088) (xy 131.379282 -236.670041) (xy 131.335208 -236.644595)
			(xy 131.295786 -236.612408) (xy 131.262038 -236.574314) (xy 131.234837 -236.5313) (xy 131.214889 -236.48448)
			(xy 131.20271 -236.435066) (xy 131.198615 -236.384338) (xy 130.880104 -236.384338) (xy 130.879609 -236.408945)
			(xy 130.871714 -236.457522) (xy 130.85613 -236.504203) (xy 130.833259 -236.54778) (xy 130.803694 -236.587124)
			(xy 130.768201 -236.621216) (xy 130.727698 -236.649172) (xy 130.683236 -236.67027) (xy 130.635965 -236.683962)
			(xy 130.58711 -236.689894) (xy 130.537935 -236.687913) (xy 130.489716 -236.678069) (xy 130.4437 -236.660617)
			(xy 130.401079 -236.63601) (xy 130.362958 -236.604885) (xy 130.330323 -236.568048) (xy 130.30402 -236.526452)
			(xy 130.284729 -236.481176) (xy 130.272952 -236.433392) (xy 130.268992 -236.384338) (xy 129.950464 -236.384338)
			(xy 129.949952 -236.409784) (xy 129.941788 -236.460018) (xy 129.925672 -236.508292) (xy 129.902021 -236.553355)
			(xy 129.871448 -236.594041) (xy 129.834744 -236.629296) (xy 129.79286 -236.658206) (xy 129.746881 -236.680023)
			(xy 129.697997 -236.694183) (xy 129.647476 -236.700317) (xy 129.596624 -236.698268) (xy 129.54676 -236.688088)
			(xy 129.499174 -236.670041) (xy 129.4551 -236.644595) (xy 129.415678 -236.612408) (xy 129.38193 -236.574314)
			(xy 129.354729 -236.5313) (xy 129.334781 -236.48448) (xy 129.322602 -236.435066) (xy 129.318507 -236.384338)
			(xy 128.999996 -236.384338) (xy 128.999501 -236.408945) (xy 128.991606 -236.457522) (xy 128.976022 -236.504203)
			(xy 128.953151 -236.54778) (xy 128.923586 -236.587124) (xy 128.888093 -236.621216) (xy 128.84759 -236.649172)
			(xy 128.803128 -236.67027) (xy 128.755857 -236.683962) (xy 128.707002 -236.689894) (xy 128.657827 -236.687913)
			(xy 128.609608 -236.678069) (xy 128.563592 -236.660617) (xy 128.520971 -236.63601) (xy 128.48285 -236.604885)
			(xy 128.450215 -236.568048) (xy 128.423912 -236.526452) (xy 128.404621 -236.481176) (xy 128.392844 -236.433392)
			(xy 128.388884 -236.384338) (xy 128.070356 -236.384338) (xy 128.069844 -236.409784) (xy 128.06168 -236.460018)
			(xy 128.045564 -236.508292) (xy 128.021913 -236.553355) (xy 127.99134 -236.594041) (xy 127.954636 -236.629296)
			(xy 127.912752 -236.658206) (xy 127.866773 -236.680023) (xy 127.817889 -236.694183) (xy 127.767368 -236.700317)
			(xy 127.716516 -236.698268) (xy 127.666652 -236.688088) (xy 127.619066 -236.670041) (xy 127.574992 -236.644595)
			(xy 127.53557 -236.612408) (xy 127.501822 -236.574314) (xy 127.474621 -236.5313) (xy 127.454673 -236.48448)
			(xy 127.442494 -236.435066) (xy 127.438399 -236.384338) (xy 127.12059 -236.384338) (xy 127.116423 -236.434628)
			(xy 127.104027 -236.483584) (xy 127.083742 -236.529832) (xy 127.056122 -236.572111) (xy 127.021921 -236.609267)
			(xy 126.982071 -236.640288) (xy 126.937659 -236.664327) (xy 126.889896 -236.680729) (xy 126.840084 -236.689046)
			(xy 126.814834 -236.689646) (xy 126.784904 -236.688923) (xy 126.726186 -236.677291) (xy 126.698248 -236.666532)
			(xy 126.689104 -236.662722) (xy 126.6698 -236.662468) (xy 126.586488 -236.694726) (xy 126.572264 -236.707934)
			(xy 126.567946 -236.71657) (xy 126.560251 -236.732391) (xy 126.543606 -236.76339) (xy 126.534672 -236.778546)
			(xy 126.531116 -236.784388) (xy 126.52756 -236.797596) (xy 126.52756 -236.914436) (xy 126.527679 -236.91994)
			(xy 126.529981 -236.930704) (xy 126.532132 -236.935772) (xy 126.544832 -236.963458) (xy 126.552198 -236.970316)
			(xy 126.570293 -236.987803) (xy 126.601075 -237.027606) (xy 126.624919 -237.071916) (xy 126.641181 -237.119533)
			(xy 126.649421 -237.169171) (xy 126.649418 -237.194344) (xy 126.97893 -237.194344) (xy 126.98289 -237.14529)
			(xy 126.994667 -237.097506) (xy 127.013958 -237.05223) (xy 127.040261 -237.010634) (xy 127.072896 -236.973797)
			(xy 127.111017 -236.942672) (xy 127.153638 -236.918065) (xy 127.199654 -236.900613) (xy 127.247873 -236.890769)
			(xy 127.297048 -236.888788) (xy 127.345903 -236.89472) (xy 127.393174 -236.908412) (xy 127.437636 -236.92951)
			(xy 127.478139 -236.957466) (xy 127.513632 -236.991558) (xy 127.543197 -237.030902) (xy 127.566068 -237.074479)
			(xy 127.581652 -237.12116) (xy 127.589547 -237.169737) (xy 127.590042 -237.194344) (xy 127.908553 -237.194344)
			(xy 127.912648 -237.143616) (xy 127.924827 -237.094202) (xy 127.944775 -237.047382) (xy 127.971976 -237.004368)
			(xy 128.005724 -236.966274) (xy 128.045146 -236.934087) (xy 128.08922 -236.908641) (xy 128.136806 -236.890594)
			(xy 128.18667 -236.880414) (xy 128.237522 -236.878365) (xy 128.288043 -236.884499) (xy 128.336927 -236.898659)
			(xy 128.382906 -236.920476) (xy 128.42479 -236.949386) (xy 128.461494 -236.984641) (xy 128.492067 -237.025327)
			(xy 128.515718 -237.07039) (xy 128.531834 -237.118664) (xy 128.539998 -237.168898) (xy 128.54051 -237.194344)
			(xy 128.848607 -237.194344) (xy 128.852702 -237.143616) (xy 128.864881 -237.094202) (xy 128.884829 -237.047382)
			(xy 128.91203 -237.004368) (xy 128.945778 -236.966274) (xy 128.9852 -236.934087) (xy 129.029274 -236.908641)
			(xy 129.07686 -236.890594) (xy 129.126724 -236.880414) (xy 129.177576 -236.878365) (xy 129.228097 -236.884499)
			(xy 129.276981 -236.898659) (xy 129.32296 -236.920476) (xy 129.364844 -236.949386) (xy 129.401548 -236.984641)
			(xy 129.432121 -237.025327) (xy 129.455772 -237.07039) (xy 129.471888 -237.118664) (xy 129.480052 -237.168898)
			(xy 129.480564 -237.194344) (xy 130.728461 -237.194344) (xy 130.732556 -237.143616) (xy 130.744735 -237.094202)
			(xy 130.764683 -237.047382) (xy 130.791884 -237.004368) (xy 130.825632 -236.966274) (xy 130.865054 -236.934087)
			(xy 130.909128 -236.908641) (xy 130.956714 -236.890594) (xy 131.006578 -236.880414) (xy 131.05743 -236.878365)
			(xy 131.107951 -236.884499) (xy 131.156835 -236.898659) (xy 131.202814 -236.920476) (xy 131.244698 -236.949386)
			(xy 131.281402 -236.984641) (xy 131.311975 -237.025327) (xy 131.335626 -237.07039) (xy 131.351742 -237.118664)
			(xy 131.359906 -237.168898) (xy 131.360418 -237.194344) (xy 131.678946 -237.194344) (xy 131.682906 -237.14529)
			(xy 131.694683 -237.097506) (xy 131.713974 -237.05223) (xy 131.740277 -237.010634) (xy 131.772912 -236.973797)
			(xy 131.811033 -236.942672) (xy 131.853654 -236.918065) (xy 131.89967 -236.900613) (xy 131.947889 -236.890769)
			(xy 131.997064 -236.888788) (xy 132.045919 -236.89472) (xy 132.09319 -236.908412) (xy 132.137652 -236.92951)
			(xy 132.178155 -236.957466) (xy 132.213648 -236.991558) (xy 132.243213 -237.030902) (xy 132.266084 -237.074479)
			(xy 132.281668 -237.12116) (xy 132.289563 -237.169737) (xy 132.290058 -237.194344) (xy 132.608569 -237.194344)
			(xy 132.612664 -237.143616) (xy 132.624843 -237.094202) (xy 132.644791 -237.047382) (xy 132.671992 -237.004368)
			(xy 132.70574 -236.966274) (xy 132.745162 -236.934087) (xy 132.789236 -236.908641) (xy 132.836822 -236.890594)
			(xy 132.886686 -236.880414) (xy 132.937538 -236.878365) (xy 132.988059 -236.884499) (xy 133.036943 -236.898659)
			(xy 133.082922 -236.920476) (xy 133.124806 -236.949386) (xy 133.16151 -236.984641) (xy 133.192083 -237.025327)
			(xy 133.215734 -237.07039) (xy 133.23185 -237.118664) (xy 133.240014 -237.168898) (xy 133.240526 -237.194344)
			(xy 133.559054 -237.194344) (xy 133.563014 -237.14529) (xy 133.574791 -237.097506) (xy 133.594082 -237.05223)
			(xy 133.620385 -237.010634) (xy 133.65302 -236.973797) (xy 133.691141 -236.942672) (xy 133.733762 -236.918065)
			(xy 133.779778 -236.900613) (xy 133.827997 -236.890769) (xy 133.877172 -236.888788) (xy 133.926027 -236.89472)
			(xy 133.973298 -236.908412) (xy 134.01776 -236.92951) (xy 134.058263 -236.957466) (xy 134.093756 -236.991558)
			(xy 134.123321 -237.030902) (xy 134.146192 -237.074479) (xy 134.161776 -237.12116) (xy 134.169671 -237.169737)
			(xy 134.170166 -237.194344) (xy 134.498854 -237.194344) (xy 134.502814 -237.14529) (xy 134.514591 -237.097506)
			(xy 134.533882 -237.05223) (xy 134.560185 -237.010634) (xy 134.59282 -236.973797) (xy 134.630941 -236.942672)
			(xy 134.673562 -236.918065) (xy 134.719578 -236.900613) (xy 134.767797 -236.890769) (xy 134.816972 -236.888788)
			(xy 134.865827 -236.89472) (xy 134.913098 -236.908412) (xy 134.95756 -236.92951) (xy 134.998063 -236.957466)
			(xy 135.033556 -236.991558) (xy 135.063121 -237.030902) (xy 135.085992 -237.074479) (xy 135.101576 -237.12116)
			(xy 135.109471 -237.169737) (xy 135.109966 -237.194344) (xy 135.438908 -237.194344) (xy 135.442868 -237.14529)
			(xy 135.454645 -237.097506) (xy 135.473936 -237.05223) (xy 135.500239 -237.010634) (xy 135.532874 -236.973797)
			(xy 135.570995 -236.942672) (xy 135.613616 -236.918065) (xy 135.659632 -236.900613) (xy 135.707851 -236.890769)
			(xy 135.757026 -236.888788) (xy 135.805881 -236.89472) (xy 135.853152 -236.908412) (xy 135.897614 -236.92951)
			(xy 135.938117 -236.957466) (xy 135.97361 -236.991558) (xy 136.003175 -237.030902) (xy 136.026046 -237.074479)
			(xy 136.04163 -237.12116) (xy 136.049525 -237.169737) (xy 136.05002 -237.194344) (xy 136.049525 -237.218951)
			(xy 136.04163 -237.267528) (xy 136.026046 -237.314209) (xy 136.003175 -237.357786) (xy 135.97361 -237.39713)
			(xy 135.938117 -237.431222) (xy 135.897614 -237.459178) (xy 135.853152 -237.480276) (xy 135.805881 -237.493968)
			(xy 135.757026 -237.4999) (xy 135.707851 -237.497919) (xy 135.659632 -237.488075) (xy 135.613616 -237.470623)
			(xy 135.570995 -237.446016) (xy 135.532874 -237.414891) (xy 135.500239 -237.378054) (xy 135.473936 -237.336458)
			(xy 135.454645 -237.291182) (xy 135.442868 -237.243398) (xy 135.438908 -237.194344) (xy 135.109966 -237.194344)
			(xy 135.109471 -237.218951) (xy 135.101576 -237.267528) (xy 135.085992 -237.314209) (xy 135.063121 -237.357786)
			(xy 135.033556 -237.39713) (xy 134.998063 -237.431222) (xy 134.95756 -237.459178) (xy 134.913098 -237.480276)
			(xy 134.865827 -237.493968) (xy 134.816972 -237.4999) (xy 134.767797 -237.497919) (xy 134.719578 -237.488075)
			(xy 134.673562 -237.470623) (xy 134.630941 -237.446016) (xy 134.59282 -237.414891) (xy 134.560185 -237.378054)
			(xy 134.533882 -237.336458) (xy 134.514591 -237.291182) (xy 134.502814 -237.243398) (xy 134.498854 -237.194344)
			(xy 134.170166 -237.194344) (xy 134.169671 -237.218951) (xy 134.161776 -237.267528) (xy 134.146192 -237.314209)
			(xy 134.123321 -237.357786) (xy 134.093756 -237.39713) (xy 134.058263 -237.431222) (xy 134.01776 -237.459178)
			(xy 133.973298 -237.480276) (xy 133.926027 -237.493968) (xy 133.877172 -237.4999) (xy 133.827997 -237.497919)
			(xy 133.779778 -237.488075) (xy 133.733762 -237.470623) (xy 133.691141 -237.446016) (xy 133.65302 -237.414891)
			(xy 133.620385 -237.378054) (xy 133.594082 -237.336458) (xy 133.574791 -237.291182) (xy 133.563014 -237.243398)
			(xy 133.559054 -237.194344) (xy 133.240526 -237.194344) (xy 133.240014 -237.21979) (xy 133.23185 -237.270024)
			(xy 133.215734 -237.318298) (xy 133.192083 -237.363361) (xy 133.16151 -237.404047) (xy 133.124806 -237.439302)
			(xy 133.082922 -237.468212) (xy 133.036943 -237.490029) (xy 132.988059 -237.504189) (xy 132.937538 -237.510323)
			(xy 132.886686 -237.508274) (xy 132.836822 -237.498094) (xy 132.789236 -237.480047) (xy 132.745162 -237.454601)
			(xy 132.70574 -237.422414) (xy 132.671992 -237.38432) (xy 132.644791 -237.341306) (xy 132.624843 -237.294486)
			(xy 132.612664 -237.245072) (xy 132.608569 -237.194344) (xy 132.290058 -237.194344) (xy 132.289563 -237.218951)
			(xy 132.281668 -237.267528) (xy 132.266084 -237.314209) (xy 132.243213 -237.357786) (xy 132.213648 -237.39713)
			(xy 132.178155 -237.431222) (xy 132.137652 -237.459178) (xy 132.09319 -237.480276) (xy 132.045919 -237.493968)
			(xy 131.997064 -237.4999) (xy 131.947889 -237.497919) (xy 131.89967 -237.488075) (xy 131.853654 -237.470623)
			(xy 131.811033 -237.446016) (xy 131.772912 -237.414891) (xy 131.740277 -237.378054) (xy 131.713974 -237.336458)
			(xy 131.694683 -237.291182) (xy 131.682906 -237.243398) (xy 131.678946 -237.194344) (xy 131.360418 -237.194344)
			(xy 131.359906 -237.21979) (xy 131.351742 -237.270024) (xy 131.335626 -237.318298) (xy 131.311975 -237.363361)
			(xy 131.281402 -237.404047) (xy 131.244698 -237.439302) (xy 131.202814 -237.468212) (xy 131.156835 -237.490029)
			(xy 131.107951 -237.504189) (xy 131.05743 -237.510323) (xy 131.006578 -237.508274) (xy 130.956714 -237.498094)
			(xy 130.909128 -237.480047) (xy 130.865054 -237.454601) (xy 130.825632 -237.422414) (xy 130.791884 -237.38432)
			(xy 130.764683 -237.341306) (xy 130.744735 -237.294486) (xy 130.732556 -237.245072) (xy 130.728461 -237.194344)
			(xy 129.480564 -237.194344) (xy 129.480052 -237.21979) (xy 129.471888 -237.270024) (xy 129.455772 -237.318298)
			(xy 129.432121 -237.363361) (xy 129.401548 -237.404047) (xy 129.364844 -237.439302) (xy 129.32296 -237.468212)
			(xy 129.276981 -237.490029) (xy 129.228097 -237.504189) (xy 129.177576 -237.510323) (xy 129.126724 -237.508274)
			(xy 129.07686 -237.498094) (xy 129.029274 -237.480047) (xy 128.9852 -237.454601) (xy 128.945778 -237.422414)
			(xy 128.91203 -237.38432) (xy 128.884829 -237.341306) (xy 128.864881 -237.294486) (xy 128.852702 -237.245072)
			(xy 128.848607 -237.194344) (xy 128.54051 -237.194344) (xy 128.539998 -237.21979) (xy 128.531834 -237.270024)
			(xy 128.515718 -237.318298) (xy 128.492067 -237.363361) (xy 128.461494 -237.404047) (xy 128.42479 -237.439302)
			(xy 128.382906 -237.468212) (xy 128.336927 -237.490029) (xy 128.288043 -237.504189) (xy 128.237522 -237.510323)
			(xy 128.18667 -237.508274) (xy 128.136806 -237.498094) (xy 128.08922 -237.480047) (xy 128.045146 -237.454601)
			(xy 128.005724 -237.422414) (xy 127.971976 -237.38432) (xy 127.944775 -237.341306) (xy 127.924827 -237.294486)
			(xy 127.912648 -237.245072) (xy 127.908553 -237.194344) (xy 127.590042 -237.194344) (xy 127.589547 -237.218951)
			(xy 127.581652 -237.267528) (xy 127.566068 -237.314209) (xy 127.543197 -237.357786) (xy 127.513632 -237.39713)
			(xy 127.478139 -237.431222) (xy 127.437636 -237.459178) (xy 127.393174 -237.480276) (xy 127.345903 -237.493968)
			(xy 127.297048 -237.4999) (xy 127.247873 -237.497919) (xy 127.199654 -237.488075) (xy 127.153638 -237.470623)
			(xy 127.111017 -237.446016) (xy 127.072896 -237.414891) (xy 127.040261 -237.378054) (xy 127.013958 -237.336458)
			(xy 126.994667 -237.291182) (xy 126.98289 -237.243398) (xy 126.97893 -237.194344) (xy 126.649418 -237.194344)
			(xy 126.649416 -237.219489) (xy 126.641166 -237.269125) (xy 126.624895 -237.316739) (xy 126.601043 -237.361044)
			(xy 126.570253 -237.400842) (xy 126.552198 -237.418372) (xy 126.544832 -237.42523) (xy 126.532132 -237.452916)
			(xy 126.529977 -237.457982) (xy 126.52768 -237.468747) (xy 126.52756 -237.474252) (xy 126.52756 -238.00435)
			(xy 127.438399 -238.00435) (xy 127.442494 -237.953622) (xy 127.454673 -237.904208) (xy 127.474621 -237.857388)
			(xy 127.501822 -237.814374) (xy 127.53557 -237.77628) (xy 127.574992 -237.744093) (xy 127.619066 -237.718647)
			(xy 127.666652 -237.7006) (xy 127.716516 -237.69042) (xy 127.767368 -237.688371) (xy 127.817889 -237.694505)
			(xy 127.866773 -237.708665) (xy 127.912752 -237.730482) (xy 127.954636 -237.759392) (xy 127.99134 -237.794647)
			(xy 128.021913 -237.835333) (xy 128.045564 -237.880396) (xy 128.06168 -237.92867) (xy 128.069844 -237.978904)
			(xy 128.070356 -238.00435) (xy 128.388884 -238.00435) (xy 128.392844 -237.955296) (xy 128.404621 -237.907512)
			(xy 128.423912 -237.862236) (xy 128.450215 -237.82064) (xy 128.48285 -237.783803) (xy 128.520971 -237.752678)
			(xy 128.563592 -237.728071) (xy 128.609608 -237.710619) (xy 128.657827 -237.700775) (xy 128.707002 -237.698794)
			(xy 128.755857 -237.704726) (xy 128.803128 -237.718418) (xy 128.84759 -237.739516) (xy 128.888093 -237.767472)
			(xy 128.923586 -237.801564) (xy 128.953151 -237.840908) (xy 128.976022 -237.884485) (xy 128.991606 -237.931166)
			(xy 128.999501 -237.979743) (xy 128.999996 -238.00435) (xy 129.318507 -238.00435) (xy 129.322602 -237.953622)
			(xy 129.334781 -237.904208) (xy 129.354729 -237.857388) (xy 129.38193 -237.814374) (xy 129.415678 -237.77628)
			(xy 129.4551 -237.744093) (xy 129.499174 -237.718647) (xy 129.54676 -237.7006) (xy 129.596624 -237.69042)
			(xy 129.647476 -237.688371) (xy 129.697997 -237.694505) (xy 129.746881 -237.708665) (xy 129.79286 -237.730482)
			(xy 129.834744 -237.759392) (xy 129.871448 -237.794647) (xy 129.902021 -237.835333) (xy 129.925672 -237.880396)
			(xy 129.941788 -237.92867) (xy 129.949952 -237.978904) (xy 129.950464 -238.00435) (xy 130.268992 -238.00435)
			(xy 130.272952 -237.955296) (xy 130.284729 -237.907512) (xy 130.30402 -237.862236) (xy 130.330323 -237.82064)
			(xy 130.362958 -237.783803) (xy 130.401079 -237.752678) (xy 130.4437 -237.728071) (xy 130.489716 -237.710619)
			(xy 130.537935 -237.700775) (xy 130.58711 -237.698794) (xy 130.635965 -237.704726) (xy 130.683236 -237.718418)
			(xy 130.727698 -237.739516) (xy 130.768201 -237.767472) (xy 130.803694 -237.801564) (xy 130.833259 -237.840908)
			(xy 130.85613 -237.884485) (xy 130.871714 -237.931166) (xy 130.879609 -237.979743) (xy 130.880104 -238.00435)
			(xy 131.198615 -238.00435) (xy 131.20271 -237.953622) (xy 131.214889 -237.904208) (xy 131.234837 -237.857388)
			(xy 131.262038 -237.814374) (xy 131.295786 -237.77628) (xy 131.335208 -237.744093) (xy 131.379282 -237.718647)
			(xy 131.426868 -237.7006) (xy 131.476732 -237.69042) (xy 131.527584 -237.688371) (xy 131.578105 -237.694505)
			(xy 131.626989 -237.708665) (xy 131.672968 -237.730482) (xy 131.714852 -237.759392) (xy 131.751556 -237.794647)
			(xy 131.782129 -237.835333) (xy 131.80578 -237.880396) (xy 131.821896 -237.92867) (xy 131.83006 -237.978904)
			(xy 131.830572 -238.00435) (xy 132.138415 -238.00435) (xy 132.14251 -237.953622) (xy 132.154689 -237.904208)
			(xy 132.174637 -237.857388) (xy 132.201838 -237.814374) (xy 132.235586 -237.77628) (xy 132.275008 -237.744093)
			(xy 132.319082 -237.718647) (xy 132.366668 -237.7006) (xy 132.416532 -237.69042) (xy 132.467384 -237.688371)
			(xy 132.517905 -237.694505) (xy 132.566789 -237.708665) (xy 132.612768 -237.730482) (xy 132.654652 -237.759392)
			(xy 132.691356 -237.794647) (xy 132.721929 -237.835333) (xy 132.74558 -237.880396) (xy 132.761696 -237.92867)
			(xy 132.76986 -237.978904) (xy 132.770372 -238.00435) (xy 133.0889 -238.00435) (xy 133.09286 -237.955296)
			(xy 133.104637 -237.907512) (xy 133.123928 -237.862236) (xy 133.150231 -237.82064) (xy 133.182866 -237.783803)
			(xy 133.220987 -237.752678) (xy 133.263608 -237.728071) (xy 133.309624 -237.710619) (xy 133.357843 -237.700775)
			(xy 133.407018 -237.698794) (xy 133.455873 -237.704726) (xy 133.503144 -237.718418) (xy 133.547606 -237.739516)
			(xy 133.588109 -237.767472) (xy 133.623602 -237.801564) (xy 133.653167 -237.840908) (xy 133.676038 -237.884485)
			(xy 133.691622 -237.931166) (xy 133.699517 -237.979743) (xy 133.700012 -238.00435) (xy 134.028954 -238.00435)
			(xy 134.032914 -237.955296) (xy 134.044691 -237.907512) (xy 134.063982 -237.862236) (xy 134.090285 -237.82064)
			(xy 134.12292 -237.783803) (xy 134.161041 -237.752678) (xy 134.203662 -237.728071) (xy 134.249678 -237.710619)
			(xy 134.297897 -237.700775) (xy 134.347072 -237.698794) (xy 134.395927 -237.704726) (xy 134.443198 -237.718418)
			(xy 134.48766 -237.739516) (xy 134.528163 -237.767472) (xy 134.563656 -237.801564) (xy 134.593221 -237.840908)
			(xy 134.616092 -237.884485) (xy 134.631676 -237.931166) (xy 134.639571 -237.979743) (xy 134.640066 -238.00435)
			(xy 134.969008 -238.00435) (xy 134.972968 -237.955296) (xy 134.984745 -237.907512) (xy 135.004036 -237.862236)
			(xy 135.030339 -237.82064) (xy 135.062974 -237.783803) (xy 135.101095 -237.752678) (xy 135.143716 -237.728071)
			(xy 135.189732 -237.710619) (xy 135.237951 -237.700775) (xy 135.287126 -237.698794) (xy 135.335981 -237.704726)
			(xy 135.383252 -237.718418) (xy 135.427714 -237.739516) (xy 135.468217 -237.767472) (xy 135.50371 -237.801564)
			(xy 135.533275 -237.840908) (xy 135.556146 -237.884485) (xy 135.57173 -237.931166) (xy 135.579625 -237.979743)
			(xy 135.58012 -238.00435) (xy 135.909062 -238.00435) (xy 135.913022 -237.955296) (xy 135.924799 -237.907512)
			(xy 135.94409 -237.862236) (xy 135.970393 -237.82064) (xy 136.003028 -237.783803) (xy 136.041149 -237.752678)
			(xy 136.08377 -237.728071) (xy 136.129786 -237.710619) (xy 136.178005 -237.700775) (xy 136.22718 -237.698794)
			(xy 136.276035 -237.704726) (xy 136.323306 -237.718418) (xy 136.367768 -237.739516) (xy 136.408271 -237.767472)
			(xy 136.443764 -237.801564) (xy 136.473329 -237.840908) (xy 136.4962 -237.884485) (xy 136.511784 -237.931166)
			(xy 136.519679 -237.979743) (xy 136.520174 -238.00435) (xy 136.519679 -238.028957) (xy 136.511784 -238.077534)
			(xy 136.4962 -238.124215) (xy 136.473329 -238.167792) (xy 136.443764 -238.207136) (xy 136.408271 -238.241228)
			(xy 136.367768 -238.269184) (xy 136.323306 -238.290282) (xy 136.276035 -238.303974) (xy 136.22718 -238.309906)
			(xy 136.178005 -238.307925) (xy 136.129786 -238.298081) (xy 136.08377 -238.280629) (xy 136.041149 -238.256022)
			(xy 136.003028 -238.224897) (xy 135.970393 -238.18806) (xy 135.94409 -238.146464) (xy 135.924799 -238.101188)
			(xy 135.913022 -238.053404) (xy 135.909062 -238.00435) (xy 135.58012 -238.00435) (xy 135.579625 -238.028957)
			(xy 135.57173 -238.077534) (xy 135.556146 -238.124215) (xy 135.533275 -238.167792) (xy 135.50371 -238.207136)
			(xy 135.468217 -238.241228) (xy 135.427714 -238.269184) (xy 135.383252 -238.290282) (xy 135.335981 -238.303974)
			(xy 135.287126 -238.309906) (xy 135.237951 -238.307925) (xy 135.189732 -238.298081) (xy 135.143716 -238.280629)
			(xy 135.101095 -238.256022) (xy 135.062974 -238.224897) (xy 135.030339 -238.18806) (xy 135.004036 -238.146464)
			(xy 134.984745 -238.101188) (xy 134.972968 -238.053404) (xy 134.969008 -238.00435) (xy 134.640066 -238.00435)
			(xy 134.639571 -238.028957) (xy 134.631676 -238.077534) (xy 134.616092 -238.124215) (xy 134.593221 -238.167792)
			(xy 134.563656 -238.207136) (xy 134.528163 -238.241228) (xy 134.48766 -238.269184) (xy 134.443198 -238.290282)
			(xy 134.395927 -238.303974) (xy 134.347072 -238.309906) (xy 134.297897 -238.307925) (xy 134.249678 -238.298081)
			(xy 134.203662 -238.280629) (xy 134.161041 -238.256022) (xy 134.12292 -238.224897) (xy 134.090285 -238.18806)
			(xy 134.063982 -238.146464) (xy 134.044691 -238.101188) (xy 134.032914 -238.053404) (xy 134.028954 -238.00435)
			(xy 133.700012 -238.00435) (xy 133.699517 -238.028957) (xy 133.691622 -238.077534) (xy 133.676038 -238.124215)
			(xy 133.653167 -238.167792) (xy 133.623602 -238.207136) (xy 133.588109 -238.241228) (xy 133.547606 -238.269184)
			(xy 133.503144 -238.290282) (xy 133.455873 -238.303974) (xy 133.407018 -238.309906) (xy 133.357843 -238.307925)
			(xy 133.309624 -238.298081) (xy 133.263608 -238.280629) (xy 133.220987 -238.256022) (xy 133.182866 -238.224897)
			(xy 133.150231 -238.18806) (xy 133.123928 -238.146464) (xy 133.104637 -238.101188) (xy 133.09286 -238.053404)
			(xy 133.0889 -238.00435) (xy 132.770372 -238.00435) (xy 132.76986 -238.029796) (xy 132.761696 -238.08003)
			(xy 132.74558 -238.128304) (xy 132.721929 -238.173367) (xy 132.691356 -238.214053) (xy 132.654652 -238.249308)
			(xy 132.612768 -238.278218) (xy 132.566789 -238.300035) (xy 132.517905 -238.314195) (xy 132.467384 -238.320329)
			(xy 132.416532 -238.31828) (xy 132.366668 -238.3081) (xy 132.319082 -238.290053) (xy 132.275008 -238.264607)
			(xy 132.235586 -238.23242) (xy 132.201838 -238.194326) (xy 132.174637 -238.151312) (xy 132.154689 -238.104492)
			(xy 132.14251 -238.055078) (xy 132.138415 -238.00435) (xy 131.830572 -238.00435) (xy 131.83006 -238.029796)
			(xy 131.821896 -238.08003) (xy 131.80578 -238.128304) (xy 131.782129 -238.173367) (xy 131.751556 -238.214053)
			(xy 131.714852 -238.249308) (xy 131.672968 -238.278218) (xy 131.626989 -238.300035) (xy 131.578105 -238.314195)
			(xy 131.527584 -238.320329) (xy 131.476732 -238.31828) (xy 131.426868 -238.3081) (xy 131.379282 -238.290053)
			(xy 131.335208 -238.264607) (xy 131.295786 -238.23242) (xy 131.262038 -238.194326) (xy 131.234837 -238.151312)
			(xy 131.214889 -238.104492) (xy 131.20271 -238.055078) (xy 131.198615 -238.00435) (xy 130.880104 -238.00435)
			(xy 130.879609 -238.028957) (xy 130.871714 -238.077534) (xy 130.85613 -238.124215) (xy 130.833259 -238.167792)
			(xy 130.803694 -238.207136) (xy 130.768201 -238.241228) (xy 130.727698 -238.269184) (xy 130.683236 -238.290282)
			(xy 130.635965 -238.303974) (xy 130.58711 -238.309906) (xy 130.537935 -238.307925) (xy 130.489716 -238.298081)
			(xy 130.4437 -238.280629) (xy 130.401079 -238.256022) (xy 130.362958 -238.224897) (xy 130.330323 -238.18806)
			(xy 130.30402 -238.146464) (xy 130.284729 -238.101188) (xy 130.272952 -238.053404) (xy 130.268992 -238.00435)
			(xy 129.950464 -238.00435) (xy 129.949952 -238.029796) (xy 129.941788 -238.08003) (xy 129.925672 -238.128304)
			(xy 129.902021 -238.173367) (xy 129.871448 -238.214053) (xy 129.834744 -238.249308) (xy 129.79286 -238.278218)
			(xy 129.746881 -238.300035) (xy 129.697997 -238.314195) (xy 129.647476 -238.320329) (xy 129.596624 -238.31828)
			(xy 129.54676 -238.3081) (xy 129.499174 -238.290053) (xy 129.4551 -238.264607) (xy 129.415678 -238.23242)
			(xy 129.38193 -238.194326) (xy 129.354729 -238.151312) (xy 129.334781 -238.104492) (xy 129.322602 -238.055078)
			(xy 129.318507 -238.00435) (xy 128.999996 -238.00435) (xy 128.999501 -238.028957) (xy 128.991606 -238.077534)
			(xy 128.976022 -238.124215) (xy 128.953151 -238.167792) (xy 128.923586 -238.207136) (xy 128.888093 -238.241228)
			(xy 128.84759 -238.269184) (xy 128.803128 -238.290282) (xy 128.755857 -238.303974) (xy 128.707002 -238.309906)
			(xy 128.657827 -238.307925) (xy 128.609608 -238.298081) (xy 128.563592 -238.280629) (xy 128.520971 -238.256022)
			(xy 128.48285 -238.224897) (xy 128.450215 -238.18806) (xy 128.423912 -238.146464) (xy 128.404621 -238.101188)
			(xy 128.392844 -238.053404) (xy 128.388884 -238.00435) (xy 128.070356 -238.00435) (xy 128.069844 -238.029796)
			(xy 128.06168 -238.08003) (xy 128.045564 -238.128304) (xy 128.021913 -238.173367) (xy 127.99134 -238.214053)
			(xy 127.954636 -238.249308) (xy 127.912752 -238.278218) (xy 127.866773 -238.300035) (xy 127.817889 -238.314195)
			(xy 127.767368 -238.320329) (xy 127.716516 -238.31828) (xy 127.666652 -238.3081) (xy 127.619066 -238.290053)
			(xy 127.574992 -238.264607) (xy 127.53557 -238.23242) (xy 127.501822 -238.194326) (xy 127.474621 -238.151312)
			(xy 127.454673 -238.104492) (xy 127.442494 -238.055078) (xy 127.438399 -238.00435) (xy 126.52756 -238.00435)
			(xy 126.52756 -238.116618) (xy 126.528019 -238.126496) (xy 126.535458 -238.144798) (xy 126.542038 -238.152178)
			(xy 126.542292 -238.152432) (xy 126.905512 -238.515652) (xy 126.91236 -238.523049) (xy 126.920089 -238.541648)
			(xy 126.920498 -238.55172) (xy 126.920498 -238.645446) (xy 126.920994 -238.655448) (xy 126.928662 -238.673924)
			(xy 126.942813 -238.688063) (xy 126.961296 -238.695715) (xy 126.971298 -238.696246) (xy 126.985268 -238.696246)
			(xy 127.009398 -238.681768) (xy 127.016002 -238.669576) (xy 127.027525 -238.649103) (xy 127.055881 -238.611649)
			(xy 127.089638 -238.578978) (xy 127.127998 -238.55186) (xy 127.170058 -238.530935) (xy 127.214826 -238.516695)
			(xy 127.261245 -238.509478) (xy 127.284734 -238.509048) (xy 127.309991 -238.509572) (xy 127.359816 -238.517891)
			(xy 127.407592 -238.534297) (xy 127.452016 -238.558343) (xy 127.491877 -238.589372) (xy 127.526088 -238.626539)
			(xy 127.553715 -238.668829) (xy 127.574005 -238.715089) (xy 127.586404 -238.764058) (xy 127.590572 -238.814356)
			(xy 127.908553 -238.814356) (xy 127.912648 -238.763628) (xy 127.924827 -238.714214) (xy 127.944775 -238.667394)
			(xy 127.971976 -238.62438) (xy 128.005724 -238.586286) (xy 128.045146 -238.554099) (xy 128.08922 -238.528653)
			(xy 128.136806 -238.510606) (xy 128.18667 -238.500426) (xy 128.237522 -238.498377) (xy 128.288043 -238.504511)
			(xy 128.336927 -238.518671) (xy 128.382906 -238.540488) (xy 128.42479 -238.569398) (xy 128.461494 -238.604653)
			(xy 128.492067 -238.645339) (xy 128.515718 -238.690402) (xy 128.531834 -238.738676) (xy 128.539998 -238.78891)
			(xy 128.54051 -238.814356) (xy 128.848607 -238.814356) (xy 128.852702 -238.763628) (xy 128.864881 -238.714214)
			(xy 128.884829 -238.667394) (xy 128.91203 -238.62438) (xy 128.945778 -238.586286) (xy 128.9852 -238.554099)
			(xy 129.029274 -238.528653) (xy 129.07686 -238.510606) (xy 129.126724 -238.500426) (xy 129.177576 -238.498377)
			(xy 129.228097 -238.504511) (xy 129.276981 -238.518671) (xy 129.32296 -238.540488) (xy 129.364844 -238.569398)
			(xy 129.401548 -238.604653) (xy 129.432121 -238.645339) (xy 129.455772 -238.690402) (xy 129.471888 -238.738676)
			(xy 129.480052 -238.78891) (xy 129.480564 -238.814356) (xy 129.798838 -238.814356) (xy 129.802798 -238.765302)
			(xy 129.814575 -238.717518) (xy 129.833866 -238.672242) (xy 129.860169 -238.630646) (xy 129.892804 -238.593809)
			(xy 129.930925 -238.562684) (xy 129.973546 -238.538077) (xy 130.019562 -238.520625) (xy 130.067781 -238.510781)
			(xy 130.116956 -238.5088) (xy 130.165811 -238.514732) (xy 130.213082 -238.528424) (xy 130.257544 -238.549522)
			(xy 130.298047 -238.577478) (xy 130.33354 -238.61157) (xy 130.363105 -238.650914) (xy 130.385976 -238.694491)
			(xy 130.40156 -238.741172) (xy 130.409455 -238.789749) (xy 130.40995 -238.814356) (xy 130.728461 -238.814356)
			(xy 130.732556 -238.763628) (xy 130.744735 -238.714214) (xy 130.764683 -238.667394) (xy 130.791884 -238.62438)
			(xy 130.825632 -238.586286) (xy 130.865054 -238.554099) (xy 130.909128 -238.528653) (xy 130.956714 -238.510606)
			(xy 131.006578 -238.500426) (xy 131.05743 -238.498377) (xy 131.107951 -238.504511) (xy 131.156835 -238.518671)
			(xy 131.202814 -238.540488) (xy 131.244698 -238.569398) (xy 131.281402 -238.604653) (xy 131.311975 -238.645339)
			(xy 131.335626 -238.690402) (xy 131.351742 -238.738676) (xy 131.359906 -238.78891) (xy 131.360418 -238.814356)
			(xy 131.678946 -238.814356) (xy 131.682906 -238.765302) (xy 131.694683 -238.717518) (xy 131.713974 -238.672242)
			(xy 131.740277 -238.630646) (xy 131.772912 -238.593809) (xy 131.811033 -238.562684) (xy 131.853654 -238.538077)
			(xy 131.89967 -238.520625) (xy 131.947889 -238.510781) (xy 131.997064 -238.5088) (xy 132.045919 -238.514732)
			(xy 132.09319 -238.528424) (xy 132.137652 -238.549522) (xy 132.178155 -238.577478) (xy 132.213648 -238.61157)
			(xy 132.243213 -238.650914) (xy 132.266084 -238.694491) (xy 132.281668 -238.741172) (xy 132.289563 -238.789749)
			(xy 132.290058 -238.814356) (xy 132.608569 -238.814356) (xy 132.612664 -238.763628) (xy 132.624843 -238.714214)
			(xy 132.644791 -238.667394) (xy 132.671992 -238.62438) (xy 132.70574 -238.586286) (xy 132.745162 -238.554099)
			(xy 132.789236 -238.528653) (xy 132.836822 -238.510606) (xy 132.886686 -238.500426) (xy 132.937538 -238.498377)
			(xy 132.988059 -238.504511) (xy 133.036943 -238.518671) (xy 133.082922 -238.540488) (xy 133.124806 -238.569398)
			(xy 133.16151 -238.604653) (xy 133.192083 -238.645339) (xy 133.215734 -238.690402) (xy 133.23185 -238.738676)
			(xy 133.240014 -238.78891) (xy 133.240526 -238.814356) (xy 133.559054 -238.814356) (xy 133.563014 -238.765302)
			(xy 133.574791 -238.717518) (xy 133.594082 -238.672242) (xy 133.620385 -238.630646) (xy 133.65302 -238.593809)
			(xy 133.691141 -238.562684) (xy 133.733762 -238.538077) (xy 133.779778 -238.520625) (xy 133.827997 -238.510781)
			(xy 133.877172 -238.5088) (xy 133.926027 -238.514732) (xy 133.973298 -238.528424) (xy 134.01776 -238.549522)
			(xy 134.058263 -238.577478) (xy 134.093756 -238.61157) (xy 134.123321 -238.650914) (xy 134.146192 -238.694491)
			(xy 134.161776 -238.741172) (xy 134.169671 -238.789749) (xy 134.170166 -238.814356) (xy 134.498854 -238.814356)
			(xy 134.502814 -238.765302) (xy 134.514591 -238.717518) (xy 134.533882 -238.672242) (xy 134.560185 -238.630646)
			(xy 134.59282 -238.593809) (xy 134.630941 -238.562684) (xy 134.673562 -238.538077) (xy 134.719578 -238.520625)
			(xy 134.767797 -238.510781) (xy 134.816972 -238.5088) (xy 134.865827 -238.514732) (xy 134.913098 -238.528424)
			(xy 134.95756 -238.549522) (xy 134.998063 -238.577478) (xy 135.033556 -238.61157) (xy 135.063121 -238.650914)
			(xy 135.085992 -238.694491) (xy 135.101576 -238.741172) (xy 135.109471 -238.789749) (xy 135.109966 -238.814356)
			(xy 135.438908 -238.814356) (xy 135.442868 -238.765302) (xy 135.454645 -238.717518) (xy 135.473936 -238.672242)
			(xy 135.500239 -238.630646) (xy 135.532874 -238.593809) (xy 135.570995 -238.562684) (xy 135.613616 -238.538077)
			(xy 135.659632 -238.520625) (xy 135.707851 -238.510781) (xy 135.757026 -238.5088) (xy 135.805881 -238.514732)
			(xy 135.853152 -238.528424) (xy 135.897614 -238.549522) (xy 135.938117 -238.577478) (xy 135.97361 -238.61157)
			(xy 136.003175 -238.650914) (xy 136.026046 -238.694491) (xy 136.04163 -238.741172) (xy 136.049525 -238.789749)
			(xy 136.05002 -238.814356) (xy 136.049525 -238.838963) (xy 136.04163 -238.88754) (xy 136.026046 -238.934221)
			(xy 136.003175 -238.977798) (xy 135.97361 -239.017142) (xy 135.938117 -239.051234) (xy 135.897614 -239.07919)
			(xy 135.853152 -239.100288) (xy 135.805881 -239.11398) (xy 135.757026 -239.119912) (xy 135.707851 -239.117931)
			(xy 135.659632 -239.108087) (xy 135.613616 -239.090635) (xy 135.570995 -239.066028) (xy 135.532874 -239.034903)
			(xy 135.500239 -238.998066) (xy 135.473936 -238.95647) (xy 135.454645 -238.911194) (xy 135.442868 -238.86341)
			(xy 135.438908 -238.814356) (xy 135.109966 -238.814356) (xy 135.109471 -238.838963) (xy 135.101576 -238.88754)
			(xy 135.085992 -238.934221) (xy 135.063121 -238.977798) (xy 135.033556 -239.017142) (xy 134.998063 -239.051234)
			(xy 134.95756 -239.07919) (xy 134.913098 -239.100288) (xy 134.865827 -239.11398) (xy 134.816972 -239.119912)
			(xy 134.767797 -239.117931) (xy 134.719578 -239.108087) (xy 134.673562 -239.090635) (xy 134.630941 -239.066028)
			(xy 134.59282 -239.034903) (xy 134.560185 -238.998066) (xy 134.533882 -238.95647) (xy 134.514591 -238.911194)
			(xy 134.502814 -238.86341) (xy 134.498854 -238.814356) (xy 134.170166 -238.814356) (xy 134.169671 -238.838963)
			(xy 134.161776 -238.88754) (xy 134.146192 -238.934221) (xy 134.123321 -238.977798) (xy 134.093756 -239.017142)
			(xy 134.058263 -239.051234) (xy 134.01776 -239.07919) (xy 133.973298 -239.100288) (xy 133.926027 -239.11398)
			(xy 133.877172 -239.119912) (xy 133.827997 -239.117931) (xy 133.779778 -239.108087) (xy 133.733762 -239.090635)
			(xy 133.691141 -239.066028) (xy 133.65302 -239.034903) (xy 133.620385 -238.998066) (xy 133.594082 -238.95647)
			(xy 133.574791 -238.911194) (xy 133.563014 -238.86341) (xy 133.559054 -238.814356) (xy 133.240526 -238.814356)
			(xy 133.240014 -238.839802) (xy 133.23185 -238.890036) (xy 133.215734 -238.93831) (xy 133.192083 -238.983373)
			(xy 133.16151 -239.024059) (xy 133.124806 -239.059314) (xy 133.082922 -239.088224) (xy 133.036943 -239.110041)
			(xy 132.988059 -239.124201) (xy 132.937538 -239.130335) (xy 132.886686 -239.128286) (xy 132.836822 -239.118106)
			(xy 132.789236 -239.100059) (xy 132.745162 -239.074613) (xy 132.70574 -239.042426) (xy 132.671992 -239.004332)
			(xy 132.644791 -238.961318) (xy 132.624843 -238.914498) (xy 132.612664 -238.865084) (xy 132.608569 -238.814356)
			(xy 132.290058 -238.814356) (xy 132.289563 -238.838963) (xy 132.281668 -238.88754) (xy 132.266084 -238.934221)
			(xy 132.243213 -238.977798) (xy 132.213648 -239.017142) (xy 132.178155 -239.051234) (xy 132.137652 -239.07919)
			(xy 132.09319 -239.100288) (xy 132.045919 -239.11398) (xy 131.997064 -239.119912) (xy 131.947889 -239.117931)
			(xy 131.89967 -239.108087) (xy 131.853654 -239.090635) (xy 131.811033 -239.066028) (xy 131.772912 -239.034903)
			(xy 131.740277 -238.998066) (xy 131.713974 -238.95647) (xy 131.694683 -238.911194) (xy 131.682906 -238.86341)
			(xy 131.678946 -238.814356) (xy 131.360418 -238.814356) (xy 131.359906 -238.839802) (xy 131.351742 -238.890036)
			(xy 131.335626 -238.93831) (xy 131.311975 -238.983373) (xy 131.281402 -239.024059) (xy 131.244698 -239.059314)
			(xy 131.202814 -239.088224) (xy 131.156835 -239.110041) (xy 131.107951 -239.124201) (xy 131.05743 -239.130335)
			(xy 131.006578 -239.128286) (xy 130.956714 -239.118106) (xy 130.909128 -239.100059) (xy 130.865054 -239.074613)
			(xy 130.825632 -239.042426) (xy 130.791884 -239.004332) (xy 130.764683 -238.961318) (xy 130.744735 -238.914498)
			(xy 130.732556 -238.865084) (xy 130.728461 -238.814356) (xy 130.40995 -238.814356) (xy 130.409455 -238.838963)
			(xy 130.40156 -238.88754) (xy 130.385976 -238.934221) (xy 130.363105 -238.977798) (xy 130.33354 -239.017142)
			(xy 130.298047 -239.051234) (xy 130.257544 -239.07919) (xy 130.213082 -239.100288) (xy 130.165811 -239.11398)
			(xy 130.116956 -239.119912) (xy 130.067781 -239.117931) (xy 130.019562 -239.108087) (xy 129.973546 -239.090635)
			(xy 129.930925 -239.066028) (xy 129.892804 -239.034903) (xy 129.860169 -238.998066) (xy 129.833866 -238.95647)
			(xy 129.814575 -238.911194) (xy 129.802798 -238.86341) (xy 129.798838 -238.814356) (xy 129.480564 -238.814356)
			(xy 129.480052 -238.839802) (xy 129.471888 -238.890036) (xy 129.455772 -238.93831) (xy 129.432121 -238.983373)
			(xy 129.401548 -239.024059) (xy 129.364844 -239.059314) (xy 129.32296 -239.088224) (xy 129.276981 -239.110041)
			(xy 129.228097 -239.124201) (xy 129.177576 -239.130335) (xy 129.126724 -239.128286) (xy 129.07686 -239.118106)
			(xy 129.029274 -239.100059) (xy 128.9852 -239.074613) (xy 128.945778 -239.042426) (xy 128.91203 -239.004332)
			(xy 128.884829 -238.961318) (xy 128.864881 -238.914498) (xy 128.852702 -238.865084) (xy 128.848607 -238.814356)
			(xy 128.54051 -238.814356) (xy 128.539998 -238.839802) (xy 128.531834 -238.890036) (xy 128.515718 -238.93831)
			(xy 128.492067 -238.983373) (xy 128.461494 -239.024059) (xy 128.42479 -239.059314) (xy 128.382906 -239.088224)
			(xy 128.336927 -239.110041) (xy 128.288043 -239.124201) (xy 128.237522 -239.130335) (xy 128.18667 -239.128286)
			(xy 128.136806 -239.118106) (xy 128.08922 -239.100059) (xy 128.045146 -239.074613) (xy 128.005724 -239.042426)
			(xy 127.971976 -239.004332) (xy 127.944775 -238.961318) (xy 127.924827 -238.914498) (xy 127.912648 -238.865084)
			(xy 127.908553 -238.814356) (xy 127.590572 -238.814356) (xy 127.590576 -238.8144) (xy 127.586404 -238.864742)
			(xy 127.574005 -238.913711) (xy 127.553715 -238.959971) (xy 127.526088 -239.002261) (xy 127.491877 -239.039428)
			(xy 127.452016 -239.070457) (xy 127.407592 -239.094503) (xy 127.359816 -239.110909) (xy 127.309991 -239.119228)
			(xy 127.284734 -239.119664) (xy 127.271971 -239.119524) (xy 127.246538 -239.11736) (xy 127.233934 -239.115346)
			(xy 127.207197 -239.110225) (xy 127.155974 -239.091808) (xy 127.108811 -239.064629) (xy 127.08763 -239.047528)
			(xy 127.0762 -239.037876) (xy 127.04699 -239.034066) (xy 126.949962 -239.079024) (xy 126.941338 -239.083464)
			(xy 126.92801 -239.097536) (xy 126.920882 -239.115559) (xy 126.920498 -239.125252) (xy 126.920498 -239.319054)
			(xy 126.935738 -239.343692) (xy 126.948946 -239.350042) (xy 126.97062 -239.361167) (xy 127.010432 -239.389242)
			(xy 127.045283 -239.423281) (xy 127.074288 -239.462421) (xy 127.096712 -239.505669) (xy 127.111985 -239.551928)
			(xy 127.119722 -239.600026) (xy 127.119723 -239.624362) (xy 127.438399 -239.624362) (xy 127.442494 -239.573634)
			(xy 127.454673 -239.52422) (xy 127.474621 -239.4774) (xy 127.501822 -239.434386) (xy 127.53557 -239.396292)
			(xy 127.574992 -239.364105) (xy 127.619066 -239.338659) (xy 127.666652 -239.320612) (xy 127.716516 -239.310432)
			(xy 127.767368 -239.308383) (xy 127.817889 -239.314517) (xy 127.866773 -239.328677) (xy 127.912752 -239.350494)
			(xy 127.954636 -239.379404) (xy 127.99134 -239.414659) (xy 128.021913 -239.455345) (xy 128.045564 -239.500408)
			(xy 128.06168 -239.548682) (xy 128.069844 -239.598916) (xy 128.070356 -239.624362) (xy 128.388884 -239.624362)
			(xy 128.392844 -239.575308) (xy 128.404621 -239.527524) (xy 128.423912 -239.482248) (xy 128.450215 -239.440652)
			(xy 128.48285 -239.403815) (xy 128.520971 -239.37269) (xy 128.563592 -239.348083) (xy 128.609608 -239.330631)
			(xy 128.657827 -239.320787) (xy 128.707002 -239.318806) (xy 128.755857 -239.324738) (xy 128.803128 -239.33843)
			(xy 128.84759 -239.359528) (xy 128.888093 -239.387484) (xy 128.923586 -239.421576) (xy 128.953151 -239.46092)
			(xy 128.976022 -239.504497) (xy 128.991606 -239.551178) (xy 128.999501 -239.599755) (xy 128.999996 -239.624362)
			(xy 129.318507 -239.624362) (xy 129.322602 -239.573634) (xy 129.334781 -239.52422) (xy 129.354729 -239.4774)
			(xy 129.38193 -239.434386) (xy 129.415678 -239.396292) (xy 129.4551 -239.364105) (xy 129.499174 -239.338659)
			(xy 129.54676 -239.320612) (xy 129.596624 -239.310432) (xy 129.647476 -239.308383) (xy 129.697997 -239.314517)
			(xy 129.746881 -239.328677) (xy 129.79286 -239.350494) (xy 129.834744 -239.379404) (xy 129.871448 -239.414659)
			(xy 129.902021 -239.455345) (xy 129.925672 -239.500408) (xy 129.941788 -239.548682) (xy 129.949952 -239.598916)
			(xy 129.950464 -239.624362) (xy 131.198615 -239.624362) (xy 131.20271 -239.573634) (xy 131.214889 -239.52422)
			(xy 131.234837 -239.4774) (xy 131.262038 -239.434386) (xy 131.295786 -239.396292) (xy 131.335208 -239.364105)
			(xy 131.379282 -239.338659) (xy 131.426868 -239.320612) (xy 131.476732 -239.310432) (xy 131.527584 -239.308383)
			(xy 131.578105 -239.314517) (xy 131.626989 -239.328677) (xy 131.672968 -239.350494) (xy 131.714852 -239.379404)
			(xy 131.751556 -239.414659) (xy 131.782129 -239.455345) (xy 131.80578 -239.500408) (xy 131.821896 -239.548682)
			(xy 131.83006 -239.598916) (xy 131.830572 -239.624362) (xy 132.138415 -239.624362) (xy 132.14251 -239.573634)
			(xy 132.154689 -239.52422) (xy 132.174637 -239.4774) (xy 132.201838 -239.434386) (xy 132.235586 -239.396292)
			(xy 132.275008 -239.364105) (xy 132.319082 -239.338659) (xy 132.366668 -239.320612) (xy 132.416532 -239.310432)
			(xy 132.467384 -239.308383) (xy 132.517905 -239.314517) (xy 132.566789 -239.328677) (xy 132.612768 -239.350494)
			(xy 132.654652 -239.379404) (xy 132.691356 -239.414659) (xy 132.721929 -239.455345) (xy 132.74558 -239.500408)
			(xy 132.761696 -239.548682) (xy 132.76986 -239.598916) (xy 132.770372 -239.624362) (xy 133.0889 -239.624362)
			(xy 133.09286 -239.575308) (xy 133.104637 -239.527524) (xy 133.123928 -239.482248) (xy 133.150231 -239.440652)
			(xy 133.182866 -239.403815) (xy 133.220987 -239.37269) (xy 133.263608 -239.348083) (xy 133.309624 -239.330631)
			(xy 133.357843 -239.320787) (xy 133.407018 -239.318806) (xy 133.455873 -239.324738) (xy 133.503144 -239.33843)
			(xy 133.547606 -239.359528) (xy 133.588109 -239.387484) (xy 133.623602 -239.421576) (xy 133.653167 -239.46092)
			(xy 133.676038 -239.504497) (xy 133.691622 -239.551178) (xy 133.699517 -239.599755) (xy 133.700012 -239.624362)
			(xy 134.028954 -239.624362) (xy 134.032914 -239.575308) (xy 134.044691 -239.527524) (xy 134.063982 -239.482248)
			(xy 134.090285 -239.440652) (xy 134.12292 -239.403815) (xy 134.161041 -239.37269) (xy 134.203662 -239.348083)
			(xy 134.249678 -239.330631) (xy 134.297897 -239.320787) (xy 134.347072 -239.318806) (xy 134.395927 -239.324738)
			(xy 134.443198 -239.33843) (xy 134.48766 -239.359528) (xy 134.528163 -239.387484) (xy 134.563656 -239.421576)
			(xy 134.593221 -239.46092) (xy 134.616092 -239.504497) (xy 134.631676 -239.551178) (xy 134.639571 -239.599755)
			(xy 134.640066 -239.624362) (xy 134.969008 -239.624362) (xy 134.972968 -239.575308) (xy 134.984745 -239.527524)
			(xy 135.004036 -239.482248) (xy 135.030339 -239.440652) (xy 135.062974 -239.403815) (xy 135.101095 -239.37269)
			(xy 135.143716 -239.348083) (xy 135.189732 -239.330631) (xy 135.237951 -239.320787) (xy 135.287126 -239.318806)
			(xy 135.335981 -239.324738) (xy 135.383252 -239.33843) (xy 135.427714 -239.359528) (xy 135.468217 -239.387484)
			(xy 135.50371 -239.421576) (xy 135.533275 -239.46092) (xy 135.556146 -239.504497) (xy 135.57173 -239.551178)
			(xy 135.579625 -239.599755) (xy 135.58012 -239.624362) (xy 135.909062 -239.624362) (xy 135.913022 -239.575308)
			(xy 135.924799 -239.527524) (xy 135.94409 -239.482248) (xy 135.970393 -239.440652) (xy 136.003028 -239.403815)
			(xy 136.041149 -239.37269) (xy 136.08377 -239.348083) (xy 136.129786 -239.330631) (xy 136.178005 -239.320787)
			(xy 136.22718 -239.318806) (xy 136.276035 -239.324738) (xy 136.323306 -239.33843) (xy 136.367768 -239.359528)
			(xy 136.408271 -239.387484) (xy 136.443764 -239.421576) (xy 136.473329 -239.46092) (xy 136.4962 -239.504497)
			(xy 136.511784 -239.551178) (xy 136.519679 -239.599755) (xy 136.520174 -239.624362) (xy 136.519679 -239.648969)
			(xy 136.511784 -239.697546) (xy 136.4962 -239.744227) (xy 136.473329 -239.787804) (xy 136.443764 -239.827148)
			(xy 136.408271 -239.86124) (xy 136.367768 -239.889196) (xy 136.323306 -239.910294) (xy 136.276035 -239.923986)
			(xy 136.22718 -239.929918) (xy 136.178005 -239.927937) (xy 136.129786 -239.918093) (xy 136.08377 -239.900641)
			(xy 136.041149 -239.876034) (xy 136.003028 -239.844909) (xy 135.970393 -239.808072) (xy 135.94409 -239.766476)
			(xy 135.924799 -239.7212) (xy 135.913022 -239.673416) (xy 135.909062 -239.624362) (xy 135.58012 -239.624362)
			(xy 135.579625 -239.648969) (xy 135.57173 -239.697546) (xy 135.556146 -239.744227) (xy 135.533275 -239.787804)
			(xy 135.50371 -239.827148) (xy 135.468217 -239.86124) (xy 135.427714 -239.889196) (xy 135.383252 -239.910294)
			(xy 135.335981 -239.923986) (xy 135.287126 -239.929918) (xy 135.237951 -239.927937) (xy 135.189732 -239.918093)
			(xy 135.143716 -239.900641) (xy 135.101095 -239.876034) (xy 135.062974 -239.844909) (xy 135.030339 -239.808072)
			(xy 135.004036 -239.766476) (xy 134.984745 -239.7212) (xy 134.972968 -239.673416) (xy 134.969008 -239.624362)
			(xy 134.640066 -239.624362) (xy 134.639571 -239.648969) (xy 134.631676 -239.697546) (xy 134.616092 -239.744227)
			(xy 134.593221 -239.787804) (xy 134.563656 -239.827148) (xy 134.528163 -239.86124) (xy 134.48766 -239.889196)
			(xy 134.443198 -239.910294) (xy 134.395927 -239.923986) (xy 134.347072 -239.929918) (xy 134.297897 -239.927937)
			(xy 134.249678 -239.918093) (xy 134.203662 -239.900641) (xy 134.161041 -239.876034) (xy 134.12292 -239.844909)
			(xy 134.090285 -239.808072) (xy 134.063982 -239.766476) (xy 134.044691 -239.7212) (xy 134.032914 -239.673416)
			(xy 134.028954 -239.624362) (xy 133.700012 -239.624362) (xy 133.699517 -239.648969) (xy 133.691622 -239.697546)
			(xy 133.676038 -239.744227) (xy 133.653167 -239.787804) (xy 133.623602 -239.827148) (xy 133.588109 -239.86124)
			(xy 133.547606 -239.889196) (xy 133.503144 -239.910294) (xy 133.455873 -239.923986) (xy 133.407018 -239.929918)
			(xy 133.357843 -239.927937) (xy 133.309624 -239.918093) (xy 133.263608 -239.900641) (xy 133.220987 -239.876034)
			(xy 133.182866 -239.844909) (xy 133.150231 -239.808072) (xy 133.123928 -239.766476) (xy 133.104637 -239.7212)
			(xy 133.09286 -239.673416) (xy 133.0889 -239.624362) (xy 132.770372 -239.624362) (xy 132.76986 -239.649808)
			(xy 132.761696 -239.700042) (xy 132.74558 -239.748316) (xy 132.721929 -239.793379) (xy 132.691356 -239.834065)
			(xy 132.654652 -239.86932) (xy 132.612768 -239.89823) (xy 132.566789 -239.920047) (xy 132.517905 -239.934207)
			(xy 132.467384 -239.940341) (xy 132.416532 -239.938292) (xy 132.366668 -239.928112) (xy 132.319082 -239.910065)
			(xy 132.275008 -239.884619) (xy 132.235586 -239.852432) (xy 132.201838 -239.814338) (xy 132.174637 -239.771324)
			(xy 132.154689 -239.724504) (xy 132.14251 -239.67509) (xy 132.138415 -239.624362) (xy 131.830572 -239.624362)
			(xy 131.83006 -239.649808) (xy 131.821896 -239.700042) (xy 131.80578 -239.748316) (xy 131.782129 -239.793379)
			(xy 131.751556 -239.834065) (xy 131.714852 -239.86932) (xy 131.672968 -239.89823) (xy 131.626989 -239.920047)
			(xy 131.578105 -239.934207) (xy 131.527584 -239.940341) (xy 131.476732 -239.938292) (xy 131.426868 -239.928112)
			(xy 131.379282 -239.910065) (xy 131.335208 -239.884619) (xy 131.295786 -239.852432) (xy 131.262038 -239.814338)
			(xy 131.234837 -239.771324) (xy 131.214889 -239.724504) (xy 131.20271 -239.67509) (xy 131.198615 -239.624362)
			(xy 129.950464 -239.624362) (xy 129.949952 -239.649808) (xy 129.941788 -239.700042) (xy 129.925672 -239.748316)
			(xy 129.902021 -239.793379) (xy 129.871448 -239.834065) (xy 129.834744 -239.86932) (xy 129.79286 -239.89823)
			(xy 129.746881 -239.920047) (xy 129.697997 -239.934207) (xy 129.647476 -239.940341) (xy 129.596624 -239.938292)
			(xy 129.54676 -239.928112) (xy 129.499174 -239.910065) (xy 129.4551 -239.884619) (xy 129.415678 -239.852432)
			(xy 129.38193 -239.814338) (xy 129.354729 -239.771324) (xy 129.334781 -239.724504) (xy 129.322602 -239.67509)
			(xy 129.318507 -239.624362) (xy 128.999996 -239.624362) (xy 128.999501 -239.648969) (xy 128.991606 -239.697546)
			(xy 128.976022 -239.744227) (xy 128.953151 -239.787804) (xy 128.923586 -239.827148) (xy 128.888093 -239.86124)
			(xy 128.84759 -239.889196) (xy 128.803128 -239.910294) (xy 128.755857 -239.923986) (xy 128.707002 -239.929918)
			(xy 128.657827 -239.927937) (xy 128.609608 -239.918093) (xy 128.563592 -239.900641) (xy 128.520971 -239.876034)
			(xy 128.48285 -239.844909) (xy 128.450215 -239.808072) (xy 128.423912 -239.766476) (xy 128.404621 -239.7212)
			(xy 128.392844 -239.673416) (xy 128.388884 -239.624362) (xy 128.070356 -239.624362) (xy 128.069844 -239.649808)
			(xy 128.06168 -239.700042) (xy 128.045564 -239.748316) (xy 128.021913 -239.793379) (xy 127.99134 -239.834065)
			(xy 127.954636 -239.86932) (xy 127.912752 -239.89823) (xy 127.866773 -239.920047) (xy 127.817889 -239.934207)
			(xy 127.767368 -239.940341) (xy 127.716516 -239.938292) (xy 127.666652 -239.928112) (xy 127.619066 -239.910065)
			(xy 127.574992 -239.884619) (xy 127.53557 -239.852432) (xy 127.501822 -239.814338) (xy 127.474621 -239.771324)
			(xy 127.454673 -239.724504) (xy 127.442494 -239.67509) (xy 127.438399 -239.624362) (xy 127.119723 -239.624362)
			(xy 127.119724 -239.648741) (xy 127.111993 -239.696839) (xy 127.096725 -239.7431) (xy 127.074306 -239.786351)
			(xy 127.045305 -239.825494) (xy 127.010458 -239.859537) (xy 126.970649 -239.887616) (xy 126.948946 -239.898682)
			(xy 126.935738 -239.905032) (xy 126.920498 -239.92967) (xy 126.920498 -240.434368) (xy 127.908553 -240.434368)
			(xy 127.912648 -240.38364) (xy 127.924827 -240.334226) (xy 127.944775 -240.287406) (xy 127.971976 -240.244392)
			(xy 128.005724 -240.206298) (xy 128.045146 -240.174111) (xy 128.08922 -240.148665) (xy 128.136806 -240.130618)
			(xy 128.18667 -240.120438) (xy 128.237522 -240.118389) (xy 128.288043 -240.124523) (xy 128.336927 -240.138683)
			(xy 128.382906 -240.1605) (xy 128.42479 -240.18941) (xy 128.461494 -240.224665) (xy 128.492067 -240.265351)
			(xy 128.515718 -240.310414) (xy 128.531834 -240.358688) (xy 128.539998 -240.408922) (xy 128.54051 -240.434368)
			(xy 128.848607 -240.434368) (xy 128.852702 -240.38364) (xy 128.864881 -240.334226) (xy 128.884829 -240.287406)
			(xy 128.91203 -240.244392) (xy 128.945778 -240.206298) (xy 128.9852 -240.174111) (xy 129.029274 -240.148665)
			(xy 129.07686 -240.130618) (xy 129.126724 -240.120438) (xy 129.177576 -240.118389) (xy 129.228097 -240.124523)
			(xy 129.276981 -240.138683) (xy 129.32296 -240.1605) (xy 129.364844 -240.18941) (xy 129.401548 -240.224665)
			(xy 129.432121 -240.265351) (xy 129.455772 -240.310414) (xy 129.471888 -240.358688) (xy 129.480052 -240.408922)
			(xy 129.480564 -240.434368) (xy 129.798838 -240.434368) (xy 129.802798 -240.385314) (xy 129.814575 -240.33753)
			(xy 129.833866 -240.292254) (xy 129.860169 -240.250658) (xy 129.892804 -240.213821) (xy 129.930925 -240.182696)
			(xy 129.973546 -240.158089) (xy 130.019562 -240.140637) (xy 130.067781 -240.130793) (xy 130.116956 -240.128812)
			(xy 130.165811 -240.134744) (xy 130.213082 -240.148436) (xy 130.257544 -240.169534) (xy 130.298047 -240.19749)
			(xy 130.33354 -240.231582) (xy 130.363105 -240.270926) (xy 130.385976 -240.314503) (xy 130.40156 -240.361184)
			(xy 130.409455 -240.409761) (xy 130.40995 -240.434368) (xy 130.728461 -240.434368) (xy 130.732556 -240.38364)
			(xy 130.744735 -240.334226) (xy 130.764683 -240.287406) (xy 130.791884 -240.244392) (xy 130.825632 -240.206298)
			(xy 130.865054 -240.174111) (xy 130.909128 -240.148665) (xy 130.956714 -240.130618) (xy 131.006578 -240.120438)
			(xy 131.05743 -240.118389) (xy 131.107951 -240.124523) (xy 131.156835 -240.138683) (xy 131.202814 -240.1605)
			(xy 131.244698 -240.18941) (xy 131.281402 -240.224665) (xy 131.311975 -240.265351) (xy 131.335626 -240.310414)
			(xy 131.351742 -240.358688) (xy 131.359906 -240.408922) (xy 131.360418 -240.434368) (xy 131.678946 -240.434368)
			(xy 131.682906 -240.385314) (xy 131.694683 -240.33753) (xy 131.713974 -240.292254) (xy 131.740277 -240.250658)
			(xy 131.772912 -240.213821) (xy 131.811033 -240.182696) (xy 131.853654 -240.158089) (xy 131.89967 -240.140637)
			(xy 131.947889 -240.130793) (xy 131.997064 -240.128812) (xy 132.045919 -240.134744) (xy 132.09319 -240.148436)
			(xy 132.137652 -240.169534) (xy 132.178155 -240.19749) (xy 132.213648 -240.231582) (xy 132.243213 -240.270926)
			(xy 132.266084 -240.314503) (xy 132.281668 -240.361184) (xy 132.289563 -240.409761) (xy 132.290058 -240.434368)
			(xy 132.608569 -240.434368) (xy 132.612664 -240.38364) (xy 132.624843 -240.334226) (xy 132.644791 -240.287406)
			(xy 132.671992 -240.244392) (xy 132.70574 -240.206298) (xy 132.745162 -240.174111) (xy 132.789236 -240.148665)
			(xy 132.836822 -240.130618) (xy 132.886686 -240.120438) (xy 132.937538 -240.118389) (xy 132.988059 -240.124523)
			(xy 133.036943 -240.138683) (xy 133.082922 -240.1605) (xy 133.124806 -240.18941) (xy 133.16151 -240.224665)
			(xy 133.192083 -240.265351) (xy 133.215734 -240.310414) (xy 133.23185 -240.358688) (xy 133.240014 -240.408922)
			(xy 133.240526 -240.434368) (xy 133.559054 -240.434368) (xy 133.563014 -240.385314) (xy 133.574791 -240.33753)
			(xy 133.594082 -240.292254) (xy 133.620385 -240.250658) (xy 133.65302 -240.213821) (xy 133.691141 -240.182696)
			(xy 133.733762 -240.158089) (xy 133.779778 -240.140637) (xy 133.827997 -240.130793) (xy 133.877172 -240.128812)
			(xy 133.926027 -240.134744) (xy 133.973298 -240.148436) (xy 134.01776 -240.169534) (xy 134.058263 -240.19749)
			(xy 134.093756 -240.231582) (xy 134.123321 -240.270926) (xy 134.146192 -240.314503) (xy 134.161776 -240.361184)
			(xy 134.169671 -240.409761) (xy 134.170166 -240.434368) (xy 134.498854 -240.434368) (xy 134.502814 -240.385314)
			(xy 134.514591 -240.33753) (xy 134.533882 -240.292254) (xy 134.560185 -240.250658) (xy 134.59282 -240.213821)
			(xy 134.630941 -240.182696) (xy 134.673562 -240.158089) (xy 134.719578 -240.140637) (xy 134.767797 -240.130793)
			(xy 134.816972 -240.128812) (xy 134.865827 -240.134744) (xy 134.913098 -240.148436) (xy 134.95756 -240.169534)
			(xy 134.998063 -240.19749) (xy 135.033556 -240.231582) (xy 135.063121 -240.270926) (xy 135.085992 -240.314503)
			(xy 135.101576 -240.361184) (xy 135.109471 -240.409761) (xy 135.109966 -240.434368) (xy 135.438908 -240.434368)
			(xy 135.442868 -240.385314) (xy 135.454645 -240.33753) (xy 135.473936 -240.292254) (xy 135.500239 -240.250658)
			(xy 135.532874 -240.213821) (xy 135.570995 -240.182696) (xy 135.613616 -240.158089) (xy 135.659632 -240.140637)
			(xy 135.707851 -240.130793) (xy 135.757026 -240.128812) (xy 135.805881 -240.134744) (xy 135.853152 -240.148436)
			(xy 135.897614 -240.169534) (xy 135.938117 -240.19749) (xy 135.97361 -240.231582) (xy 136.003175 -240.270926)
			(xy 136.026046 -240.314503) (xy 136.04163 -240.361184) (xy 136.049525 -240.409761) (xy 136.05002 -240.434368)
			(xy 136.049525 -240.458975) (xy 136.04163 -240.507552) (xy 136.026046 -240.554233) (xy 136.003175 -240.59781)
			(xy 135.97361 -240.637154) (xy 135.938117 -240.671246) (xy 135.897614 -240.699202) (xy 135.853152 -240.7203)
			(xy 135.805881 -240.733992) (xy 135.757026 -240.739924) (xy 135.707851 -240.737943) (xy 135.659632 -240.728099)
			(xy 135.613616 -240.710647) (xy 135.570995 -240.68604) (xy 135.532874 -240.654915) (xy 135.500239 -240.618078)
			(xy 135.473936 -240.576482) (xy 135.454645 -240.531206) (xy 135.442868 -240.483422) (xy 135.438908 -240.434368)
			(xy 135.109966 -240.434368) (xy 135.109471 -240.458975) (xy 135.101576 -240.507552) (xy 135.085992 -240.554233)
			(xy 135.063121 -240.59781) (xy 135.033556 -240.637154) (xy 134.998063 -240.671246) (xy 134.95756 -240.699202)
			(xy 134.913098 -240.7203) (xy 134.865827 -240.733992) (xy 134.816972 -240.739924) (xy 134.767797 -240.737943)
			(xy 134.719578 -240.728099) (xy 134.673562 -240.710647) (xy 134.630941 -240.68604) (xy 134.59282 -240.654915)
			(xy 134.560185 -240.618078) (xy 134.533882 -240.576482) (xy 134.514591 -240.531206) (xy 134.502814 -240.483422)
			(xy 134.498854 -240.434368) (xy 134.170166 -240.434368) (xy 134.169671 -240.458975) (xy 134.161776 -240.507552)
			(xy 134.146192 -240.554233) (xy 134.123321 -240.59781) (xy 134.093756 -240.637154) (xy 134.058263 -240.671246)
			(xy 134.01776 -240.699202) (xy 133.973298 -240.7203) (xy 133.926027 -240.733992) (xy 133.877172 -240.739924)
			(xy 133.827997 -240.737943) (xy 133.779778 -240.728099) (xy 133.733762 -240.710647) (xy 133.691141 -240.68604)
			(xy 133.65302 -240.654915) (xy 133.620385 -240.618078) (xy 133.594082 -240.576482) (xy 133.574791 -240.531206)
			(xy 133.563014 -240.483422) (xy 133.559054 -240.434368) (xy 133.240526 -240.434368) (xy 133.240014 -240.459814)
			(xy 133.23185 -240.510048) (xy 133.215734 -240.558322) (xy 133.192083 -240.603385) (xy 133.16151 -240.644071)
			(xy 133.124806 -240.679326) (xy 133.082922 -240.708236) (xy 133.036943 -240.730053) (xy 132.988059 -240.744213)
			(xy 132.937538 -240.750347) (xy 132.886686 -240.748298) (xy 132.836822 -240.738118) (xy 132.789236 -240.720071)
			(xy 132.745162 -240.694625) (xy 132.70574 -240.662438) (xy 132.671992 -240.624344) (xy 132.644791 -240.58133)
			(xy 132.624843 -240.53451) (xy 132.612664 -240.485096) (xy 132.608569 -240.434368) (xy 132.290058 -240.434368)
			(xy 132.289563 -240.458975) (xy 132.281668 -240.507552) (xy 132.266084 -240.554233) (xy 132.243213 -240.59781)
			(xy 132.213648 -240.637154) (xy 132.178155 -240.671246) (xy 132.137652 -240.699202) (xy 132.09319 -240.7203)
			(xy 132.045919 -240.733992) (xy 131.997064 -240.739924) (xy 131.947889 -240.737943) (xy 131.89967 -240.728099)
			(xy 131.853654 -240.710647) (xy 131.811033 -240.68604) (xy 131.772912 -240.654915) (xy 131.740277 -240.618078)
			(xy 131.713974 -240.576482) (xy 131.694683 -240.531206) (xy 131.682906 -240.483422) (xy 131.678946 -240.434368)
			(xy 131.360418 -240.434368) (xy 131.359906 -240.459814) (xy 131.351742 -240.510048) (xy 131.335626 -240.558322)
			(xy 131.311975 -240.603385) (xy 131.281402 -240.644071) (xy 131.244698 -240.679326) (xy 131.202814 -240.708236)
			(xy 131.156835 -240.730053) (xy 131.107951 -240.744213) (xy 131.05743 -240.750347) (xy 131.006578 -240.748298)
			(xy 130.956714 -240.738118) (xy 130.909128 -240.720071) (xy 130.865054 -240.694625) (xy 130.825632 -240.662438)
			(xy 130.791884 -240.624344) (xy 130.764683 -240.58133) (xy 130.744735 -240.53451) (xy 130.732556 -240.485096)
			(xy 130.728461 -240.434368) (xy 130.40995 -240.434368) (xy 130.409455 -240.458975) (xy 130.40156 -240.507552)
			(xy 130.385976 -240.554233) (xy 130.363105 -240.59781) (xy 130.33354 -240.637154) (xy 130.298047 -240.671246)
			(xy 130.257544 -240.699202) (xy 130.213082 -240.7203) (xy 130.165811 -240.733992) (xy 130.116956 -240.739924)
			(xy 130.067781 -240.737943) (xy 130.019562 -240.728099) (xy 129.973546 -240.710647) (xy 129.930925 -240.68604)
			(xy 129.892804 -240.654915) (xy 129.860169 -240.618078) (xy 129.833866 -240.576482) (xy 129.814575 -240.531206)
			(xy 129.802798 -240.483422) (xy 129.798838 -240.434368) (xy 129.480564 -240.434368) (xy 129.480052 -240.459814)
			(xy 129.471888 -240.510048) (xy 129.455772 -240.558322) (xy 129.432121 -240.603385) (xy 129.401548 -240.644071)
			(xy 129.364844 -240.679326) (xy 129.32296 -240.708236) (xy 129.276981 -240.730053) (xy 129.228097 -240.744213)
			(xy 129.177576 -240.750347) (xy 129.126724 -240.748298) (xy 129.07686 -240.738118) (xy 129.029274 -240.720071)
			(xy 128.9852 -240.694625) (xy 128.945778 -240.662438) (xy 128.91203 -240.624344) (xy 128.884829 -240.58133)
			(xy 128.864881 -240.53451) (xy 128.852702 -240.485096) (xy 128.848607 -240.434368) (xy 128.54051 -240.434368)
			(xy 128.539998 -240.459814) (xy 128.531834 -240.510048) (xy 128.515718 -240.558322) (xy 128.492067 -240.603385)
			(xy 128.461494 -240.644071) (xy 128.42479 -240.679326) (xy 128.382906 -240.708236) (xy 128.336927 -240.730053)
			(xy 128.288043 -240.744213) (xy 128.237522 -240.750347) (xy 128.18667 -240.748298) (xy 128.136806 -240.738118)
			(xy 128.08922 -240.720071) (xy 128.045146 -240.694625) (xy 128.005724 -240.662438) (xy 127.971976 -240.624344)
			(xy 127.944775 -240.58133) (xy 127.924827 -240.53451) (xy 127.912648 -240.485096) (xy 127.908553 -240.434368)
			(xy 126.920498 -240.434368) (xy 126.920498 -240.939066) (xy 126.935738 -240.963704) (xy 126.948946 -240.970054)
			(xy 126.970619 -240.98118) (xy 127.010429 -241.009254) (xy 127.045278 -241.043292) (xy 127.074281 -241.082431)
			(xy 127.096703 -241.125678) (xy 127.111976 -241.171936) (xy 127.119711 -241.220032) (xy 127.119712 -241.244374)
			(xy 127.438399 -241.244374) (xy 127.442494 -241.193646) (xy 127.454673 -241.144232) (xy 127.474621 -241.097412)
			(xy 127.501822 -241.054398) (xy 127.53557 -241.016304) (xy 127.574992 -240.984117) (xy 127.619066 -240.958671)
			(xy 127.666652 -240.940624) (xy 127.716516 -240.930444) (xy 127.767368 -240.928395) (xy 127.817889 -240.934529)
			(xy 127.866773 -240.948689) (xy 127.912752 -240.970506) (xy 127.954636 -240.999416) (xy 127.99134 -241.034671)
			(xy 128.021913 -241.075357) (xy 128.045564 -241.12042) (xy 128.06168 -241.168694) (xy 128.069844 -241.218928)
			(xy 128.070356 -241.244374) (xy 128.388884 -241.244374) (xy 128.392844 -241.19532) (xy 128.404621 -241.147536)
			(xy 128.423912 -241.10226) (xy 128.450215 -241.060664) (xy 128.48285 -241.023827) (xy 128.520971 -240.992702)
			(xy 128.563592 -240.968095) (xy 128.609608 -240.950643) (xy 128.657827 -240.940799) (xy 128.707002 -240.938818)
			(xy 128.755857 -240.94475) (xy 128.803128 -240.958442) (xy 128.84759 -240.97954) (xy 128.888093 -241.007496)
			(xy 128.923586 -241.041588) (xy 128.953151 -241.080932) (xy 128.976022 -241.124509) (xy 128.991606 -241.17119)
			(xy 128.999501 -241.219767) (xy 128.999996 -241.244374) (xy 129.318507 -241.244374) (xy 129.322602 -241.193646)
			(xy 129.334781 -241.144232) (xy 129.354729 -241.097412) (xy 129.38193 -241.054398) (xy 129.415678 -241.016304)
			(xy 129.4551 -240.984117) (xy 129.499174 -240.958671) (xy 129.54676 -240.940624) (xy 129.596624 -240.930444)
			(xy 129.647476 -240.928395) (xy 129.697997 -240.934529) (xy 129.746881 -240.948689) (xy 129.79286 -240.970506)
			(xy 129.834744 -240.999416) (xy 129.871448 -241.034671) (xy 129.902021 -241.075357) (xy 129.925672 -241.12042)
			(xy 129.941788 -241.168694) (xy 129.949952 -241.218928) (xy 129.950464 -241.244374) (xy 130.268992 -241.244374)
			(xy 130.272952 -241.19532) (xy 130.284729 -241.147536) (xy 130.30402 -241.10226) (xy 130.330323 -241.060664)
			(xy 130.362958 -241.023827) (xy 130.401079 -240.992702) (xy 130.4437 -240.968095) (xy 130.489716 -240.950643)
			(xy 130.537935 -240.940799) (xy 130.58711 -240.938818) (xy 130.635965 -240.94475) (xy 130.683236 -240.958442)
			(xy 130.727698 -240.97954) (xy 130.768201 -241.007496) (xy 130.803694 -241.041588) (xy 130.833259 -241.080932)
			(xy 130.85613 -241.124509) (xy 130.871714 -241.17119) (xy 130.879609 -241.219767) (xy 130.880104 -241.244374)
			(xy 131.198615 -241.244374) (xy 131.20271 -241.193646) (xy 131.214889 -241.144232) (xy 131.234837 -241.097412)
			(xy 131.262038 -241.054398) (xy 131.295786 -241.016304) (xy 131.335208 -240.984117) (xy 131.379282 -240.958671)
			(xy 131.426868 -240.940624) (xy 131.476732 -240.930444) (xy 131.527584 -240.928395) (xy 131.578105 -240.934529)
			(xy 131.626989 -240.948689) (xy 131.672968 -240.970506) (xy 131.714852 -240.999416) (xy 131.751556 -241.034671)
			(xy 131.782129 -241.075357) (xy 131.80578 -241.12042) (xy 131.821896 -241.168694) (xy 131.83006 -241.218928)
			(xy 131.830572 -241.244374) (xy 132.138415 -241.244374) (xy 132.14251 -241.193646) (xy 132.154689 -241.144232)
			(xy 132.174637 -241.097412) (xy 132.201838 -241.054398) (xy 132.235586 -241.016304) (xy 132.275008 -240.984117)
			(xy 132.319082 -240.958671) (xy 132.366668 -240.940624) (xy 132.416532 -240.930444) (xy 132.467384 -240.928395)
			(xy 132.517905 -240.934529) (xy 132.566789 -240.948689) (xy 132.612768 -240.970506) (xy 132.654652 -240.999416)
			(xy 132.691356 -241.034671) (xy 132.721929 -241.075357) (xy 132.74558 -241.12042) (xy 132.761696 -241.168694)
			(xy 132.76986 -241.218928) (xy 132.770372 -241.244374) (xy 133.0889 -241.244374) (xy 133.09286 -241.19532)
			(xy 133.104637 -241.147536) (xy 133.123928 -241.10226) (xy 133.150231 -241.060664) (xy 133.182866 -241.023827)
			(xy 133.220987 -240.992702) (xy 133.263608 -240.968095) (xy 133.309624 -240.950643) (xy 133.357843 -240.940799)
			(xy 133.407018 -240.938818) (xy 133.455873 -240.94475) (xy 133.503144 -240.958442) (xy 133.547606 -240.97954)
			(xy 133.588109 -241.007496) (xy 133.623602 -241.041588) (xy 133.653167 -241.080932) (xy 133.676038 -241.124509)
			(xy 133.691622 -241.17119) (xy 133.699517 -241.219767) (xy 133.700012 -241.244374) (xy 134.028954 -241.244374)
			(xy 134.032914 -241.19532) (xy 134.044691 -241.147536) (xy 134.063982 -241.10226) (xy 134.090285 -241.060664)
			(xy 134.12292 -241.023827) (xy 134.161041 -240.992702) (xy 134.203662 -240.968095) (xy 134.249678 -240.950643)
			(xy 134.297897 -240.940799) (xy 134.347072 -240.938818) (xy 134.395927 -240.94475) (xy 134.443198 -240.958442)
			(xy 134.48766 -240.97954) (xy 134.528163 -241.007496) (xy 134.563656 -241.041588) (xy 134.593221 -241.080932)
			(xy 134.616092 -241.124509) (xy 134.631676 -241.17119) (xy 134.639571 -241.219767) (xy 134.640066 -241.244374)
			(xy 134.969008 -241.244374) (xy 134.972968 -241.19532) (xy 134.984745 -241.147536) (xy 135.004036 -241.10226)
			(xy 135.030339 -241.060664) (xy 135.062974 -241.023827) (xy 135.101095 -240.992702) (xy 135.143716 -240.968095)
			(xy 135.189732 -240.950643) (xy 135.237951 -240.940799) (xy 135.287126 -240.938818) (xy 135.335981 -240.94475)
			(xy 135.383252 -240.958442) (xy 135.427714 -240.97954) (xy 135.468217 -241.007496) (xy 135.50371 -241.041588)
			(xy 135.533275 -241.080932) (xy 135.556146 -241.124509) (xy 135.57173 -241.17119) (xy 135.579625 -241.219767)
			(xy 135.58012 -241.244374) (xy 135.909062 -241.244374) (xy 135.913022 -241.19532) (xy 135.924799 -241.147536)
			(xy 135.94409 -241.10226) (xy 135.970393 -241.060664) (xy 136.003028 -241.023827) (xy 136.041149 -240.992702)
			(xy 136.08377 -240.968095) (xy 136.129786 -240.950643) (xy 136.178005 -240.940799) (xy 136.22718 -240.938818)
			(xy 136.276035 -240.94475) (xy 136.323306 -240.958442) (xy 136.367768 -240.97954) (xy 136.408271 -241.007496)
			(xy 136.443764 -241.041588) (xy 136.473329 -241.080932) (xy 136.4962 -241.124509) (xy 136.511784 -241.17119)
			(xy 136.519679 -241.219767) (xy 136.520174 -241.244374) (xy 136.519679 -241.268981) (xy 136.511784 -241.317558)
			(xy 136.4962 -241.364239) (xy 136.473329 -241.407816) (xy 136.443764 -241.44716) (xy 136.408271 -241.481252)
			(xy 136.367768 -241.509208) (xy 136.323306 -241.530306) (xy 136.276035 -241.543998) (xy 136.22718 -241.54993)
			(xy 136.178005 -241.547949) (xy 136.129786 -241.538105) (xy 136.08377 -241.520653) (xy 136.041149 -241.496046)
			(xy 136.003028 -241.464921) (xy 135.970393 -241.428084) (xy 135.94409 -241.386488) (xy 135.924799 -241.341212)
			(xy 135.913022 -241.293428) (xy 135.909062 -241.244374) (xy 135.58012 -241.244374) (xy 135.579625 -241.268981)
			(xy 135.57173 -241.317558) (xy 135.556146 -241.364239) (xy 135.533275 -241.407816) (xy 135.50371 -241.44716)
			(xy 135.468217 -241.481252) (xy 135.427714 -241.509208) (xy 135.383252 -241.530306) (xy 135.335981 -241.543998)
			(xy 135.287126 -241.54993) (xy 135.237951 -241.547949) (xy 135.189732 -241.538105) (xy 135.143716 -241.520653)
			(xy 135.101095 -241.496046) (xy 135.062974 -241.464921) (xy 135.030339 -241.428084) (xy 135.004036 -241.386488)
			(xy 134.984745 -241.341212) (xy 134.972968 -241.293428) (xy 134.969008 -241.244374) (xy 134.640066 -241.244374)
			(xy 134.639571 -241.268981) (xy 134.631676 -241.317558) (xy 134.616092 -241.364239) (xy 134.593221 -241.407816)
			(xy 134.563656 -241.44716) (xy 134.528163 -241.481252) (xy 134.48766 -241.509208) (xy 134.443198 -241.530306)
			(xy 134.395927 -241.543998) (xy 134.347072 -241.54993) (xy 134.297897 -241.547949) (xy 134.249678 -241.538105)
			(xy 134.203662 -241.520653) (xy 134.161041 -241.496046) (xy 134.12292 -241.464921) (xy 134.090285 -241.428084)
			(xy 134.063982 -241.386488) (xy 134.044691 -241.341212) (xy 134.032914 -241.293428) (xy 134.028954 -241.244374)
			(xy 133.700012 -241.244374) (xy 133.699517 -241.268981) (xy 133.691622 -241.317558) (xy 133.676038 -241.364239)
			(xy 133.653167 -241.407816) (xy 133.623602 -241.44716) (xy 133.588109 -241.481252) (xy 133.547606 -241.509208)
			(xy 133.503144 -241.530306) (xy 133.455873 -241.543998) (xy 133.407018 -241.54993) (xy 133.357843 -241.547949)
			(xy 133.309624 -241.538105) (xy 133.263608 -241.520653) (xy 133.220987 -241.496046) (xy 133.182866 -241.464921)
			(xy 133.150231 -241.428084) (xy 133.123928 -241.386488) (xy 133.104637 -241.341212) (xy 133.09286 -241.293428)
			(xy 133.0889 -241.244374) (xy 132.770372 -241.244374) (xy 132.76986 -241.26982) (xy 132.761696 -241.320054)
			(xy 132.74558 -241.368328) (xy 132.721929 -241.413391) (xy 132.691356 -241.454077) (xy 132.654652 -241.489332)
			(xy 132.612768 -241.518242) (xy 132.566789 -241.540059) (xy 132.517905 -241.554219) (xy 132.467384 -241.560353)
			(xy 132.416532 -241.558304) (xy 132.366668 -241.548124) (xy 132.319082 -241.530077) (xy 132.275008 -241.504631)
			(xy 132.235586 -241.472444) (xy 132.201838 -241.43435) (xy 132.174637 -241.391336) (xy 132.154689 -241.344516)
			(xy 132.14251 -241.295102) (xy 132.138415 -241.244374) (xy 131.830572 -241.244374) (xy 131.83006 -241.26982)
			(xy 131.821896 -241.320054) (xy 131.80578 -241.368328) (xy 131.782129 -241.413391) (xy 131.751556 -241.454077)
			(xy 131.714852 -241.489332) (xy 131.672968 -241.518242) (xy 131.626989 -241.540059) (xy 131.578105 -241.554219)
			(xy 131.527584 -241.560353) (xy 131.476732 -241.558304) (xy 131.426868 -241.548124) (xy 131.379282 -241.530077)
			(xy 131.335208 -241.504631) (xy 131.295786 -241.472444) (xy 131.262038 -241.43435) (xy 131.234837 -241.391336)
			(xy 131.214889 -241.344516) (xy 131.20271 -241.295102) (xy 131.198615 -241.244374) (xy 130.880104 -241.244374)
			(xy 130.879609 -241.268981) (xy 130.871714 -241.317558) (xy 130.85613 -241.364239) (xy 130.833259 -241.407816)
			(xy 130.803694 -241.44716) (xy 130.768201 -241.481252) (xy 130.727698 -241.509208) (xy 130.683236 -241.530306)
			(xy 130.635965 -241.543998) (xy 130.58711 -241.54993) (xy 130.537935 -241.547949) (xy 130.489716 -241.538105)
			(xy 130.4437 -241.520653) (xy 130.401079 -241.496046) (xy 130.362958 -241.464921) (xy 130.330323 -241.428084)
			(xy 130.30402 -241.386488) (xy 130.284729 -241.341212) (xy 130.272952 -241.293428) (xy 130.268992 -241.244374)
			(xy 129.950464 -241.244374) (xy 129.949952 -241.26982) (xy 129.941788 -241.320054) (xy 129.925672 -241.368328)
			(xy 129.902021 -241.413391) (xy 129.871448 -241.454077) (xy 129.834744 -241.489332) (xy 129.79286 -241.518242)
			(xy 129.746881 -241.540059) (xy 129.697997 -241.554219) (xy 129.647476 -241.560353) (xy 129.596624 -241.558304)
			(xy 129.54676 -241.548124) (xy 129.499174 -241.530077) (xy 129.4551 -241.504631) (xy 129.415678 -241.472444)
			(xy 129.38193 -241.43435) (xy 129.354729 -241.391336) (xy 129.334781 -241.344516) (xy 129.322602 -241.295102)
			(xy 129.318507 -241.244374) (xy 128.999996 -241.244374) (xy 128.999501 -241.268981) (xy 128.991606 -241.317558)
			(xy 128.976022 -241.364239) (xy 128.953151 -241.407816) (xy 128.923586 -241.44716) (xy 128.888093 -241.481252)
			(xy 128.84759 -241.509208) (xy 128.803128 -241.530306) (xy 128.755857 -241.543998) (xy 128.707002 -241.54993)
			(xy 128.657827 -241.547949) (xy 128.609608 -241.538105) (xy 128.563592 -241.520653) (xy 128.520971 -241.496046)
			(xy 128.48285 -241.464921) (xy 128.450215 -241.428084) (xy 128.423912 -241.386488) (xy 128.404621 -241.341212)
			(xy 128.392844 -241.293428) (xy 128.388884 -241.244374) (xy 128.070356 -241.244374) (xy 128.069844 -241.26982)
			(xy 128.06168 -241.320054) (xy 128.045564 -241.368328) (xy 128.021913 -241.413391) (xy 127.99134 -241.454077)
			(xy 127.954636 -241.489332) (xy 127.912752 -241.518242) (xy 127.866773 -241.540059) (xy 127.817889 -241.554219)
			(xy 127.767368 -241.560353) (xy 127.716516 -241.558304) (xy 127.666652 -241.548124) (xy 127.619066 -241.530077)
			(xy 127.574992 -241.504631) (xy 127.53557 -241.472444) (xy 127.501822 -241.43435) (xy 127.474621 -241.391336)
			(xy 127.454673 -241.344516) (xy 127.442494 -241.295102) (xy 127.438399 -241.244374) (xy 127.119712 -241.244374)
			(xy 127.119713 -241.268746) (xy 127.111981 -241.316842) (xy 127.096712 -241.363101) (xy 127.074293 -241.406349)
			(xy 127.045293 -241.44549) (xy 127.010447 -241.479531) (xy 126.970638 -241.507609) (xy 126.948946 -241.518694)
			(xy 126.935738 -241.525044) (xy 126.920498 -241.549682) (xy 126.920498 -241.743484) (xy 126.920927 -241.753166)
			(xy 126.928081 -241.771161) (xy 126.941355 -241.785262) (xy 126.949962 -241.789712) (xy 127.04699 -241.83467)
			(xy 127.076454 -241.83086) (xy 127.08763 -241.821208) (xy 127.108459 -241.804331) (xy 127.154809 -241.7774)
			(xy 127.205148 -241.758975) (xy 127.257931 -241.749622) (xy 127.284734 -241.749072) (xy 127.309989 -241.749596)
			(xy 127.35981 -241.757915) (xy 127.407582 -241.77432) (xy 127.452003 -241.798364) (xy 127.49186 -241.82939)
			(xy 127.526068 -241.866554) (xy 127.553693 -241.90884) (xy 127.573981 -241.955097) (xy 127.58638 -242.004062)
			(xy 127.590549 -242.05438) (xy 127.908553 -242.05438) (xy 127.912648 -242.003652) (xy 127.924827 -241.954238)
			(xy 127.944775 -241.907418) (xy 127.971976 -241.864404) (xy 128.005724 -241.82631) (xy 128.045146 -241.794123)
			(xy 128.08922 -241.768677) (xy 128.136806 -241.75063) (xy 128.18667 -241.74045) (xy 128.237522 -241.738401)
			(xy 128.288043 -241.744535) (xy 128.336927 -241.758695) (xy 128.382906 -241.780512) (xy 128.42479 -241.809422)
			(xy 128.461494 -241.844677) (xy 128.492067 -241.885363) (xy 128.515718 -241.930426) (xy 128.531834 -241.9787)
			(xy 128.539998 -242.028934) (xy 128.54051 -242.05438) (xy 128.848607 -242.05438) (xy 128.852702 -242.003652)
			(xy 128.864881 -241.954238) (xy 128.884829 -241.907418) (xy 128.91203 -241.864404) (xy 128.945778 -241.82631)
			(xy 128.9852 -241.794123) (xy 129.029274 -241.768677) (xy 129.07686 -241.75063) (xy 129.126724 -241.74045)
			(xy 129.177576 -241.738401) (xy 129.228097 -241.744535) (xy 129.276981 -241.758695) (xy 129.32296 -241.780512)
			(xy 129.364844 -241.809422) (xy 129.401548 -241.844677) (xy 129.432121 -241.885363) (xy 129.455772 -241.930426)
			(xy 129.471888 -241.9787) (xy 129.480052 -242.028934) (xy 129.480564 -242.05438) (xy 130.728461 -242.05438)
			(xy 130.732556 -242.003652) (xy 130.744735 -241.954238) (xy 130.764683 -241.907418) (xy 130.791884 -241.864404)
			(xy 130.825632 -241.82631) (xy 130.865054 -241.794123) (xy 130.909128 -241.768677) (xy 130.956714 -241.75063)
			(xy 131.006578 -241.74045) (xy 131.05743 -241.738401) (xy 131.107951 -241.744535) (xy 131.156835 -241.758695)
			(xy 131.202814 -241.780512) (xy 131.244698 -241.809422) (xy 131.281402 -241.844677) (xy 131.311975 -241.885363)
			(xy 131.335626 -241.930426) (xy 131.351742 -241.9787) (xy 131.359906 -242.028934) (xy 131.360418 -242.05438)
			(xy 131.678946 -242.05438) (xy 131.682906 -242.005326) (xy 131.694683 -241.957542) (xy 131.713974 -241.912266)
			(xy 131.740277 -241.87067) (xy 131.772912 -241.833833) (xy 131.811033 -241.802708) (xy 131.853654 -241.778101)
			(xy 131.89967 -241.760649) (xy 131.947889 -241.750805) (xy 131.997064 -241.748824) (xy 132.045919 -241.754756)
			(xy 132.09319 -241.768448) (xy 132.137652 -241.789546) (xy 132.178155 -241.817502) (xy 132.213648 -241.851594)
			(xy 132.243213 -241.890938) (xy 132.266084 -241.934515) (xy 132.281668 -241.981196) (xy 132.289563 -242.029773)
			(xy 132.290058 -242.05438) (xy 132.608569 -242.05438) (xy 132.612664 -242.003652) (xy 132.624843 -241.954238)
			(xy 132.644791 -241.907418) (xy 132.671992 -241.864404) (xy 132.70574 -241.82631) (xy 132.745162 -241.794123)
			(xy 132.789236 -241.768677) (xy 132.836822 -241.75063) (xy 132.886686 -241.74045) (xy 132.937538 -241.738401)
			(xy 132.988059 -241.744535) (xy 133.036943 -241.758695) (xy 133.082922 -241.780512) (xy 133.124806 -241.809422)
			(xy 133.16151 -241.844677) (xy 133.192083 -241.885363) (xy 133.215734 -241.930426) (xy 133.23185 -241.9787)
			(xy 133.240014 -242.028934) (xy 133.240526 -242.05438) (xy 133.559054 -242.05438) (xy 133.563014 -242.005326)
			(xy 133.574791 -241.957542) (xy 133.594082 -241.912266) (xy 133.620385 -241.87067) (xy 133.65302 -241.833833)
			(xy 133.691141 -241.802708) (xy 133.733762 -241.778101) (xy 133.779778 -241.760649) (xy 133.827997 -241.750805)
			(xy 133.877172 -241.748824) (xy 133.926027 -241.754756) (xy 133.973298 -241.768448) (xy 134.01776 -241.789546)
			(xy 134.058263 -241.817502) (xy 134.093756 -241.851594) (xy 134.123321 -241.890938) (xy 134.146192 -241.934515)
			(xy 134.161776 -241.981196) (xy 134.169671 -242.029773) (xy 134.170166 -242.05438) (xy 134.498854 -242.05438)
			(xy 134.502814 -242.005326) (xy 134.514591 -241.957542) (xy 134.533882 -241.912266) (xy 134.560185 -241.87067)
			(xy 134.59282 -241.833833) (xy 134.630941 -241.802708) (xy 134.673562 -241.778101) (xy 134.719578 -241.760649)
			(xy 134.767797 -241.750805) (xy 134.816972 -241.748824) (xy 134.865827 -241.754756) (xy 134.913098 -241.768448)
			(xy 134.95756 -241.789546) (xy 134.998063 -241.817502) (xy 135.033556 -241.851594) (xy 135.063121 -241.890938)
			(xy 135.085992 -241.934515) (xy 135.101576 -241.981196) (xy 135.109471 -242.029773) (xy 135.109966 -242.05438)
			(xy 135.438908 -242.05438) (xy 135.442868 -242.005326) (xy 135.454645 -241.957542) (xy 135.473936 -241.912266)
			(xy 135.500239 -241.87067) (xy 135.532874 -241.833833) (xy 135.570995 -241.802708) (xy 135.613616 -241.778101)
			(xy 135.659632 -241.760649) (xy 135.707851 -241.750805) (xy 135.757026 -241.748824) (xy 135.805881 -241.754756)
			(xy 135.853152 -241.768448) (xy 135.897614 -241.789546) (xy 135.938117 -241.817502) (xy 135.97361 -241.851594)
			(xy 136.003175 -241.890938) (xy 136.026046 -241.934515) (xy 136.04163 -241.981196) (xy 136.049525 -242.029773)
			(xy 136.05002 -242.05438) (xy 136.049525 -242.078987) (xy 136.04163 -242.127564) (xy 136.026046 -242.174245)
			(xy 136.003175 -242.217822) (xy 135.97361 -242.257166) (xy 135.938117 -242.291258) (xy 135.897614 -242.319214)
			(xy 135.853152 -242.340312) (xy 135.805881 -242.354004) (xy 135.757026 -242.359936) (xy 135.707851 -242.357955)
			(xy 135.659632 -242.348111) (xy 135.613616 -242.330659) (xy 135.570995 -242.306052) (xy 135.532874 -242.274927)
			(xy 135.500239 -242.23809) (xy 135.473936 -242.196494) (xy 135.454645 -242.151218) (xy 135.442868 -242.103434)
			(xy 135.438908 -242.05438) (xy 135.109966 -242.05438) (xy 135.109471 -242.078987) (xy 135.101576 -242.127564)
			(xy 135.085992 -242.174245) (xy 135.063121 -242.217822) (xy 135.033556 -242.257166) (xy 134.998063 -242.291258)
			(xy 134.95756 -242.319214) (xy 134.913098 -242.340312) (xy 134.865827 -242.354004) (xy 134.816972 -242.359936)
			(xy 134.767797 -242.357955) (xy 134.719578 -242.348111) (xy 134.673562 -242.330659) (xy 134.630941 -242.306052)
			(xy 134.59282 -242.274927) (xy 134.560185 -242.23809) (xy 134.533882 -242.196494) (xy 134.514591 -242.151218)
			(xy 134.502814 -242.103434) (xy 134.498854 -242.05438) (xy 134.170166 -242.05438) (xy 134.169671 -242.078987)
			(xy 134.161776 -242.127564) (xy 134.146192 -242.174245) (xy 134.123321 -242.217822) (xy 134.093756 -242.257166)
			(xy 134.058263 -242.291258) (xy 134.01776 -242.319214) (xy 133.973298 -242.340312) (xy 133.926027 -242.354004)
			(xy 133.877172 -242.359936) (xy 133.827997 -242.357955) (xy 133.779778 -242.348111) (xy 133.733762 -242.330659)
			(xy 133.691141 -242.306052) (xy 133.65302 -242.274927) (xy 133.620385 -242.23809) (xy 133.594082 -242.196494)
			(xy 133.574791 -242.151218) (xy 133.563014 -242.103434) (xy 133.559054 -242.05438) (xy 133.240526 -242.05438)
			(xy 133.240014 -242.079826) (xy 133.23185 -242.13006) (xy 133.215734 -242.178334) (xy 133.192083 -242.223397)
			(xy 133.16151 -242.264083) (xy 133.124806 -242.299338) (xy 133.082922 -242.328248) (xy 133.036943 -242.350065)
			(xy 132.988059 -242.364225) (xy 132.937538 -242.370359) (xy 132.886686 -242.36831) (xy 132.836822 -242.35813)
			(xy 132.789236 -242.340083) (xy 132.745162 -242.314637) (xy 132.70574 -242.28245) (xy 132.671992 -242.244356)
			(xy 132.644791 -242.201342) (xy 132.624843 -242.154522) (xy 132.612664 -242.105108) (xy 132.608569 -242.05438)
			(xy 132.290058 -242.05438) (xy 132.289563 -242.078987) (xy 132.281668 -242.127564) (xy 132.266084 -242.174245)
			(xy 132.243213 -242.217822) (xy 132.213648 -242.257166) (xy 132.178155 -242.291258) (xy 132.137652 -242.319214)
			(xy 132.09319 -242.340312) (xy 132.045919 -242.354004) (xy 131.997064 -242.359936) (xy 131.947889 -242.357955)
			(xy 131.89967 -242.348111) (xy 131.853654 -242.330659) (xy 131.811033 -242.306052) (xy 131.772912 -242.274927)
			(xy 131.740277 -242.23809) (xy 131.713974 -242.196494) (xy 131.694683 -242.151218) (xy 131.682906 -242.103434)
			(xy 131.678946 -242.05438) (xy 131.360418 -242.05438) (xy 131.359906 -242.079826) (xy 131.351742 -242.13006)
			(xy 131.335626 -242.178334) (xy 131.311975 -242.223397) (xy 131.281402 -242.264083) (xy 131.244698 -242.299338)
			(xy 131.202814 -242.328248) (xy 131.156835 -242.350065) (xy 131.107951 -242.364225) (xy 131.05743 -242.370359)
			(xy 131.006578 -242.36831) (xy 130.956714 -242.35813) (xy 130.909128 -242.340083) (xy 130.865054 -242.314637)
			(xy 130.825632 -242.28245) (xy 130.791884 -242.244356) (xy 130.764683 -242.201342) (xy 130.744735 -242.154522)
			(xy 130.732556 -242.105108) (xy 130.728461 -242.05438) (xy 129.480564 -242.05438) (xy 129.480052 -242.079826)
			(xy 129.471888 -242.13006) (xy 129.455772 -242.178334) (xy 129.432121 -242.223397) (xy 129.401548 -242.264083)
			(xy 129.364844 -242.299338) (xy 129.32296 -242.328248) (xy 129.276981 -242.350065) (xy 129.228097 -242.364225)
			(xy 129.177576 -242.370359) (xy 129.126724 -242.36831) (xy 129.07686 -242.35813) (xy 129.029274 -242.340083)
			(xy 128.9852 -242.314637) (xy 128.945778 -242.28245) (xy 128.91203 -242.244356) (xy 128.884829 -242.201342)
			(xy 128.864881 -242.154522) (xy 128.852702 -242.105108) (xy 128.848607 -242.05438) (xy 128.54051 -242.05438)
			(xy 128.539998 -242.079826) (xy 128.531834 -242.13006) (xy 128.515718 -242.178334) (xy 128.492067 -242.223397)
			(xy 128.461494 -242.264083) (xy 128.42479 -242.299338) (xy 128.382906 -242.328248) (xy 128.336927 -242.350065)
			(xy 128.288043 -242.364225) (xy 128.237522 -242.370359) (xy 128.18667 -242.36831) (xy 128.136806 -242.35813)
			(xy 128.08922 -242.340083) (xy 128.045146 -242.314637) (xy 128.005724 -242.28245) (xy 127.971976 -242.244356)
			(xy 127.944775 -242.201342) (xy 127.924827 -242.154522) (xy 127.912648 -242.105108) (xy 127.908553 -242.05438)
			(xy 127.590549 -242.05438) (xy 127.590551 -242.0544) (xy 127.58638 -242.104738) (xy 127.573981 -242.153703)
			(xy 127.553693 -242.19996) (xy 127.526068 -242.242246) (xy 127.49186 -242.27941) (xy 127.452003 -242.310436)
			(xy 127.407582 -242.33448) (xy 127.35981 -242.350885) (xy 127.309989 -242.359204) (xy 127.284734 -242.359688)
			(xy 127.271971 -242.359548) (xy 127.246538 -242.357384) (xy 127.233934 -242.35537) (xy 127.207197 -242.35025)
			(xy 127.155973 -242.331833) (xy 127.108809 -242.304656) (xy 127.08763 -242.287552) (xy 127.0762 -242.2779)
			(xy 127.04699 -242.27409) (xy 126.949962 -242.319048) (xy 126.94134 -242.323489) (xy 126.928019 -242.337562)
			(xy 126.920899 -242.355585) (xy 126.920498 -242.365276) (xy 126.920498 -242.559078) (xy 126.935738 -242.583716)
			(xy 126.948946 -242.590066) (xy 126.970618 -242.601192) (xy 127.010426 -242.629266) (xy 127.045273 -242.663303)
			(xy 127.074275 -242.702441) (xy 127.096695 -242.745687) (xy 127.111966 -242.791944) (xy 127.1197 -242.840038)
			(xy 127.1197 -242.864386) (xy 127.438399 -242.864386) (xy 127.442494 -242.813658) (xy 127.454673 -242.764244)
			(xy 127.474621 -242.717424) (xy 127.501822 -242.67441) (xy 127.53557 -242.636316) (xy 127.574992 -242.604129)
			(xy 127.619066 -242.578683) (xy 127.666652 -242.560636) (xy 127.716516 -242.550456) (xy 127.767368 -242.548407)
			(xy 127.817889 -242.554541) (xy 127.866773 -242.568701) (xy 127.912752 -242.590518) (xy 127.954636 -242.619428)
			(xy 127.99134 -242.654683) (xy 128.021913 -242.695369) (xy 128.045564 -242.740432) (xy 128.06168 -242.788706)
			(xy 128.069844 -242.83894) (xy 128.070356 -242.864386) (xy 128.388884 -242.864386) (xy 128.392844 -242.815332)
			(xy 128.404621 -242.767548) (xy 128.423912 -242.722272) (xy 128.450215 -242.680676) (xy 128.48285 -242.643839)
			(xy 128.520971 -242.612714) (xy 128.563592 -242.588107) (xy 128.609608 -242.570655) (xy 128.657827 -242.560811)
			(xy 128.707002 -242.55883) (xy 128.755857 -242.564762) (xy 128.803128 -242.578454) (xy 128.84759 -242.599552)
			(xy 128.888093 -242.627508) (xy 128.923586 -242.6616) (xy 128.953151 -242.700944) (xy 128.976022 -242.744521)
			(xy 128.991606 -242.791202) (xy 128.999501 -242.839779) (xy 128.999996 -242.864386) (xy 129.318507 -242.864386)
			(xy 129.322602 -242.813658) (xy 129.334781 -242.764244) (xy 129.354729 -242.717424) (xy 129.38193 -242.67441)
			(xy 129.415678 -242.636316) (xy 129.4551 -242.604129) (xy 129.499174 -242.578683) (xy 129.54676 -242.560636)
			(xy 129.596624 -242.550456) (xy 129.647476 -242.548407) (xy 129.697997 -242.554541) (xy 129.746881 -242.568701)
			(xy 129.79286 -242.590518) (xy 129.834744 -242.619428) (xy 129.871448 -242.654683) (xy 129.902021 -242.695369)
			(xy 129.925672 -242.740432) (xy 129.941788 -242.788706) (xy 129.949952 -242.83894) (xy 129.950464 -242.864386)
			(xy 130.268992 -242.864386) (xy 130.272952 -242.815332) (xy 130.284729 -242.767548) (xy 130.30402 -242.722272)
			(xy 130.330323 -242.680676) (xy 130.362958 -242.643839) (xy 130.401079 -242.612714) (xy 130.4437 -242.588107)
			(xy 130.489716 -242.570655) (xy 130.537935 -242.560811) (xy 130.58711 -242.55883) (xy 130.635965 -242.564762)
			(xy 130.683236 -242.578454) (xy 130.727698 -242.599552) (xy 130.768201 -242.627508) (xy 130.803694 -242.6616)
			(xy 130.833259 -242.700944) (xy 130.85613 -242.744521) (xy 130.871714 -242.791202) (xy 130.879609 -242.839779)
			(xy 130.880104 -242.864386) (xy 131.198615 -242.864386) (xy 131.20271 -242.813658) (xy 131.214889 -242.764244)
			(xy 131.234837 -242.717424) (xy 131.262038 -242.67441) (xy 131.295786 -242.636316) (xy 131.335208 -242.604129)
			(xy 131.379282 -242.578683) (xy 131.426868 -242.560636) (xy 131.476732 -242.550456) (xy 131.527584 -242.548407)
			(xy 131.578105 -242.554541) (xy 131.626989 -242.568701) (xy 131.672968 -242.590518) (xy 131.714852 -242.619428)
			(xy 131.751556 -242.654683) (xy 131.782129 -242.695369) (xy 131.80578 -242.740432) (xy 131.821896 -242.788706)
			(xy 131.83006 -242.83894) (xy 131.830572 -242.864386) (xy 132.138415 -242.864386) (xy 132.14251 -242.813658)
			(xy 132.154689 -242.764244) (xy 132.174637 -242.717424) (xy 132.201838 -242.67441) (xy 132.235586 -242.636316)
			(xy 132.275008 -242.604129) (xy 132.319082 -242.578683) (xy 132.366668 -242.560636) (xy 132.416532 -242.550456)
			(xy 132.467384 -242.548407) (xy 132.517905 -242.554541) (xy 132.566789 -242.568701) (xy 132.612768 -242.590518)
			(xy 132.654652 -242.619428) (xy 132.691356 -242.654683) (xy 132.721929 -242.695369) (xy 132.74558 -242.740432)
			(xy 132.761696 -242.788706) (xy 132.76986 -242.83894) (xy 132.770372 -242.864386) (xy 133.0889 -242.864386)
			(xy 133.09286 -242.815332) (xy 133.104637 -242.767548) (xy 133.123928 -242.722272) (xy 133.150231 -242.680676)
			(xy 133.182866 -242.643839) (xy 133.220987 -242.612714) (xy 133.263608 -242.588107) (xy 133.309624 -242.570655)
			(xy 133.357843 -242.560811) (xy 133.407018 -242.55883) (xy 133.455873 -242.564762) (xy 133.503144 -242.578454)
			(xy 133.547606 -242.599552) (xy 133.588109 -242.627508) (xy 133.623602 -242.6616) (xy 133.653167 -242.700944)
			(xy 133.676038 -242.744521) (xy 133.691622 -242.791202) (xy 133.699517 -242.839779) (xy 133.700012 -242.864386)
			(xy 134.028954 -242.864386) (xy 134.032914 -242.815332) (xy 134.044691 -242.767548) (xy 134.063982 -242.722272)
			(xy 134.090285 -242.680676) (xy 134.12292 -242.643839) (xy 134.161041 -242.612714) (xy 134.203662 -242.588107)
			(xy 134.249678 -242.570655) (xy 134.297897 -242.560811) (xy 134.347072 -242.55883) (xy 134.395927 -242.564762)
			(xy 134.443198 -242.578454) (xy 134.48766 -242.599552) (xy 134.528163 -242.627508) (xy 134.563656 -242.6616)
			(xy 134.593221 -242.700944) (xy 134.616092 -242.744521) (xy 134.631676 -242.791202) (xy 134.639571 -242.839779)
			(xy 134.640066 -242.864386) (xy 134.969008 -242.864386) (xy 134.972968 -242.815332) (xy 134.984745 -242.767548)
			(xy 135.004036 -242.722272) (xy 135.030339 -242.680676) (xy 135.062974 -242.643839) (xy 135.101095 -242.612714)
			(xy 135.143716 -242.588107) (xy 135.189732 -242.570655) (xy 135.237951 -242.560811) (xy 135.287126 -242.55883)
			(xy 135.335981 -242.564762) (xy 135.383252 -242.578454) (xy 135.427714 -242.599552) (xy 135.468217 -242.627508)
			(xy 135.50371 -242.6616) (xy 135.533275 -242.700944) (xy 135.556146 -242.744521) (xy 135.57173 -242.791202)
			(xy 135.579625 -242.839779) (xy 135.58012 -242.864386) (xy 135.909062 -242.864386) (xy 135.913022 -242.815332)
			(xy 135.924799 -242.767548) (xy 135.94409 -242.722272) (xy 135.970393 -242.680676) (xy 136.003028 -242.643839)
			(xy 136.041149 -242.612714) (xy 136.08377 -242.588107) (xy 136.129786 -242.570655) (xy 136.178005 -242.560811)
			(xy 136.22718 -242.55883) (xy 136.276035 -242.564762) (xy 136.323306 -242.578454) (xy 136.367768 -242.599552)
			(xy 136.408271 -242.627508) (xy 136.443764 -242.6616) (xy 136.473329 -242.700944) (xy 136.4962 -242.744521)
			(xy 136.511784 -242.791202) (xy 136.519679 -242.839779) (xy 136.520174 -242.864386) (xy 136.519679 -242.888993)
			(xy 136.511784 -242.93757) (xy 136.4962 -242.984251) (xy 136.473329 -243.027828) (xy 136.443764 -243.067172)
			(xy 136.408271 -243.101264) (xy 136.367768 -243.12922) (xy 136.323306 -243.150318) (xy 136.276035 -243.16401)
			(xy 136.22718 -243.169942) (xy 136.178005 -243.167961) (xy 136.129786 -243.158117) (xy 136.08377 -243.140665)
			(xy 136.041149 -243.116058) (xy 136.003028 -243.084933) (xy 135.970393 -243.048096) (xy 135.94409 -243.0065)
			(xy 135.924799 -242.961224) (xy 135.913022 -242.91344) (xy 135.909062 -242.864386) (xy 135.58012 -242.864386)
			(xy 135.579625 -242.888993) (xy 135.57173 -242.93757) (xy 135.556146 -242.984251) (xy 135.533275 -243.027828)
			(xy 135.50371 -243.067172) (xy 135.468217 -243.101264) (xy 135.427714 -243.12922) (xy 135.383252 -243.150318)
			(xy 135.335981 -243.16401) (xy 135.287126 -243.169942) (xy 135.237951 -243.167961) (xy 135.189732 -243.158117)
			(xy 135.143716 -243.140665) (xy 135.101095 -243.116058) (xy 135.062974 -243.084933) (xy 135.030339 -243.048096)
			(xy 135.004036 -243.0065) (xy 134.984745 -242.961224) (xy 134.972968 -242.91344) (xy 134.969008 -242.864386)
			(xy 134.640066 -242.864386) (xy 134.639571 -242.888993) (xy 134.631676 -242.93757) (xy 134.616092 -242.984251)
			(xy 134.593221 -243.027828) (xy 134.563656 -243.067172) (xy 134.528163 -243.101264) (xy 134.48766 -243.12922)
			(xy 134.443198 -243.150318) (xy 134.395927 -243.16401) (xy 134.347072 -243.169942) (xy 134.297897 -243.167961)
			(xy 134.249678 -243.158117) (xy 134.203662 -243.140665) (xy 134.161041 -243.116058) (xy 134.12292 -243.084933)
			(xy 134.090285 -243.048096) (xy 134.063982 -243.0065) (xy 134.044691 -242.961224) (xy 134.032914 -242.91344)
			(xy 134.028954 -242.864386) (xy 133.700012 -242.864386) (xy 133.699517 -242.888993) (xy 133.691622 -242.93757)
			(xy 133.676038 -242.984251) (xy 133.653167 -243.027828) (xy 133.623602 -243.067172) (xy 133.588109 -243.101264)
			(xy 133.547606 -243.12922) (xy 133.503144 -243.150318) (xy 133.455873 -243.16401) (xy 133.407018 -243.169942)
			(xy 133.357843 -243.167961) (xy 133.309624 -243.158117) (xy 133.263608 -243.140665) (xy 133.220987 -243.116058)
			(xy 133.182866 -243.084933) (xy 133.150231 -243.048096) (xy 133.123928 -243.0065) (xy 133.104637 -242.961224)
			(xy 133.09286 -242.91344) (xy 133.0889 -242.864386) (xy 132.770372 -242.864386) (xy 132.76986 -242.889832)
			(xy 132.761696 -242.940066) (xy 132.74558 -242.98834) (xy 132.721929 -243.033403) (xy 132.691356 -243.074089)
			(xy 132.654652 -243.109344) (xy 132.612768 -243.138254) (xy 132.566789 -243.160071) (xy 132.517905 -243.174231)
			(xy 132.467384 -243.180365) (xy 132.416532 -243.178316) (xy 132.366668 -243.168136) (xy 132.319082 -243.150089)
			(xy 132.275008 -243.124643) (xy 132.235586 -243.092456) (xy 132.201838 -243.054362) (xy 132.174637 -243.011348)
			(xy 132.154689 -242.964528) (xy 132.14251 -242.915114) (xy 132.138415 -242.864386) (xy 131.830572 -242.864386)
			(xy 131.83006 -242.889832) (xy 131.821896 -242.940066) (xy 131.80578 -242.98834) (xy 131.782129 -243.033403)
			(xy 131.751556 -243.074089) (xy 131.714852 -243.109344) (xy 131.672968 -243.138254) (xy 131.626989 -243.160071)
			(xy 131.578105 -243.174231) (xy 131.527584 -243.180365) (xy 131.476732 -243.178316) (xy 131.426868 -243.168136)
			(xy 131.379282 -243.150089) (xy 131.335208 -243.124643) (xy 131.295786 -243.092456) (xy 131.262038 -243.054362)
			(xy 131.234837 -243.011348) (xy 131.214889 -242.964528) (xy 131.20271 -242.915114) (xy 131.198615 -242.864386)
			(xy 130.880104 -242.864386) (xy 130.879609 -242.888993) (xy 130.871714 -242.93757) (xy 130.85613 -242.984251)
			(xy 130.833259 -243.027828) (xy 130.803694 -243.067172) (xy 130.768201 -243.101264) (xy 130.727698 -243.12922)
			(xy 130.683236 -243.150318) (xy 130.635965 -243.16401) (xy 130.58711 -243.169942) (xy 130.537935 -243.167961)
			(xy 130.489716 -243.158117) (xy 130.4437 -243.140665) (xy 130.401079 -243.116058) (xy 130.362958 -243.084933)
			(xy 130.330323 -243.048096) (xy 130.30402 -243.0065) (xy 130.284729 -242.961224) (xy 130.272952 -242.91344)
			(xy 130.268992 -242.864386) (xy 129.950464 -242.864386) (xy 129.949952 -242.889832) (xy 129.941788 -242.940066)
			(xy 129.925672 -242.98834) (xy 129.902021 -243.033403) (xy 129.871448 -243.074089) (xy 129.834744 -243.109344)
			(xy 129.79286 -243.138254) (xy 129.746881 -243.160071) (xy 129.697997 -243.174231) (xy 129.647476 -243.180365)
			(xy 129.596624 -243.178316) (xy 129.54676 -243.168136) (xy 129.499174 -243.150089) (xy 129.4551 -243.124643)
			(xy 129.415678 -243.092456) (xy 129.38193 -243.054362) (xy 129.354729 -243.011348) (xy 129.334781 -242.964528)
			(xy 129.322602 -242.915114) (xy 129.318507 -242.864386) (xy 128.999996 -242.864386) (xy 128.999501 -242.888993)
			(xy 128.991606 -242.93757) (xy 128.976022 -242.984251) (xy 128.953151 -243.027828) (xy 128.923586 -243.067172)
			(xy 128.888093 -243.101264) (xy 128.84759 -243.12922) (xy 128.803128 -243.150318) (xy 128.755857 -243.16401)
			(xy 128.707002 -243.169942) (xy 128.657827 -243.167961) (xy 128.609608 -243.158117) (xy 128.563592 -243.140665)
			(xy 128.520971 -243.116058) (xy 128.48285 -243.084933) (xy 128.450215 -243.048096) (xy 128.423912 -243.0065)
			(xy 128.404621 -242.961224) (xy 128.392844 -242.91344) (xy 128.388884 -242.864386) (xy 128.070356 -242.864386)
			(xy 128.069844 -242.889832) (xy 128.06168 -242.940066) (xy 128.045564 -242.98834) (xy 128.021913 -243.033403)
			(xy 127.99134 -243.074089) (xy 127.954636 -243.109344) (xy 127.912752 -243.138254) (xy 127.866773 -243.160071)
			(xy 127.817889 -243.174231) (xy 127.767368 -243.180365) (xy 127.716516 -243.178316) (xy 127.666652 -243.168136)
			(xy 127.619066 -243.150089) (xy 127.574992 -243.124643) (xy 127.53557 -243.092456) (xy 127.501822 -243.054362)
			(xy 127.474621 -243.011348) (xy 127.454673 -242.964528) (xy 127.442494 -242.915114) (xy 127.438399 -242.864386)
			(xy 127.1197 -242.864386) (xy 127.119701 -242.88875) (xy 127.111969 -242.936844) (xy 127.0967 -242.983102)
			(xy 127.074281 -243.026348) (xy 127.045281 -243.065487) (xy 127.010436 -243.099526) (xy 126.970628 -243.127602)
			(xy 126.948946 -243.138706) (xy 126.935738 -243.145056) (xy 126.920498 -243.169694) (xy 126.920498 -243.674392)
			(xy 127.908553 -243.674392) (xy 127.912648 -243.623664) (xy 127.924827 -243.57425) (xy 127.944775 -243.52743)
			(xy 127.971976 -243.484416) (xy 128.005724 -243.446322) (xy 128.045146 -243.414135) (xy 128.08922 -243.388689)
			(xy 128.136806 -243.370642) (xy 128.18667 -243.360462) (xy 128.237522 -243.358413) (xy 128.288043 -243.364547)
			(xy 128.336927 -243.378707) (xy 128.382906 -243.400524) (xy 128.42479 -243.429434) (xy 128.461494 -243.464689)
			(xy 128.492067 -243.505375) (xy 128.515718 -243.550438) (xy 128.531834 -243.598712) (xy 128.539998 -243.648946)
			(xy 128.54051 -243.674392) (xy 128.848607 -243.674392) (xy 128.852702 -243.623664) (xy 128.864881 -243.57425)
			(xy 128.884829 -243.52743) (xy 128.91203 -243.484416) (xy 128.945778 -243.446322) (xy 128.9852 -243.414135)
			(xy 129.029274 -243.388689) (xy 129.07686 -243.370642) (xy 129.126724 -243.360462) (xy 129.177576 -243.358413)
			(xy 129.228097 -243.364547) (xy 129.276981 -243.378707) (xy 129.32296 -243.400524) (xy 129.364844 -243.429434)
			(xy 129.401548 -243.464689) (xy 129.432121 -243.505375) (xy 129.455772 -243.550438) (xy 129.471888 -243.598712)
			(xy 129.480052 -243.648946) (xy 129.480564 -243.674392) (xy 129.798838 -243.674392) (xy 129.802798 -243.625338)
			(xy 129.814575 -243.577554) (xy 129.833866 -243.532278) (xy 129.860169 -243.490682) (xy 129.892804 -243.453845)
			(xy 129.930925 -243.42272) (xy 129.973546 -243.398113) (xy 130.019562 -243.380661) (xy 130.067781 -243.370817)
			(xy 130.116956 -243.368836) (xy 130.165811 -243.374768) (xy 130.213082 -243.38846) (xy 130.257544 -243.409558)
			(xy 130.298047 -243.437514) (xy 130.33354 -243.471606) (xy 130.363105 -243.51095) (xy 130.385976 -243.554527)
			(xy 130.40156 -243.601208) (xy 130.409455 -243.649785) (xy 130.40995 -243.674392) (xy 130.728461 -243.674392)
			(xy 130.732556 -243.623664) (xy 130.744735 -243.57425) (xy 130.764683 -243.52743) (xy 130.791884 -243.484416)
			(xy 130.825632 -243.446322) (xy 130.865054 -243.414135) (xy 130.909128 -243.388689) (xy 130.956714 -243.370642)
			(xy 131.006578 -243.360462) (xy 131.05743 -243.358413) (xy 131.107951 -243.364547) (xy 131.156835 -243.378707)
			(xy 131.202814 -243.400524) (xy 131.244698 -243.429434) (xy 131.281402 -243.464689) (xy 131.311975 -243.505375)
			(xy 131.335626 -243.550438) (xy 131.351742 -243.598712) (xy 131.359906 -243.648946) (xy 131.360418 -243.674392)
			(xy 131.678946 -243.674392) (xy 131.682906 -243.625338) (xy 131.694683 -243.577554) (xy 131.713974 -243.532278)
			(xy 131.740277 -243.490682) (xy 131.772912 -243.453845) (xy 131.811033 -243.42272) (xy 131.853654 -243.398113)
			(xy 131.89967 -243.380661) (xy 131.947889 -243.370817) (xy 131.997064 -243.368836) (xy 132.045919 -243.374768)
			(xy 132.09319 -243.38846) (xy 132.137652 -243.409558) (xy 132.178155 -243.437514) (xy 132.213648 -243.471606)
			(xy 132.243213 -243.51095) (xy 132.266084 -243.554527) (xy 132.281668 -243.601208) (xy 132.289563 -243.649785)
			(xy 132.290058 -243.674392) (xy 132.608569 -243.674392) (xy 132.612664 -243.623664) (xy 132.624843 -243.57425)
			(xy 132.644791 -243.52743) (xy 132.671992 -243.484416) (xy 132.70574 -243.446322) (xy 132.745162 -243.414135)
			(xy 132.789236 -243.388689) (xy 132.836822 -243.370642) (xy 132.886686 -243.360462) (xy 132.937538 -243.358413)
			(xy 132.988059 -243.364547) (xy 133.036943 -243.378707) (xy 133.082922 -243.400524) (xy 133.124806 -243.429434)
			(xy 133.16151 -243.464689) (xy 133.192083 -243.505375) (xy 133.215734 -243.550438) (xy 133.23185 -243.598712)
			(xy 133.240014 -243.648946) (xy 133.240526 -243.674392) (xy 133.559054 -243.674392) (xy 133.563014 -243.625338)
			(xy 133.574791 -243.577554) (xy 133.594082 -243.532278) (xy 133.620385 -243.490682) (xy 133.65302 -243.453845)
			(xy 133.691141 -243.42272) (xy 133.733762 -243.398113) (xy 133.779778 -243.380661) (xy 133.827997 -243.370817)
			(xy 133.877172 -243.368836) (xy 133.926027 -243.374768) (xy 133.973298 -243.38846) (xy 134.01776 -243.409558)
			(xy 134.058263 -243.437514) (xy 134.093756 -243.471606) (xy 134.123321 -243.51095) (xy 134.146192 -243.554527)
			(xy 134.161776 -243.601208) (xy 134.169671 -243.649785) (xy 134.170166 -243.674392) (xy 134.498854 -243.674392)
			(xy 134.502814 -243.625338) (xy 134.514591 -243.577554) (xy 134.533882 -243.532278) (xy 134.560185 -243.490682)
			(xy 134.59282 -243.453845) (xy 134.630941 -243.42272) (xy 134.673562 -243.398113) (xy 134.719578 -243.380661)
			(xy 134.767797 -243.370817) (xy 134.816972 -243.368836) (xy 134.865827 -243.374768) (xy 134.913098 -243.38846)
			(xy 134.95756 -243.409558) (xy 134.998063 -243.437514) (xy 135.033556 -243.471606) (xy 135.063121 -243.51095)
			(xy 135.085992 -243.554527) (xy 135.101576 -243.601208) (xy 135.109471 -243.649785) (xy 135.109966 -243.674392)
			(xy 135.438908 -243.674392) (xy 135.442868 -243.625338) (xy 135.454645 -243.577554) (xy 135.473936 -243.532278)
			(xy 135.500239 -243.490682) (xy 135.532874 -243.453845) (xy 135.570995 -243.42272) (xy 135.613616 -243.398113)
			(xy 135.659632 -243.380661) (xy 135.707851 -243.370817) (xy 135.757026 -243.368836) (xy 135.805881 -243.374768)
			(xy 135.853152 -243.38846) (xy 135.897614 -243.409558) (xy 135.938117 -243.437514) (xy 135.97361 -243.471606)
			(xy 136.003175 -243.51095) (xy 136.026046 -243.554527) (xy 136.04163 -243.601208) (xy 136.049525 -243.649785)
			(xy 136.05002 -243.674392) (xy 136.049525 -243.698999) (xy 136.04163 -243.747576) (xy 136.026046 -243.794257)
			(xy 136.003175 -243.837834) (xy 135.97361 -243.877178) (xy 135.938117 -243.91127) (xy 135.897614 -243.939226)
			(xy 135.853152 -243.960324) (xy 135.805881 -243.974016) (xy 135.757026 -243.979948) (xy 135.707851 -243.977967)
			(xy 135.659632 -243.968123) (xy 135.613616 -243.950671) (xy 135.570995 -243.926064) (xy 135.532874 -243.894939)
			(xy 135.500239 -243.858102) (xy 135.473936 -243.816506) (xy 135.454645 -243.77123) (xy 135.442868 -243.723446)
			(xy 135.438908 -243.674392) (xy 135.109966 -243.674392) (xy 135.109471 -243.698999) (xy 135.101576 -243.747576)
			(xy 135.085992 -243.794257) (xy 135.063121 -243.837834) (xy 135.033556 -243.877178) (xy 134.998063 -243.91127)
			(xy 134.95756 -243.939226) (xy 134.913098 -243.960324) (xy 134.865827 -243.974016) (xy 134.816972 -243.979948)
			(xy 134.767797 -243.977967) (xy 134.719578 -243.968123) (xy 134.673562 -243.950671) (xy 134.630941 -243.926064)
			(xy 134.59282 -243.894939) (xy 134.560185 -243.858102) (xy 134.533882 -243.816506) (xy 134.514591 -243.77123)
			(xy 134.502814 -243.723446) (xy 134.498854 -243.674392) (xy 134.170166 -243.674392) (xy 134.169671 -243.698999)
			(xy 134.161776 -243.747576) (xy 134.146192 -243.794257) (xy 134.123321 -243.837834) (xy 134.093756 -243.877178)
			(xy 134.058263 -243.91127) (xy 134.01776 -243.939226) (xy 133.973298 -243.960324) (xy 133.926027 -243.974016)
			(xy 133.877172 -243.979948) (xy 133.827997 -243.977967) (xy 133.779778 -243.968123) (xy 133.733762 -243.950671)
			(xy 133.691141 -243.926064) (xy 133.65302 -243.894939) (xy 133.620385 -243.858102) (xy 133.594082 -243.816506)
			(xy 133.574791 -243.77123) (xy 133.563014 -243.723446) (xy 133.559054 -243.674392) (xy 133.240526 -243.674392)
			(xy 133.240014 -243.699838) (xy 133.23185 -243.750072) (xy 133.215734 -243.798346) (xy 133.192083 -243.843409)
			(xy 133.16151 -243.884095) (xy 133.124806 -243.91935) (xy 133.082922 -243.94826) (xy 133.036943 -243.970077)
			(xy 132.988059 -243.984237) (xy 132.937538 -243.990371) (xy 132.886686 -243.988322) (xy 132.836822 -243.978142)
			(xy 132.789236 -243.960095) (xy 132.745162 -243.934649) (xy 132.70574 -243.902462) (xy 132.671992 -243.864368)
			(xy 132.644791 -243.821354) (xy 132.624843 -243.774534) (xy 132.612664 -243.72512) (xy 132.608569 -243.674392)
			(xy 132.290058 -243.674392) (xy 132.289563 -243.698999) (xy 132.281668 -243.747576) (xy 132.266084 -243.794257)
			(xy 132.243213 -243.837834) (xy 132.213648 -243.877178) (xy 132.178155 -243.91127) (xy 132.137652 -243.939226)
			(xy 132.09319 -243.960324) (xy 132.045919 -243.974016) (xy 131.997064 -243.979948) (xy 131.947889 -243.977967)
			(xy 131.89967 -243.968123) (xy 131.853654 -243.950671) (xy 131.811033 -243.926064) (xy 131.772912 -243.894939)
			(xy 131.740277 -243.858102) (xy 131.713974 -243.816506) (xy 131.694683 -243.77123) (xy 131.682906 -243.723446)
			(xy 131.678946 -243.674392) (xy 131.360418 -243.674392) (xy 131.359906 -243.699838) (xy 131.351742 -243.750072)
			(xy 131.335626 -243.798346) (xy 131.311975 -243.843409) (xy 131.281402 -243.884095) (xy 131.244698 -243.91935)
			(xy 131.202814 -243.94826) (xy 131.156835 -243.970077) (xy 131.107951 -243.984237) (xy 131.05743 -243.990371)
			(xy 131.006578 -243.988322) (xy 130.956714 -243.978142) (xy 130.909128 -243.960095) (xy 130.865054 -243.934649)
			(xy 130.825632 -243.902462) (xy 130.791884 -243.864368) (xy 130.764683 -243.821354) (xy 130.744735 -243.774534)
			(xy 130.732556 -243.72512) (xy 130.728461 -243.674392) (xy 130.40995 -243.674392) (xy 130.409455 -243.698999)
			(xy 130.40156 -243.747576) (xy 130.385976 -243.794257) (xy 130.363105 -243.837834) (xy 130.33354 -243.877178)
			(xy 130.298047 -243.91127) (xy 130.257544 -243.939226) (xy 130.213082 -243.960324) (xy 130.165811 -243.974016)
			(xy 130.116956 -243.979948) (xy 130.067781 -243.977967) (xy 130.019562 -243.968123) (xy 129.973546 -243.950671)
			(xy 129.930925 -243.926064) (xy 129.892804 -243.894939) (xy 129.860169 -243.858102) (xy 129.833866 -243.816506)
			(xy 129.814575 -243.77123) (xy 129.802798 -243.723446) (xy 129.798838 -243.674392) (xy 129.480564 -243.674392)
			(xy 129.480052 -243.699838) (xy 129.471888 -243.750072) (xy 129.455772 -243.798346) (xy 129.432121 -243.843409)
			(xy 129.401548 -243.884095) (xy 129.364844 -243.91935) (xy 129.32296 -243.94826) (xy 129.276981 -243.970077)
			(xy 129.228097 -243.984237) (xy 129.177576 -243.990371) (xy 129.126724 -243.988322) (xy 129.07686 -243.978142)
			(xy 129.029274 -243.960095) (xy 128.9852 -243.934649) (xy 128.945778 -243.902462) (xy 128.91203 -243.864368)
			(xy 128.884829 -243.821354) (xy 128.864881 -243.774534) (xy 128.852702 -243.72512) (xy 128.848607 -243.674392)
			(xy 128.54051 -243.674392) (xy 128.539998 -243.699838) (xy 128.531834 -243.750072) (xy 128.515718 -243.798346)
			(xy 128.492067 -243.843409) (xy 128.461494 -243.884095) (xy 128.42479 -243.91935) (xy 128.382906 -243.94826)
			(xy 128.336927 -243.970077) (xy 128.288043 -243.984237) (xy 128.237522 -243.990371) (xy 128.18667 -243.988322)
			(xy 128.136806 -243.978142) (xy 128.08922 -243.960095) (xy 128.045146 -243.934649) (xy 128.005724 -243.902462)
			(xy 127.971976 -243.864368) (xy 127.944775 -243.821354) (xy 127.924827 -243.774534) (xy 127.912648 -243.72512)
			(xy 127.908553 -243.674392) (xy 126.920498 -243.674392) (xy 126.920498 -244.17909) (xy 126.935738 -244.203728)
			(xy 126.948946 -244.210078) (xy 126.970617 -244.221204) (xy 127.010423 -244.249277) (xy 127.045269 -244.283314)
			(xy 127.074268 -244.322452) (xy 127.096687 -244.365696) (xy 127.111957 -244.411951) (xy 127.11969 -244.460044)
			(xy 127.11969 -244.484398) (xy 127.438399 -244.484398) (xy 127.442494 -244.43367) (xy 127.454673 -244.384256)
			(xy 127.474621 -244.337436) (xy 127.501822 -244.294422) (xy 127.53557 -244.256328) (xy 127.574992 -244.224141)
			(xy 127.619066 -244.198695) (xy 127.666652 -244.180648) (xy 127.716516 -244.170468) (xy 127.767368 -244.168419)
			(xy 127.817889 -244.174553) (xy 127.866773 -244.188713) (xy 127.912752 -244.21053) (xy 127.954636 -244.23944)
			(xy 127.99134 -244.274695) (xy 128.021913 -244.315381) (xy 128.045564 -244.360444) (xy 128.06168 -244.408718)
			(xy 128.069844 -244.458952) (xy 128.070356 -244.484398) (xy 128.388884 -244.484398) (xy 128.392844 -244.435344)
			(xy 128.404621 -244.38756) (xy 128.423912 -244.342284) (xy 128.450215 -244.300688) (xy 128.48285 -244.263851)
			(xy 128.520971 -244.232726) (xy 128.563592 -244.208119) (xy 128.609608 -244.190667) (xy 128.657827 -244.180823)
			(xy 128.707002 -244.178842) (xy 128.755857 -244.184774) (xy 128.803128 -244.198466) (xy 128.84759 -244.219564)
			(xy 128.888093 -244.24752) (xy 128.923586 -244.281612) (xy 128.953151 -244.320956) (xy 128.976022 -244.364533)
			(xy 128.991606 -244.411214) (xy 128.999501 -244.459791) (xy 128.999996 -244.484398) (xy 129.318507 -244.484398)
			(xy 129.322602 -244.43367) (xy 129.334781 -244.384256) (xy 129.354729 -244.337436) (xy 129.38193 -244.294422)
			(xy 129.415678 -244.256328) (xy 129.4551 -244.224141) (xy 129.499174 -244.198695) (xy 129.54676 -244.180648)
			(xy 129.596624 -244.170468) (xy 129.647476 -244.168419) (xy 129.697997 -244.174553) (xy 129.746881 -244.188713)
			(xy 129.79286 -244.21053) (xy 129.834744 -244.23944) (xy 129.871448 -244.274695) (xy 129.902021 -244.315381)
			(xy 129.925672 -244.360444) (xy 129.941788 -244.408718) (xy 129.949952 -244.458952) (xy 129.950464 -244.484398)
			(xy 131.198615 -244.484398) (xy 131.20271 -244.43367) (xy 131.214889 -244.384256) (xy 131.234837 -244.337436)
			(xy 131.262038 -244.294422) (xy 131.295786 -244.256328) (xy 131.335208 -244.224141) (xy 131.379282 -244.198695)
			(xy 131.426868 -244.180648) (xy 131.476732 -244.170468) (xy 131.527584 -244.168419) (xy 131.578105 -244.174553)
			(xy 131.626989 -244.188713) (xy 131.672968 -244.21053) (xy 131.714852 -244.23944) (xy 131.751556 -244.274695)
			(xy 131.782129 -244.315381) (xy 131.80578 -244.360444) (xy 131.821896 -244.408718) (xy 131.83006 -244.458952)
			(xy 131.830572 -244.484398) (xy 132.138415 -244.484398) (xy 132.14251 -244.43367) (xy 132.154689 -244.384256)
			(xy 132.174637 -244.337436) (xy 132.201838 -244.294422) (xy 132.235586 -244.256328) (xy 132.275008 -244.224141)
			(xy 132.319082 -244.198695) (xy 132.366668 -244.180648) (xy 132.416532 -244.170468) (xy 132.467384 -244.168419)
			(xy 132.517905 -244.174553) (xy 132.566789 -244.188713) (xy 132.612768 -244.21053) (xy 132.654652 -244.23944)
			(xy 132.691356 -244.274695) (xy 132.721929 -244.315381) (xy 132.74558 -244.360444) (xy 132.761696 -244.408718)
			(xy 132.76986 -244.458952) (xy 132.770372 -244.484398) (xy 133.0889 -244.484398) (xy 133.09286 -244.435344)
			(xy 133.104637 -244.38756) (xy 133.123928 -244.342284) (xy 133.150231 -244.300688) (xy 133.182866 -244.263851)
			(xy 133.220987 -244.232726) (xy 133.263608 -244.208119) (xy 133.309624 -244.190667) (xy 133.357843 -244.180823)
			(xy 133.407018 -244.178842) (xy 133.455873 -244.184774) (xy 133.503144 -244.198466) (xy 133.547606 -244.219564)
			(xy 133.588109 -244.24752) (xy 133.623602 -244.281612) (xy 133.653167 -244.320956) (xy 133.676038 -244.364533)
			(xy 133.691622 -244.411214) (xy 133.699517 -244.459791) (xy 133.700012 -244.484398) (xy 134.028954 -244.484398)
			(xy 134.032914 -244.435344) (xy 134.044691 -244.38756) (xy 134.063982 -244.342284) (xy 134.090285 -244.300688)
			(xy 134.12292 -244.263851) (xy 134.161041 -244.232726) (xy 134.203662 -244.208119) (xy 134.249678 -244.190667)
			(xy 134.297897 -244.180823) (xy 134.347072 -244.178842) (xy 134.395927 -244.184774) (xy 134.443198 -244.198466)
			(xy 134.48766 -244.219564) (xy 134.528163 -244.24752) (xy 134.563656 -244.281612) (xy 134.593221 -244.320956)
			(xy 134.616092 -244.364533) (xy 134.631676 -244.411214) (xy 134.639571 -244.459791) (xy 134.640066 -244.484398)
			(xy 134.969008 -244.484398) (xy 134.972968 -244.435344) (xy 134.984745 -244.38756) (xy 135.004036 -244.342284)
			(xy 135.030339 -244.300688) (xy 135.062974 -244.263851) (xy 135.101095 -244.232726) (xy 135.143716 -244.208119)
			(xy 135.189732 -244.190667) (xy 135.237951 -244.180823) (xy 135.287126 -244.178842) (xy 135.335981 -244.184774)
			(xy 135.383252 -244.198466) (xy 135.427714 -244.219564) (xy 135.468217 -244.24752) (xy 135.50371 -244.281612)
			(xy 135.533275 -244.320956) (xy 135.556146 -244.364533) (xy 135.57173 -244.411214) (xy 135.579625 -244.459791)
			(xy 135.58012 -244.484398) (xy 135.909062 -244.484398) (xy 135.913022 -244.435344) (xy 135.924799 -244.38756)
			(xy 135.94409 -244.342284) (xy 135.970393 -244.300688) (xy 136.003028 -244.263851) (xy 136.041149 -244.232726)
			(xy 136.08377 -244.208119) (xy 136.129786 -244.190667) (xy 136.178005 -244.180823) (xy 136.22718 -244.178842)
			(xy 136.276035 -244.184774) (xy 136.323306 -244.198466) (xy 136.367768 -244.219564) (xy 136.408271 -244.24752)
			(xy 136.443764 -244.281612) (xy 136.473329 -244.320956) (xy 136.4962 -244.364533) (xy 136.511784 -244.411214)
			(xy 136.519679 -244.459791) (xy 136.520174 -244.484398) (xy 136.519679 -244.509005) (xy 136.511784 -244.557582)
			(xy 136.4962 -244.604263) (xy 136.473329 -244.64784) (xy 136.443764 -244.687184) (xy 136.408271 -244.721276)
			(xy 136.367768 -244.749232) (xy 136.323306 -244.77033) (xy 136.276035 -244.784022) (xy 136.22718 -244.789954)
			(xy 136.178005 -244.787973) (xy 136.129786 -244.778129) (xy 136.08377 -244.760677) (xy 136.041149 -244.73607)
			(xy 136.003028 -244.704945) (xy 135.970393 -244.668108) (xy 135.94409 -244.626512) (xy 135.924799 -244.581236)
			(xy 135.913022 -244.533452) (xy 135.909062 -244.484398) (xy 135.58012 -244.484398) (xy 135.579625 -244.509005)
			(xy 135.57173 -244.557582) (xy 135.556146 -244.604263) (xy 135.533275 -244.64784) (xy 135.50371 -244.687184)
			(xy 135.468217 -244.721276) (xy 135.427714 -244.749232) (xy 135.383252 -244.77033) (xy 135.335981 -244.784022)
			(xy 135.287126 -244.789954) (xy 135.237951 -244.787973) (xy 135.189732 -244.778129) (xy 135.143716 -244.760677)
			(xy 135.101095 -244.73607) (xy 135.062974 -244.704945) (xy 135.030339 -244.668108) (xy 135.004036 -244.626512)
			(xy 134.984745 -244.581236) (xy 134.972968 -244.533452) (xy 134.969008 -244.484398) (xy 134.640066 -244.484398)
			(xy 134.639571 -244.509005) (xy 134.631676 -244.557582) (xy 134.616092 -244.604263) (xy 134.593221 -244.64784)
			(xy 134.563656 -244.687184) (xy 134.528163 -244.721276) (xy 134.48766 -244.749232) (xy 134.443198 -244.77033)
			(xy 134.395927 -244.784022) (xy 134.347072 -244.789954) (xy 134.297897 -244.787973) (xy 134.249678 -244.778129)
			(xy 134.203662 -244.760677) (xy 134.161041 -244.73607) (xy 134.12292 -244.704945) (xy 134.090285 -244.668108)
			(xy 134.063982 -244.626512) (xy 134.044691 -244.581236) (xy 134.032914 -244.533452) (xy 134.028954 -244.484398)
			(xy 133.700012 -244.484398) (xy 133.699517 -244.509005) (xy 133.691622 -244.557582) (xy 133.676038 -244.604263)
			(xy 133.653167 -244.64784) (xy 133.623602 -244.687184) (xy 133.588109 -244.721276) (xy 133.547606 -244.749232)
			(xy 133.503144 -244.77033) (xy 133.455873 -244.784022) (xy 133.407018 -244.789954) (xy 133.357843 -244.787973)
			(xy 133.309624 -244.778129) (xy 133.263608 -244.760677) (xy 133.220987 -244.73607) (xy 133.182866 -244.704945)
			(xy 133.150231 -244.668108) (xy 133.123928 -244.626512) (xy 133.104637 -244.581236) (xy 133.09286 -244.533452)
			(xy 133.0889 -244.484398) (xy 132.770372 -244.484398) (xy 132.76986 -244.509844) (xy 132.761696 -244.560078)
			(xy 132.74558 -244.608352) (xy 132.721929 -244.653415) (xy 132.691356 -244.694101) (xy 132.654652 -244.729356)
			(xy 132.612768 -244.758266) (xy 132.566789 -244.780083) (xy 132.517905 -244.794243) (xy 132.467384 -244.800377)
			(xy 132.416532 -244.798328) (xy 132.366668 -244.788148) (xy 132.319082 -244.770101) (xy 132.275008 -244.744655)
			(xy 132.235586 -244.712468) (xy 132.201838 -244.674374) (xy 132.174637 -244.63136) (xy 132.154689 -244.58454)
			(xy 132.14251 -244.535126) (xy 132.138415 -244.484398) (xy 131.830572 -244.484398) (xy 131.83006 -244.509844)
			(xy 131.821896 -244.560078) (xy 131.80578 -244.608352) (xy 131.782129 -244.653415) (xy 131.751556 -244.694101)
			(xy 131.714852 -244.729356) (xy 131.672968 -244.758266) (xy 131.626989 -244.780083) (xy 131.578105 -244.794243)
			(xy 131.527584 -244.800377) (xy 131.476732 -244.798328) (xy 131.426868 -244.788148) (xy 131.379282 -244.770101)
			(xy 131.335208 -244.744655) (xy 131.295786 -244.712468) (xy 131.262038 -244.674374) (xy 131.234837 -244.63136)
			(xy 131.214889 -244.58454) (xy 131.20271 -244.535126) (xy 131.198615 -244.484398) (xy 129.950464 -244.484398)
			(xy 129.949952 -244.509844) (xy 129.941788 -244.560078) (xy 129.925672 -244.608352) (xy 129.902021 -244.653415)
			(xy 129.871448 -244.694101) (xy 129.834744 -244.729356) (xy 129.79286 -244.758266) (xy 129.746881 -244.780083)
			(xy 129.697997 -244.794243) (xy 129.647476 -244.800377) (xy 129.596624 -244.798328) (xy 129.54676 -244.788148)
			(xy 129.499174 -244.770101) (xy 129.4551 -244.744655) (xy 129.415678 -244.712468) (xy 129.38193 -244.674374)
			(xy 129.354729 -244.63136) (xy 129.334781 -244.58454) (xy 129.322602 -244.535126) (xy 129.318507 -244.484398)
			(xy 128.999996 -244.484398) (xy 128.999501 -244.509005) (xy 128.991606 -244.557582) (xy 128.976022 -244.604263)
			(xy 128.953151 -244.64784) (xy 128.923586 -244.687184) (xy 128.888093 -244.721276) (xy 128.84759 -244.749232)
			(xy 128.803128 -244.77033) (xy 128.755857 -244.784022) (xy 128.707002 -244.789954) (xy 128.657827 -244.787973)
			(xy 128.609608 -244.778129) (xy 128.563592 -244.760677) (xy 128.520971 -244.73607) (xy 128.48285 -244.704945)
			(xy 128.450215 -244.668108) (xy 128.423912 -244.626512) (xy 128.404621 -244.581236) (xy 128.392844 -244.533452)
			(xy 128.388884 -244.484398) (xy 128.070356 -244.484398) (xy 128.069844 -244.509844) (xy 128.06168 -244.560078)
			(xy 128.045564 -244.608352) (xy 128.021913 -244.653415) (xy 127.99134 -244.694101) (xy 127.954636 -244.729356)
			(xy 127.912752 -244.758266) (xy 127.866773 -244.780083) (xy 127.817889 -244.794243) (xy 127.767368 -244.800377)
			(xy 127.716516 -244.798328) (xy 127.666652 -244.788148) (xy 127.619066 -244.770101) (xy 127.574992 -244.744655)
			(xy 127.53557 -244.712468) (xy 127.501822 -244.674374) (xy 127.474621 -244.63136) (xy 127.454673 -244.58454)
			(xy 127.442494 -244.535126) (xy 127.438399 -244.484398) (xy 127.11969 -244.484398) (xy 127.11969 -244.508754)
			(xy 127.111958 -244.556847) (xy 127.096688 -244.603102) (xy 127.074269 -244.646347) (xy 127.04527 -244.685484)
			(xy 127.010425 -244.719522) (xy 126.970618 -244.747595) (xy 126.948946 -244.758718) (xy 126.935738 -244.765068)
			(xy 126.920498 -244.789706) (xy 126.920498 -244.983508) (xy 126.920931 -244.993187) (xy 126.928091 -245.011176)
			(xy 126.941365 -245.025269) (xy 126.949962 -245.029736) (xy 127.04699 -245.074694) (xy 127.076454 -245.070884)
			(xy 127.08763 -245.061232) (xy 127.108459 -245.044353) (xy 127.154808 -245.01742) (xy 127.205147 -244.998994)
			(xy 127.257931 -244.98964) (xy 127.284734 -244.989096) (xy 127.309987 -244.98962) (xy 127.359804 -244.997938)
			(xy 127.407572 -245.014342) (xy 127.45199 -245.038384) (xy 127.491844 -245.069408) (xy 127.526049 -245.106568)
			(xy 127.553672 -245.148852) (xy 127.573959 -245.195105) (xy 127.586357 -245.244066) (xy 127.590527 -245.2944)
			(xy 127.590527 -245.294404) (xy 127.908553 -245.294404) (xy 127.912648 -245.243676) (xy 127.924827 -245.194262)
			(xy 127.944775 -245.147442) (xy 127.971976 -245.104428) (xy 128.005724 -245.066334) (xy 128.045146 -245.034147)
			(xy 128.08922 -245.008701) (xy 128.136806 -244.990654) (xy 128.18667 -244.980474) (xy 128.237522 -244.978425)
			(xy 128.288043 -244.984559) (xy 128.336927 -244.998719) (xy 128.382906 -245.020536) (xy 128.42479 -245.049446)
			(xy 128.461494 -245.084701) (xy 128.492067 -245.125387) (xy 128.515718 -245.17045) (xy 128.531834 -245.218724)
			(xy 128.539998 -245.268958) (xy 128.54051 -245.294404) (xy 128.848607 -245.294404) (xy 128.852702 -245.243676)
			(xy 128.864881 -245.194262) (xy 128.884829 -245.147442) (xy 128.91203 -245.104428) (xy 128.945778 -245.066334)
			(xy 128.9852 -245.034147) (xy 129.029274 -245.008701) (xy 129.07686 -244.990654) (xy 129.126724 -244.980474)
			(xy 129.177576 -244.978425) (xy 129.228097 -244.984559) (xy 129.276981 -244.998719) (xy 129.32296 -245.020536)
			(xy 129.364844 -245.049446) (xy 129.401548 -245.084701) (xy 129.432121 -245.125387) (xy 129.455772 -245.17045)
			(xy 129.471888 -245.218724) (xy 129.480052 -245.268958) (xy 129.480564 -245.294404) (xy 129.798838 -245.294404)
			(xy 129.802798 -245.24535) (xy 129.814575 -245.197566) (xy 129.833866 -245.15229) (xy 129.860169 -245.110694)
			(xy 129.892804 -245.073857) (xy 129.930925 -245.042732) (xy 129.973546 -245.018125) (xy 130.019562 -245.000673)
			(xy 130.067781 -244.990829) (xy 130.116956 -244.988848) (xy 130.165811 -244.99478) (xy 130.213082 -245.008472)
			(xy 130.257544 -245.02957) (xy 130.298047 -245.057526) (xy 130.33354 -245.091618) (xy 130.363105 -245.130962)
			(xy 130.385976 -245.174539) (xy 130.40156 -245.22122) (xy 130.409455 -245.269797) (xy 130.40995 -245.294404)
			(xy 130.728461 -245.294404) (xy 130.732556 -245.243676) (xy 130.744735 -245.194262) (xy 130.764683 -245.147442)
			(xy 130.791884 -245.104428) (xy 130.825632 -245.066334) (xy 130.865054 -245.034147) (xy 130.909128 -245.008701)
			(xy 130.956714 -244.990654) (xy 131.006578 -244.980474) (xy 131.05743 -244.978425) (xy 131.107951 -244.984559)
			(xy 131.156835 -244.998719) (xy 131.202814 -245.020536) (xy 131.244698 -245.049446) (xy 131.281402 -245.084701)
			(xy 131.311975 -245.125387) (xy 131.335626 -245.17045) (xy 131.351742 -245.218724) (xy 131.359906 -245.268958)
			(xy 131.360418 -245.294404) (xy 131.678946 -245.294404) (xy 131.682906 -245.24535) (xy 131.694683 -245.197566)
			(xy 131.713974 -245.15229) (xy 131.740277 -245.110694) (xy 131.772912 -245.073857) (xy 131.811033 -245.042732)
			(xy 131.853654 -245.018125) (xy 131.89967 -245.000673) (xy 131.947889 -244.990829) (xy 131.997064 -244.988848)
			(xy 132.045919 -244.99478) (xy 132.09319 -245.008472) (xy 132.137652 -245.02957) (xy 132.178155 -245.057526)
			(xy 132.213648 -245.091618) (xy 132.243213 -245.130962) (xy 132.266084 -245.174539) (xy 132.281668 -245.22122)
			(xy 132.289563 -245.269797) (xy 132.290058 -245.294404) (xy 132.608569 -245.294404) (xy 132.612664 -245.243676)
			(xy 132.624843 -245.194262) (xy 132.644791 -245.147442) (xy 132.671992 -245.104428) (xy 132.70574 -245.066334)
			(xy 132.745162 -245.034147) (xy 132.789236 -245.008701) (xy 132.836822 -244.990654) (xy 132.886686 -244.980474)
			(xy 132.937538 -244.978425) (xy 132.988059 -244.984559) (xy 133.036943 -244.998719) (xy 133.082922 -245.020536)
			(xy 133.124806 -245.049446) (xy 133.16151 -245.084701) (xy 133.192083 -245.125387) (xy 133.215734 -245.17045)
			(xy 133.23185 -245.218724) (xy 133.240014 -245.268958) (xy 133.240526 -245.294404) (xy 133.559054 -245.294404)
			(xy 133.563014 -245.24535) (xy 133.574791 -245.197566) (xy 133.594082 -245.15229) (xy 133.620385 -245.110694)
			(xy 133.65302 -245.073857) (xy 133.691141 -245.042732) (xy 133.733762 -245.018125) (xy 133.779778 -245.000673)
			(xy 133.827997 -244.990829) (xy 133.877172 -244.988848) (xy 133.926027 -244.99478) (xy 133.973298 -245.008472)
			(xy 134.01776 -245.02957) (xy 134.058263 -245.057526) (xy 134.093756 -245.091618) (xy 134.123321 -245.130962)
			(xy 134.146192 -245.174539) (xy 134.161776 -245.22122) (xy 134.169671 -245.269797) (xy 134.170166 -245.294404)
			(xy 134.498854 -245.294404) (xy 134.502814 -245.24535) (xy 134.514591 -245.197566) (xy 134.533882 -245.15229)
			(xy 134.560185 -245.110694) (xy 134.59282 -245.073857) (xy 134.630941 -245.042732) (xy 134.673562 -245.018125)
			(xy 134.719578 -245.000673) (xy 134.767797 -244.990829) (xy 134.816972 -244.988848) (xy 134.865827 -244.99478)
			(xy 134.913098 -245.008472) (xy 134.95756 -245.02957) (xy 134.998063 -245.057526) (xy 135.033556 -245.091618)
			(xy 135.063121 -245.130962) (xy 135.085992 -245.174539) (xy 135.101576 -245.22122) (xy 135.109471 -245.269797)
			(xy 135.109966 -245.294404) (xy 135.438908 -245.294404) (xy 135.442868 -245.24535) (xy 135.454645 -245.197566)
			(xy 135.473936 -245.15229) (xy 135.500239 -245.110694) (xy 135.532874 -245.073857) (xy 135.570995 -245.042732)
			(xy 135.613616 -245.018125) (xy 135.659632 -245.000673) (xy 135.707851 -244.990829) (xy 135.757026 -244.988848)
			(xy 135.805881 -244.99478) (xy 135.853152 -245.008472) (xy 135.897614 -245.02957) (xy 135.938117 -245.057526)
			(xy 135.97361 -245.091618) (xy 136.003175 -245.130962) (xy 136.026046 -245.174539) (xy 136.04163 -245.22122)
			(xy 136.049525 -245.269797) (xy 136.05002 -245.294404) (xy 136.049525 -245.319011) (xy 136.04163 -245.367588)
			(xy 136.026046 -245.414269) (xy 136.003175 -245.457846) (xy 135.97361 -245.49719) (xy 135.938117 -245.531282)
			(xy 135.897614 -245.559238) (xy 135.853152 -245.580336) (xy 135.805881 -245.594028) (xy 135.757026 -245.59996)
			(xy 135.707851 -245.597979) (xy 135.659632 -245.588135) (xy 135.613616 -245.570683) (xy 135.570995 -245.546076)
			(xy 135.532874 -245.514951) (xy 135.500239 -245.478114) (xy 135.473936 -245.436518) (xy 135.454645 -245.391242)
			(xy 135.442868 -245.343458) (xy 135.438908 -245.294404) (xy 135.109966 -245.294404) (xy 135.109471 -245.319011)
			(xy 135.101576 -245.367588) (xy 135.085992 -245.414269) (xy 135.063121 -245.457846) (xy 135.033556 -245.49719)
			(xy 134.998063 -245.531282) (xy 134.95756 -245.559238) (xy 134.913098 -245.580336) (xy 134.865827 -245.594028)
			(xy 134.816972 -245.59996) (xy 134.767797 -245.597979) (xy 134.719578 -245.588135) (xy 134.673562 -245.570683)
			(xy 134.630941 -245.546076) (xy 134.59282 -245.514951) (xy 134.560185 -245.478114) (xy 134.533882 -245.436518)
			(xy 134.514591 -245.391242) (xy 134.502814 -245.343458) (xy 134.498854 -245.294404) (xy 134.170166 -245.294404)
			(xy 134.169671 -245.319011) (xy 134.161776 -245.367588) (xy 134.146192 -245.414269) (xy 134.123321 -245.457846)
			(xy 134.093756 -245.49719) (xy 134.058263 -245.531282) (xy 134.01776 -245.559238) (xy 133.973298 -245.580336)
			(xy 133.926027 -245.594028) (xy 133.877172 -245.59996) (xy 133.827997 -245.597979) (xy 133.779778 -245.588135)
			(xy 133.733762 -245.570683) (xy 133.691141 -245.546076) (xy 133.65302 -245.514951) (xy 133.620385 -245.478114)
			(xy 133.594082 -245.436518) (xy 133.574791 -245.391242) (xy 133.563014 -245.343458) (xy 133.559054 -245.294404)
			(xy 133.240526 -245.294404) (xy 133.240014 -245.31985) (xy 133.23185 -245.370084) (xy 133.215734 -245.418358)
			(xy 133.192083 -245.463421) (xy 133.16151 -245.504107) (xy 133.124806 -245.539362) (xy 133.082922 -245.568272)
			(xy 133.036943 -245.590089) (xy 132.988059 -245.604249) (xy 132.937538 -245.610383) (xy 132.886686 -245.608334)
			(xy 132.836822 -245.598154) (xy 132.789236 -245.580107) (xy 132.745162 -245.554661) (xy 132.70574 -245.522474)
			(xy 132.671992 -245.48438) (xy 132.644791 -245.441366) (xy 132.624843 -245.394546) (xy 132.612664 -245.345132)
			(xy 132.608569 -245.294404) (xy 132.290058 -245.294404) (xy 132.289563 -245.319011) (xy 132.281668 -245.367588)
			(xy 132.266084 -245.414269) (xy 132.243213 -245.457846) (xy 132.213648 -245.49719) (xy 132.178155 -245.531282)
			(xy 132.137652 -245.559238) (xy 132.09319 -245.580336) (xy 132.045919 -245.594028) (xy 131.997064 -245.59996)
			(xy 131.947889 -245.597979) (xy 131.89967 -245.588135) (xy 131.853654 -245.570683) (xy 131.811033 -245.546076)
			(xy 131.772912 -245.514951) (xy 131.740277 -245.478114) (xy 131.713974 -245.436518) (xy 131.694683 -245.391242)
			(xy 131.682906 -245.343458) (xy 131.678946 -245.294404) (xy 131.360418 -245.294404) (xy 131.359906 -245.31985)
			(xy 131.351742 -245.370084) (xy 131.335626 -245.418358) (xy 131.311975 -245.463421) (xy 131.281402 -245.504107)
			(xy 131.244698 -245.539362) (xy 131.202814 -245.568272) (xy 131.156835 -245.590089) (xy 131.107951 -245.604249)
			(xy 131.05743 -245.610383) (xy 131.006578 -245.608334) (xy 130.956714 -245.598154) (xy 130.909128 -245.580107)
			(xy 130.865054 -245.554661) (xy 130.825632 -245.522474) (xy 130.791884 -245.48438) (xy 130.764683 -245.441366)
			(xy 130.744735 -245.394546) (xy 130.732556 -245.345132) (xy 130.728461 -245.294404) (xy 130.40995 -245.294404)
			(xy 130.409455 -245.319011) (xy 130.40156 -245.367588) (xy 130.385976 -245.414269) (xy 130.363105 -245.457846)
			(xy 130.33354 -245.49719) (xy 130.298047 -245.531282) (xy 130.257544 -245.559238) (xy 130.213082 -245.580336)
			(xy 130.165811 -245.594028) (xy 130.116956 -245.59996) (xy 130.067781 -245.597979) (xy 130.019562 -245.588135)
			(xy 129.973546 -245.570683) (xy 129.930925 -245.546076) (xy 129.892804 -245.514951) (xy 129.860169 -245.478114)
			(xy 129.833866 -245.436518) (xy 129.814575 -245.391242) (xy 129.802798 -245.343458) (xy 129.798838 -245.294404)
			(xy 129.480564 -245.294404) (xy 129.480052 -245.31985) (xy 129.471888 -245.370084) (xy 129.455772 -245.418358)
			(xy 129.432121 -245.463421) (xy 129.401548 -245.504107) (xy 129.364844 -245.539362) (xy 129.32296 -245.568272)
			(xy 129.276981 -245.590089) (xy 129.228097 -245.604249) (xy 129.177576 -245.610383) (xy 129.126724 -245.608334)
			(xy 129.07686 -245.598154) (xy 129.029274 -245.580107) (xy 128.9852 -245.554661) (xy 128.945778 -245.522474)
			(xy 128.91203 -245.48438) (xy 128.884829 -245.441366) (xy 128.864881 -245.394546) (xy 128.852702 -245.345132)
			(xy 128.848607 -245.294404) (xy 128.54051 -245.294404) (xy 128.539998 -245.31985) (xy 128.531834 -245.370084)
			(xy 128.515718 -245.418358) (xy 128.492067 -245.463421) (xy 128.461494 -245.504107) (xy 128.42479 -245.539362)
			(xy 128.382906 -245.568272) (xy 128.336927 -245.590089) (xy 128.288043 -245.604249) (xy 128.237522 -245.610383)
			(xy 128.18667 -245.608334) (xy 128.136806 -245.598154) (xy 128.08922 -245.580107) (xy 128.045146 -245.554661)
			(xy 128.005724 -245.522474) (xy 127.971976 -245.48438) (xy 127.944775 -245.441366) (xy 127.924827 -245.394546)
			(xy 127.912648 -245.345132) (xy 127.908553 -245.294404) (xy 127.590527 -245.294404) (xy 127.586357 -245.344734)
			(xy 127.573959 -245.393695) (xy 127.553672 -245.439948) (xy 127.526049 -245.482232) (xy 127.491844 -245.519392)
			(xy 127.45199 -245.550416) (xy 127.407572 -245.574458) (xy 127.359804 -245.590862) (xy 127.309987 -245.59918)
			(xy 127.284734 -245.599712) (xy 127.271971 -245.599572) (xy 127.246538 -245.597407) (xy 127.233934 -245.595394)
			(xy 127.207196 -245.590274) (xy 127.155972 -245.571859) (xy 127.108806 -245.544683) (xy 127.08763 -245.527576)
			(xy 127.0762 -245.517924) (xy 127.04699 -245.514114) (xy 126.949962 -245.559072) (xy 126.941343 -245.563515)
			(xy 126.928029 -245.577589) (xy 126.920917 -245.59561) (xy 126.920498 -245.6053) (xy 126.920498 -245.799102)
			(xy 126.935738 -245.82374) (xy 126.948946 -245.83009) (xy 126.971001 -245.841408) (xy 127.011434 -245.870083)
			(xy 127.046706 -245.904911) (xy 127.075891 -245.944977) (xy 127.098224 -245.98923) (xy 127.113117 -246.036509)
			(xy 127.117094 -246.060976) (xy 127.118364 -246.070628) (xy 127.120396 -246.10441) (xy 127.438399 -246.10441)
			(xy 127.442494 -246.053682) (xy 127.454673 -246.004268) (xy 127.474621 -245.957448) (xy 127.501822 -245.914434)
			(xy 127.53557 -245.87634) (xy 127.574992 -245.844153) (xy 127.619066 -245.818707) (xy 127.666652 -245.80066)
			(xy 127.716516 -245.79048) (xy 127.767368 -245.788431) (xy 127.817889 -245.794565) (xy 127.866773 -245.808725)
			(xy 127.912752 -245.830542) (xy 127.954636 -245.859452) (xy 127.99134 -245.894707) (xy 128.021913 -245.935393)
			(xy 128.045564 -245.980456) (xy 128.06168 -246.02873) (xy 128.069844 -246.078964) (xy 128.070356 -246.10441)
			(xy 128.388884 -246.10441) (xy 128.392844 -246.055356) (xy 128.404621 -246.007572) (xy 128.423912 -245.962296)
			(xy 128.450215 -245.9207) (xy 128.48285 -245.883863) (xy 128.520971 -245.852738) (xy 128.563592 -245.828131)
			(xy 128.609608 -245.810679) (xy 128.657827 -245.800835) (xy 128.707002 -245.798854) (xy 128.755857 -245.804786)
			(xy 128.803128 -245.818478) (xy 128.84759 -245.839576) (xy 128.888093 -245.867532) (xy 128.923586 -245.901624)
			(xy 128.953151 -245.940968) (xy 128.976022 -245.984545) (xy 128.991606 -246.031226) (xy 128.999501 -246.079803)
			(xy 128.999996 -246.10441) (xy 129.318507 -246.10441) (xy 129.322602 -246.053682) (xy 129.334781 -246.004268)
			(xy 129.354729 -245.957448) (xy 129.38193 -245.914434) (xy 129.415678 -245.87634) (xy 129.4551 -245.844153)
			(xy 129.499174 -245.818707) (xy 129.54676 -245.80066) (xy 129.596624 -245.79048) (xy 129.647476 -245.788431)
			(xy 129.697997 -245.794565) (xy 129.746881 -245.808725) (xy 129.79286 -245.830542) (xy 129.834744 -245.859452)
			(xy 129.871448 -245.894707) (xy 129.902021 -245.935393) (xy 129.925672 -245.980456) (xy 129.941788 -246.02873)
			(xy 129.949952 -246.078964) (xy 129.950464 -246.10441) (xy 130.268992 -246.10441) (xy 130.272952 -246.055356)
			(xy 130.284729 -246.007572) (xy 130.30402 -245.962296) (xy 130.330323 -245.9207) (xy 130.362958 -245.883863)
			(xy 130.401079 -245.852738) (xy 130.4437 -245.828131) (xy 130.489716 -245.810679) (xy 130.537935 -245.800835)
			(xy 130.58711 -245.798854) (xy 130.635965 -245.804786) (xy 130.683236 -245.818478) (xy 130.727698 -245.839576)
			(xy 130.768201 -245.867532) (xy 130.803694 -245.901624) (xy 130.833259 -245.940968) (xy 130.85613 -245.984545)
			(xy 130.871714 -246.031226) (xy 130.879609 -246.079803) (xy 130.880104 -246.10441) (xy 131.198615 -246.10441)
			(xy 131.20271 -246.053682) (xy 131.214889 -246.004268) (xy 131.234837 -245.957448) (xy 131.262038 -245.914434)
			(xy 131.295786 -245.87634) (xy 131.335208 -245.844153) (xy 131.379282 -245.818707) (xy 131.426868 -245.80066)
			(xy 131.476732 -245.79048) (xy 131.527584 -245.788431) (xy 131.578105 -245.794565) (xy 131.626989 -245.808725)
			(xy 131.672968 -245.830542) (xy 131.714852 -245.859452) (xy 131.751556 -245.894707) (xy 131.782129 -245.935393)
			(xy 131.80578 -245.980456) (xy 131.821896 -246.02873) (xy 131.83006 -246.078964) (xy 131.830572 -246.10441)
			(xy 132.138415 -246.10441) (xy 132.14251 -246.053682) (xy 132.154689 -246.004268) (xy 132.174637 -245.957448)
			(xy 132.201838 -245.914434) (xy 132.235586 -245.87634) (xy 132.275008 -245.844153) (xy 132.319082 -245.818707)
			(xy 132.366668 -245.80066) (xy 132.416532 -245.79048) (xy 132.467384 -245.788431) (xy 132.517905 -245.794565)
			(xy 132.566789 -245.808725) (xy 132.612768 -245.830542) (xy 132.654652 -245.859452) (xy 132.691356 -245.894707)
			(xy 132.721929 -245.935393) (xy 132.74558 -245.980456) (xy 132.761696 -246.02873) (xy 132.76986 -246.078964)
			(xy 132.770372 -246.10441) (xy 133.0889 -246.10441) (xy 133.09286 -246.055356) (xy 133.104637 -246.007572)
			(xy 133.123928 -245.962296) (xy 133.150231 -245.9207) (xy 133.182866 -245.883863) (xy 133.220987 -245.852738)
			(xy 133.263608 -245.828131) (xy 133.309624 -245.810679) (xy 133.357843 -245.800835) (xy 133.407018 -245.798854)
			(xy 133.455873 -245.804786) (xy 133.503144 -245.818478) (xy 133.547606 -245.839576) (xy 133.588109 -245.867532)
			(xy 133.623602 -245.901624) (xy 133.653167 -245.940968) (xy 133.676038 -245.984545) (xy 133.691622 -246.031226)
			(xy 133.699517 -246.079803) (xy 133.700012 -246.10441) (xy 134.028954 -246.10441) (xy 134.032914 -246.055356)
			(xy 134.044691 -246.007572) (xy 134.063982 -245.962296) (xy 134.090285 -245.9207) (xy 134.12292 -245.883863)
			(xy 134.161041 -245.852738) (xy 134.203662 -245.828131) (xy 134.249678 -245.810679) (xy 134.297897 -245.800835)
			(xy 134.347072 -245.798854) (xy 134.395927 -245.804786) (xy 134.443198 -245.818478) (xy 134.48766 -245.839576)
			(xy 134.528163 -245.867532) (xy 134.563656 -245.901624) (xy 134.593221 -245.940968) (xy 134.616092 -245.984545)
			(xy 134.631676 -246.031226) (xy 134.639571 -246.079803) (xy 134.640066 -246.10441) (xy 134.969008 -246.10441)
			(xy 134.972968 -246.055356) (xy 134.984745 -246.007572) (xy 135.004036 -245.962296) (xy 135.030339 -245.9207)
			(xy 135.062974 -245.883863) (xy 135.101095 -245.852738) (xy 135.143716 -245.828131) (xy 135.189732 -245.810679)
			(xy 135.237951 -245.800835) (xy 135.287126 -245.798854) (xy 135.335981 -245.804786) (xy 135.383252 -245.818478)
			(xy 135.427714 -245.839576) (xy 135.468217 -245.867532) (xy 135.50371 -245.901624) (xy 135.533275 -245.940968)
			(xy 135.556146 -245.984545) (xy 135.57173 -246.031226) (xy 135.579625 -246.079803) (xy 135.58012 -246.10441)
			(xy 135.909062 -246.10441) (xy 135.913022 -246.055356) (xy 135.924799 -246.007572) (xy 135.94409 -245.962296)
			(xy 135.970393 -245.9207) (xy 136.003028 -245.883863) (xy 136.041149 -245.852738) (xy 136.08377 -245.828131)
			(xy 136.129786 -245.810679) (xy 136.178005 -245.800835) (xy 136.22718 -245.798854) (xy 136.276035 -245.804786)
			(xy 136.323306 -245.818478) (xy 136.367768 -245.839576) (xy 136.408271 -245.867532) (xy 136.443764 -245.901624)
			(xy 136.473329 -245.940968) (xy 136.4962 -245.984545) (xy 136.511784 -246.031226) (xy 136.519679 -246.079803)
			(xy 136.520174 -246.10441) (xy 136.519679 -246.129017) (xy 136.511784 -246.177594) (xy 136.4962 -246.224275)
			(xy 136.473329 -246.267852) (xy 136.443764 -246.307196) (xy 136.408271 -246.341288) (xy 136.367768 -246.369244)
			(xy 136.323306 -246.390342) (xy 136.276035 -246.404034) (xy 136.22718 -246.409966) (xy 136.178005 -246.407985)
			(xy 136.129786 -246.398141) (xy 136.08377 -246.380689) (xy 136.041149 -246.356082) (xy 136.003028 -246.324957)
			(xy 135.970393 -246.28812) (xy 135.94409 -246.246524) (xy 135.924799 -246.201248) (xy 135.913022 -246.153464)
			(xy 135.909062 -246.10441) (xy 135.58012 -246.10441) (xy 135.579625 -246.129017) (xy 135.57173 -246.177594)
			(xy 135.556146 -246.224275) (xy 135.533275 -246.267852) (xy 135.50371 -246.307196) (xy 135.468217 -246.341288)
			(xy 135.427714 -246.369244) (xy 135.383252 -246.390342) (xy 135.335981 -246.404034) (xy 135.287126 -246.409966)
			(xy 135.237951 -246.407985) (xy 135.189732 -246.398141) (xy 135.143716 -246.380689) (xy 135.101095 -246.356082)
			(xy 135.062974 -246.324957) (xy 135.030339 -246.28812) (xy 135.004036 -246.246524) (xy 134.984745 -246.201248)
			(xy 134.972968 -246.153464) (xy 134.969008 -246.10441) (xy 134.640066 -246.10441) (xy 134.639571 -246.129017)
			(xy 134.631676 -246.177594) (xy 134.616092 -246.224275) (xy 134.593221 -246.267852) (xy 134.563656 -246.307196)
			(xy 134.528163 -246.341288) (xy 134.48766 -246.369244) (xy 134.443198 -246.390342) (xy 134.395927 -246.404034)
			(xy 134.347072 -246.409966) (xy 134.297897 -246.407985) (xy 134.249678 -246.398141) (xy 134.203662 -246.380689)
			(xy 134.161041 -246.356082) (xy 134.12292 -246.324957) (xy 134.090285 -246.28812) (xy 134.063982 -246.246524)
			(xy 134.044691 -246.201248) (xy 134.032914 -246.153464) (xy 134.028954 -246.10441) (xy 133.700012 -246.10441)
			(xy 133.699517 -246.129017) (xy 133.691622 -246.177594) (xy 133.676038 -246.224275) (xy 133.653167 -246.267852)
			(xy 133.623602 -246.307196) (xy 133.588109 -246.341288) (xy 133.547606 -246.369244) (xy 133.503144 -246.390342)
			(xy 133.455873 -246.404034) (xy 133.407018 -246.409966) (xy 133.357843 -246.407985) (xy 133.309624 -246.398141)
			(xy 133.263608 -246.380689) (xy 133.220987 -246.356082) (xy 133.182866 -246.324957) (xy 133.150231 -246.28812)
			(xy 133.123928 -246.246524) (xy 133.104637 -246.201248) (xy 133.09286 -246.153464) (xy 133.0889 -246.10441)
			(xy 132.770372 -246.10441) (xy 132.76986 -246.129856) (xy 132.761696 -246.18009) (xy 132.74558 -246.228364)
			(xy 132.721929 -246.273427) (xy 132.691356 -246.314113) (xy 132.654652 -246.349368) (xy 132.612768 -246.378278)
			(xy 132.566789 -246.400095) (xy 132.517905 -246.414255) (xy 132.467384 -246.420389) (xy 132.416532 -246.41834)
			(xy 132.366668 -246.40816) (xy 132.319082 -246.390113) (xy 132.275008 -246.364667) (xy 132.235586 -246.33248)
			(xy 132.201838 -246.294386) (xy 132.174637 -246.251372) (xy 132.154689 -246.204552) (xy 132.14251 -246.155138)
			(xy 132.138415 -246.10441) (xy 131.830572 -246.10441) (xy 131.83006 -246.129856) (xy 131.821896 -246.18009)
			(xy 131.80578 -246.228364) (xy 131.782129 -246.273427) (xy 131.751556 -246.314113) (xy 131.714852 -246.349368)
			(xy 131.672968 -246.378278) (xy 131.626989 -246.400095) (xy 131.578105 -246.414255) (xy 131.527584 -246.420389)
			(xy 131.476732 -246.41834) (xy 131.426868 -246.40816) (xy 131.379282 -246.390113) (xy 131.335208 -246.364667)
			(xy 131.295786 -246.33248) (xy 131.262038 -246.294386) (xy 131.234837 -246.251372) (xy 131.214889 -246.204552)
			(xy 131.20271 -246.155138) (xy 131.198615 -246.10441) (xy 130.880104 -246.10441) (xy 130.879609 -246.129017)
			(xy 130.871714 -246.177594) (xy 130.85613 -246.224275) (xy 130.833259 -246.267852) (xy 130.803694 -246.307196)
			(xy 130.768201 -246.341288) (xy 130.727698 -246.369244) (xy 130.683236 -246.390342) (xy 130.635965 -246.404034)
			(xy 130.58711 -246.409966) (xy 130.537935 -246.407985) (xy 130.489716 -246.398141) (xy 130.4437 -246.380689)
			(xy 130.401079 -246.356082) (xy 130.362958 -246.324957) (xy 130.330323 -246.28812) (xy 130.30402 -246.246524)
			(xy 130.284729 -246.201248) (xy 130.272952 -246.153464) (xy 130.268992 -246.10441) (xy 129.950464 -246.10441)
			(xy 129.949952 -246.129856) (xy 129.941788 -246.18009) (xy 129.925672 -246.228364) (xy 129.902021 -246.273427)
			(xy 129.871448 -246.314113) (xy 129.834744 -246.349368) (xy 129.79286 -246.378278) (xy 129.746881 -246.400095)
			(xy 129.697997 -246.414255) (xy 129.647476 -246.420389) (xy 129.596624 -246.41834) (xy 129.54676 -246.40816)
			(xy 129.499174 -246.390113) (xy 129.4551 -246.364667) (xy 129.415678 -246.33248) (xy 129.38193 -246.294386)
			(xy 129.354729 -246.251372) (xy 129.334781 -246.204552) (xy 129.322602 -246.155138) (xy 129.318507 -246.10441)
			(xy 128.999996 -246.10441) (xy 128.999501 -246.129017) (xy 128.991606 -246.177594) (xy 128.976022 -246.224275)
			(xy 128.953151 -246.267852) (xy 128.923586 -246.307196) (xy 128.888093 -246.341288) (xy 128.84759 -246.369244)
			(xy 128.803128 -246.390342) (xy 128.755857 -246.404034) (xy 128.707002 -246.409966) (xy 128.657827 -246.407985)
			(xy 128.609608 -246.398141) (xy 128.563592 -246.380689) (xy 128.520971 -246.356082) (xy 128.48285 -246.324957)
			(xy 128.450215 -246.28812) (xy 128.423912 -246.246524) (xy 128.404621 -246.201248) (xy 128.392844 -246.153464)
			(xy 128.388884 -246.10441) (xy 128.070356 -246.10441) (xy 128.069844 -246.129856) (xy 128.06168 -246.18009)
			(xy 128.045564 -246.228364) (xy 128.021913 -246.273427) (xy 127.99134 -246.314113) (xy 127.954636 -246.349368)
			(xy 127.912752 -246.378278) (xy 127.866773 -246.400095) (xy 127.817889 -246.414255) (xy 127.767368 -246.420389)
			(xy 127.716516 -246.41834) (xy 127.666652 -246.40816) (xy 127.619066 -246.390113) (xy 127.574992 -246.364667)
			(xy 127.53557 -246.33248) (xy 127.501822 -246.294386) (xy 127.474621 -246.251372) (xy 127.454673 -246.204552)
			(xy 127.442494 -246.155138) (xy 127.438399 -246.10441) (xy 127.120396 -246.10441) (xy 127.119983 -246.127361)
			(xy 127.113116 -246.172747) (xy 127.099539 -246.216595) (xy 127.079556 -246.25792) (xy 127.053617 -246.295791)
			(xy 127.022305 -246.329356) (xy 127.004572 -246.343932) (xy 126.995936 -246.35079) (xy 126.98603 -246.369586)
			(xy 126.98095 -246.4562) (xy 126.980783 -246.466975) (xy 126.988414 -246.487106) (xy 126.995682 -246.495062)
			(xy 127.071374 -246.570754) (xy 127.078215 -246.578154) (xy 127.085933 -246.596753) (xy 127.08636 -246.606822)
			(xy 127.08636 -246.914416) (xy 127.908553 -246.914416) (xy 127.912648 -246.863688) (xy 127.924827 -246.814274)
			(xy 127.944775 -246.767454) (xy 127.971976 -246.72444) (xy 128.005724 -246.686346) (xy 128.045146 -246.654159)
			(xy 128.08922 -246.628713) (xy 128.136806 -246.610666) (xy 128.18667 -246.600486) (xy 128.237522 -246.598437)
			(xy 128.288043 -246.604571) (xy 128.336927 -246.618731) (xy 128.382906 -246.640548) (xy 128.42479 -246.669458)
			(xy 128.461494 -246.704713) (xy 128.492067 -246.745399) (xy 128.515718 -246.790462) (xy 128.531834 -246.838736)
			(xy 128.539998 -246.88897) (xy 128.54051 -246.914416) (xy 128.848607 -246.914416) (xy 128.852702 -246.863688)
			(xy 128.864881 -246.814274) (xy 128.884829 -246.767454) (xy 128.91203 -246.72444) (xy 128.945778 -246.686346)
			(xy 128.9852 -246.654159) (xy 129.029274 -246.628713) (xy 129.07686 -246.610666) (xy 129.126724 -246.600486)
			(xy 129.177576 -246.598437) (xy 129.228097 -246.604571) (xy 129.276981 -246.618731) (xy 129.32296 -246.640548)
			(xy 129.364844 -246.669458) (xy 129.401548 -246.704713) (xy 129.432121 -246.745399) (xy 129.455772 -246.790462)
			(xy 129.471888 -246.838736) (xy 129.480052 -246.88897) (xy 129.480564 -246.914416) (xy 130.728461 -246.914416)
			(xy 130.732556 -246.863688) (xy 130.744735 -246.814274) (xy 130.764683 -246.767454) (xy 130.791884 -246.72444)
			(xy 130.825632 -246.686346) (xy 130.865054 -246.654159) (xy 130.909128 -246.628713) (xy 130.956714 -246.610666)
			(xy 131.006578 -246.600486) (xy 131.05743 -246.598437) (xy 131.107951 -246.604571) (xy 131.156835 -246.618731)
			(xy 131.202814 -246.640548) (xy 131.244698 -246.669458) (xy 131.281402 -246.704713) (xy 131.311975 -246.745399)
			(xy 131.335626 -246.790462) (xy 131.351742 -246.838736) (xy 131.359906 -246.88897) (xy 131.360418 -246.914416)
			(xy 131.678946 -246.914416) (xy 131.682906 -246.865362) (xy 131.694683 -246.817578) (xy 131.713974 -246.772302)
			(xy 131.740277 -246.730706) (xy 131.772912 -246.693869) (xy 131.811033 -246.662744) (xy 131.853654 -246.638137)
			(xy 131.89967 -246.620685) (xy 131.947889 -246.610841) (xy 131.997064 -246.60886) (xy 132.045919 -246.614792)
			(xy 132.09319 -246.628484) (xy 132.137652 -246.649582) (xy 132.178155 -246.677538) (xy 132.213648 -246.71163)
			(xy 132.243213 -246.750974) (xy 132.266084 -246.794551) (xy 132.281668 -246.841232) (xy 132.289563 -246.889809)
			(xy 132.290058 -246.914416) (xy 132.608569 -246.914416) (xy 132.612664 -246.863688) (xy 132.624843 -246.814274)
			(xy 132.644791 -246.767454) (xy 132.671992 -246.72444) (xy 132.70574 -246.686346) (xy 132.745162 -246.654159)
			(xy 132.789236 -246.628713) (xy 132.836822 -246.610666) (xy 132.886686 -246.600486) (xy 132.937538 -246.598437)
			(xy 132.988059 -246.604571) (xy 133.036943 -246.618731) (xy 133.082922 -246.640548) (xy 133.124806 -246.669458)
			(xy 133.16151 -246.704713) (xy 133.192083 -246.745399) (xy 133.215734 -246.790462) (xy 133.23185 -246.838736)
			(xy 133.240014 -246.88897) (xy 133.240526 -246.914416) (xy 133.559054 -246.914416) (xy 133.563014 -246.865362)
			(xy 133.574791 -246.817578) (xy 133.594082 -246.772302) (xy 133.620385 -246.730706) (xy 133.65302 -246.693869)
			(xy 133.691141 -246.662744) (xy 133.733762 -246.638137) (xy 133.779778 -246.620685) (xy 133.827997 -246.610841)
			(xy 133.877172 -246.60886) (xy 133.926027 -246.614792) (xy 133.973298 -246.628484) (xy 134.01776 -246.649582)
			(xy 134.058263 -246.677538) (xy 134.093756 -246.71163) (xy 134.123321 -246.750974) (xy 134.146192 -246.794551)
			(xy 134.161776 -246.841232) (xy 134.169671 -246.889809) (xy 134.170166 -246.914416) (xy 134.498854 -246.914416)
			(xy 134.502814 -246.865362) (xy 134.514591 -246.817578) (xy 134.533882 -246.772302) (xy 134.560185 -246.730706)
			(xy 134.59282 -246.693869) (xy 134.630941 -246.662744) (xy 134.673562 -246.638137) (xy 134.719578 -246.620685)
			(xy 134.767797 -246.610841) (xy 134.816972 -246.60886) (xy 134.865827 -246.614792) (xy 134.913098 -246.628484)
			(xy 134.95756 -246.649582) (xy 134.998063 -246.677538) (xy 135.033556 -246.71163) (xy 135.063121 -246.750974)
			(xy 135.085992 -246.794551) (xy 135.101576 -246.841232) (xy 135.109471 -246.889809) (xy 135.109966 -246.914416)
			(xy 135.438908 -246.914416) (xy 135.442868 -246.865362) (xy 135.454645 -246.817578) (xy 135.473936 -246.772302)
			(xy 135.500239 -246.730706) (xy 135.532874 -246.693869) (xy 135.570995 -246.662744) (xy 135.613616 -246.638137)
			(xy 135.659632 -246.620685) (xy 135.707851 -246.610841) (xy 135.757026 -246.60886) (xy 135.805881 -246.614792)
			(xy 135.853152 -246.628484) (xy 135.897614 -246.649582) (xy 135.938117 -246.677538) (xy 135.97361 -246.71163)
			(xy 136.003175 -246.750974) (xy 136.026046 -246.794551) (xy 136.04163 -246.841232) (xy 136.049525 -246.889809)
			(xy 136.05002 -246.914416) (xy 136.049525 -246.939023) (xy 136.04163 -246.9876) (xy 136.026046 -247.034281)
			(xy 136.003175 -247.077858) (xy 135.97361 -247.117202) (xy 135.938117 -247.151294) (xy 135.897614 -247.17925)
			(xy 135.853152 -247.200348) (xy 135.805881 -247.21404) (xy 135.757026 -247.219972) (xy 135.707851 -247.217991)
			(xy 135.659632 -247.208147) (xy 135.613616 -247.190695) (xy 135.570995 -247.166088) (xy 135.532874 -247.134963)
			(xy 135.500239 -247.098126) (xy 135.473936 -247.05653) (xy 135.454645 -247.011254) (xy 135.442868 -246.96347)
			(xy 135.438908 -246.914416) (xy 135.109966 -246.914416) (xy 135.109471 -246.939023) (xy 135.101576 -246.9876)
			(xy 135.085992 -247.034281) (xy 135.063121 -247.077858) (xy 135.033556 -247.117202) (xy 134.998063 -247.151294)
			(xy 134.95756 -247.17925) (xy 134.913098 -247.200348) (xy 134.865827 -247.21404) (xy 134.816972 -247.219972)
			(xy 134.767797 -247.217991) (xy 134.719578 -247.208147) (xy 134.673562 -247.190695) (xy 134.630941 -247.166088)
			(xy 134.59282 -247.134963) (xy 134.560185 -247.098126) (xy 134.533882 -247.05653) (xy 134.514591 -247.011254)
			(xy 134.502814 -246.96347) (xy 134.498854 -246.914416) (xy 134.170166 -246.914416) (xy 134.169671 -246.939023)
			(xy 134.161776 -246.9876) (xy 134.146192 -247.034281) (xy 134.123321 -247.077858) (xy 134.093756 -247.117202)
			(xy 134.058263 -247.151294) (xy 134.01776 -247.17925) (xy 133.973298 -247.200348) (xy 133.926027 -247.21404)
			(xy 133.877172 -247.219972) (xy 133.827997 -247.217991) (xy 133.779778 -247.208147) (xy 133.733762 -247.190695)
			(xy 133.691141 -247.166088) (xy 133.65302 -247.134963) (xy 133.620385 -247.098126) (xy 133.594082 -247.05653)
			(xy 133.574791 -247.011254) (xy 133.563014 -246.96347) (xy 133.559054 -246.914416) (xy 133.240526 -246.914416)
			(xy 133.240014 -246.939862) (xy 133.23185 -246.990096) (xy 133.215734 -247.03837) (xy 133.192083 -247.083433)
			(xy 133.16151 -247.124119) (xy 133.124806 -247.159374) (xy 133.082922 -247.188284) (xy 133.036943 -247.210101)
			(xy 132.988059 -247.224261) (xy 132.937538 -247.230395) (xy 132.886686 -247.228346) (xy 132.836822 -247.218166)
			(xy 132.789236 -247.200119) (xy 132.745162 -247.174673) (xy 132.70574 -247.142486) (xy 132.671992 -247.104392)
			(xy 132.644791 -247.061378) (xy 132.624843 -247.014558) (xy 132.612664 -246.965144) (xy 132.608569 -246.914416)
			(xy 132.290058 -246.914416) (xy 132.289563 -246.939023) (xy 132.281668 -246.9876) (xy 132.266084 -247.034281)
			(xy 132.243213 -247.077858) (xy 132.213648 -247.117202) (xy 132.178155 -247.151294) (xy 132.137652 -247.17925)
			(xy 132.09319 -247.200348) (xy 132.045919 -247.21404) (xy 131.997064 -247.219972) (xy 131.947889 -247.217991)
			(xy 131.89967 -247.208147) (xy 131.853654 -247.190695) (xy 131.811033 -247.166088) (xy 131.772912 -247.134963)
			(xy 131.740277 -247.098126) (xy 131.713974 -247.05653) (xy 131.694683 -247.011254) (xy 131.682906 -246.96347)
			(xy 131.678946 -246.914416) (xy 131.360418 -246.914416) (xy 131.359906 -246.939862) (xy 131.351742 -246.990096)
			(xy 131.335626 -247.03837) (xy 131.311975 -247.083433) (xy 131.281402 -247.124119) (xy 131.244698 -247.159374)
			(xy 131.202814 -247.188284) (xy 131.156835 -247.210101) (xy 131.107951 -247.224261) (xy 131.05743 -247.230395)
			(xy 131.006578 -247.228346) (xy 130.956714 -247.218166) (xy 130.909128 -247.200119) (xy 130.865054 -247.174673)
			(xy 130.825632 -247.142486) (xy 130.791884 -247.104392) (xy 130.764683 -247.061378) (xy 130.744735 -247.014558)
			(xy 130.732556 -246.965144) (xy 130.728461 -246.914416) (xy 129.480564 -246.914416) (xy 129.480052 -246.939862)
			(xy 129.471888 -246.990096) (xy 129.455772 -247.03837) (xy 129.432121 -247.083433) (xy 129.401548 -247.124119)
			(xy 129.364844 -247.159374) (xy 129.32296 -247.188284) (xy 129.276981 -247.210101) (xy 129.228097 -247.224261)
			(xy 129.177576 -247.230395) (xy 129.126724 -247.228346) (xy 129.07686 -247.218166) (xy 129.029274 -247.200119)
			(xy 128.9852 -247.174673) (xy 128.945778 -247.142486) (xy 128.91203 -247.104392) (xy 128.884829 -247.061378)
			(xy 128.864881 -247.014558) (xy 128.852702 -246.965144) (xy 128.848607 -246.914416) (xy 128.54051 -246.914416)
			(xy 128.539998 -246.939862) (xy 128.531834 -246.990096) (xy 128.515718 -247.03837) (xy 128.492067 -247.083433)
			(xy 128.461494 -247.124119) (xy 128.42479 -247.159374) (xy 128.382906 -247.188284) (xy 128.336927 -247.210101)
			(xy 128.288043 -247.224261) (xy 128.237522 -247.230395) (xy 128.18667 -247.228346) (xy 128.136806 -247.218166)
			(xy 128.08922 -247.200119) (xy 128.045146 -247.174673) (xy 128.005724 -247.142486) (xy 127.971976 -247.104392)
			(xy 127.944775 -247.061378) (xy 127.924827 -247.014558) (xy 127.912648 -246.965144) (xy 127.908553 -246.914416)
			(xy 127.08636 -246.914416) (xy 127.08636 -247.584468) (xy 127.091186 -247.594628) (xy 127.102081 -247.619154)
			(xy 127.11605 -247.670965) (xy 127.120753 -247.72442) (xy 127.120753 -247.724422) (xy 127.438399 -247.724422)
			(xy 127.442494 -247.673694) (xy 127.454673 -247.62428) (xy 127.474621 -247.57746) (xy 127.501822 -247.534446)
			(xy 127.53557 -247.496352) (xy 127.574992 -247.464165) (xy 127.619066 -247.438719) (xy 127.666652 -247.420672)
			(xy 127.716516 -247.410492) (xy 127.767368 -247.408443) (xy 127.817889 -247.414577) (xy 127.866773 -247.428737)
			(xy 127.912752 -247.450554) (xy 127.954636 -247.479464) (xy 127.99134 -247.514719) (xy 128.021913 -247.555405)
			(xy 128.045564 -247.600468) (xy 128.06168 -247.648742) (xy 128.069844 -247.698976) (xy 128.070356 -247.724422)
			(xy 128.388884 -247.724422) (xy 128.392844 -247.675368) (xy 128.404621 -247.627584) (xy 128.423912 -247.582308)
			(xy 128.450215 -247.540712) (xy 128.48285 -247.503875) (xy 128.520971 -247.47275) (xy 128.563592 -247.448143)
			(xy 128.609608 -247.430691) (xy 128.657827 -247.420847) (xy 128.707002 -247.418866) (xy 128.755857 -247.424798)
			(xy 128.803128 -247.43849) (xy 128.84759 -247.459588) (xy 128.888093 -247.487544) (xy 128.923586 -247.521636)
			(xy 128.953151 -247.56098) (xy 128.976022 -247.604557) (xy 128.991606 -247.651238) (xy 128.999501 -247.699815)
			(xy 128.999996 -247.724422) (xy 129.318507 -247.724422) (xy 129.322602 -247.673694) (xy 129.334781 -247.62428)
			(xy 129.354729 -247.57746) (xy 129.38193 -247.534446) (xy 129.415678 -247.496352) (xy 129.4551 -247.464165)
			(xy 129.499174 -247.438719) (xy 129.54676 -247.420672) (xy 129.596624 -247.410492) (xy 129.647476 -247.408443)
			(xy 129.697997 -247.414577) (xy 129.746881 -247.428737) (xy 129.79286 -247.450554) (xy 129.834744 -247.479464)
			(xy 129.871448 -247.514719) (xy 129.902021 -247.555405) (xy 129.925672 -247.600468) (xy 129.941788 -247.648742)
			(xy 129.949952 -247.698976) (xy 129.950464 -247.724422) (xy 130.268992 -247.724422) (xy 130.272952 -247.675368)
			(xy 130.284729 -247.627584) (xy 130.30402 -247.582308) (xy 130.330323 -247.540712) (xy 130.362958 -247.503875)
			(xy 130.401079 -247.47275) (xy 130.4437 -247.448143) (xy 130.489716 -247.430691) (xy 130.537935 -247.420847)
			(xy 130.58711 -247.418866) (xy 130.635965 -247.424798) (xy 130.683236 -247.43849) (xy 130.727698 -247.459588)
			(xy 130.768201 -247.487544) (xy 130.803694 -247.521636) (xy 130.833259 -247.56098) (xy 130.85613 -247.604557)
			(xy 130.871714 -247.651238) (xy 130.879609 -247.699815) (xy 130.880104 -247.724422) (xy 131.198615 -247.724422)
			(xy 131.20271 -247.673694) (xy 131.214889 -247.62428) (xy 131.234837 -247.57746) (xy 131.262038 -247.534446)
			(xy 131.295786 -247.496352) (xy 131.335208 -247.464165) (xy 131.379282 -247.438719) (xy 131.426868 -247.420672)
			(xy 131.476732 -247.410492) (xy 131.527584 -247.408443) (xy 131.578105 -247.414577) (xy 131.626989 -247.428737)
			(xy 131.672968 -247.450554) (xy 131.714852 -247.479464) (xy 131.751556 -247.514719) (xy 131.782129 -247.555405)
			(xy 131.80578 -247.600468) (xy 131.821896 -247.648742) (xy 131.83006 -247.698976) (xy 131.830572 -247.724422)
			(xy 132.138415 -247.724422) (xy 132.14251 -247.673694) (xy 132.154689 -247.62428) (xy 132.174637 -247.57746)
			(xy 132.201838 -247.534446) (xy 132.235586 -247.496352) (xy 132.275008 -247.464165) (xy 132.319082 -247.438719)
			(xy 132.366668 -247.420672) (xy 132.416532 -247.410492) (xy 132.467384 -247.408443) (xy 132.517905 -247.414577)
			(xy 132.566789 -247.428737) (xy 132.612768 -247.450554) (xy 132.654652 -247.479464) (xy 132.691356 -247.514719)
			(xy 132.721929 -247.555405) (xy 132.74558 -247.600468) (xy 132.761696 -247.648742) (xy 132.76986 -247.698976)
			(xy 132.770372 -247.724422) (xy 133.0889 -247.724422) (xy 133.09286 -247.675368) (xy 133.104637 -247.627584)
			(xy 133.123928 -247.582308) (xy 133.150231 -247.540712) (xy 133.182866 -247.503875) (xy 133.220987 -247.47275)
			(xy 133.263608 -247.448143) (xy 133.309624 -247.430691) (xy 133.357843 -247.420847) (xy 133.407018 -247.418866)
			(xy 133.455873 -247.424798) (xy 133.503144 -247.43849) (xy 133.547606 -247.459588) (xy 133.588109 -247.487544)
			(xy 133.623602 -247.521636) (xy 133.653167 -247.56098) (xy 133.676038 -247.604557) (xy 133.691622 -247.651238)
			(xy 133.699517 -247.699815) (xy 133.700012 -247.724422) (xy 134.028954 -247.724422) (xy 134.032914 -247.675368)
			(xy 134.044691 -247.627584) (xy 134.063982 -247.582308) (xy 134.090285 -247.540712) (xy 134.12292 -247.503875)
			(xy 134.161041 -247.47275) (xy 134.203662 -247.448143) (xy 134.249678 -247.430691) (xy 134.297897 -247.420847)
			(xy 134.347072 -247.418866) (xy 134.395927 -247.424798) (xy 134.443198 -247.43849) (xy 134.48766 -247.459588)
			(xy 134.528163 -247.487544) (xy 134.563656 -247.521636) (xy 134.593221 -247.56098) (xy 134.616092 -247.604557)
			(xy 134.631676 -247.651238) (xy 134.639571 -247.699815) (xy 134.640066 -247.724422) (xy 134.969008 -247.724422)
			(xy 134.972968 -247.675368) (xy 134.984745 -247.627584) (xy 135.004036 -247.582308) (xy 135.030339 -247.540712)
			(xy 135.062974 -247.503875) (xy 135.101095 -247.47275) (xy 135.143716 -247.448143) (xy 135.189732 -247.430691)
			(xy 135.237951 -247.420847) (xy 135.287126 -247.418866) (xy 135.335981 -247.424798) (xy 135.383252 -247.43849)
			(xy 135.427714 -247.459588) (xy 135.468217 -247.487544) (xy 135.50371 -247.521636) (xy 135.533275 -247.56098)
			(xy 135.556146 -247.604557) (xy 135.57173 -247.651238) (xy 135.579625 -247.699815) (xy 135.58012 -247.724422)
			(xy 135.909062 -247.724422) (xy 135.913022 -247.675368) (xy 135.924799 -247.627584) (xy 135.94409 -247.582308)
			(xy 135.970393 -247.540712) (xy 136.003028 -247.503875) (xy 136.041149 -247.47275) (xy 136.08377 -247.448143)
			(xy 136.129786 -247.430691) (xy 136.178005 -247.420847) (xy 136.22718 -247.418866) (xy 136.276035 -247.424798)
			(xy 136.323306 -247.43849) (xy 136.367768 -247.459588) (xy 136.408271 -247.487544) (xy 136.443764 -247.521636)
			(xy 136.473329 -247.56098) (xy 136.4962 -247.604557) (xy 136.511784 -247.651238) (xy 136.519679 -247.699815)
			(xy 136.520174 -247.724422) (xy 136.519679 -247.749029) (xy 136.511784 -247.797606) (xy 136.4962 -247.844287)
			(xy 136.473329 -247.887864) (xy 136.443764 -247.927208) (xy 136.408271 -247.9613) (xy 136.367768 -247.989256)
			(xy 136.323306 -248.010354) (xy 136.276035 -248.024046) (xy 136.22718 -248.029978) (xy 136.178005 -248.027997)
			(xy 136.129786 -248.018153) (xy 136.08377 -248.000701) (xy 136.041149 -247.976094) (xy 136.003028 -247.944969)
			(xy 135.970393 -247.908132) (xy 135.94409 -247.866536) (xy 135.924799 -247.82126) (xy 135.913022 -247.773476)
			(xy 135.909062 -247.724422) (xy 135.58012 -247.724422) (xy 135.579625 -247.749029) (xy 135.57173 -247.797606)
			(xy 135.556146 -247.844287) (xy 135.533275 -247.887864) (xy 135.50371 -247.927208) (xy 135.468217 -247.9613)
			(xy 135.427714 -247.989256) (xy 135.383252 -248.010354) (xy 135.335981 -248.024046) (xy 135.287126 -248.029978)
			(xy 135.237951 -248.027997) (xy 135.189732 -248.018153) (xy 135.143716 -248.000701) (xy 135.101095 -247.976094)
			(xy 135.062974 -247.944969) (xy 135.030339 -247.908132) (xy 135.004036 -247.866536) (xy 134.984745 -247.82126)
			(xy 134.972968 -247.773476) (xy 134.969008 -247.724422) (xy 134.640066 -247.724422) (xy 134.639571 -247.749029)
			(xy 134.631676 -247.797606) (xy 134.616092 -247.844287) (xy 134.593221 -247.887864) (xy 134.563656 -247.927208)
			(xy 134.528163 -247.9613) (xy 134.48766 -247.989256) (xy 134.443198 -248.010354) (xy 134.395927 -248.024046)
			(xy 134.347072 -248.029978) (xy 134.297897 -248.027997) (xy 134.249678 -248.018153) (xy 134.203662 -248.000701)
			(xy 134.161041 -247.976094) (xy 134.12292 -247.944969) (xy 134.090285 -247.908132) (xy 134.063982 -247.866536)
			(xy 134.044691 -247.82126) (xy 134.032914 -247.773476) (xy 134.028954 -247.724422) (xy 133.700012 -247.724422)
			(xy 133.699517 -247.749029) (xy 133.691622 -247.797606) (xy 133.676038 -247.844287) (xy 133.653167 -247.887864)
			(xy 133.623602 -247.927208) (xy 133.588109 -247.9613) (xy 133.547606 -247.989256) (xy 133.503144 -248.010354)
			(xy 133.455873 -248.024046) (xy 133.407018 -248.029978) (xy 133.357843 -248.027997) (xy 133.309624 -248.018153)
			(xy 133.263608 -248.000701) (xy 133.220987 -247.976094) (xy 133.182866 -247.944969) (xy 133.150231 -247.908132)
			(xy 133.123928 -247.866536) (xy 133.104637 -247.82126) (xy 133.09286 -247.773476) (xy 133.0889 -247.724422)
			(xy 132.770372 -247.724422) (xy 132.76986 -247.749868) (xy 132.761696 -247.800102) (xy 132.74558 -247.848376)
			(xy 132.721929 -247.893439) (xy 132.691356 -247.934125) (xy 132.654652 -247.96938) (xy 132.612768 -247.99829)
			(xy 132.566789 -248.020107) (xy 132.517905 -248.034267) (xy 132.467384 -248.040401) (xy 132.416532 -248.038352)
			(xy 132.366668 -248.028172) (xy 132.319082 -248.010125) (xy 132.275008 -247.984679) (xy 132.235586 -247.952492)
			(xy 132.201838 -247.914398) (xy 132.174637 -247.871384) (xy 132.154689 -247.824564) (xy 132.14251 -247.77515)
			(xy 132.138415 -247.724422) (xy 131.830572 -247.724422) (xy 131.83006 -247.749868) (xy 131.821896 -247.800102)
			(xy 131.80578 -247.848376) (xy 131.782129 -247.893439) (xy 131.751556 -247.934125) (xy 131.714852 -247.96938)
			(xy 131.672968 -247.99829) (xy 131.626989 -248.020107) (xy 131.578105 -248.034267) (xy 131.527584 -248.040401)
			(xy 131.476732 -248.038352) (xy 131.426868 -248.028172) (xy 131.379282 -248.010125) (xy 131.335208 -247.984679)
			(xy 131.295786 -247.952492) (xy 131.262038 -247.914398) (xy 131.234837 -247.871384) (xy 131.214889 -247.824564)
			(xy 131.20271 -247.77515) (xy 131.198615 -247.724422) (xy 130.880104 -247.724422) (xy 130.879609 -247.749029)
			(xy 130.871714 -247.797606) (xy 130.85613 -247.844287) (xy 130.833259 -247.887864) (xy 130.803694 -247.927208)
			(xy 130.768201 -247.9613) (xy 130.727698 -247.989256) (xy 130.683236 -248.010354) (xy 130.635965 -248.024046)
			(xy 130.58711 -248.029978) (xy 130.537935 -248.027997) (xy 130.489716 -248.018153) (xy 130.4437 -248.000701)
			(xy 130.401079 -247.976094) (xy 130.362958 -247.944969) (xy 130.330323 -247.908132) (xy 130.30402 -247.866536)
			(xy 130.284729 -247.82126) (xy 130.272952 -247.773476) (xy 130.268992 -247.724422) (xy 129.950464 -247.724422)
			(xy 129.949952 -247.749868) (xy 129.941788 -247.800102) (xy 129.925672 -247.848376) (xy 129.902021 -247.893439)
			(xy 129.871448 -247.934125) (xy 129.834744 -247.96938) (xy 129.79286 -247.99829) (xy 129.746881 -248.020107)
			(xy 129.697997 -248.034267) (xy 129.647476 -248.040401) (xy 129.596624 -248.038352) (xy 129.54676 -248.028172)
			(xy 129.499174 -248.010125) (xy 129.4551 -247.984679) (xy 129.415678 -247.952492) (xy 129.38193 -247.914398)
			(xy 129.354729 -247.871384) (xy 129.334781 -247.824564) (xy 129.322602 -247.77515) (xy 129.318507 -247.724422)
			(xy 128.999996 -247.724422) (xy 128.999501 -247.749029) (xy 128.991606 -247.797606) (xy 128.976022 -247.844287)
			(xy 128.953151 -247.887864) (xy 128.923586 -247.927208) (xy 128.888093 -247.9613) (xy 128.84759 -247.989256)
			(xy 128.803128 -248.010354) (xy 128.755857 -248.024046) (xy 128.707002 -248.029978) (xy 128.657827 -248.027997)
			(xy 128.609608 -248.018153) (xy 128.563592 -248.000701) (xy 128.520971 -247.976094) (xy 128.48285 -247.944969)
			(xy 128.450215 -247.908132) (xy 128.423912 -247.866536) (xy 128.404621 -247.82126) (xy 128.392844 -247.773476)
			(xy 128.388884 -247.724422) (xy 128.070356 -247.724422) (xy 128.069844 -247.749868) (xy 128.06168 -247.800102)
			(xy 128.045564 -247.848376) (xy 128.021913 -247.893439) (xy 127.99134 -247.934125) (xy 127.954636 -247.96938)
			(xy 127.912752 -247.99829) (xy 127.866773 -248.020107) (xy 127.817889 -248.034267) (xy 127.767368 -248.040401)
			(xy 127.716516 -248.038352) (xy 127.666652 -248.028172) (xy 127.619066 -248.010125) (xy 127.574992 -247.984679)
			(xy 127.53557 -247.952492) (xy 127.501822 -247.914398) (xy 127.474621 -247.871384) (xy 127.454673 -247.824564)
			(xy 127.442494 -247.77515) (xy 127.438399 -247.724422) (xy 127.120753 -247.724422) (xy 127.116043 -247.777874)
			(xy 127.102067 -247.829684) (xy 127.091186 -247.854216) (xy 127.08636 -247.864376) (xy 127.08636 -248.13895)
			(xy 127.086915 -248.150478) (xy 127.096978 -248.171224) (xy 127.105664 -248.178828) (xy 127.1778 -248.235724)
			(xy 127.200406 -248.24055) (xy 127.211836 -248.237756) (xy 127.229782 -248.233675) (xy 127.266331 -248.229345)
			(xy 127.284734 -248.22912) (xy 127.309985 -248.229644) (xy 127.359798 -248.237962) (xy 127.407563 -248.254364)
			(xy 127.451976 -248.278404) (xy 127.491828 -248.309426) (xy 127.52603 -248.346583) (xy 127.553651 -248.388863)
			(xy 127.573936 -248.435113) (xy 127.586333 -248.48407) (xy 127.590503 -248.5344) (xy 127.590501 -248.534428)
			(xy 127.908553 -248.534428) (xy 127.912648 -248.4837) (xy 127.924827 -248.434286) (xy 127.944775 -248.387466)
			(xy 127.971976 -248.344452) (xy 128.005724 -248.306358) (xy 128.045146 -248.274171) (xy 128.08922 -248.248725)
			(xy 128.136806 -248.230678) (xy 128.18667 -248.220498) (xy 128.237522 -248.218449) (xy 128.288043 -248.224583)
			(xy 128.336927 -248.238743) (xy 128.382906 -248.26056) (xy 128.42479 -248.28947) (xy 128.461494 -248.324725)
			(xy 128.492067 -248.365411) (xy 128.515718 -248.410474) (xy 128.531834 -248.458748) (xy 128.539998 -248.508982)
			(xy 128.54051 -248.534428) (xy 128.848607 -248.534428) (xy 128.852702 -248.4837) (xy 128.864881 -248.434286)
			(xy 128.884829 -248.387466) (xy 128.91203 -248.344452) (xy 128.945778 -248.306358) (xy 128.9852 -248.274171)
			(xy 129.029274 -248.248725) (xy 129.07686 -248.230678) (xy 129.126724 -248.220498) (xy 129.177576 -248.218449)
			(xy 129.228097 -248.224583) (xy 129.276981 -248.238743) (xy 129.32296 -248.26056) (xy 129.364844 -248.28947)
			(xy 129.401548 -248.324725) (xy 129.432121 -248.365411) (xy 129.455772 -248.410474) (xy 129.471888 -248.458748)
			(xy 129.480052 -248.508982) (xy 129.480564 -248.534428) (xy 129.798838 -248.534428) (xy 129.802798 -248.485374)
			(xy 129.814575 -248.43759) (xy 129.833866 -248.392314) (xy 129.860169 -248.350718) (xy 129.892804 -248.313881)
			(xy 129.930925 -248.282756) (xy 129.973546 -248.258149) (xy 130.019562 -248.240697) (xy 130.067781 -248.230853)
			(xy 130.116956 -248.228872) (xy 130.165811 -248.234804) (xy 130.213082 -248.248496) (xy 130.257544 -248.269594)
			(xy 130.298047 -248.29755) (xy 130.33354 -248.331642) (xy 130.363105 -248.370986) (xy 130.385976 -248.414563)
			(xy 130.40156 -248.461244) (xy 130.409455 -248.509821) (xy 130.40995 -248.534428) (xy 130.728461 -248.534428)
			(xy 130.732556 -248.4837) (xy 130.744735 -248.434286) (xy 130.764683 -248.387466) (xy 130.791884 -248.344452)
			(xy 130.825632 -248.306358) (xy 130.865054 -248.274171) (xy 130.909128 -248.248725) (xy 130.956714 -248.230678)
			(xy 131.006578 -248.220498) (xy 131.05743 -248.218449) (xy 131.107951 -248.224583) (xy 131.156835 -248.238743)
			(xy 131.202814 -248.26056) (xy 131.244698 -248.28947) (xy 131.281402 -248.324725) (xy 131.311975 -248.365411)
			(xy 131.335626 -248.410474) (xy 131.351742 -248.458748) (xy 131.359906 -248.508982) (xy 131.360418 -248.534428)
			(xy 131.678946 -248.534428) (xy 131.682906 -248.485374) (xy 131.694683 -248.43759) (xy 131.713974 -248.392314)
			(xy 131.740277 -248.350718) (xy 131.772912 -248.313881) (xy 131.811033 -248.282756) (xy 131.853654 -248.258149)
			(xy 131.89967 -248.240697) (xy 131.947889 -248.230853) (xy 131.997064 -248.228872) (xy 132.045919 -248.234804)
			(xy 132.09319 -248.248496) (xy 132.137652 -248.269594) (xy 132.178155 -248.29755) (xy 132.213648 -248.331642)
			(xy 132.243213 -248.370986) (xy 132.266084 -248.414563) (xy 132.281668 -248.461244) (xy 132.289563 -248.509821)
			(xy 132.290058 -248.534428) (xy 132.608569 -248.534428) (xy 132.612664 -248.4837) (xy 132.624843 -248.434286)
			(xy 132.644791 -248.387466) (xy 132.671992 -248.344452) (xy 132.70574 -248.306358) (xy 132.745162 -248.274171)
			(xy 132.789236 -248.248725) (xy 132.836822 -248.230678) (xy 132.886686 -248.220498) (xy 132.937538 -248.218449)
			(xy 132.988059 -248.224583) (xy 133.036943 -248.238743) (xy 133.082922 -248.26056) (xy 133.124806 -248.28947)
			(xy 133.16151 -248.324725) (xy 133.192083 -248.365411) (xy 133.215734 -248.410474) (xy 133.23185 -248.458748)
			(xy 133.240014 -248.508982) (xy 133.240526 -248.534428) (xy 133.559054 -248.534428) (xy 133.563014 -248.485374)
			(xy 133.574791 -248.43759) (xy 133.594082 -248.392314) (xy 133.620385 -248.350718) (xy 133.65302 -248.313881)
			(xy 133.691141 -248.282756) (xy 133.733762 -248.258149) (xy 133.779778 -248.240697) (xy 133.827997 -248.230853)
			(xy 133.877172 -248.228872) (xy 133.926027 -248.234804) (xy 133.973298 -248.248496) (xy 134.01776 -248.269594)
			(xy 134.058263 -248.29755) (xy 134.093756 -248.331642) (xy 134.123321 -248.370986) (xy 134.146192 -248.414563)
			(xy 134.161776 -248.461244) (xy 134.169671 -248.509821) (xy 134.170166 -248.534428) (xy 134.498854 -248.534428)
			(xy 134.502814 -248.485374) (xy 134.514591 -248.43759) (xy 134.533882 -248.392314) (xy 134.560185 -248.350718)
			(xy 134.59282 -248.313881) (xy 134.630941 -248.282756) (xy 134.673562 -248.258149) (xy 134.719578 -248.240697)
			(xy 134.767797 -248.230853) (xy 134.816972 -248.228872) (xy 134.865827 -248.234804) (xy 134.913098 -248.248496)
			(xy 134.95756 -248.269594) (xy 134.998063 -248.29755) (xy 135.033556 -248.331642) (xy 135.063121 -248.370986)
			(xy 135.085992 -248.414563) (xy 135.101576 -248.461244) (xy 135.109471 -248.509821) (xy 135.109966 -248.534428)
			(xy 135.438908 -248.534428) (xy 135.442868 -248.485374) (xy 135.454645 -248.43759) (xy 135.473936 -248.392314)
			(xy 135.500239 -248.350718) (xy 135.532874 -248.313881) (xy 135.570995 -248.282756) (xy 135.613616 -248.258149)
			(xy 135.659632 -248.240697) (xy 135.707851 -248.230853) (xy 135.757026 -248.228872) (xy 135.805881 -248.234804)
			(xy 135.853152 -248.248496) (xy 135.897614 -248.269594) (xy 135.938117 -248.29755) (xy 135.97361 -248.331642)
			(xy 136.003175 -248.370986) (xy 136.026046 -248.414563) (xy 136.04163 -248.461244) (xy 136.049525 -248.509821)
			(xy 136.05002 -248.534428) (xy 136.049525 -248.559035) (xy 136.04163 -248.607612) (xy 136.026046 -248.654293)
			(xy 136.003175 -248.69787) (xy 135.97361 -248.737214) (xy 135.938117 -248.771306) (xy 135.897614 -248.799262)
			(xy 135.853152 -248.82036) (xy 135.805881 -248.834052) (xy 135.757026 -248.839984) (xy 135.707851 -248.838003)
			(xy 135.659632 -248.828159) (xy 135.613616 -248.810707) (xy 135.570995 -248.7861) (xy 135.532874 -248.754975)
			(xy 135.500239 -248.718138) (xy 135.473936 -248.676542) (xy 135.454645 -248.631266) (xy 135.442868 -248.583482)
			(xy 135.438908 -248.534428) (xy 135.109966 -248.534428) (xy 135.109471 -248.559035) (xy 135.101576 -248.607612)
			(xy 135.085992 -248.654293) (xy 135.063121 -248.69787) (xy 135.033556 -248.737214) (xy 134.998063 -248.771306)
			(xy 134.95756 -248.799262) (xy 134.913098 -248.82036) (xy 134.865827 -248.834052) (xy 134.816972 -248.839984)
			(xy 134.767797 -248.838003) (xy 134.719578 -248.828159) (xy 134.673562 -248.810707) (xy 134.630941 -248.7861)
			(xy 134.59282 -248.754975) (xy 134.560185 -248.718138) (xy 134.533882 -248.676542) (xy 134.514591 -248.631266)
			(xy 134.502814 -248.583482) (xy 134.498854 -248.534428) (xy 134.170166 -248.534428) (xy 134.169671 -248.559035)
			(xy 134.161776 -248.607612) (xy 134.146192 -248.654293) (xy 134.123321 -248.69787) (xy 134.093756 -248.737214)
			(xy 134.058263 -248.771306) (xy 134.01776 -248.799262) (xy 133.973298 -248.82036) (xy 133.926027 -248.834052)
			(xy 133.877172 -248.839984) (xy 133.827997 -248.838003) (xy 133.779778 -248.828159) (xy 133.733762 -248.810707)
			(xy 133.691141 -248.7861) (xy 133.65302 -248.754975) (xy 133.620385 -248.718138) (xy 133.594082 -248.676542)
			(xy 133.574791 -248.631266) (xy 133.563014 -248.583482) (xy 133.559054 -248.534428) (xy 133.240526 -248.534428)
			(xy 133.240014 -248.559874) (xy 133.23185 -248.610108) (xy 133.215734 -248.658382) (xy 133.192083 -248.703445)
			(xy 133.16151 -248.744131) (xy 133.124806 -248.779386) (xy 133.082922 -248.808296) (xy 133.036943 -248.830113)
			(xy 132.988059 -248.844273) (xy 132.937538 -248.850407) (xy 132.886686 -248.848358) (xy 132.836822 -248.838178)
			(xy 132.789236 -248.820131) (xy 132.745162 -248.794685) (xy 132.70574 -248.762498) (xy 132.671992 -248.724404)
			(xy 132.644791 -248.68139) (xy 132.624843 -248.63457) (xy 132.612664 -248.585156) (xy 132.608569 -248.534428)
			(xy 132.290058 -248.534428) (xy 132.289563 -248.559035) (xy 132.281668 -248.607612) (xy 132.266084 -248.654293)
			(xy 132.243213 -248.69787) (xy 132.213648 -248.737214) (xy 132.178155 -248.771306) (xy 132.137652 -248.799262)
			(xy 132.09319 -248.82036) (xy 132.045919 -248.834052) (xy 131.997064 -248.839984) (xy 131.947889 -248.838003)
			(xy 131.89967 -248.828159) (xy 131.853654 -248.810707) (xy 131.811033 -248.7861) (xy 131.772912 -248.754975)
			(xy 131.740277 -248.718138) (xy 131.713974 -248.676542) (xy 131.694683 -248.631266) (xy 131.682906 -248.583482)
			(xy 131.678946 -248.534428) (xy 131.360418 -248.534428) (xy 131.359906 -248.559874) (xy 131.351742 -248.610108)
			(xy 131.335626 -248.658382) (xy 131.311975 -248.703445) (xy 131.281402 -248.744131) (xy 131.244698 -248.779386)
			(xy 131.202814 -248.808296) (xy 131.156835 -248.830113) (xy 131.107951 -248.844273) (xy 131.05743 -248.850407)
			(xy 131.006578 -248.848358) (xy 130.956714 -248.838178) (xy 130.909128 -248.820131) (xy 130.865054 -248.794685)
			(xy 130.825632 -248.762498) (xy 130.791884 -248.724404) (xy 130.764683 -248.68139) (xy 130.744735 -248.63457)
			(xy 130.732556 -248.585156) (xy 130.728461 -248.534428) (xy 130.40995 -248.534428) (xy 130.409455 -248.559035)
			(xy 130.40156 -248.607612) (xy 130.385976 -248.654293) (xy 130.363105 -248.69787) (xy 130.33354 -248.737214)
			(xy 130.298047 -248.771306) (xy 130.257544 -248.799262) (xy 130.213082 -248.82036) (xy 130.165811 -248.834052)
			(xy 130.116956 -248.839984) (xy 130.067781 -248.838003) (xy 130.019562 -248.828159) (xy 129.973546 -248.810707)
			(xy 129.930925 -248.7861) (xy 129.892804 -248.754975) (xy 129.860169 -248.718138) (xy 129.833866 -248.676542)
			(xy 129.814575 -248.631266) (xy 129.802798 -248.583482) (xy 129.798838 -248.534428) (xy 129.480564 -248.534428)
			(xy 129.480052 -248.559874) (xy 129.471888 -248.610108) (xy 129.455772 -248.658382) (xy 129.432121 -248.703445)
			(xy 129.401548 -248.744131) (xy 129.364844 -248.779386) (xy 129.32296 -248.808296) (xy 129.276981 -248.830113)
			(xy 129.228097 -248.844273) (xy 129.177576 -248.850407) (xy 129.126724 -248.848358) (xy 129.07686 -248.838178)
			(xy 129.029274 -248.820131) (xy 128.9852 -248.794685) (xy 128.945778 -248.762498) (xy 128.91203 -248.724404)
			(xy 128.884829 -248.68139) (xy 128.864881 -248.63457) (xy 128.852702 -248.585156) (xy 128.848607 -248.534428)
			(xy 128.54051 -248.534428) (xy 128.539998 -248.559874) (xy 128.531834 -248.610108) (xy 128.515718 -248.658382)
			(xy 128.492067 -248.703445) (xy 128.461494 -248.744131) (xy 128.42479 -248.779386) (xy 128.382906 -248.808296)
			(xy 128.336927 -248.830113) (xy 128.288043 -248.844273) (xy 128.237522 -248.850407) (xy 128.18667 -248.848358)
			(xy 128.136806 -248.838178) (xy 128.08922 -248.820131) (xy 128.045146 -248.794685) (xy 128.005724 -248.762498)
			(xy 127.971976 -248.724404) (xy 127.944775 -248.68139) (xy 127.924827 -248.63457) (xy 127.912648 -248.585156)
			(xy 127.908553 -248.534428) (xy 127.590501 -248.534428) (xy 127.586333 -248.58473) (xy 127.573936 -248.633687)
			(xy 127.553651 -248.679937) (xy 127.52603 -248.722217) (xy 127.491828 -248.759374) (xy 127.451976 -248.790396)
			(xy 127.407563 -248.814436) (xy 127.359798 -248.830838) (xy 127.309985 -248.839156) (xy 127.284734 -248.839736)
			(xy 127.266331 -248.839506) (xy 127.229783 -248.835177) (xy 127.211836 -248.8311) (xy 127.200406 -248.828306)
			(xy 127.1778 -248.833132) (xy 127.105664 -248.890028) (xy 127.096942 -248.897603) (xy 127.086873 -248.918367)
			(xy 127.08636 -248.929906) (xy 127.08636 -249.20448) (xy 127.091186 -249.21464) (xy 127.100338 -249.235039)
			(xy 127.113242 -249.277847) (xy 127.119761 -249.322079) (xy 127.120142 -249.344434) (xy 127.438399 -249.344434)
			(xy 127.442494 -249.293706) (xy 127.454673 -249.244292) (xy 127.474621 -249.197472) (xy 127.501822 -249.154458)
			(xy 127.53557 -249.116364) (xy 127.574992 -249.084177) (xy 127.619066 -249.058731) (xy 127.666652 -249.040684)
			(xy 127.716516 -249.030504) (xy 127.767368 -249.028455) (xy 127.817889 -249.034589) (xy 127.866773 -249.048749)
			(xy 127.912752 -249.070566) (xy 127.954636 -249.099476) (xy 127.99134 -249.134731) (xy 128.021913 -249.175417)
			(xy 128.045564 -249.22048) (xy 128.06168 -249.268754) (xy 128.069844 -249.318988) (xy 128.070356 -249.344434)
			(xy 128.388884 -249.344434) (xy 128.392844 -249.29538) (xy 128.404621 -249.247596) (xy 128.423912 -249.20232)
			(xy 128.450215 -249.160724) (xy 128.48285 -249.123887) (xy 128.520971 -249.092762) (xy 128.563592 -249.068155)
			(xy 128.609608 -249.050703) (xy 128.657827 -249.040859) (xy 128.707002 -249.038878) (xy 128.755857 -249.04481)
			(xy 128.803128 -249.058502) (xy 128.84759 -249.0796) (xy 128.888093 -249.107556) (xy 128.923586 -249.141648)
			(xy 128.953151 -249.180992) (xy 128.976022 -249.224569) (xy 128.991606 -249.27125) (xy 128.999501 -249.319827)
			(xy 128.999996 -249.344434) (xy 129.328938 -249.344434) (xy 129.332898 -249.29538) (xy 129.344675 -249.247596)
			(xy 129.363966 -249.20232) (xy 129.390269 -249.160724) (xy 129.422904 -249.123887) (xy 129.461025 -249.092762)
			(xy 129.503646 -249.068155) (xy 129.549662 -249.050703) (xy 129.597881 -249.040859) (xy 129.647056 -249.038878)
			(xy 129.695911 -249.04481) (xy 129.743182 -249.058502) (xy 129.787644 -249.0796) (xy 129.828147 -249.107556)
			(xy 129.86364 -249.141648) (xy 129.893205 -249.180992) (xy 129.916076 -249.224569) (xy 129.93166 -249.27125)
			(xy 129.939555 -249.319827) (xy 129.94005 -249.344434) (xy 131.198615 -249.344434) (xy 131.20271 -249.293706)
			(xy 131.214889 -249.244292) (xy 131.234837 -249.197472) (xy 131.262038 -249.154458) (xy 131.295786 -249.116364)
			(xy 131.335208 -249.084177) (xy 131.379282 -249.058731) (xy 131.426868 -249.040684) (xy 131.476732 -249.030504)
			(xy 131.527584 -249.028455) (xy 131.578105 -249.034589) (xy 131.626989 -249.048749) (xy 131.672968 -249.070566)
			(xy 131.714852 -249.099476) (xy 131.751556 -249.134731) (xy 131.782129 -249.175417) (xy 131.80578 -249.22048)
			(xy 131.821896 -249.268754) (xy 131.83006 -249.318988) (xy 131.830572 -249.344434) (xy 132.148846 -249.344434)
			(xy 132.152806 -249.29538) (xy 132.164583 -249.247596) (xy 132.183874 -249.20232) (xy 132.210177 -249.160724)
			(xy 132.242812 -249.123887) (xy 132.280933 -249.092762) (xy 132.323554 -249.068155) (xy 132.36957 -249.050703)
			(xy 132.417789 -249.040859) (xy 132.466964 -249.038878) (xy 132.515819 -249.04481) (xy 132.56309 -249.058502)
			(xy 132.607552 -249.0796) (xy 132.648055 -249.107556) (xy 132.683548 -249.141648) (xy 132.713113 -249.180992)
			(xy 132.735984 -249.224569) (xy 132.751568 -249.27125) (xy 132.759463 -249.319827) (xy 132.759958 -249.344434)
			(xy 133.0889 -249.344434) (xy 133.09286 -249.29538) (xy 133.104637 -249.247596) (xy 133.123928 -249.20232)
			(xy 133.150231 -249.160724) (xy 133.182866 -249.123887) (xy 133.220987 -249.092762) (xy 133.263608 -249.068155)
			(xy 133.309624 -249.050703) (xy 133.357843 -249.040859) (xy 133.407018 -249.038878) (xy 133.455873 -249.04481)
			(xy 133.503144 -249.058502) (xy 133.547606 -249.0796) (xy 133.588109 -249.107556) (xy 133.623602 -249.141648)
			(xy 133.653167 -249.180992) (xy 133.676038 -249.224569) (xy 133.691622 -249.27125) (xy 133.699517 -249.319827)
			(xy 133.700012 -249.344434) (xy 134.028954 -249.344434) (xy 134.032914 -249.29538) (xy 134.044691 -249.247596)
			(xy 134.063982 -249.20232) (xy 134.090285 -249.160724) (xy 134.12292 -249.123887) (xy 134.161041 -249.092762)
			(xy 134.203662 -249.068155) (xy 134.249678 -249.050703) (xy 134.297897 -249.040859) (xy 134.347072 -249.038878)
			(xy 134.395927 -249.04481) (xy 134.443198 -249.058502) (xy 134.48766 -249.0796) (xy 134.528163 -249.107556)
			(xy 134.563656 -249.141648) (xy 134.593221 -249.180992) (xy 134.616092 -249.224569) (xy 134.631676 -249.27125)
			(xy 134.639571 -249.319827) (xy 134.640066 -249.344434) (xy 134.969008 -249.344434) (xy 134.972968 -249.29538)
			(xy 134.984745 -249.247596) (xy 135.004036 -249.20232) (xy 135.030339 -249.160724) (xy 135.062974 -249.123887)
			(xy 135.101095 -249.092762) (xy 135.143716 -249.068155) (xy 135.189732 -249.050703) (xy 135.237951 -249.040859)
			(xy 135.287126 -249.038878) (xy 135.335981 -249.04481) (xy 135.383252 -249.058502) (xy 135.427714 -249.0796)
			(xy 135.468217 -249.107556) (xy 135.50371 -249.141648) (xy 135.533275 -249.180992) (xy 135.556146 -249.224569)
			(xy 135.57173 -249.27125) (xy 135.579625 -249.319827) (xy 135.58012 -249.344434) (xy 135.909062 -249.344434)
			(xy 135.913022 -249.29538) (xy 135.924799 -249.247596) (xy 135.94409 -249.20232) (xy 135.970393 -249.160724)
			(xy 136.003028 -249.123887) (xy 136.041149 -249.092762) (xy 136.08377 -249.068155) (xy 136.129786 -249.050703)
			(xy 136.178005 -249.040859) (xy 136.22718 -249.038878) (xy 136.276035 -249.04481) (xy 136.323306 -249.058502)
			(xy 136.367768 -249.0796) (xy 136.408271 -249.107556) (xy 136.443764 -249.141648) (xy 136.473329 -249.180992)
			(xy 136.4962 -249.224569) (xy 136.511784 -249.27125) (xy 136.519679 -249.319827) (xy 136.520174 -249.344434)
			(xy 136.519679 -249.369041) (xy 136.511784 -249.417618) (xy 136.4962 -249.464299) (xy 136.473329 -249.507876)
			(xy 136.443764 -249.54722) (xy 136.408271 -249.581312) (xy 136.367768 -249.609268) (xy 136.323306 -249.630366)
			(xy 136.276035 -249.644058) (xy 136.22718 -249.64999) (xy 136.178005 -249.648009) (xy 136.129786 -249.638165)
			(xy 136.08377 -249.620713) (xy 136.041149 -249.596106) (xy 136.003028 -249.564981) (xy 135.970393 -249.528144)
			(xy 135.94409 -249.486548) (xy 135.924799 -249.441272) (xy 135.913022 -249.393488) (xy 135.909062 -249.344434)
			(xy 135.58012 -249.344434) (xy 135.579625 -249.369041) (xy 135.57173 -249.417618) (xy 135.556146 -249.464299)
			(xy 135.533275 -249.507876) (xy 135.50371 -249.54722) (xy 135.468217 -249.581312) (xy 135.427714 -249.609268)
			(xy 135.383252 -249.630366) (xy 135.335981 -249.644058) (xy 135.287126 -249.64999) (xy 135.237951 -249.648009)
			(xy 135.189732 -249.638165) (xy 135.143716 -249.620713) (xy 135.101095 -249.596106) (xy 135.062974 -249.564981)
			(xy 135.030339 -249.528144) (xy 135.004036 -249.486548) (xy 134.984745 -249.441272) (xy 134.972968 -249.393488)
			(xy 134.969008 -249.344434) (xy 134.640066 -249.344434) (xy 134.639571 -249.369041) (xy 134.631676 -249.417618)
			(xy 134.616092 -249.464299) (xy 134.593221 -249.507876) (xy 134.563656 -249.54722) (xy 134.528163 -249.581312)
			(xy 134.48766 -249.609268) (xy 134.443198 -249.630366) (xy 134.395927 -249.644058) (xy 134.347072 -249.64999)
			(xy 134.297897 -249.648009) (xy 134.249678 -249.638165) (xy 134.203662 -249.620713) (xy 134.161041 -249.596106)
			(xy 134.12292 -249.564981) (xy 134.090285 -249.528144) (xy 134.063982 -249.486548) (xy 134.044691 -249.441272)
			(xy 134.032914 -249.393488) (xy 134.028954 -249.344434) (xy 133.700012 -249.344434) (xy 133.699517 -249.369041)
			(xy 133.691622 -249.417618) (xy 133.676038 -249.464299) (xy 133.653167 -249.507876) (xy 133.623602 -249.54722)
			(xy 133.588109 -249.581312) (xy 133.547606 -249.609268) (xy 133.503144 -249.630366) (xy 133.455873 -249.644058)
			(xy 133.407018 -249.64999) (xy 133.357843 -249.648009) (xy 133.309624 -249.638165) (xy 133.263608 -249.620713)
			(xy 133.220987 -249.596106) (xy 133.182866 -249.564981) (xy 133.150231 -249.528144) (xy 133.123928 -249.486548)
			(xy 133.104637 -249.441272) (xy 133.09286 -249.393488) (xy 133.0889 -249.344434) (xy 132.759958 -249.344434)
			(xy 132.759463 -249.369041) (xy 132.751568 -249.417618) (xy 132.735984 -249.464299) (xy 132.713113 -249.507876)
			(xy 132.683548 -249.54722) (xy 132.648055 -249.581312) (xy 132.607552 -249.609268) (xy 132.56309 -249.630366)
			(xy 132.515819 -249.644058) (xy 132.466964 -249.64999) (xy 132.417789 -249.648009) (xy 132.36957 -249.638165)
			(xy 132.323554 -249.620713) (xy 132.280933 -249.596106) (xy 132.242812 -249.564981) (xy 132.210177 -249.528144)
			(xy 132.183874 -249.486548) (xy 132.164583 -249.441272) (xy 132.152806 -249.393488) (xy 132.148846 -249.344434)
			(xy 131.830572 -249.344434) (xy 131.83006 -249.36988) (xy 131.821896 -249.420114) (xy 131.80578 -249.468388)
			(xy 131.782129 -249.513451) (xy 131.751556 -249.554137) (xy 131.714852 -249.589392) (xy 131.672968 -249.618302)
			(xy 131.626989 -249.640119) (xy 131.578105 -249.654279) (xy 131.527584 -249.660413) (xy 131.476732 -249.658364)
			(xy 131.426868 -249.648184) (xy 131.379282 -249.630137) (xy 131.335208 -249.604691) (xy 131.295786 -249.572504)
			(xy 131.262038 -249.53441) (xy 131.234837 -249.491396) (xy 131.214889 -249.444576) (xy 131.20271 -249.395162)
			(xy 131.198615 -249.344434) (xy 129.94005 -249.344434) (xy 129.939555 -249.369041) (xy 129.93166 -249.417618)
			(xy 129.916076 -249.464299) (xy 129.893205 -249.507876) (xy 129.86364 -249.54722) (xy 129.828147 -249.581312)
			(xy 129.787644 -249.609268) (xy 129.743182 -249.630366) (xy 129.695911 -249.644058) (xy 129.647056 -249.64999)
			(xy 129.597881 -249.648009) (xy 129.549662 -249.638165) (xy 129.503646 -249.620713) (xy 129.461025 -249.596106)
			(xy 129.422904 -249.564981) (xy 129.390269 -249.528144) (xy 129.363966 -249.486548) (xy 129.344675 -249.441272)
			(xy 129.332898 -249.393488) (xy 129.328938 -249.344434) (xy 128.999996 -249.344434) (xy 128.999501 -249.369041)
			(xy 128.991606 -249.417618) (xy 128.976022 -249.464299) (xy 128.953151 -249.507876) (xy 128.923586 -249.54722)
			(xy 128.888093 -249.581312) (xy 128.84759 -249.609268) (xy 128.803128 -249.630366) (xy 128.755857 -249.644058)
			(xy 128.707002 -249.64999) (xy 128.657827 -249.648009) (xy 128.609608 -249.638165) (xy 128.563592 -249.620713)
			(xy 128.520971 -249.596106) (xy 128.48285 -249.564981) (xy 128.450215 -249.528144) (xy 128.423912 -249.486548)
			(xy 128.404621 -249.441272) (xy 128.392844 -249.393488) (xy 128.388884 -249.344434) (xy 128.070356 -249.344434)
			(xy 128.069844 -249.36988) (xy 128.06168 -249.420114) (xy 128.045564 -249.468388) (xy 128.021913 -249.513451)
			(xy 127.99134 -249.554137) (xy 127.954636 -249.589392) (xy 127.912752 -249.618302) (xy 127.866773 -249.640119)
			(xy 127.817889 -249.654279) (xy 127.767368 -249.660413) (xy 127.716516 -249.658364) (xy 127.666652 -249.648184)
			(xy 127.619066 -249.630137) (xy 127.574992 -249.604691) (xy 127.53557 -249.572504) (xy 127.501822 -249.53441)
			(xy 127.474621 -249.491396) (xy 127.454673 -249.444576) (xy 127.442494 -249.395162) (xy 127.438399 -249.344434)
			(xy 127.120142 -249.344434) (xy 127.119645 -249.369451) (xy 127.111493 -249.418816) (xy 127.095397 -249.46619)
			(xy 127.071788 -249.510304) (xy 127.041299 -249.549975) (xy 127.004746 -249.58414) (xy 126.963109 -249.611885)
			(xy 126.917504 -249.632465) (xy 126.869152 -249.64533) (xy 126.844298 -249.648218) (xy 126.835408 -249.649234)
			(xy 126.81966 -249.6566) (xy 126.569978 -249.906282) (xy 126.5682 -249.945398) (xy 126.580646 -249.960638)
			(xy 126.596879 -249.981286) (xy 126.622759 -250.026986) (xy 126.640451 -250.076435) (xy 126.649434 -250.128181)
			(xy 126.649988 -250.15444) (xy 127.908553 -250.15444) (xy 127.912648 -250.103712) (xy 127.924827 -250.054298)
			(xy 127.944775 -250.007478) (xy 127.971976 -249.964464) (xy 128.005724 -249.92637) (xy 128.045146 -249.894183)
			(xy 128.08922 -249.868737) (xy 128.136806 -249.85069) (xy 128.18667 -249.84051) (xy 128.237522 -249.838461)
			(xy 128.288043 -249.844595) (xy 128.336927 -249.858755) (xy 128.382906 -249.880572) (xy 128.42479 -249.909482)
			(xy 128.461494 -249.944737) (xy 128.492067 -249.985423) (xy 128.515718 -250.030486) (xy 128.531834 -250.07876)
			(xy 128.539998 -250.128994) (xy 128.54051 -250.15444) (xy 128.859038 -250.15444) (xy 128.862998 -250.105386)
			(xy 128.874775 -250.057602) (xy 128.894066 -250.012326) (xy 128.920369 -249.97073) (xy 128.953004 -249.933893)
			(xy 128.991125 -249.902768) (xy 129.033746 -249.878161) (xy 129.079762 -249.860709) (xy 129.127981 -249.850865)
			(xy 129.177156 -249.848884) (xy 129.226011 -249.854816) (xy 129.273282 -249.868508) (xy 129.317744 -249.889606)
			(xy 129.358247 -249.917562) (xy 129.39374 -249.951654) (xy 129.423305 -249.990998) (xy 129.446176 -250.034575)
			(xy 129.46176 -250.081256) (xy 129.469655 -250.129833) (xy 129.47015 -250.15444) (xy 129.798838 -250.15444)
			(xy 129.802798 -250.105386) (xy 129.814575 -250.057602) (xy 129.833866 -250.012326) (xy 129.860169 -249.97073)
			(xy 129.892804 -249.933893) (xy 129.930925 -249.902768) (xy 129.973546 -249.878161) (xy 130.019562 -249.860709)
			(xy 130.067781 -249.850865) (xy 130.116956 -249.848884) (xy 130.165811 -249.854816) (xy 130.213082 -249.868508)
			(xy 130.257544 -249.889606) (xy 130.298047 -249.917562) (xy 130.33354 -249.951654) (xy 130.363105 -249.990998)
			(xy 130.385976 -250.034575) (xy 130.40156 -250.081256) (xy 130.409455 -250.129833) (xy 130.40995 -250.15444)
			(xy 130.728461 -250.15444) (xy 130.732556 -250.103712) (xy 130.744735 -250.054298) (xy 130.764683 -250.007478)
			(xy 130.791884 -249.964464) (xy 130.825632 -249.92637) (xy 130.865054 -249.894183) (xy 130.909128 -249.868737)
			(xy 130.956714 -249.85069) (xy 131.006578 -249.84051) (xy 131.05743 -249.838461) (xy 131.107951 -249.844595)
			(xy 131.156835 -249.858755) (xy 131.202814 -249.880572) (xy 131.244698 -249.909482) (xy 131.281402 -249.944737)
			(xy 131.311975 -249.985423) (xy 131.335626 -250.030486) (xy 131.351742 -250.07876) (xy 131.359906 -250.128994)
			(xy 131.360418 -250.15444) (xy 131.678946 -250.15444) (xy 131.682906 -250.105386) (xy 131.694683 -250.057602)
			(xy 131.713974 -250.012326) (xy 131.740277 -249.97073) (xy 131.772912 -249.933893) (xy 131.811033 -249.902768)
			(xy 131.853654 -249.878161) (xy 131.89967 -249.860709) (xy 131.947889 -249.850865) (xy 131.997064 -249.848884)
			(xy 132.045919 -249.854816) (xy 132.09319 -249.868508) (xy 132.137652 -249.889606) (xy 132.178155 -249.917562)
			(xy 132.213648 -249.951654) (xy 132.243213 -249.990998) (xy 132.266084 -250.034575) (xy 132.281668 -250.081256)
			(xy 132.289563 -250.129833) (xy 132.290058 -250.15444) (xy 132.619 -250.15444) (xy 132.62296 -250.105386)
			(xy 132.634737 -250.057602) (xy 132.654028 -250.012326) (xy 132.680331 -249.97073) (xy 132.712966 -249.933893)
			(xy 132.751087 -249.902768) (xy 132.793708 -249.878161) (xy 132.839724 -249.860709) (xy 132.887943 -249.850865)
			(xy 132.937118 -249.848884) (xy 132.985973 -249.854816) (xy 133.033244 -249.868508) (xy 133.077706 -249.889606)
			(xy 133.118209 -249.917562) (xy 133.153702 -249.951654) (xy 133.183267 -249.990998) (xy 133.206138 -250.034575)
			(xy 133.221722 -250.081256) (xy 133.229617 -250.129833) (xy 133.230112 -250.15444) (xy 133.559054 -250.15444)
			(xy 133.563014 -250.105386) (xy 133.574791 -250.057602) (xy 133.594082 -250.012326) (xy 133.620385 -249.97073)
			(xy 133.65302 -249.933893) (xy 133.691141 -249.902768) (xy 133.733762 -249.878161) (xy 133.779778 -249.860709)
			(xy 133.827997 -249.850865) (xy 133.877172 -249.848884) (xy 133.926027 -249.854816) (xy 133.973298 -249.868508)
			(xy 134.01776 -249.889606) (xy 134.058263 -249.917562) (xy 134.093756 -249.951654) (xy 134.123321 -249.990998)
			(xy 134.146192 -250.034575) (xy 134.161776 -250.081256) (xy 134.169671 -250.129833) (xy 134.170166 -250.15444)
			(xy 134.498854 -250.15444) (xy 134.502814 -250.105386) (xy 134.514591 -250.057602) (xy 134.533882 -250.012326)
			(xy 134.560185 -249.97073) (xy 134.59282 -249.933893) (xy 134.630941 -249.902768) (xy 134.673562 -249.878161)
			(xy 134.719578 -249.860709) (xy 134.767797 -249.850865) (xy 134.816972 -249.848884) (xy 134.865827 -249.854816)
			(xy 134.913098 -249.868508) (xy 134.95756 -249.889606) (xy 134.998063 -249.917562) (xy 135.033556 -249.951654)
			(xy 135.063121 -249.990998) (xy 135.085992 -250.034575) (xy 135.101576 -250.081256) (xy 135.109471 -250.129833)
			(xy 135.109966 -250.15444) (xy 135.438908 -250.15444) (xy 135.442868 -250.105386) (xy 135.454645 -250.057602)
			(xy 135.473936 -250.012326) (xy 135.500239 -249.97073) (xy 135.532874 -249.933893) (xy 135.570995 -249.902768)
			(xy 135.613616 -249.878161) (xy 135.659632 -249.860709) (xy 135.707851 -249.850865) (xy 135.757026 -249.848884)
			(xy 135.805881 -249.854816) (xy 135.853152 -249.868508) (xy 135.897614 -249.889606) (xy 135.938117 -249.917562)
			(xy 135.97361 -249.951654) (xy 136.003175 -249.990998) (xy 136.026046 -250.034575) (xy 136.04163 -250.081256)
			(xy 136.049525 -250.129833) (xy 136.05002 -250.15444) (xy 136.049525 -250.179047) (xy 136.04163 -250.227624)
			(xy 136.026046 -250.274305) (xy 136.003175 -250.317882) (xy 135.97361 -250.357226) (xy 135.938117 -250.391318)
			(xy 135.897614 -250.419274) (xy 135.853152 -250.440372) (xy 135.805881 -250.454064) (xy 135.757026 -250.459996)
			(xy 135.707851 -250.458015) (xy 135.659632 -250.448171) (xy 135.613616 -250.430719) (xy 135.570995 -250.406112)
			(xy 135.532874 -250.374987) (xy 135.500239 -250.33815) (xy 135.473936 -250.296554) (xy 135.454645 -250.251278)
			(xy 135.442868 -250.203494) (xy 135.438908 -250.15444) (xy 135.109966 -250.15444) (xy 135.109471 -250.179047)
			(xy 135.101576 -250.227624) (xy 135.085992 -250.274305) (xy 135.063121 -250.317882) (xy 135.033556 -250.357226)
			(xy 134.998063 -250.391318) (xy 134.95756 -250.419274) (xy 134.913098 -250.440372) (xy 134.865827 -250.454064)
			(xy 134.816972 -250.459996) (xy 134.767797 -250.458015) (xy 134.719578 -250.448171) (xy 134.673562 -250.430719)
			(xy 134.630941 -250.406112) (xy 134.59282 -250.374987) (xy 134.560185 -250.33815) (xy 134.533882 -250.296554)
			(xy 134.514591 -250.251278) (xy 134.502814 -250.203494) (xy 134.498854 -250.15444) (xy 134.170166 -250.15444)
			(xy 134.169671 -250.179047) (xy 134.161776 -250.227624) (xy 134.146192 -250.274305) (xy 134.123321 -250.317882)
			(xy 134.093756 -250.357226) (xy 134.058263 -250.391318) (xy 134.01776 -250.419274) (xy 133.973298 -250.440372)
			(xy 133.926027 -250.454064) (xy 133.877172 -250.459996) (xy 133.827997 -250.458015) (xy 133.779778 -250.448171)
			(xy 133.733762 -250.430719) (xy 133.691141 -250.406112) (xy 133.65302 -250.374987) (xy 133.620385 -250.33815)
			(xy 133.594082 -250.296554) (xy 133.574791 -250.251278) (xy 133.563014 -250.203494) (xy 133.559054 -250.15444)
			(xy 133.230112 -250.15444) (xy 133.229617 -250.179047) (xy 133.221722 -250.227624) (xy 133.206138 -250.274305)
			(xy 133.183267 -250.317882) (xy 133.153702 -250.357226) (xy 133.118209 -250.391318) (xy 133.077706 -250.419274)
			(xy 133.033244 -250.440372) (xy 132.985973 -250.454064) (xy 132.937118 -250.459996) (xy 132.887943 -250.458015)
			(xy 132.839724 -250.448171) (xy 132.793708 -250.430719) (xy 132.751087 -250.406112) (xy 132.712966 -250.374987)
			(xy 132.680331 -250.33815) (xy 132.654028 -250.296554) (xy 132.634737 -250.251278) (xy 132.62296 -250.203494)
			(xy 132.619 -250.15444) (xy 132.290058 -250.15444) (xy 132.289563 -250.179047) (xy 132.281668 -250.227624)
			(xy 132.266084 -250.274305) (xy 132.243213 -250.317882) (xy 132.213648 -250.357226) (xy 132.178155 -250.391318)
			(xy 132.137652 -250.419274) (xy 132.09319 -250.440372) (xy 132.045919 -250.454064) (xy 131.997064 -250.459996)
			(xy 131.947889 -250.458015) (xy 131.89967 -250.448171) (xy 131.853654 -250.430719) (xy 131.811033 -250.406112)
			(xy 131.772912 -250.374987) (xy 131.740277 -250.33815) (xy 131.713974 -250.296554) (xy 131.694683 -250.251278)
			(xy 131.682906 -250.203494) (xy 131.678946 -250.15444) (xy 131.360418 -250.15444) (xy 131.359906 -250.179886)
			(xy 131.351742 -250.23012) (xy 131.335626 -250.278394) (xy 131.311975 -250.323457) (xy 131.281402 -250.364143)
			(xy 131.244698 -250.399398) (xy 131.202814 -250.428308) (xy 131.156835 -250.450125) (xy 131.107951 -250.464285)
			(xy 131.05743 -250.470419) (xy 131.006578 -250.46837) (xy 130.956714 -250.45819) (xy 130.909128 -250.440143)
			(xy 130.865054 -250.414697) (xy 130.825632 -250.38251) (xy 130.791884 -250.344416) (xy 130.764683 -250.301402)
			(xy 130.744735 -250.254582) (xy 130.732556 -250.205168) (xy 130.728461 -250.15444) (xy 130.40995 -250.15444)
			(xy 130.409455 -250.179047) (xy 130.40156 -250.227624) (xy 130.385976 -250.274305) (xy 130.363105 -250.317882)
			(xy 130.33354 -250.357226) (xy 130.298047 -250.391318) (xy 130.257544 -250.419274) (xy 130.213082 -250.440372)
			(xy 130.165811 -250.454064) (xy 130.116956 -250.459996) (xy 130.067781 -250.458015) (xy 130.019562 -250.448171)
			(xy 129.973546 -250.430719) (xy 129.930925 -250.406112) (xy 129.892804 -250.374987) (xy 129.860169 -250.33815)
			(xy 129.833866 -250.296554) (xy 129.814575 -250.251278) (xy 129.802798 -250.203494) (xy 129.798838 -250.15444)
			(xy 129.47015 -250.15444) (xy 129.469655 -250.179047) (xy 129.46176 -250.227624) (xy 129.446176 -250.274305)
			(xy 129.423305 -250.317882) (xy 129.39374 -250.357226) (xy 129.358247 -250.391318) (xy 129.317744 -250.419274)
			(xy 129.273282 -250.440372) (xy 129.226011 -250.454064) (xy 129.177156 -250.459996) (xy 129.127981 -250.458015)
			(xy 129.079762 -250.448171) (xy 129.033746 -250.430719) (xy 128.991125 -250.406112) (xy 128.953004 -250.374987)
			(xy 128.920369 -250.33815) (xy 128.894066 -250.296554) (xy 128.874775 -250.251278) (xy 128.862998 -250.203494)
			(xy 128.859038 -250.15444) (xy 128.54051 -250.15444) (xy 128.539998 -250.179886) (xy 128.531834 -250.23012)
			(xy 128.515718 -250.278394) (xy 128.492067 -250.323457) (xy 128.461494 -250.364143) (xy 128.42479 -250.399398)
			(xy 128.382906 -250.428308) (xy 128.336927 -250.450125) (xy 128.288043 -250.464285) (xy 128.237522 -250.470419)
			(xy 128.18667 -250.46837) (xy 128.136806 -250.45819) (xy 128.08922 -250.440143) (xy 128.045146 -250.414697)
			(xy 128.005724 -250.38251) (xy 127.971976 -250.344416) (xy 127.944775 -250.301402) (xy 127.924827 -250.254582)
			(xy 127.912648 -250.205168) (xy 127.908553 -250.15444) (xy 126.649988 -250.15444) (xy 126.649514 -250.178429)
			(xy 126.642003 -250.225814) (xy 126.627172 -250.271442) (xy 126.605386 -250.314187) (xy 126.577182 -250.352999)
			(xy 126.543253 -250.386921) (xy 126.504436 -250.415117) (xy 126.461686 -250.436895) (xy 126.416056 -250.451717)
			(xy 126.368669 -250.459219) (xy 126.34468 -250.459748) (xy 126.320585 -250.45927) (xy 126.272998 -250.451655)
			(xy 126.227197 -250.436664) (xy 126.184317 -250.41467) (xy 126.164594 -250.40082) (xy 126.157228 -250.39574)
			(xy 126.140718 -250.39066) (xy 126.10211 -250.392692) (xy 126.09281 -250.393574) (xy 126.075747 -250.401138)
			(xy 126.068836 -250.407424) (xy 125.511814 -250.964446) (xy 126.50903 -250.964446) (xy 126.51299 -250.915392)
			(xy 126.524767 -250.867608) (xy 126.544058 -250.822332) (xy 126.570361 -250.780736) (xy 126.602996 -250.743899)
			(xy 126.641117 -250.712774) (xy 126.683738 -250.688167) (xy 126.729754 -250.670715) (xy 126.777973 -250.660871)
			(xy 126.827148 -250.65889) (xy 126.876003 -250.664822) (xy 126.923274 -250.678514) (xy 126.967736 -250.699612)
			(xy 127.008239 -250.727568) (xy 127.043732 -250.76166) (xy 127.073297 -250.801004) (xy 127.096168 -250.844581)
			(xy 127.111752 -250.891262) (xy 127.119647 -250.939839) (xy 127.120142 -250.964446) (xy 127.438399 -250.964446)
			(xy 127.442494 -250.913718) (xy 127.454673 -250.864304) (xy 127.474621 -250.817484) (xy 127.501822 -250.77447)
			(xy 127.53557 -250.736376) (xy 127.574992 -250.704189) (xy 127.619066 -250.678743) (xy 127.666652 -250.660696)
			(xy 127.716516 -250.650516) (xy 127.767368 -250.648467) (xy 127.817889 -250.654601) (xy 127.866773 -250.668761)
			(xy 127.912752 -250.690578) (xy 127.954636 -250.719488) (xy 127.99134 -250.754743) (xy 128.021913 -250.795429)
			(xy 128.045564 -250.840492) (xy 128.06168 -250.888766) (xy 128.069844 -250.939) (xy 128.070356 -250.964446)
			(xy 128.388884 -250.964446) (xy 128.392844 -250.915392) (xy 128.404621 -250.867608) (xy 128.423912 -250.822332)
			(xy 128.450215 -250.780736) (xy 128.48285 -250.743899) (xy 128.520971 -250.712774) (xy 128.563592 -250.688167)
			(xy 128.609608 -250.670715) (xy 128.657827 -250.660871) (xy 128.707002 -250.65889) (xy 128.755857 -250.664822)
			(xy 128.803128 -250.678514) (xy 128.84759 -250.699612) (xy 128.888093 -250.727568) (xy 128.923586 -250.76166)
			(xy 128.953151 -250.801004) (xy 128.976022 -250.844581) (xy 128.991606 -250.891262) (xy 128.999501 -250.939839)
			(xy 128.999996 -250.964446) (xy 129.318507 -250.964446) (xy 129.322602 -250.913718) (xy 129.334781 -250.864304)
			(xy 129.354729 -250.817484) (xy 129.38193 -250.77447) (xy 129.415678 -250.736376) (xy 129.4551 -250.704189)
			(xy 129.499174 -250.678743) (xy 129.54676 -250.660696) (xy 129.596624 -250.650516) (xy 129.647476 -250.648467)
			(xy 129.697997 -250.654601) (xy 129.746881 -250.668761) (xy 129.79286 -250.690578) (xy 129.834744 -250.719488)
			(xy 129.871448 -250.754743) (xy 129.902021 -250.795429) (xy 129.925672 -250.840492) (xy 129.941788 -250.888766)
			(xy 129.949952 -250.939) (xy 129.950464 -250.964446) (xy 130.268992 -250.964446) (xy 130.272952 -250.915392)
			(xy 130.284729 -250.867608) (xy 130.30402 -250.822332) (xy 130.330323 -250.780736) (xy 130.362958 -250.743899)
			(xy 130.401079 -250.712774) (xy 130.4437 -250.688167) (xy 130.489716 -250.670715) (xy 130.537935 -250.660871)
			(xy 130.58711 -250.65889) (xy 130.635965 -250.664822) (xy 130.683236 -250.678514) (xy 130.727698 -250.699612)
			(xy 130.768201 -250.727568) (xy 130.803694 -250.76166) (xy 130.833259 -250.801004) (xy 130.85613 -250.844581)
			(xy 130.871714 -250.891262) (xy 130.879609 -250.939839) (xy 130.880104 -250.964446) (xy 131.198615 -250.964446)
			(xy 131.20271 -250.913718) (xy 131.214889 -250.864304) (xy 131.234837 -250.817484) (xy 131.262038 -250.77447)
			(xy 131.295786 -250.736376) (xy 131.335208 -250.704189) (xy 131.379282 -250.678743) (xy 131.426868 -250.660696)
			(xy 131.476732 -250.650516) (xy 131.527584 -250.648467) (xy 131.578105 -250.654601) (xy 131.626989 -250.668761)
			(xy 131.672968 -250.690578) (xy 131.714852 -250.719488) (xy 131.751556 -250.754743) (xy 131.782129 -250.795429)
			(xy 131.80578 -250.840492) (xy 131.821896 -250.888766) (xy 131.83006 -250.939) (xy 131.830572 -250.964446)
			(xy 132.138415 -250.964446) (xy 132.14251 -250.913718) (xy 132.154689 -250.864304) (xy 132.174637 -250.817484)
			(xy 132.201838 -250.77447) (xy 132.235586 -250.736376) (xy 132.275008 -250.704189) (xy 132.319082 -250.678743)
			(xy 132.366668 -250.660696) (xy 132.416532 -250.650516) (xy 132.467384 -250.648467) (xy 132.517905 -250.654601)
			(xy 132.566789 -250.668761) (xy 132.612768 -250.690578) (xy 132.654652 -250.719488) (xy 132.691356 -250.754743)
			(xy 132.721929 -250.795429) (xy 132.74558 -250.840492) (xy 132.761696 -250.888766) (xy 132.76986 -250.939)
			(xy 132.770372 -250.964446) (xy 133.0889 -250.964446) (xy 133.09286 -250.915392) (xy 133.104637 -250.867608)
			(xy 133.123928 -250.822332) (xy 133.150231 -250.780736) (xy 133.182866 -250.743899) (xy 133.220987 -250.712774)
			(xy 133.263608 -250.688167) (xy 133.309624 -250.670715) (xy 133.357843 -250.660871) (xy 133.407018 -250.65889)
			(xy 133.455873 -250.664822) (xy 133.503144 -250.678514) (xy 133.547606 -250.699612) (xy 133.588109 -250.727568)
			(xy 133.623602 -250.76166) (xy 133.653167 -250.801004) (xy 133.676038 -250.844581) (xy 133.691622 -250.891262)
			(xy 133.699517 -250.939839) (xy 133.700012 -250.964446) (xy 134.028954 -250.964446) (xy 134.032914 -250.915392)
			(xy 134.044691 -250.867608) (xy 134.063982 -250.822332) (xy 134.090285 -250.780736) (xy 134.12292 -250.743899)
			(xy 134.161041 -250.712774) (xy 134.203662 -250.688167) (xy 134.249678 -250.670715) (xy 134.297897 -250.660871)
			(xy 134.347072 -250.65889) (xy 134.395927 -250.664822) (xy 134.443198 -250.678514) (xy 134.48766 -250.699612)
			(xy 134.528163 -250.727568) (xy 134.563656 -250.76166) (xy 134.593221 -250.801004) (xy 134.616092 -250.844581)
			(xy 134.631676 -250.891262) (xy 134.639571 -250.939839) (xy 134.640066 -250.964446) (xy 134.969008 -250.964446)
			(xy 134.972968 -250.915392) (xy 134.984745 -250.867608) (xy 135.004036 -250.822332) (xy 135.030339 -250.780736)
			(xy 135.062974 -250.743899) (xy 135.101095 -250.712774) (xy 135.143716 -250.688167) (xy 135.189732 -250.670715)
			(xy 135.237951 -250.660871) (xy 135.287126 -250.65889) (xy 135.335981 -250.664822) (xy 135.383252 -250.678514)
			(xy 135.427714 -250.699612) (xy 135.468217 -250.727568) (xy 135.50371 -250.76166) (xy 135.533275 -250.801004)
			(xy 135.556146 -250.844581) (xy 135.57173 -250.891262) (xy 135.579625 -250.939839) (xy 135.58012 -250.964446)
			(xy 135.909062 -250.964446) (xy 135.913022 -250.915392) (xy 135.924799 -250.867608) (xy 135.94409 -250.822332)
			(xy 135.970393 -250.780736) (xy 136.003028 -250.743899) (xy 136.041149 -250.712774) (xy 136.08377 -250.688167)
			(xy 136.129786 -250.670715) (xy 136.178005 -250.660871) (xy 136.22718 -250.65889) (xy 136.276035 -250.664822)
			(xy 136.323306 -250.678514) (xy 136.367768 -250.699612) (xy 136.408271 -250.727568) (xy 136.443764 -250.76166)
			(xy 136.473329 -250.801004) (xy 136.4962 -250.844581) (xy 136.511784 -250.891262) (xy 136.519679 -250.939839)
			(xy 136.520174 -250.964446) (xy 136.519679 -250.989053) (xy 136.511784 -251.03763) (xy 136.4962 -251.084311)
			(xy 136.473329 -251.127888) (xy 136.443764 -251.167232) (xy 136.408271 -251.201324) (xy 136.367768 -251.22928)
			(xy 136.323306 -251.250378) (xy 136.276035 -251.26407) (xy 136.22718 -251.270002) (xy 136.178005 -251.268021)
			(xy 136.129786 -251.258177) (xy 136.08377 -251.240725) (xy 136.041149 -251.216118) (xy 136.003028 -251.184993)
			(xy 135.970393 -251.148156) (xy 135.94409 -251.10656) (xy 135.924799 -251.061284) (xy 135.913022 -251.0135)
			(xy 135.909062 -250.964446) (xy 135.58012 -250.964446) (xy 135.579625 -250.989053) (xy 135.57173 -251.03763)
			(xy 135.556146 -251.084311) (xy 135.533275 -251.127888) (xy 135.50371 -251.167232) (xy 135.468217 -251.201324)
			(xy 135.427714 -251.22928) (xy 135.383252 -251.250378) (xy 135.335981 -251.26407) (xy 135.287126 -251.270002)
			(xy 135.237951 -251.268021) (xy 135.189732 -251.258177) (xy 135.143716 -251.240725) (xy 135.101095 -251.216118)
			(xy 135.062974 -251.184993) (xy 135.030339 -251.148156) (xy 135.004036 -251.10656) (xy 134.984745 -251.061284)
			(xy 134.972968 -251.0135) (xy 134.969008 -250.964446) (xy 134.640066 -250.964446) (xy 134.639571 -250.989053)
			(xy 134.631676 -251.03763) (xy 134.616092 -251.084311) (xy 134.593221 -251.127888) (xy 134.563656 -251.167232)
			(xy 134.528163 -251.201324) (xy 134.48766 -251.22928) (xy 134.443198 -251.250378) (xy 134.395927 -251.26407)
			(xy 134.347072 -251.270002) (xy 134.297897 -251.268021) (xy 134.249678 -251.258177) (xy 134.203662 -251.240725)
			(xy 134.161041 -251.216118) (xy 134.12292 -251.184993) (xy 134.090285 -251.148156) (xy 134.063982 -251.10656)
			(xy 134.044691 -251.061284) (xy 134.032914 -251.0135) (xy 134.028954 -250.964446) (xy 133.700012 -250.964446)
			(xy 133.699517 -250.989053) (xy 133.691622 -251.03763) (xy 133.676038 -251.084311) (xy 133.653167 -251.127888)
			(xy 133.623602 -251.167232) (xy 133.588109 -251.201324) (xy 133.547606 -251.22928) (xy 133.503144 -251.250378)
			(xy 133.455873 -251.26407) (xy 133.407018 -251.270002) (xy 133.357843 -251.268021) (xy 133.309624 -251.258177)
			(xy 133.263608 -251.240725) (xy 133.220987 -251.216118) (xy 133.182866 -251.184993) (xy 133.150231 -251.148156)
			(xy 133.123928 -251.10656) (xy 133.104637 -251.061284) (xy 133.09286 -251.0135) (xy 133.0889 -250.964446)
			(xy 132.770372 -250.964446) (xy 132.76986 -250.989892) (xy 132.761696 -251.040126) (xy 132.74558 -251.0884)
			(xy 132.721929 -251.133463) (xy 132.691356 -251.174149) (xy 132.654652 -251.209404) (xy 132.612768 -251.238314)
			(xy 132.566789 -251.260131) (xy 132.517905 -251.274291) (xy 132.467384 -251.280425) (xy 132.416532 -251.278376)
			(xy 132.366668 -251.268196) (xy 132.319082 -251.250149) (xy 132.275008 -251.224703) (xy 132.235586 -251.192516)
			(xy 132.201838 -251.154422) (xy 132.174637 -251.111408) (xy 132.154689 -251.064588) (xy 132.14251 -251.015174)
			(xy 132.138415 -250.964446) (xy 131.830572 -250.964446) (xy 131.83006 -250.989892) (xy 131.821896 -251.040126)
			(xy 131.80578 -251.0884) (xy 131.782129 -251.133463) (xy 131.751556 -251.174149) (xy 131.714852 -251.209404)
			(xy 131.672968 -251.238314) (xy 131.626989 -251.260131) (xy 131.578105 -251.274291) (xy 131.527584 -251.280425)
			(xy 131.476732 -251.278376) (xy 131.426868 -251.268196) (xy 131.379282 -251.250149) (xy 131.335208 -251.224703)
			(xy 131.295786 -251.192516) (xy 131.262038 -251.154422) (xy 131.234837 -251.111408) (xy 131.214889 -251.064588)
			(xy 131.20271 -251.015174) (xy 131.198615 -250.964446) (xy 130.880104 -250.964446) (xy 130.879609 -250.989053)
			(xy 130.871714 -251.03763) (xy 130.85613 -251.084311) (xy 130.833259 -251.127888) (xy 130.803694 -251.167232)
			(xy 130.768201 -251.201324) (xy 130.727698 -251.22928) (xy 130.683236 -251.250378) (xy 130.635965 -251.26407)
			(xy 130.58711 -251.270002) (xy 130.537935 -251.268021) (xy 130.489716 -251.258177) (xy 130.4437 -251.240725)
			(xy 130.401079 -251.216118) (xy 130.362958 -251.184993) (xy 130.330323 -251.148156) (xy 130.30402 -251.10656)
			(xy 130.284729 -251.061284) (xy 130.272952 -251.0135) (xy 130.268992 -250.964446) (xy 129.950464 -250.964446)
			(xy 129.949952 -250.989892) (xy 129.941788 -251.040126) (xy 129.925672 -251.0884) (xy 129.902021 -251.133463)
			(xy 129.871448 -251.174149) (xy 129.834744 -251.209404) (xy 129.79286 -251.238314) (xy 129.746881 -251.260131)
			(xy 129.697997 -251.274291) (xy 129.647476 -251.280425) (xy 129.596624 -251.278376) (xy 129.54676 -251.268196)
			(xy 129.499174 -251.250149) (xy 129.4551 -251.224703) (xy 129.415678 -251.192516) (xy 129.38193 -251.154422)
			(xy 129.354729 -251.111408) (xy 129.334781 -251.064588) (xy 129.322602 -251.015174) (xy 129.318507 -250.964446)
			(xy 128.999996 -250.964446) (xy 128.999501 -250.989053) (xy 128.991606 -251.03763) (xy 128.976022 -251.084311)
			(xy 128.953151 -251.127888) (xy 128.923586 -251.167232) (xy 128.888093 -251.201324) (xy 128.84759 -251.22928)
			(xy 128.803128 -251.250378) (xy 128.755857 -251.26407) (xy 128.707002 -251.270002) (xy 128.657827 -251.268021)
			(xy 128.609608 -251.258177) (xy 128.563592 -251.240725) (xy 128.520971 -251.216118) (xy 128.48285 -251.184993)
			(xy 128.450215 -251.148156) (xy 128.423912 -251.10656) (xy 128.404621 -251.061284) (xy 128.392844 -251.0135)
			(xy 128.388884 -250.964446) (xy 128.070356 -250.964446) (xy 128.069844 -250.989892) (xy 128.06168 -251.040126)
			(xy 128.045564 -251.0884) (xy 128.021913 -251.133463) (xy 127.99134 -251.174149) (xy 127.954636 -251.209404)
			(xy 127.912752 -251.238314) (xy 127.866773 -251.260131) (xy 127.817889 -251.274291) (xy 127.767368 -251.280425)
			(xy 127.716516 -251.278376) (xy 127.666652 -251.268196) (xy 127.619066 -251.250149) (xy 127.574992 -251.224703)
			(xy 127.53557 -251.192516) (xy 127.501822 -251.154422) (xy 127.474621 -251.111408) (xy 127.454673 -251.064588)
			(xy 127.442494 -251.015174) (xy 127.438399 -250.964446) (xy 127.120142 -250.964446) (xy 127.119647 -250.989053)
			(xy 127.111752 -251.03763) (xy 127.096168 -251.084311) (xy 127.073297 -251.127888) (xy 127.043732 -251.167232)
			(xy 127.008239 -251.201324) (xy 126.967736 -251.22928) (xy 126.923274 -251.250378) (xy 126.876003 -251.26407)
			(xy 126.827148 -251.270002) (xy 126.777973 -251.268021) (xy 126.729754 -251.258177) (xy 126.683738 -251.240725)
			(xy 126.641117 -251.216118) (xy 126.602996 -251.184993) (xy 126.570361 -251.148156) (xy 126.544058 -251.10656)
			(xy 126.524767 -251.061284) (xy 126.51299 -251.0135) (xy 126.50903 -250.964446) (xy 125.511814 -250.964446)
			(xy 125.0061 -251.47016) (xy 124.998703 -251.477011) (xy 124.980105 -251.484752) (xy 124.970032 -251.485146)
			(xy 124.82576 -251.485146) (xy 124.824998 -251.485146) (xy 124.813439 -251.485871) (xy 124.792797 -251.496322)
			(xy 124.785374 -251.505212) (xy 124.782326 -251.50953) (xy 124.73051 -251.595128) (xy 124.729494 -251.621798)
			(xy 124.73559 -251.633736) (xy 124.746429 -251.655595) (xy 124.761798 -251.701901) (xy 124.769625 -251.750058)
			(xy 124.770134 -251.774452) (xy 126.038876 -251.774452) (xy 126.042836 -251.725398) (xy 126.054613 -251.677614)
			(xy 126.073904 -251.632338) (xy 126.100207 -251.590742) (xy 126.132842 -251.553905) (xy 126.170963 -251.52278)
			(xy 126.213584 -251.498173) (xy 126.2596 -251.480721) (xy 126.307819 -251.470877) (xy 126.356994 -251.468896)
			(xy 126.405849 -251.474828) (xy 126.45312 -251.48852) (xy 126.497582 -251.509618) (xy 126.538085 -251.537574)
			(xy 126.573578 -251.571666) (xy 126.603143 -251.61101) (xy 126.626014 -251.654587) (xy 126.641598 -251.701268)
			(xy 126.649493 -251.749845) (xy 126.649988 -251.774452) (xy 127.908553 -251.774452) (xy 127.912648 -251.723724)
			(xy 127.924827 -251.67431) (xy 127.944775 -251.62749) (xy 127.971976 -251.584476) (xy 128.005724 -251.546382)
			(xy 128.045146 -251.514195) (xy 128.08922 -251.488749) (xy 128.136806 -251.470702) (xy 128.18667 -251.460522)
			(xy 128.237522 -251.458473) (xy 128.288043 -251.464607) (xy 128.336927 -251.478767) (xy 128.382906 -251.500584)
			(xy 128.42479 -251.529494) (xy 128.461494 -251.564749) (xy 128.492067 -251.605435) (xy 128.515718 -251.650498)
			(xy 128.531834 -251.698772) (xy 128.539998 -251.749006) (xy 128.54051 -251.774452) (xy 128.859038 -251.774452)
			(xy 128.862998 -251.725398) (xy 128.874775 -251.677614) (xy 128.894066 -251.632338) (xy 128.920369 -251.590742)
			(xy 128.953004 -251.553905) (xy 128.991125 -251.52278) (xy 129.033746 -251.498173) (xy 129.079762 -251.480721)
			(xy 129.127981 -251.470877) (xy 129.177156 -251.468896) (xy 129.226011 -251.474828) (xy 129.273282 -251.48852)
			(xy 129.317744 -251.509618) (xy 129.358247 -251.537574) (xy 129.39374 -251.571666) (xy 129.423305 -251.61101)
			(xy 129.446176 -251.654587) (xy 129.46176 -251.701268) (xy 129.469655 -251.749845) (xy 129.47015 -251.774452)
			(xy 130.728461 -251.774452) (xy 130.732556 -251.723724) (xy 130.744735 -251.67431) (xy 130.764683 -251.62749)
			(xy 130.791884 -251.584476) (xy 130.825632 -251.546382) (xy 130.865054 -251.514195) (xy 130.909128 -251.488749)
			(xy 130.956714 -251.470702) (xy 131.006578 -251.460522) (xy 131.05743 -251.458473) (xy 131.107951 -251.464607)
			(xy 131.156835 -251.478767) (xy 131.202814 -251.500584) (xy 131.244698 -251.529494) (xy 131.281402 -251.564749)
			(xy 131.311975 -251.605435) (xy 131.335626 -251.650498) (xy 131.351742 -251.698772) (xy 131.359906 -251.749006)
			(xy 131.360418 -251.774452) (xy 131.678946 -251.774452) (xy 131.682906 -251.725398) (xy 131.694683 -251.677614)
			(xy 131.713974 -251.632338) (xy 131.740277 -251.590742) (xy 131.772912 -251.553905) (xy 131.811033 -251.52278)
			(xy 131.853654 -251.498173) (xy 131.89967 -251.480721) (xy 131.947889 -251.470877) (xy 131.997064 -251.468896)
			(xy 132.045919 -251.474828) (xy 132.09319 -251.48852) (xy 132.137652 -251.509618) (xy 132.178155 -251.537574)
			(xy 132.213648 -251.571666) (xy 132.243213 -251.61101) (xy 132.266084 -251.654587) (xy 132.281668 -251.701268)
			(xy 132.289563 -251.749845) (xy 132.290058 -251.774452) (xy 132.619 -251.774452) (xy 132.62296 -251.725398)
			(xy 132.634737 -251.677614) (xy 132.654028 -251.632338) (xy 132.680331 -251.590742) (xy 132.712966 -251.553905)
			(xy 132.751087 -251.52278) (xy 132.793708 -251.498173) (xy 132.839724 -251.480721) (xy 132.887943 -251.470877)
			(xy 132.937118 -251.468896) (xy 132.985973 -251.474828) (xy 133.033244 -251.48852) (xy 133.077706 -251.509618)
			(xy 133.118209 -251.537574) (xy 133.153702 -251.571666) (xy 133.183267 -251.61101) (xy 133.206138 -251.654587)
			(xy 133.221722 -251.701268) (xy 133.229617 -251.749845) (xy 133.230112 -251.774452) (xy 133.559054 -251.774452)
			(xy 133.563014 -251.725398) (xy 133.574791 -251.677614) (xy 133.594082 -251.632338) (xy 133.620385 -251.590742)
			(xy 133.65302 -251.553905) (xy 133.691141 -251.52278) (xy 133.733762 -251.498173) (xy 133.779778 -251.480721)
			(xy 133.827997 -251.470877) (xy 133.877172 -251.468896) (xy 133.926027 -251.474828) (xy 133.973298 -251.48852)
			(xy 134.01776 -251.509618) (xy 134.058263 -251.537574) (xy 134.093756 -251.571666) (xy 134.123321 -251.61101)
			(xy 134.146192 -251.654587) (xy 134.161776 -251.701268) (xy 134.169671 -251.749845) (xy 134.170166 -251.774452)
			(xy 134.498854 -251.774452) (xy 134.502814 -251.725398) (xy 134.514591 -251.677614) (xy 134.533882 -251.632338)
			(xy 134.560185 -251.590742) (xy 134.59282 -251.553905) (xy 134.630941 -251.52278) (xy 134.673562 -251.498173)
			(xy 134.719578 -251.480721) (xy 134.767797 -251.470877) (xy 134.816972 -251.468896) (xy 134.865827 -251.474828)
			(xy 134.913098 -251.48852) (xy 134.95756 -251.509618) (xy 134.998063 -251.537574) (xy 135.033556 -251.571666)
			(xy 135.063121 -251.61101) (xy 135.085992 -251.654587) (xy 135.101576 -251.701268) (xy 135.109471 -251.749845)
			(xy 135.109966 -251.774452) (xy 135.438908 -251.774452) (xy 135.442868 -251.725398) (xy 135.454645 -251.677614)
			(xy 135.473936 -251.632338) (xy 135.500239 -251.590742) (xy 135.532874 -251.553905) (xy 135.570995 -251.52278)
			(xy 135.613616 -251.498173) (xy 135.659632 -251.480721) (xy 135.707851 -251.470877) (xy 135.757026 -251.468896)
			(xy 135.805881 -251.474828) (xy 135.853152 -251.48852) (xy 135.897614 -251.509618) (xy 135.938117 -251.537574)
			(xy 135.97361 -251.571666) (xy 136.003175 -251.61101) (xy 136.026046 -251.654587) (xy 136.04163 -251.701268)
			(xy 136.049525 -251.749845) (xy 136.05002 -251.774452) (xy 136.049525 -251.799059) (xy 136.04163 -251.847636)
			(xy 136.026046 -251.894317) (xy 136.003175 -251.937894) (xy 135.97361 -251.977238) (xy 135.938117 -252.01133)
			(xy 135.897614 -252.039286) (xy 135.853152 -252.060384) (xy 135.805881 -252.074076) (xy 135.757026 -252.080008)
			(xy 135.707851 -252.078027) (xy 135.659632 -252.068183) (xy 135.613616 -252.050731) (xy 135.570995 -252.026124)
			(xy 135.532874 -251.994999) (xy 135.500239 -251.958162) (xy 135.473936 -251.916566) (xy 135.454645 -251.87129)
			(xy 135.442868 -251.823506) (xy 135.438908 -251.774452) (xy 135.109966 -251.774452) (xy 135.109471 -251.799059)
			(xy 135.101576 -251.847636) (xy 135.085992 -251.894317) (xy 135.063121 -251.937894) (xy 135.033556 -251.977238)
			(xy 134.998063 -252.01133) (xy 134.95756 -252.039286) (xy 134.913098 -252.060384) (xy 134.865827 -252.074076)
			(xy 134.816972 -252.080008) (xy 134.767797 -252.078027) (xy 134.719578 -252.068183) (xy 134.673562 -252.050731)
			(xy 134.630941 -252.026124) (xy 134.59282 -251.994999) (xy 134.560185 -251.958162) (xy 134.533882 -251.916566)
			(xy 134.514591 -251.87129) (xy 134.502814 -251.823506) (xy 134.498854 -251.774452) (xy 134.170166 -251.774452)
			(xy 134.169671 -251.799059) (xy 134.161776 -251.847636) (xy 134.146192 -251.894317) (xy 134.123321 -251.937894)
			(xy 134.093756 -251.977238) (xy 134.058263 -252.01133) (xy 134.01776 -252.039286) (xy 133.973298 -252.060384)
			(xy 133.926027 -252.074076) (xy 133.877172 -252.080008) (xy 133.827997 -252.078027) (xy 133.779778 -252.068183)
			(xy 133.733762 -252.050731) (xy 133.691141 -252.026124) (xy 133.65302 -251.994999) (xy 133.620385 -251.958162)
			(xy 133.594082 -251.916566) (xy 133.574791 -251.87129) (xy 133.563014 -251.823506) (xy 133.559054 -251.774452)
			(xy 133.230112 -251.774452) (xy 133.229617 -251.799059) (xy 133.221722 -251.847636) (xy 133.206138 -251.894317)
			(xy 133.183267 -251.937894) (xy 133.153702 -251.977238) (xy 133.118209 -252.01133) (xy 133.077706 -252.039286)
			(xy 133.033244 -252.060384) (xy 132.985973 -252.074076) (xy 132.937118 -252.080008) (xy 132.887943 -252.078027)
			(xy 132.839724 -252.068183) (xy 132.793708 -252.050731) (xy 132.751087 -252.026124) (xy 132.712966 -251.994999)
			(xy 132.680331 -251.958162) (xy 132.654028 -251.916566) (xy 132.634737 -251.87129) (xy 132.62296 -251.823506)
			(xy 132.619 -251.774452) (xy 132.290058 -251.774452) (xy 132.289563 -251.799059) (xy 132.281668 -251.847636)
			(xy 132.266084 -251.894317) (xy 132.243213 -251.937894) (xy 132.213648 -251.977238) (xy 132.178155 -252.01133)
			(xy 132.137652 -252.039286) (xy 132.09319 -252.060384) (xy 132.045919 -252.074076) (xy 131.997064 -252.080008)
			(xy 131.947889 -252.078027) (xy 131.89967 -252.068183) (xy 131.853654 -252.050731) (xy 131.811033 -252.026124)
			(xy 131.772912 -251.994999) (xy 131.740277 -251.958162) (xy 131.713974 -251.916566) (xy 131.694683 -251.87129)
			(xy 131.682906 -251.823506) (xy 131.678946 -251.774452) (xy 131.360418 -251.774452) (xy 131.359906 -251.799898)
			(xy 131.351742 -251.850132) (xy 131.335626 -251.898406) (xy 131.311975 -251.943469) (xy 131.281402 -251.984155)
			(xy 131.244698 -252.01941) (xy 131.202814 -252.04832) (xy 131.156835 -252.070137) (xy 131.107951 -252.084297)
			(xy 131.05743 -252.090431) (xy 131.006578 -252.088382) (xy 130.956714 -252.078202) (xy 130.909128 -252.060155)
			(xy 130.865054 -252.034709) (xy 130.825632 -252.002522) (xy 130.791884 -251.964428) (xy 130.764683 -251.921414)
			(xy 130.744735 -251.874594) (xy 130.732556 -251.82518) (xy 130.728461 -251.774452) (xy 129.47015 -251.774452)
			(xy 129.469655 -251.799059) (xy 129.46176 -251.847636) (xy 129.446176 -251.894317) (xy 129.423305 -251.937894)
			(xy 129.39374 -251.977238) (xy 129.358247 -252.01133) (xy 129.317744 -252.039286) (xy 129.273282 -252.060384)
			(xy 129.226011 -252.074076) (xy 129.177156 -252.080008) (xy 129.127981 -252.078027) (xy 129.079762 -252.068183)
			(xy 129.033746 -252.050731) (xy 128.991125 -252.026124) (xy 128.953004 -251.994999) (xy 128.920369 -251.958162)
			(xy 128.894066 -251.916566) (xy 128.874775 -251.87129) (xy 128.862998 -251.823506) (xy 128.859038 -251.774452)
			(xy 128.54051 -251.774452) (xy 128.539998 -251.799898) (xy 128.531834 -251.850132) (xy 128.515718 -251.898406)
			(xy 128.492067 -251.943469) (xy 128.461494 -251.984155) (xy 128.42479 -252.01941) (xy 128.382906 -252.04832)
			(xy 128.336927 -252.070137) (xy 128.288043 -252.084297) (xy 128.237522 -252.090431) (xy 128.18667 -252.088382)
			(xy 128.136806 -252.078202) (xy 128.08922 -252.060155) (xy 128.045146 -252.034709) (xy 128.005724 -252.002522)
			(xy 127.971976 -251.964428) (xy 127.944775 -251.921414) (xy 127.924827 -251.874594) (xy 127.912648 -251.82518)
			(xy 127.908553 -251.774452) (xy 126.649988 -251.774452) (xy 126.649493 -251.799059) (xy 126.641598 -251.847636)
			(xy 126.626014 -251.894317) (xy 126.603143 -251.937894) (xy 126.573578 -251.977238) (xy 126.538085 -252.01133)
			(xy 126.497582 -252.039286) (xy 126.45312 -252.060384) (xy 126.405849 -252.074076) (xy 126.356994 -252.080008)
			(xy 126.307819 -252.078027) (xy 126.2596 -252.068183) (xy 126.213584 -252.050731) (xy 126.170963 -252.026124)
			(xy 126.132842 -251.994999) (xy 126.100207 -251.958162) (xy 126.073904 -251.916566) (xy 126.054613 -251.87129)
			(xy 126.042836 -251.823506) (xy 126.038876 -251.774452) (xy 124.770134 -251.774452) (xy 124.769612 -251.799707)
			(xy 124.761299 -251.849529) (xy 124.744898 -251.897303) (xy 124.720857 -251.941726) (xy 124.689833 -251.981586)
			(xy 124.652671 -252.015796) (xy 124.610385 -252.043422) (xy 124.564129 -252.063712) (xy 124.515164 -252.076112)
			(xy 124.464826 -252.080283) (xy 124.414488 -252.076112) (xy 124.365523 -252.063712) (xy 124.319267 -252.043422)
			(xy 124.276981 -252.015796) (xy 124.239819 -251.981586) (xy 124.208795 -251.941726) (xy 124.184754 -251.897303)
			(xy 124.168353 -251.849529) (xy 124.16004 -251.799707) (xy 124.159518 -251.774452) (xy 124.160166 -251.745752)
			(xy 124.170901 -251.689365) (xy 124.180854 -251.662438) (xy 124.18314 -251.656596) (xy 124.184664 -251.644404)
			(xy 124.184156 -251.638054) (xy 124.183226 -251.631946) (xy 124.178857 -251.620394) (xy 124.17552 -251.615194)
			(xy 124.129546 -251.547376) (xy 124.122017 -251.537358) (xy 124.099899 -251.525643) (xy 124.087382 -251.525024)
			(xy 123.393708 -251.525024) (xy 123.383872 -251.524485) (xy 123.365714 -251.516895) (xy 123.358402 -251.510292)
			(xy 123.122182 -251.274072) (xy 123.100592 -251.266452) (xy 123.088908 -251.267722) (xy 123.054618 -251.269754)
			(xy 123.030625 -251.269285) (xy 122.983228 -251.261781) (xy 122.937589 -251.246956) (xy 122.89483 -251.225174)
			(xy 122.856005 -251.196972) (xy 122.82207 -251.163044) (xy 122.793859 -251.124225) (xy 122.772069 -251.081471)
			(xy 122.757234 -251.035834) (xy 122.74972 -250.988439) (xy 122.74931 -250.964446) (xy 122.751342 -250.930156)
			(xy 122.752612 -250.918472) (xy 122.744992 -250.896882) (xy 122.46229 -250.61418) (xy 122.455178 -250.606814)
			(xy 122.436382 -250.599194) (xy 121.520458 -250.599194) (xy 121.510618 -250.599725) (xy 121.492449 -250.607304)
			(xy 121.485152 -250.613926) (xy 121.420382 -250.678696) (xy 121.413843 -250.685762) (xy 121.406129 -250.703387)
			(xy 121.405396 -250.712986) (xy 121.40438 -250.743212) (xy 121.40446 -250.752121) (xy 121.410067 -250.769021)
			(xy 121.415302 -250.776232) (xy 121.430515 -250.796527) (xy 121.454703 -250.841105) (xy 121.471204 -250.889063)
			(xy 121.479565 -250.939087) (xy 121.480072 -250.964446) (xy 121.479598 -250.988434) (xy 121.472086 -251.035818)
			(xy 121.457254 -251.081443) (xy 121.435467 -251.124187) (xy 121.407263 -251.162996) (xy 121.373334 -251.196916)
			(xy 121.334517 -251.22511) (xy 121.291768 -251.246885) (xy 121.246138 -251.261705) (xy 121.198752 -251.269204)
			(xy 121.174764 -251.269754) (xy 121.163224 -251.269625) (xy 121.140213 -251.267845) (xy 121.12879 -251.266198)
			(xy 121.12498 -251.26569) (xy 121.123964 -251.26569) (xy 121.100338 -251.261232) (xy 121.054781 -251.245869)
			(xy 121.012197 -251.22355) (xy 120.992646 -251.209556) (xy 120.986296 -251.204984) (xy 120.963944 -251.19711)
			(xy 120.959626 -251.195778) (xy 120.950682 -251.194495) (xy 120.946164 -251.19457) (xy 120.923812 -251.195078)
			(xy 120.914449 -251.195734) (xy 120.897114 -251.202891) (xy 120.89003 -251.209048) (xy 120.889522 -251.209556)
			(xy 120.775476 -251.323602) (xy 120.771264 -251.32807) (xy 120.764957 -251.338601) (xy 120.76303 -251.34443)
			(xy 120.761256 -251.350754) (xy 120.760618 -251.363869) (xy 120.76176 -251.370338) (xy 120.782334 -251.464318)
			(xy 120.799352 -251.483876) (xy 120.811544 -251.488448) (xy 120.836146 -251.498244) (xy 120.881806 -251.525053)
			(xy 120.922158 -251.559336) (xy 120.955992 -251.600065) (xy 120.982295 -251.646019) (xy 121.000277 -251.695821)
			(xy 121.0094 -251.747977) (xy 121.009918 -251.774452) (xy 122.278914 -251.774452) (xy 122.282874 -251.725398)
			(xy 122.294651 -251.677614) (xy 122.313942 -251.632338) (xy 122.340245 -251.590742) (xy 122.37288 -251.553905)
			(xy 122.411001 -251.52278) (xy 122.453622 -251.498173) (xy 122.499638 -251.480721) (xy 122.547857 -251.470877)
			(xy 122.597032 -251.468896) (xy 122.645887 -251.474828) (xy 122.693158 -251.48852) (xy 122.73762 -251.509618)
			(xy 122.778123 -251.537574) (xy 122.813616 -251.571666) (xy 122.843181 -251.61101) (xy 122.866052 -251.654587)
			(xy 122.881636 -251.701268) (xy 122.889531 -251.749845) (xy 122.890026 -251.774452) (xy 122.889531 -251.799059)
			(xy 122.881636 -251.847636) (xy 122.866052 -251.894317) (xy 122.843181 -251.937894) (xy 122.813616 -251.977238)
			(xy 122.778123 -252.01133) (xy 122.73762 -252.039286) (xy 122.693158 -252.060384) (xy 122.645887 -252.074076)
			(xy 122.597032 -252.080008) (xy 122.547857 -252.078027) (xy 122.499638 -252.068183) (xy 122.453622 -252.050731)
			(xy 122.411001 -252.026124) (xy 122.37288 -251.994999) (xy 122.340245 -251.958162) (xy 122.313942 -251.916566)
			(xy 122.294651 -251.87129) (xy 122.282874 -251.823506) (xy 122.278914 -251.774452) (xy 121.009918 -251.774452)
			(xy 121.009396 -251.799707) (xy 121.001083 -251.849529) (xy 120.984682 -251.897303) (xy 120.960641 -251.941726)
			(xy 120.929617 -251.981586) (xy 120.892455 -252.015796) (xy 120.850169 -252.043422) (xy 120.803913 -252.063712)
			(xy 120.754948 -252.076112) (xy 120.70461 -252.080283) (xy 120.654272 -252.076112) (xy 120.605307 -252.063712)
			(xy 120.559051 -252.043422) (xy 120.516765 -252.015796) (xy 120.479603 -251.981586) (xy 120.448579 -251.941726)
			(xy 120.424538 -251.897303) (xy 120.408137 -251.849529) (xy 120.399824 -251.799707) (xy 120.399302 -251.774452)
			(xy 120.39985 -251.748229) (xy 120.40882 -251.696556) (xy 120.426488 -251.647176) (xy 120.438926 -251.624084)
			(xy 120.442228 -251.618242) (xy 120.44553 -251.605796) (xy 120.44553 -251.598938) (xy 120.445359 -251.592207)
			(xy 120.441882 -251.579203) (xy 120.438672 -251.573284) (xy 120.395492 -251.49937) (xy 120.393206 -251.495814)
			(xy 120.386135 -251.486807) (xy 120.36622 -251.47557) (xy 120.354852 -251.474224) (xy 119.685308 -251.474224)
			(xy 119.675472 -251.473685) (xy 119.657314 -251.466095) (xy 119.650002 -251.459492) (xy 119.442738 -251.252228)
			(xy 119.414036 -251.245878) (xy 119.399812 -251.250958) (xy 119.374406 -251.259704) (xy 119.321519 -251.269162)
			(xy 119.294656 -251.269754) (xy 119.290592 -251.269754) (xy 119.267013 -251.268998) (xy 119.220503 -251.261117)
			(xy 119.175757 -251.246178) (xy 119.133841 -251.224536) (xy 119.095752 -251.196706) (xy 119.062395 -251.16335)
			(xy 119.034565 -251.12526) (xy 119.012922 -251.083344) (xy 118.997983 -251.038599) (xy 118.990102 -250.992089)
			(xy 118.989348 -250.96851) (xy 118.989348 -250.966478) (xy 118.989348 -250.964446) (xy 118.98993 -250.937582)
			(xy 118.999377 -250.88469) (xy 119.008144 -250.85929) (xy 119.013224 -250.845066) (xy 119.006874 -250.816364)
			(xy 118.80469 -250.61418) (xy 118.797578 -250.606814) (xy 118.778782 -250.599194) (xy 117.827298 -250.599194)
			(xy 117.817463 -250.599736) (xy 117.79931 -250.60733) (xy 117.791992 -250.613926) (xy 117.675152 -250.730766)
			(xy 117.667231 -250.739453) (xy 117.659644 -250.761673) (xy 117.662752 -250.784947) (xy 117.668802 -250.795028)
			(xy 117.680935 -250.813934) (xy 117.700117 -250.854554) (xy 117.713137 -250.897548) (xy 117.719715 -250.941985)
			(xy 117.72011 -250.964446) (xy 117.72011 -250.97105) (xy 117.719153 -250.99474) (xy 117.710821 -251.041412)
			(xy 117.695373 -251.086234) (xy 117.673182 -251.12813) (xy 117.644781 -251.166092) (xy 117.610853 -251.199206)
			(xy 117.572213 -251.226678) (xy 117.529791 -251.247845) (xy 117.484606 -251.2622) (xy 117.437746 -251.269398)
			(xy 117.41404 -251.269754) (xy 117.408198 -251.269754) (xy 117.386574 -251.268913) (xy 117.343876 -251.261876)
			(xy 117.302604 -251.248867) (xy 117.263588 -251.230148) (xy 117.245384 -251.218446) (xy 117.235298 -251.212427)
			(xy 117.212035 -251.209372) (xy 117.189813 -251.216898) (xy 117.181122 -251.224796) (xy 117.061742 -251.344176)
			(xy 117.053799 -251.353082) (xy 117.04638 -251.375731) (xy 117.047518 -251.38761) (xy 117.061488 -251.478796)
			(xy 117.075458 -251.498354) (xy 117.08638 -251.503942) (xy 117.107195 -251.515377) (xy 117.145324 -251.543687)
			(xy 117.178616 -251.577553) (xy 117.206271 -251.616161) (xy 117.227622 -251.658581) (xy 117.242155 -251.703792)
			(xy 117.249522 -251.750707) (xy 117.249956 -251.774452) (xy 118.518952 -251.774452) (xy 118.522912 -251.725398)
			(xy 118.534689 -251.677614) (xy 118.55398 -251.632338) (xy 118.580283 -251.590742) (xy 118.612918 -251.553905)
			(xy 118.651039 -251.52278) (xy 118.69366 -251.498173) (xy 118.739676 -251.480721) (xy 118.787895 -251.470877)
			(xy 118.83707 -251.468896) (xy 118.885925 -251.474828) (xy 118.933196 -251.48852) (xy 118.977658 -251.509618)
			(xy 119.018161 -251.537574) (xy 119.053654 -251.571666) (xy 119.083219 -251.61101) (xy 119.10609 -251.654587)
			(xy 119.121674 -251.701268) (xy 119.129569 -251.749845) (xy 119.130064 -251.774452) (xy 119.129569 -251.799059)
			(xy 119.121674 -251.847636) (xy 119.10609 -251.894317) (xy 119.083219 -251.937894) (xy 119.053654 -251.977238)
			(xy 119.018161 -252.01133) (xy 118.977658 -252.039286) (xy 118.933196 -252.060384) (xy 118.885925 -252.074076)
			(xy 118.83707 -252.080008) (xy 118.787895 -252.078027) (xy 118.739676 -252.068183) (xy 118.69366 -252.050731)
			(xy 118.651039 -252.026124) (xy 118.612918 -251.994999) (xy 118.580283 -251.958162) (xy 118.55398 -251.916566)
			(xy 118.534689 -251.87129) (xy 118.522912 -251.823506) (xy 118.518952 -251.774452) (xy 117.249956 -251.774452)
			(xy 117.249434 -251.799707) (xy 117.241121 -251.849529) (xy 117.22472 -251.897303) (xy 117.200679 -251.941726)
			(xy 117.169655 -251.981586) (xy 117.132493 -252.015796) (xy 117.090207 -252.043422) (xy 117.043951 -252.063712)
			(xy 116.994986 -252.076112) (xy 116.944648 -252.080283) (xy 116.89431 -252.076112) (xy 116.845345 -252.063712)
			(xy 116.799089 -252.043422) (xy 116.756803 -252.015796) (xy 116.719641 -251.981586) (xy 116.688617 -251.941726)
			(xy 116.664576 -251.897303) (xy 116.648175 -251.849529) (xy 116.639862 -251.799707) (xy 116.63934 -251.774452)
			(xy 116.639888 -251.748229) (xy 116.648859 -251.696557) (xy 116.666529 -251.647178) (xy 116.678964 -251.624084)
			(xy 116.682266 -251.618242) (xy 116.685568 -251.605796) (xy 116.685568 -251.598938) (xy 116.685398 -251.592206)
			(xy 116.681923 -251.579202) (xy 116.67871 -251.573284) (xy 116.63553 -251.49937) (xy 116.633244 -251.495814)
			(xy 116.626169 -251.486817) (xy 116.606252 -251.475604) (xy 116.59489 -251.474224) (xy 116.197888 -251.474224)
			(xy 116.188045 -251.473699) (xy 116.169867 -251.46613) (xy 116.162582 -251.459492) (xy 115.888008 -251.184918)
			(xy 115.885005 -251.182035) (xy 115.87824 -251.177185) (xy 115.874546 -251.175266) (xy 115.869279 -251.17283)
			(xy 115.857993 -251.170142) (xy 115.852194 -251.169932) (xy 115.782852 -251.169424) (xy 115.772996 -251.169825)
			(xy 115.754691 -251.177127) (xy 115.747292 -251.183648) (xy 115.747038 -251.183902) (xy 115.729846 -251.199913)
			(xy 115.691462 -251.226997) (xy 115.649385 -251.24789) (xy 115.604608 -251.262097) (xy 115.558183 -251.269285)
			(xy 115.534694 -251.269754) (xy 115.510702 -251.269283) (xy 115.463308 -251.261776) (xy 115.417672 -251.246949)
			(xy 115.374917 -251.225166) (xy 115.336095 -251.196963) (xy 115.302163 -251.163035) (xy 115.273955 -251.124217)
			(xy 115.252166 -251.081465) (xy 115.237333 -251.035831) (xy 115.22982 -250.988438) (xy 115.229386 -250.964446)
			(xy 115.229851 -250.939545) (xy 115.237883 -250.890395) (xy 115.25379 -250.843203) (xy 115.277151 -250.79922)
			(xy 115.307344 -250.759615) (xy 115.325144 -250.742196) (xy 115.332256 -250.735846) (xy 115.344194 -250.710954)
			(xy 115.346222 -250.706437) (xy 115.348657 -250.696842) (xy 115.34902 -250.691904) (xy 115.35029 -250.671584)
			(xy 115.350506 -250.660742) (xy 115.342881 -250.640464) (xy 115.335558 -250.632468) (xy 115.31727 -250.61418)
			(xy 115.309858 -250.607503) (xy 115.291422 -250.599934) (xy 115.281456 -250.599448) (xy 115.268756 -250.599448)
			(xy 115.263422 -250.599194) (xy 114.744754 -250.599194) (xy 114.73942 -250.599448) (xy 113.961926 -250.599448)
			(xy 113.952232 -250.599822) (xy 113.934204 -250.606946) (xy 113.920143 -250.620287) (xy 113.915698 -250.628912)
			(xy 113.87201 -250.724416) (xy 113.876074 -250.753626) (xy 113.88598 -250.765056) (xy 113.903299 -250.786016)
			(xy 113.930983 -250.832804) (xy 113.949938 -250.883757) (xy 113.959564 -250.937263) (xy 113.960148 -250.964446)
			(xy 113.959626 -250.989701) (xy 113.951313 -251.039523) (xy 113.934912 -251.087297) (xy 113.910871 -251.13172)
			(xy 113.879847 -251.17158) (xy 113.842685 -251.20579) (xy 113.800399 -251.233416) (xy 113.754143 -251.253706)
			(xy 113.705178 -251.266106) (xy 113.65484 -251.270277) (xy 113.604502 -251.266106) (xy 113.555537 -251.253706)
			(xy 113.509281 -251.233416) (xy 113.466995 -251.20579) (xy 113.429833 -251.17158) (xy 113.398809 -251.13172)
			(xy 113.374768 -251.087297) (xy 113.358367 -251.039523) (xy 113.350054 -250.989701) (xy 113.349532 -250.964446)
			(xy 113.350131 -250.937266) (xy 113.359766 -250.883765) (xy 113.378722 -250.832817) (xy 113.406401 -250.78603)
			(xy 113.4237 -250.765056) (xy 113.433606 -250.753626) (xy 113.43767 -250.724416) (xy 113.393982 -250.628912)
			(xy 113.387632 -250.615196) (xy 113.362994 -250.599194) (xy 112.864646 -250.599194) (xy 112.859312 -250.599448)
			(xy 111.918496 -250.599448) (xy 111.910622 -250.601988) (xy 111.883849 -250.610427) (xy 111.828453 -250.619492)
			(xy 111.800386 -250.620022) (xy 111.772318 -250.619506) (xy 111.71692 -250.610442) (xy 111.69015 -250.601988)
			(xy 111.682276 -250.599448) (xy 109.756448 -250.599448) (xy 109.751114 -250.599194) (xy 109.438948 -250.599194)
			(xy 109.429109 -250.599727) (xy 109.410943 -250.607308) (xy 109.403642 -250.613926) (xy 109.233716 -250.783852)
			(xy 109.228382 -250.815856) (xy 109.235494 -250.830588) (xy 109.245262 -250.851536) (xy 109.259062 -250.895647)
			(xy 109.266039 -250.941336) (xy 109.266482 -250.964446) (xy 109.266008 -250.988434) (xy 109.258496 -251.035819)
			(xy 109.243664 -251.081445) (xy 109.221878 -251.124189) (xy 109.193673 -251.163) (xy 109.159745 -251.19692)
			(xy 109.120928 -251.225115) (xy 109.078178 -251.246892) (xy 109.032549 -251.261713) (xy 108.985162 -251.269214)
			(xy 108.961174 -251.269754) (xy 108.938066 -251.269308) (xy 108.892381 -251.26231) (xy 108.848268 -251.248522)
			(xy 108.827316 -251.238766) (xy 108.812584 -251.231654) (xy 108.78058 -251.236988) (xy 108.661708 -251.35586)
			(xy 108.654469 -251.362571) (xy 108.636264 -251.370165) (xy 108.626402 -251.370592) (xy 107.819698 -251.370592)
			(xy 107.809385 -251.371056) (xy 107.79042 -251.379161) (xy 107.776194 -251.394095) (xy 107.773479 -251.400564)
			(xy 111.932723 -251.400564) (xy 111.936753 -251.348066) (xy 111.94875 -251.296798) (xy 111.968433 -251.247963)
			(xy 111.995339 -251.202704) (xy 112.028839 -251.162083) (xy 112.068147 -251.127052) (xy 112.112342 -251.098432)
			(xy 112.160387 -251.076893) (xy 112.211158 -251.062941) (xy 112.263463 -251.056903) (xy 112.316077 -251.05892)
			(xy 112.367767 -251.068944) (xy 112.41732 -251.086742) (xy 112.463576 -251.111895) (xy 112.50545 -251.143814)
			(xy 112.541962 -251.181752) (xy 112.572254 -251.224818) (xy 112.595617 -251.272003) (xy 112.611503 -251.322202)
			(xy 112.61954 -251.374238) (xy 112.620044 -251.400564) (xy 112.61954 -251.42689) (xy 112.611503 -251.478926)
			(xy 112.595617 -251.529125) (xy 112.572254 -251.57631) (xy 112.541962 -251.619376) (xy 112.50545 -251.657314)
			(xy 112.463576 -251.689233) (xy 112.41732 -251.714386) (xy 112.367767 -251.732184) (xy 112.316077 -251.742208)
			(xy 112.263463 -251.744225) (xy 112.211158 -251.738187) (xy 112.160387 -251.724235) (xy 112.112342 -251.702696)
			(xy 112.068147 -251.674076) (xy 112.028839 -251.639045) (xy 111.995339 -251.598424) (xy 111.968433 -251.553165)
			(xy 111.94875 -251.50433) (xy 111.936753 -251.453062) (xy 111.932723 -251.400564) (xy 107.773479 -251.400564)
			(xy 107.7722 -251.403612) (xy 107.739688 -251.489972) (xy 107.736479 -251.499714) (xy 107.737277 -251.52019)
			(xy 107.74604 -251.538714) (xy 107.753404 -251.545852) (xy 107.7724 -251.563391) (xy 107.804783 -251.60369)
			(xy 107.82991 -251.648871) (xy 107.847063 -251.69764) (xy 107.855751 -251.748603) (xy 107.856274 -251.774452)
			(xy 109.12527 -251.774452) (xy 109.12923 -251.725398) (xy 109.141007 -251.677614) (xy 109.160298 -251.632338)
			(xy 109.186601 -251.590742) (xy 109.219236 -251.553905) (xy 109.257357 -251.52278) (xy 109.299978 -251.498173)
			(xy 109.345994 -251.480721) (xy 109.394213 -251.470877) (xy 109.443388 -251.468896) (xy 109.492243 -251.474828)
			(xy 109.539514 -251.48852) (xy 109.583976 -251.509618) (xy 109.624479 -251.537574) (xy 109.659972 -251.571666)
			(xy 109.689537 -251.61101) (xy 109.712408 -251.654587) (xy 109.727992 -251.701268) (xy 109.735887 -251.749845)
			(xy 109.736382 -251.774452) (xy 112.878882 -251.774452) (xy 112.882842 -251.725398) (xy 112.894619 -251.677614)
			(xy 112.91391 -251.632338) (xy 112.940213 -251.590742) (xy 112.972848 -251.553905) (xy 113.010969 -251.52278)
			(xy 113.05359 -251.498173) (xy 113.099606 -251.480721) (xy 113.147825 -251.470877) (xy 113.197 -251.468896)
			(xy 113.245855 -251.474828) (xy 113.293126 -251.48852) (xy 113.337588 -251.509618) (xy 113.378091 -251.537574)
			(xy 113.413584 -251.571666) (xy 113.443149 -251.61101) (xy 113.46602 -251.654587) (xy 113.481604 -251.701268)
			(xy 113.489499 -251.749845) (xy 113.489994 -251.774452) (xy 114.75899 -251.774452) (xy 114.76295 -251.725398)
			(xy 114.774727 -251.677614) (xy 114.794018 -251.632338) (xy 114.820321 -251.590742) (xy 114.852956 -251.553905)
			(xy 114.891077 -251.52278) (xy 114.933698 -251.498173) (xy 114.979714 -251.480721) (xy 115.027933 -251.470877)
			(xy 115.077108 -251.468896) (xy 115.125963 -251.474828) (xy 115.173234 -251.48852) (xy 115.217696 -251.509618)
			(xy 115.258199 -251.537574) (xy 115.293692 -251.571666) (xy 115.323257 -251.61101) (xy 115.346128 -251.654587)
			(xy 115.361712 -251.701268) (xy 115.369607 -251.749845) (xy 115.370102 -251.774452) (xy 115.369607 -251.799059)
			(xy 115.361712 -251.847636) (xy 115.346128 -251.894317) (xy 115.323257 -251.937894) (xy 115.293692 -251.977238)
			(xy 115.258199 -252.01133) (xy 115.217696 -252.039286) (xy 115.173234 -252.060384) (xy 115.125963 -252.074076)
			(xy 115.077108 -252.080008) (xy 115.027933 -252.078027) (xy 114.979714 -252.068183) (xy 114.933698 -252.050731)
			(xy 114.891077 -252.026124) (xy 114.852956 -251.994999) (xy 114.820321 -251.958162) (xy 114.794018 -251.916566)
			(xy 114.774727 -251.87129) (xy 114.76295 -251.823506) (xy 114.75899 -251.774452) (xy 113.489994 -251.774452)
			(xy 113.489499 -251.799059) (xy 113.481604 -251.847636) (xy 113.46602 -251.894317) (xy 113.443149 -251.937894)
			(xy 113.413584 -251.977238) (xy 113.378091 -252.01133) (xy 113.337588 -252.039286) (xy 113.293126 -252.060384)
			(xy 113.245855 -252.074076) (xy 113.197 -252.080008) (xy 113.147825 -252.078027) (xy 113.099606 -252.068183)
			(xy 113.05359 -252.050731) (xy 113.010969 -252.026124) (xy 112.972848 -251.994999) (xy 112.940213 -251.958162)
			(xy 112.91391 -251.916566) (xy 112.894619 -251.87129) (xy 112.882842 -251.823506) (xy 112.878882 -251.774452)
			(xy 109.736382 -251.774452) (xy 109.735887 -251.799059) (xy 109.727992 -251.847636) (xy 109.712408 -251.894317)
			(xy 109.689537 -251.937894) (xy 109.659972 -251.977238) (xy 109.624479 -252.01133) (xy 109.583976 -252.039286)
			(xy 109.539514 -252.060384) (xy 109.492243 -252.074076) (xy 109.443388 -252.080008) (xy 109.394213 -252.078027)
			(xy 109.345994 -252.068183) (xy 109.299978 -252.050731) (xy 109.257357 -252.026124) (xy 109.219236 -251.994999)
			(xy 109.186601 -251.958162) (xy 109.160298 -251.916566) (xy 109.141007 -251.87129) (xy 109.12923 -251.823506)
			(xy 109.12527 -251.774452) (xy 107.856274 -251.774452) (xy 107.855752 -251.799707) (xy 107.847439 -251.849529)
			(xy 107.831038 -251.897303) (xy 107.806997 -251.941726) (xy 107.775973 -251.981586) (xy 107.738811 -252.015796)
			(xy 107.696525 -252.043422) (xy 107.650269 -252.063712) (xy 107.601304 -252.076112) (xy 107.550966 -252.080283)
			(xy 107.500628 -252.076112) (xy 107.451663 -252.063712) (xy 107.405407 -252.043422) (xy 107.363121 -252.015796)
			(xy 107.325959 -251.981586) (xy 107.294935 -251.941726) (xy 107.270894 -251.897303) (xy 107.254493 -251.849529)
			(xy 107.24618 -251.799707) (xy 107.245658 -251.774452) (xy 107.245797 -251.761689) (xy 107.24796 -251.736255)
			(xy 107.249976 -251.723652) (xy 107.249722 -251.723652) (xy 107.254596 -251.698171) (xy 107.271773 -251.649223)
			(xy 107.296968 -251.603879) (xy 107.329457 -251.563439) (xy 107.348528 -251.545852) (xy 107.355853 -251.538687)
			(xy 107.364591 -251.520171) (xy 107.36542 -251.499714) (xy 107.362244 -251.489972) (xy 107.329732 -251.403612)
			(xy 107.325675 -251.394128) (xy 107.311461 -251.379206) (xy 107.292536 -251.371045) (xy 107.282234 -251.370592)
			(xy 105.939844 -251.370592) (xy 105.929537 -251.371066) (xy 105.91059 -251.379182) (xy 105.896381 -251.394116)
			(xy 105.892346 -251.403612) (xy 105.859834 -251.489972) (xy 105.856623 -251.499713) (xy 105.857421 -251.520189)
			(xy 105.866191 -251.538708) (xy 105.87355 -251.545852) (xy 105.892543 -251.563393) (xy 105.924921 -251.603693)
			(xy 105.950045 -251.648874) (xy 105.967195 -251.697643) (xy 105.975882 -251.748604) (xy 105.97642 -251.774452)
			(xy 105.975898 -251.799707) (xy 105.967585 -251.849529) (xy 105.951184 -251.897303) (xy 105.927143 -251.941726)
			(xy 105.896119 -251.981586) (xy 105.858957 -252.015796) (xy 105.816671 -252.043422) (xy 105.770415 -252.063712)
			(xy 105.72145 -252.076112) (xy 105.671112 -252.080283) (xy 105.620774 -252.076112) (xy 105.571809 -252.063712)
			(xy 105.525553 -252.043422) (xy 105.483267 -252.015796) (xy 105.446105 -251.981586) (xy 105.415081 -251.941726)
			(xy 105.39104 -251.897303) (xy 105.374639 -251.849529) (xy 105.366326 -251.799707) (xy 105.365804 -251.774452)
			(xy 105.365943 -251.761689) (xy 105.368106 -251.736255) (xy 105.370122 -251.723652) (xy 105.369868 -251.723652)
			(xy 105.374742 -251.698172) (xy 105.391921 -251.649226) (xy 105.417119 -251.603884) (xy 105.449611 -251.563448)
			(xy 105.468674 -251.545852) (xy 105.475994 -251.538684) (xy 105.484723 -251.52017) (xy 105.485552 -251.499717)
			(xy 105.48239 -251.489972) (xy 105.449878 -251.403612) (xy 105.445818 -251.394134) (xy 105.431601 -251.379227)
			(xy 105.412678 -251.371085) (xy 105.40238 -251.370592) (xy 104.059736 -251.370592) (xy 104.04943 -251.371068)
			(xy 104.030485 -251.379186) (xy 104.016279 -251.394119) (xy 104.012238 -251.403612) (xy 103.979726 -251.489972)
			(xy 103.976516 -251.499713) (xy 103.977313 -251.520189) (xy 103.986082 -251.538709) (xy 103.993442 -251.545852)
			(xy 104.012436 -251.563393) (xy 104.044815 -251.603693) (xy 104.069939 -251.648874) (xy 104.08709 -251.697642)
			(xy 104.095776 -251.748604) (xy 104.096312 -251.774452) (xy 104.09579 -251.799707) (xy 104.087477 -251.849529)
			(xy 104.071076 -251.897303) (xy 104.047035 -251.941726) (xy 104.016011 -251.981586) (xy 103.978849 -252.015796)
			(xy 103.936563 -252.043422) (xy 103.890307 -252.063712) (xy 103.841342 -252.076112) (xy 103.791004 -252.080283)
			(xy 103.740666 -252.076112) (xy 103.691701 -252.063712) (xy 103.645445 -252.043422) (xy 103.603159 -252.015796)
			(xy 103.565997 -251.981586) (xy 103.534973 -251.941726) (xy 103.510932 -251.897303) (xy 103.494531 -251.849529)
			(xy 103.486218 -251.799707) (xy 103.485696 -251.774452) (xy 103.485835 -251.761689) (xy 103.487998 -251.736255)
			(xy 103.490014 -251.723652) (xy 103.48976 -251.723652) (xy 103.494634 -251.698172) (xy 103.511813 -251.649225)
			(xy 103.53701 -251.603883) (xy 103.569502 -251.563447) (xy 103.588566 -251.545852) (xy 103.595887 -251.538685)
			(xy 103.604618 -251.52017) (xy 103.605446 -251.499717) (xy 103.602282 -251.489972) (xy 103.56977 -251.403612)
			(xy 103.56571 -251.394135) (xy 103.551492 -251.37923) (xy 103.53257 -251.371092) (xy 103.522272 -251.370592)
			(xy 102.798626 -251.370592) (xy 102.788789 -251.371128) (xy 102.770628 -251.378715) (xy 102.76332 -251.385324)
			(xy 102.664006 -251.484892) (xy 102.657288 -251.492128) (xy 102.649684 -251.510333) (xy 102.649274 -251.520198)
			(xy 102.649274 -251.807472) (xy 102.649743 -251.817345) (xy 102.657197 -251.835633) (xy 102.663752 -251.843032)
			(xy 102.664006 -251.843286) (xy 103.237284 -252.416564) (xy 111.913673 -252.416564) (xy 111.917703 -252.364066)
			(xy 111.9297 -252.312798) (xy 111.949383 -252.263963) (xy 111.976289 -252.218704) (xy 112.009789 -252.178083)
			(xy 112.049097 -252.143052) (xy 112.093292 -252.114432) (xy 112.141337 -252.092893) (xy 112.192108 -252.078941)
			(xy 112.244413 -252.072903) (xy 112.297027 -252.07492) (xy 112.348717 -252.084944) (xy 112.39827 -252.102742)
			(xy 112.444526 -252.127895) (xy 112.4864 -252.159814) (xy 112.522912 -252.197752) (xy 112.553204 -252.240818)
			(xy 112.576567 -252.288003) (xy 112.592453 -252.338202) (xy 112.60049 -252.390238) (xy 112.600994 -252.416564)
			(xy 112.60049 -252.44289) (xy 112.592453 -252.494926) (xy 112.576567 -252.545125) (xy 112.557092 -252.584458)
			(xy 120.86896 -252.584458) (xy 120.87292 -252.535404) (xy 120.884697 -252.48762) (xy 120.903988 -252.442344)
			(xy 120.930291 -252.400748) (xy 120.962926 -252.363911) (xy 121.001047 -252.332786) (xy 121.043668 -252.308179)
			(xy 121.089684 -252.290727) (xy 121.137903 -252.280883) (xy 121.187078 -252.278902) (xy 121.235933 -252.284834)
			(xy 121.283204 -252.298526) (xy 121.327666 -252.319624) (xy 121.368169 -252.34758) (xy 121.403662 -252.381672)
			(xy 121.433227 -252.421016) (xy 121.456098 -252.464593) (xy 121.471682 -252.511274) (xy 121.479577 -252.559851)
			(xy 121.480072 -252.584458) (xy 122.748814 -252.584458) (xy 122.752774 -252.535404) (xy 122.764551 -252.48762)
			(xy 122.783842 -252.442344) (xy 122.810145 -252.400748) (xy 122.84278 -252.363911) (xy 122.880901 -252.332786)
			(xy 122.923522 -252.308179) (xy 122.969538 -252.290727) (xy 123.017757 -252.280883) (xy 123.066932 -252.278902)
			(xy 123.115787 -252.284834) (xy 123.163058 -252.298526) (xy 123.20752 -252.319624) (xy 123.248023 -252.34758)
			(xy 123.283516 -252.381672) (xy 123.313081 -252.421016) (xy 123.335952 -252.464593) (xy 123.351536 -252.511274)
			(xy 123.359431 -252.559851) (xy 123.359926 -252.584458) (xy 124.628922 -252.584458) (xy 124.632882 -252.535404)
			(xy 124.644659 -252.48762) (xy 124.66395 -252.442344) (xy 124.690253 -252.400748) (xy 124.722888 -252.363911)
			(xy 124.761009 -252.332786) (xy 124.80363 -252.308179) (xy 124.849646 -252.290727) (xy 124.897865 -252.280883)
			(xy 124.94704 -252.278902) (xy 124.995895 -252.284834) (xy 125.043166 -252.298526) (xy 125.087628 -252.319624)
			(xy 125.128131 -252.34758) (xy 125.163624 -252.381672) (xy 125.193189 -252.421016) (xy 125.21606 -252.464593)
			(xy 125.231644 -252.511274) (xy 125.239539 -252.559851) (xy 125.240034 -252.584458) (xy 126.50903 -252.584458)
			(xy 126.51299 -252.535404) (xy 126.524767 -252.48762) (xy 126.544058 -252.442344) (xy 126.570361 -252.400748)
			(xy 126.602996 -252.363911) (xy 126.641117 -252.332786) (xy 126.683738 -252.308179) (xy 126.729754 -252.290727)
			(xy 126.777973 -252.280883) (xy 126.827148 -252.278902) (xy 126.876003 -252.284834) (xy 126.923274 -252.298526)
			(xy 126.967736 -252.319624) (xy 127.008239 -252.34758) (xy 127.043732 -252.381672) (xy 127.073297 -252.421016)
			(xy 127.096168 -252.464593) (xy 127.111752 -252.511274) (xy 127.119647 -252.559851) (xy 127.120142 -252.584458)
			(xy 127.44883 -252.584458) (xy 127.45279 -252.535404) (xy 127.464567 -252.48762) (xy 127.483858 -252.442344)
			(xy 127.510161 -252.400748) (xy 127.542796 -252.363911) (xy 127.580917 -252.332786) (xy 127.623538 -252.308179)
			(xy 127.669554 -252.290727) (xy 127.717773 -252.280883) (xy 127.766948 -252.278902) (xy 127.815803 -252.284834)
			(xy 127.863074 -252.298526) (xy 127.907536 -252.319624) (xy 127.948039 -252.34758) (xy 127.983532 -252.381672)
			(xy 128.013097 -252.421016) (xy 128.035968 -252.464593) (xy 128.051552 -252.511274) (xy 128.059447 -252.559851)
			(xy 128.059942 -252.584458) (xy 128.388884 -252.584458) (xy 128.392844 -252.535404) (xy 128.404621 -252.48762)
			(xy 128.423912 -252.442344) (xy 128.450215 -252.400748) (xy 128.48285 -252.363911) (xy 128.520971 -252.332786)
			(xy 128.563592 -252.308179) (xy 128.609608 -252.290727) (xy 128.657827 -252.280883) (xy 128.707002 -252.278902)
			(xy 128.755857 -252.284834) (xy 128.803128 -252.298526) (xy 128.84759 -252.319624) (xy 128.888093 -252.34758)
			(xy 128.923586 -252.381672) (xy 128.953151 -252.421016) (xy 128.976022 -252.464593) (xy 128.991606 -252.511274)
			(xy 128.999501 -252.559851) (xy 128.999996 -252.584458) (xy 129.318507 -252.584458) (xy 129.322602 -252.53373)
			(xy 129.334781 -252.484316) (xy 129.354729 -252.437496) (xy 129.38193 -252.394482) (xy 129.415678 -252.356388)
			(xy 129.4551 -252.324201) (xy 129.499174 -252.298755) (xy 129.54676 -252.280708) (xy 129.596624 -252.270528)
			(xy 129.647476 -252.268479) (xy 129.697997 -252.274613) (xy 129.746881 -252.288773) (xy 129.79286 -252.31059)
			(xy 129.834744 -252.3395) (xy 129.871448 -252.374755) (xy 129.902021 -252.415441) (xy 129.925672 -252.460504)
			(xy 129.941788 -252.508778) (xy 129.949952 -252.559012) (xy 129.950464 -252.584458) (xy 130.268992 -252.584458)
			(xy 130.272952 -252.535404) (xy 130.284729 -252.48762) (xy 130.30402 -252.442344) (xy 130.330323 -252.400748)
			(xy 130.362958 -252.363911) (xy 130.401079 -252.332786) (xy 130.4437 -252.308179) (xy 130.489716 -252.290727)
			(xy 130.537935 -252.280883) (xy 130.58711 -252.278902) (xy 130.635965 -252.284834) (xy 130.683236 -252.298526)
			(xy 130.727698 -252.319624) (xy 130.768201 -252.34758) (xy 130.803694 -252.381672) (xy 130.833259 -252.421016)
			(xy 130.85613 -252.464593) (xy 130.871714 -252.511274) (xy 130.879609 -252.559851) (xy 130.880104 -252.584458)
			(xy 131.209046 -252.584458) (xy 131.213006 -252.535404) (xy 131.224783 -252.48762) (xy 131.244074 -252.442344)
			(xy 131.270377 -252.400748) (xy 131.303012 -252.363911) (xy 131.341133 -252.332786) (xy 131.383754 -252.308179)
			(xy 131.42977 -252.290727) (xy 131.477989 -252.280883) (xy 131.527164 -252.278902) (xy 131.576019 -252.284834)
			(xy 131.62329 -252.298526) (xy 131.667752 -252.319624) (xy 131.708255 -252.34758) (xy 131.743748 -252.381672)
			(xy 131.773313 -252.421016) (xy 131.796184 -252.464593) (xy 131.811768 -252.511274) (xy 131.819663 -252.559851)
			(xy 131.820158 -252.584458) (xy 132.138415 -252.584458) (xy 132.14251 -252.53373) (xy 132.154689 -252.484316)
			(xy 132.174637 -252.437496) (xy 132.201838 -252.394482) (xy 132.235586 -252.356388) (xy 132.275008 -252.324201)
			(xy 132.319082 -252.298755) (xy 132.366668 -252.280708) (xy 132.416532 -252.270528) (xy 132.467384 -252.268479)
			(xy 132.517905 -252.274613) (xy 132.566789 -252.288773) (xy 132.612768 -252.31059) (xy 132.654652 -252.3395)
			(xy 132.691356 -252.374755) (xy 132.721929 -252.415441) (xy 132.74558 -252.460504) (xy 132.761696 -252.508778)
			(xy 132.76986 -252.559012) (xy 132.770372 -252.584458) (xy 133.0889 -252.584458) (xy 133.09286 -252.535404)
			(xy 133.104637 -252.48762) (xy 133.123928 -252.442344) (xy 133.150231 -252.400748) (xy 133.182866 -252.363911)
			(xy 133.220987 -252.332786) (xy 133.263608 -252.308179) (xy 133.309624 -252.290727) (xy 133.357843 -252.280883)
			(xy 133.407018 -252.278902) (xy 133.455873 -252.284834) (xy 133.503144 -252.298526) (xy 133.547606 -252.319624)
			(xy 133.588109 -252.34758) (xy 133.623602 -252.381672) (xy 133.653167 -252.421016) (xy 133.676038 -252.464593)
			(xy 133.691622 -252.511274) (xy 133.699517 -252.559851) (xy 133.700012 -252.584458) (xy 134.028954 -252.584458)
			(xy 134.032914 -252.535404) (xy 134.044691 -252.48762) (xy 134.063982 -252.442344) (xy 134.090285 -252.400748)
			(xy 134.12292 -252.363911) (xy 134.161041 -252.332786) (xy 134.203662 -252.308179) (xy 134.249678 -252.290727)
			(xy 134.297897 -252.280883) (xy 134.347072 -252.278902) (xy 134.395927 -252.284834) (xy 134.443198 -252.298526)
			(xy 134.48766 -252.319624) (xy 134.528163 -252.34758) (xy 134.563656 -252.381672) (xy 134.593221 -252.421016)
			(xy 134.616092 -252.464593) (xy 134.631676 -252.511274) (xy 134.639571 -252.559851) (xy 134.640066 -252.584458)
			(xy 134.969008 -252.584458) (xy 134.972968 -252.535404) (xy 134.984745 -252.48762) (xy 135.004036 -252.442344)
			(xy 135.030339 -252.400748) (xy 135.062974 -252.363911) (xy 135.101095 -252.332786) (xy 135.143716 -252.308179)
			(xy 135.189732 -252.290727) (xy 135.237951 -252.280883) (xy 135.287126 -252.278902) (xy 135.335981 -252.284834)
			(xy 135.383252 -252.298526) (xy 135.427714 -252.319624) (xy 135.468217 -252.34758) (xy 135.50371 -252.381672)
			(xy 135.533275 -252.421016) (xy 135.556146 -252.464593) (xy 135.57173 -252.511274) (xy 135.579625 -252.559851)
			(xy 135.58012 -252.584458) (xy 135.909062 -252.584458) (xy 135.913022 -252.535404) (xy 135.924799 -252.48762)
			(xy 135.94409 -252.442344) (xy 135.970393 -252.400748) (xy 136.003028 -252.363911) (xy 136.041149 -252.332786)
			(xy 136.08377 -252.308179) (xy 136.129786 -252.290727) (xy 136.178005 -252.280883) (xy 136.22718 -252.278902)
			(xy 136.276035 -252.284834) (xy 136.323306 -252.298526) (xy 136.367768 -252.319624) (xy 136.408271 -252.34758)
			(xy 136.443764 -252.381672) (xy 136.473329 -252.421016) (xy 136.4962 -252.464593) (xy 136.511784 -252.511274)
			(xy 136.519679 -252.559851) (xy 136.520174 -252.584458) (xy 136.519679 -252.609065) (xy 136.511784 -252.657642)
			(xy 136.4962 -252.704323) (xy 136.473329 -252.7479) (xy 136.443764 -252.787244) (xy 136.408271 -252.821336)
			(xy 136.367768 -252.849292) (xy 136.323306 -252.87039) (xy 136.276035 -252.884082) (xy 136.22718 -252.890014)
			(xy 136.178005 -252.888033) (xy 136.129786 -252.878189) (xy 136.08377 -252.860737) (xy 136.041149 -252.83613)
			(xy 136.003028 -252.805005) (xy 135.970393 -252.768168) (xy 135.94409 -252.726572) (xy 135.924799 -252.681296)
			(xy 135.913022 -252.633512) (xy 135.909062 -252.584458) (xy 135.58012 -252.584458) (xy 135.579625 -252.609065)
			(xy 135.57173 -252.657642) (xy 135.556146 -252.704323) (xy 135.533275 -252.7479) (xy 135.50371 -252.787244)
			(xy 135.468217 -252.821336) (xy 135.427714 -252.849292) (xy 135.383252 -252.87039) (xy 135.335981 -252.884082)
			(xy 135.287126 -252.890014) (xy 135.237951 -252.888033) (xy 135.189732 -252.878189) (xy 135.143716 -252.860737)
			(xy 135.101095 -252.83613) (xy 135.062974 -252.805005) (xy 135.030339 -252.768168) (xy 135.004036 -252.726572)
			(xy 134.984745 -252.681296) (xy 134.972968 -252.633512) (xy 134.969008 -252.584458) (xy 134.640066 -252.584458)
			(xy 134.639571 -252.609065) (xy 134.631676 -252.657642) (xy 134.616092 -252.704323) (xy 134.593221 -252.7479)
			(xy 134.563656 -252.787244) (xy 134.528163 -252.821336) (xy 134.48766 -252.849292) (xy 134.443198 -252.87039)
			(xy 134.395927 -252.884082) (xy 134.347072 -252.890014) (xy 134.297897 -252.888033) (xy 134.249678 -252.878189)
			(xy 134.203662 -252.860737) (xy 134.161041 -252.83613) (xy 134.12292 -252.805005) (xy 134.090285 -252.768168)
			(xy 134.063982 -252.726572) (xy 134.044691 -252.681296) (xy 134.032914 -252.633512) (xy 134.028954 -252.584458)
			(xy 133.700012 -252.584458) (xy 133.699517 -252.609065) (xy 133.691622 -252.657642) (xy 133.676038 -252.704323)
			(xy 133.653167 -252.7479) (xy 133.623602 -252.787244) (xy 133.588109 -252.821336) (xy 133.547606 -252.849292)
			(xy 133.503144 -252.87039) (xy 133.455873 -252.884082) (xy 133.407018 -252.890014) (xy 133.357843 -252.888033)
			(xy 133.309624 -252.878189) (xy 133.263608 -252.860737) (xy 133.220987 -252.83613) (xy 133.182866 -252.805005)
			(xy 133.150231 -252.768168) (xy 133.123928 -252.726572) (xy 133.104637 -252.681296) (xy 133.09286 -252.633512)
			(xy 133.0889 -252.584458) (xy 132.770372 -252.584458) (xy 132.76986 -252.609904) (xy 132.761696 -252.660138)
			(xy 132.74558 -252.708412) (xy 132.721929 -252.753475) (xy 132.691356 -252.794161) (xy 132.654652 -252.829416)
			(xy 132.612768 -252.858326) (xy 132.566789 -252.880143) (xy 132.517905 -252.894303) (xy 132.467384 -252.900437)
			(xy 132.416532 -252.898388) (xy 132.366668 -252.888208) (xy 132.319082 -252.870161) (xy 132.275008 -252.844715)
			(xy 132.235586 -252.812528) (xy 132.201838 -252.774434) (xy 132.174637 -252.73142) (xy 132.154689 -252.6846)
			(xy 132.14251 -252.635186) (xy 132.138415 -252.584458) (xy 131.820158 -252.584458) (xy 131.819663 -252.609065)
			(xy 131.811768 -252.657642) (xy 131.796184 -252.704323) (xy 131.773313 -252.7479) (xy 131.743748 -252.787244)
			(xy 131.708255 -252.821336) (xy 131.667752 -252.849292) (xy 131.62329 -252.87039) (xy 131.576019 -252.884082)
			(xy 131.527164 -252.890014) (xy 131.477989 -252.888033) (xy 131.42977 -252.878189) (xy 131.383754 -252.860737)
			(xy 131.341133 -252.83613) (xy 131.303012 -252.805005) (xy 131.270377 -252.768168) (xy 131.244074 -252.726572)
			(xy 131.224783 -252.681296) (xy 131.213006 -252.633512) (xy 131.209046 -252.584458) (xy 130.880104 -252.584458)
			(xy 130.879609 -252.609065) (xy 130.871714 -252.657642) (xy 130.85613 -252.704323) (xy 130.833259 -252.7479)
			(xy 130.803694 -252.787244) (xy 130.768201 -252.821336) (xy 130.727698 -252.849292) (xy 130.683236 -252.87039)
			(xy 130.635965 -252.884082) (xy 130.58711 -252.890014) (xy 130.537935 -252.888033) (xy 130.489716 -252.878189)
			(xy 130.4437 -252.860737) (xy 130.401079 -252.83613) (xy 130.362958 -252.805005) (xy 130.330323 -252.768168)
			(xy 130.30402 -252.726572) (xy 130.284729 -252.681296) (xy 130.272952 -252.633512) (xy 130.268992 -252.584458)
			(xy 129.950464 -252.584458) (xy 129.949952 -252.609904) (xy 129.941788 -252.660138) (xy 129.925672 -252.708412)
			(xy 129.902021 -252.753475) (xy 129.871448 -252.794161) (xy 129.834744 -252.829416) (xy 129.79286 -252.858326)
			(xy 129.746881 -252.880143) (xy 129.697997 -252.894303) (xy 129.647476 -252.900437) (xy 129.596624 -252.898388)
			(xy 129.54676 -252.888208) (xy 129.499174 -252.870161) (xy 129.4551 -252.844715) (xy 129.415678 -252.812528)
			(xy 129.38193 -252.774434) (xy 129.354729 -252.73142) (xy 129.334781 -252.6846) (xy 129.322602 -252.635186)
			(xy 129.318507 -252.584458) (xy 128.999996 -252.584458) (xy 128.999501 -252.609065) (xy 128.991606 -252.657642)
			(xy 128.976022 -252.704323) (xy 128.953151 -252.7479) (xy 128.923586 -252.787244) (xy 128.888093 -252.821336)
			(xy 128.84759 -252.849292) (xy 128.803128 -252.87039) (xy 128.755857 -252.884082) (xy 128.707002 -252.890014)
			(xy 128.657827 -252.888033) (xy 128.609608 -252.878189) (xy 128.563592 -252.860737) (xy 128.520971 -252.83613)
			(xy 128.48285 -252.805005) (xy 128.450215 -252.768168) (xy 128.423912 -252.726572) (xy 128.404621 -252.681296)
			(xy 128.392844 -252.633512) (xy 128.388884 -252.584458) (xy 128.059942 -252.584458) (xy 128.059447 -252.609065)
			(xy 128.051552 -252.657642) (xy 128.035968 -252.704323) (xy 128.013097 -252.7479) (xy 127.983532 -252.787244)
			(xy 127.948039 -252.821336) (xy 127.907536 -252.849292) (xy 127.863074 -252.87039) (xy 127.815803 -252.884082)
			(xy 127.766948 -252.890014) (xy 127.717773 -252.888033) (xy 127.669554 -252.878189) (xy 127.623538 -252.860737)
			(xy 127.580917 -252.83613) (xy 127.542796 -252.805005) (xy 127.510161 -252.768168) (xy 127.483858 -252.726572)
			(xy 127.464567 -252.681296) (xy 127.45279 -252.633512) (xy 127.44883 -252.584458) (xy 127.120142 -252.584458)
			(xy 127.119647 -252.609065) (xy 127.111752 -252.657642) (xy 127.096168 -252.704323) (xy 127.073297 -252.7479)
			(xy 127.043732 -252.787244) (xy 127.008239 -252.821336) (xy 126.967736 -252.849292) (xy 126.923274 -252.87039)
			(xy 126.876003 -252.884082) (xy 126.827148 -252.890014) (xy 126.777973 -252.888033) (xy 126.729754 -252.878189)
			(xy 126.683738 -252.860737) (xy 126.641117 -252.83613) (xy 126.602996 -252.805005) (xy 126.570361 -252.768168)
			(xy 126.544058 -252.726572) (xy 126.524767 -252.681296) (xy 126.51299 -252.633512) (xy 126.50903 -252.584458)
			(xy 125.240034 -252.584458) (xy 125.239539 -252.609065) (xy 125.231644 -252.657642) (xy 125.21606 -252.704323)
			(xy 125.193189 -252.7479) (xy 125.163624 -252.787244) (xy 125.128131 -252.821336) (xy 125.087628 -252.849292)
			(xy 125.043166 -252.87039) (xy 124.995895 -252.884082) (xy 124.94704 -252.890014) (xy 124.897865 -252.888033)
			(xy 124.849646 -252.878189) (xy 124.80363 -252.860737) (xy 124.761009 -252.83613) (xy 124.722888 -252.805005)
			(xy 124.690253 -252.768168) (xy 124.66395 -252.726572) (xy 124.644659 -252.681296) (xy 124.632882 -252.633512)
			(xy 124.628922 -252.584458) (xy 123.359926 -252.584458) (xy 123.359431 -252.609065) (xy 123.351536 -252.657642)
			(xy 123.335952 -252.704323) (xy 123.313081 -252.7479) (xy 123.283516 -252.787244) (xy 123.248023 -252.821336)
			(xy 123.20752 -252.849292) (xy 123.163058 -252.87039) (xy 123.115787 -252.884082) (xy 123.066932 -252.890014)
			(xy 123.017757 -252.888033) (xy 122.969538 -252.878189) (xy 122.923522 -252.860737) (xy 122.880901 -252.83613)
			(xy 122.84278 -252.805005) (xy 122.810145 -252.768168) (xy 122.783842 -252.726572) (xy 122.764551 -252.681296)
			(xy 122.752774 -252.633512) (xy 122.748814 -252.584458) (xy 121.480072 -252.584458) (xy 121.479577 -252.609065)
			(xy 121.471682 -252.657642) (xy 121.456098 -252.704323) (xy 121.433227 -252.7479) (xy 121.403662 -252.787244)
			(xy 121.368169 -252.821336) (xy 121.327666 -252.849292) (xy 121.283204 -252.87039) (xy 121.235933 -252.884082)
			(xy 121.187078 -252.890014) (xy 121.137903 -252.888033) (xy 121.089684 -252.878189) (xy 121.043668 -252.860737)
			(xy 121.001047 -252.83613) (xy 120.962926 -252.805005) (xy 120.930291 -252.768168) (xy 120.903988 -252.726572)
			(xy 120.884697 -252.681296) (xy 120.87292 -252.633512) (xy 120.86896 -252.584458) (xy 112.557092 -252.584458)
			(xy 112.553204 -252.59231) (xy 112.522912 -252.635376) (xy 112.4864 -252.673314) (xy 112.444526 -252.705233)
			(xy 112.39827 -252.730386) (xy 112.348717 -252.748184) (xy 112.297027 -252.758208) (xy 112.244413 -252.760225)
			(xy 112.192108 -252.754187) (xy 112.141337 -252.740235) (xy 112.093292 -252.718696) (xy 112.049097 -252.690076)
			(xy 112.009789 -252.655045) (xy 111.976289 -252.614424) (xy 111.949383 -252.569165) (xy 111.9297 -252.52033)
			(xy 111.917703 -252.469062) (xy 111.913673 -252.416564) (xy 103.237284 -252.416564) (xy 103.962708 -253.141988)
			(xy 103.96601 -253.144274) (xy 103.985963 -253.159196) (xy 104.021193 -253.194424) (xy 104.036114 -253.214378)
			(xy 104.0384 -253.21768) (xy 104.468676 -253.647702) (xy 104.469184 -253.64821) (xy 104.476565 -253.654792)
			(xy 104.494864 -253.662238) (xy 104.504744 -253.662688) (xy 105.29951 -253.662688) (xy 105.306368 -253.66218)
			(xy 105.316639 -253.660215) (xy 105.334474 -253.649337) (xy 105.340912 -253.641098) (xy 105.342182 -253.63932)
			(xy 105.394252 -253.55804) (xy 105.39603 -253.532132) (xy 105.390696 -253.520448) (xy 105.381815 -253.500287)
			(xy 105.36928 -253.458053) (xy 105.362923 -253.414459) (xy 105.362502 -253.392432) (xy 105.362502 -253.387606)
			(xy 105.363398 -253.362612) (xy 105.372326 -253.313406) (xy 105.389153 -253.266312) (xy 105.413429 -253.22259)
			(xy 105.444506 -253.183408) (xy 105.481552 -253.149813) (xy 105.523577 -253.122705) (xy 105.569458 -253.102807)
			(xy 105.617968 -253.090651) (xy 105.66781 -253.086563) (xy 105.717652 -253.090651) (xy 105.766162 -253.102807)
			(xy 105.812043 -253.122705) (xy 105.854068 -253.149813) (xy 105.891114 -253.183408) (xy 105.922191 -253.22259)
			(xy 105.946467 -253.266312) (xy 105.963294 -253.313406) (xy 105.972222 -253.362612) (xy 105.973118 -253.387606)
			(xy 105.973118 -253.390654) (xy 105.973118 -253.392432) (xy 107.242114 -253.392432) (xy 107.246074 -253.343378)
			(xy 107.257851 -253.295594) (xy 107.277142 -253.250318) (xy 107.303445 -253.208722) (xy 107.33608 -253.171885)
			(xy 107.374201 -253.14076) (xy 107.416822 -253.116153) (xy 107.462838 -253.098701) (xy 107.511057 -253.088857)
			(xy 107.560232 -253.086876) (xy 107.609087 -253.092808) (xy 107.656358 -253.1065) (xy 107.70082 -253.127598)
			(xy 107.741323 -253.155554) (xy 107.776816 -253.189646) (xy 107.806381 -253.22899) (xy 107.829252 -253.272567)
			(xy 107.844836 -253.319248) (xy 107.852731 -253.367825) (xy 107.853226 -253.392432) (xy 109.122222 -253.392432)
			(xy 109.126182 -253.343378) (xy 109.137959 -253.295594) (xy 109.15725 -253.250318) (xy 109.183553 -253.208722)
			(xy 109.216188 -253.171885) (xy 109.254309 -253.14076) (xy 109.29693 -253.116153) (xy 109.342946 -253.098701)
			(xy 109.391165 -253.088857) (xy 109.44034 -253.086876) (xy 109.489195 -253.092808) (xy 109.536466 -253.1065)
			(xy 109.580928 -253.127598) (xy 109.621431 -253.155554) (xy 109.656924 -253.189646) (xy 109.686489 -253.22899)
			(xy 109.70936 -253.272567) (xy 109.724944 -253.319248) (xy 109.732839 -253.367825) (xy 109.733334 -253.392432)
			(xy 109.732839 -253.417039) (xy 109.730316 -253.432564) (xy 111.913673 -253.432564) (xy 111.917703 -253.380066)
			(xy 111.9297 -253.328798) (xy 111.949383 -253.279963) (xy 111.976289 -253.234704) (xy 112.009789 -253.194083)
			(xy 112.049097 -253.159052) (xy 112.093292 -253.130432) (xy 112.141337 -253.108893) (xy 112.192108 -253.094941)
			(xy 112.244413 -253.088903) (xy 112.297027 -253.09092) (xy 112.348717 -253.100944) (xy 112.39827 -253.118742)
			(xy 112.444526 -253.143895) (xy 112.4864 -253.175814) (xy 112.522912 -253.213752) (xy 112.553204 -253.256818)
			(xy 112.576567 -253.304003) (xy 112.592453 -253.354202) (xy 112.598358 -253.392432) (xy 112.882184 -253.392432)
			(xy 112.886144 -253.343378) (xy 112.897921 -253.295594) (xy 112.917212 -253.250318) (xy 112.943515 -253.208722)
			(xy 112.97615 -253.171885) (xy 113.014271 -253.14076) (xy 113.056892 -253.116153) (xy 113.102908 -253.098701)
			(xy 113.151127 -253.088857) (xy 113.200302 -253.086876) (xy 113.249157 -253.092808) (xy 113.296428 -253.1065)
			(xy 113.34089 -253.127598) (xy 113.381393 -253.155554) (xy 113.416886 -253.189646) (xy 113.446451 -253.22899)
			(xy 113.469322 -253.272567) (xy 113.484906 -253.319248) (xy 113.492801 -253.367825) (xy 113.493296 -253.392432)
			(xy 114.762038 -253.392432) (xy 114.765998 -253.343378) (xy 114.777775 -253.295594) (xy 114.797066 -253.250318)
			(xy 114.823369 -253.208722) (xy 114.856004 -253.171885) (xy 114.894125 -253.14076) (xy 114.936746 -253.116153)
			(xy 114.982762 -253.098701) (xy 115.030981 -253.088857) (xy 115.080156 -253.086876) (xy 115.129011 -253.092808)
			(xy 115.176282 -253.1065) (xy 115.220744 -253.127598) (xy 115.261247 -253.155554) (xy 115.29674 -253.189646)
			(xy 115.326305 -253.22899) (xy 115.349176 -253.272567) (xy 115.36476 -253.319248) (xy 115.372655 -253.367825)
			(xy 115.37315 -253.392432) (xy 116.642146 -253.392432) (xy 116.646106 -253.343378) (xy 116.657883 -253.295594)
			(xy 116.677174 -253.250318) (xy 116.703477 -253.208722) (xy 116.736112 -253.171885) (xy 116.774233 -253.14076)
			(xy 116.816854 -253.116153) (xy 116.86287 -253.098701) (xy 116.911089 -253.088857) (xy 116.960264 -253.086876)
			(xy 117.009119 -253.092808) (xy 117.05639 -253.1065) (xy 117.100852 -253.127598) (xy 117.141355 -253.155554)
			(xy 117.176848 -253.189646) (xy 117.206413 -253.22899) (xy 117.229284 -253.272567) (xy 117.244868 -253.319248)
			(xy 117.252763 -253.367825) (xy 117.253258 -253.392432) (xy 118.522 -253.392432) (xy 118.52596 -253.343378)
			(xy 118.537737 -253.295594) (xy 118.557028 -253.250318) (xy 118.583331 -253.208722) (xy 118.615966 -253.171885)
			(xy 118.654087 -253.14076) (xy 118.696708 -253.116153) (xy 118.742724 -253.098701) (xy 118.790943 -253.088857)
			(xy 118.840118 -253.086876) (xy 118.888973 -253.092808) (xy 118.936244 -253.1065) (xy 118.980706 -253.127598)
			(xy 119.021209 -253.155554) (xy 119.056702 -253.189646) (xy 119.086267 -253.22899) (xy 119.109138 -253.272567)
			(xy 119.124722 -253.319248) (xy 119.132617 -253.367825) (xy 119.133112 -253.392432) (xy 119.133071 -253.394464)
			(xy 122.278914 -253.394464) (xy 122.282874 -253.34541) (xy 122.294651 -253.297626) (xy 122.313942 -253.25235)
			(xy 122.340245 -253.210754) (xy 122.37288 -253.173917) (xy 122.411001 -253.142792) (xy 122.453622 -253.118185)
			(xy 122.499638 -253.100733) (xy 122.547857 -253.090889) (xy 122.597032 -253.088908) (xy 122.645887 -253.09484)
			(xy 122.693158 -253.108532) (xy 122.73762 -253.12963) (xy 122.778123 -253.157586) (xy 122.813616 -253.191678)
			(xy 122.843181 -253.231022) (xy 122.866052 -253.274599) (xy 122.881636 -253.32128) (xy 122.889531 -253.369857)
			(xy 122.890026 -253.394464) (xy 124.159022 -253.394464) (xy 124.162982 -253.34541) (xy 124.174759 -253.297626)
			(xy 124.19405 -253.25235) (xy 124.220353 -253.210754) (xy 124.252988 -253.173917) (xy 124.291109 -253.142792)
			(xy 124.33373 -253.118185) (xy 124.379746 -253.100733) (xy 124.427965 -253.090889) (xy 124.47714 -253.088908)
			(xy 124.525995 -253.09484) (xy 124.573266 -253.108532) (xy 124.617728 -253.12963) (xy 124.658231 -253.157586)
			(xy 124.693724 -253.191678) (xy 124.723289 -253.231022) (xy 124.74616 -253.274599) (xy 124.761744 -253.32128)
			(xy 124.769639 -253.369857) (xy 124.770134 -253.394464) (xy 126.038876 -253.394464) (xy 126.042836 -253.34541)
			(xy 126.054613 -253.297626) (xy 126.073904 -253.25235) (xy 126.100207 -253.210754) (xy 126.132842 -253.173917)
			(xy 126.170963 -253.142792) (xy 126.213584 -253.118185) (xy 126.2596 -253.100733) (xy 126.307819 -253.090889)
			(xy 126.356994 -253.088908) (xy 126.405849 -253.09484) (xy 126.45312 -253.108532) (xy 126.497582 -253.12963)
			(xy 126.538085 -253.157586) (xy 126.573578 -253.191678) (xy 126.603143 -253.231022) (xy 126.626014 -253.274599)
			(xy 126.641598 -253.32128) (xy 126.649493 -253.369857) (xy 126.649988 -253.394464) (xy 127.908553 -253.394464)
			(xy 127.912648 -253.343736) (xy 127.924827 -253.294322) (xy 127.944775 -253.247502) (xy 127.971976 -253.204488)
			(xy 128.005724 -253.166394) (xy 128.045146 -253.134207) (xy 128.08922 -253.108761) (xy 128.136806 -253.090714)
			(xy 128.18667 -253.080534) (xy 128.237522 -253.078485) (xy 128.288043 -253.084619) (xy 128.336927 -253.098779)
			(xy 128.382906 -253.120596) (xy 128.42479 -253.149506) (xy 128.461494 -253.184761) (xy 128.492067 -253.225447)
			(xy 128.515718 -253.27051) (xy 128.531834 -253.318784) (xy 128.539998 -253.369018) (xy 128.54051 -253.394464)
			(xy 128.848607 -253.394464) (xy 128.852702 -253.343736) (xy 128.864881 -253.294322) (xy 128.884829 -253.247502)
			(xy 128.91203 -253.204488) (xy 128.945778 -253.166394) (xy 128.9852 -253.134207) (xy 129.029274 -253.108761)
			(xy 129.07686 -253.090714) (xy 129.126724 -253.080534) (xy 129.177576 -253.078485) (xy 129.228097 -253.084619)
			(xy 129.276981 -253.098779) (xy 129.32296 -253.120596) (xy 129.364844 -253.149506) (xy 129.401548 -253.184761)
			(xy 129.432121 -253.225447) (xy 129.455772 -253.27051) (xy 129.471888 -253.318784) (xy 129.480052 -253.369018)
			(xy 129.480564 -253.394464) (xy 129.798838 -253.394464) (xy 129.802798 -253.34541) (xy 129.814575 -253.297626)
			(xy 129.833866 -253.25235) (xy 129.860169 -253.210754) (xy 129.892804 -253.173917) (xy 129.930925 -253.142792)
			(xy 129.973546 -253.118185) (xy 130.019562 -253.100733) (xy 130.067781 -253.090889) (xy 130.116956 -253.088908)
			(xy 130.165811 -253.09484) (xy 130.213082 -253.108532) (xy 130.257544 -253.12963) (xy 130.298047 -253.157586)
			(xy 130.33354 -253.191678) (xy 130.363105 -253.231022) (xy 130.385976 -253.274599) (xy 130.40156 -253.32128)
			(xy 130.409455 -253.369857) (xy 130.40995 -253.394464) (xy 130.728461 -253.394464) (xy 130.732556 -253.343736)
			(xy 130.744735 -253.294322) (xy 130.764683 -253.247502) (xy 130.791884 -253.204488) (xy 130.825632 -253.166394)
			(xy 130.865054 -253.134207) (xy 130.909128 -253.108761) (xy 130.956714 -253.090714) (xy 131.006578 -253.080534)
			(xy 131.05743 -253.078485) (xy 131.107951 -253.084619) (xy 131.156835 -253.098779) (xy 131.202814 -253.120596)
			(xy 131.244698 -253.149506) (xy 131.281402 -253.184761) (xy 131.311975 -253.225447) (xy 131.335626 -253.27051)
			(xy 131.351742 -253.318784) (xy 131.359906 -253.369018) (xy 131.360418 -253.394464) (xy 131.678946 -253.394464)
			(xy 131.682906 -253.34541) (xy 131.694683 -253.297626) (xy 131.713974 -253.25235) (xy 131.740277 -253.210754)
			(xy 131.772912 -253.173917) (xy 131.811033 -253.142792) (xy 131.853654 -253.118185) (xy 131.89967 -253.100733)
			(xy 131.947889 -253.090889) (xy 131.997064 -253.088908) (xy 132.045919 -253.09484) (xy 132.09319 -253.108532)
			(xy 132.137652 -253.12963) (xy 132.178155 -253.157586) (xy 132.213648 -253.191678) (xy 132.243213 -253.231022)
			(xy 132.266084 -253.274599) (xy 132.281668 -253.32128) (xy 132.289563 -253.369857) (xy 132.290058 -253.394464)
			(xy 132.608569 -253.394464) (xy 132.612664 -253.343736) (xy 132.624843 -253.294322) (xy 132.644791 -253.247502)
			(xy 132.671992 -253.204488) (xy 132.70574 -253.166394) (xy 132.745162 -253.134207) (xy 132.789236 -253.108761)
			(xy 132.836822 -253.090714) (xy 132.886686 -253.080534) (xy 132.937538 -253.078485) (xy 132.988059 -253.084619)
			(xy 133.036943 -253.098779) (xy 133.082922 -253.120596) (xy 133.124806 -253.149506) (xy 133.16151 -253.184761)
			(xy 133.192083 -253.225447) (xy 133.215734 -253.27051) (xy 133.23185 -253.318784) (xy 133.240014 -253.369018)
			(xy 133.240526 -253.394464) (xy 133.559054 -253.394464) (xy 133.563014 -253.34541) (xy 133.574791 -253.297626)
			(xy 133.594082 -253.25235) (xy 133.620385 -253.210754) (xy 133.65302 -253.173917) (xy 133.691141 -253.142792)
			(xy 133.733762 -253.118185) (xy 133.779778 -253.100733) (xy 133.827997 -253.090889) (xy 133.877172 -253.088908)
			(xy 133.926027 -253.09484) (xy 133.973298 -253.108532) (xy 134.01776 -253.12963) (xy 134.058263 -253.157586)
			(xy 134.093756 -253.191678) (xy 134.123321 -253.231022) (xy 134.146192 -253.274599) (xy 134.161776 -253.32128)
			(xy 134.169671 -253.369857) (xy 134.170166 -253.394464) (xy 134.498854 -253.394464) (xy 134.502814 -253.34541)
			(xy 134.514591 -253.297626) (xy 134.533882 -253.25235) (xy 134.560185 -253.210754) (xy 134.59282 -253.173917)
			(xy 134.630941 -253.142792) (xy 134.673562 -253.118185) (xy 134.719578 -253.100733) (xy 134.767797 -253.090889)
			(xy 134.816972 -253.088908) (xy 134.865827 -253.09484) (xy 134.913098 -253.108532) (xy 134.95756 -253.12963)
			(xy 134.998063 -253.157586) (xy 135.033556 -253.191678) (xy 135.063121 -253.231022) (xy 135.085992 -253.274599)
			(xy 135.101576 -253.32128) (xy 135.109471 -253.369857) (xy 135.109966 -253.394464) (xy 135.438908 -253.394464)
			(xy 135.442868 -253.34541) (xy 135.454645 -253.297626) (xy 135.473936 -253.25235) (xy 135.500239 -253.210754)
			(xy 135.532874 -253.173917) (xy 135.570995 -253.142792) (xy 135.613616 -253.118185) (xy 135.659632 -253.100733)
			(xy 135.707851 -253.090889) (xy 135.757026 -253.088908) (xy 135.805881 -253.09484) (xy 135.853152 -253.108532)
			(xy 135.897614 -253.12963) (xy 135.938117 -253.157586) (xy 135.97361 -253.191678) (xy 136.003175 -253.231022)
			(xy 136.026046 -253.274599) (xy 136.04163 -253.32128) (xy 136.049525 -253.369857) (xy 136.05002 -253.394464)
			(xy 136.049525 -253.419071) (xy 136.04163 -253.467648) (xy 136.026046 -253.514329) (xy 136.003175 -253.557906)
			(xy 135.97361 -253.59725) (xy 135.938117 -253.631342) (xy 135.897614 -253.659298) (xy 135.853152 -253.680396)
			(xy 135.805881 -253.694088) (xy 135.757026 -253.70002) (xy 135.707851 -253.698039) (xy 135.659632 -253.688195)
			(xy 135.613616 -253.670743) (xy 135.570995 -253.646136) (xy 135.532874 -253.615011) (xy 135.500239 -253.578174)
			(xy 135.473936 -253.536578) (xy 135.454645 -253.491302) (xy 135.442868 -253.443518) (xy 135.438908 -253.394464)
			(xy 135.109966 -253.394464) (xy 135.109471 -253.419071) (xy 135.101576 -253.467648) (xy 135.085992 -253.514329)
			(xy 135.063121 -253.557906) (xy 135.033556 -253.59725) (xy 134.998063 -253.631342) (xy 134.95756 -253.659298)
			(xy 134.913098 -253.680396) (xy 134.865827 -253.694088) (xy 134.816972 -253.70002) (xy 134.767797 -253.698039)
			(xy 134.719578 -253.688195) (xy 134.673562 -253.670743) (xy 134.630941 -253.646136) (xy 134.59282 -253.615011)
			(xy 134.560185 -253.578174) (xy 134.533882 -253.536578) (xy 134.514591 -253.491302) (xy 134.502814 -253.443518)
			(xy 134.498854 -253.394464) (xy 134.170166 -253.394464) (xy 134.169671 -253.419071) (xy 134.161776 -253.467648)
			(xy 134.146192 -253.514329) (xy 134.123321 -253.557906) (xy 134.093756 -253.59725) (xy 134.058263 -253.631342)
			(xy 134.01776 -253.659298) (xy 133.973298 -253.680396) (xy 133.926027 -253.694088) (xy 133.877172 -253.70002)
			(xy 133.827997 -253.698039) (xy 133.779778 -253.688195) (xy 133.733762 -253.670743) (xy 133.691141 -253.646136)
			(xy 133.65302 -253.615011) (xy 133.620385 -253.578174) (xy 133.594082 -253.536578) (xy 133.574791 -253.491302)
			(xy 133.563014 -253.443518) (xy 133.559054 -253.394464) (xy 133.240526 -253.394464) (xy 133.240014 -253.41991)
			(xy 133.23185 -253.470144) (xy 133.215734 -253.518418) (xy 133.192083 -253.563481) (xy 133.16151 -253.604167)
			(xy 133.124806 -253.639422) (xy 133.082922 -253.668332) (xy 133.036943 -253.690149) (xy 132.988059 -253.704309)
			(xy 132.937538 -253.710443) (xy 132.886686 -253.708394) (xy 132.836822 -253.698214) (xy 132.789236 -253.680167)
			(xy 132.745162 -253.654721) (xy 132.70574 -253.622534) (xy 132.671992 -253.58444) (xy 132.644791 -253.541426)
			(xy 132.624843 -253.494606) (xy 132.612664 -253.445192) (xy 132.608569 -253.394464) (xy 132.290058 -253.394464)
			(xy 132.289563 -253.419071) (xy 132.281668 -253.467648) (xy 132.266084 -253.514329) (xy 132.243213 -253.557906)
			(xy 132.213648 -253.59725) (xy 132.178155 -253.631342) (xy 132.137652 -253.659298) (xy 132.09319 -253.680396)
			(xy 132.045919 -253.694088) (xy 131.997064 -253.70002) (xy 131.947889 -253.698039) (xy 131.89967 -253.688195)
			(xy 131.853654 -253.670743) (xy 131.811033 -253.646136) (xy 131.772912 -253.615011) (xy 131.740277 -253.578174)
			(xy 131.713974 -253.536578) (xy 131.694683 -253.491302) (xy 131.682906 -253.443518) (xy 131.678946 -253.394464)
			(xy 131.360418 -253.394464) (xy 131.359906 -253.41991) (xy 131.351742 -253.470144) (xy 131.335626 -253.518418)
			(xy 131.311975 -253.563481) (xy 131.281402 -253.604167) (xy 131.244698 -253.639422) (xy 131.202814 -253.668332)
			(xy 131.156835 -253.690149) (xy 131.107951 -253.704309) (xy 131.05743 -253.710443) (xy 131.006578 -253.708394)
			(xy 130.956714 -253.698214) (xy 130.909128 -253.680167) (xy 130.865054 -253.654721) (xy 130.825632 -253.622534)
			(xy 130.791884 -253.58444) (xy 130.764683 -253.541426) (xy 130.744735 -253.494606) (xy 130.732556 -253.445192)
			(xy 130.728461 -253.394464) (xy 130.40995 -253.394464) (xy 130.409455 -253.419071) (xy 130.40156 -253.467648)
			(xy 130.385976 -253.514329) (xy 130.363105 -253.557906) (xy 130.33354 -253.59725) (xy 130.298047 -253.631342)
			(xy 130.257544 -253.659298) (xy 130.213082 -253.680396) (xy 130.165811 -253.694088) (xy 130.116956 -253.70002)
			(xy 130.067781 -253.698039) (xy 130.019562 -253.688195) (xy 129.973546 -253.670743) (xy 129.930925 -253.646136)
			(xy 129.892804 -253.615011) (xy 129.860169 -253.578174) (xy 129.833866 -253.536578) (xy 129.814575 -253.491302)
			(xy 129.802798 -253.443518) (xy 129.798838 -253.394464) (xy 129.480564 -253.394464) (xy 129.480052 -253.41991)
			(xy 129.471888 -253.470144) (xy 129.455772 -253.518418) (xy 129.432121 -253.563481) (xy 129.401548 -253.604167)
			(xy 129.364844 -253.639422) (xy 129.32296 -253.668332) (xy 129.276981 -253.690149) (xy 129.228097 -253.704309)
			(xy 129.177576 -253.710443) (xy 129.126724 -253.708394) (xy 129.07686 -253.698214) (xy 129.029274 -253.680167)
			(xy 128.9852 -253.654721) (xy 128.945778 -253.622534) (xy 128.91203 -253.58444) (xy 128.884829 -253.541426)
			(xy 128.864881 -253.494606) (xy 128.852702 -253.445192) (xy 128.848607 -253.394464) (xy 128.54051 -253.394464)
			(xy 128.539998 -253.41991) (xy 128.531834 -253.470144) (xy 128.515718 -253.518418) (xy 128.492067 -253.563481)
			(xy 128.461494 -253.604167) (xy 128.42479 -253.639422) (xy 128.382906 -253.668332) (xy 128.336927 -253.690149)
			(xy 128.288043 -253.704309) (xy 128.237522 -253.710443) (xy 128.18667 -253.708394) (xy 128.136806 -253.698214)
			(xy 128.08922 -253.680167) (xy 128.045146 -253.654721) (xy 128.005724 -253.622534) (xy 127.971976 -253.58444)
			(xy 127.944775 -253.541426) (xy 127.924827 -253.494606) (xy 127.912648 -253.445192) (xy 127.908553 -253.394464)
			(xy 126.649988 -253.394464) (xy 126.649493 -253.419071) (xy 126.641598 -253.467648) (xy 126.626014 -253.514329)
			(xy 126.603143 -253.557906) (xy 126.573578 -253.59725) (xy 126.538085 -253.631342) (xy 126.497582 -253.659298)
			(xy 126.45312 -253.680396) (xy 126.405849 -253.694088) (xy 126.356994 -253.70002) (xy 126.307819 -253.698039)
			(xy 126.2596 -253.688195) (xy 126.213584 -253.670743) (xy 126.170963 -253.646136) (xy 126.132842 -253.615011)
			(xy 126.100207 -253.578174) (xy 126.073904 -253.536578) (xy 126.054613 -253.491302) (xy 126.042836 -253.443518)
			(xy 126.038876 -253.394464) (xy 124.770134 -253.394464) (xy 124.769639 -253.419071) (xy 124.761744 -253.467648)
			(xy 124.74616 -253.514329) (xy 124.723289 -253.557906) (xy 124.693724 -253.59725) (xy 124.658231 -253.631342)
			(xy 124.617728 -253.659298) (xy 124.573266 -253.680396) (xy 124.525995 -253.694088) (xy 124.47714 -253.70002)
			(xy 124.427965 -253.698039) (xy 124.379746 -253.688195) (xy 124.33373 -253.670743) (xy 124.291109 -253.646136)
			(xy 124.252988 -253.615011) (xy 124.220353 -253.578174) (xy 124.19405 -253.536578) (xy 124.174759 -253.491302)
			(xy 124.162982 -253.443518) (xy 124.159022 -253.394464) (xy 122.890026 -253.394464) (xy 122.889531 -253.419071)
			(xy 122.881636 -253.467648) (xy 122.866052 -253.514329) (xy 122.843181 -253.557906) (xy 122.813616 -253.59725)
			(xy 122.778123 -253.631342) (xy 122.73762 -253.659298) (xy 122.693158 -253.680396) (xy 122.645887 -253.694088)
			(xy 122.597032 -253.70002) (xy 122.547857 -253.698039) (xy 122.499638 -253.688195) (xy 122.453622 -253.670743)
			(xy 122.411001 -253.646136) (xy 122.37288 -253.615011) (xy 122.340245 -253.578174) (xy 122.313942 -253.536578)
			(xy 122.294651 -253.491302) (xy 122.282874 -253.443518) (xy 122.278914 -253.394464) (xy 119.133071 -253.394464)
			(xy 119.132617 -253.417039) (xy 119.124722 -253.465616) (xy 119.109138 -253.512297) (xy 119.086267 -253.555874)
			(xy 119.056702 -253.595218) (xy 119.021209 -253.62931) (xy 118.980706 -253.657266) (xy 118.936244 -253.678364)
			(xy 118.888973 -253.692056) (xy 118.840118 -253.697988) (xy 118.790943 -253.696007) (xy 118.742724 -253.686163)
			(xy 118.696708 -253.668711) (xy 118.654087 -253.644104) (xy 118.615966 -253.612979) (xy 118.583331 -253.576142)
			(xy 118.557028 -253.534546) (xy 118.537737 -253.48927) (xy 118.52596 -253.441486) (xy 118.522 -253.392432)
			(xy 117.253258 -253.392432) (xy 117.252763 -253.417039) (xy 117.244868 -253.465616) (xy 117.229284 -253.512297)
			(xy 117.206413 -253.555874) (xy 117.176848 -253.595218) (xy 117.141355 -253.62931) (xy 117.100852 -253.657266)
			(xy 117.05639 -253.678364) (xy 117.009119 -253.692056) (xy 116.960264 -253.697988) (xy 116.911089 -253.696007)
			(xy 116.86287 -253.686163) (xy 116.816854 -253.668711) (xy 116.774233 -253.644104) (xy 116.736112 -253.612979)
			(xy 116.703477 -253.576142) (xy 116.677174 -253.534546) (xy 116.657883 -253.48927) (xy 116.646106 -253.441486)
			(xy 116.642146 -253.392432) (xy 115.37315 -253.392432) (xy 115.372655 -253.417039) (xy 115.36476 -253.465616)
			(xy 115.349176 -253.512297) (xy 115.326305 -253.555874) (xy 115.29674 -253.595218) (xy 115.261247 -253.62931)
			(xy 115.220744 -253.657266) (xy 115.176282 -253.678364) (xy 115.129011 -253.692056) (xy 115.080156 -253.697988)
			(xy 115.030981 -253.696007) (xy 114.982762 -253.686163) (xy 114.936746 -253.668711) (xy 114.894125 -253.644104)
			(xy 114.856004 -253.612979) (xy 114.823369 -253.576142) (xy 114.797066 -253.534546) (xy 114.777775 -253.48927)
			(xy 114.765998 -253.441486) (xy 114.762038 -253.392432) (xy 113.493296 -253.392432) (xy 113.492801 -253.417039)
			(xy 113.484906 -253.465616) (xy 113.469322 -253.512297) (xy 113.446451 -253.555874) (xy 113.416886 -253.595218)
			(xy 113.381393 -253.62931) (xy 113.34089 -253.657266) (xy 113.296428 -253.678364) (xy 113.249157 -253.692056)
			(xy 113.200302 -253.697988) (xy 113.151127 -253.696007) (xy 113.102908 -253.686163) (xy 113.056892 -253.668711)
			(xy 113.014271 -253.644104) (xy 112.97615 -253.612979) (xy 112.943515 -253.576142) (xy 112.917212 -253.534546)
			(xy 112.897921 -253.48927) (xy 112.886144 -253.441486) (xy 112.882184 -253.392432) (xy 112.598358 -253.392432)
			(xy 112.60049 -253.406238) (xy 112.600994 -253.432564) (xy 112.60049 -253.45889) (xy 112.592453 -253.510926)
			(xy 112.576567 -253.561125) (xy 112.553204 -253.60831) (xy 112.522912 -253.651376) (xy 112.4864 -253.689314)
			(xy 112.444526 -253.721233) (xy 112.39827 -253.746386) (xy 112.348717 -253.764184) (xy 112.297027 -253.774208)
			(xy 112.244413 -253.776225) (xy 112.192108 -253.770187) (xy 112.141337 -253.756235) (xy 112.093292 -253.734696)
			(xy 112.049097 -253.706076) (xy 112.009789 -253.671045) (xy 111.976289 -253.630424) (xy 111.949383 -253.585165)
			(xy 111.9297 -253.53633) (xy 111.917703 -253.485062) (xy 111.913673 -253.432564) (xy 109.730316 -253.432564)
			(xy 109.724944 -253.465616) (xy 109.70936 -253.512297) (xy 109.686489 -253.555874) (xy 109.656924 -253.595218)
			(xy 109.621431 -253.62931) (xy 109.580928 -253.657266) (xy 109.536466 -253.678364) (xy 109.489195 -253.692056)
			(xy 109.44034 -253.697988) (xy 109.391165 -253.696007) (xy 109.342946 -253.686163) (xy 109.29693 -253.668711)
			(xy 109.254309 -253.644104) (xy 109.216188 -253.612979) (xy 109.183553 -253.576142) (xy 109.15725 -253.534546)
			(xy 109.137959 -253.48927) (xy 109.126182 -253.441486) (xy 109.122222 -253.392432) (xy 107.853226 -253.392432)
			(xy 107.852731 -253.417039) (xy 107.844836 -253.465616) (xy 107.829252 -253.512297) (xy 107.806381 -253.555874)
			(xy 107.776816 -253.595218) (xy 107.741323 -253.62931) (xy 107.70082 -253.657266) (xy 107.656358 -253.678364)
			(xy 107.609087 -253.692056) (xy 107.560232 -253.697988) (xy 107.511057 -253.696007) (xy 107.462838 -253.686163)
			(xy 107.416822 -253.668711) (xy 107.374201 -253.644104) (xy 107.33608 -253.612979) (xy 107.303445 -253.576142)
			(xy 107.277142 -253.534546) (xy 107.257851 -253.48927) (xy 107.246074 -253.441486) (xy 107.242114 -253.392432)
			(xy 105.973118 -253.392432) (xy 105.972739 -253.414463) (xy 105.966404 -253.458067) (xy 105.953844 -253.5003)
			(xy 105.944924 -253.520448) (xy 105.93959 -253.532132) (xy 105.941368 -253.55804) (xy 105.993438 -253.63932)
			(xy 105.994708 -253.641098) (xy 106.001117 -253.649374) (xy 106.018961 -253.660269) (xy 106.029252 -253.66218)
			(xy 106.03611 -253.662688) (xy 106.345736 -253.662688) (xy 106.355577 -253.663217) (xy 106.373748 -253.670794)
			(xy 106.381042 -253.67742) (xy 107.152186 -254.448564) (xy 111.913673 -254.448564) (xy 111.917703 -254.396066)
			(xy 111.9297 -254.344798) (xy 111.949383 -254.295963) (xy 111.976289 -254.250704) (xy 112.009789 -254.210083)
			(xy 112.049097 -254.175052) (xy 112.093292 -254.146432) (xy 112.141337 -254.124893) (xy 112.192108 -254.110941)
			(xy 112.244413 -254.104903) (xy 112.297027 -254.10692) (xy 112.348717 -254.116944) (xy 112.39827 -254.134742)
			(xy 112.444526 -254.159895) (xy 112.4864 -254.191814) (xy 112.49858 -254.20447) (xy 120.86896 -254.20447)
			(xy 120.87292 -254.155416) (xy 120.884697 -254.107632) (xy 120.903988 -254.062356) (xy 120.930291 -254.02076)
			(xy 120.962926 -253.983923) (xy 121.001047 -253.952798) (xy 121.043668 -253.928191) (xy 121.089684 -253.910739)
			(xy 121.137903 -253.900895) (xy 121.187078 -253.898914) (xy 121.235933 -253.904846) (xy 121.283204 -253.918538)
			(xy 121.327666 -253.939636) (xy 121.368169 -253.967592) (xy 121.403662 -254.001684) (xy 121.433227 -254.041028)
			(xy 121.456098 -254.084605) (xy 121.471682 -254.131286) (xy 121.479577 -254.179863) (xy 121.480072 -254.20447)
			(xy 122.748814 -254.20447) (xy 122.752774 -254.155416) (xy 122.764551 -254.107632) (xy 122.783842 -254.062356)
			(xy 122.810145 -254.02076) (xy 122.84278 -253.983923) (xy 122.880901 -253.952798) (xy 122.923522 -253.928191)
			(xy 122.969538 -253.910739) (xy 123.017757 -253.900895) (xy 123.066932 -253.898914) (xy 123.115787 -253.904846)
			(xy 123.163058 -253.918538) (xy 123.20752 -253.939636) (xy 123.248023 -253.967592) (xy 123.283516 -254.001684)
			(xy 123.313081 -254.041028) (xy 123.335952 -254.084605) (xy 123.351536 -254.131286) (xy 123.359431 -254.179863)
			(xy 123.359926 -254.20447) (xy 124.628922 -254.20447) (xy 124.632882 -254.155416) (xy 124.644659 -254.107632)
			(xy 124.66395 -254.062356) (xy 124.690253 -254.02076) (xy 124.722888 -253.983923) (xy 124.761009 -253.952798)
			(xy 124.80363 -253.928191) (xy 124.849646 -253.910739) (xy 124.897865 -253.900895) (xy 124.94704 -253.898914)
			(xy 124.995895 -253.904846) (xy 125.043166 -253.918538) (xy 125.087628 -253.939636) (xy 125.128131 -253.967592)
			(xy 125.163624 -254.001684) (xy 125.193189 -254.041028) (xy 125.21606 -254.084605) (xy 125.231644 -254.131286)
			(xy 125.239539 -254.179863) (xy 125.240034 -254.20447) (xy 126.50903 -254.20447) (xy 126.51299 -254.155416)
			(xy 126.524767 -254.107632) (xy 126.544058 -254.062356) (xy 126.570361 -254.02076) (xy 126.602996 -253.983923)
			(xy 126.641117 -253.952798) (xy 126.683738 -253.928191) (xy 126.729754 -253.910739) (xy 126.777973 -253.900895)
			(xy 126.827148 -253.898914) (xy 126.876003 -253.904846) (xy 126.923274 -253.918538) (xy 126.967736 -253.939636)
			(xy 127.008239 -253.967592) (xy 127.043732 -254.001684) (xy 127.073297 -254.041028) (xy 127.096168 -254.084605)
			(xy 127.111752 -254.131286) (xy 127.119647 -254.179863) (xy 127.120142 -254.20447) (xy 127.438399 -254.20447)
			(xy 127.442494 -254.153742) (xy 127.454673 -254.104328) (xy 127.474621 -254.057508) (xy 127.501822 -254.014494)
			(xy 127.53557 -253.9764) (xy 127.574992 -253.944213) (xy 127.619066 -253.918767) (xy 127.666652 -253.90072)
			(xy 127.716516 -253.89054) (xy 127.767368 -253.888491) (xy 127.817889 -253.894625) (xy 127.866773 -253.908785)
			(xy 127.912752 -253.930602) (xy 127.954636 -253.959512) (xy 127.99134 -253.994767) (xy 128.021913 -254.035453)
			(xy 128.045564 -254.080516) (xy 128.06168 -254.12879) (xy 128.069844 -254.179024) (xy 128.070356 -254.20447)
			(xy 128.388884 -254.20447) (xy 128.392844 -254.155416) (xy 128.404621 -254.107632) (xy 128.423912 -254.062356)
			(xy 128.450215 -254.02076) (xy 128.48285 -253.983923) (xy 128.520971 -253.952798) (xy 128.563592 -253.928191)
			(xy 128.609608 -253.910739) (xy 128.657827 -253.900895) (xy 128.707002 -253.898914) (xy 128.755857 -253.904846)
			(xy 128.803128 -253.918538) (xy 128.84759 -253.939636) (xy 128.888093 -253.967592) (xy 128.923586 -254.001684)
			(xy 128.953151 -254.041028) (xy 128.976022 -254.084605) (xy 128.991606 -254.131286) (xy 128.999501 -254.179863)
			(xy 128.999996 -254.20447) (xy 129.318507 -254.20447) (xy 129.322602 -254.153742) (xy 129.334781 -254.104328)
			(xy 129.354729 -254.057508) (xy 129.38193 -254.014494) (xy 129.415678 -253.9764) (xy 129.4551 -253.944213)
			(xy 129.499174 -253.918767) (xy 129.54676 -253.90072) (xy 129.596624 -253.89054) (xy 129.647476 -253.888491)
			(xy 129.697997 -253.894625) (xy 129.746881 -253.908785) (xy 129.79286 -253.930602) (xy 129.834744 -253.959512)
			(xy 129.871448 -253.994767) (xy 129.902021 -254.035453) (xy 129.925672 -254.080516) (xy 129.941788 -254.12879)
			(xy 129.949952 -254.179024) (xy 129.950464 -254.20447) (xy 131.198615 -254.20447) (xy 131.20271 -254.153742)
			(xy 131.214889 -254.104328) (xy 131.234837 -254.057508) (xy 131.262038 -254.014494) (xy 131.295786 -253.9764)
			(xy 131.335208 -253.944213) (xy 131.379282 -253.918767) (xy 131.426868 -253.90072) (xy 131.476732 -253.89054)
			(xy 131.527584 -253.888491) (xy 131.578105 -253.894625) (xy 131.626989 -253.908785) (xy 131.672968 -253.930602)
			(xy 131.714852 -253.959512) (xy 131.751556 -253.994767) (xy 131.782129 -254.035453) (xy 131.80578 -254.080516)
			(xy 131.821896 -254.12879) (xy 131.83006 -254.179024) (xy 131.830572 -254.20447) (xy 132.138415 -254.20447)
			(xy 132.14251 -254.153742) (xy 132.154689 -254.104328) (xy 132.174637 -254.057508) (xy 132.201838 -254.014494)
			(xy 132.235586 -253.9764) (xy 132.275008 -253.944213) (xy 132.319082 -253.918767) (xy 132.366668 -253.90072)
			(xy 132.416532 -253.89054) (xy 132.467384 -253.888491) (xy 132.517905 -253.894625) (xy 132.566789 -253.908785)
			(xy 132.612768 -253.930602) (xy 132.654652 -253.959512) (xy 132.691356 -253.994767) (xy 132.721929 -254.035453)
			(xy 132.74558 -254.080516) (xy 132.761696 -254.12879) (xy 132.76986 -254.179024) (xy 132.770372 -254.20447)
			(xy 133.0889 -254.20447) (xy 133.09286 -254.155416) (xy 133.104637 -254.107632) (xy 133.123928 -254.062356)
			(xy 133.150231 -254.02076) (xy 133.182866 -253.983923) (xy 133.220987 -253.952798) (xy 133.263608 -253.928191)
			(xy 133.309624 -253.910739) (xy 133.357843 -253.900895) (xy 133.407018 -253.898914) (xy 133.455873 -253.904846)
			(xy 133.503144 -253.918538) (xy 133.547606 -253.939636) (xy 133.588109 -253.967592) (xy 133.623602 -254.001684)
			(xy 133.653167 -254.041028) (xy 133.676038 -254.084605) (xy 133.691622 -254.131286) (xy 133.699517 -254.179863)
			(xy 133.700012 -254.20447) (xy 134.028954 -254.20447) (xy 134.032914 -254.155416) (xy 134.044691 -254.107632)
			(xy 134.063982 -254.062356) (xy 134.090285 -254.02076) (xy 134.12292 -253.983923) (xy 134.161041 -253.952798)
			(xy 134.203662 -253.928191) (xy 134.249678 -253.910739) (xy 134.297897 -253.900895) (xy 134.347072 -253.898914)
			(xy 134.395927 -253.904846) (xy 134.443198 -253.918538) (xy 134.48766 -253.939636) (xy 134.528163 -253.967592)
			(xy 134.563656 -254.001684) (xy 134.593221 -254.041028) (xy 134.616092 -254.084605) (xy 134.631676 -254.131286)
			(xy 134.639571 -254.179863) (xy 134.640066 -254.20447) (xy 134.969008 -254.20447) (xy 134.972968 -254.155416)
			(xy 134.984745 -254.107632) (xy 135.004036 -254.062356) (xy 135.030339 -254.02076) (xy 135.062974 -253.983923)
			(xy 135.101095 -253.952798) (xy 135.143716 -253.928191) (xy 135.189732 -253.910739) (xy 135.237951 -253.900895)
			(xy 135.287126 -253.898914) (xy 135.335981 -253.904846) (xy 135.383252 -253.918538) (xy 135.427714 -253.939636)
			(xy 135.468217 -253.967592) (xy 135.50371 -254.001684) (xy 135.533275 -254.041028) (xy 135.556146 -254.084605)
			(xy 135.57173 -254.131286) (xy 135.579625 -254.179863) (xy 135.58012 -254.20447) (xy 135.909062 -254.20447)
			(xy 135.913022 -254.155416) (xy 135.924799 -254.107632) (xy 135.94409 -254.062356) (xy 135.970393 -254.02076)
			(xy 136.003028 -253.983923) (xy 136.041149 -253.952798) (xy 136.08377 -253.928191) (xy 136.129786 -253.910739)
			(xy 136.178005 -253.900895) (xy 136.22718 -253.898914) (xy 136.276035 -253.904846) (xy 136.323306 -253.918538)
			(xy 136.367768 -253.939636) (xy 136.408271 -253.967592) (xy 136.443764 -254.001684) (xy 136.473329 -254.041028)
			(xy 136.4962 -254.084605) (xy 136.511784 -254.131286) (xy 136.519679 -254.179863) (xy 136.520174 -254.20447)
			(xy 136.519679 -254.229077) (xy 136.511784 -254.277654) (xy 136.4962 -254.324335) (xy 136.473329 -254.367912)
			(xy 136.443764 -254.407256) (xy 136.408271 -254.441348) (xy 136.367768 -254.469304) (xy 136.323306 -254.490402)
			(xy 136.276035 -254.504094) (xy 136.22718 -254.510026) (xy 136.178005 -254.508045) (xy 136.129786 -254.498201)
			(xy 136.08377 -254.480749) (xy 136.041149 -254.456142) (xy 136.003028 -254.425017) (xy 135.970393 -254.38818)
			(xy 135.94409 -254.346584) (xy 135.924799 -254.301308) (xy 135.913022 -254.253524) (xy 135.909062 -254.20447)
			(xy 135.58012 -254.20447) (xy 135.579625 -254.229077) (xy 135.57173 -254.277654) (xy 135.556146 -254.324335)
			(xy 135.533275 -254.367912) (xy 135.50371 -254.407256) (xy 135.468217 -254.441348) (xy 135.427714 -254.469304)
			(xy 135.383252 -254.490402) (xy 135.335981 -254.504094) (xy 135.287126 -254.510026) (xy 135.237951 -254.508045)
			(xy 135.189732 -254.498201) (xy 135.143716 -254.480749) (xy 135.101095 -254.456142) (xy 135.062974 -254.425017)
			(xy 135.030339 -254.38818) (xy 135.004036 -254.346584) (xy 134.984745 -254.301308) (xy 134.972968 -254.253524)
			(xy 134.969008 -254.20447) (xy 134.640066 -254.20447) (xy 134.639571 -254.229077) (xy 134.631676 -254.277654)
			(xy 134.616092 -254.324335) (xy 134.593221 -254.367912) (xy 134.563656 -254.407256) (xy 134.528163 -254.441348)
			(xy 134.48766 -254.469304) (xy 134.443198 -254.490402) (xy 134.395927 -254.504094) (xy 134.347072 -254.510026)
			(xy 134.297897 -254.508045) (xy 134.249678 -254.498201) (xy 134.203662 -254.480749) (xy 134.161041 -254.456142)
			(xy 134.12292 -254.425017) (xy 134.090285 -254.38818) (xy 134.063982 -254.346584) (xy 134.044691 -254.301308)
			(xy 134.032914 -254.253524) (xy 134.028954 -254.20447) (xy 133.700012 -254.20447) (xy 133.699517 -254.229077)
			(xy 133.691622 -254.277654) (xy 133.676038 -254.324335) (xy 133.653167 -254.367912) (xy 133.623602 -254.407256)
			(xy 133.588109 -254.441348) (xy 133.547606 -254.469304) (xy 133.503144 -254.490402) (xy 133.455873 -254.504094)
			(xy 133.407018 -254.510026) (xy 133.357843 -254.508045) (xy 133.309624 -254.498201) (xy 133.263608 -254.480749)
			(xy 133.220987 -254.456142) (xy 133.182866 -254.425017) (xy 133.150231 -254.38818) (xy 133.123928 -254.346584)
			(xy 133.104637 -254.301308) (xy 133.09286 -254.253524) (xy 133.0889 -254.20447) (xy 132.770372 -254.20447)
			(xy 132.76986 -254.229916) (xy 132.761696 -254.28015) (xy 132.74558 -254.328424) (xy 132.721929 -254.373487)
			(xy 132.691356 -254.414173) (xy 132.654652 -254.449428) (xy 132.612768 -254.478338) (xy 132.566789 -254.500155)
			(xy 132.517905 -254.514315) (xy 132.467384 -254.520449) (xy 132.416532 -254.5184) (xy 132.366668 -254.50822)
			(xy 132.319082 -254.490173) (xy 132.275008 -254.464727) (xy 132.235586 -254.43254) (xy 132.201838 -254.394446)
			(xy 132.174637 -254.351432) (xy 132.154689 -254.304612) (xy 132.14251 -254.255198) (xy 132.138415 -254.20447)
			(xy 131.830572 -254.20447) (xy 131.83006 -254.229916) (xy 131.821896 -254.28015) (xy 131.80578 -254.328424)
			(xy 131.782129 -254.373487) (xy 131.751556 -254.414173) (xy 131.714852 -254.449428) (xy 131.672968 -254.478338)
			(xy 131.626989 -254.500155) (xy 131.578105 -254.514315) (xy 131.527584 -254.520449) (xy 131.476732 -254.5184)
			(xy 131.426868 -254.50822) (xy 131.379282 -254.490173) (xy 131.335208 -254.464727) (xy 131.295786 -254.43254)
			(xy 131.262038 -254.394446) (xy 131.234837 -254.351432) (xy 131.214889 -254.304612) (xy 131.20271 -254.255198)
			(xy 131.198615 -254.20447) (xy 129.950464 -254.20447) (xy 129.949952 -254.229916) (xy 129.941788 -254.28015)
			(xy 129.925672 -254.328424) (xy 129.902021 -254.373487) (xy 129.871448 -254.414173) (xy 129.834744 -254.449428)
			(xy 129.79286 -254.478338) (xy 129.746881 -254.500155) (xy 129.697997 -254.514315) (xy 129.647476 -254.520449)
			(xy 129.596624 -254.5184) (xy 129.54676 -254.50822) (xy 129.499174 -254.490173) (xy 129.4551 -254.464727)
			(xy 129.415678 -254.43254) (xy 129.38193 -254.394446) (xy 129.354729 -254.351432) (xy 129.334781 -254.304612)
			(xy 129.322602 -254.255198) (xy 129.318507 -254.20447) (xy 128.999996 -254.20447) (xy 128.999501 -254.229077)
			(xy 128.991606 -254.277654) (xy 128.976022 -254.324335) (xy 128.953151 -254.367912) (xy 128.923586 -254.407256)
			(xy 128.888093 -254.441348) (xy 128.84759 -254.469304) (xy 128.803128 -254.490402) (xy 128.755857 -254.504094)
			(xy 128.707002 -254.510026) (xy 128.657827 -254.508045) (xy 128.609608 -254.498201) (xy 128.563592 -254.480749)
			(xy 128.520971 -254.456142) (xy 128.48285 -254.425017) (xy 128.450215 -254.38818) (xy 128.423912 -254.346584)
			(xy 128.404621 -254.301308) (xy 128.392844 -254.253524) (xy 128.388884 -254.20447) (xy 128.070356 -254.20447)
			(xy 128.069844 -254.229916) (xy 128.06168 -254.28015) (xy 128.045564 -254.328424) (xy 128.021913 -254.373487)
			(xy 127.99134 -254.414173) (xy 127.954636 -254.449428) (xy 127.912752 -254.478338) (xy 127.866773 -254.500155)
			(xy 127.817889 -254.514315) (xy 127.767368 -254.520449) (xy 127.716516 -254.5184) (xy 127.666652 -254.50822)
			(xy 127.619066 -254.490173) (xy 127.574992 -254.464727) (xy 127.53557 -254.43254) (xy 127.501822 -254.394446)
			(xy 127.474621 -254.351432) (xy 127.454673 -254.304612) (xy 127.442494 -254.255198) (xy 127.438399 -254.20447)
			(xy 127.120142 -254.20447) (xy 127.119647 -254.229077) (xy 127.111752 -254.277654) (xy 127.096168 -254.324335)
			(xy 127.073297 -254.367912) (xy 127.043732 -254.407256) (xy 127.008239 -254.441348) (xy 126.967736 -254.469304)
			(xy 126.923274 -254.490402) (xy 126.876003 -254.504094) (xy 126.827148 -254.510026) (xy 126.777973 -254.508045)
			(xy 126.729754 -254.498201) (xy 126.683738 -254.480749) (xy 126.641117 -254.456142) (xy 126.602996 -254.425017)
			(xy 126.570361 -254.38818) (xy 126.544058 -254.346584) (xy 126.524767 -254.301308) (xy 126.51299 -254.253524)
			(xy 126.50903 -254.20447) (xy 125.240034 -254.20447) (xy 125.239539 -254.229077) (xy 125.231644 -254.277654)
			(xy 125.21606 -254.324335) (xy 125.193189 -254.367912) (xy 125.163624 -254.407256) (xy 125.128131 -254.441348)
			(xy 125.087628 -254.469304) (xy 125.043166 -254.490402) (xy 124.995895 -254.504094) (xy 124.94704 -254.510026)
			(xy 124.897865 -254.508045) (xy 124.849646 -254.498201) (xy 124.80363 -254.480749) (xy 124.761009 -254.456142)
			(xy 124.722888 -254.425017) (xy 124.690253 -254.38818) (xy 124.66395 -254.346584) (xy 124.644659 -254.301308)
			(xy 124.632882 -254.253524) (xy 124.628922 -254.20447) (xy 123.359926 -254.20447) (xy 123.359431 -254.229077)
			(xy 123.351536 -254.277654) (xy 123.335952 -254.324335) (xy 123.313081 -254.367912) (xy 123.283516 -254.407256)
			(xy 123.248023 -254.441348) (xy 123.20752 -254.469304) (xy 123.163058 -254.490402) (xy 123.115787 -254.504094)
			(xy 123.066932 -254.510026) (xy 123.017757 -254.508045) (xy 122.969538 -254.498201) (xy 122.923522 -254.480749)
			(xy 122.880901 -254.456142) (xy 122.84278 -254.425017) (xy 122.810145 -254.38818) (xy 122.783842 -254.346584)
			(xy 122.764551 -254.301308) (xy 122.752774 -254.253524) (xy 122.748814 -254.20447) (xy 121.480072 -254.20447)
			(xy 121.479577 -254.229077) (xy 121.471682 -254.277654) (xy 121.456098 -254.324335) (xy 121.433227 -254.367912)
			(xy 121.403662 -254.407256) (xy 121.368169 -254.441348) (xy 121.327666 -254.469304) (xy 121.283204 -254.490402)
			(xy 121.235933 -254.504094) (xy 121.187078 -254.510026) (xy 121.137903 -254.508045) (xy 121.089684 -254.498201)
			(xy 121.043668 -254.480749) (xy 121.001047 -254.456142) (xy 120.962926 -254.425017) (xy 120.930291 -254.38818)
			(xy 120.903988 -254.346584) (xy 120.884697 -254.301308) (xy 120.87292 -254.253524) (xy 120.86896 -254.20447)
			(xy 112.49858 -254.20447) (xy 112.522912 -254.229752) (xy 112.553204 -254.272818) (xy 112.576567 -254.320003)
			(xy 112.592453 -254.370202) (xy 112.60049 -254.422238) (xy 112.600994 -254.448564) (xy 112.60049 -254.47489)
			(xy 112.592453 -254.526926) (xy 112.576567 -254.577125) (xy 112.553204 -254.62431) (xy 112.522912 -254.667376)
			(xy 112.4864 -254.705314) (xy 112.444526 -254.737233) (xy 112.39827 -254.762386) (xy 112.348717 -254.780184)
			(xy 112.297027 -254.790208) (xy 112.244413 -254.792225) (xy 112.192108 -254.786187) (xy 112.141337 -254.772235)
			(xy 112.093292 -254.750696) (xy 112.049097 -254.722076) (xy 112.009789 -254.687045) (xy 111.976289 -254.646424)
			(xy 111.949383 -254.601165) (xy 111.9297 -254.55233) (xy 111.917703 -254.501062) (xy 111.913673 -254.448564)
			(xy 107.152186 -254.448564) (xy 107.416854 -254.713232) (xy 107.423559 -254.720473) (xy 107.431139 -254.738678)
			(xy 107.431586 -254.748538) (xy 107.431586 -255.014476) (xy 122.278914 -255.014476) (xy 122.282874 -254.965422)
			(xy 122.294651 -254.917638) (xy 122.313942 -254.872362) (xy 122.340245 -254.830766) (xy 122.37288 -254.793929)
			(xy 122.411001 -254.762804) (xy 122.453622 -254.738197) (xy 122.499638 -254.720745) (xy 122.547857 -254.710901)
			(xy 122.597032 -254.70892) (xy 122.645887 -254.714852) (xy 122.693158 -254.728544) (xy 122.73762 -254.749642)
			(xy 122.778123 -254.777598) (xy 122.813616 -254.81169) (xy 122.843181 -254.851034) (xy 122.866052 -254.894611)
			(xy 122.881636 -254.941292) (xy 122.889531 -254.989869) (xy 122.890026 -255.014476) (xy 124.159022 -255.014476)
			(xy 124.162982 -254.965422) (xy 124.174759 -254.917638) (xy 124.19405 -254.872362) (xy 124.220353 -254.830766)
			(xy 124.252988 -254.793929) (xy 124.291109 -254.762804) (xy 124.33373 -254.738197) (xy 124.379746 -254.720745)
			(xy 124.427965 -254.710901) (xy 124.47714 -254.70892) (xy 124.525995 -254.714852) (xy 124.573266 -254.728544)
			(xy 124.617728 -254.749642) (xy 124.658231 -254.777598) (xy 124.693724 -254.81169) (xy 124.723289 -254.851034)
			(xy 124.74616 -254.894611) (xy 124.761744 -254.941292) (xy 124.769639 -254.989869) (xy 124.770134 -255.014476)
			(xy 126.038876 -255.014476) (xy 126.042836 -254.965422) (xy 126.054613 -254.917638) (xy 126.073904 -254.872362)
			(xy 126.100207 -254.830766) (xy 126.132842 -254.793929) (xy 126.170963 -254.762804) (xy 126.213584 -254.738197)
			(xy 126.2596 -254.720745) (xy 126.307819 -254.710901) (xy 126.356994 -254.70892) (xy 126.405849 -254.714852)
			(xy 126.45312 -254.728544) (xy 126.497582 -254.749642) (xy 126.538085 -254.777598) (xy 126.573578 -254.81169)
			(xy 126.603143 -254.851034) (xy 126.626014 -254.894611) (xy 126.641598 -254.941292) (xy 126.649493 -254.989869)
			(xy 126.649988 -255.014476) (xy 127.908553 -255.014476) (xy 127.912648 -254.963748) (xy 127.924827 -254.914334)
			(xy 127.944775 -254.867514) (xy 127.971976 -254.8245) (xy 128.005724 -254.786406) (xy 128.045146 -254.754219)
			(xy 128.08922 -254.728773) (xy 128.136806 -254.710726) (xy 128.18667 -254.700546) (xy 128.237522 -254.698497)
			(xy 128.288043 -254.704631) (xy 128.336927 -254.718791) (xy 128.382906 -254.740608) (xy 128.42479 -254.769518)
			(xy 128.461494 -254.804773) (xy 128.492067 -254.845459) (xy 128.515718 -254.890522) (xy 128.531834 -254.938796)
			(xy 128.539998 -254.98903) (xy 128.54051 -255.014476) (xy 128.848607 -255.014476) (xy 128.852702 -254.963748)
			(xy 128.864881 -254.914334) (xy 128.884829 -254.867514) (xy 128.91203 -254.8245) (xy 128.945778 -254.786406)
			(xy 128.9852 -254.754219) (xy 129.029274 -254.728773) (xy 129.07686 -254.710726) (xy 129.126724 -254.700546)
			(xy 129.177576 -254.698497) (xy 129.228097 -254.704631) (xy 129.276981 -254.718791) (xy 129.32296 -254.740608)
			(xy 129.364844 -254.769518) (xy 129.401548 -254.804773) (xy 129.432121 -254.845459) (xy 129.455772 -254.890522)
			(xy 129.471888 -254.938796) (xy 129.480052 -254.98903) (xy 129.480564 -255.014476) (xy 129.798838 -255.014476)
			(xy 129.802798 -254.965422) (xy 129.814575 -254.917638) (xy 129.833866 -254.872362) (xy 129.860169 -254.830766)
			(xy 129.892804 -254.793929) (xy 129.930925 -254.762804) (xy 129.973546 -254.738197) (xy 130.019562 -254.720745)
			(xy 130.067781 -254.710901) (xy 130.116956 -254.70892) (xy 130.165811 -254.714852) (xy 130.213082 -254.728544)
			(xy 130.257544 -254.749642) (xy 130.298047 -254.777598) (xy 130.33354 -254.81169) (xy 130.363105 -254.851034)
			(xy 130.385976 -254.894611) (xy 130.40156 -254.941292) (xy 130.409455 -254.989869) (xy 130.40995 -255.014476)
			(xy 130.728461 -255.014476) (xy 130.732556 -254.963748) (xy 130.744735 -254.914334) (xy 130.764683 -254.867514)
			(xy 130.791884 -254.8245) (xy 130.825632 -254.786406) (xy 130.865054 -254.754219) (xy 130.909128 -254.728773)
			(xy 130.956714 -254.710726) (xy 131.006578 -254.700546) (xy 131.05743 -254.698497) (xy 131.107951 -254.704631)
			(xy 131.156835 -254.718791) (xy 131.202814 -254.740608) (xy 131.244698 -254.769518) (xy 131.281402 -254.804773)
			(xy 131.311975 -254.845459) (xy 131.335626 -254.890522) (xy 131.351742 -254.938796) (xy 131.359906 -254.98903)
			(xy 131.360418 -255.014476) (xy 131.678946 -255.014476) (xy 131.682906 -254.965422) (xy 131.694683 -254.917638)
			(xy 131.713974 -254.872362) (xy 131.740277 -254.830766) (xy 131.772912 -254.793929) (xy 131.811033 -254.762804)
			(xy 131.853654 -254.738197) (xy 131.89967 -254.720745) (xy 131.947889 -254.710901) (xy 131.997064 -254.70892)
			(xy 132.045919 -254.714852) (xy 132.09319 -254.728544) (xy 132.137652 -254.749642) (xy 132.178155 -254.777598)
			(xy 132.213648 -254.81169) (xy 132.243213 -254.851034) (xy 132.266084 -254.894611) (xy 132.281668 -254.941292)
			(xy 132.289563 -254.989869) (xy 132.290058 -255.014476) (xy 132.608569 -255.014476) (xy 132.612664 -254.963748)
			(xy 132.624843 -254.914334) (xy 132.644791 -254.867514) (xy 132.671992 -254.8245) (xy 132.70574 -254.786406)
			(xy 132.745162 -254.754219) (xy 132.789236 -254.728773) (xy 132.836822 -254.710726) (xy 132.886686 -254.700546)
			(xy 132.937538 -254.698497) (xy 132.988059 -254.704631) (xy 133.036943 -254.718791) (xy 133.082922 -254.740608)
			(xy 133.124806 -254.769518) (xy 133.16151 -254.804773) (xy 133.192083 -254.845459) (xy 133.215734 -254.890522)
			(xy 133.23185 -254.938796) (xy 133.240014 -254.98903) (xy 133.240526 -255.014476) (xy 133.559054 -255.014476)
			(xy 133.563014 -254.965422) (xy 133.574791 -254.917638) (xy 133.594082 -254.872362) (xy 133.620385 -254.830766)
			(xy 133.65302 -254.793929) (xy 133.691141 -254.762804) (xy 133.733762 -254.738197) (xy 133.779778 -254.720745)
			(xy 133.827997 -254.710901) (xy 133.877172 -254.70892) (xy 133.926027 -254.714852) (xy 133.973298 -254.728544)
			(xy 134.01776 -254.749642) (xy 134.058263 -254.777598) (xy 134.093756 -254.81169) (xy 134.123321 -254.851034)
			(xy 134.146192 -254.894611) (xy 134.161776 -254.941292) (xy 134.169671 -254.989869) (xy 134.170166 -255.014476)
			(xy 134.498854 -255.014476) (xy 134.502814 -254.965422) (xy 134.514591 -254.917638) (xy 134.533882 -254.872362)
			(xy 134.560185 -254.830766) (xy 134.59282 -254.793929) (xy 134.630941 -254.762804) (xy 134.673562 -254.738197)
			(xy 134.719578 -254.720745) (xy 134.767797 -254.710901) (xy 134.816972 -254.70892) (xy 134.865827 -254.714852)
			(xy 134.913098 -254.728544) (xy 134.95756 -254.749642) (xy 134.998063 -254.777598) (xy 135.033556 -254.81169)
			(xy 135.063121 -254.851034) (xy 135.085992 -254.894611) (xy 135.101576 -254.941292) (xy 135.109471 -254.989869)
			(xy 135.109966 -255.014476) (xy 135.438908 -255.014476) (xy 135.442868 -254.965422) (xy 135.454645 -254.917638)
			(xy 135.473936 -254.872362) (xy 135.500239 -254.830766) (xy 135.532874 -254.793929) (xy 135.570995 -254.762804)
			(xy 135.613616 -254.738197) (xy 135.659632 -254.720745) (xy 135.707851 -254.710901) (xy 135.757026 -254.70892)
			(xy 135.805881 -254.714852) (xy 135.853152 -254.728544) (xy 135.897614 -254.749642) (xy 135.938117 -254.777598)
			(xy 135.97361 -254.81169) (xy 136.003175 -254.851034) (xy 136.026046 -254.894611) (xy 136.04163 -254.941292)
			(xy 136.049525 -254.989869) (xy 136.05002 -255.014476) (xy 136.049525 -255.039083) (xy 136.04163 -255.08766)
			(xy 136.026046 -255.134341) (xy 136.003175 -255.177918) (xy 135.97361 -255.217262) (xy 135.938117 -255.251354)
			(xy 135.897614 -255.27931) (xy 135.853152 -255.300408) (xy 135.805881 -255.3141) (xy 135.757026 -255.320032)
			(xy 135.707851 -255.318051) (xy 135.659632 -255.308207) (xy 135.613616 -255.290755) (xy 135.570995 -255.266148)
			(xy 135.532874 -255.235023) (xy 135.500239 -255.198186) (xy 135.473936 -255.15659) (xy 135.454645 -255.111314)
			(xy 135.442868 -255.06353) (xy 135.438908 -255.014476) (xy 135.109966 -255.014476) (xy 135.109471 -255.039083)
			(xy 135.101576 -255.08766) (xy 135.085992 -255.134341) (xy 135.063121 -255.177918) (xy 135.033556 -255.217262)
			(xy 134.998063 -255.251354) (xy 134.95756 -255.27931) (xy 134.913098 -255.300408) (xy 134.865827 -255.3141)
			(xy 134.816972 -255.320032) (xy 134.767797 -255.318051) (xy 134.719578 -255.308207) (xy 134.673562 -255.290755)
			(xy 134.630941 -255.266148) (xy 134.59282 -255.235023) (xy 134.560185 -255.198186) (xy 134.533882 -255.15659)
			(xy 134.514591 -255.111314) (xy 134.502814 -255.06353) (xy 134.498854 -255.014476) (xy 134.170166 -255.014476)
			(xy 134.169671 -255.039083) (xy 134.161776 -255.08766) (xy 134.146192 -255.134341) (xy 134.123321 -255.177918)
			(xy 134.093756 -255.217262) (xy 134.058263 -255.251354) (xy 134.01776 -255.27931) (xy 133.973298 -255.300408)
			(xy 133.926027 -255.3141) (xy 133.877172 -255.320032) (xy 133.827997 -255.318051) (xy 133.779778 -255.308207)
			(xy 133.733762 -255.290755) (xy 133.691141 -255.266148) (xy 133.65302 -255.235023) (xy 133.620385 -255.198186)
			(xy 133.594082 -255.15659) (xy 133.574791 -255.111314) (xy 133.563014 -255.06353) (xy 133.559054 -255.014476)
			(xy 133.240526 -255.014476) (xy 133.240014 -255.039922) (xy 133.23185 -255.090156) (xy 133.215734 -255.13843)
			(xy 133.192083 -255.183493) (xy 133.16151 -255.224179) (xy 133.124806 -255.259434) (xy 133.082922 -255.288344)
			(xy 133.036943 -255.310161) (xy 132.988059 -255.324321) (xy 132.937538 -255.330455) (xy 132.886686 -255.328406)
			(xy 132.836822 -255.318226) (xy 132.789236 -255.300179) (xy 132.745162 -255.274733) (xy 132.70574 -255.242546)
			(xy 132.671992 -255.204452) (xy 132.644791 -255.161438) (xy 132.624843 -255.114618) (xy 132.612664 -255.065204)
			(xy 132.608569 -255.014476) (xy 132.290058 -255.014476) (xy 132.289563 -255.039083) (xy 132.281668 -255.08766)
			(xy 132.266084 -255.134341) (xy 132.243213 -255.177918) (xy 132.213648 -255.217262) (xy 132.178155 -255.251354)
			(xy 132.137652 -255.27931) (xy 132.09319 -255.300408) (xy 132.045919 -255.3141) (xy 131.997064 -255.320032)
			(xy 131.947889 -255.318051) (xy 131.89967 -255.308207) (xy 131.853654 -255.290755) (xy 131.811033 -255.266148)
			(xy 131.772912 -255.235023) (xy 131.740277 -255.198186) (xy 131.713974 -255.15659) (xy 131.694683 -255.111314)
			(xy 131.682906 -255.06353) (xy 131.678946 -255.014476) (xy 131.360418 -255.014476) (xy 131.359906 -255.039922)
			(xy 131.351742 -255.090156) (xy 131.335626 -255.13843) (xy 131.311975 -255.183493) (xy 131.281402 -255.224179)
			(xy 131.244698 -255.259434) (xy 131.202814 -255.288344) (xy 131.156835 -255.310161) (xy 131.107951 -255.324321)
			(xy 131.05743 -255.330455) (xy 131.006578 -255.328406) (xy 130.956714 -255.318226) (xy 130.909128 -255.300179)
			(xy 130.865054 -255.274733) (xy 130.825632 -255.242546) (xy 130.791884 -255.204452) (xy 130.764683 -255.161438)
			(xy 130.744735 -255.114618) (xy 130.732556 -255.065204) (xy 130.728461 -255.014476) (xy 130.40995 -255.014476)
			(xy 130.409455 -255.039083) (xy 130.40156 -255.08766) (xy 130.385976 -255.134341) (xy 130.363105 -255.177918)
			(xy 130.33354 -255.217262) (xy 130.298047 -255.251354) (xy 130.257544 -255.27931) (xy 130.213082 -255.300408)
			(xy 130.165811 -255.3141) (xy 130.116956 -255.320032) (xy 130.067781 -255.318051) (xy 130.019562 -255.308207)
			(xy 129.973546 -255.290755) (xy 129.930925 -255.266148) (xy 129.892804 -255.235023) (xy 129.860169 -255.198186)
			(xy 129.833866 -255.15659) (xy 129.814575 -255.111314) (xy 129.802798 -255.06353) (xy 129.798838 -255.014476)
			(xy 129.480564 -255.014476) (xy 129.480052 -255.039922) (xy 129.471888 -255.090156) (xy 129.455772 -255.13843)
			(xy 129.432121 -255.183493) (xy 129.401548 -255.224179) (xy 129.364844 -255.259434) (xy 129.32296 -255.288344)
			(xy 129.276981 -255.310161) (xy 129.228097 -255.324321) (xy 129.177576 -255.330455) (xy 129.126724 -255.328406)
			(xy 129.07686 -255.318226) (xy 129.029274 -255.300179) (xy 128.9852 -255.274733) (xy 128.945778 -255.242546)
			(xy 128.91203 -255.204452) (xy 128.884829 -255.161438) (xy 128.864881 -255.114618) (xy 128.852702 -255.065204)
			(xy 128.848607 -255.014476) (xy 128.54051 -255.014476) (xy 128.539998 -255.039922) (xy 128.531834 -255.090156)
			(xy 128.515718 -255.13843) (xy 128.492067 -255.183493) (xy 128.461494 -255.224179) (xy 128.42479 -255.259434)
			(xy 128.382906 -255.288344) (xy 128.336927 -255.310161) (xy 128.288043 -255.324321) (xy 128.237522 -255.330455)
			(xy 128.18667 -255.328406) (xy 128.136806 -255.318226) (xy 128.08922 -255.300179) (xy 128.045146 -255.274733)
			(xy 128.005724 -255.242546) (xy 127.971976 -255.204452) (xy 127.944775 -255.161438) (xy 127.924827 -255.114618)
			(xy 127.912648 -255.065204) (xy 127.908553 -255.014476) (xy 126.649988 -255.014476) (xy 126.649493 -255.039083)
			(xy 126.641598 -255.08766) (xy 126.626014 -255.134341) (xy 126.603143 -255.177918) (xy 126.573578 -255.217262)
			(xy 126.538085 -255.251354) (xy 126.497582 -255.27931) (xy 126.45312 -255.300408) (xy 126.405849 -255.3141)
			(xy 126.356994 -255.320032) (xy 126.307819 -255.318051) (xy 126.2596 -255.308207) (xy 126.213584 -255.290755)
			(xy 126.170963 -255.266148) (xy 126.132842 -255.235023) (xy 126.100207 -255.198186) (xy 126.073904 -255.15659)
			(xy 126.054613 -255.111314) (xy 126.042836 -255.06353) (xy 126.038876 -255.014476) (xy 124.770134 -255.014476)
			(xy 124.769639 -255.039083) (xy 124.761744 -255.08766) (xy 124.74616 -255.134341) (xy 124.723289 -255.177918)
			(xy 124.693724 -255.217262) (xy 124.658231 -255.251354) (xy 124.617728 -255.27931) (xy 124.573266 -255.300408)
			(xy 124.525995 -255.3141) (xy 124.47714 -255.320032) (xy 124.427965 -255.318051) (xy 124.379746 -255.308207)
			(xy 124.33373 -255.290755) (xy 124.291109 -255.266148) (xy 124.252988 -255.235023) (xy 124.220353 -255.198186)
			(xy 124.19405 -255.15659) (xy 124.174759 -255.111314) (xy 124.162982 -255.06353) (xy 124.159022 -255.014476)
			(xy 122.890026 -255.014476) (xy 122.889531 -255.039083) (xy 122.881636 -255.08766) (xy 122.866052 -255.134341)
			(xy 122.843181 -255.177918) (xy 122.813616 -255.217262) (xy 122.778123 -255.251354) (xy 122.73762 -255.27931)
			(xy 122.693158 -255.300408) (xy 122.645887 -255.3141) (xy 122.597032 -255.320032) (xy 122.547857 -255.318051)
			(xy 122.499638 -255.308207) (xy 122.453622 -255.290755) (xy 122.411001 -255.266148) (xy 122.37288 -255.235023)
			(xy 122.340245 -255.198186) (xy 122.313942 -255.15659) (xy 122.294651 -255.111314) (xy 122.282874 -255.06353)
			(xy 122.278914 -255.014476) (xy 107.431586 -255.014476) (xy 107.431586 -255.468882) (xy 107.432057 -255.478754)
			(xy 107.439515 -255.497038) (xy 107.446064 -255.504442) (xy 107.446318 -255.504696) (xy 107.471972 -255.53035)
			(xy 117.096797 -255.53035) (xy 117.100827 -255.477852) (xy 117.112824 -255.426584) (xy 117.132507 -255.377749)
			(xy 117.159413 -255.33249) (xy 117.192913 -255.291869) (xy 117.232221 -255.256838) (xy 117.276416 -255.228218)
			(xy 117.324461 -255.206679) (xy 117.375232 -255.192727) (xy 117.427537 -255.186689) (xy 117.480151 -255.188706)
			(xy 117.531841 -255.19873) (xy 117.581394 -255.216528) (xy 117.62765 -255.241681) (xy 117.669524 -255.2736)
			(xy 117.706036 -255.311538) (xy 117.736328 -255.354604) (xy 117.759691 -255.401789) (xy 117.775577 -255.451988)
			(xy 117.783614 -255.504024) (xy 117.784118 -255.53035) (xy 117.783614 -255.556676) (xy 117.775577 -255.608712)
			(xy 117.759691 -255.658911) (xy 117.736328 -255.706096) (xy 117.706036 -255.749162) (xy 117.669524 -255.7871)
			(xy 117.62765 -255.819019) (xy 117.617604 -255.824482) (xy 120.86896 -255.824482) (xy 120.87292 -255.775428)
			(xy 120.884697 -255.727644) (xy 120.903988 -255.682368) (xy 120.930291 -255.640772) (xy 120.962926 -255.603935)
			(xy 121.001047 -255.57281) (xy 121.043668 -255.548203) (xy 121.089684 -255.530751) (xy 121.137903 -255.520907)
			(xy 121.187078 -255.518926) (xy 121.235933 -255.524858) (xy 121.283204 -255.53855) (xy 121.327666 -255.559648)
			(xy 121.368169 -255.587604) (xy 121.403662 -255.621696) (xy 121.433227 -255.66104) (xy 121.456098 -255.704617)
			(xy 121.471682 -255.751298) (xy 121.479577 -255.799875) (xy 121.480072 -255.824482) (xy 122.748814 -255.824482)
			(xy 122.752774 -255.775428) (xy 122.764551 -255.727644) (xy 122.783842 -255.682368) (xy 122.810145 -255.640772)
			(xy 122.84278 -255.603935) (xy 122.880901 -255.57281) (xy 122.923522 -255.548203) (xy 122.969538 -255.530751)
			(xy 123.017757 -255.520907) (xy 123.066932 -255.518926) (xy 123.115787 -255.524858) (xy 123.163058 -255.53855)
			(xy 123.20752 -255.559648) (xy 123.248023 -255.587604) (xy 123.283516 -255.621696) (xy 123.313081 -255.66104)
			(xy 123.335952 -255.704617) (xy 123.351536 -255.751298) (xy 123.359431 -255.799875) (xy 123.359926 -255.824482)
			(xy 124.628922 -255.824482) (xy 124.632882 -255.775428) (xy 124.644659 -255.727644) (xy 124.66395 -255.682368)
			(xy 124.690253 -255.640772) (xy 124.722888 -255.603935) (xy 124.761009 -255.57281) (xy 124.80363 -255.548203)
			(xy 124.849646 -255.530751) (xy 124.897865 -255.520907) (xy 124.94704 -255.518926) (xy 124.995895 -255.524858)
			(xy 125.043166 -255.53855) (xy 125.087628 -255.559648) (xy 125.128131 -255.587604) (xy 125.163624 -255.621696)
			(xy 125.193189 -255.66104) (xy 125.21606 -255.704617) (xy 125.231644 -255.751298) (xy 125.239539 -255.799875)
			(xy 125.240034 -255.824482) (xy 126.50903 -255.824482) (xy 126.51299 -255.775428) (xy 126.524767 -255.727644)
			(xy 126.544058 -255.682368) (xy 126.570361 -255.640772) (xy 126.602996 -255.603935) (xy 126.641117 -255.57281)
			(xy 126.683738 -255.548203) (xy 126.729754 -255.530751) (xy 126.777973 -255.520907) (xy 126.827148 -255.518926)
			(xy 126.876003 -255.524858) (xy 126.923274 -255.53855) (xy 126.967736 -255.559648) (xy 127.008239 -255.587604)
			(xy 127.043732 -255.621696) (xy 127.073297 -255.66104) (xy 127.096168 -255.704617) (xy 127.111752 -255.751298)
			(xy 127.119647 -255.799875) (xy 127.120142 -255.824482) (xy 127.438399 -255.824482) (xy 127.442494 -255.773754)
			(xy 127.454673 -255.72434) (xy 127.474621 -255.67752) (xy 127.501822 -255.634506) (xy 127.53557 -255.596412)
			(xy 127.574992 -255.564225) (xy 127.619066 -255.538779) (xy 127.666652 -255.520732) (xy 127.716516 -255.510552)
			(xy 127.767368 -255.508503) (xy 127.817889 -255.514637) (xy 127.866773 -255.528797) (xy 127.912752 -255.550614)
			(xy 127.954636 -255.579524) (xy 127.99134 -255.614779) (xy 128.021913 -255.655465) (xy 128.045564 -255.700528)
			(xy 128.06168 -255.748802) (xy 128.069844 -255.799036) (xy 128.070356 -255.824482) (xy 128.388884 -255.824482)
			(xy 128.392844 -255.775428) (xy 128.404621 -255.727644) (xy 128.423912 -255.682368) (xy 128.450215 -255.640772)
			(xy 128.48285 -255.603935) (xy 128.520971 -255.57281) (xy 128.563592 -255.548203) (xy 128.609608 -255.530751)
			(xy 128.657827 -255.520907) (xy 128.707002 -255.518926) (xy 128.755857 -255.524858) (xy 128.803128 -255.53855)
			(xy 128.84759 -255.559648) (xy 128.888093 -255.587604) (xy 128.923586 -255.621696) (xy 128.953151 -255.66104)
			(xy 128.976022 -255.704617) (xy 128.991606 -255.751298) (xy 128.999501 -255.799875) (xy 128.999996 -255.824482)
			(xy 129.318507 -255.824482) (xy 129.322602 -255.773754) (xy 129.334781 -255.72434) (xy 129.354729 -255.67752)
			(xy 129.38193 -255.634506) (xy 129.415678 -255.596412) (xy 129.4551 -255.564225) (xy 129.499174 -255.538779)
			(xy 129.54676 -255.520732) (xy 129.596624 -255.510552) (xy 129.647476 -255.508503) (xy 129.697997 -255.514637)
			(xy 129.746881 -255.528797) (xy 129.79286 -255.550614) (xy 129.834744 -255.579524) (xy 129.871448 -255.614779)
			(xy 129.902021 -255.655465) (xy 129.925672 -255.700528) (xy 129.941788 -255.748802) (xy 129.949952 -255.799036)
			(xy 129.950464 -255.824482) (xy 130.268992 -255.824482) (xy 130.272952 -255.775428) (xy 130.284729 -255.727644)
			(xy 130.30402 -255.682368) (xy 130.330323 -255.640772) (xy 130.362958 -255.603935) (xy 130.401079 -255.57281)
			(xy 130.4437 -255.548203) (xy 130.489716 -255.530751) (xy 130.537935 -255.520907) (xy 130.58711 -255.518926)
			(xy 130.635965 -255.524858) (xy 130.683236 -255.53855) (xy 130.727698 -255.559648) (xy 130.768201 -255.587604)
			(xy 130.803694 -255.621696) (xy 130.833259 -255.66104) (xy 130.85613 -255.704617) (xy 130.871714 -255.751298)
			(xy 130.879609 -255.799875) (xy 130.880104 -255.824482) (xy 131.198615 -255.824482) (xy 131.20271 -255.773754)
			(xy 131.214889 -255.72434) (xy 131.234837 -255.67752) (xy 131.262038 -255.634506) (xy 131.295786 -255.596412)
			(xy 131.335208 -255.564225) (xy 131.379282 -255.538779) (xy 131.426868 -255.520732) (xy 131.476732 -255.510552)
			(xy 131.527584 -255.508503) (xy 131.578105 -255.514637) (xy 131.626989 -255.528797) (xy 131.672968 -255.550614)
			(xy 131.714852 -255.579524) (xy 131.751556 -255.614779) (xy 131.782129 -255.655465) (xy 131.80578 -255.700528)
			(xy 131.821896 -255.748802) (xy 131.83006 -255.799036) (xy 131.830572 -255.824482) (xy 132.138415 -255.824482)
			(xy 132.14251 -255.773754) (xy 132.154689 -255.72434) (xy 132.174637 -255.67752) (xy 132.201838 -255.634506)
			(xy 132.235586 -255.596412) (xy 132.275008 -255.564225) (xy 132.319082 -255.538779) (xy 132.366668 -255.520732)
			(xy 132.416532 -255.510552) (xy 132.467384 -255.508503) (xy 132.517905 -255.514637) (xy 132.566789 -255.528797)
			(xy 132.612768 -255.550614) (xy 132.654652 -255.579524) (xy 132.691356 -255.614779) (xy 132.721929 -255.655465)
			(xy 132.74558 -255.700528) (xy 132.761696 -255.748802) (xy 132.76986 -255.799036) (xy 132.770372 -255.824482)
			(xy 133.0889 -255.824482) (xy 133.09286 -255.775428) (xy 133.104637 -255.727644) (xy 133.123928 -255.682368)
			(xy 133.150231 -255.640772) (xy 133.182866 -255.603935) (xy 133.220987 -255.57281) (xy 133.263608 -255.548203)
			(xy 133.309624 -255.530751) (xy 133.357843 -255.520907) (xy 133.407018 -255.518926) (xy 133.455873 -255.524858)
			(xy 133.503144 -255.53855) (xy 133.547606 -255.559648) (xy 133.588109 -255.587604) (xy 133.623602 -255.621696)
			(xy 133.653167 -255.66104) (xy 133.676038 -255.704617) (xy 133.691622 -255.751298) (xy 133.699517 -255.799875)
			(xy 133.700012 -255.824482) (xy 134.028954 -255.824482) (xy 134.032914 -255.775428) (xy 134.044691 -255.727644)
			(xy 134.063982 -255.682368) (xy 134.090285 -255.640772) (xy 134.12292 -255.603935) (xy 134.161041 -255.57281)
			(xy 134.203662 -255.548203) (xy 134.249678 -255.530751) (xy 134.297897 -255.520907) (xy 134.347072 -255.518926)
			(xy 134.395927 -255.524858) (xy 134.443198 -255.53855) (xy 134.48766 -255.559648) (xy 134.528163 -255.587604)
			(xy 134.563656 -255.621696) (xy 134.593221 -255.66104) (xy 134.616092 -255.704617) (xy 134.631676 -255.751298)
			(xy 134.639571 -255.799875) (xy 134.640066 -255.824482) (xy 134.969008 -255.824482) (xy 134.972968 -255.775428)
			(xy 134.984745 -255.727644) (xy 135.004036 -255.682368) (xy 135.030339 -255.640772) (xy 135.062974 -255.603935)
			(xy 135.101095 -255.57281) (xy 135.143716 -255.548203) (xy 135.189732 -255.530751) (xy 135.237951 -255.520907)
			(xy 135.287126 -255.518926) (xy 135.335981 -255.524858) (xy 135.383252 -255.53855) (xy 135.427714 -255.559648)
			(xy 135.468217 -255.587604) (xy 135.50371 -255.621696) (xy 135.533275 -255.66104) (xy 135.556146 -255.704617)
			(xy 135.57173 -255.751298) (xy 135.579625 -255.799875) (xy 135.58012 -255.824482) (xy 135.909062 -255.824482)
			(xy 135.913022 -255.775428) (xy 135.924799 -255.727644) (xy 135.94409 -255.682368) (xy 135.970393 -255.640772)
			(xy 136.003028 -255.603935) (xy 136.041149 -255.57281) (xy 136.08377 -255.548203) (xy 136.129786 -255.530751)
			(xy 136.178005 -255.520907) (xy 136.22718 -255.518926) (xy 136.276035 -255.524858) (xy 136.323306 -255.53855)
			(xy 136.367768 -255.559648) (xy 136.408271 -255.587604) (xy 136.443764 -255.621696) (xy 136.473329 -255.66104)
			(xy 136.4962 -255.704617) (xy 136.511784 -255.751298) (xy 136.519679 -255.799875) (xy 136.520174 -255.824482)
			(xy 136.519679 -255.849089) (xy 136.511784 -255.897666) (xy 136.4962 -255.944347) (xy 136.473329 -255.987924)
			(xy 136.443764 -256.027268) (xy 136.408271 -256.06136) (xy 136.367768 -256.089316) (xy 136.323306 -256.110414)
			(xy 136.276035 -256.124106) (xy 136.22718 -256.130038) (xy 136.178005 -256.128057) (xy 136.129786 -256.118213)
			(xy 136.08377 -256.100761) (xy 136.041149 -256.076154) (xy 136.003028 -256.045029) (xy 135.970393 -256.008192)
			(xy 135.94409 -255.966596) (xy 135.924799 -255.92132) (xy 135.913022 -255.873536) (xy 135.909062 -255.824482)
			(xy 135.58012 -255.824482) (xy 135.579625 -255.849089) (xy 135.57173 -255.897666) (xy 135.556146 -255.944347)
			(xy 135.533275 -255.987924) (xy 135.50371 -256.027268) (xy 135.468217 -256.06136) (xy 135.427714 -256.089316)
			(xy 135.383252 -256.110414) (xy 135.335981 -256.124106) (xy 135.287126 -256.130038) (xy 135.237951 -256.128057)
			(xy 135.189732 -256.118213) (xy 135.143716 -256.100761) (xy 135.101095 -256.076154) (xy 135.062974 -256.045029)
			(xy 135.030339 -256.008192) (xy 135.004036 -255.966596) (xy 134.984745 -255.92132) (xy 134.972968 -255.873536)
			(xy 134.969008 -255.824482) (xy 134.640066 -255.824482) (xy 134.639571 -255.849089) (xy 134.631676 -255.897666)
			(xy 134.616092 -255.944347) (xy 134.593221 -255.987924) (xy 134.563656 -256.027268) (xy 134.528163 -256.06136)
			(xy 134.48766 -256.089316) (xy 134.443198 -256.110414) (xy 134.395927 -256.124106) (xy 134.347072 -256.130038)
			(xy 134.297897 -256.128057) (xy 134.249678 -256.118213) (xy 134.203662 -256.100761) (xy 134.161041 -256.076154)
			(xy 134.12292 -256.045029) (xy 134.090285 -256.008192) (xy 134.063982 -255.966596) (xy 134.044691 -255.92132)
			(xy 134.032914 -255.873536) (xy 134.028954 -255.824482) (xy 133.700012 -255.824482) (xy 133.699517 -255.849089)
			(xy 133.691622 -255.897666) (xy 133.676038 -255.944347) (xy 133.653167 -255.987924) (xy 133.623602 -256.027268)
			(xy 133.588109 -256.06136) (xy 133.547606 -256.089316) (xy 133.503144 -256.110414) (xy 133.455873 -256.124106)
			(xy 133.407018 -256.130038) (xy 133.357843 -256.128057) (xy 133.309624 -256.118213) (xy 133.263608 -256.100761)
			(xy 133.220987 -256.076154) (xy 133.182866 -256.045029) (xy 133.150231 -256.008192) (xy 133.123928 -255.966596)
			(xy 133.104637 -255.92132) (xy 133.09286 -255.873536) (xy 133.0889 -255.824482) (xy 132.770372 -255.824482)
			(xy 132.76986 -255.849928) (xy 132.761696 -255.900162) (xy 132.74558 -255.948436) (xy 132.721929 -255.993499)
			(xy 132.691356 -256.034185) (xy 132.654652 -256.06944) (xy 132.612768 -256.09835) (xy 132.566789 -256.120167)
			(xy 132.517905 -256.134327) (xy 132.467384 -256.140461) (xy 132.416532 -256.138412) (xy 132.366668 -256.128232)
			(xy 132.319082 -256.110185) (xy 132.275008 -256.084739) (xy 132.235586 -256.052552) (xy 132.201838 -256.014458)
			(xy 132.174637 -255.971444) (xy 132.154689 -255.924624) (xy 132.14251 -255.87521) (xy 132.138415 -255.824482)
			(xy 131.830572 -255.824482) (xy 131.83006 -255.849928) (xy 131.821896 -255.900162) (xy 131.80578 -255.948436)
			(xy 131.782129 -255.993499) (xy 131.751556 -256.034185) (xy 131.714852 -256.06944) (xy 131.672968 -256.09835)
			(xy 131.626989 -256.120167) (xy 131.578105 -256.134327) (xy 131.527584 -256.140461) (xy 131.476732 -256.138412)
			(xy 131.426868 -256.128232) (xy 131.379282 -256.110185) (xy 131.335208 -256.084739) (xy 131.295786 -256.052552)
			(xy 131.262038 -256.014458) (xy 131.234837 -255.971444) (xy 131.214889 -255.924624) (xy 131.20271 -255.87521)
			(xy 131.198615 -255.824482) (xy 130.880104 -255.824482) (xy 130.879609 -255.849089) (xy 130.871714 -255.897666)
			(xy 130.85613 -255.944347) (xy 130.833259 -255.987924) (xy 130.803694 -256.027268) (xy 130.768201 -256.06136)
			(xy 130.727698 -256.089316) (xy 130.683236 -256.110414) (xy 130.635965 -256.124106) (xy 130.58711 -256.130038)
			(xy 130.537935 -256.128057) (xy 130.489716 -256.118213) (xy 130.4437 -256.100761) (xy 130.401079 -256.076154)
			(xy 130.362958 -256.045029) (xy 130.330323 -256.008192) (xy 130.30402 -255.966596) (xy 130.284729 -255.92132)
			(xy 130.272952 -255.873536) (xy 130.268992 -255.824482) (xy 129.950464 -255.824482) (xy 129.949952 -255.849928)
			(xy 129.941788 -255.900162) (xy 129.925672 -255.948436) (xy 129.902021 -255.993499) (xy 129.871448 -256.034185)
			(xy 129.834744 -256.06944) (xy 129.79286 -256.09835) (xy 129.746881 -256.120167) (xy 129.697997 -256.134327)
			(xy 129.647476 -256.140461) (xy 129.596624 -256.138412) (xy 129.54676 -256.128232) (xy 129.499174 -256.110185)
			(xy 129.4551 -256.084739) (xy 129.415678 -256.052552) (xy 129.38193 -256.014458) (xy 129.354729 -255.971444)
			(xy 129.334781 -255.924624) (xy 129.322602 -255.87521) (xy 129.318507 -255.824482) (xy 128.999996 -255.824482)
			(xy 128.999501 -255.849089) (xy 128.991606 -255.897666) (xy 128.976022 -255.944347) (xy 128.953151 -255.987924)
			(xy 128.923586 -256.027268) (xy 128.888093 -256.06136) (xy 128.84759 -256.089316) (xy 128.803128 -256.110414)
			(xy 128.755857 -256.124106) (xy 128.707002 -256.130038) (xy 128.657827 -256.128057) (xy 128.609608 -256.118213)
			(xy 128.563592 -256.100761) (xy 128.520971 -256.076154) (xy 128.48285 -256.045029) (xy 128.450215 -256.008192)
			(xy 128.423912 -255.966596) (xy 128.404621 -255.92132) (xy 128.392844 -255.873536) (xy 128.388884 -255.824482)
			(xy 128.070356 -255.824482) (xy 128.069844 -255.849928) (xy 128.06168 -255.900162) (xy 128.045564 -255.948436)
			(xy 128.021913 -255.993499) (xy 127.99134 -256.034185) (xy 127.954636 -256.06944) (xy 127.912752 -256.09835)
			(xy 127.866773 -256.120167) (xy 127.817889 -256.134327) (xy 127.767368 -256.140461) (xy 127.716516 -256.138412)
			(xy 127.666652 -256.128232) (xy 127.619066 -256.110185) (xy 127.574992 -256.084739) (xy 127.53557 -256.052552)
			(xy 127.501822 -256.014458) (xy 127.474621 -255.971444) (xy 127.454673 -255.924624) (xy 127.442494 -255.87521)
			(xy 127.438399 -255.824482) (xy 127.120142 -255.824482) (xy 127.119647 -255.849089) (xy 127.111752 -255.897666)
			(xy 127.096168 -255.944347) (xy 127.073297 -255.987924) (xy 127.043732 -256.027268) (xy 127.008239 -256.06136)
			(xy 126.967736 -256.089316) (xy 126.923274 -256.110414) (xy 126.876003 -256.124106) (xy 126.827148 -256.130038)
			(xy 126.777973 -256.128057) (xy 126.729754 -256.118213) (xy 126.683738 -256.100761) (xy 126.641117 -256.076154)
			(xy 126.602996 -256.045029) (xy 126.570361 -256.008192) (xy 126.544058 -255.966596) (xy 126.524767 -255.92132)
			(xy 126.51299 -255.873536) (xy 126.50903 -255.824482) (xy 125.240034 -255.824482) (xy 125.239539 -255.849089)
			(xy 125.231644 -255.897666) (xy 125.21606 -255.944347) (xy 125.193189 -255.987924) (xy 125.163624 -256.027268)
			(xy 125.128131 -256.06136) (xy 125.087628 -256.089316) (xy 125.043166 -256.110414) (xy 124.995895 -256.124106)
			(xy 124.94704 -256.130038) (xy 124.897865 -256.128057) (xy 124.849646 -256.118213) (xy 124.80363 -256.100761)
			(xy 124.761009 -256.076154) (xy 124.722888 -256.045029) (xy 124.690253 -256.008192) (xy 124.66395 -255.966596)
			(xy 124.644659 -255.92132) (xy 124.632882 -255.873536) (xy 124.628922 -255.824482) (xy 123.359926 -255.824482)
			(xy 123.359431 -255.849089) (xy 123.351536 -255.897666) (xy 123.335952 -255.944347) (xy 123.313081 -255.987924)
			(xy 123.283516 -256.027268) (xy 123.248023 -256.06136) (xy 123.20752 -256.089316) (xy 123.163058 -256.110414)
			(xy 123.115787 -256.124106) (xy 123.066932 -256.130038) (xy 123.017757 -256.128057) (xy 122.969538 -256.118213)
			(xy 122.923522 -256.100761) (xy 122.880901 -256.076154) (xy 122.84278 -256.045029) (xy 122.810145 -256.008192)
			(xy 122.783842 -255.966596) (xy 122.764551 -255.92132) (xy 122.752774 -255.873536) (xy 122.748814 -255.824482)
			(xy 121.480072 -255.824482) (xy 121.479577 -255.849089) (xy 121.471682 -255.897666) (xy 121.456098 -255.944347)
			(xy 121.433227 -255.987924) (xy 121.403662 -256.027268) (xy 121.368169 -256.06136) (xy 121.327666 -256.089316)
			(xy 121.283204 -256.110414) (xy 121.235933 -256.124106) (xy 121.187078 -256.130038) (xy 121.137903 -256.128057)
			(xy 121.089684 -256.118213) (xy 121.043668 -256.100761) (xy 121.001047 -256.076154) (xy 120.962926 -256.045029)
			(xy 120.930291 -256.008192) (xy 120.903988 -255.966596) (xy 120.884697 -255.92132) (xy 120.87292 -255.873536)
			(xy 120.86896 -255.824482) (xy 117.617604 -255.824482) (xy 117.581394 -255.844172) (xy 117.531841 -255.86197)
			(xy 117.480151 -255.871994) (xy 117.427537 -255.874011) (xy 117.375232 -255.867973) (xy 117.324461 -255.854021)
			(xy 117.276416 -255.832482) (xy 117.232221 -255.803862) (xy 117.192913 -255.768831) (xy 117.159413 -255.72821)
			(xy 117.132507 -255.682951) (xy 117.112824 -255.634116) (xy 117.100827 -255.582848) (xy 117.096797 -255.53035)
			(xy 107.471972 -255.53035) (xy 107.5944 -255.652778) (xy 107.594908 -255.653286) (xy 107.602288 -255.659872)
			(xy 107.620587 -255.667333) (xy 107.630468 -255.667764) (xy 111.703612 -255.667764) (xy 111.713455 -255.668289)
			(xy 111.731634 -255.675857) (xy 111.738918 -255.682496) (xy 112.146842 -256.09042) (xy 112.153496 -256.096504)
			(xy 112.169882 -256.104002) (xy 112.187846 -256.105429) (xy 112.196626 -256.103374) (xy 112.211358 -256.099056)
			(xy 112.2172 -256.0955) (xy 112.23764 -256.083341) (xy 112.281159 -256.064158) (xy 112.326909 -256.051166)
			(xy 112.374014 -256.044614) (xy 112.397794 -256.044192) (xy 112.404398 -256.044192) (xy 112.431041 -256.045208)
			(xy 112.483548 -256.054459) (xy 112.533994 -256.071715) (xy 112.581167 -256.096561) (xy 112.623932 -256.128399)
			(xy 112.661262 -256.166465) (xy 112.692261 -256.209843) (xy 112.716181 -256.257492) (xy 112.73245 -256.308265)
			(xy 112.740675 -256.360942) (xy 112.741202 -256.3876) (xy 113.004095 -256.3876) (xy 113.008125 -256.335102)
			(xy 113.020122 -256.283834) (xy 113.039805 -256.234999) (xy 113.066711 -256.18974) (xy 113.100211 -256.149119)
			(xy 113.139519 -256.114088) (xy 113.183714 -256.085468) (xy 113.231759 -256.063929) (xy 113.28253 -256.049977)
			(xy 113.334835 -256.043939) (xy 113.387449 -256.045956) (xy 113.439139 -256.05598) (xy 113.488692 -256.073778)
			(xy 113.534948 -256.098931) (xy 113.576822 -256.13085) (xy 113.613334 -256.168788) (xy 113.643626 -256.211854)
			(xy 113.666989 -256.259039) (xy 113.682875 -256.309238) (xy 113.690912 -256.361274) (xy 113.691416 -256.3876)
			(xy 113.954055 -256.3876) (xy 113.958085 -256.335102) (xy 113.970082 -256.283834) (xy 113.989765 -256.234999)
			(xy 114.016671 -256.18974) (xy 114.050171 -256.149119) (xy 114.089479 -256.114088) (xy 114.133674 -256.085468)
			(xy 114.181719 -256.063929) (xy 114.23249 -256.049977) (xy 114.284795 -256.043939) (xy 114.337409 -256.045956)
			(xy 114.389099 -256.05598) (xy 114.438652 -256.073778) (xy 114.484908 -256.098931) (xy 114.526782 -256.13085)
			(xy 114.563294 -256.168788) (xy 114.593586 -256.211854) (xy 114.616949 -256.259039) (xy 114.632835 -256.309238)
			(xy 114.640872 -256.361274) (xy 114.641376 -256.3876) (xy 114.904015 -256.3876) (xy 114.908045 -256.335102)
			(xy 114.920042 -256.283834) (xy 114.939725 -256.234999) (xy 114.966631 -256.18974) (xy 115.000131 -256.149119)
			(xy 115.039439 -256.114088) (xy 115.083634 -256.085468) (xy 115.131679 -256.063929) (xy 115.18245 -256.049977)
			(xy 115.234755 -256.043939) (xy 115.287369 -256.045956) (xy 115.339059 -256.05598) (xy 115.388612 -256.073778)
			(xy 115.434868 -256.098931) (xy 115.476742 -256.13085) (xy 115.513254 -256.168788) (xy 115.543546 -256.211854)
			(xy 115.566909 -256.259039) (xy 115.582795 -256.309238) (xy 115.590832 -256.361274) (xy 115.591336 -256.3876)
			(xy 115.853975 -256.3876) (xy 115.858005 -256.335102) (xy 115.870002 -256.283834) (xy 115.889685 -256.234999)
			(xy 115.916591 -256.18974) (xy 115.950091 -256.149119) (xy 115.989399 -256.114088) (xy 116.033594 -256.085468)
			(xy 116.081639 -256.063929) (xy 116.13241 -256.049977) (xy 116.184715 -256.043939) (xy 116.237329 -256.045956)
			(xy 116.289019 -256.05598) (xy 116.338572 -256.073778) (xy 116.384828 -256.098931) (xy 116.426702 -256.13085)
			(xy 116.463214 -256.168788) (xy 116.493506 -256.211854) (xy 116.516869 -256.259039) (xy 116.532755 -256.309238)
			(xy 116.540792 -256.361274) (xy 116.541296 -256.3876) (xy 116.540792 -256.413926) (xy 116.532755 -256.465962)
			(xy 116.528214 -256.48031) (xy 117.096797 -256.48031) (xy 117.100827 -256.427812) (xy 117.112824 -256.376544)
			(xy 117.132507 -256.327709) (xy 117.159413 -256.28245) (xy 117.192913 -256.241829) (xy 117.232221 -256.206798)
			(xy 117.276416 -256.178178) (xy 117.324461 -256.156639) (xy 117.375232 -256.142687) (xy 117.427537 -256.136649)
			(xy 117.480151 -256.138666) (xy 117.531841 -256.14869) (xy 117.581394 -256.166488) (xy 117.62765 -256.191641)
			(xy 117.669524 -256.22356) (xy 117.706036 -256.261498) (xy 117.736328 -256.304564) (xy 117.759691 -256.351749)
			(xy 117.775577 -256.401948) (xy 117.783614 -256.453984) (xy 117.784118 -256.48031) (xy 117.783614 -256.506636)
			(xy 117.775577 -256.558672) (xy 117.759691 -256.608871) (xy 117.747007 -256.634488) (xy 122.278914 -256.634488)
			(xy 122.282874 -256.585434) (xy 122.294651 -256.53765) (xy 122.313942 -256.492374) (xy 122.340245 -256.450778)
			(xy 122.37288 -256.413941) (xy 122.411001 -256.382816) (xy 122.453622 -256.358209) (xy 122.499638 -256.340757)
			(xy 122.547857 -256.330913) (xy 122.597032 -256.328932) (xy 122.645887 -256.334864) (xy 122.693158 -256.348556)
			(xy 122.73762 -256.369654) (xy 122.778123 -256.39761) (xy 122.813616 -256.431702) (xy 122.843181 -256.471046)
			(xy 122.866052 -256.514623) (xy 122.881636 -256.561304) (xy 122.889531 -256.609881) (xy 122.890026 -256.634488)
			(xy 124.159022 -256.634488) (xy 124.162982 -256.585434) (xy 124.174759 -256.53765) (xy 124.19405 -256.492374)
			(xy 124.220353 -256.450778) (xy 124.252988 -256.413941) (xy 124.291109 -256.382816) (xy 124.33373 -256.358209)
			(xy 124.379746 -256.340757) (xy 124.427965 -256.330913) (xy 124.47714 -256.328932) (xy 124.525995 -256.334864)
			(xy 124.573266 -256.348556) (xy 124.617728 -256.369654) (xy 124.658231 -256.39761) (xy 124.693724 -256.431702)
			(xy 124.723289 -256.471046) (xy 124.74616 -256.514623) (xy 124.761744 -256.561304) (xy 124.769639 -256.609881)
			(xy 124.770134 -256.634488) (xy 126.038876 -256.634488) (xy 126.042836 -256.585434) (xy 126.054613 -256.53765)
			(xy 126.073904 -256.492374) (xy 126.100207 -256.450778) (xy 126.132842 -256.413941) (xy 126.170963 -256.382816)
			(xy 126.213584 -256.358209) (xy 126.2596 -256.340757) (xy 126.307819 -256.330913) (xy 126.356994 -256.328932)
			(xy 126.405849 -256.334864) (xy 126.45312 -256.348556) (xy 126.497582 -256.369654) (xy 126.538085 -256.39761)
			(xy 126.573578 -256.431702) (xy 126.603143 -256.471046) (xy 126.626014 -256.514623) (xy 126.641598 -256.561304)
			(xy 126.649493 -256.609881) (xy 126.649988 -256.634488) (xy 127.918984 -256.634488) (xy 127.922944 -256.585434)
			(xy 127.934721 -256.53765) (xy 127.954012 -256.492374) (xy 127.980315 -256.450778) (xy 128.01295 -256.413941)
			(xy 128.051071 -256.382816) (xy 128.093692 -256.358209) (xy 128.139708 -256.340757) (xy 128.187927 -256.330913)
			(xy 128.237102 -256.328932) (xy 128.285957 -256.334864) (xy 128.333228 -256.348556) (xy 128.37769 -256.369654)
			(xy 128.418193 -256.39761) (xy 128.453686 -256.431702) (xy 128.483251 -256.471046) (xy 128.506122 -256.514623)
			(xy 128.521706 -256.561304) (xy 128.529601 -256.609881) (xy 128.530096 -256.634488) (xy 128.848607 -256.634488)
			(xy 128.852702 -256.58376) (xy 128.864881 -256.534346) (xy 128.884829 -256.487526) (xy 128.91203 -256.444512)
			(xy 128.945778 -256.406418) (xy 128.9852 -256.374231) (xy 129.029274 -256.348785) (xy 129.07686 -256.330738)
			(xy 129.126724 -256.320558) (xy 129.177576 -256.318509) (xy 129.228097 -256.324643) (xy 129.276981 -256.338803)
			(xy 129.32296 -256.36062) (xy 129.364844 -256.38953) (xy 129.401548 -256.424785) (xy 129.432121 -256.465471)
			(xy 129.455772 -256.510534) (xy 129.471888 -256.558808) (xy 129.480052 -256.609042) (xy 129.480564 -256.634488)
			(xy 130.738892 -256.634488) (xy 130.742852 -256.585434) (xy 130.754629 -256.53765) (xy 130.77392 -256.492374)
			(xy 130.800223 -256.450778) (xy 130.832858 -256.413941) (xy 130.870979 -256.382816) (xy 130.9136 -256.358209)
			(xy 130.959616 -256.340757) (xy 131.007835 -256.330913) (xy 131.05701 -256.328932) (xy 131.105865 -256.334864)
			(xy 131.153136 -256.348556) (xy 131.197598 -256.369654) (xy 131.238101 -256.39761) (xy 131.273594 -256.431702)
			(xy 131.303159 -256.471046) (xy 131.32603 -256.514623) (xy 131.341614 -256.561304) (xy 131.349509 -256.609881)
			(xy 131.350004 -256.634488) (xy 131.678946 -256.634488) (xy 131.682906 -256.585434) (xy 131.694683 -256.53765)
			(xy 131.713974 -256.492374) (xy 131.740277 -256.450778) (xy 131.772912 -256.413941) (xy 131.811033 -256.382816)
			(xy 131.853654 -256.358209) (xy 131.89967 -256.340757) (xy 131.947889 -256.330913) (xy 131.997064 -256.328932)
			(xy 132.045919 -256.334864) (xy 132.09319 -256.348556) (xy 132.137652 -256.369654) (xy 132.178155 -256.39761)
			(xy 132.213648 -256.431702) (xy 132.243213 -256.471046) (xy 132.266084 -256.514623) (xy 132.281668 -256.561304)
			(xy 132.289563 -256.609881) (xy 132.290058 -256.634488) (xy 132.608569 -256.634488) (xy 132.612664 -256.58376)
			(xy 132.624843 -256.534346) (xy 132.644791 -256.487526) (xy 132.671992 -256.444512) (xy 132.70574 -256.406418)
			(xy 132.745162 -256.374231) (xy 132.789236 -256.348785) (xy 132.836822 -256.330738) (xy 132.886686 -256.320558)
			(xy 132.937538 -256.318509) (xy 132.988059 -256.324643) (xy 133.036943 -256.338803) (xy 133.082922 -256.36062)
			(xy 133.124806 -256.38953) (xy 133.16151 -256.424785) (xy 133.192083 -256.465471) (xy 133.215734 -256.510534)
			(xy 133.23185 -256.558808) (xy 133.240014 -256.609042) (xy 133.240526 -256.634488) (xy 133.559054 -256.634488)
			(xy 133.563014 -256.585434) (xy 133.574791 -256.53765) (xy 133.594082 -256.492374) (xy 133.620385 -256.450778)
			(xy 133.65302 -256.413941) (xy 133.691141 -256.382816) (xy 133.733762 -256.358209) (xy 133.779778 -256.340757)
			(xy 133.827997 -256.330913) (xy 133.877172 -256.328932) (xy 133.926027 -256.334864) (xy 133.973298 -256.348556)
			(xy 134.01776 -256.369654) (xy 134.058263 -256.39761) (xy 134.093756 -256.431702) (xy 134.123321 -256.471046)
			(xy 134.146192 -256.514623) (xy 134.161776 -256.561304) (xy 134.169671 -256.609881) (xy 134.170166 -256.634488)
			(xy 134.498854 -256.634488) (xy 134.502814 -256.585434) (xy 134.514591 -256.53765) (xy 134.533882 -256.492374)
			(xy 134.560185 -256.450778) (xy 134.59282 -256.413941) (xy 134.630941 -256.382816) (xy 134.673562 -256.358209)
			(xy 134.719578 -256.340757) (xy 134.767797 -256.330913) (xy 134.816972 -256.328932) (xy 134.865827 -256.334864)
			(xy 134.913098 -256.348556) (xy 134.95756 -256.369654) (xy 134.998063 -256.39761) (xy 135.033556 -256.431702)
			(xy 135.063121 -256.471046) (xy 135.085992 -256.514623) (xy 135.101576 -256.561304) (xy 135.109471 -256.609881)
			(xy 135.109966 -256.634488) (xy 135.438908 -256.634488) (xy 135.442868 -256.585434) (xy 135.454645 -256.53765)
			(xy 135.473936 -256.492374) (xy 135.500239 -256.450778) (xy 135.532874 -256.413941) (xy 135.570995 -256.382816)
			(xy 135.613616 -256.358209) (xy 135.659632 -256.340757) (xy 135.707851 -256.330913) (xy 135.757026 -256.328932)
			(xy 135.805881 -256.334864) (xy 135.853152 -256.348556) (xy 135.897614 -256.369654) (xy 135.938117 -256.39761)
			(xy 135.97361 -256.431702) (xy 136.003175 -256.471046) (xy 136.026046 -256.514623) (xy 136.04163 -256.561304)
			(xy 136.049525 -256.609881) (xy 136.05002 -256.634488) (xy 136.049525 -256.659095) (xy 136.04163 -256.707672)
			(xy 136.026046 -256.754353) (xy 136.003175 -256.79793) (xy 135.97361 -256.837274) (xy 135.938117 -256.871366)
			(xy 135.897614 -256.899322) (xy 135.853152 -256.92042) (xy 135.805881 -256.934112) (xy 135.757026 -256.940044)
			(xy 135.707851 -256.938063) (xy 135.659632 -256.928219) (xy 135.613616 -256.910767) (xy 135.570995 -256.88616)
			(xy 135.532874 -256.855035) (xy 135.500239 -256.818198) (xy 135.473936 -256.776602) (xy 135.454645 -256.731326)
			(xy 135.442868 -256.683542) (xy 135.438908 -256.634488) (xy 135.109966 -256.634488) (xy 135.109471 -256.659095)
			(xy 135.101576 -256.707672) (xy 135.085992 -256.754353) (xy 135.063121 -256.79793) (xy 135.033556 -256.837274)
			(xy 134.998063 -256.871366) (xy 134.95756 -256.899322) (xy 134.913098 -256.92042) (xy 134.865827 -256.934112)
			(xy 134.816972 -256.940044) (xy 134.767797 -256.938063) (xy 134.719578 -256.928219) (xy 134.673562 -256.910767)
			(xy 134.630941 -256.88616) (xy 134.59282 -256.855035) (xy 134.560185 -256.818198) (xy 134.533882 -256.776602)
			(xy 134.514591 -256.731326) (xy 134.502814 -256.683542) (xy 134.498854 -256.634488) (xy 134.170166 -256.634488)
			(xy 134.169671 -256.659095) (xy 134.161776 -256.707672) (xy 134.146192 -256.754353) (xy 134.123321 -256.79793)
			(xy 134.093756 -256.837274) (xy 134.058263 -256.871366) (xy 134.01776 -256.899322) (xy 133.973298 -256.92042)
			(xy 133.926027 -256.934112) (xy 133.877172 -256.940044) (xy 133.827997 -256.938063) (xy 133.779778 -256.928219)
			(xy 133.733762 -256.910767) (xy 133.691141 -256.88616) (xy 133.65302 -256.855035) (xy 133.620385 -256.818198)
			(xy 133.594082 -256.776602) (xy 133.574791 -256.731326) (xy 133.563014 -256.683542) (xy 133.559054 -256.634488)
			(xy 133.240526 -256.634488) (xy 133.240014 -256.659934) (xy 133.23185 -256.710168) (xy 133.215734 -256.758442)
			(xy 133.192083 -256.803505) (xy 133.16151 -256.844191) (xy 133.124806 -256.879446) (xy 133.082922 -256.908356)
			(xy 133.036943 -256.930173) (xy 132.988059 -256.944333) (xy 132.937538 -256.950467) (xy 132.886686 -256.948418)
			(xy 132.836822 -256.938238) (xy 132.789236 -256.920191) (xy 132.745162 -256.894745) (xy 132.70574 -256.862558)
			(xy 132.671992 -256.824464) (xy 132.644791 -256.78145) (xy 132.624843 -256.73463) (xy 132.612664 -256.685216)
			(xy 132.608569 -256.634488) (xy 132.290058 -256.634488) (xy 132.289563 -256.659095) (xy 132.281668 -256.707672)
			(xy 132.266084 -256.754353) (xy 132.243213 -256.79793) (xy 132.213648 -256.837274) (xy 132.178155 -256.871366)
			(xy 132.137652 -256.899322) (xy 132.09319 -256.92042) (xy 132.045919 -256.934112) (xy 131.997064 -256.940044)
			(xy 131.947889 -256.938063) (xy 131.89967 -256.928219) (xy 131.853654 -256.910767) (xy 131.811033 -256.88616)
			(xy 131.772912 -256.855035) (xy 131.740277 -256.818198) (xy 131.713974 -256.776602) (xy 131.694683 -256.731326)
			(xy 131.682906 -256.683542) (xy 131.678946 -256.634488) (xy 131.350004 -256.634488) (xy 131.349509 -256.659095)
			(xy 131.341614 -256.707672) (xy 131.32603 -256.754353) (xy 131.303159 -256.79793) (xy 131.273594 -256.837274)
			(xy 131.238101 -256.871366) (xy 131.197598 -256.899322) (xy 131.153136 -256.92042) (xy 131.105865 -256.934112)
			(xy 131.05701 -256.940044) (xy 131.007835 -256.938063) (xy 130.959616 -256.928219) (xy 130.9136 -256.910767)
			(xy 130.870979 -256.88616) (xy 130.832858 -256.855035) (xy 130.800223 -256.818198) (xy 130.77392 -256.776602)
			(xy 130.754629 -256.731326) (xy 130.742852 -256.683542) (xy 130.738892 -256.634488) (xy 129.480564 -256.634488)
			(xy 129.480052 -256.659934) (xy 129.471888 -256.710168) (xy 129.455772 -256.758442) (xy 129.432121 -256.803505)
			(xy 129.401548 -256.844191) (xy 129.364844 -256.879446) (xy 129.32296 -256.908356) (xy 129.276981 -256.930173)
			(xy 129.228097 -256.944333) (xy 129.177576 -256.950467) (xy 129.126724 -256.948418) (xy 129.07686 -256.938238)
			(xy 129.029274 -256.920191) (xy 128.9852 -256.894745) (xy 128.945778 -256.862558) (xy 128.91203 -256.824464)
			(xy 128.884829 -256.78145) (xy 128.864881 -256.73463) (xy 128.852702 -256.685216) (xy 128.848607 -256.634488)
			(xy 128.530096 -256.634488) (xy 128.529601 -256.659095) (xy 128.521706 -256.707672) (xy 128.506122 -256.754353)
			(xy 128.483251 -256.79793) (xy 128.453686 -256.837274) (xy 128.418193 -256.871366) (xy 128.37769 -256.899322)
			(xy 128.333228 -256.92042) (xy 128.285957 -256.934112) (xy 128.237102 -256.940044) (xy 128.187927 -256.938063)
			(xy 128.139708 -256.928219) (xy 128.093692 -256.910767) (xy 128.051071 -256.88616) (xy 128.01295 -256.855035)
			(xy 127.980315 -256.818198) (xy 127.954012 -256.776602) (xy 127.934721 -256.731326) (xy 127.922944 -256.683542)
			(xy 127.918984 -256.634488) (xy 126.649988 -256.634488) (xy 126.649493 -256.659095) (xy 126.641598 -256.707672)
			(xy 126.626014 -256.754353) (xy 126.603143 -256.79793) (xy 126.573578 -256.837274) (xy 126.538085 -256.871366)
			(xy 126.497582 -256.899322) (xy 126.45312 -256.92042) (xy 126.405849 -256.934112) (xy 126.356994 -256.940044)
			(xy 126.307819 -256.938063) (xy 126.2596 -256.928219) (xy 126.213584 -256.910767) (xy 126.170963 -256.88616)
			(xy 126.132842 -256.855035) (xy 126.100207 -256.818198) (xy 126.073904 -256.776602) (xy 126.054613 -256.731326)
			(xy 126.042836 -256.683542) (xy 126.038876 -256.634488) (xy 124.770134 -256.634488) (xy 124.769639 -256.659095)
			(xy 124.761744 -256.707672) (xy 124.74616 -256.754353) (xy 124.723289 -256.79793) (xy 124.693724 -256.837274)
			(xy 124.658231 -256.871366) (xy 124.617728 -256.899322) (xy 124.573266 -256.92042) (xy 124.525995 -256.934112)
			(xy 124.47714 -256.940044) (xy 124.427965 -256.938063) (xy 124.379746 -256.928219) (xy 124.33373 -256.910767)
			(xy 124.291109 -256.88616) (xy 124.252988 -256.855035) (xy 124.220353 -256.818198) (xy 124.19405 -256.776602)
			(xy 124.174759 -256.731326) (xy 124.162982 -256.683542) (xy 124.159022 -256.634488) (xy 122.890026 -256.634488)
			(xy 122.889531 -256.659095) (xy 122.881636 -256.707672) (xy 122.866052 -256.754353) (xy 122.843181 -256.79793)
			(xy 122.813616 -256.837274) (xy 122.778123 -256.871366) (xy 122.73762 -256.899322) (xy 122.693158 -256.92042)
			(xy 122.645887 -256.934112) (xy 122.597032 -256.940044) (xy 122.547857 -256.938063) (xy 122.499638 -256.928219)
			(xy 122.453622 -256.910767) (xy 122.411001 -256.88616) (xy 122.37288 -256.855035) (xy 122.340245 -256.818198)
			(xy 122.313942 -256.776602) (xy 122.294651 -256.731326) (xy 122.282874 -256.683542) (xy 122.278914 -256.634488)
			(xy 117.747007 -256.634488) (xy 117.736328 -256.656056) (xy 117.706036 -256.699122) (xy 117.669524 -256.73706)
			(xy 117.62765 -256.768979) (xy 117.581394 -256.794132) (xy 117.531841 -256.81193) (xy 117.480151 -256.821954)
			(xy 117.427537 -256.823971) (xy 117.375232 -256.817933) (xy 117.324461 -256.803981) (xy 117.276416 -256.782442)
			(xy 117.232221 -256.753822) (xy 117.192913 -256.718791) (xy 117.159413 -256.67817) (xy 117.132507 -256.632911)
			(xy 117.112824 -256.584076) (xy 117.100827 -256.532808) (xy 117.096797 -256.48031) (xy 116.528214 -256.48031)
			(xy 116.516869 -256.516161) (xy 116.493506 -256.563346) (xy 116.463214 -256.606412) (xy 116.426702 -256.64435)
			(xy 116.384828 -256.676269) (xy 116.338572 -256.701422) (xy 116.289019 -256.71922) (xy 116.237329 -256.729244)
			(xy 116.184715 -256.731261) (xy 116.13241 -256.725223) (xy 116.081639 -256.711271) (xy 116.033594 -256.689732)
			(xy 115.989399 -256.661112) (xy 115.950091 -256.626081) (xy 115.916591 -256.58546) (xy 115.889685 -256.540201)
			(xy 115.870002 -256.491366) (xy 115.858005 -256.440098) (xy 115.853975 -256.3876) (xy 115.591336 -256.3876)
			(xy 115.590832 -256.413926) (xy 115.582795 -256.465962) (xy 115.566909 -256.516161) (xy 115.543546 -256.563346)
			(xy 115.513254 -256.606412) (xy 115.476742 -256.64435) (xy 115.434868 -256.676269) (xy 115.388612 -256.701422)
			(xy 115.339059 -256.71922) (xy 115.287369 -256.729244) (xy 115.234755 -256.731261) (xy 115.18245 -256.725223)
			(xy 115.131679 -256.711271) (xy 115.083634 -256.689732) (xy 115.039439 -256.661112) (xy 115.000131 -256.626081)
			(xy 114.966631 -256.58546) (xy 114.939725 -256.540201) (xy 114.920042 -256.491366) (xy 114.908045 -256.440098)
			(xy 114.904015 -256.3876) (xy 114.641376 -256.3876) (xy 114.640872 -256.413926) (xy 114.632835 -256.465962)
			(xy 114.616949 -256.516161) (xy 114.593586 -256.563346) (xy 114.563294 -256.606412) (xy 114.526782 -256.64435)
			(xy 114.484908 -256.676269) (xy 114.438652 -256.701422) (xy 114.389099 -256.71922) (xy 114.337409 -256.729244)
			(xy 114.284795 -256.731261) (xy 114.23249 -256.725223) (xy 114.181719 -256.711271) (xy 114.133674 -256.689732)
			(xy 114.089479 -256.661112) (xy 114.050171 -256.626081) (xy 114.016671 -256.58546) (xy 113.989765 -256.540201)
			(xy 113.970082 -256.491366) (xy 113.958085 -256.440098) (xy 113.954055 -256.3876) (xy 113.691416 -256.3876)
			(xy 113.690912 -256.413926) (xy 113.682875 -256.465962) (xy 113.666989 -256.516161) (xy 113.643626 -256.563346)
			(xy 113.613334 -256.606412) (xy 113.576822 -256.64435) (xy 113.534948 -256.676269) (xy 113.488692 -256.701422)
			(xy 113.439139 -256.71922) (xy 113.387449 -256.729244) (xy 113.334835 -256.731261) (xy 113.28253 -256.725223)
			(xy 113.231759 -256.711271) (xy 113.183714 -256.689732) (xy 113.139519 -256.661112) (xy 113.100211 -256.626081)
			(xy 113.066711 -256.58546) (xy 113.039805 -256.540201) (xy 113.020122 -256.491366) (xy 113.008125 -256.440098)
			(xy 113.004095 -256.3876) (xy 112.741202 -256.3876) (xy 112.74069 -256.414366) (xy 112.732386 -256.467251)
			(xy 112.715977 -256.518207) (xy 112.691863 -256.566001) (xy 112.660626 -256.609476) (xy 112.623022 -256.647578)
			(xy 112.579964 -256.679385) (xy 112.532492 -256.704128) (xy 112.481756 -256.721206) (xy 112.455452 -256.726182)
			(xy 112.447578 -256.727452) (xy 112.425226 -256.739136) (xy 112.417098 -256.743454) (xy 112.39754 -256.765044)
			(xy 112.391636 -256.77229) (xy 112.38499 -256.789742) (xy 112.384586 -256.79908) (xy 112.384586 -257.74523)
			(xy 113.238283 -257.74523) (xy 113.242313 -257.692732) (xy 113.25431 -257.641464) (xy 113.273993 -257.592629)
			(xy 113.300899 -257.54737) (xy 113.334399 -257.506749) (xy 113.373707 -257.471718) (xy 113.417902 -257.443098)
			(xy 113.465947 -257.421559) (xy 113.516718 -257.407607) (xy 113.569023 -257.401569) (xy 113.621637 -257.403586)
			(xy 113.673327 -257.41361) (xy 113.72288 -257.431408) (xy 113.769136 -257.456561) (xy 113.81101 -257.48848)
			(xy 113.847522 -257.526418) (xy 113.877814 -257.569484) (xy 113.901177 -257.616669) (xy 113.917063 -257.666868)
			(xy 113.9251 -257.718904) (xy 113.925604 -257.74523) (xy 115.838227 -257.74523) (xy 115.842257 -257.692732)
			(xy 115.854254 -257.641464) (xy 115.873937 -257.592629) (xy 115.900843 -257.54737) (xy 115.934343 -257.506749)
			(xy 115.973651 -257.471718) (xy 116.017846 -257.443098) (xy 116.065891 -257.421559) (xy 116.116662 -257.407607)
			(xy 116.168967 -257.401569) (xy 116.221581 -257.403586) (xy 116.273271 -257.41361) (xy 116.319656 -257.43027)
			(xy 117.096797 -257.43027) (xy 117.100827 -257.377772) (xy 117.112824 -257.326504) (xy 117.132507 -257.277669)
			(xy 117.159413 -257.23241) (xy 117.192913 -257.191789) (xy 117.232221 -257.156758) (xy 117.276416 -257.128138)
			(xy 117.324461 -257.106599) (xy 117.375232 -257.092647) (xy 117.427537 -257.086609) (xy 117.480151 -257.088626)
			(xy 117.531841 -257.09865) (xy 117.581394 -257.116448) (xy 117.62765 -257.141601) (xy 117.669524 -257.17352)
			(xy 117.706036 -257.211458) (xy 117.736328 -257.254524) (xy 117.759691 -257.301709) (xy 117.775577 -257.351908)
			(xy 117.783614 -257.403944) (xy 117.784118 -257.43027) (xy 117.783614 -257.456596) (xy 117.775577 -257.508632)
			(xy 117.759691 -257.558831) (xy 117.736328 -257.606016) (xy 117.706036 -257.649082) (xy 117.669524 -257.68702)
			(xy 117.62765 -257.718939) (xy 117.581394 -257.744092) (xy 117.531841 -257.76189) (xy 117.480151 -257.771914)
			(xy 117.427537 -257.773931) (xy 117.375232 -257.767893) (xy 117.324461 -257.753941) (xy 117.276416 -257.732402)
			(xy 117.232221 -257.703782) (xy 117.192913 -257.668751) (xy 117.159413 -257.62813) (xy 117.132507 -257.582871)
			(xy 117.112824 -257.534036) (xy 117.100827 -257.482768) (xy 117.096797 -257.43027) (xy 116.319656 -257.43027)
			(xy 116.322824 -257.431408) (xy 116.36908 -257.456561) (xy 116.410954 -257.48848) (xy 116.447466 -257.526418)
			(xy 116.477758 -257.569484) (xy 116.501121 -257.616669) (xy 116.517007 -257.666868) (xy 116.525044 -257.718904)
			(xy 116.525548 -257.74523) (xy 116.525044 -257.771556) (xy 116.517007 -257.823592) (xy 116.501121 -257.873791)
			(xy 116.477758 -257.920976) (xy 116.471132 -257.930396) (xy 120.865649 -257.930396) (xy 120.869679 -257.877898)
			(xy 120.881676 -257.82663) (xy 120.901359 -257.777795) (xy 120.928265 -257.732536) (xy 120.961765 -257.691915)
			(xy 121.001073 -257.656884) (xy 121.045268 -257.628264) (xy 121.093313 -257.606725) (xy 121.144084 -257.592773)
			(xy 121.196389 -257.586735) (xy 121.249003 -257.588752) (xy 121.300693 -257.598776) (xy 121.350246 -257.616574)
			(xy 121.396502 -257.641727) (xy 121.438376 -257.673646) (xy 121.474888 -257.711584) (xy 121.50518 -257.75465)
			(xy 121.528543 -257.801835) (xy 121.544429 -257.852034) (xy 121.552466 -257.90407) (xy 121.55297 -257.930396)
			(xy 122.791223 -257.930396) (xy 122.795253 -257.877898) (xy 122.80725 -257.82663) (xy 122.826933 -257.777795)
			(xy 122.853839 -257.732536) (xy 122.887339 -257.691915) (xy 122.926647 -257.656884) (xy 122.970842 -257.628264)
			(xy 123.018887 -257.606725) (xy 123.069658 -257.592773) (xy 123.121963 -257.586735) (xy 123.174577 -257.588752)
			(xy 123.226267 -257.598776) (xy 123.27582 -257.616574) (xy 123.322076 -257.641727) (xy 123.36395 -257.673646)
			(xy 123.400462 -257.711584) (xy 123.430754 -257.75465) (xy 123.454117 -257.801835) (xy 123.470003 -257.852034)
			(xy 123.47804 -257.90407) (xy 123.478544 -257.930396) (xy 124.696223 -257.930396) (xy 124.700253 -257.877898)
			(xy 124.71225 -257.82663) (xy 124.731933 -257.777795) (xy 124.758839 -257.732536) (xy 124.792339 -257.691915)
			(xy 124.831647 -257.656884) (xy 124.875842 -257.628264) (xy 124.923887 -257.606725) (xy 124.974658 -257.592773)
			(xy 125.026963 -257.586735) (xy 125.079577 -257.588752) (xy 125.131267 -257.598776) (xy 125.18082 -257.616574)
			(xy 125.227076 -257.641727) (xy 125.26895 -257.673646) (xy 125.305462 -257.711584) (xy 125.335754 -257.75465)
			(xy 125.359117 -257.801835) (xy 125.375003 -257.852034) (xy 125.38304 -257.90407) (xy 125.383544 -257.930396)
			(xy 125.38304 -257.956722) (xy 125.375003 -258.008758) (xy 125.359117 -258.058957) (xy 125.335754 -258.106142)
			(xy 125.305462 -258.149208) (xy 125.26895 -258.187146) (xy 125.227076 -258.219065) (xy 125.18082 -258.244218)
			(xy 125.131267 -258.262016) (xy 125.079577 -258.27204) (xy 125.026963 -258.274057) (xy 124.974658 -258.268019)
			(xy 124.923887 -258.254067) (xy 124.875842 -258.232528) (xy 124.831647 -258.203908) (xy 124.792339 -258.168877)
			(xy 124.758839 -258.128256) (xy 124.731933 -258.082997) (xy 124.71225 -258.034162) (xy 124.700253 -257.982894)
			(xy 124.696223 -257.930396) (xy 123.478544 -257.930396) (xy 123.47804 -257.956722) (xy 123.470003 -258.008758)
			(xy 123.454117 -258.058957) (xy 123.430754 -258.106142) (xy 123.400462 -258.149208) (xy 123.36395 -258.187146)
			(xy 123.322076 -258.219065) (xy 123.27582 -258.244218) (xy 123.226267 -258.262016) (xy 123.174577 -258.27204)
			(xy 123.121963 -258.274057) (xy 123.069658 -258.268019) (xy 123.018887 -258.254067) (xy 122.970842 -258.232528)
			(xy 122.926647 -258.203908) (xy 122.887339 -258.168877) (xy 122.853839 -258.128256) (xy 122.826933 -258.082997)
			(xy 122.80725 -258.034162) (xy 122.795253 -257.982894) (xy 122.791223 -257.930396) (xy 121.55297 -257.930396)
			(xy 121.552466 -257.956722) (xy 121.544429 -258.008758) (xy 121.528543 -258.058957) (xy 121.50518 -258.106142)
			(xy 121.474888 -258.149208) (xy 121.438376 -258.187146) (xy 121.396502 -258.219065) (xy 121.350246 -258.244218)
			(xy 121.300693 -258.262016) (xy 121.249003 -258.27204) (xy 121.196389 -258.274057) (xy 121.144084 -258.268019)
			(xy 121.093313 -258.254067) (xy 121.045268 -258.232528) (xy 121.001073 -258.203908) (xy 120.961765 -258.168877)
			(xy 120.928265 -258.128256) (xy 120.901359 -258.082997) (xy 120.881676 -258.034162) (xy 120.869679 -257.982894)
			(xy 120.865649 -257.930396) (xy 116.471132 -257.930396) (xy 116.447466 -257.964042) (xy 116.410954 -258.00198)
			(xy 116.36908 -258.033899) (xy 116.322824 -258.059052) (xy 116.273271 -258.07685) (xy 116.221581 -258.086874)
			(xy 116.168967 -258.088891) (xy 116.116662 -258.082853) (xy 116.065891 -258.068901) (xy 116.017846 -258.047362)
			(xy 115.973651 -258.018742) (xy 115.934343 -257.983711) (xy 115.900843 -257.94309) (xy 115.873937 -257.897831)
			(xy 115.854254 -257.848996) (xy 115.842257 -257.797728) (xy 115.838227 -257.74523) (xy 113.925604 -257.74523)
			(xy 113.9251 -257.771556) (xy 113.917063 -257.823592) (xy 113.901177 -257.873791) (xy 113.877814 -257.920976)
			(xy 113.847522 -257.964042) (xy 113.81101 -258.00198) (xy 113.769136 -258.033899) (xy 113.72288 -258.059052)
			(xy 113.673327 -258.07685) (xy 113.621637 -258.086874) (xy 113.569023 -258.088891) (xy 113.516718 -258.082853)
			(xy 113.465947 -258.068901) (xy 113.417902 -258.047362) (xy 113.373707 -258.018742) (xy 113.334399 -257.983711)
			(xy 113.300899 -257.94309) (xy 113.273993 -257.897831) (xy 113.25431 -257.848996) (xy 113.242313 -257.797728)
			(xy 113.238283 -257.74523) (xy 112.384586 -257.74523) (xy 112.384586 -258.38023) (xy 117.096797 -258.38023)
			(xy 117.100827 -258.327732) (xy 117.112824 -258.276464) (xy 117.132507 -258.227629) (xy 117.159413 -258.18237)
			(xy 117.192913 -258.141749) (xy 117.232221 -258.106718) (xy 117.276416 -258.078098) (xy 117.324461 -258.056559)
			(xy 117.375232 -258.042607) (xy 117.427537 -258.036569) (xy 117.480151 -258.038586) (xy 117.531841 -258.04861)
			(xy 117.581394 -258.066408) (xy 117.62765 -258.091561) (xy 117.669524 -258.12348) (xy 117.706036 -258.161418)
			(xy 117.736328 -258.204484) (xy 117.759691 -258.251669) (xy 117.775577 -258.301868) (xy 117.783614 -258.353904)
			(xy 117.784118 -258.38023) (xy 117.783614 -258.406556) (xy 117.775577 -258.458592) (xy 117.759691 -258.508791)
			(xy 117.736328 -258.555976) (xy 117.706036 -258.599042) (xy 117.669524 -258.63698) (xy 117.62765 -258.668899)
			(xy 117.581394 -258.694052) (xy 117.531841 -258.71185) (xy 117.480151 -258.721874) (xy 117.427537 -258.723891)
			(xy 117.375232 -258.717853) (xy 117.324461 -258.703901) (xy 117.276416 -258.682362) (xy 117.232221 -258.653742)
			(xy 117.192913 -258.618711) (xy 117.159413 -258.57809) (xy 117.132507 -258.532831) (xy 117.112824 -258.483996)
			(xy 117.100827 -258.432728) (xy 117.096797 -258.38023) (xy 112.384586 -258.38023) (xy 112.384586 -258.847082)
			(xy 112.385057 -258.856954) (xy 112.392515 -258.875238) (xy 112.399064 -258.882642) (xy 112.399318 -258.882896)
			(xy 112.649 -259.132578) (xy 112.649508 -259.133086) (xy 112.656888 -259.139672) (xy 112.675187 -259.147133)
			(xy 112.685068 -259.147564) (xy 113.21669 -259.147564) (xy 113.225889 -259.147164) (xy 113.243109 -259.140678)
			(xy 113.256958 -259.128564) (xy 113.261648 -259.12064) (xy 113.302542 -259.042916) (xy 113.306547 -259.034552)
			(xy 113.308862 -259.016169) (xy 113.304451 -258.998174) (xy 113.299494 -258.990338) (xy 113.285148 -258.968716)
			(xy 113.262443 -258.922059) (xy 113.24703 -258.872513) (xy 113.23926 -258.82121) (xy 113.238788 -258.795266)
			(xy 113.238788 -258.788154) (xy 113.239836 -258.761534) (xy 113.249142 -258.70908) (xy 113.266436 -258.658693)
			(xy 113.291305 -258.611581) (xy 113.323151 -258.568875) (xy 113.36121 -258.531599) (xy 113.404569 -258.500649)
			(xy 113.452188 -258.476765) (xy 113.502924 -258.460523) (xy 113.55556 -258.45231) (xy 113.582196 -258.451858)
			(xy 113.608838 -258.452367) (xy 113.66148 -258.460609) (xy 113.712219 -258.476879) (xy 113.759837 -258.500789)
			(xy 113.803193 -258.531763) (xy 113.841246 -258.56906) (xy 113.873085 -258.611786) (xy 113.897945 -258.658914)
			(xy 113.91523 -258.709316) (xy 113.924527 -258.761783) (xy 113.925604 -258.788408) (xy 113.925604 -258.79298)
			(xy 113.925604 -258.795266) (xy 113.925128 -258.821209) (xy 113.917328 -258.872504) (xy 113.901916 -258.922047)
			(xy 113.87924 -258.968715) (xy 113.864898 -258.990338) (xy 113.860007 -258.998202) (xy 113.855635 -259.016183)
			(xy 113.85788 -259.034551) (xy 113.86185 -259.042916) (xy 113.902744 -259.12064) (xy 113.907406 -259.128589)
			(xy 113.921242 -259.14074) (xy 113.938493 -259.14718) (xy 113.947702 -259.147564) (xy 115.816634 -259.147564)
			(xy 115.825829 -259.147157) (xy 115.843037 -259.140662) (xy 115.856874 -259.128544) (xy 115.861592 -259.12064)
			(xy 115.902486 -259.042916) (xy 115.906488 -259.034552) (xy 115.908802 -259.016169) (xy 115.904394 -258.998174)
			(xy 115.899438 -258.990338) (xy 115.88509 -258.968717) (xy 115.862383 -258.92206) (xy 115.846967 -258.872514)
			(xy 115.839196 -258.821211) (xy 115.838732 -258.795266) (xy 115.838732 -258.788154) (xy 115.839781 -258.761535)
			(xy 115.849086 -258.709084) (xy 115.866381 -258.6587) (xy 115.891251 -258.611591) (xy 115.923097 -258.568889)
			(xy 115.961157 -258.531617) (xy 116.004517 -258.500671) (xy 116.052135 -258.476794) (xy 116.102871 -258.460557)
			(xy 116.155505 -258.452351) (xy 116.18214 -258.451858) (xy 116.208784 -258.452363) (xy 116.261433 -258.460598)
			(xy 116.312179 -258.476863) (xy 116.359805 -258.50077) (xy 116.403169 -258.531743) (xy 116.441229 -258.569041)
			(xy 116.473074 -258.611768) (xy 116.497939 -258.658901) (xy 116.515228 -258.709307) (xy 116.524526 -258.761779)
			(xy 116.525548 -258.788408) (xy 116.525548 -258.79298) (xy 116.525548 -258.795266) (xy 116.525072 -258.821209)
			(xy 116.523687 -258.830318) (xy 120.865649 -258.830318) (xy 120.869679 -258.77782) (xy 120.881676 -258.726552)
			(xy 120.901359 -258.677717) (xy 120.928265 -258.632458) (xy 120.961765 -258.591837) (xy 121.001073 -258.556806)
			(xy 121.045268 -258.528186) (xy 121.093313 -258.506647) (xy 121.144084 -258.492695) (xy 121.196389 -258.486657)
			(xy 121.249003 -258.488674) (xy 121.300693 -258.498698) (xy 121.350246 -258.516496) (xy 121.396502 -258.541649)
			(xy 121.438376 -258.573568) (xy 121.474888 -258.611506) (xy 121.50518 -258.654572) (xy 121.528543 -258.701757)
			(xy 121.544429 -258.751956) (xy 121.552466 -258.803992) (xy 121.55297 -258.830318) (xy 122.791223 -258.830318)
			(xy 122.795253 -258.77782) (xy 122.80725 -258.726552) (xy 122.826933 -258.677717) (xy 122.853839 -258.632458)
			(xy 122.887339 -258.591837) (xy 122.926647 -258.556806) (xy 122.970842 -258.528186) (xy 123.018887 -258.506647)
			(xy 123.069658 -258.492695) (xy 123.121963 -258.486657) (xy 123.174577 -258.488674) (xy 123.226267 -258.498698)
			(xy 123.27582 -258.516496) (xy 123.322076 -258.541649) (xy 123.36395 -258.573568) (xy 123.400462 -258.611506)
			(xy 123.430754 -258.654572) (xy 123.454117 -258.701757) (xy 123.470003 -258.751956) (xy 123.47804 -258.803992)
			(xy 123.478544 -258.830318) (xy 124.696223 -258.830318) (xy 124.700253 -258.77782) (xy 124.71225 -258.726552)
			(xy 124.731933 -258.677717) (xy 124.758839 -258.632458) (xy 124.792339 -258.591837) (xy 124.831647 -258.556806)
			(xy 124.875842 -258.528186) (xy 124.923887 -258.506647) (xy 124.974658 -258.492695) (xy 125.026963 -258.486657)
			(xy 125.079577 -258.488674) (xy 125.131267 -258.498698) (xy 125.18082 -258.516496) (xy 125.227076 -258.541649)
			(xy 125.26895 -258.573568) (xy 125.305462 -258.611506) (xy 125.335754 -258.654572) (xy 125.359117 -258.701757)
			(xy 125.375003 -258.751956) (xy 125.38304 -258.803992) (xy 125.383544 -258.830318) (xy 125.38304 -258.856644)
			(xy 125.375003 -258.90868) (xy 125.359117 -258.958879) (xy 125.335754 -259.006064) (xy 125.305462 -259.04913)
			(xy 125.26895 -259.087068) (xy 125.227076 -259.118987) (xy 125.18082 -259.14414) (xy 125.131267 -259.161938)
			(xy 125.079577 -259.171962) (xy 125.026963 -259.173979) (xy 124.974658 -259.167941) (xy 124.923887 -259.153989)
			(xy 124.875842 -259.13245) (xy 124.831647 -259.10383) (xy 124.792339 -259.068799) (xy 124.758839 -259.028178)
			(xy 124.731933 -258.982919) (xy 124.71225 -258.934084) (xy 124.700253 -258.882816) (xy 124.696223 -258.830318)
			(xy 123.478544 -258.830318) (xy 123.47804 -258.856644) (xy 123.470003 -258.90868) (xy 123.454117 -258.958879)
			(xy 123.430754 -259.006064) (xy 123.400462 -259.04913) (xy 123.36395 -259.087068) (xy 123.322076 -259.118987)
			(xy 123.27582 -259.14414) (xy 123.226267 -259.161938) (xy 123.174577 -259.171962) (xy 123.121963 -259.173979)
			(xy 123.069658 -259.167941) (xy 123.018887 -259.153989) (xy 122.970842 -259.13245) (xy 122.926647 -259.10383)
			(xy 122.887339 -259.068799) (xy 122.853839 -259.028178) (xy 122.826933 -258.982919) (xy 122.80725 -258.934084)
			(xy 122.795253 -258.882816) (xy 122.791223 -258.830318) (xy 121.55297 -258.830318) (xy 121.552466 -258.856644)
			(xy 121.544429 -258.90868) (xy 121.528543 -258.958879) (xy 121.50518 -259.006064) (xy 121.474888 -259.04913)
			(xy 121.438376 -259.087068) (xy 121.396502 -259.118987) (xy 121.350246 -259.14414) (xy 121.300693 -259.161938)
			(xy 121.249003 -259.171962) (xy 121.196389 -259.173979) (xy 121.144084 -259.167941) (xy 121.093313 -259.153989)
			(xy 121.045268 -259.13245) (xy 121.001073 -259.10383) (xy 120.961765 -259.068799) (xy 120.928265 -259.028178)
			(xy 120.901359 -258.982919) (xy 120.881676 -258.934084) (xy 120.869679 -258.882816) (xy 120.865649 -258.830318)
			(xy 116.523687 -258.830318) (xy 116.517273 -258.872505) (xy 116.501862 -258.922049) (xy 116.479189 -258.968719)
			(xy 116.464842 -258.990338) (xy 116.459948 -258.998201) (xy 116.455572 -259.016183) (xy 116.457819 -259.034552)
			(xy 116.461794 -259.042916) (xy 116.502688 -259.12064) (xy 116.507347 -259.128596) (xy 116.521181 -259.140761)
			(xy 116.538433 -259.147221) (xy 116.547646 -259.147564) (xy 117.111526 -259.147564) (xy 117.117393 -259.147402)
			(xy 117.128814 -259.144713) (xy 117.134132 -259.14223) (xy 117.152928 -259.132832) (xy 117.163088 -259.125974)
			(xy 117.167406 -259.122672) (xy 117.170454 -259.118608) (xy 117.186829 -259.098484) (xy 117.22461 -259.062929)
			(xy 117.267308 -259.033459) (xy 117.313952 -259.010746) (xy 117.363482 -258.995307) (xy 117.41477 -258.987491)
			(xy 117.44071 -258.987036) (xy 117.467696 -258.987539) (xy 117.521002 -258.995984) (xy 117.572331 -259.012664)
			(xy 117.620418 -259.037169) (xy 117.664079 -259.068896) (xy 117.702239 -259.107062) (xy 117.733959 -259.150728)
			(xy 117.758457 -259.198819) (xy 117.775129 -259.250151) (xy 117.783566 -259.303458) (xy 117.784118 -259.330444)
			(xy 117.783521 -259.359127) (xy 117.773948 -259.415689) (xy 117.75511 -259.469874) (xy 117.727531 -259.520176)
			(xy 117.710204 -259.543042) (xy 117.705124 -259.5499) (xy 117.696996 -259.572506) (xy 117.695577 -259.576873)
			(xy 117.694178 -259.585948) (xy 117.694202 -259.59054) (xy 117.69471 -259.611876) (xy 117.695349 -259.621427)
			(xy 117.702786 -259.63905) (xy 117.709188 -259.646166) (xy 117.709442 -259.64642) (xy 117.793262 -259.73024)
			(xy 120.865649 -259.73024) (xy 120.869679 -259.677742) (xy 120.881676 -259.626474) (xy 120.901359 -259.577639)
			(xy 120.928265 -259.53238) (xy 120.961765 -259.491759) (xy 121.001073 -259.456728) (xy 121.045268 -259.428108)
			(xy 121.093313 -259.406569) (xy 121.144084 -259.392617) (xy 121.196389 -259.386579) (xy 121.249003 -259.388596)
			(xy 121.300693 -259.39862) (xy 121.350246 -259.416418) (xy 121.396502 -259.441571) (xy 121.438376 -259.47349)
			(xy 121.474888 -259.511428) (xy 121.50518 -259.554494) (xy 121.528543 -259.601679) (xy 121.544429 -259.651878)
			(xy 121.552466 -259.703914) (xy 121.55297 -259.73024) (xy 122.791223 -259.73024) (xy 122.795253 -259.677742)
			(xy 122.80725 -259.626474) (xy 122.826933 -259.577639) (xy 122.853839 -259.53238) (xy 122.887339 -259.491759)
			(xy 122.926647 -259.456728) (xy 122.970842 -259.428108) (xy 123.018887 -259.406569) (xy 123.069658 -259.392617)
			(xy 123.121963 -259.386579) (xy 123.174577 -259.388596) (xy 123.226267 -259.39862) (xy 123.27582 -259.416418)
			(xy 123.322076 -259.441571) (xy 123.36395 -259.47349) (xy 123.400462 -259.511428) (xy 123.430754 -259.554494)
			(xy 123.454117 -259.601679) (xy 123.470003 -259.651878) (xy 123.47804 -259.703914) (xy 123.478544 -259.73024)
			(xy 124.696223 -259.73024) (xy 124.700253 -259.677742) (xy 124.71225 -259.626474) (xy 124.731933 -259.577639)
			(xy 124.758839 -259.53238) (xy 124.792339 -259.491759) (xy 124.831647 -259.456728) (xy 124.875842 -259.428108)
			(xy 124.923887 -259.406569) (xy 124.974658 -259.392617) (xy 125.026963 -259.386579) (xy 125.079577 -259.388596)
			(xy 125.131267 -259.39862) (xy 125.18082 -259.416418) (xy 125.227076 -259.441571) (xy 125.26895 -259.47349)
			(xy 125.305462 -259.511428) (xy 125.335754 -259.554494) (xy 125.359117 -259.601679) (xy 125.375003 -259.651878)
			(xy 125.38304 -259.703914) (xy 125.383544 -259.73024) (xy 125.38304 -259.756566) (xy 125.375003 -259.808602)
			(xy 125.359117 -259.858801) (xy 125.335754 -259.905986) (xy 125.305462 -259.949052) (xy 125.26895 -259.98699)
			(xy 125.227076 -260.018909) (xy 125.18082 -260.044062) (xy 125.131267 -260.06186) (xy 125.079577 -260.071884)
			(xy 125.026963 -260.073901) (xy 124.974658 -260.067863) (xy 124.923887 -260.053911) (xy 124.875842 -260.032372)
			(xy 124.831647 -260.003752) (xy 124.792339 -259.968721) (xy 124.758839 -259.9281) (xy 124.731933 -259.882841)
			(xy 124.71225 -259.834006) (xy 124.700253 -259.782738) (xy 124.696223 -259.73024) (xy 123.478544 -259.73024)
			(xy 123.47804 -259.756566) (xy 123.470003 -259.808602) (xy 123.454117 -259.858801) (xy 123.430754 -259.905986)
			(xy 123.400462 -259.949052) (xy 123.36395 -259.98699) (xy 123.322076 -260.018909) (xy 123.27582 -260.044062)
			(xy 123.226267 -260.06186) (xy 123.174577 -260.071884) (xy 123.121963 -260.073901) (xy 123.069658 -260.067863)
			(xy 123.018887 -260.053911) (xy 122.970842 -260.032372) (xy 122.926647 -260.003752) (xy 122.887339 -259.968721)
			(xy 122.853839 -259.9281) (xy 122.826933 -259.882841) (xy 122.80725 -259.834006) (xy 122.795253 -259.782738)
			(xy 122.791223 -259.73024) (xy 121.55297 -259.73024) (xy 121.552466 -259.756566) (xy 121.544429 -259.808602)
			(xy 121.528543 -259.858801) (xy 121.50518 -259.905986) (xy 121.474888 -259.949052) (xy 121.438376 -259.98699)
			(xy 121.396502 -260.018909) (xy 121.350246 -260.044062) (xy 121.300693 -260.06186) (xy 121.249003 -260.071884)
			(xy 121.196389 -260.073901) (xy 121.144084 -260.067863) (xy 121.093313 -260.053911) (xy 121.045268 -260.032372)
			(xy 121.001073 -260.003752) (xy 120.961765 -259.968721) (xy 120.928265 -259.9281) (xy 120.901359 -259.882841)
			(xy 120.881676 -259.834006) (xy 120.869679 -259.782738) (xy 120.865649 -259.73024) (xy 117.793262 -259.73024)
			(xy 118.084854 -260.021832) (xy 118.091559 -260.029073) (xy 118.099139 -260.047278) (xy 118.099586 -260.057138)
			(xy 118.099586 -260.269482) (xy 118.100057 -260.279354) (xy 118.107515 -260.297638) (xy 118.114064 -260.305042)
			(xy 118.114318 -260.305296) (xy 118.2878 -260.478778) (xy 118.288308 -260.479286) (xy 118.295688 -260.485872)
			(xy 118.313987 -260.493333) (xy 118.323868 -260.493764) (xy 121.70791 -260.493764) (xy 121.717753 -260.494288)
			(xy 121.735933 -260.501856) (xy 121.743216 -260.508496) (xy 122.09526 -260.86054) (xy 122.100848 -260.863842)
			(xy 122.122331 -260.877214) (xy 122.160943 -260.909917) (xy 122.193636 -260.948538) (xy 122.20702 -260.970014)
			(xy 122.210322 -260.975602) (xy 122.360944 -261.126224) (xy 123.518942 -261.126224) (xy 123.522902 -261.07717)
			(xy 123.534679 -261.029386) (xy 123.55397 -260.98411) (xy 123.580273 -260.942514) (xy 123.612908 -260.905677)
			(xy 123.651029 -260.874552) (xy 123.69365 -260.849945) (xy 123.739666 -260.832493) (xy 123.787885 -260.822649)
			(xy 123.83706 -260.820668) (xy 123.885915 -260.8266) (xy 123.933186 -260.840292) (xy 123.977648 -260.86139)
			(xy 124.018151 -260.889346) (xy 124.053644 -260.923438) (xy 124.083209 -260.962782) (xy 124.10608 -261.006359)
			(xy 124.121664 -261.05304) (xy 124.129559 -261.101617) (xy 124.130054 -261.126224) (xy 125.39905 -261.126224)
			(xy 125.40301 -261.07717) (xy 125.414787 -261.029386) (xy 125.434078 -260.98411) (xy 125.460381 -260.942514)
			(xy 125.493016 -260.905677) (xy 125.531137 -260.874552) (xy 125.573758 -260.849945) (xy 125.619774 -260.832493)
			(xy 125.667993 -260.822649) (xy 125.717168 -260.820668) (xy 125.766023 -260.8266) (xy 125.813294 -260.840292)
			(xy 125.857756 -260.86139) (xy 125.898259 -260.889346) (xy 125.933752 -260.923438) (xy 125.963317 -260.962782)
			(xy 125.986188 -261.006359) (xy 126.001772 -261.05304) (xy 126.009667 -261.101617) (xy 126.010162 -261.126224)
			(xy 127.278904 -261.126224) (xy 127.282864 -261.07717) (xy 127.294641 -261.029386) (xy 127.313932 -260.98411)
			(xy 127.340235 -260.942514) (xy 127.37287 -260.905677) (xy 127.410991 -260.874552) (xy 127.453612 -260.849945)
			(xy 127.499628 -260.832493) (xy 127.547847 -260.822649) (xy 127.597022 -260.820668) (xy 127.645877 -260.8266)
			(xy 127.693148 -260.840292) (xy 127.73761 -260.86139) (xy 127.778113 -260.889346) (xy 127.813606 -260.923438)
			(xy 127.843171 -260.962782) (xy 127.866042 -261.006359) (xy 127.881626 -261.05304) (xy 127.889521 -261.101617)
			(xy 127.890016 -261.126224) (xy 128.218958 -261.126224) (xy 128.222918 -261.07717) (xy 128.234695 -261.029386)
			(xy 128.253986 -260.98411) (xy 128.280289 -260.942514) (xy 128.312924 -260.905677) (xy 128.351045 -260.874552)
			(xy 128.393666 -260.849945) (xy 128.439682 -260.832493) (xy 128.487901 -260.822649) (xy 128.537076 -260.820668)
			(xy 128.585931 -260.8266) (xy 128.633202 -260.840292) (xy 128.677664 -260.86139) (xy 128.718167 -260.889346)
			(xy 128.75366 -260.923438) (xy 128.783225 -260.962782) (xy 128.806096 -261.006359) (xy 128.82168 -261.05304)
			(xy 128.829575 -261.101617) (xy 128.83007 -261.126224) (xy 129.159012 -261.126224) (xy 129.162972 -261.07717)
			(xy 129.174749 -261.029386) (xy 129.19404 -260.98411) (xy 129.220343 -260.942514) (xy 129.252978 -260.905677)
			(xy 129.291099 -260.874552) (xy 129.33372 -260.849945) (xy 129.379736 -260.832493) (xy 129.427955 -260.822649)
			(xy 129.47713 -260.820668) (xy 129.525985 -260.8266) (xy 129.573256 -260.840292) (xy 129.617718 -260.86139)
			(xy 129.658221 -260.889346) (xy 129.693714 -260.923438) (xy 129.723279 -260.962782) (xy 129.74615 -261.006359)
			(xy 129.761734 -261.05304) (xy 129.769629 -261.101617) (xy 129.770124 -261.126224) (xy 130.099066 -261.126224)
			(xy 130.103026 -261.07717) (xy 130.114803 -261.029386) (xy 130.134094 -260.98411) (xy 130.160397 -260.942514)
			(xy 130.193032 -260.905677) (xy 130.231153 -260.874552) (xy 130.273774 -260.849945) (xy 130.31979 -260.832493)
			(xy 130.368009 -260.822649) (xy 130.417184 -260.820668) (xy 130.466039 -260.8266) (xy 130.51331 -260.840292)
			(xy 130.557772 -260.86139) (xy 130.598275 -260.889346) (xy 130.633768 -260.923438) (xy 130.663333 -260.962782)
			(xy 130.686204 -261.006359) (xy 130.701788 -261.05304) (xy 130.709683 -261.101617) (xy 130.710178 -261.126224)
			(xy 131.038866 -261.126224) (xy 131.042826 -261.07717) (xy 131.054603 -261.029386) (xy 131.073894 -260.98411)
			(xy 131.100197 -260.942514) (xy 131.132832 -260.905677) (xy 131.170953 -260.874552) (xy 131.213574 -260.849945)
			(xy 131.25959 -260.832493) (xy 131.307809 -260.822649) (xy 131.356984 -260.820668) (xy 131.405839 -260.8266)
			(xy 131.45311 -260.840292) (xy 131.497572 -260.86139) (xy 131.538075 -260.889346) (xy 131.573568 -260.923438)
			(xy 131.603133 -260.962782) (xy 131.626004 -261.006359) (xy 131.641588 -261.05304) (xy 131.649483 -261.101617)
			(xy 131.649978 -261.126224) (xy 131.97892 -261.126224) (xy 131.98288 -261.07717) (xy 131.994657 -261.029386)
			(xy 132.013948 -260.98411) (xy 132.040251 -260.942514) (xy 132.072886 -260.905677) (xy 132.111007 -260.874552)
			(xy 132.153628 -260.849945) (xy 132.199644 -260.832493) (xy 132.247863 -260.822649) (xy 132.297038 -260.820668)
			(xy 132.345893 -260.8266) (xy 132.393164 -260.840292) (xy 132.437626 -260.86139) (xy 132.478129 -260.889346)
			(xy 132.513622 -260.923438) (xy 132.543187 -260.962782) (xy 132.566058 -261.006359) (xy 132.581642 -261.05304)
			(xy 132.589537 -261.101617) (xy 132.590032 -261.126224) (xy 132.918974 -261.126224) (xy 132.922934 -261.07717)
			(xy 132.934711 -261.029386) (xy 132.954002 -260.98411) (xy 132.980305 -260.942514) (xy 133.01294 -260.905677)
			(xy 133.051061 -260.874552) (xy 133.093682 -260.849945) (xy 133.139698 -260.832493) (xy 133.187917 -260.822649)
			(xy 133.237092 -260.820668) (xy 133.285947 -260.8266) (xy 133.333218 -260.840292) (xy 133.37768 -260.86139)
			(xy 133.418183 -260.889346) (xy 133.453676 -260.923438) (xy 133.483241 -260.962782) (xy 133.506112 -261.006359)
			(xy 133.521696 -261.05304) (xy 133.529591 -261.101617) (xy 133.530086 -261.126224) (xy 133.859028 -261.126224)
			(xy 133.862988 -261.07717) (xy 133.874765 -261.029386) (xy 133.894056 -260.98411) (xy 133.920359 -260.942514)
			(xy 133.952994 -260.905677) (xy 133.991115 -260.874552) (xy 134.033736 -260.849945) (xy 134.079752 -260.832493)
			(xy 134.127971 -260.822649) (xy 134.177146 -260.820668) (xy 134.226001 -260.8266) (xy 134.273272 -260.840292)
			(xy 134.317734 -260.86139) (xy 134.358237 -260.889346) (xy 134.39373 -260.923438) (xy 134.423295 -260.962782)
			(xy 134.446166 -261.006359) (xy 134.46175 -261.05304) (xy 134.469645 -261.101617) (xy 134.47014 -261.126224)
			(xy 134.798828 -261.126224) (xy 134.802788 -261.07717) (xy 134.814565 -261.029386) (xy 134.833856 -260.98411)
			(xy 134.860159 -260.942514) (xy 134.892794 -260.905677) (xy 134.930915 -260.874552) (xy 134.973536 -260.849945)
			(xy 135.019552 -260.832493) (xy 135.067771 -260.822649) (xy 135.116946 -260.820668) (xy 135.165801 -260.8266)
			(xy 135.213072 -260.840292) (xy 135.257534 -260.86139) (xy 135.298037 -260.889346) (xy 135.33353 -260.923438)
			(xy 135.363095 -260.962782) (xy 135.385966 -261.006359) (xy 135.40155 -261.05304) (xy 135.409445 -261.101617)
			(xy 135.40994 -261.126224) (xy 135.738882 -261.126224) (xy 135.742842 -261.07717) (xy 135.754619 -261.029386)
			(xy 135.77391 -260.98411) (xy 135.800213 -260.942514) (xy 135.832848 -260.905677) (xy 135.870969 -260.874552)
			(xy 135.91359 -260.849945) (xy 135.959606 -260.832493) (xy 136.007825 -260.822649) (xy 136.057 -260.820668)
			(xy 136.105855 -260.8266) (xy 136.153126 -260.840292) (xy 136.197588 -260.86139) (xy 136.238091 -260.889346)
			(xy 136.273584 -260.923438) (xy 136.303149 -260.962782) (xy 136.32602 -261.006359) (xy 136.341604 -261.05304)
			(xy 136.349499 -261.101617) (xy 136.349994 -261.126224) (xy 136.678936 -261.126224) (xy 136.682896 -261.07717)
			(xy 136.694673 -261.029386) (xy 136.713964 -260.98411) (xy 136.740267 -260.942514) (xy 136.772902 -260.905677)
			(xy 136.811023 -260.874552) (xy 136.853644 -260.849945) (xy 136.89966 -260.832493) (xy 136.947879 -260.822649)
			(xy 136.997054 -260.820668) (xy 137.045909 -260.8266) (xy 137.09318 -260.840292) (xy 137.137642 -260.86139)
			(xy 137.178145 -260.889346) (xy 137.213638 -260.923438) (xy 137.243203 -260.962782) (xy 137.266074 -261.006359)
			(xy 137.281658 -261.05304) (xy 137.289553 -261.101617) (xy 137.290048 -261.126224) (xy 137.289553 -261.150831)
			(xy 137.281658 -261.199408) (xy 137.266074 -261.246089) (xy 137.243203 -261.289666) (xy 137.213638 -261.32901)
			(xy 137.178145 -261.363102) (xy 137.137642 -261.391058) (xy 137.09318 -261.412156) (xy 137.045909 -261.425848)
			(xy 136.997054 -261.43178) (xy 136.947879 -261.429799) (xy 136.89966 -261.419955) (xy 136.853644 -261.402503)
			(xy 136.811023 -261.377896) (xy 136.772902 -261.346771) (xy 136.740267 -261.309934) (xy 136.713964 -261.268338)
			(xy 136.694673 -261.223062) (xy 136.682896 -261.175278) (xy 136.678936 -261.126224) (xy 136.349994 -261.126224)
			(xy 136.349499 -261.150831) (xy 136.341604 -261.199408) (xy 136.32602 -261.246089) (xy 136.303149 -261.289666)
			(xy 136.273584 -261.32901) (xy 136.238091 -261.363102) (xy 136.197588 -261.391058) (xy 136.153126 -261.412156)
			(xy 136.105855 -261.425848) (xy 136.057 -261.43178) (xy 136.007825 -261.429799) (xy 135.959606 -261.419955)
			(xy 135.91359 -261.402503) (xy 135.870969 -261.377896) (xy 135.832848 -261.346771) (xy 135.800213 -261.309934)
			(xy 135.77391 -261.268338) (xy 135.754619 -261.223062) (xy 135.742842 -261.175278) (xy 135.738882 -261.126224)
			(xy 135.40994 -261.126224) (xy 135.409445 -261.150831) (xy 135.40155 -261.199408) (xy 135.385966 -261.246089)
			(xy 135.363095 -261.289666) (xy 135.33353 -261.32901) (xy 135.298037 -261.363102) (xy 135.257534 -261.391058)
			(xy 135.213072 -261.412156) (xy 135.165801 -261.425848) (xy 135.116946 -261.43178) (xy 135.067771 -261.429799)
			(xy 135.019552 -261.419955) (xy 134.973536 -261.402503) (xy 134.930915 -261.377896) (xy 134.892794 -261.346771)
			(xy 134.860159 -261.309934) (xy 134.833856 -261.268338) (xy 134.814565 -261.223062) (xy 134.802788 -261.175278)
			(xy 134.798828 -261.126224) (xy 134.47014 -261.126224) (xy 134.469645 -261.150831) (xy 134.46175 -261.199408)
			(xy 134.446166 -261.246089) (xy 134.423295 -261.289666) (xy 134.39373 -261.32901) (xy 134.358237 -261.363102)
			(xy 134.317734 -261.391058) (xy 134.273272 -261.412156) (xy 134.226001 -261.425848) (xy 134.177146 -261.43178)
			(xy 134.127971 -261.429799) (xy 134.079752 -261.419955) (xy 134.033736 -261.402503) (xy 133.991115 -261.377896)
			(xy 133.952994 -261.346771) (xy 133.920359 -261.309934) (xy 133.894056 -261.268338) (xy 133.874765 -261.223062)
			(xy 133.862988 -261.175278) (xy 133.859028 -261.126224) (xy 133.530086 -261.126224) (xy 133.529591 -261.150831)
			(xy 133.521696 -261.199408) (xy 133.506112 -261.246089) (xy 133.483241 -261.289666) (xy 133.453676 -261.32901)
			(xy 133.418183 -261.363102) (xy 133.37768 -261.391058) (xy 133.333218 -261.412156) (xy 133.285947 -261.425848)
			(xy 133.237092 -261.43178) (xy 133.187917 -261.429799) (xy 133.139698 -261.419955) (xy 133.093682 -261.402503)
			(xy 133.051061 -261.377896) (xy 133.01294 -261.346771) (xy 132.980305 -261.309934) (xy 132.954002 -261.268338)
			(xy 132.934711 -261.223062) (xy 132.922934 -261.175278) (xy 132.918974 -261.126224) (xy 132.590032 -261.126224)
			(xy 132.589537 -261.150831) (xy 132.581642 -261.199408) (xy 132.566058 -261.246089) (xy 132.543187 -261.289666)
			(xy 132.513622 -261.32901) (xy 132.478129 -261.363102) (xy 132.437626 -261.391058) (xy 132.393164 -261.412156)
			(xy 132.345893 -261.425848) (xy 132.297038 -261.43178) (xy 132.247863 -261.429799) (xy 132.199644 -261.419955)
			(xy 132.153628 -261.402503) (xy 132.111007 -261.377896) (xy 132.072886 -261.346771) (xy 132.040251 -261.309934)
			(xy 132.013948 -261.268338) (xy 131.994657 -261.223062) (xy 131.98288 -261.175278) (xy 131.97892 -261.126224)
			(xy 131.649978 -261.126224) (xy 131.649483 -261.150831) (xy 131.641588 -261.199408) (xy 131.626004 -261.246089)
			(xy 131.603133 -261.289666) (xy 131.573568 -261.32901) (xy 131.538075 -261.363102) (xy 131.497572 -261.391058)
			(xy 131.45311 -261.412156) (xy 131.405839 -261.425848) (xy 131.356984 -261.43178) (xy 131.307809 -261.429799)
			(xy 131.25959 -261.419955) (xy 131.213574 -261.402503) (xy 131.170953 -261.377896) (xy 131.132832 -261.346771)
			(xy 131.100197 -261.309934) (xy 131.073894 -261.268338) (xy 131.054603 -261.223062) (xy 131.042826 -261.175278)
			(xy 131.038866 -261.126224) (xy 130.710178 -261.126224) (xy 130.709683 -261.150831) (xy 130.701788 -261.199408)
			(xy 130.686204 -261.246089) (xy 130.663333 -261.289666) (xy 130.633768 -261.32901) (xy 130.598275 -261.363102)
			(xy 130.557772 -261.391058) (xy 130.51331 -261.412156) (xy 130.466039 -261.425848) (xy 130.417184 -261.43178)
			(xy 130.368009 -261.429799) (xy 130.31979 -261.419955) (xy 130.273774 -261.402503) (xy 130.231153 -261.377896)
			(xy 130.193032 -261.346771) (xy 130.160397 -261.309934) (xy 130.134094 -261.268338) (xy 130.114803 -261.223062)
			(xy 130.103026 -261.175278) (xy 130.099066 -261.126224) (xy 129.770124 -261.126224) (xy 129.769629 -261.150831)
			(xy 129.761734 -261.199408) (xy 129.74615 -261.246089) (xy 129.723279 -261.289666) (xy 129.693714 -261.32901)
			(xy 129.658221 -261.363102) (xy 129.617718 -261.391058) (xy 129.573256 -261.412156) (xy 129.525985 -261.425848)
			(xy 129.47713 -261.43178) (xy 129.427955 -261.429799) (xy 129.379736 -261.419955) (xy 129.33372 -261.402503)
			(xy 129.291099 -261.377896) (xy 129.252978 -261.346771) (xy 129.220343 -261.309934) (xy 129.19404 -261.268338)
			(xy 129.174749 -261.223062) (xy 129.162972 -261.175278) (xy 129.159012 -261.126224) (xy 128.83007 -261.126224)
			(xy 128.829575 -261.150831) (xy 128.82168 -261.199408) (xy 128.806096 -261.246089) (xy 128.783225 -261.289666)
			(xy 128.75366 -261.32901) (xy 128.718167 -261.363102) (xy 128.677664 -261.391058) (xy 128.633202 -261.412156)
			(xy 128.585931 -261.425848) (xy 128.537076 -261.43178) (xy 128.487901 -261.429799) (xy 128.439682 -261.419955)
			(xy 128.393666 -261.402503) (xy 128.351045 -261.377896) (xy 128.312924 -261.346771) (xy 128.280289 -261.309934)
			(xy 128.253986 -261.268338) (xy 128.234695 -261.223062) (xy 128.222918 -261.175278) (xy 128.218958 -261.126224)
			(xy 127.890016 -261.126224) (xy 127.889521 -261.150831) (xy 127.881626 -261.199408) (xy 127.866042 -261.246089)
			(xy 127.843171 -261.289666) (xy 127.813606 -261.32901) (xy 127.778113 -261.363102) (xy 127.73761 -261.391058)
			(xy 127.693148 -261.412156) (xy 127.645877 -261.425848) (xy 127.597022 -261.43178) (xy 127.547847 -261.429799)
			(xy 127.499628 -261.419955) (xy 127.453612 -261.402503) (xy 127.410991 -261.377896) (xy 127.37287 -261.346771)
			(xy 127.340235 -261.309934) (xy 127.313932 -261.268338) (xy 127.294641 -261.223062) (xy 127.282864 -261.175278)
			(xy 127.278904 -261.126224) (xy 126.010162 -261.126224) (xy 126.009667 -261.150831) (xy 126.001772 -261.199408)
			(xy 125.986188 -261.246089) (xy 125.963317 -261.289666) (xy 125.933752 -261.32901) (xy 125.898259 -261.363102)
			(xy 125.857756 -261.391058) (xy 125.813294 -261.412156) (xy 125.766023 -261.425848) (xy 125.717168 -261.43178)
			(xy 125.667993 -261.429799) (xy 125.619774 -261.419955) (xy 125.573758 -261.402503) (xy 125.531137 -261.377896)
			(xy 125.493016 -261.346771) (xy 125.460381 -261.309934) (xy 125.434078 -261.268338) (xy 125.414787 -261.223062)
			(xy 125.40301 -261.175278) (xy 125.39905 -261.126224) (xy 124.130054 -261.126224) (xy 124.129559 -261.150831)
			(xy 124.121664 -261.199408) (xy 124.10608 -261.246089) (xy 124.083209 -261.289666) (xy 124.053644 -261.32901)
			(xy 124.018151 -261.363102) (xy 123.977648 -261.391058) (xy 123.933186 -261.412156) (xy 123.885915 -261.425848)
			(xy 123.83706 -261.43178) (xy 123.787885 -261.429799) (xy 123.739666 -261.419955) (xy 123.69365 -261.402503)
			(xy 123.651029 -261.377896) (xy 123.612908 -261.346771) (xy 123.580273 -261.309934) (xy 123.55397 -261.268338)
			(xy 123.534679 -261.223062) (xy 123.522902 -261.175278) (xy 123.518942 -261.126224) (xy 122.360944 -261.126224)
			(xy 123.17095 -261.93623) (xy 123.988842 -261.93623) (xy 123.992802 -261.887176) (xy 124.004579 -261.839392)
			(xy 124.02387 -261.794116) (xy 124.050173 -261.75252) (xy 124.082808 -261.715683) (xy 124.120929 -261.684558)
			(xy 124.16355 -261.659951) (xy 124.209566 -261.642499) (xy 124.257785 -261.632655) (xy 124.30696 -261.630674)
			(xy 124.355815 -261.636606) (xy 124.403086 -261.650298) (xy 124.447548 -261.671396) (xy 124.488051 -261.699352)
			(xy 124.523544 -261.733444) (xy 124.553109 -261.772788) (xy 124.57598 -261.816365) (xy 124.591564 -261.863046)
			(xy 124.599459 -261.911623) (xy 124.599954 -261.93623) (xy 125.86895 -261.93623) (xy 125.87291 -261.887176)
			(xy 125.884687 -261.839392) (xy 125.903978 -261.794116) (xy 125.930281 -261.75252) (xy 125.962916 -261.715683)
			(xy 126.001037 -261.684558) (xy 126.043658 -261.659951) (xy 126.089674 -261.642499) (xy 126.137893 -261.632655)
			(xy 126.187068 -261.630674) (xy 126.235923 -261.636606) (xy 126.283194 -261.650298) (xy 126.327656 -261.671396)
			(xy 126.368159 -261.699352) (xy 126.403652 -261.733444) (xy 126.433217 -261.772788) (xy 126.456088 -261.816365)
			(xy 126.471672 -261.863046) (xy 126.479567 -261.911623) (xy 126.480062 -261.93623) (xy 127.738627 -261.93623)
			(xy 127.742722 -261.885502) (xy 127.754901 -261.836088) (xy 127.774849 -261.789268) (xy 127.80205 -261.746254)
			(xy 127.835798 -261.70816) (xy 127.87522 -261.675973) (xy 127.919294 -261.650527) (xy 127.96688 -261.63248)
			(xy 128.016744 -261.6223) (xy 128.067596 -261.620251) (xy 128.118117 -261.626385) (xy 128.167001 -261.640545)
			(xy 128.21298 -261.662362) (xy 128.254864 -261.691272) (xy 128.291568 -261.726527) (xy 128.322141 -261.767213)
			(xy 128.345792 -261.812276) (xy 128.361908 -261.86055) (xy 128.370072 -261.910784) (xy 128.370584 -261.93623)
			(xy 128.688858 -261.93623) (xy 128.692818 -261.887176) (xy 128.704595 -261.839392) (xy 128.723886 -261.794116)
			(xy 128.750189 -261.75252) (xy 128.782824 -261.715683) (xy 128.820945 -261.684558) (xy 128.863566 -261.659951)
			(xy 128.909582 -261.642499) (xy 128.957801 -261.632655) (xy 129.006976 -261.630674) (xy 129.055831 -261.636606)
			(xy 129.103102 -261.650298) (xy 129.147564 -261.671396) (xy 129.188067 -261.699352) (xy 129.22356 -261.733444)
			(xy 129.253125 -261.772788) (xy 129.275996 -261.816365) (xy 129.29158 -261.863046) (xy 129.299475 -261.911623)
			(xy 129.29997 -261.93623) (xy 129.628912 -261.93623) (xy 129.632872 -261.887176) (xy 129.644649 -261.839392)
			(xy 129.66394 -261.794116) (xy 129.690243 -261.75252) (xy 129.722878 -261.715683) (xy 129.760999 -261.684558)
			(xy 129.80362 -261.659951) (xy 129.849636 -261.642499) (xy 129.897855 -261.632655) (xy 129.94703 -261.630674)
			(xy 129.995885 -261.636606) (xy 130.043156 -261.650298) (xy 130.087618 -261.671396) (xy 130.128121 -261.699352)
			(xy 130.163614 -261.733444) (xy 130.193179 -261.772788) (xy 130.21605 -261.816365) (xy 130.231634 -261.863046)
			(xy 130.239529 -261.911623) (xy 130.240024 -261.93623) (xy 130.568966 -261.93623) (xy 130.572926 -261.887176)
			(xy 130.584703 -261.839392) (xy 130.603994 -261.794116) (xy 130.630297 -261.75252) (xy 130.662932 -261.715683)
			(xy 130.701053 -261.684558) (xy 130.743674 -261.659951) (xy 130.78969 -261.642499) (xy 130.837909 -261.632655)
			(xy 130.887084 -261.630674) (xy 130.935939 -261.636606) (xy 130.98321 -261.650298) (xy 131.027672 -261.671396)
			(xy 131.068175 -261.699352) (xy 131.103668 -261.733444) (xy 131.133233 -261.772788) (xy 131.156104 -261.816365)
			(xy 131.171688 -261.863046) (xy 131.179583 -261.911623) (xy 131.180078 -261.93623) (xy 131.498589 -261.93623)
			(xy 131.502684 -261.885502) (xy 131.514863 -261.836088) (xy 131.534811 -261.789268) (xy 131.562012 -261.746254)
			(xy 131.59576 -261.70816) (xy 131.635182 -261.675973) (xy 131.679256 -261.650527) (xy 131.726842 -261.63248)
			(xy 131.776706 -261.6223) (xy 131.827558 -261.620251) (xy 131.878079 -261.626385) (xy 131.926963 -261.640545)
			(xy 131.972942 -261.662362) (xy 132.014826 -261.691272) (xy 132.05153 -261.726527) (xy 132.082103 -261.767213)
			(xy 132.105754 -261.812276) (xy 132.12187 -261.86055) (xy 132.130034 -261.910784) (xy 132.130546 -261.93623)
			(xy 132.44882 -261.93623) (xy 132.45278 -261.887176) (xy 132.464557 -261.839392) (xy 132.483848 -261.794116)
			(xy 132.510151 -261.75252) (xy 132.542786 -261.715683) (xy 132.580907 -261.684558) (xy 132.623528 -261.659951)
			(xy 132.669544 -261.642499) (xy 132.717763 -261.632655) (xy 132.766938 -261.630674) (xy 132.815793 -261.636606)
			(xy 132.863064 -261.650298) (xy 132.907526 -261.671396) (xy 132.948029 -261.699352) (xy 132.983522 -261.733444)
			(xy 133.013087 -261.772788) (xy 133.035958 -261.816365) (xy 133.051542 -261.863046) (xy 133.059437 -261.911623)
			(xy 133.059932 -261.93623) (xy 133.388874 -261.93623) (xy 133.392834 -261.887176) (xy 133.404611 -261.839392)
			(xy 133.423902 -261.794116) (xy 133.450205 -261.75252) (xy 133.48284 -261.715683) (xy 133.520961 -261.684558)
			(xy 133.563582 -261.659951) (xy 133.609598 -261.642499) (xy 133.657817 -261.632655) (xy 133.706992 -261.630674)
			(xy 133.755847 -261.636606) (xy 133.803118 -261.650298) (xy 133.84758 -261.671396) (xy 133.888083 -261.699352)
			(xy 133.923576 -261.733444) (xy 133.953141 -261.772788) (xy 133.976012 -261.816365) (xy 133.991596 -261.863046)
			(xy 133.999491 -261.911623) (xy 133.999986 -261.93623) (xy 134.328928 -261.93623) (xy 134.332888 -261.887176)
			(xy 134.344665 -261.839392) (xy 134.363956 -261.794116) (xy 134.390259 -261.75252) (xy 134.422894 -261.715683)
			(xy 134.461015 -261.684558) (xy 134.503636 -261.659951) (xy 134.549652 -261.642499) (xy 134.597871 -261.632655)
			(xy 134.647046 -261.630674) (xy 134.695901 -261.636606) (xy 134.743172 -261.650298) (xy 134.787634 -261.671396)
			(xy 134.828137 -261.699352) (xy 134.86363 -261.733444) (xy 134.893195 -261.772788) (xy 134.916066 -261.816365)
			(xy 134.93165 -261.863046) (xy 134.939545 -261.911623) (xy 134.94004 -261.93623) (xy 135.268982 -261.93623)
			(xy 135.272942 -261.887176) (xy 135.284719 -261.839392) (xy 135.30401 -261.794116) (xy 135.330313 -261.75252)
			(xy 135.362948 -261.715683) (xy 135.401069 -261.684558) (xy 135.44369 -261.659951) (xy 135.489706 -261.642499)
			(xy 135.537925 -261.632655) (xy 135.5871 -261.630674) (xy 135.635955 -261.636606) (xy 135.683226 -261.650298)
			(xy 135.727688 -261.671396) (xy 135.768191 -261.699352) (xy 135.803684 -261.733444) (xy 135.833249 -261.772788)
			(xy 135.85612 -261.816365) (xy 135.871704 -261.863046) (xy 135.879599 -261.911623) (xy 135.880094 -261.93623)
			(xy 136.209036 -261.93623) (xy 136.212996 -261.887176) (xy 136.224773 -261.839392) (xy 136.244064 -261.794116)
			(xy 136.270367 -261.75252) (xy 136.303002 -261.715683) (xy 136.341123 -261.684558) (xy 136.383744 -261.659951)
			(xy 136.42976 -261.642499) (xy 136.477979 -261.632655) (xy 136.527154 -261.630674) (xy 136.576009 -261.636606)
			(xy 136.62328 -261.650298) (xy 136.667742 -261.671396) (xy 136.708245 -261.699352) (xy 136.743738 -261.733444)
			(xy 136.773303 -261.772788) (xy 136.796174 -261.816365) (xy 136.811758 -261.863046) (xy 136.819653 -261.911623)
			(xy 136.820148 -261.93623) (xy 136.819653 -261.960837) (xy 136.811758 -262.009414) (xy 136.796174 -262.056095)
			(xy 136.773303 -262.099672) (xy 136.743738 -262.139016) (xy 136.708245 -262.173108) (xy 136.667742 -262.201064)
			(xy 136.62328 -262.222162) (xy 136.576009 -262.235854) (xy 136.527154 -262.241786) (xy 136.477979 -262.239805)
			(xy 136.42976 -262.229961) (xy 136.383744 -262.212509) (xy 136.341123 -262.187902) (xy 136.303002 -262.156777)
			(xy 136.270367 -262.11994) (xy 136.244064 -262.078344) (xy 136.224773 -262.033068) (xy 136.212996 -261.985284)
			(xy 136.209036 -261.93623) (xy 135.880094 -261.93623) (xy 135.879599 -261.960837) (xy 135.871704 -262.009414)
			(xy 135.85612 -262.056095) (xy 135.833249 -262.099672) (xy 135.803684 -262.139016) (xy 135.768191 -262.173108)
			(xy 135.727688 -262.201064) (xy 135.683226 -262.222162) (xy 135.635955 -262.235854) (xy 135.5871 -262.241786)
			(xy 135.537925 -262.239805) (xy 135.489706 -262.229961) (xy 135.44369 -262.212509) (xy 135.401069 -262.187902)
			(xy 135.362948 -262.156777) (xy 135.330313 -262.11994) (xy 135.30401 -262.078344) (xy 135.284719 -262.033068)
			(xy 135.272942 -261.985284) (xy 135.268982 -261.93623) (xy 134.94004 -261.93623) (xy 134.939545 -261.960837)
			(xy 134.93165 -262.009414) (xy 134.916066 -262.056095) (xy 134.893195 -262.099672) (xy 134.86363 -262.139016)
			(xy 134.828137 -262.173108) (xy 134.787634 -262.201064) (xy 134.743172 -262.222162) (xy 134.695901 -262.235854)
			(xy 134.647046 -262.241786) (xy 134.597871 -262.239805) (xy 134.549652 -262.229961) (xy 134.503636 -262.212509)
			(xy 134.461015 -262.187902) (xy 134.422894 -262.156777) (xy 134.390259 -262.11994) (xy 134.363956 -262.078344)
			(xy 134.344665 -262.033068) (xy 134.332888 -261.985284) (xy 134.328928 -261.93623) (xy 133.999986 -261.93623)
			(xy 133.999491 -261.960837) (xy 133.991596 -262.009414) (xy 133.976012 -262.056095) (xy 133.953141 -262.099672)
			(xy 133.923576 -262.139016) (xy 133.888083 -262.173108) (xy 133.84758 -262.201064) (xy 133.803118 -262.222162)
			(xy 133.755847 -262.235854) (xy 133.706992 -262.241786) (xy 133.657817 -262.239805) (xy 133.609598 -262.229961)
			(xy 133.563582 -262.212509) (xy 133.520961 -262.187902) (xy 133.48284 -262.156777) (xy 133.450205 -262.11994)
			(xy 133.423902 -262.078344) (xy 133.404611 -262.033068) (xy 133.392834 -261.985284) (xy 133.388874 -261.93623)
			(xy 133.059932 -261.93623) (xy 133.059437 -261.960837) (xy 133.051542 -262.009414) (xy 133.035958 -262.056095)
			(xy 133.013087 -262.099672) (xy 132.983522 -262.139016) (xy 132.948029 -262.173108) (xy 132.907526 -262.201064)
			(xy 132.863064 -262.222162) (xy 132.815793 -262.235854) (xy 132.766938 -262.241786) (xy 132.717763 -262.239805)
			(xy 132.669544 -262.229961) (xy 132.623528 -262.212509) (xy 132.580907 -262.187902) (xy 132.542786 -262.156777)
			(xy 132.510151 -262.11994) (xy 132.483848 -262.078344) (xy 132.464557 -262.033068) (xy 132.45278 -261.985284)
			(xy 132.44882 -261.93623) (xy 132.130546 -261.93623) (xy 132.130034 -261.961676) (xy 132.12187 -262.01191)
			(xy 132.105754 -262.060184) (xy 132.082103 -262.105247) (xy 132.05153 -262.145933) (xy 132.014826 -262.181188)
			(xy 131.972942 -262.210098) (xy 131.926963 -262.231915) (xy 131.878079 -262.246075) (xy 131.827558 -262.252209)
			(xy 131.776706 -262.25016) (xy 131.726842 -262.23998) (xy 131.679256 -262.221933) (xy 131.635182 -262.196487)
			(xy 131.59576 -262.1643) (xy 131.562012 -262.126206) (xy 131.534811 -262.083192) (xy 131.514863 -262.036372)
			(xy 131.502684 -261.986958) (xy 131.498589 -261.93623) (xy 131.180078 -261.93623) (xy 131.179583 -261.960837)
			(xy 131.171688 -262.009414) (xy 131.156104 -262.056095) (xy 131.133233 -262.099672) (xy 131.103668 -262.139016)
			(xy 131.068175 -262.173108) (xy 131.027672 -262.201064) (xy 130.98321 -262.222162) (xy 130.935939 -262.235854)
			(xy 130.887084 -262.241786) (xy 130.837909 -262.239805) (xy 130.78969 -262.229961) (xy 130.743674 -262.212509)
			(xy 130.701053 -262.187902) (xy 130.662932 -262.156777) (xy 130.630297 -262.11994) (xy 130.603994 -262.078344)
			(xy 130.584703 -262.033068) (xy 130.572926 -261.985284) (xy 130.568966 -261.93623) (xy 130.240024 -261.93623)
			(xy 130.239529 -261.960837) (xy 130.231634 -262.009414) (xy 130.21605 -262.056095) (xy 130.193179 -262.099672)
			(xy 130.163614 -262.139016) (xy 130.128121 -262.173108) (xy 130.087618 -262.201064) (xy 130.043156 -262.222162)
			(xy 129.995885 -262.235854) (xy 129.94703 -262.241786) (xy 129.897855 -262.239805) (xy 129.849636 -262.229961)
			(xy 129.80362 -262.212509) (xy 129.760999 -262.187902) (xy 129.722878 -262.156777) (xy 129.690243 -262.11994)
			(xy 129.66394 -262.078344) (xy 129.644649 -262.033068) (xy 129.632872 -261.985284) (xy 129.628912 -261.93623)
			(xy 129.29997 -261.93623) (xy 129.299475 -261.960837) (xy 129.29158 -262.009414) (xy 129.275996 -262.056095)
			(xy 129.253125 -262.099672) (xy 129.22356 -262.139016) (xy 129.188067 -262.173108) (xy 129.147564 -262.201064)
			(xy 129.103102 -262.222162) (xy 129.055831 -262.235854) (xy 129.006976 -262.241786) (xy 128.957801 -262.239805)
			(xy 128.909582 -262.229961) (xy 128.863566 -262.212509) (xy 128.820945 -262.187902) (xy 128.782824 -262.156777)
			(xy 128.750189 -262.11994) (xy 128.723886 -262.078344) (xy 128.704595 -262.033068) (xy 128.692818 -261.985284)
			(xy 128.688858 -261.93623) (xy 128.370584 -261.93623) (xy 128.370072 -261.961676) (xy 128.361908 -262.01191)
			(xy 128.345792 -262.060184) (xy 128.322141 -262.105247) (xy 128.291568 -262.145933) (xy 128.254864 -262.181188)
			(xy 128.21298 -262.210098) (xy 128.167001 -262.231915) (xy 128.118117 -262.246075) (xy 128.067596 -262.252209)
			(xy 128.016744 -262.25016) (xy 127.96688 -262.23998) (xy 127.919294 -262.221933) (xy 127.87522 -262.196487)
			(xy 127.835798 -262.1643) (xy 127.80205 -262.126206) (xy 127.774849 -262.083192) (xy 127.754901 -262.036372)
			(xy 127.742722 -261.986958) (xy 127.738627 -261.93623) (xy 126.480062 -261.93623) (xy 126.479567 -261.960837)
			(xy 126.471672 -262.009414) (xy 126.456088 -262.056095) (xy 126.433217 -262.099672) (xy 126.403652 -262.139016)
			(xy 126.368159 -262.173108) (xy 126.327656 -262.201064) (xy 126.283194 -262.222162) (xy 126.235923 -262.235854)
			(xy 126.187068 -262.241786) (xy 126.137893 -262.239805) (xy 126.089674 -262.229961) (xy 126.043658 -262.212509)
			(xy 126.001037 -262.187902) (xy 125.962916 -262.156777) (xy 125.930281 -262.11994) (xy 125.903978 -262.078344)
			(xy 125.884687 -262.033068) (xy 125.87291 -261.985284) (xy 125.86895 -261.93623) (xy 124.599954 -261.93623)
			(xy 124.599459 -261.960837) (xy 124.591564 -262.009414) (xy 124.57598 -262.056095) (xy 124.553109 -262.099672)
			(xy 124.523544 -262.139016) (xy 124.488051 -262.173108) (xy 124.447548 -262.201064) (xy 124.403086 -262.222162)
			(xy 124.355815 -262.235854) (xy 124.30696 -262.241786) (xy 124.257785 -262.239805) (xy 124.209566 -262.229961)
			(xy 124.16355 -262.212509) (xy 124.120929 -262.187902) (xy 124.082808 -262.156777) (xy 124.050173 -262.11994)
			(xy 124.02387 -262.078344) (xy 124.004579 -262.033068) (xy 123.992802 -261.985284) (xy 123.988842 -261.93623)
			(xy 123.17095 -261.93623) (xy 123.678188 -262.443468) (xy 123.685136 -262.449851) (xy 123.702352 -262.457529)
			(xy 123.721178 -262.458476) (xy 123.730258 -262.455914) (xy 123.752882 -262.449015) (xy 123.799576 -262.441481)
			(xy 123.823222 -262.440928) (xy 123.828302 -262.440928) (xy 123.852112 -262.441658) (xy 123.89908 -262.449596)
			(xy 123.944245 -262.464731) (xy 123.986511 -262.486698) (xy 124.024853 -262.514963) (xy 124.05834 -262.54884)
			(xy 124.086158 -262.587507) (xy 124.107634 -262.630025) (xy 124.122245 -262.675362) (xy 124.129638 -262.722419)
			(xy 124.130054 -262.746236) (xy 124.130054 -262.753602) (xy 124.1298 -262.763508) (xy 124.137166 -262.782304)
			(xy 124.194062 -262.840724) (xy 124.201487 -262.847674) (xy 124.220223 -262.855541) (xy 124.230384 -262.855964)
			(xy 125.299724 -262.855964) (xy 125.309656 -262.85542) (xy 125.327972 -262.847718) (xy 125.335284 -262.840978)
			(xy 125.385068 -262.78967) (xy 125.391617 -262.782343) (xy 125.399071 -262.764179) (xy 125.399546 -262.754364)
			(xy 125.399546 -262.746236) (xy 125.400068 -262.720981) (xy 125.408381 -262.671159) (xy 125.424782 -262.623385)
			(xy 125.448823 -262.578962) (xy 125.479847 -262.539102) (xy 125.517009 -262.504892) (xy 125.559295 -262.477266)
			(xy 125.605551 -262.456976) (xy 125.654516 -262.444576) (xy 125.704854 -262.440405) (xy 125.755192 -262.444576)
			(xy 125.804157 -262.456976) (xy 125.850413 -262.477266) (xy 125.892699 -262.504892) (xy 125.929861 -262.539102)
			(xy 125.960885 -262.578962) (xy 125.984926 -262.623385) (xy 126.001327 -262.671159) (xy 126.00964 -262.720981)
			(xy 126.010162 -262.746236) (xy 126.010162 -262.753602) (xy 126.009908 -262.763508) (xy 126.017274 -262.782304)
			(xy 126.07417 -262.840724) (xy 126.081596 -262.847673) (xy 126.100331 -262.855537) (xy 126.110492 -262.855964)
			(xy 127.179578 -262.855964) (xy 127.189505 -262.85541) (xy 127.207807 -262.847695) (xy 127.215138 -262.840978)
			(xy 127.264922 -262.78967) (xy 127.271476 -262.782345) (xy 127.278937 -262.764181) (xy 127.2794 -262.754364)
			(xy 127.2794 -262.746236) (xy 127.279922 -262.720981) (xy 127.288235 -262.671159) (xy 127.304636 -262.623385)
			(xy 127.328677 -262.578962) (xy 127.359701 -262.539102) (xy 127.396863 -262.504892) (xy 127.439149 -262.477266)
			(xy 127.485405 -262.456976) (xy 127.53437 -262.444576) (xy 127.584708 -262.440405) (xy 127.635046 -262.444576)
			(xy 127.684011 -262.456976) (xy 127.730267 -262.477266) (xy 127.772553 -262.504892) (xy 127.809715 -262.539102)
			(xy 127.840739 -262.578962) (xy 127.86478 -262.623385) (xy 127.881181 -262.671159) (xy 127.889494 -262.720981)
			(xy 127.890016 -262.746236) (xy 127.890016 -262.753602) (xy 127.889762 -262.763508) (xy 127.897128 -262.782304)
			(xy 127.954024 -262.840724) (xy 127.961452 -262.847664) (xy 127.980189 -262.855509) (xy 127.990346 -262.855964)
			(xy 128.119632 -262.855964) (xy 128.129563 -262.855419) (xy 128.147877 -262.847715) (xy 128.155192 -262.840978)
			(xy 128.20269 -262.79221) (xy 128.210056 -262.772652) (xy 128.209548 -262.761984) (xy 128.20904 -262.746236)
			(xy 128.209527 -262.721426) (xy 128.217289 -262.672418) (xy 128.232622 -262.625228) (xy 128.255149 -262.581017)
			(xy 128.284314 -262.540874) (xy 128.3194 -262.505788) (xy 128.359543 -262.476623) (xy 128.403754 -262.454096)
			(xy 128.450944 -262.438763) (xy 128.499952 -262.431001) (xy 128.549572 -262.431001) (xy 128.59858 -262.438763)
			(xy 128.64577 -262.454096) (xy 128.689981 -262.476623) (xy 128.730124 -262.505788) (xy 128.76521 -262.540874)
			(xy 128.794375 -262.581017) (xy 128.816902 -262.625228) (xy 128.832235 -262.672418) (xy 128.839997 -262.721426)
			(xy 128.840484 -262.746236) (xy 128.839976 -262.761984) (xy 128.839468 -262.772652) (xy 128.846834 -262.79221)
			(xy 128.894078 -262.840724) (xy 128.901504 -262.847672) (xy 128.92024 -262.855533) (xy 128.9304 -262.855964)
			(xy 129.059686 -262.855964) (xy 129.069612 -262.855409) (xy 129.087912 -262.847691) (xy 129.095246 -262.840978)
			(xy 129.142744 -262.79221) (xy 129.15011 -262.772652) (xy 129.149602 -262.761984) (xy 129.149348 -262.746236)
			(xy 129.149834 -262.721446) (xy 129.15759 -262.672478) (xy 129.172911 -262.625325) (xy 129.19542 -262.58115)
			(xy 129.224562 -262.541039) (xy 129.259619 -262.505982) (xy 129.29973 -262.47684) (xy 129.343905 -262.454331)
			(xy 129.391058 -262.43901) (xy 129.440026 -262.431254) (xy 129.489606 -262.431254) (xy 129.538574 -262.43901)
			(xy 129.585727 -262.454331) (xy 129.629902 -262.47684) (xy 129.670013 -262.505982) (xy 129.70507 -262.541039)
			(xy 129.734212 -262.58115) (xy 129.756721 -262.625325) (xy 129.772042 -262.672478) (xy 129.779798 -262.721446)
			(xy 129.780284 -262.746236) (xy 129.78003 -262.761984) (xy 129.779522 -262.772652) (xy 129.786888 -262.79221)
			(xy 129.834132 -262.840724) (xy 129.841561 -262.847663) (xy 129.860297 -262.855505) (xy 129.870454 -262.855964)
			(xy 129.99974 -262.855964) (xy 130.00967 -262.855417) (xy 130.027982 -262.847711) (xy 130.0353 -262.840978)
			(xy 130.085084 -262.78967) (xy 130.091631 -262.782342) (xy 130.099084 -262.764179) (xy 130.099562 -262.754364)
			(xy 130.099562 -262.746236) (xy 130.100084 -262.720981) (xy 130.108397 -262.671159) (xy 130.124798 -262.623385)
			(xy 130.148839 -262.578962) (xy 130.179863 -262.539102) (xy 130.217025 -262.504892) (xy 130.259311 -262.477266)
			(xy 130.305567 -262.456976) (xy 130.354532 -262.444576) (xy 130.40487 -262.440405) (xy 130.455208 -262.444576)
			(xy 130.504173 -262.456976) (xy 130.550429 -262.477266) (xy 130.592715 -262.504892) (xy 130.629877 -262.539102)
			(xy 130.660901 -262.578962) (xy 130.684942 -262.623385) (xy 130.701343 -262.671159) (xy 130.709656 -262.720981)
			(xy 130.710178 -262.746236) (xy 130.710178 -262.753602) (xy 130.709924 -262.763508) (xy 130.71729 -262.782304)
			(xy 130.774186 -262.840724) (xy 130.781612 -262.84767) (xy 130.800348 -262.855529) (xy 130.810508 -262.855964)
			(xy 130.93954 -262.855964) (xy 130.94947 -262.855417) (xy 130.967782 -262.847711) (xy 130.9751 -262.840978)
			(xy 131.022598 -262.79221) (xy 131.029964 -262.772652) (xy 131.029456 -262.761984) (xy 131.028948 -262.746236)
			(xy 131.029435 -262.721426) (xy 131.037197 -262.672418) (xy 131.05253 -262.625228) (xy 131.075057 -262.581017)
			(xy 131.104222 -262.540874) (xy 131.139308 -262.505788) (xy 131.179451 -262.476623) (xy 131.223662 -262.454096)
			(xy 131.270852 -262.438763) (xy 131.31986 -262.431001) (xy 131.36948 -262.431001) (xy 131.418488 -262.438763)
			(xy 131.465678 -262.454096) (xy 131.509889 -262.476623) (xy 131.550032 -262.505788) (xy 131.585118 -262.540874)
			(xy 131.614283 -262.581017) (xy 131.63681 -262.625228) (xy 131.652143 -262.672418) (xy 131.659905 -262.721426)
			(xy 131.660392 -262.746236) (xy 131.659884 -262.761984) (xy 131.659376 -262.772652) (xy 131.666742 -262.79221)
			(xy 131.713986 -262.840724) (xy 131.721412 -262.84767) (xy 131.740148 -262.855529) (xy 131.750308 -262.855964)
			(xy 131.879594 -262.855964) (xy 131.88952 -262.855407) (xy 131.907818 -262.847688) (xy 131.915154 -262.840978)
			(xy 131.964938 -262.78967) (xy 131.97149 -262.782344) (xy 131.978949 -262.76418) (xy 131.979416 -262.754364)
			(xy 131.979416 -262.746236) (xy 131.979938 -262.720981) (xy 131.988251 -262.671159) (xy 132.004652 -262.623385)
			(xy 132.028693 -262.578962) (xy 132.059717 -262.539102) (xy 132.096879 -262.504892) (xy 132.139165 -262.477266)
			(xy 132.185421 -262.456976) (xy 132.234386 -262.444576) (xy 132.284724 -262.440405) (xy 132.335062 -262.444576)
			(xy 132.384027 -262.456976) (xy 132.430283 -262.477266) (xy 132.472569 -262.504892) (xy 132.509731 -262.539102)
			(xy 132.540755 -262.578962) (xy 132.564796 -262.623385) (xy 132.581197 -262.671159) (xy 132.58951 -262.720981)
			(xy 132.590032 -262.746236) (xy 132.590032 -262.753602) (xy 132.589778 -262.763508) (xy 132.597144 -262.782304)
			(xy 132.65404 -262.840724) (xy 132.661469 -262.847662) (xy 132.680206 -262.8555) (xy 132.690362 -262.855964)
			(xy 132.819648 -262.855964) (xy 132.829578 -262.855416) (xy 132.847887 -262.847708) (xy 132.855208 -262.840978)
			(xy 132.902706 -262.79221) (xy 132.910072 -262.772652) (xy 132.909564 -262.761984) (xy 132.909056 -262.746236)
			(xy 132.909543 -262.721426) (xy 132.917305 -262.672418) (xy 132.932638 -262.625228) (xy 132.955165 -262.581017)
			(xy 132.98433 -262.540874) (xy 133.019416 -262.505788) (xy 133.059559 -262.476623) (xy 133.10377 -262.454096)
			(xy 133.15096 -262.438763) (xy 133.199968 -262.431001) (xy 133.249588 -262.431001) (xy 133.298596 -262.438763)
			(xy 133.345786 -262.454096) (xy 133.389997 -262.476623) (xy 133.43014 -262.505788) (xy 133.465226 -262.540874)
			(xy 133.494391 -262.581017) (xy 133.516918 -262.625228) (xy 133.532251 -262.672418) (xy 133.540013 -262.721426)
			(xy 133.5405 -262.746236) (xy 133.539992 -262.761984) (xy 133.539484 -262.772652) (xy 133.54685 -262.79221)
			(xy 133.594094 -262.840724) (xy 133.601521 -262.847669) (xy 133.620257 -262.855525) (xy 133.630416 -262.855964)
			(xy 133.759702 -262.855964) (xy 133.769627 -262.855406) (xy 133.787923 -262.847684) (xy 133.795262 -262.840978)
			(xy 133.845046 -262.78967) (xy 133.851597 -262.782344) (xy 133.859055 -262.76418) (xy 133.859524 -262.754364)
			(xy 133.859524 -262.746236) (xy 133.860046 -262.720981) (xy 133.868359 -262.671159) (xy 133.88476 -262.623385)
			(xy 133.908801 -262.578962) (xy 133.939825 -262.539102) (xy 133.976987 -262.504892) (xy 134.019273 -262.477266)
			(xy 134.065529 -262.456976) (xy 134.114494 -262.444576) (xy 134.164832 -262.440405) (xy 134.21517 -262.444576)
			(xy 134.264135 -262.456976) (xy 134.310391 -262.477266) (xy 134.352677 -262.504892) (xy 134.389839 -262.539102)
			(xy 134.420863 -262.578962) (xy 134.444904 -262.623385) (xy 134.461305 -262.671159) (xy 134.469618 -262.720981)
			(xy 134.47014 -262.746236) (xy 134.47014 -262.753602) (xy 134.469886 -262.763508) (xy 134.477252 -262.782304)
			(xy 134.534148 -262.840724) (xy 134.541572 -262.847676) (xy 134.560308 -262.855549) (xy 134.57047 -262.855964)
			(xy 134.699502 -262.855964) (xy 134.709427 -262.855406) (xy 134.727723 -262.847684) (xy 134.735062 -262.840978)
			(xy 134.784846 -262.78967) (xy 134.791397 -262.782344) (xy 134.798855 -262.76418) (xy 134.799324 -262.754364)
			(xy 134.799324 -262.746236) (xy 134.799768 -262.722242) (xy 134.80727 -262.674844) (xy 134.822096 -262.629204)
			(xy 134.84388 -262.586445) (xy 134.872085 -262.547621) (xy 134.906018 -262.513688) (xy 134.944841 -262.485482)
			(xy 134.9876 -262.463697) (xy 135.03324 -262.448871) (xy 135.080638 -262.441368) (xy 135.104632 -262.440928)
			(xy 135.128583 -262.441398) (xy 135.175895 -262.448885) (xy 135.221457 -262.463669) (xy 135.264152 -262.485388)
			(xy 135.302929 -262.51351) (xy 135.336839 -262.547342) (xy 135.365048 -262.586056) (xy 135.386865 -262.628701)
			(xy 135.401753 -262.674229) (xy 135.409347 -262.721525) (xy 135.40994 -262.745474) (xy 135.40994 -262.746236)
			(xy 135.738882 -262.746236) (xy 135.742842 -262.697182) (xy 135.754619 -262.649398) (xy 135.77391 -262.604122)
			(xy 135.800213 -262.562526) (xy 135.832848 -262.525689) (xy 135.870969 -262.494564) (xy 135.91359 -262.469957)
			(xy 135.959606 -262.452505) (xy 136.007825 -262.442661) (xy 136.057 -262.44068) (xy 136.105855 -262.446612)
			(xy 136.153126 -262.460304) (xy 136.197588 -262.481402) (xy 136.238091 -262.509358) (xy 136.273584 -262.54345)
			(xy 136.303149 -262.582794) (xy 136.32602 -262.626371) (xy 136.341604 -262.673052) (xy 136.349499 -262.721629)
			(xy 136.349994 -262.746236) (xy 136.349499 -262.770843) (xy 136.341604 -262.81942) (xy 136.32602 -262.866101)
			(xy 136.303149 -262.909678) (xy 136.273584 -262.949022) (xy 136.238091 -262.983114) (xy 136.197588 -263.01107)
			(xy 136.153126 -263.032168) (xy 136.105855 -263.04586) (xy 136.057 -263.051792) (xy 136.007825 -263.049811)
			(xy 135.959606 -263.039967) (xy 135.91359 -263.022515) (xy 135.870969 -262.997908) (xy 135.832848 -262.966783)
			(xy 135.800213 -262.929946) (xy 135.77391 -262.88835) (xy 135.754619 -262.843074) (xy 135.742842 -262.79529)
			(xy 135.738882 -262.746236) (xy 135.40994 -262.746236) (xy 135.40994 -262.746998) (xy 135.409581 -262.766265)
			(xy 135.404612 -262.804479) (xy 135.400034 -262.823198) (xy 135.400034 -262.823452) (xy 135.39978 -262.82396)
			(xy 135.398415 -262.830246) (xy 135.398536 -262.843105) (xy 135.400034 -262.84936) (xy 135.40199 -262.855756)
			(xy 135.408677 -262.867332) (xy 135.413242 -262.87222) (xy 136.054338 -263.513316) (xy 136.05764 -263.516364)
			(xy 136.057894 -263.516618) (xy 136.067625 -263.523837) (xy 136.091228 -263.52916) (xy 136.103106 -263.526778)
			(xy 136.198864 -263.50214) (xy 136.217914 -263.483852) (xy 136.221724 -263.470644) (xy 136.229083 -263.4472)
			(xy 136.250233 -263.402853) (xy 136.278215 -263.362466) (xy 136.312305 -263.327084) (xy 136.351623 -263.297619)
			(xy 136.395153 -263.274834) (xy 136.441771 -263.259317) (xy 136.490273 -263.251468) (xy 136.51484 -263.250934)
			(xy 136.53883 -263.251383) (xy 136.586218 -263.258895) (xy 136.631848 -263.273728) (xy 136.674595 -263.295516)
			(xy 136.713408 -263.323723) (xy 136.74733 -263.357654) (xy 136.775527 -263.396475) (xy 136.797304 -263.439228)
			(xy 136.812124 -263.484862) (xy 136.819623 -263.532252) (xy 136.820148 -263.556242) (xy 136.820065 -263.5681)
			(xy 136.818285 -263.591749) (xy 136.816592 -263.603486) (xy 136.816592 -263.60374) (xy 136.815422 -263.614719)
			(xy 136.821491 -263.635922) (xy 136.828276 -263.644634) (xy 136.877044 -263.701784) (xy 136.88187 -263.70661)
			(xy 136.889064 -263.712473) (xy 136.906382 -263.719102) (xy 136.915652 -263.719564)
		)
		(stroke
			(width 0)
			(type solid)
		)
		(fill yes)
		(layer "In11.Cu")
		(net "PVDDCR_SOC_P1")
	)
	(gr_poly
		(pts
			(xy 369.038632 -263.610852) (xy 369.045744 -263.604248) (xy 369.096544 -263.55802) (xy 369.101624 -263.551924)
			(xy 369.10518 -263.546082) (xy 369.110006 -263.536176) (xy 369.110768 -263.527032) (xy 369.113641 -263.502138)
			(xy 369.126465 -263.4537) (xy 369.147029 -263.408006) (xy 369.174781 -263.366286) (xy 369.208975 -263.329659)
			(xy 369.248693 -263.299109) (xy 369.292867 -263.275458) (xy 369.340312 -263.25934) (xy 369.389752 -263.251188)
			(xy 369.414806 -263.25068) (xy 369.440002 -263.251196) (xy 369.489712 -263.259469) (xy 369.537388 -263.27579)
			(xy 369.581739 -263.299716) (xy 369.621561 -263.330598) (xy 369.655773 -263.367597) (xy 369.670076 -263.388348)
			(xy 369.673124 -263.39292) (xy 369.682014 -263.40181) (xy 369.688318 -263.407618) (xy 369.703761 -263.415035)
			(xy 369.71224 -263.416288) (xy 369.78717 -263.42467) (xy 369.79856 -263.425311) (xy 369.820067 -263.417795)
			(xy 369.828572 -263.410192) (xy 370.114322 -263.124442) (xy 370.121563 -263.117735) (xy 370.139767 -263.110152)
			(xy 370.149628 -263.10971) (xy 371.02288 -263.10971) (xy 371.032717 -263.109173) (xy 371.050876 -263.101584)
			(xy 371.058186 -263.094978) (xy 371.130322 -263.022842) (xy 371.137042 -263.015606) (xy 371.144655 -262.997402)
			(xy 371.145054 -262.987536) (xy 371.145054 -262.444992) (xy 371.144628 -262.434923) (xy 371.136906 -262.416326)
			(xy 371.130068 -262.408924) (xy 370.781326 -262.060182) (xy 370.772536 -262.052302) (xy 370.750156 -262.044884)
			(xy 370.7384 -262.045958) (xy 370.647976 -262.058912) (xy 370.628418 -262.072374) (xy 370.622576 -262.083042)
			(xy 370.610948 -262.103255) (xy 370.582516 -262.140214) (xy 370.548798 -262.172424) (xy 370.510578 -262.199137)
			(xy 370.468743 -262.219733) (xy 370.424265 -262.233733) (xy 370.378175 -262.240812) (xy 370.35486 -262.241284)
			(xy 370.330872 -262.24081) (xy 370.283486 -262.233299) (xy 370.237859 -262.218468) (xy 370.195114 -262.196682)
			(xy 370.156302 -262.168477) (xy 370.122381 -262.134549) (xy 370.094185 -262.095732) (xy 370.072408 -262.052982)
			(xy 370.057586 -262.007352) (xy 370.050085 -261.959965) (xy 370.049552 -261.935976) (xy 370.049994 -261.91266)
			(xy 370.057081 -261.866569) (xy 370.071087 -261.82209) (xy 370.091687 -261.780254) (xy 370.118403 -261.742034)
			(xy 370.150615 -261.708315) (xy 370.187575 -261.67988) (xy 370.207794 -261.66826) (xy 370.217906 -261.662046)
			(xy 370.231414 -261.642569) (xy 370.233702 -261.630922) (xy 370.244878 -261.55269) (xy 370.245988 -261.540871)
			(xy 370.238577 -261.518349) (xy 370.230654 -261.50951) (xy 370.111782 -261.390638) (xy 370.103267 -261.382826)
			(xy 370.081491 -261.375164) (xy 370.058554 -261.377772) (xy 370.048536 -261.383526) (xy 370.023834 -261.398435)
			(xy 369.97021 -261.41971) (xy 369.91355 -261.430568) (xy 369.884706 -261.431278) (xy 369.860713 -261.430832)
			(xy 369.813319 -261.423326) (xy 369.767682 -261.408498) (xy 369.724928 -261.386712) (xy 369.686108 -261.358506)
			(xy 369.652178 -261.324574) (xy 369.623975 -261.285752) (xy 369.602193 -261.242995) (xy 369.587368 -261.197358)
			(xy 369.579866 -261.149963) (xy 369.579398 -261.12597) (xy 369.579772 -261.104341) (xy 369.585884 -261.061517)
			(xy 369.597995 -261.01999) (xy 369.615862 -260.980594) (xy 369.62715 -260.96214) (xy 369.636548 -260.947154)
			(xy 369.632738 -260.911594) (xy 369.45824 -260.737096) (xy 369.451128 -260.72973) (xy 369.432332 -260.72211)
			(xy 366.238028 -260.72211) (xy 366.22819 -260.721574) (xy 366.210029 -260.713988) (xy 366.202722 -260.707378)
			(xy 365.865156 -260.369812) (xy 365.855643 -260.361358) (xy 365.831259 -260.354182) (xy 365.818674 -260.356096)
			(xy 365.725202 -260.376162) (xy 365.705644 -260.392672) (xy 365.701072 -260.40461) (xy 365.691291 -260.428468)
			(xy 365.665619 -260.473185) (xy 365.633553 -260.513563) (xy 365.595813 -260.548696) (xy 365.553247 -260.577795)
			(xy 365.50681 -260.600206) (xy 365.457545 -260.615426) (xy 365.406559 -260.623114) (xy 365.380778 -260.623558)
			(xy 365.353793 -260.623027) (xy 365.300486 -260.614582) (xy 365.249157 -260.597903) (xy 365.201069 -260.573401)
			(xy 365.157405 -260.541678) (xy 365.11924 -260.503516) (xy 365.087514 -260.459855) (xy 365.063008 -260.411769)
			(xy 365.046325 -260.360441) (xy 365.037875 -260.307135) (xy 365.03737 -260.28015) (xy 365.037834 -260.254372)
			(xy 365.045539 -260.203395) (xy 365.060769 -260.154139) (xy 365.083183 -260.10771) (xy 365.112277 -260.065147)
			(xy 365.1474 -260.027406) (xy 365.187765 -259.995331) (xy 365.232466 -259.969643) (xy 365.256318 -259.959856)
			(xy 365.268256 -259.955284) (xy 365.284766 -259.935726) (xy 365.304832 -259.842254) (xy 365.306304 -259.83393)
			(xy 365.304268 -259.817159) (xy 365.29686 -259.801975) (xy 365.291116 -259.795772) (xy 364.78464 -259.289296)
			(xy 364.777528 -259.28193) (xy 364.758732 -259.27431) (xy 360.421428 -259.27431) (xy 360.41159 -259.273774)
			(xy 360.393429 -259.266188) (xy 360.386122 -259.259578) (xy 360.136186 -259.009642) (xy 360.129465 -259.002407)
			(xy 360.121851 -258.984202) (xy 360.121454 -258.974336) (xy 360.121454 -256.68732) (xy 360.118152 -256.67208)
			(xy 360.117136 -256.666492) (xy 360.105452 -256.64033) (xy 360.09834 -256.633472) (xy 360.079041 -256.613939)
			(xy 360.046288 -256.569868) (xy 360.02097 -256.521145) (xy 360.003732 -256.469013) (xy 359.995014 -256.414801)
			(xy 359.994454 -256.387346) (xy 359.995216 -256.363978) (xy 359.995216 -256.363724) (xy 359.996232 -256.351024)
			(xy 359.997248 -256.34315) (xy 359.998776 -256.331987) (xy 360.0031 -256.309872) (xy 360.005884 -256.298954)
			(xy 360.007769 -256.29027) (xy 360.00617 -256.272587) (xy 359.998666 -256.256495) (xy 359.992676 -256.249932)
			(xy 359.62844 -255.885696) (xy 359.621328 -255.87833) (xy 359.602532 -255.87071) (xy 355.570028 -255.87071)
			(xy 355.56019 -255.870174) (xy 355.542029 -255.862588) (xy 355.534722 -255.855978) (xy 355.47681 -255.798066)
			(xy 355.46665 -255.794256) (xy 355.444079 -255.785274) (xy 355.401515 -255.761865) (xy 355.362674 -255.732692)
			(xy 355.32833 -255.698337) (xy 355.299171 -255.659485) (xy 355.275776 -255.616913) (xy 355.266752 -255.594358)
			(xy 355.262942 -255.584198) (xy 355.106986 -255.428242) (xy 355.100265 -255.421007) (xy 355.092651 -255.402802)
			(xy 355.092254 -255.392936) (xy 355.092254 -254.850392) (xy 355.091828 -254.840323) (xy 355.084106 -254.821726)
			(xy 355.077268 -254.814324) (xy 354.21824 -253.955296) (xy 354.211128 -253.94793) (xy 354.192332 -253.94031)
			(xy 352.213926 -253.94031) (xy 352.204089 -253.939774) (xy 352.185927 -253.932187) (xy 352.17862 -253.925578)
			(xy 351.927414 -253.674372) (xy 351.920986 -253.668414) (xy 351.905171 -253.660889) (xy 351.887743 -253.65916)
			(xy 351.879154 -253.66091) (xy 351.866962 -253.663958) (xy 351.862136 -253.666498) (xy 351.841149 -253.676283)
			(xy 351.796954 -253.6901) (xy 351.751177 -253.697067) (xy 351.728024 -253.697486) (xy 351.724976 -253.697486)
			(xy 351.701293 -253.696804) (xy 351.654559 -253.689022) (xy 351.609589 -253.674115) (xy 351.567461 -253.652439)
			(xy 351.529187 -253.624515) (xy 351.495686 -253.591015) (xy 351.467762 -253.552741) (xy 351.446086 -253.510613)
			(xy 351.431178 -253.465643) (xy 351.423396 -253.418909) (xy 351.422716 -253.395226) (xy 351.422716 -253.393702)
			(xy 351.422716 -253.392178) (xy 351.42315 -253.369028) (xy 351.430142 -253.323259) (xy 351.443947 -253.279064)
			(xy 351.453704 -253.258066) (xy 351.456244 -253.25324) (xy 351.459292 -253.241048) (xy 351.461029 -253.232464)
			(xy 351.459254 -253.215054) (xy 351.451747 -253.199246) (xy 351.44583 -253.192788) (xy 350.796606 -252.543564)
			(xy 350.789443 -252.537025) (xy 350.771625 -252.529406) (xy 350.752252 -252.52893) (xy 350.743012 -252.53188)
			(xy 350.64446 -252.568456) (xy 350.62668 -252.592078) (xy 350.625664 -252.607064) (xy 350.623267 -252.632351)
			(xy 350.611146 -252.681676) (xy 350.591028 -252.728313) (xy 350.563467 -252.770977) (xy 350.529223 -252.808489)
			(xy 350.489243 -252.839815) (xy 350.444628 -252.864091) (xy 350.39661 -252.880647) (xy 350.346514 -252.889025)
			(xy 350.321118 -252.889512) (xy 350.297202 -252.889049) (xy 350.249954 -252.881592) (xy 350.204448 -252.866859)
			(xy 350.161795 -252.845209) (xy 350.123041 -252.817173) (xy 350.089133 -252.783436) (xy 350.060901 -252.744824)
			(xy 350.039035 -252.702282) (xy 350.024072 -252.656851) (xy 350.016376 -252.609642) (xy 350.01581 -252.585728)
			(xy 350.01581 -252.584204) (xy 350.015935 -252.572214) (xy 350.017843 -252.54831) (xy 350.01962 -252.536452)
			(xy 350.019874 -252.53442) (xy 350.020128 -252.531372) (xy 350.025013 -252.506601) (xy 350.041816 -252.458994)
			(xy 350.066218 -252.414797) (xy 350.097554 -252.375213) (xy 350.134972 -252.341321) (xy 350.177453 -252.314042)
			(xy 350.223841 -252.294118) (xy 350.272873 -252.282093) (xy 350.298004 -252.279658) (xy 350.298766 -252.279658)
			(xy 350.308281 -252.278384) (xy 350.325422 -252.269771) (xy 350.338229 -252.255489) (xy 350.341946 -252.246638)
			(xy 350.373442 -252.16231) (xy 350.376456 -252.153075) (xy 350.376019 -252.133672) (xy 350.368362 -252.115837)
			(xy 350.361758 -252.108716) (xy 350.22536 -251.972318) (xy 350.217662 -251.965374) (xy 350.198389 -251.95779)
			(xy 350.188022 -251.957586) (xy 350.105218 -251.960126) (xy 350.086676 -251.968762) (xy 350.079564 -251.97689)
			(xy 350.062027 -251.995836) (xy 350.021754 -252.02813) (xy 349.976622 -252.053188) (xy 349.927917 -252.070296)
			(xy 349.877029 -252.078967) (xy 349.851218 -252.079506) (xy 349.827224 -252.079061) (xy 349.779826 -252.071557)
			(xy 349.734186 -252.05673) (xy 349.691428 -252.034945) (xy 349.652604 -252.00674) (xy 349.618671 -251.972808)
			(xy 349.590463 -251.933986) (xy 349.568676 -251.891228) (xy 349.553847 -251.845589) (xy 349.54634 -251.798192)
			(xy 349.54591 -251.774198) (xy 349.546449 -251.748388) (xy 349.555128 -251.697502) (xy 349.572239 -251.648799)
			(xy 349.597294 -251.603667) (xy 349.629581 -251.563389) (xy 349.648526 -251.545852) (xy 349.656654 -251.53874)
			(xy 349.66529 -251.520198) (xy 349.66783 -251.437394) (xy 349.667649 -251.427027) (xy 349.660037 -251.407761)
			(xy 349.653098 -251.400056) (xy 349.51162 -251.258578) (xy 349.484442 -251.25172) (xy 349.470726 -251.256038)
			(xy 349.448844 -251.262318) (xy 349.403825 -251.269073) (xy 349.381064 -251.2695) (xy 349.357075 -251.269027)
			(xy 349.309688 -251.261516) (xy 349.264059 -251.246685) (xy 349.221312 -251.2249) (xy 349.182499 -251.196696)
			(xy 349.148576 -251.162767) (xy 349.120377 -251.12395) (xy 349.098598 -251.0812) (xy 349.083774 -251.035569)
			(xy 349.07627 -250.988181) (xy 349.075756 -250.964192) (xy 349.076177 -250.94143) (xy 349.082937 -250.896412)
			(xy 349.089218 -250.87453) (xy 349.093536 -250.860814) (xy 349.086678 -250.833636) (xy 348.990158 -250.737116)
			(xy 348.983046 -250.72975) (xy 348.96425 -250.72213) (xy 348.375986 -250.72213) (xy 348.366143 -250.721605)
			(xy 348.347965 -250.714035) (xy 348.34068 -250.707398) (xy 348.096586 -250.463304) (xy 348.093806 -250.460597)
			(xy 348.087551 -250.456008) (xy 348.08414 -250.45416) (xy 348.075504 -250.449588) (xy 348.056962 -250.447556)
			(xy 348.047818 -250.449842) (xy 348.029094 -250.454368) (xy 347.990879 -250.459213) (xy 347.971618 -250.459494)
			(xy 347.97111 -250.459494) (xy 347.947117 -250.459049) (xy 347.899721 -250.451543) (xy 347.854083 -250.436715)
			(xy 347.811326 -250.41493) (xy 347.772504 -250.386724) (xy 347.738573 -250.352793) (xy 347.710368 -250.31397)
			(xy 347.688583 -250.271214) (xy 347.673756 -250.225575) (xy 347.666251 -250.178179) (xy 347.665802 -250.154186)
			(xy 347.665802 -250.153678) (xy 347.666095 -250.134418) (xy 347.670934 -250.096202) (xy 347.675454 -250.077478)
			(xy 347.677294 -250.068874) (xy 347.675659 -250.05137) (xy 347.668183 -250.035458) (xy 347.662246 -250.028964)
			(xy 346.688918 -249.055636) (xy 346.681806 -249.04827) (xy 346.66301 -249.04065) (xy 345.97213 -249.04065)
			(xy 345.963239 -249.040986) (xy 345.94653 -249.047071) (xy 345.932919 -249.058514) (xy 345.928188 -249.06605)
			(xy 345.885008 -249.140726) (xy 345.881842 -249.146721) (xy 345.878503 -249.159855) (xy 345.878404 -249.166634)
			(xy 345.878404 -249.179842) (xy 345.888564 -249.197114) (xy 345.889072 -249.197876) (xy 345.890088 -249.199654)
			(xy 345.89085 -249.201178) (xy 345.891104 -249.201686) (xy 345.898434 -249.215962) (xy 345.910397 -249.245743)
			(xy 345.91498 -249.261122) (xy 345.91498 -249.261376) (xy 345.915742 -249.264424) (xy 345.920677 -249.2838)
			(xy 345.926024 -249.323427) (xy 345.92641 -249.343418) (xy 345.92641 -249.348498) (xy 345.925621 -249.372265)
			(xy 345.917586 -249.419134) (xy 345.90238 -249.46419) (xy 345.880371 -249.506342) (xy 345.852092 -249.544572)
			(xy 345.818226 -249.577954) (xy 345.779593 -249.60568) (xy 345.737128 -249.627079) (xy 345.691858 -249.641635)
			(xy 345.644878 -249.648994) (xy 345.621102 -249.649488) (xy 345.597109 -249.649042) (xy 345.549715 -249.641535)
			(xy 345.504078 -249.626707) (xy 345.461323 -249.604921) (xy 345.422503 -249.576715) (xy 345.388573 -249.542783)
			(xy 345.360369 -249.503961) (xy 345.338586 -249.461205) (xy 345.32376 -249.415568) (xy 345.316257 -249.368173)
			(xy 345.315794 -249.34418) (xy 345.315794 -249.331734) (xy 345.317193 -249.308078) (xy 345.326373 -249.261589)
			(xy 345.342602 -249.217068) (xy 345.35364 -249.196098) (xy 345.356688 -249.190764) (xy 345.360498 -249.17654)
			(xy 345.362566 -249.166794) (xy 345.359941 -249.147064) (xy 345.355418 -249.138186) (xy 345.317826 -249.072908)
			(xy 345.309698 -249.06224) (xy 345.303094 -249.055636) (xy 345.295982 -249.04827) (xy 345.277186 -249.04065)
			(xy 344.573606 -249.04065) (xy 344.563769 -249.040111) (xy 344.54561 -249.032523) (xy 344.5383 -249.025918)
			(xy 344.428064 -248.915682) (xy 344.421355 -248.908442) (xy 344.413767 -248.890238) (xy 344.413332 -248.880376)
			(xy 344.413332 -248.8565) (xy 344.412844 -248.84649) (xy 344.405186 -248.827993) (xy 344.391034 -248.813832)
			(xy 344.372542 -248.806162) (xy 344.362532 -248.8057) (xy 344.351102 -248.8057) (xy 344.340942 -248.810526)
			(xy 344.320542 -248.819676) (xy 344.277734 -248.832576) (xy 344.233503 -248.839091) (xy 344.211148 -248.839482)
			(xy 344.18589 -248.838993) (xy 344.136061 -248.830686) (xy 344.08828 -248.814289) (xy 344.04385 -248.790251)
			(xy 344.003983 -248.759227) (xy 343.969766 -248.722063) (xy 343.942134 -248.679774) (xy 343.92184 -248.633514)
			(xy 343.909438 -248.584544) (xy 343.905266 -248.5342) (xy 343.909438 -248.483856) (xy 343.92184 -248.434886)
			(xy 343.942134 -248.388626) (xy 343.969766 -248.346337) (xy 344.003983 -248.309173) (xy 344.04385 -248.278149)
			(xy 344.08828 -248.254111) (xy 344.136061 -248.237714) (xy 344.18589 -248.229407) (xy 344.211148 -248.228866)
			(xy 344.230472 -248.229145) (xy 344.268816 -248.233981) (xy 344.287602 -248.238518) (xy 344.299286 -248.241566)
			(xy 344.322146 -248.236994) (xy 344.393774 -248.181368) (xy 344.402615 -248.173783) (xy 344.412823 -248.152872)
			(xy 344.413332 -248.141236) (xy 344.413332 -247.878092) (xy 344.410538 -247.866408) (xy 344.407998 -247.861074)
			(xy 344.407744 -247.860566) (xy 344.397608 -247.839274) (xy 344.383288 -247.794345) (xy 344.376043 -247.747749)
			(xy 344.376048 -247.700594) (xy 344.383301 -247.653999) (xy 344.397629 -247.609073) (xy 344.407744 -247.58777)
			(xy 344.407998 -247.587262) (xy 344.410538 -247.581928) (xy 344.413332 -247.570244) (xy 344.413332 -247.3071)
			(xy 344.412756 -247.295479) (xy 344.402569 -247.274586) (xy 344.393774 -247.266968) (xy 344.322146 -247.211342)
			(xy 344.299286 -247.20677) (xy 344.287602 -247.209818) (xy 344.268816 -247.214355) (xy 344.230472 -247.219198)
			(xy 344.211148 -247.21947) (xy 344.185891 -247.218981) (xy 344.136064 -247.210674) (xy 344.088285 -247.194278)
			(xy 344.043857 -247.170241) (xy 344.003991 -247.139218) (xy 343.969776 -247.102056) (xy 343.942145 -247.059769)
			(xy 343.921852 -247.01351) (xy 343.90945 -246.964542) (xy 343.905278 -246.9142) (xy 343.90945 -246.863858)
			(xy 343.921852 -246.81489) (xy 343.942145 -246.768631) (xy 343.969776 -246.726344) (xy 344.003991 -246.689182)
			(xy 344.043857 -246.658159) (xy 344.088285 -246.634122) (xy 344.136064 -246.617726) (xy 344.185891 -246.609419)
			(xy 344.211148 -246.608854) (xy 344.230472 -246.609133) (xy 344.268816 -246.613969) (xy 344.287602 -246.618506)
			(xy 344.299286 -246.621554) (xy 344.322146 -246.616982) (xy 344.393774 -246.561356) (xy 344.402613 -246.55377)
			(xy 344.412816 -246.532859) (xy 344.413332 -246.521224) (xy 344.413332 -246.25808) (xy 344.410538 -246.246396)
			(xy 344.407998 -246.241062) (xy 344.407744 -246.240554) (xy 344.397609 -246.219262) (xy 344.38329 -246.174333)
			(xy 344.376048 -246.127738) (xy 344.376054 -246.080583) (xy 344.383308 -246.03399) (xy 344.397638 -245.989065)
			(xy 344.407744 -245.967758) (xy 344.407998 -245.96725) (xy 344.410538 -245.961916) (xy 344.413332 -245.950232)
			(xy 344.413332 -245.687088) (xy 344.412754 -245.675468) (xy 344.402564 -245.654579) (xy 344.393774 -245.646956)
			(xy 344.322146 -245.59133) (xy 344.299286 -245.586758) (xy 344.287602 -245.589806) (xy 344.268816 -245.594343)
			(xy 344.230472 -245.599187) (xy 344.211148 -245.599458) (xy 344.187153 -245.598991) (xy 344.139752 -245.591491)
			(xy 344.094109 -245.576669) (xy 344.051346 -245.554888) (xy 344.012517 -245.526687) (xy 343.978577 -245.492758)
			(xy 343.950363 -245.453938) (xy 343.928569 -245.411182) (xy 343.913732 -245.365543) (xy 343.906217 -245.318145)
			(xy 343.90584 -245.29415) (xy 343.906332 -245.26929) (xy 343.914396 -245.220228) (xy 343.930301 -245.173121)
			(xy 343.953627 -245.129212) (xy 343.983759 -245.089663) (xy 344.0199 -245.055518) (xy 344.040206 -245.041166)
			(xy 344.04046 -245.040912) (xy 344.045232 -245.037435) (xy 344.053185 -245.028712) (xy 344.056208 -245.02364)
			(xy 344.064336 -245.009416) (xy 344.068239 -245.001646) (xy 344.07109 -244.984505) (xy 344.069924 -244.975888)
			(xy 344.069162 -244.970808) (xy 344.067892 -244.966998) (xy 344.061034 -244.943884) (xy 344.059002 -244.936772)
			(xy 344.044016 -244.8814) (xy 344.042238 -244.874288) (xy 344.028268 -244.850666) (xy 344.023188 -244.84584)
			(xy 344.004846 -244.828045) (xy 343.969152 -244.791462) (xy 343.951814 -244.772688) (xy 343.943774 -244.76481)
			(xy 343.922964 -244.756302) (xy 343.900511 -244.757446) (xy 343.890346 -244.762274) (xy 343.867231 -244.774047)
			(xy 343.818112 -244.790713) (xy 343.766929 -244.799126) (xy 343.740994 -244.799612) (xy 343.716198 -244.799126)
			(xy 343.667215 -244.791371) (xy 343.620048 -244.776052) (xy 343.575856 -244.753547) (xy 343.535726 -244.72441)
			(xy 343.500645 -244.689356) (xy 343.471477 -244.649248) (xy 343.448939 -244.605072) (xy 343.433585 -244.557917)
			(xy 343.425793 -244.50894) (xy 343.425272 -244.484144) (xy 343.425811 -244.457251) (xy 343.434918 -244.404243)
			(xy 343.452877 -244.353544) (xy 343.479168 -244.306622) (xy 343.51303 -244.264835) (xy 343.553484 -244.22939)
			(xy 343.576148 -244.214904) (xy 343.585471 -244.208549) (xy 343.597875 -244.189736) (xy 343.601018 -244.167422)
			(xy 343.598246 -244.156484) (xy 343.583006 -244.10543) (xy 343.581228 -244.098826) (xy 343.562686 -244.023134)
			(xy 343.560146 -244.01145) (xy 343.539318 -243.985288) (xy 343.535508 -243.980462) (xy 343.526618 -243.97335)
			(xy 343.460578 -243.942616) (xy 343.43594 -243.943378) (xy 343.425272 -243.949474) (xy 343.401571 -243.962151)
			(xy 343.350924 -243.980139) (xy 343.297966 -243.989308) (xy 343.271094 -243.98986) (xy 343.246282 -243.989373)
			(xy 343.197268 -243.981609) (xy 343.150073 -243.966273) (xy 343.105858 -243.943744) (xy 343.065711 -243.914575)
			(xy 343.030621 -243.879485) (xy 343.001453 -243.839337) (xy 342.978924 -243.795121) (xy 342.96359 -243.747926)
			(xy 342.955827 -243.698912) (xy 342.955827 -243.649288) (xy 342.96359 -243.600274) (xy 342.978924 -243.553079)
			(xy 343.001453 -243.508863) (xy 343.030621 -243.468715) (xy 343.065711 -243.433625) (xy 343.105858 -243.404456)
			(xy 343.150073 -243.381927) (xy 343.197268 -243.366591) (xy 343.246282 -243.358827) (xy 343.271094 -243.358416)
			(xy 343.297967 -243.358976) (xy 343.350929 -243.368123) (xy 343.401574 -243.386119) (xy 343.425272 -243.398802)
			(xy 343.43594 -243.404898) (xy 343.460578 -243.40566) (xy 343.52103 -243.377466) (xy 343.526211 -243.374856)
			(xy 343.535313 -243.367668) (xy 343.539064 -243.363242) (xy 343.539318 -243.362988) (xy 343.55278 -243.34597)
			(xy 343.556269 -243.341377) (xy 343.561279 -243.33099) (xy 343.562686 -243.325396) (xy 343.581228 -243.25072)
			(xy 343.603072 -243.174012) (xy 343.59088 -243.142262) (xy 343.576148 -243.133118) (xy 343.553517 -243.118624)
			(xy 343.513102 -243.083208) (xy 343.479263 -243.041463) (xy 343.452976 -242.994594) (xy 343.434999 -242.943953)
			(xy 343.42585 -242.891) (xy 343.425272 -242.864132) (xy 343.425812 -242.83724) (xy 343.434921 -242.784232)
			(xy 343.452881 -242.733535) (xy 343.479173 -242.686615) (xy 343.513035 -242.644829) (xy 343.55349 -242.609386)
			(xy 343.576148 -242.594892) (xy 343.585469 -242.588537) (xy 343.597869 -242.569724) (xy 343.601007 -242.547412)
			(xy 343.598246 -242.536472) (xy 343.583006 -242.485418) (xy 343.581228 -242.478814) (xy 343.562686 -242.403122)
			(xy 343.560146 -242.391438) (xy 343.539318 -242.365276) (xy 343.535508 -242.36045) (xy 343.526618 -242.353338)
			(xy 343.460578 -242.322604) (xy 343.43594 -242.323366) (xy 343.425272 -242.329462) (xy 343.40157 -242.342135)
			(xy 343.350923 -242.360119) (xy 343.297966 -242.369285) (xy 343.271094 -242.369848) (xy 343.246283 -242.369361)
			(xy 343.197271 -242.361597) (xy 343.150078 -242.346262) (xy 343.105864 -242.323733) (xy 343.065719 -242.294566)
			(xy 343.030631 -242.259477) (xy 343.001463 -242.219331) (xy 342.978935 -242.175117) (xy 342.963601 -242.127923)
			(xy 342.955839 -242.078911) (xy 342.955839 -242.029289) (xy 342.963601 -241.980277) (xy 342.978935 -241.933083)
			(xy 343.001463 -241.888869) (xy 343.030631 -241.848723) (xy 343.065719 -241.813634) (xy 343.105864 -241.784467)
			(xy 343.150078 -241.761938) (xy 343.197271 -241.746603) (xy 343.246283 -241.738839) (xy 343.271094 -241.738404)
			(xy 343.297967 -241.738964) (xy 343.35093 -241.748111) (xy 343.401574 -241.766106) (xy 343.425272 -241.77879)
			(xy 343.43594 -241.784886) (xy 343.460578 -241.785648) (xy 343.52103 -241.757454) (xy 343.526215 -241.754848)
			(xy 343.535326 -241.747668) (xy 343.539064 -241.74323) (xy 343.539318 -241.742976) (xy 343.55278 -241.725958)
			(xy 343.556267 -241.721364) (xy 343.561275 -241.710976) (xy 343.562686 -241.705384) (xy 343.581228 -241.630708)
			(xy 343.603072 -241.554) (xy 343.59088 -241.52225) (xy 343.576148 -241.513106) (xy 343.553518 -241.498612)
			(xy 343.513104 -241.463195) (xy 343.479267 -241.42145) (xy 343.452981 -241.374581) (xy 343.435006 -241.32394)
			(xy 343.425859 -241.270988) (xy 343.425272 -241.24412) (xy 343.425813 -241.217228) (xy 343.434924 -241.164222)
			(xy 343.452885 -241.113527) (xy 343.479178 -241.066608) (xy 343.513041 -241.024823) (xy 343.553495 -240.989382)
			(xy 343.576148 -240.97488) (xy 343.585484 -240.968528) (xy 343.597917 -240.949712) (xy 343.60109 -240.927384)
			(xy 343.598246 -240.91646) (xy 343.583006 -240.865406) (xy 343.581228 -240.858802) (xy 343.562686 -240.78311)
			(xy 343.560146 -240.771426) (xy 343.539318 -240.745264) (xy 343.535508 -240.740438) (xy 343.526618 -240.733326)
			(xy 343.460578 -240.702592) (xy 343.43594 -240.703354) (xy 343.425272 -240.70945) (xy 343.40157 -240.722124)
			(xy 343.350923 -240.740108) (xy 343.297966 -240.749274) (xy 343.271094 -240.749836) (xy 343.246284 -240.749349)
			(xy 343.197274 -240.741586) (xy 343.150082 -240.726251) (xy 343.10587 -240.703723) (xy 343.065726 -240.674556)
			(xy 343.03064 -240.639469) (xy 343.001474 -240.599325) (xy 342.978947 -240.555112) (xy 342.963613 -240.50792)
			(xy 342.955851 -240.45891) (xy 342.955851 -240.40929) (xy 342.963613 -240.36028) (xy 342.978947 -240.313088)
			(xy 343.001474 -240.268875) (xy 343.03064 -240.228731) (xy 343.065726 -240.193644) (xy 343.10587 -240.164477)
			(xy 343.150082 -240.141949) (xy 343.197274 -240.126614) (xy 343.246284 -240.118851) (xy 343.271094 -240.118392)
			(xy 343.297967 -240.118952) (xy 343.35093 -240.128098) (xy 343.401575 -240.146093) (xy 343.425272 -240.158778)
			(xy 343.43594 -240.164874) (xy 343.460578 -240.165636) (xy 343.52103 -240.137442) (xy 343.526214 -240.134836)
			(xy 343.535325 -240.127655) (xy 343.539064 -240.123218) (xy 343.539318 -240.122964) (xy 343.55278 -240.105946)
			(xy 343.556266 -240.101351) (xy 343.561272 -240.090963) (xy 343.562686 -240.085372) (xy 343.581228 -240.010696)
			(xy 343.603072 -239.933988) (xy 343.59088 -239.902238) (xy 343.576148 -239.893094) (xy 343.553519 -239.8786)
			(xy 343.513106 -239.843182) (xy 343.47927 -239.801437) (xy 343.452987 -239.754568) (xy 343.435013 -239.703927)
			(xy 343.425868 -239.650975) (xy 343.425272 -239.624108) (xy 343.425814 -239.597217) (xy 343.434926 -239.544212)
			(xy 343.452889 -239.493518) (xy 343.479182 -239.446601) (xy 343.513046 -239.404818) (xy 343.5535 -239.369378)
			(xy 343.576148 -239.354868) (xy 343.585482 -239.348516) (xy 343.597911 -239.3297) (xy 343.601079 -239.307375)
			(xy 343.598246 -239.296448) (xy 343.583006 -239.245394) (xy 343.581228 -239.23879) (xy 343.562686 -239.163098)
			(xy 343.560146 -239.151414) (xy 343.539318 -239.125252) (xy 343.535508 -239.120426) (xy 343.526618 -239.113314)
			(xy 343.460578 -239.08258) (xy 343.43594 -239.083342) (xy 343.425272 -239.089438) (xy 343.40157 -239.102112)
			(xy 343.350923 -239.120097) (xy 343.297966 -239.129264) (xy 343.271094 -239.129824) (xy 343.246285 -239.129337)
			(xy 343.197277 -239.121574) (xy 343.150087 -239.10624) (xy 343.105876 -239.083713) (xy 343.065734 -239.054547)
			(xy 343.030649 -239.019461) (xy 343.001484 -238.979319) (xy 342.978958 -238.935108) (xy 342.963625 -238.887917)
			(xy 342.955863 -238.838909) (xy 342.955863 -238.789291) (xy 342.963625 -238.740283) (xy 342.978958 -238.693092)
			(xy 343.001484 -238.648881) (xy 343.030649 -238.608739) (xy 343.065734 -238.573653) (xy 343.105876 -238.544487)
			(xy 343.150087 -238.52196) (xy 343.197277 -238.506626) (xy 343.246285 -238.498863) (xy 343.271094 -238.49838)
			(xy 343.297967 -238.49894) (xy 343.35093 -238.508086) (xy 343.401575 -238.52608) (xy 343.425272 -238.538766)
			(xy 343.43594 -238.544862) (xy 343.460578 -238.545624) (xy 343.52103 -238.51743) (xy 343.526214 -238.514823)
			(xy 343.535323 -238.507641) (xy 343.539064 -238.503206) (xy 343.539318 -238.502952) (xy 343.55278 -238.485934)
			(xy 343.556265 -238.481339) (xy 343.561268 -238.47095) (xy 343.562686 -238.46536) (xy 343.581228 -238.390684)
			(xy 343.603072 -238.313976) (xy 343.59088 -238.282226) (xy 343.576148 -238.273082) (xy 343.553519 -238.258587)
			(xy 343.513108 -238.22317) (xy 343.479274 -238.181424) (xy 343.452992 -238.134555) (xy 343.43502 -238.083914)
			(xy 343.425877 -238.030963) (xy 343.425272 -238.004096) (xy 343.425815 -237.977205) (xy 343.434929 -237.924202)
			(xy 343.452893 -237.873509) (xy 343.479187 -237.826594) (xy 343.513051 -237.784812) (xy 343.553506 -237.749374)
			(xy 343.576148 -237.734856) (xy 343.58548 -237.728503) (xy 343.597904 -237.709688) (xy 343.601067 -237.687365)
			(xy 343.598246 -237.676436) (xy 343.583006 -237.625382) (xy 343.581228 -237.618778) (xy 343.562686 -237.543086)
			(xy 343.560146 -237.531402) (xy 343.539318 -237.50524) (xy 343.535508 -237.500414) (xy 343.526618 -237.493302)
			(xy 343.460578 -237.462568) (xy 343.43594 -237.46333) (xy 343.425272 -237.469426) (xy 343.40157 -237.482101)
			(xy 343.350924 -237.500086) (xy 343.297966 -237.509253) (xy 343.271094 -237.509812) (xy 343.246286 -237.509325)
			(xy 343.19728 -237.501562) (xy 343.150091 -237.486229) (xy 343.105883 -237.463703) (xy 343.065742 -237.434538)
			(xy 343.030658 -237.399453) (xy 343.001494 -237.359312) (xy 342.978969 -237.315103) (xy 342.963636 -237.267915)
			(xy 342.955875 -237.218908) (xy 342.955875 -237.169292) (xy 342.963636 -237.120285) (xy 342.978969 -237.073097)
			(xy 343.001494 -237.028888) (xy 343.030658 -236.988747) (xy 343.065742 -236.953662) (xy 343.105883 -236.924497)
			(xy 343.150091 -236.901971) (xy 343.19728 -236.886638) (xy 343.246286 -236.878875) (xy 343.271094 -236.878368)
			(xy 343.297967 -236.878928) (xy 343.35093 -236.888074) (xy 343.401576 -236.906067) (xy 343.425272 -236.918754)
			(xy 343.43594 -236.92485) (xy 343.460578 -236.925612) (xy 343.52103 -236.897418) (xy 343.526213 -236.894811)
			(xy 343.535321 -236.887627) (xy 343.539064 -236.883194) (xy 343.539318 -236.88294) (xy 343.55278 -236.865922)
			(xy 343.556264 -236.861327) (xy 343.561265 -236.850937) (xy 343.562686 -236.845348) (xy 343.581228 -236.770672)
			(xy 343.603072 -236.693964) (xy 343.59088 -236.662214) (xy 343.576148 -236.65307) (xy 343.55352 -236.638575)
			(xy 343.51311 -236.603157) (xy 343.479278 -236.561411) (xy 343.452997 -236.514542) (xy 343.435027 -236.463902)
			(xy 343.425887 -236.410951) (xy 343.425272 -236.384084) (xy 343.425816 -236.357194) (xy 343.434932 -236.304191)
			(xy 343.452897 -236.2535) (xy 343.479192 -236.206586) (xy 343.513057 -236.164807) (xy 343.553511 -236.12937)
			(xy 343.576148 -236.114844) (xy 343.585478 -236.108491) (xy 343.597897 -236.089676) (xy 343.601056 -236.067355)
			(xy 343.598246 -236.056424) (xy 343.583006 -236.00537) (xy 343.581228 -235.998766) (xy 343.562686 -235.923074)
			(xy 343.560146 -235.91139) (xy 343.539318 -235.885228) (xy 343.535508 -235.880402) (xy 343.526618 -235.87329)
			(xy 343.460578 -235.842556) (xy 343.43594 -235.843318) (xy 343.425272 -235.849414) (xy 343.40157 -235.862089)
			(xy 343.350924 -235.880076) (xy 343.297966 -235.889243) (xy 343.271094 -235.8898) (xy 343.246286 -235.889313)
			(xy 343.197282 -235.881551) (xy 343.150096 -235.866218) (xy 343.105889 -235.843693) (xy 343.06575 -235.814529)
			(xy 343.030667 -235.779446) (xy 343.001504 -235.739306) (xy 342.97898 -235.695099) (xy 342.963648 -235.647912)
			(xy 342.955887 -235.598908) (xy 342.955887 -235.549292) (xy 342.963648 -235.500288) (xy 342.97898 -235.453101)
			(xy 343.001504 -235.408894) (xy 343.030667 -235.368754) (xy 343.06575 -235.333671) (xy 343.105889 -235.304507)
			(xy 343.150096 -235.281982) (xy 343.197282 -235.266649) (xy 343.246286 -235.258887) (xy 343.271094 -235.258356)
			(xy 343.297967 -235.258916) (xy 343.35093 -235.268061) (xy 343.401576 -235.286054) (xy 343.425272 -235.298742)
			(xy 343.43594 -235.304838) (xy 343.460578 -235.3056) (xy 343.52103 -235.277406) (xy 343.526213 -235.274798)
			(xy 343.535319 -235.267614) (xy 343.539064 -235.263182) (xy 343.539318 -235.262928) (xy 343.55278 -235.24591)
			(xy 343.556263 -235.241314) (xy 343.561262 -235.230924) (xy 343.562686 -235.225336) (xy 343.581228 -235.15066)
			(xy 343.603072 -235.073952) (xy 343.59088 -235.042202) (xy 343.576148 -235.033058) (xy 343.553515 -235.018565)
			(xy 343.513095 -234.98315) (xy 343.479251 -234.941406) (xy 343.452958 -234.894538) (xy 343.434974 -234.843896)
			(xy 343.425819 -234.790941) (xy 343.425272 -234.764072) (xy 343.425809 -234.737178) (xy 343.434912 -234.684167)
			(xy 343.452868 -234.633465) (xy 343.479157 -234.586539) (xy 343.513018 -234.544748) (xy 343.553471 -234.509299)
			(xy 343.576148 -234.494832) (xy 343.585476 -234.488478) (xy 343.597891 -234.469664) (xy 343.601045 -234.447345)
			(xy 343.598246 -234.436412) (xy 343.583006 -234.385358) (xy 343.581228 -234.378754) (xy 343.562686 -234.303062)
			(xy 343.560146 -234.291378) (xy 343.539318 -234.265216) (xy 343.535508 -234.26039) (xy 343.526618 -234.253278)
			(xy 343.460578 -234.222544) (xy 343.43594 -234.223306) (xy 343.425272 -234.229402) (xy 343.40157 -234.242078)
			(xy 343.350924 -234.260065) (xy 343.297966 -234.269232) (xy 343.271094 -234.269788) (xy 343.246287 -234.269301)
			(xy 343.197285 -234.261539) (xy 343.150101 -234.246207) (xy 343.105895 -234.223682) (xy 343.065758 -234.19452)
			(xy 343.030676 -234.159438) (xy 343.001515 -234.1193) (xy 342.978991 -234.075094) (xy 342.96366 -234.027909)
			(xy 342.955899 -233.978907) (xy 342.955899 -233.929293) (xy 342.96366 -233.880291) (xy 342.978991 -233.833106)
			(xy 343.001515 -233.7889) (xy 343.030676 -233.748762) (xy 343.065758 -233.71368) (xy 343.105895 -233.684518)
			(xy 343.150101 -233.661993) (xy 343.197285 -233.646661) (xy 343.246287 -233.638899) (xy 343.271094 -233.638344)
			(xy 343.297967 -233.638904) (xy 343.35093 -233.648049) (xy 343.401577 -233.666041) (xy 343.425272 -233.67873)
			(xy 343.43594 -233.684826) (xy 343.460578 -233.685588) (xy 343.52103 -233.657394) (xy 343.526212 -233.654786)
			(xy 343.535318 -233.6476) (xy 343.539064 -233.64317) (xy 343.539318 -233.642916) (xy 343.55278 -233.625898)
			(xy 343.556262 -233.621302) (xy 343.561258 -233.610911) (xy 343.562686 -233.605324) (xy 343.581228 -233.530648)
			(xy 343.603072 -233.45394) (xy 343.59088 -233.42219) (xy 343.576148 -233.413046) (xy 343.553516 -233.398553)
			(xy 343.513098 -233.363137) (xy 343.479255 -233.321393) (xy 343.452963 -233.274524) (xy 343.434982 -233.223883)
			(xy 343.425828 -233.170929) (xy 343.425272 -233.14406) (xy 343.42581 -233.117167) (xy 343.434915 -233.064156)
			(xy 343.452872 -233.013456) (xy 343.479161 -232.966532) (xy 343.513023 -232.924742) (xy 343.553477 -232.889295)
			(xy 343.576148 -232.87482) (xy 343.585474 -232.868466) (xy 343.597884 -232.849652) (xy 343.601034 -232.827335)
			(xy 343.598246 -232.8164) (xy 343.583006 -232.765346) (xy 343.581228 -232.758742) (xy 343.562686 -232.68305)
			(xy 343.560146 -232.671366) (xy 343.539318 -232.645204) (xy 343.535508 -232.640378) (xy 343.526618 -232.633266)
			(xy 343.460578 -232.602532) (xy 343.43594 -232.603294) (xy 343.425272 -232.60939) (xy 343.40157 -232.622066)
			(xy 343.350924 -232.640054) (xy 343.297966 -232.649222) (xy 343.271094 -232.649776) (xy 343.246288 -232.649289)
			(xy 343.197288 -232.641527) (xy 343.150105 -232.626196) (xy 343.105901 -232.603672) (xy 343.065765 -232.574511)
			(xy 343.030685 -232.53943) (xy 343.001525 -232.499293) (xy 342.979002 -232.455089) (xy 342.963671 -232.407906)
			(xy 342.955911 -232.358906) (xy 342.955911 -232.309294) (xy 342.963671 -232.260294) (xy 342.979002 -232.213111)
			(xy 343.001525 -232.168907) (xy 343.030685 -232.12877) (xy 343.065765 -232.093689) (xy 343.105901 -232.064528)
			(xy 343.150105 -232.042004) (xy 343.197288 -232.026673) (xy 343.246288 -232.018911) (xy 343.271094 -232.018332)
			(xy 343.299034 -232.019602) (xy 343.31148 -232.020872) (xy 343.334594 -232.010966) (xy 343.390728 -231.94264)
			(xy 343.398135 -231.932634) (xy 343.403054 -231.908259) (xy 343.400126 -231.896158) (xy 343.386156 -231.843834)
			(xy 343.373778 -231.791488) (xy 343.356493 -231.685312) (xy 343.347819 -231.578089) (xy 343.347294 -231.524302)
			(xy 343.347294 -231.523286) (xy 343.347761 -231.472282) (xy 343.35552 -231.370571) (xy 343.362788 -231.320086)
			(xy 343.369683 -231.277622) (xy 343.388241 -231.19361) (xy 343.399872 -231.152192) (xy 343.403428 -231.14)
			(xy 343.398602 -231.11587) (xy 343.337642 -231.04094) (xy 343.333653 -231.036319) (xy 343.323894 -231.02899)
			(xy 343.318338 -231.026462) (xy 343.306593 -231.028059) (xy 343.282947 -231.029712) (xy 343.271094 -231.029764)
			(xy 343.246305 -231.029277) (xy 343.197338 -231.021521) (xy 343.150186 -231.006199) (xy 343.106012 -230.983691)
			(xy 343.065903 -230.954549) (xy 343.030847 -230.919492) (xy 343.001706 -230.879382) (xy 342.979198 -230.835208)
			(xy 342.963878 -230.788057) (xy 342.956122 -230.739089) (xy 342.956122 -230.689511) (xy 342.963878 -230.640543)
			(xy 342.979198 -230.593392) (xy 343.001706 -230.549218) (xy 343.030847 -230.509108) (xy 343.065903 -230.474051)
			(xy 343.106012 -230.444909) (xy 343.150186 -230.422401) (xy 343.197338 -230.407079) (xy 343.246305 -230.399323)
			(xy 343.271094 -230.398828) (xy 343.297957 -230.399345) (xy 343.350914 -230.408404) (xy 343.401567 -230.426312)
			(xy 343.425272 -230.43896) (xy 343.43594 -230.445056) (xy 343.460578 -230.445818) (xy 343.52103 -230.417624)
			(xy 343.526213 -230.415017) (xy 343.535322 -230.407834) (xy 343.539064 -230.4034) (xy 343.559892 -230.377238)
			(xy 343.562432 -230.365808) (xy 343.570069 -230.33196) (xy 343.587856 -230.264881) (xy 343.597992 -230.231696)
			(xy 343.600821 -230.220782) (xy 343.597774 -230.198472) (xy 343.585468 -230.179615) (xy 343.576148 -230.173276)
			(xy 343.553502 -230.158769) (xy 343.513065 -230.123317) (xy 343.479216 -230.08153) (xy 343.452933 -230.034613)
			(xy 343.434976 -229.983923) (xy 343.425862 -229.930924) (xy 343.425272 -229.904036) (xy 343.425835 -229.877167)
			(xy 343.434978 -229.824212) (xy 343.452956 -229.773569) (xy 343.479249 -229.726702) (xy 343.513098 -229.684964)
			(xy 343.553526 -229.649559) (xy 343.576148 -229.63505) (xy 343.585495 -229.628541) (xy 343.597812 -229.609419)
			(xy 343.600719 -229.586859) (xy 343.597738 -229.575868) (xy 343.594944 -229.566978) (xy 343.594944 -229.565708)
			(xy 343.592912 -229.558342) (xy 343.58443 -229.529763) (xy 343.569312 -229.472091) (xy 343.562686 -229.443026)
			(xy 343.560146 -229.431596) (xy 343.539318 -229.405434) (xy 343.535508 -229.400608) (xy 343.526618 -229.393496)
			(xy 343.460578 -229.362762) (xy 343.43594 -229.363524) (xy 343.425272 -229.36962) (xy 343.401561 -229.382252)
			(xy 343.350907 -229.400148) (xy 343.297955 -229.409218) (xy 343.271094 -229.409752) (xy 343.246306 -229.409265)
			(xy 343.19734 -229.401509) (xy 343.150191 -229.386188) (xy 343.106019 -229.363681) (xy 343.065911 -229.33454)
			(xy 343.030856 -229.299484) (xy 343.001716 -229.259376) (xy 342.979209 -229.215203) (xy 342.96389 -229.168054)
			(xy 342.956134 -229.119088) (xy 342.956134 -229.069512) (xy 342.96389 -229.020546) (xy 342.979209 -228.973397)
			(xy 343.001716 -228.929224) (xy 343.030856 -228.889116) (xy 343.065911 -228.85406) (xy 343.106019 -228.824919)
			(xy 343.150191 -228.802412) (xy 343.19734 -228.787091) (xy 343.246306 -228.779335) (xy 343.271094 -228.778816)
			(xy 343.297957 -228.779334) (xy 343.350912 -228.788395) (xy 343.401563 -228.806308) (xy 343.425272 -228.818948)
			(xy 343.43594 -228.825044) (xy 343.460578 -228.825806) (xy 343.52103 -228.797612) (xy 343.526213 -228.795004)
			(xy 343.53532 -228.787821) (xy 343.539064 -228.783388) (xy 343.539318 -228.783134) (xy 343.55278 -228.766116)
			(xy 343.556264 -228.76152) (xy 343.561263 -228.751131) (xy 343.562686 -228.745542) (xy 343.581228 -228.670866)
			(xy 343.603072 -228.594158) (xy 343.59088 -228.562408) (xy 343.576148 -228.553264) (xy 343.55352 -228.538769)
			(xy 343.513111 -228.503351) (xy 343.479279 -228.461605) (xy 343.453 -228.414736) (xy 343.435031 -228.364095)
			(xy 343.425891 -228.311144) (xy 343.425272 -228.284278) (xy 343.425816 -228.257388) (xy 343.434933 -228.204386)
			(xy 343.452899 -228.153696) (xy 343.479195 -228.106783) (xy 343.513059 -228.065004) (xy 343.553514 -228.029568)
			(xy 343.576148 -228.015038) (xy 343.585477 -228.008684) (xy 343.597894 -227.98987) (xy 343.60105 -227.96755)
			(xy 343.598246 -227.956618) (xy 343.583006 -227.905564) (xy 343.581228 -227.89896) (xy 343.562686 -227.823268)
			(xy 343.560146 -227.811584) (xy 343.539318 -227.785422) (xy 343.535508 -227.780596) (xy 343.526618 -227.773484)
			(xy 343.460578 -227.74275) (xy 343.43594 -227.743512) (xy 343.425272 -227.749608) (xy 343.401561 -227.762241)
			(xy 343.350907 -227.780137) (xy 343.297955 -227.789207) (xy 343.271094 -227.78974) (xy 343.246307 -227.789253)
			(xy 343.197343 -227.781497) (xy 343.150196 -227.766177) (xy 343.106025 -227.74367) (xy 343.065919 -227.714531)
			(xy 343.030865 -227.679476) (xy 343.001726 -227.63937) (xy 342.97922 -227.595199) (xy 342.963901 -227.548051)
			(xy 342.956146 -227.499087) (xy 342.956146 -227.449513) (xy 342.963901 -227.400549) (xy 342.97922 -227.353401)
			(xy 343.001726 -227.30923) (xy 343.030865 -227.269124) (xy 343.065919 -227.234069) (xy 343.106025 -227.20493)
			(xy 343.150196 -227.182423) (xy 343.197343 -227.167103) (xy 343.246307 -227.159347) (xy 343.271094 -227.158804)
			(xy 343.297957 -227.159322) (xy 343.350912 -227.168383) (xy 343.401564 -227.186295) (xy 343.425272 -227.198936)
			(xy 343.43594 -227.205032) (xy 343.460578 -227.205794) (xy 343.52103 -227.1776) (xy 343.526213 -227.174992)
			(xy 343.535319 -227.167807) (xy 343.539064 -227.163376) (xy 343.539318 -227.163122) (xy 343.55278 -227.146104)
			(xy 343.556263 -227.141508) (xy 343.56126 -227.131118) (xy 343.562686 -227.12553) (xy 343.581228 -227.050854)
			(xy 343.603072 -226.974146) (xy 343.59088 -226.942396) (xy 343.576148 -226.933252) (xy 343.553516 -226.918759)
			(xy 343.513097 -226.883343) (xy 343.479253 -226.841599) (xy 343.452961 -226.794731) (xy 343.434978 -226.744089)
			(xy 343.425824 -226.691135) (xy 343.425272 -226.664266) (xy 343.425809 -226.637372) (xy 343.434913 -226.584361)
			(xy 343.45287 -226.53366) (xy 343.479159 -226.486735) (xy 343.51302 -226.444945) (xy 343.553474 -226.409497)
			(xy 343.576148 -226.395026) (xy 343.585475 -226.388672) (xy 343.597888 -226.369858) (xy 343.601039 -226.34754)
			(xy 343.598246 -226.336606) (xy 343.583006 -226.285552) (xy 343.581228 -226.278948) (xy 343.562686 -226.203256)
			(xy 343.560146 -226.191572) (xy 343.539318 -226.16541) (xy 343.535508 -226.160584) (xy 343.526618 -226.153472)
			(xy 343.460578 -226.122738) (xy 343.43594 -226.1235) (xy 343.425272 -226.129596) (xy 343.401561 -226.142229)
			(xy 343.350907 -226.160126) (xy 343.297955 -226.169196) (xy 343.271094 -226.169728) (xy 343.246308 -226.169241)
			(xy 343.197346 -226.161486) (xy 343.1502 -226.146166) (xy 343.106031 -226.12366) (xy 343.065927 -226.094522)
			(xy 343.030874 -226.059469) (xy 343.001737 -226.019364) (xy 342.979232 -225.975194) (xy 342.963913 -225.928048)
			(xy 342.956158 -225.879086) (xy 342.956158 -225.829514) (xy 342.963913 -225.780552) (xy 342.979232 -225.733406)
			(xy 343.001737 -225.689236) (xy 343.030874 -225.649131) (xy 343.065927 -225.614078) (xy 343.106031 -225.58494)
			(xy 343.1502 -225.562434) (xy 343.197346 -225.547114) (xy 343.246308 -225.539359) (xy 343.271094 -225.538792)
			(xy 343.297957 -225.53931) (xy 343.350913 -225.54837) (xy 343.401564 -225.566282) (xy 343.425272 -225.578924)
			(xy 343.43594 -225.58502) (xy 343.460578 -225.585782) (xy 343.52103 -225.557588) (xy 343.526212 -225.554979)
			(xy 343.535317 -225.547793) (xy 343.539064 -225.543364) (xy 343.539318 -225.54311) (xy 343.55278 -225.526092)
			(xy 343.556271 -225.521499) (xy 343.561285 -225.511113) (xy 343.562686 -225.505518) (xy 343.581228 -225.430842)
			(xy 343.5985 -225.370136) (xy 343.599008 -225.368612) (xy 343.601802 -225.359976) (xy 343.59977 -225.33864)
			(xy 343.586054 -225.314764) (xy 343.578942 -225.305112) (xy 343.575132 -225.301048) (xy 343.570052 -225.297492)
			(xy 343.569798 -225.297238) (xy 343.549489 -225.282903) (xy 343.513381 -225.248744) (xy 343.48328 -225.209188)
			(xy 343.459981 -225.16528) (xy 343.4441 -225.118179) (xy 343.436055 -225.069128) (xy 343.436059 -225.019421)
			(xy 343.444112 -224.970371) (xy 343.460001 -224.923273) (xy 343.483307 -224.879369) (xy 343.513415 -224.839818)
			(xy 343.54953 -224.805664) (xy 343.569798 -224.79127) (xy 343.570052 -224.791016) (xy 343.575132 -224.78746)
			(xy 343.578942 -224.783396) (xy 343.586054 -224.773744) (xy 343.594436 -224.759012) (xy 343.596952 -224.754337)
			(xy 343.600153 -224.744217) (xy 343.600786 -224.738946) (xy 343.601802 -224.728786) (xy 343.59977 -224.722182)
			(xy 343.59977 -224.72142) (xy 343.5985 -224.717356) (xy 343.583006 -224.66554) (xy 343.581228 -224.658936)
			(xy 343.562686 -224.583244) (xy 343.560146 -224.57156) (xy 343.539318 -224.545398) (xy 343.535508 -224.540826)
			(xy 343.526364 -224.53346) (xy 343.449402 -224.497646) (xy 343.42578 -224.498408) (xy 343.415112 -224.503996)
			(xy 343.392886 -224.515262) (xy 343.345682 -224.531221) (xy 343.296516 -224.539315) (xy 343.271602 -224.53981)
			(xy 343.26576 -224.53981) (xy 343.252044 -224.539048) (xy 343.226518 -224.536937) (xy 343.176649 -224.525269)
			(xy 343.129427 -224.505442) (xy 343.086176 -224.478012) (xy 343.048109 -224.443748) (xy 343.016296 -224.403612)
			(xy 342.991627 -224.358729) (xy 342.974795 -224.310358) (xy 342.966272 -224.259856) (xy 342.965786 -224.234248)
			(xy 342.966234 -224.210599) (xy 342.973533 -224.163867) (xy 342.98795 -224.118819) (xy 343.00914 -224.076533)
			(xy 343.036595 -224.038018) (xy 343.069659 -224.004197) (xy 343.107543 -223.975877) (xy 343.149339 -223.953736)
			(xy 343.194049 -223.938303) (xy 343.240604 -223.929948) (xy 343.264236 -223.92894) (xy 343.264744 -223.92894)
			(xy 343.271602 -223.928686) (xy 343.296526 -223.92922) (xy 343.345702 -223.937391) (xy 343.3929 -223.953435)
			(xy 343.415112 -223.964754) (xy 343.42578 -223.970596) (xy 343.449402 -223.971104) (xy 343.52103 -223.937576)
			(xy 343.526211 -223.934966) (xy 343.535315 -223.92778) (xy 343.539064 -223.923352) (xy 343.539318 -223.923098)
			(xy 343.55278 -223.90608) (xy 343.55627 -223.901487) (xy 343.561282 -223.8911) (xy 343.562686 -223.885506)
			(xy 343.581228 -223.81083) (xy 343.5985 -223.750124) (xy 343.599008 -223.7486) (xy 343.601802 -223.739964)
			(xy 343.59977 -223.718628) (xy 343.586054 -223.694752) (xy 343.578942 -223.6851) (xy 343.575132 -223.681036)
			(xy 343.570052 -223.67748) (xy 343.569798 -223.677226) (xy 343.549482 -223.662891) (xy 343.513359 -223.628729)
			(xy 343.483245 -223.589169) (xy 343.459934 -223.545254) (xy 343.444041 -223.498144) (xy 343.435986 -223.449083)
			(xy 343.435983 -223.399364) (xy 343.44403 -223.350302) (xy 343.459915 -223.303189) (xy 343.483219 -223.259271)
			(xy 343.513328 -223.219706) (xy 343.549446 -223.185538) (xy 343.569798 -223.171258) (xy 343.570052 -223.171004)
			(xy 343.575132 -223.167448) (xy 343.578942 -223.163384) (xy 343.586054 -223.153732) (xy 343.594436 -223.139)
			(xy 343.596951 -223.134325) (xy 343.600149 -223.124204) (xy 343.600786 -223.118934) (xy 343.601802 -223.108774)
			(xy 343.59977 -223.10217) (xy 343.59977 -223.101408) (xy 343.5985 -223.097344) (xy 343.583006 -223.045528)
			(xy 343.581228 -223.038924) (xy 343.562686 -222.963232) (xy 343.560146 -222.951548) (xy 343.539318 -222.925386)
			(xy 343.535508 -222.920814) (xy 343.526364 -222.913448) (xy 343.449402 -222.877634) (xy 343.42578 -222.878396)
			(xy 343.415112 -222.883984) (xy 343.392886 -222.895251) (xy 343.345682 -222.91121) (xy 343.296516 -222.919304)
			(xy 343.271602 -222.919798) (xy 343.26576 -222.919798) (xy 343.252044 -222.919036) (xy 343.226518 -222.916925)
			(xy 343.17665 -222.905257) (xy 343.129429 -222.88543) (xy 343.086179 -222.858) (xy 343.048114 -222.823736)
			(xy 343.016301 -222.783599) (xy 342.991634 -222.738716) (xy 342.974804 -222.690345) (xy 342.966283 -222.639844)
			(xy 342.965786 -222.614236) (xy 342.966234 -222.590587) (xy 342.973536 -222.543857) (xy 342.987954 -222.498811)
			(xy 343.009144 -222.456526) (xy 343.036599 -222.418013) (xy 343.069663 -222.384193) (xy 343.107546 -222.355875)
			(xy 343.149342 -222.333735) (xy 343.194051 -222.318303) (xy 343.240604 -222.309948) (xy 343.264236 -222.308928)
			(xy 343.264744 -222.308928) (xy 343.271602 -222.308674) (xy 343.296526 -222.309208) (xy 343.345701 -222.317381)
			(xy 343.392897 -222.333429) (xy 343.415112 -222.344742) (xy 343.42578 -222.350584) (xy 343.449402 -222.351092)
			(xy 343.52103 -222.317564) (xy 343.526211 -222.314954) (xy 343.535313 -222.307766) (xy 343.539064 -222.30334)
			(xy 343.539318 -222.303086) (xy 343.560146 -222.276924) (xy 343.562686 -222.26524) (xy 343.57589 -222.207645)
			(xy 343.609573 -222.094374) (xy 343.651391 -221.983848) (xy 343.701125 -221.87665) (xy 343.75851 -221.773346)
			(xy 343.823245 -221.674481) (xy 343.894988 -221.580578) (xy 343.93378 -221.536006) (xy 343.939876 -221.528894)
			(xy 343.94648 -221.511622) (xy 343.94648 -221.39783) (xy 343.945464 -221.39275) (xy 343.934992 -221.338745)
			(xy 343.923672 -221.229315) (xy 343.922858 -221.17431) (xy 343.922858 -221.13494) (xy 343.922644 -221.12813)
			(xy 343.919042 -221.114995) (xy 343.915746 -221.109032) (xy 343.765378 -220.857064) (xy 343.763049 -220.853339)
			(xy 343.757301 -220.846695) (xy 343.753948 -220.843856) (xy 340.419944 -218.110308) (xy 340.393782 -218.105736)
			(xy 340.381082 -218.110308) (xy 340.379812 -218.110816) (xy 340.375748 -218.112086) (xy 340.368382 -218.11615)
			(xy 340.361778 -218.119198) (xy 340.335542 -218.131432) (xy 340.280299 -218.148729) (xy 340.223081 -218.157503)
			(xy 340.194138 -218.15806) (xy 340.16424 -218.157474) (xy 340.105177 -218.148139) (xy 340.048292 -218.129707)
			(xy 339.994978 -218.102629) (xy 339.946539 -218.067568) (xy 339.90416 -218.025382) (xy 339.886036 -218.001596)
			(xy 339.880956 -217.994484) (xy 339.859366 -217.980006) (xy 339.852 -217.974926) (xy 339.813392 -217.96502)
			(xy 339.795104 -217.967052) (xy 339.786468 -217.971624) (xy 339.759049 -217.985478) (xy 339.701601 -218.007246)
			(xy 339.641951 -218.021939) (xy 339.580965 -218.029342) (xy 339.550248 -218.02979) (xy 339.516072 -218.029239)
			(xy 339.448337 -218.020089) (xy 339.382437 -218.001948) (xy 339.319562 -217.975142) (xy 339.260844 -217.940155)
			(xy 339.233764 -217.9193) (xy 339.227414 -217.91422) (xy 339.205062 -217.906092) (xy 339.200883 -217.904681)
			(xy 339.192199 -217.903146) (xy 339.18779 -217.903044) (xy 338.896706 -217.903044) (xy 338.892294 -217.903127)
			(xy 338.883604 -217.904652) (xy 338.879434 -217.906092) (xy 338.857082 -217.91422) (xy 338.850732 -217.9193)
			(xy 338.823637 -217.940133) (xy 338.764923 -217.975118) (xy 338.70205 -218.001922) (xy 338.636154 -218.020062)
			(xy 338.568422 -218.029211) (xy 338.534248 -218.02979) (xy 338.505664 -218.029399) (xy 338.448858 -218.02298)
			(xy 338.39313 -218.010229) (xy 338.339185 -217.991307) (xy 338.313268 -217.979244) (xy 338.307172 -217.976196)
			(xy 338.297774 -217.971624) (xy 338.27466 -217.965528) (xy 338.261706 -217.967052) (xy 338.24164 -217.971878)
			(xy 338.237904 -217.972856) (xy 338.230759 -217.975786) (xy 338.227416 -217.97772) (xy 338.224622 -217.979498)
			(xy 338.204302 -217.993722) (xy 338.199222 -218.00058) (xy 338.183783 -218.021152) (xy 338.148264 -218.058354)
			(xy 338.108067 -218.090445) (xy 338.063922 -218.116842) (xy 338.016629 -218.137065) (xy 337.967047 -218.150748)
			(xy 337.916076 -218.157643) (xy 337.890358 -218.15806) (xy 337.863112 -218.157571) (xy 337.809176 -218.149811)
			(xy 337.756893 -218.134454) (xy 337.707327 -218.111813) (xy 337.661488 -218.082349) (xy 337.620308 -218.046662)
			(xy 337.584625 -218.005479) (xy 337.555167 -217.959636) (xy 337.532532 -217.910068) (xy 337.51718 -217.857783)
			(xy 337.509426 -217.803846) (xy 337.509426 -217.749354) (xy 337.51718 -217.695417) (xy 337.532532 -217.643132)
			(xy 337.555167 -217.593564) (xy 337.584625 -217.547721) (xy 337.620308 -217.506538) (xy 337.661488 -217.470851)
			(xy 337.707327 -217.441387) (xy 337.756893 -217.418746) (xy 337.809176 -217.403389) (xy 337.863112 -217.395629)
			(xy 337.890358 -217.395044) (xy 337.89112 -217.395044) (xy 337.909914 -217.395275) (xy 337.94732 -217.398961)
			(xy 337.965796 -217.40241) (xy 337.968844 -217.403172) (xy 337.977226 -217.40368) (xy 337.984713 -217.403939)
			(xy 337.999305 -217.400578) (xy 338.005928 -217.397076) (xy 338.022184 -217.387932) (xy 338.025966 -217.385681)
			(xy 338.032737 -217.380059) (xy 338.035646 -217.376756) (xy 338.053172 -217.356182) (xy 338.056474 -217.347546)
			(xy 338.06752 -217.318492) (xy 338.095701 -217.263089) (xy 338.130428 -217.211537) (xy 338.171183 -217.164604)
			(xy 338.217357 -217.122992) (xy 338.268262 -217.087322) (xy 338.323137 -217.058126) (xy 338.381163 -217.035841)
			(xy 338.441474 -217.020799) (xy 338.503169 -217.013224) (xy 338.534248 -217.012774) (xy 338.568424 -217.013325)
			(xy 338.63616 -217.022474) (xy 338.702061 -217.040614) (xy 338.764938 -217.067417) (xy 338.823657 -217.102402)
			(xy 338.850732 -217.123264) (xy 338.857082 -217.128344) (xy 338.879434 -217.136472) (xy 338.883612 -217.137884)
			(xy 338.892297 -217.139421) (xy 338.896706 -217.13952) (xy 338.951824 -217.13952) (xy 338.965695 -217.139048)
			(xy 338.99241 -217.131573) (xy 339.016128 -217.117183) (xy 339.035096 -217.09694) (xy 339.047914 -217.072337)
			(xy 339.053637 -217.045192) (xy 339.05184 -217.017509) (xy 339.042658 -216.991331) (xy 339.026768 -216.968591)
			(xy 339.01634 -216.959434) (xy 331.469746 -210.77174) (xy 331.468222 -210.770216) (xy 325.748396 -206.080106)
			(xy 325.748142 -206.079852) (xy 325.744586 -206.076804) (xy 325.290434 -205.622652) (xy 325.280311 -205.613188)
			(xy 325.256183 -205.599581) (xy 325.229287 -205.592952) (xy 325.201599 -205.593788) (xy 325.175152 -205.602028)
			(xy 325.151889 -205.617066) (xy 325.133517 -205.637798) (xy 325.127112 -205.650084) (xy 325.115011 -205.673857)
			(xy 325.085199 -205.718092) (xy 325.049521 -205.757748) (xy 325.008671 -205.792052) (xy 324.963444 -205.820337)
			(xy 324.914721 -205.842054) (xy 324.863451 -205.856778) (xy 324.810629 -205.864223) (xy 324.783958 -205.864714)
			(xy 324.756354 -205.864223) (xy 324.701722 -205.856262) (xy 324.648808 -205.840511) (xy 324.598716 -205.817299)
			(xy 324.552492 -205.787112) (xy 324.5111 -205.750578) (xy 324.492874 -205.72984) (xy 324.483648 -205.719665)
			(xy 324.460945 -205.704224) (xy 324.434949 -205.695392) (xy 324.407539 -205.693806) (xy 324.380698 -205.699581)
			(xy 324.356366 -205.7123) (xy 324.336303 -205.731043) (xy 324.32879 -205.74254) (xy 324.31137 -205.769951)
			(xy 324.270637 -205.820538) (xy 324.2238 -205.865534) (xy 324.17162 -205.904206) (xy 324.114946 -205.935928)
			(xy 324.054697 -205.960183) (xy 323.991852 -205.976578) (xy 323.927432 -205.984847) (xy 323.894958 -205.985364)
			(xy 323.863682 -205.984883) (xy 323.801603 -205.977208) (xy 323.740933 -205.961978) (xy 323.682589 -205.939423)
			(xy 323.627451 -205.909884) (xy 323.576351 -205.873807) (xy 323.530061 -205.831736) (xy 323.489279 -205.784306)
			(xy 323.47154 -205.758542) (xy 323.463207 -205.746913) (xy 323.441371 -205.728446) (xy 323.415274 -205.716754)
			(xy 323.386958 -205.712753) (xy 323.358642 -205.716754) (xy 323.332545 -205.728446) (xy 323.310709 -205.746913)
			(xy 323.302376 -205.758542) (xy 323.284654 -205.78432) (xy 323.24388 -205.831761) (xy 323.197592 -205.873841)
			(xy 323.146491 -205.909922) (xy 323.091348 -205.939461) (xy 323.032998 -205.962011) (xy 322.972321 -205.977229)
			(xy 322.910236 -205.984888) (xy 322.878958 -205.985364) (xy 322.846983 -205.98486) (xy 322.783537 -205.97684)
			(xy 322.721596 -205.960931) (xy 322.662137 -205.937386) (xy 322.606098 -205.906574) (xy 322.554363 -205.868982)
			(xy 322.507747 -205.825203) (xy 322.466984 -205.775926) (xy 322.432719 -205.721929) (xy 322.405492 -205.664064)
			(xy 322.385731 -205.603243) (xy 322.373748 -205.540425) (xy 322.369733 -205.4766) (xy 322.373748 -205.412775)
			(xy 322.385731 -205.349957) (xy 322.405492 -205.289136) (xy 322.432719 -205.231271) (xy 322.466984 -205.177274)
			(xy 322.507747 -205.127997) (xy 322.554363 -205.084218) (xy 322.606098 -205.046626) (xy 322.662137 -205.015814)
			(xy 322.721596 -204.992269) (xy 322.783537 -204.97636) (xy 322.846983 -204.96834) (xy 322.878958 -204.96784)
			(xy 322.910234 -204.968321) (xy 322.972315 -204.975998) (xy 323.032985 -204.991227) (xy 323.091331 -205.01378)
			(xy 323.146472 -205.043317) (xy 323.197575 -205.079391) (xy 323.24387 -205.121458) (xy 323.284658 -205.168884)
			(xy 323.302376 -205.194662) (xy 323.310709 -205.206291) (xy 323.332545 -205.224758) (xy 323.358642 -205.23645)
			(xy 323.386958 -205.240451) (xy 323.415274 -205.23645) (xy 323.441371 -205.224758) (xy 323.463207 -205.206291)
			(xy 323.47154 -205.194662) (xy 323.489262 -205.168885) (xy 323.530036 -205.121444) (xy 323.576324 -205.079366)
			(xy 323.627426 -205.043285) (xy 323.682569 -205.013748) (xy 323.740919 -204.9912) (xy 323.801595 -204.975983)
			(xy 323.86368 -204.968326) (xy 323.894958 -204.96784) (xy 323.927884 -204.968358) (xy 323.993187 -204.976854)
			(xy 324.056845 -204.99371) (xy 324.117795 -205.018644) (xy 324.175016 -205.051238) (xy 324.22755 -205.090947)
			(xy 324.274517 -205.137105) (xy 324.315133 -205.188941) (xy 324.332346 -205.217014) (xy 324.339752 -205.228589)
			(xy 324.359573 -205.247608) (xy 324.383743 -205.260662) (xy 324.410515 -205.266809) (xy 324.437958 -205.265606)
			(xy 324.46409 -205.257139) (xy 324.487024 -205.24202) (xy 324.49643 -205.232) (xy 324.513488 -205.213106)
			(xy 324.551761 -205.179545) (xy 324.594143 -205.151351) (xy 324.616826 -205.139798) (xy 324.629074 -205.133327)
			(xy 324.649809 -205.114977) (xy 324.66485 -205.09173) (xy 324.673093 -205.065296) (xy 324.67393 -205.03762)
			(xy 324.6673 -205.010736) (xy 324.65369 -204.986623) (xy 324.644258 -204.976476) (xy 323.559424 -203.891642)
			(xy 323.555614 -203.888086) (xy 318.312292 -199.588882) (xy 318.30899 -199.586342) (xy 318.296644 -199.578423)
			(xy 318.268773 -199.569326) (xy 318.239466 -199.568509) (xy 318.211132 -199.57604) (xy 318.186098 -199.5913)
			(xy 318.175894 -199.601836) (xy 318.155198 -199.623979) (xy 318.109412 -199.663696) (xy 318.059234 -199.697695)
			(xy 318.005374 -199.725495) (xy 317.948594 -199.746704) (xy 317.889697 -199.761021) (xy 317.829518 -199.768243)
			(xy 317.799212 -199.768714) (xy 317.798958 -199.768714) (xy 317.767884 -199.768246) (xy 317.706199 -199.76067)
			(xy 317.645896 -199.745635) (xy 317.587875 -199.723366) (xy 317.532998 -199.694195) (xy 317.482084 -199.658555)
			(xy 317.435891 -199.616978) (xy 317.395106 -199.570084) (xy 317.360339 -199.51857) (xy 317.345822 -199.491092)
			(xy 317.33848 -199.477815) (xy 317.317442 -199.455977) (xy 317.290909 -199.441298) (xy 317.261231 -199.435077)
			(xy 317.231037 -199.437865) (xy 317.21679 -199.443086) (xy 317.192116 -199.452759) (xy 317.141211 -199.467518)
			(xy 317.11519 -199.47255) (xy 317.105929 -199.474525) (xy 317.08973 -199.484305) (xy 317.083694 -199.4916)
			(xy 317.064898 -199.516238) (xy 317.059547 -199.523874) (xy 317.054188 -199.541718) (xy 317.054484 -199.551036)
			(xy 317.055754 -199.580246) (xy 317.055754 -199.581008) (xy 317.055254 -199.608869) (xy 317.047162 -199.664001)
			(xy 317.031137 -199.717369) (xy 317.00752 -199.767839) (xy 316.976812 -199.814336) (xy 316.939668 -199.855873)
			(xy 316.896877 -199.891565) (xy 316.849349 -199.920653) (xy 316.798096 -199.942518) (xy 316.771274 -199.95007)
			(xy 316.76043 -199.953495) (xy 316.743019 -199.968079) (xy 316.733596 -199.988743) (xy 316.733174 -200.000108)
			(xy 316.733428 -200.00341) (xy 316.735206 -200.044812) (xy 316.734729 -200.076372) (xy 316.72692 -200.139007)
			(xy 316.711424 -200.200195) (xy 316.688478 -200.258996) (xy 316.658434 -200.314508) (xy 316.621755 -200.365877)
			(xy 316.579003 -200.412314) (xy 316.530836 -200.453107) (xy 316.477993 -200.487628) (xy 316.421286 -200.515348)
			(xy 316.361585 -200.53584) (xy 316.299808 -200.548791) (xy 316.236903 -200.554001) (xy 316.173837 -200.551389)
			(xy 316.111579 -200.540997) (xy 316.051084 -200.522984) (xy 315.993282 -200.497626) (xy 315.93906 -200.465313)
			(xy 315.889251 -200.426541) (xy 315.844621 -200.381906) (xy 315.805855 -200.332094) (xy 315.773548 -200.277869)
			(xy 315.748197 -200.220063) (xy 315.73019 -200.159567) (xy 315.719805 -200.097307) (xy 315.7172 -200.034241)
			(xy 315.722417 -199.971337) (xy 315.735374 -199.909561) (xy 315.755874 -199.849863) (xy 315.7836 -199.793158)
			(xy 315.818127 -199.740319) (xy 315.858925 -199.692156) (xy 315.905367 -199.64941) (xy 315.95674 -199.612736)
			(xy 316.012255 -199.582699) (xy 316.071058 -199.559759) (xy 316.132248 -199.544269) (xy 316.194884 -199.536467)
			(xy 316.226444 -199.53605) (xy 316.234064 -199.53605) (xy 316.243208 -199.536304) (xy 316.259464 -199.530716)
			(xy 316.294516 -199.502522) (xy 316.303406 -199.489314) (xy 316.305438 -199.481186) (xy 316.31318 -199.45451)
			(xy 316.335314 -199.403566) (xy 316.364596 -199.356367) (xy 316.400407 -199.313908) (xy 316.441993 -199.277086)
			(xy 316.488474 -199.246678) (xy 316.513464 -199.234552) (xy 316.520068 -199.231504) (xy 316.530482 -199.222614)
			(xy 316.551818 -199.190102) (xy 316.554612 -199.165972) (xy 316.55004 -199.154288) (xy 316.539323 -199.125092)
			(xy 316.524274 -199.064746) (xy 316.516716 -199.003013) (xy 316.516258 -198.971916) (xy 316.51672 -198.941188)
			(xy 316.524122 -198.880178) (xy 316.53882 -198.820505) (xy 316.560599 -198.763037) (xy 316.589144 -198.708611)
			(xy 316.624037 -198.65802) (xy 316.664771 -198.612002) (xy 316.710752 -198.571226) (xy 316.76131 -198.536286)
			(xy 316.788292 -198.521574) (xy 316.800346 -198.514692) (xy 316.820497 -198.495622) (xy 316.83476 -198.471825)
			(xy 316.842079 -198.445064) (xy 316.841912 -198.417321) (xy 316.834272 -198.39065) (xy 316.819723 -198.367026)
			(xy 316.809882 -198.357236) (xy 316.807596 -198.355204) (xy 316.427104 -198.043292) (xy 316.423548 -198.040498)
			(xy 316.411746 -198.033006) (xy 316.385242 -198.024148) (xy 316.35733 -198.022799) (xy 316.330095 -198.029061)
			(xy 316.305575 -198.042466) (xy 316.285602 -198.062011) (xy 316.27167 -198.086235) (xy 316.267846 -198.09968)
			(xy 316.259665 -198.130045) (xy 316.236815 -198.188636) (xy 316.206916 -198.243963) (xy 316.170424 -198.295181)
			(xy 316.127895 -198.34151) (xy 316.07998 -198.382243) (xy 316.027409 -198.416758) (xy 315.970983 -198.444528)
			(xy 315.911565 -198.46513) (xy 315.85006 -198.47825) (xy 315.818774 -198.481442) (xy 315.804687 -198.483205)
			(xy 315.77823 -198.493468) (xy 315.75561 -198.510603) (xy 315.738566 -198.533293) (xy 315.728411 -198.559791)
			(xy 315.725926 -198.58806) (xy 315.728096 -198.602092) (xy 315.732354 -198.625739) (xy 315.736929 -198.673571)
			(xy 315.73724 -198.697596) (xy 315.73724 -198.698612) (xy 315.736738 -198.730589) (xy 315.728723 -198.794039)
			(xy 315.712818 -198.855984) (xy 315.689275 -198.915446) (xy 315.658465 -198.97149) (xy 315.620873 -199.02323)
			(xy 315.577094 -199.06985) (xy 315.527816 -199.110616) (xy 315.473818 -199.144884) (xy 315.415951 -199.172115)
			(xy 315.355127 -199.191878) (xy 315.292306 -199.203861) (xy 315.228478 -199.207877) (xy 315.16465 -199.203861)
			(xy 315.101829 -199.191878) (xy 315.041005 -199.172115) (xy 314.983138 -199.144884) (xy 314.92914 -199.110616)
			(xy 314.879862 -199.06985) (xy 314.836083 -199.02323) (xy 314.798491 -198.97149) (xy 314.767681 -198.915446)
			(xy 314.744138 -198.855984) (xy 314.728233 -198.794039) (xy 314.720218 -198.730589) (xy 314.719716 -198.698612)
			(xy 314.720179 -198.667146) (xy 314.72793 -198.604693) (xy 314.743327 -198.543674) (xy 314.766135 -198.485021)
			(xy 314.796005 -198.42963) (xy 314.832482 -198.378348) (xy 314.875007 -198.331958) (xy 314.92293 -198.291169)
			(xy 314.97552 -198.256604) (xy 315.031973 -198.228792) (xy 315.091426 -198.208158) (xy 315.15297 -198.195017)
			(xy 315.184282 -198.191882) (xy 315.198375 -198.190124) (xy 315.224846 -198.179868) (xy 315.247481 -198.162735)
			(xy 315.264537 -198.140042) (xy 315.274703 -198.113536) (xy 315.277195 -198.085257) (xy 315.27496 -198.071232)
			(xy 315.270701 -198.047585) (xy 315.266124 -197.999753) (xy 315.265816 -197.975728) (xy 315.265816 -197.974712)
			(xy 315.266347 -197.941222) (xy 315.275131 -197.87482) (xy 315.292549 -197.810145) (xy 315.318299 -197.748312)
			(xy 315.351937 -197.690391) (xy 315.371988 -197.663562) (xy 315.380253 -197.652067) (xy 315.390697 -197.625765)
			(xy 315.39352 -197.597605) (xy 315.388504 -197.569753) (xy 315.376035 -197.544348) (xy 315.357071 -197.523341)
			(xy 315.333069 -197.508347) (xy 315.305873 -197.500519) (xy 315.291724 -197.499986) (xy 314.26912 -197.499986)
			(xy 314.241942 -197.521068) (xy 314.237624 -197.538086) (xy 314.229199 -197.569101) (xy 314.205581 -197.628875)
			(xy 314.17462 -197.685197) (xy 314.136809 -197.737168) (xy 314.09275 -197.783961) (xy 314.043147 -197.82483)
			(xy 313.988789 -197.859122) (xy 313.930543 -197.886292) (xy 313.869339 -197.905906) (xy 313.837828 -197.912228)
			(xy 313.81954 -197.91553) (xy 313.796426 -197.94347) (xy 313.796426 -202.052936) (xy 313.79689 -202.062811)
			(xy 313.80434 -202.081103) (xy 313.810904 -202.088496) (xy 313.811158 -202.08875) (xy 314.656681 -202.934273)
			(xy 318.629532 -202.934273) (xy 318.629532 -202.870351) (xy 318.637543 -202.806933) (xy 318.65344 -202.745019)
			(xy 318.676972 -202.685586) (xy 318.707766 -202.629571) (xy 318.745339 -202.577856) (xy 318.789096 -202.531259)
			(xy 318.838349 -202.490514) (xy 318.89232 -202.456263) (xy 318.950159 -202.429046) (xy 319.010952 -202.409293)
			(xy 319.073742 -202.397315) (xy 319.137538 -202.393302) (xy 319.201334 -202.397315) (xy 319.264124 -202.409293)
			(xy 319.324917 -202.429046) (xy 319.382756 -202.456263) (xy 319.436727 -202.490514) (xy 319.48598 -202.531259)
			(xy 319.529737 -202.577856) (xy 319.56731 -202.629571) (xy 319.598104 -202.685586) (xy 319.621636 -202.745019)
			(xy 319.637533 -202.806933) (xy 319.645544 -202.870351) (xy 319.646046 -202.902312) (xy 319.6456 -202.930717)
			(xy 320.156072 -202.930717) (xy 320.156072 -202.866795) (xy 320.164083 -202.803377) (xy 320.17998 -202.741463)
			(xy 320.203512 -202.68203) (xy 320.234306 -202.626015) (xy 320.271879 -202.5743) (xy 320.315636 -202.527703)
			(xy 320.364889 -202.486958) (xy 320.41886 -202.452707) (xy 320.476699 -202.42549) (xy 320.537492 -202.405737)
			(xy 320.600282 -202.393759) (xy 320.664078 -202.389746) (xy 320.727874 -202.393759) (xy 320.790664 -202.405737)
			(xy 320.851457 -202.42549) (xy 320.909296 -202.452707) (xy 320.963267 -202.486958) (xy 321.01252 -202.527703)
			(xy 321.056277 -202.5743) (xy 321.09385 -202.626015) (xy 321.124644 -202.68203) (xy 321.148176 -202.741463)
			(xy 321.164073 -202.803377) (xy 321.172084 -202.866795) (xy 321.172586 -202.898756) (xy 321.172084 -202.930717)
			(xy 321.164073 -202.994135) (xy 321.148176 -203.056049) (xy 321.124644 -203.115482) (xy 321.09385 -203.171497)
			(xy 321.056277 -203.223212) (xy 321.01252 -203.269809) (xy 320.963267 -203.310554) (xy 320.909296 -203.344805)
			(xy 320.851457 -203.372022) (xy 320.790664 -203.391775) (xy 320.727874 -203.403753) (xy 320.664078 -203.407767)
			(xy 320.600282 -203.403753) (xy 320.537492 -203.391775) (xy 320.476699 -203.372022) (xy 320.41886 -203.344805)
			(xy 320.364889 -203.310554) (xy 320.315636 -203.269809) (xy 320.271879 -203.223212) (xy 320.234306 -203.171497)
			(xy 320.203512 -203.115482) (xy 320.17998 -203.056049) (xy 320.164083 -202.994135) (xy 320.156072 -202.930717)
			(xy 319.6456 -202.930717) (xy 319.645544 -202.934273) (xy 319.637533 -202.997691) (xy 319.621636 -203.059605)
			(xy 319.598104 -203.119038) (xy 319.56731 -203.175053) (xy 319.529737 -203.226768) (xy 319.48598 -203.273365)
			(xy 319.436727 -203.31411) (xy 319.382756 -203.348361) (xy 319.324917 -203.375578) (xy 319.264124 -203.395331)
			(xy 319.201334 -203.407309) (xy 319.137538 -203.411323) (xy 319.073742 -203.407309) (xy 319.010952 -203.395331)
			(xy 318.950159 -203.375578) (xy 318.89232 -203.348361) (xy 318.838349 -203.31411) (xy 318.789096 -203.273365)
			(xy 318.745339 -203.226768) (xy 318.707766 -203.175053) (xy 318.676972 -203.119038) (xy 318.65344 -203.059605)
			(xy 318.637543 -202.997691) (xy 318.629532 -202.934273) (xy 314.656681 -202.934273) (xy 317.192708 -205.4703)
			(xy 318.902841 -205.4703) (xy 318.906855 -205.406501) (xy 318.918832 -205.343709) (xy 318.938585 -205.282912)
			(xy 318.965802 -205.225071) (xy 319.000053 -205.171096) (xy 319.040798 -205.12184) (xy 319.087395 -205.078078)
			(xy 319.13911 -205.040502) (xy 319.195126 -205.009703) (xy 319.25456 -204.986167) (xy 319.316476 -204.970265)
			(xy 319.379896 -204.962248) (xy 319.411858 -204.961744) (xy 319.441876 -204.962229) (xy 319.501492 -204.969319)
			(xy 319.559858 -204.98338) (xy 319.616162 -205.004217) (xy 319.66962 -205.031541) (xy 319.719488 -205.06497)
			(xy 319.742566 -205.084172) (xy 319.749459 -205.089584) (xy 319.765823 -205.095823) (xy 319.77457 -205.096364)
			(xy 319.804288 -205.097126) (xy 319.812982 -205.096979) (xy 319.829478 -205.091522) (xy 319.836546 -205.086458)
			(xy 319.863408 -205.066278) (xy 319.921431 -205.032405) (xy 319.98341 -205.006469) (xy 320.048264 -204.988921)
			(xy 320.114865 -204.980067) (xy 320.148458 -204.979524) (xy 320.181081 -204.979996) (xy 320.245791 -204.988338)
			(xy 320.308902 -205.00489) (xy 320.369377 -205.029379) (xy 320.426222 -205.061404) (xy 320.478503 -205.100439)
			(xy 320.50228 -205.12278) (xy 320.509138 -205.129384) (xy 320.526156 -205.13675) (xy 320.613532 -205.139544)
			(xy 320.631058 -205.133702) (xy 320.638424 -205.127352) (xy 320.661392 -205.108503) (xy 320.710956 -205.075732)
			(xy 320.764004 -205.048963) (xy 320.81981 -205.028562) (xy 320.877615 -205.014806) (xy 320.936629 -205.007883)
			(xy 320.966338 -205.007464) (xy 321.000741 -205.008062) (xy 321.068916 -205.017374) (xy 321.135214 -205.035783)
			(xy 321.19843 -205.062954) (xy 321.25741 -205.098392) (xy 321.2846 -205.119478) (xy 321.29168 -205.124707)
			(xy 321.308313 -205.130421) (xy 321.317112 -205.130654) (xy 321.347084 -205.130146) (xy 321.355814 -205.129679)
			(xy 321.372181 -205.123568) (xy 321.379088 -205.118208) (xy 321.402112 -205.099213) (xy 321.451824 -205.066174)
			(xy 321.505062 -205.03918) (xy 321.561093 -205.018602) (xy 321.619147 -205.004723) (xy 321.678427 -204.997734)
			(xy 321.708272 -204.997304) (xy 321.740236 -204.997759) (xy 321.803661 -205.005768) (xy 321.865582 -205.021664)
			(xy 321.925022 -205.045195) (xy 321.981044 -205.075991) (xy 322.032764 -205.113565) (xy 322.079368 -205.157326)
			(xy 322.120118 -205.206583) (xy 322.154374 -205.260559) (xy 322.181594 -205.318402) (xy 322.20135 -205.379202)
			(xy 322.213329 -205.441998) (xy 322.217344 -205.5058) (xy 322.213329 -205.569602) (xy 322.20135 -205.632398)
			(xy 322.181594 -205.693198) (xy 322.154374 -205.751041) (xy 322.120118 -205.805017) (xy 322.079368 -205.854274)
			(xy 322.032764 -205.898035) (xy 321.981044 -205.935609) (xy 321.925022 -205.966405) (xy 321.865582 -205.989936)
			(xy 321.803661 -206.005832) (xy 321.740236 -206.013841) (xy 321.708272 -206.01432) (xy 321.673869 -206.01372)
			(xy 321.605694 -206.004409) (xy 321.539395 -205.986) (xy 321.47618 -205.95883) (xy 321.4172 -205.923392)
			(xy 321.39001 -205.902306) (xy 321.382929 -205.897079) (xy 321.366296 -205.891365) (xy 321.357498 -205.89113)
			(xy 321.327526 -205.891638) (xy 321.318794 -205.892092) (xy 321.302427 -205.898211) (xy 321.295522 -205.903576)
			(xy 321.272493 -205.922564) (xy 321.222782 -205.955605) (xy 321.169545 -205.9826) (xy 321.113515 -206.003179)
			(xy 321.055462 -206.017059) (xy 320.996183 -206.02405) (xy 320.966338 -206.02448) (xy 320.933715 -206.024009)
			(xy 320.869005 -206.015667) (xy 320.805894 -205.999115) (xy 320.745419 -205.974625) (xy 320.688574 -205.9426)
			(xy 320.636293 -205.903565) (xy 320.612516 -205.881224) (xy 320.605658 -205.87462) (xy 320.58864 -205.867254)
			(xy 320.501264 -205.86446) (xy 320.483738 -205.870302) (xy 320.476372 -205.876652) (xy 320.453394 -205.895488)
			(xy 320.403833 -205.928263) (xy 320.350788 -205.955035) (xy 320.294983 -205.97544) (xy 320.23718 -205.989197)
			(xy 320.178167 -205.996121) (xy 320.148458 -205.99654) (xy 320.118438 -205.996109) (xy 320.05882 -205.989009)
			(xy 320.000453 -205.974938) (xy 319.944149 -205.954091) (xy 319.890692 -205.926757) (xy 319.840826 -205.893318)
			(xy 319.81775 -205.874112) (xy 319.810854 -205.868704) (xy 319.794492 -205.862463) (xy 319.785746 -205.86192)
			(xy 319.756028 -205.861158) (xy 319.747335 -205.861316) (xy 319.730839 -205.866766) (xy 319.72377 -205.871826)
			(xy 319.696901 -205.891996) (xy 319.63888 -205.925871) (xy 319.576903 -205.95181) (xy 319.51205 -205.96936)
			(xy 319.445451 -205.978215) (xy 319.411858 -205.97876) (xy 319.379896 -205.978352) (xy 319.316476 -205.970335)
			(xy 319.25456 -205.954433) (xy 319.195126 -205.930897) (xy 319.13911 -205.900098) (xy 319.087395 -205.862522)
			(xy 319.040798 -205.81876) (xy 319.000053 -205.769504) (xy 318.965802 -205.715529) (xy 318.938585 -205.657688)
			(xy 318.918832 -205.596891) (xy 318.906855 -205.534099) (xy 318.902841 -205.4703) (xy 317.192708 -205.4703)
			(xy 319.257934 -207.535526) (xy 319.261337 -207.539096) (xy 319.266836 -207.547282) (xy 319.268856 -207.551782)
			(xy 319.276222 -207.569308) (xy 319.278236 -207.57381) (xy 319.283742 -207.581992) (xy 319.287144 -207.585564)
			(xy 324.681596 -212.980016) (xy 326.752462 -212.980016) (xy 326.756491 -212.837695) (xy 326.768566 -212.69583)
			(xy 326.788647 -212.554876) (xy 326.81667 -212.415283) (xy 326.852546 -212.277499) (xy 326.89616 -212.141966)
			(xy 326.947372 -212.009117) (xy 327.006018 -211.879378) (xy 327.071909 -211.753165) (xy 327.144836 -211.630882)
			(xy 327.224564 -211.51292) (xy 327.310838 -211.399658) (xy 327.403382 -211.291459) (xy 327.501898 -211.188668)
			(xy 327.606073 -211.091616) (xy 327.715571 -211.000612) (xy 327.830042 -210.91595) (xy 327.94912 -210.837899)
			(xy 328.072423 -210.76671) (xy 328.199556 -210.702611) (xy 328.330112 -210.645807) (xy 328.463672 -210.596481)
			(xy 328.599809 -210.554789) (xy 328.738087 -210.520866) (xy 328.878062 -210.494821) (xy 329.019287 -210.476736)
			(xy 329.161308 -210.466671) (xy 329.303672 -210.464656) (xy 329.445922 -210.470699) (xy 329.587602 -210.484779)
			(xy 329.728258 -210.506853) (xy 329.86744 -210.536849) (xy 330.004702 -210.574671) (xy 330.139605 -210.620199)
			(xy 330.271716 -210.673285) (xy 330.400612 -210.733761) (xy 330.52588 -210.801432) (xy 330.647119 -210.876082)
			(xy 330.76394 -210.957471) (xy 330.87597 -211.045339) (xy 330.982849 -211.139405) (xy 331.084235 -211.239366)
			(xy 331.179804 -211.344904) (xy 331.269249 -211.455679) (xy 331.352283 -211.571337) (xy 331.428641 -211.691507)
			(xy 331.498078 -211.815805) (xy 331.560371 -211.943832) (xy 331.615322 -212.075179) (xy 331.662754 -212.209424)
			(xy 331.702515 -212.346137) (xy 331.734477 -212.484881) (xy 331.758539 -212.625211) (xy 331.774623 -212.766677)
			(xy 331.782679 -212.908827) (xy 331.783182 -212.980016) (xy 331.782679 -213.051205) (xy 331.774623 -213.193355)
			(xy 331.758539 -213.334821) (xy 331.734477 -213.475151) (xy 331.702515 -213.613895) (xy 331.662754 -213.750608)
			(xy 331.615322 -213.884853) (xy 331.560371 -214.0162) (xy 331.498078 -214.144227) (xy 331.428641 -214.268525)
			(xy 331.352283 -214.388695) (xy 331.269249 -214.504353) (xy 331.179804 -214.615128) (xy 331.084235 -214.720666)
			(xy 330.982849 -214.820627) (xy 330.87597 -214.914693) (xy 330.76394 -215.002561) (xy 330.647119 -215.08395)
			(xy 330.52588 -215.1586) (xy 330.400612 -215.226271) (xy 330.271716 -215.286747) (xy 330.139605 -215.339833)
			(xy 330.004702 -215.385361) (xy 329.86744 -215.423183) (xy 329.728258 -215.453179) (xy 329.587602 -215.475253)
			(xy 329.445922 -215.489333) (xy 329.303672 -215.495376) (xy 329.161308 -215.493361) (xy 329.019287 -215.483296)
			(xy 328.878062 -215.465211) (xy 328.738087 -215.439166) (xy 328.599809 -215.405243) (xy 328.463672 -215.363551)
			(xy 328.330112 -215.314225) (xy 328.199556 -215.257421) (xy 328.072423 -215.193322) (xy 327.94912 -215.122133)
			(xy 327.830042 -215.044082) (xy 327.715571 -214.95942) (xy 327.606073 -214.868416) (xy 327.501898 -214.771364)
			(xy 327.403382 -214.668573) (xy 327.310838 -214.560374) (xy 327.224564 -214.447112) (xy 327.144836 -214.32915)
			(xy 327.071909 -214.206867) (xy 327.006018 -214.080654) (xy 326.947372 -213.950915) (xy 326.89616 -213.818066)
			(xy 326.852546 -213.682533) (xy 326.81667 -213.544749) (xy 326.788647 -213.405156) (xy 326.768566 -213.264202)
			(xy 326.756491 -213.122337) (xy 326.752462 -212.980016) (xy 324.681596 -212.980016) (xy 325.396352 -213.694772)
			(xy 325.403718 -213.702392) (xy 325.404226 -213.7029) (xy 325.405242 -213.703916) (xy 325.551292 -213.85022)
			(xy 325.5581 -213.857566) (xy 325.565827 -213.876028) (xy 325.566278 -213.886034) (xy 325.566278 -214.093806)
			(xy 325.566278 -214.096092) (xy 325.566278 -214.0966) (xy 325.566532 -214.10549) (xy 325.566532 -217.357706)
			(xy 325.56699 -217.367583) (xy 325.574434 -217.385882) (xy 325.58101 -217.393266) (xy 325.581264 -217.39352)
			(xy 329.489287 -221.301543) (xy 336.332312 -221.301543) (xy 336.332312 -221.248245) (xy 336.340255 -221.195541)
			(xy 336.355965 -221.144611) (xy 336.379091 -221.09659) (xy 336.409115 -221.052553) (xy 336.445367 -221.013482)
			(xy 336.487038 -220.980251) (xy 336.533196 -220.953602) (xy 336.58281 -220.93413) (xy 336.634772 -220.92227)
			(xy 336.687922 -220.918287) (xy 336.741072 -220.92227) (xy 336.793034 -220.93413) (xy 336.842648 -220.953602)
			(xy 336.888806 -220.980251) (xy 336.930477 -221.013482) (xy 336.966729 -221.052553) (xy 336.996753 -221.09659)
			(xy 337.019879 -221.144611) (xy 337.035589 -221.195541) (xy 337.043532 -221.248245) (xy 337.043861 -221.265852)
			(xy 337.271507 -221.265852) (xy 337.276988 -221.211975) (xy 337.290564 -221.159548) (xy 337.311922 -221.109782)
			(xy 337.34057 -221.063824) (xy 337.375846 -221.022734) (xy 337.416938 -220.987459) (xy 337.462898 -220.958814)
			(xy 337.512665 -220.937458) (xy 337.565092 -220.923884) (xy 337.61897 -220.918406) (xy 337.673057 -220.92115)
			(xy 337.726104 -220.932052) (xy 337.776888 -220.950861) (xy 337.824239 -220.977143) (xy 337.867064 -221.010292)
			(xy 337.904376 -221.049543) (xy 337.935313 -221.093992) (xy 337.959164 -221.142613) (xy 337.975377 -221.194285)
			(xy 337.983578 -221.247816) (xy 337.984084 -221.274894) (xy 337.983677 -221.299271) (xy 337.979739 -221.327959)
			(xy 340.334844 -221.327959) (xy 340.334844 -221.274661) (xy 340.342787 -221.221957) (xy 340.358497 -221.171027)
			(xy 340.381623 -221.123006) (xy 340.411647 -221.078969) (xy 340.447899 -221.039898) (xy 340.48957 -221.006667)
			(xy 340.535728 -220.980018) (xy 340.585342 -220.960546) (xy 340.637304 -220.948686) (xy 340.690454 -220.944703)
			(xy 340.743604 -220.948686) (xy 340.795566 -220.960546) (xy 340.84518 -220.980018) (xy 340.891338 -221.006667)
			(xy 340.933009 -221.039898) (xy 340.969261 -221.078969) (xy 340.999285 -221.123006) (xy 341.022411 -221.171027)
			(xy 341.038121 -221.221957) (xy 341.046064 -221.274661) (xy 341.046562 -221.30131) (xy 341.046064 -221.327959)
			(xy 341.223844 -221.327959) (xy 341.223844 -221.274661) (xy 341.231787 -221.221957) (xy 341.247497 -221.171027)
			(xy 341.270623 -221.123006) (xy 341.300647 -221.078969) (xy 341.336899 -221.039898) (xy 341.37857 -221.006667)
			(xy 341.424728 -220.980018) (xy 341.474342 -220.960546) (xy 341.526304 -220.948686) (xy 341.579454 -220.944703)
			(xy 341.632604 -220.948686) (xy 341.684566 -220.960546) (xy 341.73418 -220.980018) (xy 341.780338 -221.006667)
			(xy 341.822009 -221.039898) (xy 341.858261 -221.078969) (xy 341.888285 -221.123006) (xy 341.911411 -221.171027)
			(xy 341.927121 -221.221957) (xy 341.935064 -221.274661) (xy 341.935562 -221.30131) (xy 341.935064 -221.327959)
			(xy 342.112844 -221.327959) (xy 342.112844 -221.274661) (xy 342.120787 -221.221957) (xy 342.136497 -221.171027)
			(xy 342.159623 -221.123006) (xy 342.189647 -221.078969) (xy 342.225899 -221.039898) (xy 342.26757 -221.006667)
			(xy 342.313728 -220.980018) (xy 342.363342 -220.960546) (xy 342.415304 -220.948686) (xy 342.468454 -220.944703)
			(xy 342.521604 -220.948686) (xy 342.573566 -220.960546) (xy 342.62318 -220.980018) (xy 342.669338 -221.006667)
			(xy 342.711009 -221.039898) (xy 342.747261 -221.078969) (xy 342.777285 -221.123006) (xy 342.800411 -221.171027)
			(xy 342.816121 -221.221957) (xy 342.824064 -221.274661) (xy 342.824562 -221.30131) (xy 342.824064 -221.327959)
			(xy 342.816121 -221.380663) (xy 342.800411 -221.431593) (xy 342.777285 -221.479614) (xy 342.747261 -221.523651)
			(xy 342.711009 -221.562722) (xy 342.669338 -221.595953) (xy 342.62318 -221.622602) (xy 342.573566 -221.642074)
			(xy 342.521604 -221.653934) (xy 342.468454 -221.657918) (xy 342.415304 -221.653934) (xy 342.363342 -221.642074)
			(xy 342.313728 -221.622602) (xy 342.26757 -221.595953) (xy 342.225899 -221.562722) (xy 342.189647 -221.523651)
			(xy 342.159623 -221.479614) (xy 342.136497 -221.431593) (xy 342.120787 -221.380663) (xy 342.112844 -221.327959)
			(xy 341.935064 -221.327959) (xy 341.927121 -221.380663) (xy 341.911411 -221.431593) (xy 341.888285 -221.479614)
			(xy 341.858261 -221.523651) (xy 341.822009 -221.562722) (xy 341.780338 -221.595953) (xy 341.73418 -221.622602)
			(xy 341.684566 -221.642074) (xy 341.632604 -221.653934) (xy 341.579454 -221.657918) (xy 341.526304 -221.653934)
			(xy 341.474342 -221.642074) (xy 341.424728 -221.622602) (xy 341.37857 -221.595953) (xy 341.336899 -221.562722)
			(xy 341.300647 -221.523651) (xy 341.270623 -221.479614) (xy 341.247497 -221.431593) (xy 341.231787 -221.380663)
			(xy 341.223844 -221.327959) (xy 341.046064 -221.327959) (xy 341.038121 -221.380663) (xy 341.022411 -221.431593)
			(xy 340.999285 -221.479614) (xy 340.969261 -221.523651) (xy 340.933009 -221.562722) (xy 340.891338 -221.595953)
			(xy 340.84518 -221.622602) (xy 340.795566 -221.642074) (xy 340.743604 -221.653934) (xy 340.690454 -221.657918)
			(xy 340.637304 -221.653934) (xy 340.585342 -221.642074) (xy 340.535728 -221.622602) (xy 340.48957 -221.595953)
			(xy 340.447899 -221.562722) (xy 340.411647 -221.523651) (xy 340.381623 -221.479614) (xy 340.358497 -221.431593)
			(xy 340.342787 -221.380663) (xy 340.334844 -221.327959) (xy 337.979739 -221.327959) (xy 337.977046 -221.347573)
			(xy 337.970876 -221.37116) (xy 337.967467 -221.384747) (xy 337.967481 -221.412752) (xy 337.975103 -221.439699)
			(xy 337.989761 -221.463561) (xy 338.010351 -221.482543) (xy 338.035324 -221.495216) (xy 338.062802 -221.500626)
			(xy 338.076794 -221.499938) (xy 338.101178 -221.498922) (xy 338.126001 -221.499354) (xy 338.174992 -221.507382)
			(xy 338.22204 -221.52323) (xy 338.265903 -221.546481) (xy 338.305428 -221.576522) (xy 338.339571 -221.612562)
			(xy 338.367434 -221.65365) (xy 338.388283 -221.698705) (xy 338.401569 -221.746539) (xy 338.40694 -221.795893)
			(xy 338.404256 -221.845465) (xy 338.393588 -221.893951) (xy 338.375217 -221.940071) (xy 338.349625 -221.982612)
			(xy 338.317489 -222.020452) (xy 338.279654 -222.052595) (xy 338.237118 -222.078193) (xy 338.191 -222.096573)
			(xy 338.142517 -222.107249) (xy 338.092945 -222.109942) (xy 338.043591 -222.104578) (xy 337.995754 -222.091301)
			(xy 337.950695 -222.07046) (xy 337.909602 -222.042604) (xy 337.873557 -222.008466) (xy 337.843509 -221.968947)
			(xy 337.820251 -221.925087) (xy 337.804395 -221.878043) (xy 337.796358 -221.829052) (xy 337.79587 -221.80423)
			(xy 337.79605 -221.789596) (xy 337.798844 -221.760463) (xy 337.801458 -221.746064) (xy 337.803696 -221.732232)
			(xy 337.80144 -221.704316) (xy 337.791668 -221.67807) (xy 337.775116 -221.655477) (xy 337.753038 -221.638245)
			(xy 337.727101 -221.627678) (xy 337.699267 -221.624574) (xy 337.68538 -221.62643) (xy 337.671128 -221.628594)
			(xy 337.642391 -221.63088) (xy 337.627976 -221.631002) (xy 337.600898 -221.630477) (xy 337.547367 -221.622273)
			(xy 337.495696 -221.606057) (xy 337.447076 -221.582204) (xy 337.402629 -221.551264) (xy 337.363379 -221.513951)
			(xy 337.330233 -221.471124) (xy 337.303953 -221.423772) (xy 337.285147 -221.372986) (xy 337.274248 -221.319939)
			(xy 337.271507 -221.265852) (xy 337.043861 -221.265852) (xy 337.04403 -221.274894) (xy 337.043532 -221.301543)
			(xy 337.035589 -221.354247) (xy 337.019879 -221.405177) (xy 336.996753 -221.453198) (xy 336.966729 -221.497235)
			(xy 336.930477 -221.536306) (xy 336.888806 -221.569537) (xy 336.842648 -221.596186) (xy 336.793034 -221.615658)
			(xy 336.741072 -221.627518) (xy 336.687922 -221.631502) (xy 336.634772 -221.627518) (xy 336.58281 -221.615658)
			(xy 336.533196 -221.596186) (xy 336.487038 -221.569537) (xy 336.445367 -221.536306) (xy 336.409115 -221.497235)
			(xy 336.379091 -221.453198) (xy 336.355965 -221.405177) (xy 336.340255 -221.354247) (xy 336.332312 -221.301543)
			(xy 329.489287 -221.301543) (xy 329.991974 -221.80423) (xy 332.155304 -221.80423) (xy 332.159264 -221.755176)
			(xy 332.171041 -221.707392) (xy 332.190332 -221.662116) (xy 332.216635 -221.62052) (xy 332.24927 -221.583683)
			(xy 332.287391 -221.552558) (xy 332.330012 -221.527951) (xy 332.376028 -221.510499) (xy 332.424247 -221.500655)
			(xy 332.473422 -221.498674) (xy 332.522277 -221.504606) (xy 332.569548 -221.518298) (xy 332.61401 -221.539396)
			(xy 332.654513 -221.567352) (xy 332.690006 -221.601444) (xy 332.719571 -221.640788) (xy 332.742442 -221.684365)
			(xy 332.758026 -221.731046) (xy 332.765921 -221.779623) (xy 332.766416 -221.80423) (xy 332.765921 -221.828837)
			(xy 332.758026 -221.877414) (xy 332.742442 -221.924095) (xy 332.719571 -221.967672) (xy 332.690006 -222.007016)
			(xy 332.654513 -222.041108) (xy 332.61401 -222.069064) (xy 332.569548 -222.090162) (xy 332.522277 -222.103854)
			(xy 332.473422 -222.109786) (xy 332.424247 -222.107805) (xy 332.376028 -222.097961) (xy 332.330012 -222.080509)
			(xy 332.287391 -222.055902) (xy 332.24927 -222.024777) (xy 332.216635 -221.98794) (xy 332.190332 -221.946344)
			(xy 332.171041 -221.901068) (xy 332.159264 -221.853284) (xy 332.155304 -221.80423) (xy 329.991974 -221.80423)
			(xy 330.652882 -222.465138) (xy 330.673964 -222.472758) (xy 330.685394 -222.471742) (xy 330.685648 -222.471742)
			(xy 330.773024 -222.46336) (xy 330.792328 -222.45193) (xy 330.798678 -222.442532) (xy 330.813016 -222.422308)
			(xy 330.84715 -222.386361) (xy 330.886644 -222.356401) (xy 330.93046 -222.333216) (xy 330.977446 -222.317415)
			(xy 331.026368 -222.309414) (xy 331.051154 -222.308928) (xy 331.075148 -222.309371) (xy 331.122547 -222.316872)
			(xy 331.168189 -222.331697) (xy 331.210949 -222.35348) (xy 331.249774 -222.381686) (xy 331.283708 -222.415619)
			(xy 331.311914 -222.454443) (xy 331.333699 -222.497202) (xy 331.348526 -222.542843) (xy 331.356028 -222.590242)
			(xy 331.356462 -222.614236) (xy 331.685404 -222.614236) (xy 331.689364 -222.565182) (xy 331.701141 -222.517398)
			(xy 331.720432 -222.472122) (xy 331.746735 -222.430526) (xy 331.77937 -222.393689) (xy 331.817491 -222.362564)
			(xy 331.860112 -222.337957) (xy 331.906128 -222.320505) (xy 331.954347 -222.310661) (xy 332.003522 -222.30868)
			(xy 332.052377 -222.314612) (xy 332.099648 -222.328304) (xy 332.14411 -222.349402) (xy 332.184613 -222.377358)
			(xy 332.220106 -222.41145) (xy 332.249671 -222.450794) (xy 332.272542 -222.494371) (xy 332.288126 -222.541052)
			(xy 332.296021 -222.589629) (xy 332.296516 -222.614236) (xy 333.565258 -222.614236) (xy 333.569218 -222.565182)
			(xy 333.580995 -222.517398) (xy 333.600286 -222.472122) (xy 333.626589 -222.430526) (xy 333.659224 -222.393689)
			(xy 333.697345 -222.362564) (xy 333.739966 -222.337957) (xy 333.785982 -222.320505) (xy 333.834201 -222.310661)
			(xy 333.883376 -222.30868) (xy 333.932231 -222.314612) (xy 333.979502 -222.328304) (xy 334.023964 -222.349402)
			(xy 334.064467 -222.377358) (xy 334.09996 -222.41145) (xy 334.129525 -222.450794) (xy 334.152396 -222.494371)
			(xy 334.16798 -222.541052) (xy 334.175875 -222.589629) (xy 334.17637 -222.614236) (xy 334.505312 -222.614236)
			(xy 334.509272 -222.565182) (xy 334.521049 -222.517398) (xy 334.54034 -222.472122) (xy 334.566643 -222.430526)
			(xy 334.599278 -222.393689) (xy 334.637399 -222.362564) (xy 334.68002 -222.337957) (xy 334.726036 -222.320505)
			(xy 334.774255 -222.310661) (xy 334.82343 -222.30868) (xy 334.872285 -222.314612) (xy 334.919556 -222.328304)
			(xy 334.964018 -222.349402) (xy 335.004521 -222.377358) (xy 335.040014 -222.41145) (xy 335.069579 -222.450794)
			(xy 335.09245 -222.494371) (xy 335.108034 -222.541052) (xy 335.115929 -222.589629) (xy 335.116424 -222.614236)
			(xy 335.445366 -222.614236) (xy 335.449326 -222.565182) (xy 335.461103 -222.517398) (xy 335.480394 -222.472122)
			(xy 335.506697 -222.430526) (xy 335.539332 -222.393689) (xy 335.577453 -222.362564) (xy 335.620074 -222.337957)
			(xy 335.66609 -222.320505) (xy 335.714309 -222.310661) (xy 335.763484 -222.30868) (xy 335.812339 -222.314612)
			(xy 335.85961 -222.328304) (xy 335.904072 -222.349402) (xy 335.944575 -222.377358) (xy 335.980068 -222.41145)
			(xy 336.009633 -222.450794) (xy 336.032504 -222.494371) (xy 336.048088 -222.541052) (xy 336.055983 -222.589629)
			(xy 336.056478 -222.614236) (xy 336.38542 -222.614236) (xy 336.38938 -222.565182) (xy 336.401157 -222.517398)
			(xy 336.420448 -222.472122) (xy 336.446751 -222.430526) (xy 336.479386 -222.393689) (xy 336.517507 -222.362564)
			(xy 336.560128 -222.337957) (xy 336.606144 -222.320505) (xy 336.654363 -222.310661) (xy 336.703538 -222.30868)
			(xy 336.752393 -222.314612) (xy 336.799664 -222.328304) (xy 336.844126 -222.349402) (xy 336.884629 -222.377358)
			(xy 336.920122 -222.41145) (xy 336.949687 -222.450794) (xy 336.972558 -222.494371) (xy 336.988142 -222.541052)
			(xy 336.996037 -222.589629) (xy 336.996532 -222.614236) (xy 337.32522 -222.614236) (xy 337.32918 -222.565182)
			(xy 337.340957 -222.517398) (xy 337.360248 -222.472122) (xy 337.386551 -222.430526) (xy 337.419186 -222.393689)
			(xy 337.457307 -222.362564) (xy 337.499928 -222.337957) (xy 337.545944 -222.320505) (xy 337.594163 -222.310661)
			(xy 337.643338 -222.30868) (xy 337.692193 -222.314612) (xy 337.739464 -222.328304) (xy 337.783926 -222.349402)
			(xy 337.824429 -222.377358) (xy 337.859922 -222.41145) (xy 337.889487 -222.450794) (xy 337.912358 -222.494371)
			(xy 337.927942 -222.541052) (xy 337.935837 -222.589629) (xy 337.936332 -222.614236) (xy 338.265274 -222.614236)
			(xy 338.269234 -222.565182) (xy 338.281011 -222.517398) (xy 338.300302 -222.472122) (xy 338.326605 -222.430526)
			(xy 338.35924 -222.393689) (xy 338.397361 -222.362564) (xy 338.439982 -222.337957) (xy 338.485998 -222.320505)
			(xy 338.534217 -222.310661) (xy 338.583392 -222.30868) (xy 338.632247 -222.314612) (xy 338.679518 -222.328304)
			(xy 338.72398 -222.349402) (xy 338.764483 -222.377358) (xy 338.799976 -222.41145) (xy 338.829541 -222.450794)
			(xy 338.852412 -222.494371) (xy 338.867996 -222.541052) (xy 338.875891 -222.589629) (xy 338.876386 -222.614236)
			(xy 339.205328 -222.614236) (xy 339.209288 -222.565182) (xy 339.221065 -222.517398) (xy 339.240356 -222.472122)
			(xy 339.266659 -222.430526) (xy 339.299294 -222.393689) (xy 339.337415 -222.362564) (xy 339.380036 -222.337957)
			(xy 339.426052 -222.320505) (xy 339.474271 -222.310661) (xy 339.523446 -222.30868) (xy 339.572301 -222.314612)
			(xy 339.619572 -222.328304) (xy 339.664034 -222.349402) (xy 339.704537 -222.377358) (xy 339.74003 -222.41145)
			(xy 339.769595 -222.450794) (xy 339.792466 -222.494371) (xy 339.80805 -222.541052) (xy 339.815945 -222.589629)
			(xy 339.81644 -222.614236) (xy 340.145382 -222.614236) (xy 340.149342 -222.565182) (xy 340.161119 -222.517398)
			(xy 340.18041 -222.472122) (xy 340.206713 -222.430526) (xy 340.239348 -222.393689) (xy 340.277469 -222.362564)
			(xy 340.32009 -222.337957) (xy 340.366106 -222.320505) (xy 340.414325 -222.310661) (xy 340.4635 -222.30868)
			(xy 340.512355 -222.314612) (xy 340.559626 -222.328304) (xy 340.604088 -222.349402) (xy 340.644591 -222.377358)
			(xy 340.680084 -222.41145) (xy 340.709649 -222.450794) (xy 340.73252 -222.494371) (xy 340.748104 -222.541052)
			(xy 340.755999 -222.589629) (xy 340.756494 -222.614236) (xy 341.085182 -222.614236) (xy 341.089142 -222.565182)
			(xy 341.100919 -222.517398) (xy 341.12021 -222.472122) (xy 341.146513 -222.430526) (xy 341.179148 -222.393689)
			(xy 341.217269 -222.362564) (xy 341.25989 -222.337957) (xy 341.305906 -222.320505) (xy 341.354125 -222.310661)
			(xy 341.4033 -222.30868) (xy 341.452155 -222.314612) (xy 341.499426 -222.328304) (xy 341.543888 -222.349402)
			(xy 341.584391 -222.377358) (xy 341.619884 -222.41145) (xy 341.649449 -222.450794) (xy 341.67232 -222.494371)
			(xy 341.687904 -222.541052) (xy 341.695799 -222.589629) (xy 341.696294 -222.614236) (xy 342.025236 -222.614236)
			(xy 342.029196 -222.565182) (xy 342.040973 -222.517398) (xy 342.060264 -222.472122) (xy 342.086567 -222.430526)
			(xy 342.119202 -222.393689) (xy 342.157323 -222.362564) (xy 342.199944 -222.337957) (xy 342.24596 -222.320505)
			(xy 342.294179 -222.310661) (xy 342.343354 -222.30868) (xy 342.392209 -222.314612) (xy 342.43948 -222.328304)
			(xy 342.483942 -222.349402) (xy 342.524445 -222.377358) (xy 342.559938 -222.41145) (xy 342.589503 -222.450794)
			(xy 342.612374 -222.494371) (xy 342.627958 -222.541052) (xy 342.635853 -222.589629) (xy 342.636348 -222.614236)
			(xy 342.635853 -222.638843) (xy 342.627958 -222.68742) (xy 342.612374 -222.734101) (xy 342.589503 -222.777678)
			(xy 342.559938 -222.817022) (xy 342.524445 -222.851114) (xy 342.483942 -222.87907) (xy 342.43948 -222.900168)
			(xy 342.392209 -222.91386) (xy 342.343354 -222.919792) (xy 342.294179 -222.917811) (xy 342.24596 -222.907967)
			(xy 342.199944 -222.890515) (xy 342.157323 -222.865908) (xy 342.119202 -222.834783) (xy 342.086567 -222.797946)
			(xy 342.060264 -222.75635) (xy 342.040973 -222.711074) (xy 342.029196 -222.66329) (xy 342.025236 -222.614236)
			(xy 341.696294 -222.614236) (xy 341.695799 -222.638843) (xy 341.687904 -222.68742) (xy 341.67232 -222.734101)
			(xy 341.649449 -222.777678) (xy 341.619884 -222.817022) (xy 341.584391 -222.851114) (xy 341.543888 -222.87907)
			(xy 341.499426 -222.900168) (xy 341.452155 -222.91386) (xy 341.4033 -222.919792) (xy 341.354125 -222.917811)
			(xy 341.305906 -222.907967) (xy 341.25989 -222.890515) (xy 341.217269 -222.865908) (xy 341.179148 -222.834783)
			(xy 341.146513 -222.797946) (xy 341.12021 -222.75635) (xy 341.100919 -222.711074) (xy 341.089142 -222.66329)
			(xy 341.085182 -222.614236) (xy 340.756494 -222.614236) (xy 340.755999 -222.638843) (xy 340.748104 -222.68742)
			(xy 340.73252 -222.734101) (xy 340.709649 -222.777678) (xy 340.680084 -222.817022) (xy 340.644591 -222.851114)
			(xy 340.604088 -222.87907) (xy 340.559626 -222.900168) (xy 340.512355 -222.91386) (xy 340.4635 -222.919792)
			(xy 340.414325 -222.917811) (xy 340.366106 -222.907967) (xy 340.32009 -222.890515) (xy 340.277469 -222.865908)
			(xy 340.239348 -222.834783) (xy 340.206713 -222.797946) (xy 340.18041 -222.75635) (xy 340.161119 -222.711074)
			(xy 340.149342 -222.66329) (xy 340.145382 -222.614236) (xy 339.81644 -222.614236) (xy 339.815945 -222.638843)
			(xy 339.80805 -222.68742) (xy 339.792466 -222.734101) (xy 339.769595 -222.777678) (xy 339.74003 -222.817022)
			(xy 339.704537 -222.851114) (xy 339.664034 -222.87907) (xy 339.619572 -222.900168) (xy 339.572301 -222.91386)
			(xy 339.523446 -222.919792) (xy 339.474271 -222.917811) (xy 339.426052 -222.907967) (xy 339.380036 -222.890515)
			(xy 339.337415 -222.865908) (xy 339.299294 -222.834783) (xy 339.266659 -222.797946) (xy 339.240356 -222.75635)
			(xy 339.221065 -222.711074) (xy 339.209288 -222.66329) (xy 339.205328 -222.614236) (xy 338.876386 -222.614236)
			(xy 338.875891 -222.638843) (xy 338.867996 -222.68742) (xy 338.852412 -222.734101) (xy 338.829541 -222.777678)
			(xy 338.799976 -222.817022) (xy 338.764483 -222.851114) (xy 338.72398 -222.87907) (xy 338.679518 -222.900168)
			(xy 338.632247 -222.91386) (xy 338.583392 -222.919792) (xy 338.534217 -222.917811) (xy 338.485998 -222.907967)
			(xy 338.439982 -222.890515) (xy 338.397361 -222.865908) (xy 338.35924 -222.834783) (xy 338.326605 -222.797946)
			(xy 338.300302 -222.75635) (xy 338.281011 -222.711074) (xy 338.269234 -222.66329) (xy 338.265274 -222.614236)
			(xy 337.936332 -222.614236) (xy 337.935837 -222.638843) (xy 337.927942 -222.68742) (xy 337.912358 -222.734101)
			(xy 337.889487 -222.777678) (xy 337.859922 -222.817022) (xy 337.824429 -222.851114) (xy 337.783926 -222.87907)
			(xy 337.739464 -222.900168) (xy 337.692193 -222.91386) (xy 337.643338 -222.919792) (xy 337.594163 -222.917811)
			(xy 337.545944 -222.907967) (xy 337.499928 -222.890515) (xy 337.457307 -222.865908) (xy 337.419186 -222.834783)
			(xy 337.386551 -222.797946) (xy 337.360248 -222.75635) (xy 337.340957 -222.711074) (xy 337.32918 -222.66329)
			(xy 337.32522 -222.614236) (xy 336.996532 -222.614236) (xy 336.996037 -222.638843) (xy 336.988142 -222.68742)
			(xy 336.972558 -222.734101) (xy 336.949687 -222.777678) (xy 336.920122 -222.817022) (xy 336.884629 -222.851114)
			(xy 336.844126 -222.87907) (xy 336.799664 -222.900168) (xy 336.752393 -222.91386) (xy 336.703538 -222.919792)
			(xy 336.654363 -222.917811) (xy 336.606144 -222.907967) (xy 336.560128 -222.890515) (xy 336.517507 -222.865908)
			(xy 336.479386 -222.834783) (xy 336.446751 -222.797946) (xy 336.420448 -222.75635) (xy 336.401157 -222.711074)
			(xy 336.38938 -222.66329) (xy 336.38542 -222.614236) (xy 336.056478 -222.614236) (xy 336.055983 -222.638843)
			(xy 336.048088 -222.68742) (xy 336.032504 -222.734101) (xy 336.009633 -222.777678) (xy 335.980068 -222.817022)
			(xy 335.944575 -222.851114) (xy 335.904072 -222.87907) (xy 335.85961 -222.900168) (xy 335.812339 -222.91386)
			(xy 335.763484 -222.919792) (xy 335.714309 -222.917811) (xy 335.66609 -222.907967) (xy 335.620074 -222.890515)
			(xy 335.577453 -222.865908) (xy 335.539332 -222.834783) (xy 335.506697 -222.797946) (xy 335.480394 -222.75635)
			(xy 335.461103 -222.711074) (xy 335.449326 -222.66329) (xy 335.445366 -222.614236) (xy 335.116424 -222.614236)
			(xy 335.115929 -222.638843) (xy 335.108034 -222.68742) (xy 335.09245 -222.734101) (xy 335.069579 -222.777678)
			(xy 335.040014 -222.817022) (xy 335.004521 -222.851114) (xy 334.964018 -222.87907) (xy 334.919556 -222.900168)
			(xy 334.872285 -222.91386) (xy 334.82343 -222.919792) (xy 334.774255 -222.917811) (xy 334.726036 -222.907967)
			(xy 334.68002 -222.890515) (xy 334.637399 -222.865908) (xy 334.599278 -222.834783) (xy 334.566643 -222.797946)
			(xy 334.54034 -222.75635) (xy 334.521049 -222.711074) (xy 334.509272 -222.66329) (xy 334.505312 -222.614236)
			(xy 334.17637 -222.614236) (xy 334.175875 -222.638843) (xy 334.16798 -222.68742) (xy 334.152396 -222.734101)
			(xy 334.129525 -222.777678) (xy 334.09996 -222.817022) (xy 334.064467 -222.851114) (xy 334.023964 -222.87907)
			(xy 333.979502 -222.900168) (xy 333.932231 -222.91386) (xy 333.883376 -222.919792) (xy 333.834201 -222.917811)
			(xy 333.785982 -222.907967) (xy 333.739966 -222.890515) (xy 333.697345 -222.865908) (xy 333.659224 -222.834783)
			(xy 333.626589 -222.797946) (xy 333.600286 -222.75635) (xy 333.580995 -222.711074) (xy 333.569218 -222.66329)
			(xy 333.565258 -222.614236) (xy 332.296516 -222.614236) (xy 332.296021 -222.638843) (xy 332.288126 -222.68742)
			(xy 332.272542 -222.734101) (xy 332.249671 -222.777678) (xy 332.220106 -222.817022) (xy 332.184613 -222.851114)
			(xy 332.14411 -222.87907) (xy 332.099648 -222.900168) (xy 332.052377 -222.91386) (xy 332.003522 -222.919792)
			(xy 331.954347 -222.917811) (xy 331.906128 -222.907967) (xy 331.860112 -222.890515) (xy 331.817491 -222.865908)
			(xy 331.77937 -222.834783) (xy 331.746735 -222.797946) (xy 331.720432 -222.75635) (xy 331.701141 -222.711074)
			(xy 331.689364 -222.66329) (xy 331.685404 -222.614236) (xy 331.356462 -222.614236) (xy 331.355977 -222.63902)
			(xy 331.347965 -222.687937) (xy 331.332157 -222.734918) (xy 331.308969 -222.778728) (xy 331.279009 -222.818218)
			(xy 331.243064 -222.852351) (xy 331.222858 -222.866712) (xy 331.21346 -222.873062) (xy 331.20203 -222.892366)
			(xy 331.193648 -222.979234) (xy 331.193168 -222.987334) (xy 331.196797 -223.003141) (xy 331.20076 -223.010222)
			(xy 331.20457 -223.016826) (xy 331.339952 -223.152208) (xy 331.371702 -223.157542) (xy 331.386434 -223.150176)
			(xy 331.407493 -223.140323) (xy 331.451851 -223.126399) (xy 331.497808 -223.119359) (xy 331.521054 -223.118934)
			(xy 331.545048 -223.119377) (xy 331.592447 -223.126878) (xy 331.638088 -223.141703) (xy 331.680847 -223.163487)
			(xy 331.719672 -223.191692) (xy 331.753605 -223.225625) (xy 331.781811 -223.264449) (xy 331.803595 -223.307208)
			(xy 331.818421 -223.352849) (xy 331.825923 -223.400248) (xy 331.826362 -223.424242) (xy 332.155304 -223.424242)
			(xy 332.159264 -223.375188) (xy 332.171041 -223.327404) (xy 332.190332 -223.282128) (xy 332.216635 -223.240532)
			(xy 332.24927 -223.203695) (xy 332.287391 -223.17257) (xy 332.330012 -223.147963) (xy 332.376028 -223.130511)
			(xy 332.424247 -223.120667) (xy 332.473422 -223.118686) (xy 332.522277 -223.124618) (xy 332.569548 -223.13831)
			(xy 332.61401 -223.159408) (xy 332.654513 -223.187364) (xy 332.690006 -223.221456) (xy 332.719571 -223.2608)
			(xy 332.742442 -223.304377) (xy 332.758026 -223.351058) (xy 332.765921 -223.399635) (xy 332.766416 -223.424242)
			(xy 333.095358 -223.424242) (xy 333.099318 -223.375188) (xy 333.111095 -223.327404) (xy 333.130386 -223.282128)
			(xy 333.156689 -223.240532) (xy 333.189324 -223.203695) (xy 333.227445 -223.17257) (xy 333.270066 -223.147963)
			(xy 333.316082 -223.130511) (xy 333.364301 -223.120667) (xy 333.413476 -223.118686) (xy 333.462331 -223.124618)
			(xy 333.509602 -223.13831) (xy 333.554064 -223.159408) (xy 333.594567 -223.187364) (xy 333.63006 -223.221456)
			(xy 333.659625 -223.2608) (xy 333.682496 -223.304377) (xy 333.69808 -223.351058) (xy 333.705975 -223.399635)
			(xy 333.70647 -223.424242) (xy 334.035412 -223.424242) (xy 334.039372 -223.375188) (xy 334.051149 -223.327404)
			(xy 334.07044 -223.282128) (xy 334.096743 -223.240532) (xy 334.129378 -223.203695) (xy 334.167499 -223.17257)
			(xy 334.21012 -223.147963) (xy 334.256136 -223.130511) (xy 334.304355 -223.120667) (xy 334.35353 -223.118686)
			(xy 334.402385 -223.124618) (xy 334.449656 -223.13831) (xy 334.494118 -223.159408) (xy 334.534621 -223.187364)
			(xy 334.570114 -223.221456) (xy 334.599679 -223.2608) (xy 334.62255 -223.304377) (xy 334.638134 -223.351058)
			(xy 334.646029 -223.399635) (xy 334.646524 -223.424242) (xy 334.975212 -223.424242) (xy 334.979172 -223.375188)
			(xy 334.990949 -223.327404) (xy 335.01024 -223.282128) (xy 335.036543 -223.240532) (xy 335.069178 -223.203695)
			(xy 335.107299 -223.17257) (xy 335.14992 -223.147963) (xy 335.195936 -223.130511) (xy 335.244155 -223.120667)
			(xy 335.29333 -223.118686) (xy 335.342185 -223.124618) (xy 335.389456 -223.13831) (xy 335.433918 -223.159408)
			(xy 335.474421 -223.187364) (xy 335.509914 -223.221456) (xy 335.539479 -223.2608) (xy 335.56235 -223.304377)
			(xy 335.577934 -223.351058) (xy 335.585829 -223.399635) (xy 335.586324 -223.424242) (xy 335.915266 -223.424242)
			(xy 335.919226 -223.375188) (xy 335.931003 -223.327404) (xy 335.950294 -223.282128) (xy 335.976597 -223.240532)
			(xy 336.009232 -223.203695) (xy 336.047353 -223.17257) (xy 336.089974 -223.147963) (xy 336.13599 -223.130511)
			(xy 336.184209 -223.120667) (xy 336.233384 -223.118686) (xy 336.282239 -223.124618) (xy 336.32951 -223.13831)
			(xy 336.373972 -223.159408) (xy 336.414475 -223.187364) (xy 336.449968 -223.221456) (xy 336.479533 -223.2608)
			(xy 336.502404 -223.304377) (xy 336.517988 -223.351058) (xy 336.525883 -223.399635) (xy 336.526378 -223.424242)
			(xy 336.85532 -223.424242) (xy 336.85928 -223.375188) (xy 336.871057 -223.327404) (xy 336.890348 -223.282128)
			(xy 336.916651 -223.240532) (xy 336.949286 -223.203695) (xy 336.987407 -223.17257) (xy 337.030028 -223.147963)
			(xy 337.076044 -223.130511) (xy 337.124263 -223.120667) (xy 337.173438 -223.118686) (xy 337.222293 -223.124618)
			(xy 337.269564 -223.13831) (xy 337.314026 -223.159408) (xy 337.354529 -223.187364) (xy 337.390022 -223.221456)
			(xy 337.419587 -223.2608) (xy 337.442458 -223.304377) (xy 337.458042 -223.351058) (xy 337.465937 -223.399635)
			(xy 337.466432 -223.424242) (xy 337.795374 -223.424242) (xy 337.799334 -223.375188) (xy 337.811111 -223.327404)
			(xy 337.830402 -223.282128) (xy 337.856705 -223.240532) (xy 337.88934 -223.203695) (xy 337.927461 -223.17257)
			(xy 337.970082 -223.147963) (xy 338.016098 -223.130511) (xy 338.064317 -223.120667) (xy 338.113492 -223.118686)
			(xy 338.162347 -223.124618) (xy 338.209618 -223.13831) (xy 338.25408 -223.159408) (xy 338.294583 -223.187364)
			(xy 338.330076 -223.221456) (xy 338.359641 -223.2608) (xy 338.382512 -223.304377) (xy 338.398096 -223.351058)
			(xy 338.405991 -223.399635) (xy 338.406486 -223.424242) (xy 338.735174 -223.424242) (xy 338.739134 -223.375188)
			(xy 338.750911 -223.327404) (xy 338.770202 -223.282128) (xy 338.796505 -223.240532) (xy 338.82914 -223.203695)
			(xy 338.867261 -223.17257) (xy 338.909882 -223.147963) (xy 338.955898 -223.130511) (xy 339.004117 -223.120667)
			(xy 339.053292 -223.118686) (xy 339.102147 -223.124618) (xy 339.149418 -223.13831) (xy 339.19388 -223.159408)
			(xy 339.234383 -223.187364) (xy 339.269876 -223.221456) (xy 339.299441 -223.2608) (xy 339.322312 -223.304377)
			(xy 339.337896 -223.351058) (xy 339.345791 -223.399635) (xy 339.346286 -223.424242) (xy 341.555336 -223.424242)
			(xy 341.559296 -223.375188) (xy 341.571073 -223.327404) (xy 341.590364 -223.282128) (xy 341.616667 -223.240532)
			(xy 341.649302 -223.203695) (xy 341.687423 -223.17257) (xy 341.730044 -223.147963) (xy 341.77606 -223.130511)
			(xy 341.824279 -223.120667) (xy 341.873454 -223.118686) (xy 341.922309 -223.124618) (xy 341.96958 -223.13831)
			(xy 342.014042 -223.159408) (xy 342.054545 -223.187364) (xy 342.090038 -223.221456) (xy 342.119603 -223.2608)
			(xy 342.142474 -223.304377) (xy 342.158058 -223.351058) (xy 342.165953 -223.399635) (xy 342.166448 -223.424242)
			(xy 342.49539 -223.424242) (xy 342.49935 -223.375188) (xy 342.511127 -223.327404) (xy 342.530418 -223.282128)
			(xy 342.556721 -223.240532) (xy 342.589356 -223.203695) (xy 342.627477 -223.17257) (xy 342.670098 -223.147963)
			(xy 342.716114 -223.130511) (xy 342.764333 -223.120667) (xy 342.813508 -223.118686) (xy 342.862363 -223.124618)
			(xy 342.909634 -223.13831) (xy 342.954096 -223.159408) (xy 342.994599 -223.187364) (xy 343.030092 -223.221456)
			(xy 343.059657 -223.2608) (xy 343.082528 -223.304377) (xy 343.098112 -223.351058) (xy 343.106007 -223.399635)
			(xy 343.106502 -223.424242) (xy 343.106007 -223.448849) (xy 343.098112 -223.497426) (xy 343.082528 -223.544107)
			(xy 343.059657 -223.587684) (xy 343.030092 -223.627028) (xy 342.994599 -223.66112) (xy 342.954096 -223.689076)
			(xy 342.909634 -223.710174) (xy 342.862363 -223.723866) (xy 342.813508 -223.729798) (xy 342.764333 -223.727817)
			(xy 342.716114 -223.717973) (xy 342.670098 -223.700521) (xy 342.627477 -223.675914) (xy 342.589356 -223.644789)
			(xy 342.556721 -223.607952) (xy 342.530418 -223.566356) (xy 342.511127 -223.52108) (xy 342.49935 -223.473296)
			(xy 342.49539 -223.424242) (xy 342.166448 -223.424242) (xy 342.165953 -223.448849) (xy 342.158058 -223.497426)
			(xy 342.142474 -223.544107) (xy 342.119603 -223.587684) (xy 342.090038 -223.627028) (xy 342.054545 -223.66112)
			(xy 342.014042 -223.689076) (xy 341.96958 -223.710174) (xy 341.922309 -223.723866) (xy 341.873454 -223.729798)
			(xy 341.824279 -223.727817) (xy 341.77606 -223.717973) (xy 341.730044 -223.700521) (xy 341.687423 -223.675914)
			(xy 341.649302 -223.644789) (xy 341.616667 -223.607952) (xy 341.590364 -223.566356) (xy 341.571073 -223.52108)
			(xy 341.559296 -223.473296) (xy 341.555336 -223.424242) (xy 339.346286 -223.424242) (xy 339.345791 -223.448849)
			(xy 339.337896 -223.497426) (xy 339.322312 -223.544107) (xy 339.299441 -223.587684) (xy 339.269876 -223.627028)
			(xy 339.234383 -223.66112) (xy 339.19388 -223.689076) (xy 339.149418 -223.710174) (xy 339.102147 -223.723866)
			(xy 339.053292 -223.729798) (xy 339.004117 -223.727817) (xy 338.955898 -223.717973) (xy 338.909882 -223.700521)
			(xy 338.867261 -223.675914) (xy 338.82914 -223.644789) (xy 338.796505 -223.607952) (xy 338.770202 -223.566356)
			(xy 338.750911 -223.52108) (xy 338.739134 -223.473296) (xy 338.735174 -223.424242) (xy 338.406486 -223.424242)
			(xy 338.405991 -223.448849) (xy 338.398096 -223.497426) (xy 338.382512 -223.544107) (xy 338.359641 -223.587684)
			(xy 338.330076 -223.627028) (xy 338.294583 -223.66112) (xy 338.25408 -223.689076) (xy 338.209618 -223.710174)
			(xy 338.162347 -223.723866) (xy 338.113492 -223.729798) (xy 338.064317 -223.727817) (xy 338.016098 -223.717973)
			(xy 337.970082 -223.700521) (xy 337.927461 -223.675914) (xy 337.88934 -223.644789) (xy 337.856705 -223.607952)
			(xy 337.830402 -223.566356) (xy 337.811111 -223.52108) (xy 337.799334 -223.473296) (xy 337.795374 -223.424242)
			(xy 337.466432 -223.424242) (xy 337.465937 -223.448849) (xy 337.458042 -223.497426) (xy 337.442458 -223.544107)
			(xy 337.419587 -223.587684) (xy 337.390022 -223.627028) (xy 337.354529 -223.66112) (xy 337.314026 -223.689076)
			(xy 337.269564 -223.710174) (xy 337.222293 -223.723866) (xy 337.173438 -223.729798) (xy 337.124263 -223.727817)
			(xy 337.076044 -223.717973) (xy 337.030028 -223.700521) (xy 336.987407 -223.675914) (xy 336.949286 -223.644789)
			(xy 336.916651 -223.607952) (xy 336.890348 -223.566356) (xy 336.871057 -223.52108) (xy 336.85928 -223.473296)
			(xy 336.85532 -223.424242) (xy 336.526378 -223.424242) (xy 336.525883 -223.448849) (xy 336.517988 -223.497426)
			(xy 336.502404 -223.544107) (xy 336.479533 -223.587684) (xy 336.449968 -223.627028) (xy 336.414475 -223.66112)
			(xy 336.373972 -223.689076) (xy 336.32951 -223.710174) (xy 336.282239 -223.723866) (xy 336.233384 -223.729798)
			(xy 336.184209 -223.727817) (xy 336.13599 -223.717973) (xy 336.089974 -223.700521) (xy 336.047353 -223.675914)
			(xy 336.009232 -223.644789) (xy 335.976597 -223.607952) (xy 335.950294 -223.566356) (xy 335.931003 -223.52108)
			(xy 335.919226 -223.473296) (xy 335.915266 -223.424242) (xy 335.586324 -223.424242) (xy 335.585829 -223.448849)
			(xy 335.577934 -223.497426) (xy 335.56235 -223.544107) (xy 335.539479 -223.587684) (xy 335.509914 -223.627028)
			(xy 335.474421 -223.66112) (xy 335.433918 -223.689076) (xy 335.389456 -223.710174) (xy 335.342185 -223.723866)
			(xy 335.29333 -223.729798) (xy 335.244155 -223.727817) (xy 335.195936 -223.717973) (xy 335.14992 -223.700521)
			(xy 335.107299 -223.675914) (xy 335.069178 -223.644789) (xy 335.036543 -223.607952) (xy 335.01024 -223.566356)
			(xy 334.990949 -223.52108) (xy 334.979172 -223.473296) (xy 334.975212 -223.424242) (xy 334.646524 -223.424242)
			(xy 334.646029 -223.448849) (xy 334.638134 -223.497426) (xy 334.62255 -223.544107) (xy 334.599679 -223.587684)
			(xy 334.570114 -223.627028) (xy 334.534621 -223.66112) (xy 334.494118 -223.689076) (xy 334.449656 -223.710174)
			(xy 334.402385 -223.723866) (xy 334.35353 -223.729798) (xy 334.304355 -223.727817) (xy 334.256136 -223.717973)
			(xy 334.21012 -223.700521) (xy 334.167499 -223.675914) (xy 334.129378 -223.644789) (xy 334.096743 -223.607952)
			(xy 334.07044 -223.566356) (xy 334.051149 -223.52108) (xy 334.039372 -223.473296) (xy 334.035412 -223.424242)
			(xy 333.70647 -223.424242) (xy 333.705975 -223.448849) (xy 333.69808 -223.497426) (xy 333.682496 -223.544107)
			(xy 333.659625 -223.587684) (xy 333.63006 -223.627028) (xy 333.594567 -223.66112) (xy 333.554064 -223.689076)
			(xy 333.509602 -223.710174) (xy 333.462331 -223.723866) (xy 333.413476 -223.729798) (xy 333.364301 -223.727817)
			(xy 333.316082 -223.717973) (xy 333.270066 -223.700521) (xy 333.227445 -223.675914) (xy 333.189324 -223.644789)
			(xy 333.156689 -223.607952) (xy 333.130386 -223.566356) (xy 333.111095 -223.52108) (xy 333.099318 -223.473296)
			(xy 333.095358 -223.424242) (xy 332.766416 -223.424242) (xy 332.765921 -223.448849) (xy 332.758026 -223.497426)
			(xy 332.742442 -223.544107) (xy 332.719571 -223.587684) (xy 332.690006 -223.627028) (xy 332.654513 -223.66112)
			(xy 332.61401 -223.689076) (xy 332.569548 -223.710174) (xy 332.522277 -223.723866) (xy 332.473422 -223.729798)
			(xy 332.424247 -223.727817) (xy 332.376028 -223.717973) (xy 332.330012 -223.700521) (xy 332.287391 -223.675914)
			(xy 332.24927 -223.644789) (xy 332.216635 -223.607952) (xy 332.190332 -223.566356) (xy 332.171041 -223.52108)
			(xy 332.159264 -223.473296) (xy 332.155304 -223.424242) (xy 331.826362 -223.424242) (xy 331.825925 -223.447487)
			(xy 331.818881 -223.493441) (xy 331.804961 -223.537798) (xy 331.79512 -223.558862) (xy 331.787754 -223.573594)
			(xy 331.793088 -223.605344) (xy 332.190852 -224.003108) (xy 332.193138 -224.00514) (xy 332.200302 -224.011555)
			(xy 332.213899 -224.025156) (xy 332.220316 -224.032318) (xy 332.222348 -224.034604) (xy 332.456028 -224.268284)
			(xy 332.463128 -224.274841) (xy 332.480842 -224.282534) (xy 332.500144 -224.283113) (xy 332.509368 -224.280222)
			(xy 332.60792 -224.244408) (xy 332.6257 -224.221294) (xy 332.62697 -224.206562) (xy 332.62976 -224.181598)
			(xy 332.642449 -224.133) (xy 332.662922 -224.087134) (xy 332.690627 -224.045239) (xy 332.724816 -224.008443)
			(xy 332.764567 -223.97774) (xy 332.808807 -223.953957) (xy 332.856344 -223.937737) (xy 332.905894 -223.929517)
			(xy 332.931008 -223.92894) (xy 332.954999 -223.929387) (xy 333.002391 -223.936895) (xy 333.048025 -223.951725)
			(xy 333.090776 -223.973511) (xy 333.129593 -224.001718) (xy 333.163519 -224.03565) (xy 333.191718 -224.074472)
			(xy 333.213497 -224.117227) (xy 333.228318 -224.162863) (xy 333.235818 -224.210257) (xy 333.236316 -224.234248)
			(xy 334.505312 -224.234248) (xy 334.509272 -224.185194) (xy 334.521049 -224.13741) (xy 334.54034 -224.092134)
			(xy 334.566643 -224.050538) (xy 334.599278 -224.013701) (xy 334.637399 -223.982576) (xy 334.68002 -223.957969)
			(xy 334.726036 -223.940517) (xy 334.774255 -223.930673) (xy 334.82343 -223.928692) (xy 334.872285 -223.934624)
			(xy 334.919556 -223.948316) (xy 334.964018 -223.969414) (xy 335.004521 -223.99737) (xy 335.040014 -224.031462)
			(xy 335.069579 -224.070806) (xy 335.09245 -224.114383) (xy 335.108034 -224.161064) (xy 335.115929 -224.209641)
			(xy 335.116424 -224.234248) (xy 335.445366 -224.234248) (xy 335.449326 -224.185194) (xy 335.461103 -224.13741)
			(xy 335.480394 -224.092134) (xy 335.506697 -224.050538) (xy 335.539332 -224.013701) (xy 335.577453 -223.982576)
			(xy 335.620074 -223.957969) (xy 335.66609 -223.940517) (xy 335.714309 -223.930673) (xy 335.763484 -223.928692)
			(xy 335.812339 -223.934624) (xy 335.85961 -223.948316) (xy 335.904072 -223.969414) (xy 335.944575 -223.99737)
			(xy 335.980068 -224.031462) (xy 336.009633 -224.070806) (xy 336.032504 -224.114383) (xy 336.048088 -224.161064)
			(xy 336.055983 -224.209641) (xy 336.056478 -224.234248) (xy 337.32522 -224.234248) (xy 337.32918 -224.185194)
			(xy 337.340957 -224.13741) (xy 337.360248 -224.092134) (xy 337.386551 -224.050538) (xy 337.419186 -224.013701)
			(xy 337.457307 -223.982576) (xy 337.499928 -223.957969) (xy 337.545944 -223.940517) (xy 337.594163 -223.930673)
			(xy 337.643338 -223.928692) (xy 337.692193 -223.934624) (xy 337.739464 -223.948316) (xy 337.783926 -223.969414)
			(xy 337.824429 -223.99737) (xy 337.859922 -224.031462) (xy 337.889487 -224.070806) (xy 337.912358 -224.114383)
			(xy 337.927942 -224.161064) (xy 337.935837 -224.209641) (xy 337.936332 -224.234248) (xy 338.265274 -224.234248)
			(xy 338.269234 -224.185194) (xy 338.281011 -224.13741) (xy 338.300302 -224.092134) (xy 338.326605 -224.050538)
			(xy 338.35924 -224.013701) (xy 338.397361 -223.982576) (xy 338.439982 -223.957969) (xy 338.485998 -223.940517)
			(xy 338.534217 -223.930673) (xy 338.583392 -223.928692) (xy 338.632247 -223.934624) (xy 338.679518 -223.948316)
			(xy 338.72398 -223.969414) (xy 338.764483 -223.99737) (xy 338.799976 -224.031462) (xy 338.829541 -224.070806)
			(xy 338.852412 -224.114383) (xy 338.867996 -224.161064) (xy 338.875891 -224.209641) (xy 338.876386 -224.234248)
			(xy 339.205328 -224.234248) (xy 339.209288 -224.185194) (xy 339.221065 -224.13741) (xy 339.240356 -224.092134)
			(xy 339.266659 -224.050538) (xy 339.299294 -224.013701) (xy 339.337415 -223.982576) (xy 339.380036 -223.957969)
			(xy 339.426052 -223.940517) (xy 339.474271 -223.930673) (xy 339.523446 -223.928692) (xy 339.572301 -223.934624)
			(xy 339.619572 -223.948316) (xy 339.664034 -223.969414) (xy 339.704537 -223.99737) (xy 339.74003 -224.031462)
			(xy 339.769595 -224.070806) (xy 339.792466 -224.114383) (xy 339.80805 -224.161064) (xy 339.815945 -224.209641)
			(xy 339.81644 -224.234248) (xy 341.085182 -224.234248) (xy 341.089142 -224.185194) (xy 341.100919 -224.13741)
			(xy 341.12021 -224.092134) (xy 341.146513 -224.050538) (xy 341.179148 -224.013701) (xy 341.217269 -223.982576)
			(xy 341.25989 -223.957969) (xy 341.305906 -223.940517) (xy 341.354125 -223.930673) (xy 341.4033 -223.928692)
			(xy 341.452155 -223.934624) (xy 341.499426 -223.948316) (xy 341.543888 -223.969414) (xy 341.584391 -223.99737)
			(xy 341.619884 -224.031462) (xy 341.649449 -224.070806) (xy 341.67232 -224.114383) (xy 341.687904 -224.161064)
			(xy 341.695799 -224.209641) (xy 341.696294 -224.234248) (xy 342.025236 -224.234248) (xy 342.029196 -224.185194)
			(xy 342.040973 -224.13741) (xy 342.060264 -224.092134) (xy 342.086567 -224.050538) (xy 342.119202 -224.013701)
			(xy 342.157323 -223.982576) (xy 342.199944 -223.957969) (xy 342.24596 -223.940517) (xy 342.294179 -223.930673)
			(xy 342.343354 -223.928692) (xy 342.392209 -223.934624) (xy 342.43948 -223.948316) (xy 342.483942 -223.969414)
			(xy 342.524445 -223.99737) (xy 342.559938 -224.031462) (xy 342.589503 -224.070806) (xy 342.612374 -224.114383)
			(xy 342.627958 -224.161064) (xy 342.635853 -224.209641) (xy 342.636348 -224.234248) (xy 342.635853 -224.258855)
			(xy 342.627958 -224.307432) (xy 342.612374 -224.354113) (xy 342.589503 -224.39769) (xy 342.559938 -224.437034)
			(xy 342.524445 -224.471126) (xy 342.483942 -224.499082) (xy 342.43948 -224.52018) (xy 342.392209 -224.533872)
			(xy 342.343354 -224.539804) (xy 342.294179 -224.537823) (xy 342.24596 -224.527979) (xy 342.199944 -224.510527)
			(xy 342.157323 -224.48592) (xy 342.119202 -224.454795) (xy 342.086567 -224.417958) (xy 342.060264 -224.376362)
			(xy 342.040973 -224.331086) (xy 342.029196 -224.283302) (xy 342.025236 -224.234248) (xy 341.696294 -224.234248)
			(xy 341.695799 -224.258855) (xy 341.687904 -224.307432) (xy 341.67232 -224.354113) (xy 341.649449 -224.39769)
			(xy 341.619884 -224.437034) (xy 341.584391 -224.471126) (xy 341.543888 -224.499082) (xy 341.499426 -224.52018)
			(xy 341.452155 -224.533872) (xy 341.4033 -224.539804) (xy 341.354125 -224.537823) (xy 341.305906 -224.527979)
			(xy 341.25989 -224.510527) (xy 341.217269 -224.48592) (xy 341.179148 -224.454795) (xy 341.146513 -224.417958)
			(xy 341.12021 -224.376362) (xy 341.100919 -224.331086) (xy 341.089142 -224.283302) (xy 341.085182 -224.234248)
			(xy 339.81644 -224.234248) (xy 339.815945 -224.258855) (xy 339.80805 -224.307432) (xy 339.792466 -224.354113)
			(xy 339.769595 -224.39769) (xy 339.74003 -224.437034) (xy 339.704537 -224.471126) (xy 339.664034 -224.499082)
			(xy 339.619572 -224.52018) (xy 339.572301 -224.533872) (xy 339.523446 -224.539804) (xy 339.474271 -224.537823)
			(xy 339.426052 -224.527979) (xy 339.380036 -224.510527) (xy 339.337415 -224.48592) (xy 339.299294 -224.454795)
			(xy 339.266659 -224.417958) (xy 339.240356 -224.376362) (xy 339.221065 -224.331086) (xy 339.209288 -224.283302)
			(xy 339.205328 -224.234248) (xy 338.876386 -224.234248) (xy 338.875891 -224.258855) (xy 338.867996 -224.307432)
			(xy 338.852412 -224.354113) (xy 338.829541 -224.39769) (xy 338.799976 -224.437034) (xy 338.764483 -224.471126)
			(xy 338.72398 -224.499082) (xy 338.679518 -224.52018) (xy 338.632247 -224.533872) (xy 338.583392 -224.539804)
			(xy 338.534217 -224.537823) (xy 338.485998 -224.527979) (xy 338.439982 -224.510527) (xy 338.397361 -224.48592)
			(xy 338.35924 -224.454795) (xy 338.326605 -224.417958) (xy 338.300302 -224.376362) (xy 338.281011 -224.331086)
			(xy 338.269234 -224.283302) (xy 338.265274 -224.234248) (xy 337.936332 -224.234248) (xy 337.935837 -224.258855)
			(xy 337.927942 -224.307432) (xy 337.912358 -224.354113) (xy 337.889487 -224.39769) (xy 337.859922 -224.437034)
			(xy 337.824429 -224.471126) (xy 337.783926 -224.499082) (xy 337.739464 -224.52018) (xy 337.692193 -224.533872)
			(xy 337.643338 -224.539804) (xy 337.594163 -224.537823) (xy 337.545944 -224.527979) (xy 337.499928 -224.510527)
			(xy 337.457307 -224.48592) (xy 337.419186 -224.454795) (xy 337.386551 -224.417958) (xy 337.360248 -224.376362)
			(xy 337.340957 -224.331086) (xy 337.32918 -224.283302) (xy 337.32522 -224.234248) (xy 336.056478 -224.234248)
			(xy 336.055983 -224.258855) (xy 336.048088 -224.307432) (xy 336.032504 -224.354113) (xy 336.009633 -224.39769)
			(xy 335.980068 -224.437034) (xy 335.944575 -224.471126) (xy 335.904072 -224.499082) (xy 335.85961 -224.52018)
			(xy 335.812339 -224.533872) (xy 335.763484 -224.539804) (xy 335.714309 -224.537823) (xy 335.66609 -224.527979)
			(xy 335.620074 -224.510527) (xy 335.577453 -224.48592) (xy 335.539332 -224.454795) (xy 335.506697 -224.417958)
			(xy 335.480394 -224.376362) (xy 335.461103 -224.331086) (xy 335.449326 -224.283302) (xy 335.445366 -224.234248)
			(xy 335.116424 -224.234248) (xy 335.115929 -224.258855) (xy 335.108034 -224.307432) (xy 335.09245 -224.354113)
			(xy 335.069579 -224.39769) (xy 335.040014 -224.437034) (xy 335.004521 -224.471126) (xy 334.964018 -224.499082)
			(xy 334.919556 -224.52018) (xy 334.872285 -224.533872) (xy 334.82343 -224.539804) (xy 334.774255 -224.537823)
			(xy 334.726036 -224.527979) (xy 334.68002 -224.510527) (xy 334.637399 -224.48592) (xy 334.599278 -224.454795)
			(xy 334.566643 -224.417958) (xy 334.54034 -224.376362) (xy 334.521049 -224.331086) (xy 334.509272 -224.283302)
			(xy 334.505312 -224.234248) (xy 333.236316 -224.234248) (xy 333.235851 -224.258855) (xy 333.227963 -224.307434)
			(xy 333.212383 -224.354117) (xy 333.189514 -224.397696) (xy 333.15995 -224.437041) (xy 333.124456 -224.471133)
			(xy 333.083951 -224.499088) (xy 333.039487 -224.520182) (xy 332.992213 -224.533869) (xy 332.967838 -224.53727)
			(xy 332.953868 -224.539048) (xy 332.932278 -224.555558) (xy 332.895702 -224.644204) (xy 332.895702 -224.644712)
			(xy 332.892146 -224.653094) (xy 332.891384 -224.671636) (xy 332.901036 -224.699068) (xy 332.905862 -224.705418)
			(xy 332.919832 -224.724722) (xy 332.928722 -224.738184) (xy 332.92923 -224.738946) (xy 332.931262 -224.74174)
			(xy 332.939644 -224.7519) (xy 332.941422 -224.753678) (xy 333.029814 -224.84207) (xy 333.037425 -224.84906)
			(xy 333.056567 -224.856796) (xy 333.066898 -224.857056) (xy 333.149194 -224.855278) (xy 333.167736 -224.846896)
			(xy 333.174848 -224.839276) (xy 333.176118 -224.838006) (xy 333.176372 -224.837752) (xy 333.18323 -224.83064)
			(xy 333.183484 -224.830132) (xy 333.184246 -224.82937) (xy 333.201303 -224.81279) (xy 333.239609 -224.784589)
			(xy 333.281824 -224.762671) (xy 333.326928 -224.747564) (xy 333.373829 -224.739634) (xy 333.397606 -224.738946)
			(xy 333.404718 -224.738946) (xy 333.4284 -224.739666) (xy 333.475121 -224.747524) (xy 333.520068 -224.762507)
			(xy 333.56216 -224.784253) (xy 333.600387 -224.81224) (xy 333.633832 -224.845798) (xy 333.66169 -224.88412)
			(xy 333.683294 -224.926285) (xy 333.698124 -224.971282) (xy 333.705824 -225.01803) (xy 333.70647 -225.041714)
			(xy 333.70647 -225.044508) (xy 333.705693 -225.074936) (xy 333.693537 -225.134568) (xy 333.68234 -225.162872)
			(xy 333.677006 -225.175826) (xy 333.680562 -225.20275) (xy 333.741522 -225.28149) (xy 333.749107 -225.290331)
			(xy 333.770018 -225.300539) (xy 333.781654 -225.301048) (xy 333.789782 -225.301048) (xy 333.793338 -225.30054)
			(xy 333.812665 -225.297947) (xy 333.851563 -225.295148) (xy 333.871062 -225.294952) (xy 333.891074 -225.295154)
			(xy 333.93099 -225.298078) (xy 333.950818 -225.300794) (xy 333.95285 -225.301048) (xy 333.957168 -225.301302)
			(xy 333.969673 -225.301484) (xy 333.992449 -225.291227) (xy 334.000602 -225.281744) (xy 334.05318 -225.213672)
			(xy 334.058299 -225.206406) (xy 334.063709 -225.189489) (xy 334.063049 -225.171741) (xy 334.060038 -225.16338)
			(xy 334.059784 -225.162618) (xy 334.05953 -225.162364) (xy 334.048576 -225.134402) (xy 334.036678 -225.075546)
			(xy 334.035908 -225.045524) (xy 334.035908 -225.039936) (xy 334.036694 -225.016164) (xy 334.044724 -224.969287)
			(xy 334.059926 -224.924221) (xy 334.081932 -224.882058) (xy 334.11021 -224.843817) (xy 334.144075 -224.810423)
			(xy 334.182708 -224.782685) (xy 334.225176 -224.761272) (xy 334.27045 -224.746703) (xy 334.317436 -224.739331)
			(xy 334.341216 -224.738946) (xy 334.365132 -224.739412) (xy 334.412378 -224.746872) (xy 334.457882 -224.761608)
			(xy 334.500533 -224.783259) (xy 334.539286 -224.811295) (xy 334.573194 -224.84503) (xy 334.601427 -224.88364)
			(xy 334.623294 -224.92618) (xy 334.638262 -224.97161) (xy 334.645962 -225.018817) (xy 334.646524 -225.04273)
			(xy 334.646524 -225.044254) (xy 334.975212 -225.044254) (xy 334.979172 -224.9952) (xy 334.990949 -224.947416)
			(xy 335.01024 -224.90214) (xy 335.036543 -224.860544) (xy 335.069178 -224.823707) (xy 335.107299 -224.792582)
			(xy 335.14992 -224.767975) (xy 335.195936 -224.750523) (xy 335.244155 -224.740679) (xy 335.29333 -224.738698)
			(xy 335.342185 -224.74463) (xy 335.389456 -224.758322) (xy 335.433918 -224.77942) (xy 335.474421 -224.807376)
			(xy 335.509914 -224.841468) (xy 335.539479 -224.880812) (xy 335.56235 -224.924389) (xy 335.577934 -224.97107)
			(xy 335.585829 -225.019647) (xy 335.586324 -225.044254) (xy 335.915266 -225.044254) (xy 335.919226 -224.9952)
			(xy 335.931003 -224.947416) (xy 335.950294 -224.90214) (xy 335.976597 -224.860544) (xy 336.009232 -224.823707)
			(xy 336.047353 -224.792582) (xy 336.089974 -224.767975) (xy 336.13599 -224.750523) (xy 336.184209 -224.740679)
			(xy 336.233384 -224.738698) (xy 336.282239 -224.74463) (xy 336.32951 -224.758322) (xy 336.373972 -224.77942)
			(xy 336.414475 -224.807376) (xy 336.449968 -224.841468) (xy 336.479533 -224.880812) (xy 336.502404 -224.924389)
			(xy 336.517988 -224.97107) (xy 336.525883 -225.019647) (xy 336.526378 -225.044254) (xy 336.85532 -225.044254)
			(xy 336.85928 -224.9952) (xy 336.871057 -224.947416) (xy 336.890348 -224.90214) (xy 336.916651 -224.860544)
			(xy 336.949286 -224.823707) (xy 336.987407 -224.792582) (xy 337.030028 -224.767975) (xy 337.076044 -224.750523)
			(xy 337.124263 -224.740679) (xy 337.173438 -224.738698) (xy 337.222293 -224.74463) (xy 337.269564 -224.758322)
			(xy 337.314026 -224.77942) (xy 337.354529 -224.807376) (xy 337.390022 -224.841468) (xy 337.419587 -224.880812)
			(xy 337.442458 -224.924389) (xy 337.458042 -224.97107) (xy 337.465937 -225.019647) (xy 337.466432 -225.044254)
			(xy 337.795374 -225.044254) (xy 337.799334 -224.9952) (xy 337.811111 -224.947416) (xy 337.830402 -224.90214)
			(xy 337.856705 -224.860544) (xy 337.88934 -224.823707) (xy 337.927461 -224.792582) (xy 337.970082 -224.767975)
			(xy 338.016098 -224.750523) (xy 338.064317 -224.740679) (xy 338.113492 -224.738698) (xy 338.162347 -224.74463)
			(xy 338.209618 -224.758322) (xy 338.25408 -224.77942) (xy 338.294583 -224.807376) (xy 338.330076 -224.841468)
			(xy 338.359641 -224.880812) (xy 338.382512 -224.924389) (xy 338.398096 -224.97107) (xy 338.405991 -225.019647)
			(xy 338.406486 -225.044254) (xy 338.724743 -225.044254) (xy 338.728838 -224.993526) (xy 338.741017 -224.944112)
			(xy 338.760965 -224.897292) (xy 338.788166 -224.854278) (xy 338.821914 -224.816184) (xy 338.861336 -224.783997)
			(xy 338.90541 -224.758551) (xy 338.952996 -224.740504) (xy 339.00286 -224.730324) (xy 339.053712 -224.728275)
			(xy 339.104233 -224.734409) (xy 339.153117 -224.748569) (xy 339.199096 -224.770386) (xy 339.24098 -224.799296)
			(xy 339.277684 -224.834551) (xy 339.308257 -224.875237) (xy 339.331908 -224.9203) (xy 339.348024 -224.968574)
			(xy 339.356188 -225.018808) (xy 339.3567 -225.044254) (xy 339.675228 -225.044254) (xy 339.679188 -224.9952)
			(xy 339.690965 -224.947416) (xy 339.710256 -224.90214) (xy 339.736559 -224.860544) (xy 339.769194 -224.823707)
			(xy 339.807315 -224.792582) (xy 339.849936 -224.767975) (xy 339.895952 -224.750523) (xy 339.944171 -224.740679)
			(xy 339.993346 -224.738698) (xy 340.042201 -224.74463) (xy 340.089472 -224.758322) (xy 340.133934 -224.77942)
			(xy 340.174437 -224.807376) (xy 340.20993 -224.841468) (xy 340.239495 -224.880812) (xy 340.262366 -224.924389)
			(xy 340.27795 -224.97107) (xy 340.285845 -225.019647) (xy 340.28634 -225.044254) (xy 340.615282 -225.044254)
			(xy 340.619242 -224.9952) (xy 340.631019 -224.947416) (xy 340.65031 -224.90214) (xy 340.676613 -224.860544)
			(xy 340.709248 -224.823707) (xy 340.747369 -224.792582) (xy 340.78999 -224.767975) (xy 340.836006 -224.750523)
			(xy 340.884225 -224.740679) (xy 340.9334 -224.738698) (xy 340.982255 -224.74463) (xy 341.029526 -224.758322)
			(xy 341.073988 -224.77942) (xy 341.114491 -224.807376) (xy 341.149984 -224.841468) (xy 341.179549 -224.880812)
			(xy 341.20242 -224.924389) (xy 341.218004 -224.97107) (xy 341.225899 -225.019647) (xy 341.226394 -225.044254)
			(xy 341.544905 -225.044254) (xy 341.549 -224.993526) (xy 341.561179 -224.944112) (xy 341.581127 -224.897292)
			(xy 341.608328 -224.854278) (xy 341.642076 -224.816184) (xy 341.681498 -224.783997) (xy 341.725572 -224.758551)
			(xy 341.773158 -224.740504) (xy 341.823022 -224.730324) (xy 341.873874 -224.728275) (xy 341.924395 -224.734409)
			(xy 341.973279 -224.748569) (xy 342.019258 -224.770386) (xy 342.061142 -224.799296) (xy 342.097846 -224.834551)
			(xy 342.128419 -224.875237) (xy 342.15207 -224.9203) (xy 342.168186 -224.968574) (xy 342.17635 -225.018808)
			(xy 342.176862 -225.044254) (xy 342.49539 -225.044254) (xy 342.49935 -224.9952) (xy 342.511127 -224.947416)
			(xy 342.530418 -224.90214) (xy 342.556721 -224.860544) (xy 342.589356 -224.823707) (xy 342.627477 -224.792582)
			(xy 342.670098 -224.767975) (xy 342.716114 -224.750523) (xy 342.764333 -224.740679) (xy 342.813508 -224.738698)
			(xy 342.862363 -224.74463) (xy 342.909634 -224.758322) (xy 342.954096 -224.77942) (xy 342.994599 -224.807376)
			(xy 343.030092 -224.841468) (xy 343.059657 -224.880812) (xy 343.082528 -224.924389) (xy 343.098112 -224.97107)
			(xy 343.106007 -225.019647) (xy 343.106502 -225.044254) (xy 343.106007 -225.068861) (xy 343.098112 -225.117438)
			(xy 343.082528 -225.164119) (xy 343.059657 -225.207696) (xy 343.030092 -225.24704) (xy 342.994599 -225.281132)
			(xy 342.954096 -225.309088) (xy 342.909634 -225.330186) (xy 342.862363 -225.343878) (xy 342.813508 -225.34981)
			(xy 342.764333 -225.347829) (xy 342.716114 -225.337985) (xy 342.670098 -225.320533) (xy 342.627477 -225.295926)
			(xy 342.589356 -225.264801) (xy 342.556721 -225.227964) (xy 342.530418 -225.186368) (xy 342.511127 -225.141092)
			(xy 342.49935 -225.093308) (xy 342.49539 -225.044254) (xy 342.176862 -225.044254) (xy 342.17635 -225.0697)
			(xy 342.168186 -225.119934) (xy 342.15207 -225.168208) (xy 342.128419 -225.213271) (xy 342.097846 -225.253957)
			(xy 342.061142 -225.289212) (xy 342.019258 -225.318122) (xy 341.973279 -225.339939) (xy 341.924395 -225.354099)
			(xy 341.873874 -225.360233) (xy 341.823022 -225.358184) (xy 341.773158 -225.348004) (xy 341.725572 -225.329957)
			(xy 341.681498 -225.304511) (xy 341.642076 -225.272324) (xy 341.608328 -225.23423) (xy 341.581127 -225.191216)
			(xy 341.561179 -225.144396) (xy 341.549 -225.094982) (xy 341.544905 -225.044254) (xy 341.226394 -225.044254)
			(xy 341.225899 -225.068861) (xy 341.218004 -225.117438) (xy 341.20242 -225.164119) (xy 341.179549 -225.207696)
			(xy 341.149984 -225.24704) (xy 341.114491 -225.281132) (xy 341.073988 -225.309088) (xy 341.029526 -225.330186)
			(xy 340.982255 -225.343878) (xy 340.9334 -225.34981) (xy 340.884225 -225.347829) (xy 340.836006 -225.337985)
			(xy 340.78999 -225.320533) (xy 340.747369 -225.295926) (xy 340.709248 -225.264801) (xy 340.676613 -225.227964)
			(xy 340.65031 -225.186368) (xy 340.631019 -225.141092) (xy 340.619242 -225.093308) (xy 340.615282 -225.044254)
			(xy 340.28634 -225.044254) (xy 340.285845 -225.068861) (xy 340.27795 -225.117438) (xy 340.262366 -225.164119)
			(xy 340.239495 -225.207696) (xy 340.20993 -225.24704) (xy 340.174437 -225.281132) (xy 340.133934 -225.309088)
			(xy 340.089472 -225.330186) (xy 340.042201 -225.343878) (xy 339.993346 -225.34981) (xy 339.944171 -225.347829)
			(xy 339.895952 -225.337985) (xy 339.849936 -225.320533) (xy 339.807315 -225.295926) (xy 339.769194 -225.264801)
			(xy 339.736559 -225.227964) (xy 339.710256 -225.186368) (xy 339.690965 -225.141092) (xy 339.679188 -225.093308)
			(xy 339.675228 -225.044254) (xy 339.3567 -225.044254) (xy 339.356188 -225.0697) (xy 339.348024 -225.119934)
			(xy 339.331908 -225.168208) (xy 339.308257 -225.213271) (xy 339.277684 -225.253957) (xy 339.24098 -225.289212)
			(xy 339.199096 -225.318122) (xy 339.153117 -225.339939) (xy 339.104233 -225.354099) (xy 339.053712 -225.360233)
			(xy 339.00286 -225.358184) (xy 338.952996 -225.348004) (xy 338.90541 -225.329957) (xy 338.861336 -225.304511)
			(xy 338.821914 -225.272324) (xy 338.788166 -225.23423) (xy 338.760965 -225.191216) (xy 338.741017 -225.144396)
			(xy 338.728838 -225.094982) (xy 338.724743 -225.044254) (xy 338.406486 -225.044254) (xy 338.405991 -225.068861)
			(xy 338.398096 -225.117438) (xy 338.382512 -225.164119) (xy 338.359641 -225.207696) (xy 338.330076 -225.24704)
			(xy 338.294583 -225.281132) (xy 338.25408 -225.309088) (xy 338.209618 -225.330186) (xy 338.162347 -225.343878)
			(xy 338.113492 -225.34981) (xy 338.064317 -225.347829) (xy 338.016098 -225.337985) (xy 337.970082 -225.320533)
			(xy 337.927461 -225.295926) (xy 337.88934 -225.264801) (xy 337.856705 -225.227964) (xy 337.830402 -225.186368)
			(xy 337.811111 -225.141092) (xy 337.799334 -225.093308) (xy 337.795374 -225.044254) (xy 337.466432 -225.044254)
			(xy 337.465937 -225.068861) (xy 337.458042 -225.117438) (xy 337.442458 -225.164119) (xy 337.419587 -225.207696)
			(xy 337.390022 -225.24704) (xy 337.354529 -225.281132) (xy 337.314026 -225.309088) (xy 337.269564 -225.330186)
			(xy 337.222293 -225.343878) (xy 337.173438 -225.34981) (xy 337.124263 -225.347829) (xy 337.076044 -225.337985)
			(xy 337.030028 -225.320533) (xy 336.987407 -225.295926) (xy 336.949286 -225.264801) (xy 336.916651 -225.227964)
			(xy 336.890348 -225.186368) (xy 336.871057 -225.141092) (xy 336.85928 -225.093308) (xy 336.85532 -225.044254)
			(xy 336.526378 -225.044254) (xy 336.525883 -225.068861) (xy 336.517988 -225.117438) (xy 336.502404 -225.164119)
			(xy 336.479533 -225.207696) (xy 336.449968 -225.24704) (xy 336.414475 -225.281132) (xy 336.373972 -225.309088)
			(xy 336.32951 -225.330186) (xy 336.282239 -225.343878) (xy 336.233384 -225.34981) (xy 336.184209 -225.347829)
			(xy 336.13599 -225.337985) (xy 336.089974 -225.320533) (xy 336.047353 -225.295926) (xy 336.009232 -225.264801)
			(xy 335.976597 -225.227964) (xy 335.950294 -225.186368) (xy 335.931003 -225.141092) (xy 335.919226 -225.093308)
			(xy 335.915266 -225.044254) (xy 335.586324 -225.044254) (xy 335.585829 -225.068861) (xy 335.577934 -225.117438)
			(xy 335.56235 -225.164119) (xy 335.539479 -225.207696) (xy 335.509914 -225.24704) (xy 335.474421 -225.281132)
			(xy 335.433918 -225.309088) (xy 335.389456 -225.330186) (xy 335.342185 -225.343878) (xy 335.29333 -225.34981)
			(xy 335.244155 -225.347829) (xy 335.195936 -225.337985) (xy 335.14992 -225.320533) (xy 335.107299 -225.295926)
			(xy 335.069178 -225.264801) (xy 335.036543 -225.227964) (xy 335.01024 -225.186368) (xy 334.990949 -225.141092)
			(xy 334.979172 -225.093308) (xy 334.975212 -225.044254) (xy 334.646524 -225.044254) (xy 334.646401 -225.056244)
			(xy 334.644495 -225.080148) (xy 334.642714 -225.092006) (xy 334.64246 -225.094038) (xy 334.642206 -225.097086)
			(xy 334.637528 -225.121027) (xy 334.621582 -225.167125) (xy 334.598511 -225.210103) (xy 334.568902 -225.248866)
			(xy 334.533507 -225.28243) (xy 334.493228 -225.309941) (xy 334.449087 -225.330699) (xy 334.402207 -225.344177)
			(xy 334.378046 -225.34753) (xy 334.364076 -225.349308) (xy 334.342486 -225.365564) (xy 334.305656 -225.45421)
			(xy 334.302514 -225.462918) (xy 334.30199 -225.481408) (xy 334.30464 -225.490278) (xy 334.30464 -225.490532)
			(xy 334.31099 -225.50882) (xy 334.315816 -225.51517) (xy 334.336901 -225.54377) (xy 334.372447 -225.605296)
			(xy 334.386682 -225.637852) (xy 334.389386 -225.643835) (xy 334.397356 -225.654261) (xy 334.40243 -225.658426)
			(xy 334.420972 -225.672904) (xy 334.426496 -225.676937) (xy 334.439115 -225.682201) (xy 334.445864 -225.683318)
			(xy 334.516984 -225.69297) (xy 334.52689 -225.693224) (xy 334.537304 -225.692716) (xy 334.546194 -225.688144)
			(xy 334.549963 -225.686253) (xy 334.55686 -225.681403) (xy 334.55991 -225.678492) (xy 334.56499 -225.673412)
			(xy 334.567022 -225.670618) (xy 334.581568 -225.652067) (xy 334.615401 -225.619242) (xy 334.653866 -225.591993)
			(xy 334.696055 -225.570963) (xy 334.740969 -225.556652) (xy 334.787547 -225.549396) (xy 334.811116 -225.548952)
			(xy 334.836374 -225.549475) (xy 334.8862 -225.557792) (xy 334.933978 -225.574196) (xy 334.978404 -225.598241)
			(xy 335.018267 -225.629269) (xy 335.052479 -225.666435) (xy 335.080108 -225.708726) (xy 335.100399 -225.754987)
			(xy 335.1128 -225.803957) (xy 335.116968 -225.85426) (xy 335.445366 -225.85426) (xy 335.449326 -225.805206)
			(xy 335.461103 -225.757422) (xy 335.480394 -225.712146) (xy 335.506697 -225.67055) (xy 335.539332 -225.633713)
			(xy 335.577453 -225.602588) (xy 335.620074 -225.577981) (xy 335.66609 -225.560529) (xy 335.714309 -225.550685)
			(xy 335.763484 -225.548704) (xy 335.812339 -225.554636) (xy 335.85961 -225.568328) (xy 335.904072 -225.589426)
			(xy 335.944575 -225.617382) (xy 335.980068 -225.651474) (xy 336.009633 -225.690818) (xy 336.032504 -225.734395)
			(xy 336.048088 -225.781076) (xy 336.055983 -225.829653) (xy 336.056478 -225.85426) (xy 336.38542 -225.85426)
			(xy 336.38938 -225.805206) (xy 336.401157 -225.757422) (xy 336.420448 -225.712146) (xy 336.446751 -225.67055)
			(xy 336.479386 -225.633713) (xy 336.517507 -225.602588) (xy 336.560128 -225.577981) (xy 336.606144 -225.560529)
			(xy 336.654363 -225.550685) (xy 336.703538 -225.548704) (xy 336.752393 -225.554636) (xy 336.799664 -225.568328)
			(xy 336.844126 -225.589426) (xy 336.884629 -225.617382) (xy 336.920122 -225.651474) (xy 336.949687 -225.690818)
			(xy 336.972558 -225.734395) (xy 336.988142 -225.781076) (xy 336.996037 -225.829653) (xy 336.996532 -225.85426)
			(xy 337.32522 -225.85426) (xy 337.32918 -225.805206) (xy 337.340957 -225.757422) (xy 337.360248 -225.712146)
			(xy 337.386551 -225.67055) (xy 337.419186 -225.633713) (xy 337.457307 -225.602588) (xy 337.499928 -225.577981)
			(xy 337.545944 -225.560529) (xy 337.594163 -225.550685) (xy 337.643338 -225.548704) (xy 337.692193 -225.554636)
			(xy 337.739464 -225.568328) (xy 337.783926 -225.589426) (xy 337.824429 -225.617382) (xy 337.859922 -225.651474)
			(xy 337.889487 -225.690818) (xy 337.912358 -225.734395) (xy 337.927942 -225.781076) (xy 337.935837 -225.829653)
			(xy 337.936332 -225.85426) (xy 338.254843 -225.85426) (xy 338.258938 -225.803532) (xy 338.271117 -225.754118)
			(xy 338.291065 -225.707298) (xy 338.318266 -225.664284) (xy 338.352014 -225.62619) (xy 338.391436 -225.594003)
			(xy 338.43551 -225.568557) (xy 338.483096 -225.55051) (xy 338.53296 -225.54033) (xy 338.583812 -225.538281)
			(xy 338.634333 -225.544415) (xy 338.683217 -225.558575) (xy 338.729196 -225.580392) (xy 338.77108 -225.609302)
			(xy 338.807784 -225.644557) (xy 338.838357 -225.685243) (xy 338.862008 -225.730306) (xy 338.878124 -225.77858)
			(xy 338.886288 -225.828814) (xy 338.8868 -225.85426) (xy 339.205328 -225.85426) (xy 339.209288 -225.805206)
			(xy 339.221065 -225.757422) (xy 339.240356 -225.712146) (xy 339.266659 -225.67055) (xy 339.299294 -225.633713)
			(xy 339.337415 -225.602588) (xy 339.380036 -225.577981) (xy 339.426052 -225.560529) (xy 339.474271 -225.550685)
			(xy 339.523446 -225.548704) (xy 339.572301 -225.554636) (xy 339.619572 -225.568328) (xy 339.664034 -225.589426)
			(xy 339.704537 -225.617382) (xy 339.74003 -225.651474) (xy 339.769595 -225.690818) (xy 339.792466 -225.734395)
			(xy 339.80805 -225.781076) (xy 339.815945 -225.829653) (xy 339.81644 -225.85426) (xy 340.134951 -225.85426)
			(xy 340.139046 -225.803532) (xy 340.151225 -225.754118) (xy 340.171173 -225.707298) (xy 340.198374 -225.664284)
			(xy 340.232122 -225.62619) (xy 340.271544 -225.594003) (xy 340.315618 -225.568557) (xy 340.363204 -225.55051)
			(xy 340.413068 -225.54033) (xy 340.46392 -225.538281) (xy 340.514441 -225.544415) (xy 340.563325 -225.558575)
			(xy 340.609304 -225.580392) (xy 340.651188 -225.609302) (xy 340.687892 -225.644557) (xy 340.718465 -225.685243)
			(xy 340.742116 -225.730306) (xy 340.758232 -225.77858) (xy 340.766396 -225.828814) (xy 340.766908 -225.85426)
			(xy 341.085182 -225.85426) (xy 341.089142 -225.805206) (xy 341.100919 -225.757422) (xy 341.12021 -225.712146)
			(xy 341.146513 -225.67055) (xy 341.179148 -225.633713) (xy 341.217269 -225.602588) (xy 341.25989 -225.577981)
			(xy 341.305906 -225.560529) (xy 341.354125 -225.550685) (xy 341.4033 -225.548704) (xy 341.452155 -225.554636)
			(xy 341.499426 -225.568328) (xy 341.543888 -225.589426) (xy 341.584391 -225.617382) (xy 341.619884 -225.651474)
			(xy 341.649449 -225.690818) (xy 341.67232 -225.734395) (xy 341.687904 -225.781076) (xy 341.695799 -225.829653)
			(xy 341.696294 -225.85426) (xy 342.014805 -225.85426) (xy 342.0189 -225.803532) (xy 342.031079 -225.754118)
			(xy 342.051027 -225.707298) (xy 342.078228 -225.664284) (xy 342.111976 -225.62619) (xy 342.151398 -225.594003)
			(xy 342.195472 -225.568557) (xy 342.243058 -225.55051) (xy 342.292922 -225.54033) (xy 342.343774 -225.538281)
			(xy 342.394295 -225.544415) (xy 342.443179 -225.558575) (xy 342.489158 -225.580392) (xy 342.531042 -225.609302)
			(xy 342.567746 -225.644557) (xy 342.598319 -225.685243) (xy 342.62197 -225.730306) (xy 342.638086 -225.77858)
			(xy 342.64625 -225.828814) (xy 342.646762 -225.85426) (xy 342.64625 -225.879706) (xy 342.638086 -225.92994)
			(xy 342.62197 -225.978214) (xy 342.598319 -226.023277) (xy 342.567746 -226.063963) (xy 342.531042 -226.099218)
			(xy 342.489158 -226.128128) (xy 342.443179 -226.149945) (xy 342.394295 -226.164105) (xy 342.343774 -226.170239)
			(xy 342.292922 -226.16819) (xy 342.243058 -226.15801) (xy 342.195472 -226.139963) (xy 342.151398 -226.114517)
			(xy 342.111976 -226.08233) (xy 342.078228 -226.044236) (xy 342.051027 -226.001222) (xy 342.031079 -225.954402)
			(xy 342.0189 -225.904988) (xy 342.014805 -225.85426) (xy 341.696294 -225.85426) (xy 341.695799 -225.878867)
			(xy 341.687904 -225.927444) (xy 341.67232 -225.974125) (xy 341.649449 -226.017702) (xy 341.619884 -226.057046)
			(xy 341.584391 -226.091138) (xy 341.543888 -226.119094) (xy 341.499426 -226.140192) (xy 341.452155 -226.153884)
			(xy 341.4033 -226.159816) (xy 341.354125 -226.157835) (xy 341.305906 -226.147991) (xy 341.25989 -226.130539)
			(xy 341.217269 -226.105932) (xy 341.179148 -226.074807) (xy 341.146513 -226.03797) (xy 341.12021 -225.996374)
			(xy 341.100919 -225.951098) (xy 341.089142 -225.903314) (xy 341.085182 -225.85426) (xy 340.766908 -225.85426)
			(xy 340.766396 -225.879706) (xy 340.758232 -225.92994) (xy 340.742116 -225.978214) (xy 340.718465 -226.023277)
			(xy 340.687892 -226.063963) (xy 340.651188 -226.099218) (xy 340.609304 -226.128128) (xy 340.563325 -226.149945)
			(xy 340.514441 -226.164105) (xy 340.46392 -226.170239) (xy 340.413068 -226.16819) (xy 340.363204 -226.15801)
			(xy 340.315618 -226.139963) (xy 340.271544 -226.114517) (xy 340.232122 -226.08233) (xy 340.198374 -226.044236)
			(xy 340.171173 -226.001222) (xy 340.151225 -225.954402) (xy 340.139046 -225.904988) (xy 340.134951 -225.85426)
			(xy 339.81644 -225.85426) (xy 339.815945 -225.878867) (xy 339.80805 -225.927444) (xy 339.792466 -225.974125)
			(xy 339.769595 -226.017702) (xy 339.74003 -226.057046) (xy 339.704537 -226.091138) (xy 339.664034 -226.119094)
			(xy 339.619572 -226.140192) (xy 339.572301 -226.153884) (xy 339.523446 -226.159816) (xy 339.474271 -226.157835)
			(xy 339.426052 -226.147991) (xy 339.380036 -226.130539) (xy 339.337415 -226.105932) (xy 339.299294 -226.074807)
			(xy 339.266659 -226.03797) (xy 339.240356 -225.996374) (xy 339.221065 -225.951098) (xy 339.209288 -225.903314)
			(xy 339.205328 -225.85426) (xy 338.8868 -225.85426) (xy 338.886288 -225.879706) (xy 338.878124 -225.92994)
			(xy 338.862008 -225.978214) (xy 338.838357 -226.023277) (xy 338.807784 -226.063963) (xy 338.77108 -226.099218)
			(xy 338.729196 -226.128128) (xy 338.683217 -226.149945) (xy 338.634333 -226.164105) (xy 338.583812 -226.170239)
			(xy 338.53296 -226.16819) (xy 338.483096 -226.15801) (xy 338.43551 -226.139963) (xy 338.391436 -226.114517)
			(xy 338.352014 -226.08233) (xy 338.318266 -226.044236) (xy 338.291065 -226.001222) (xy 338.271117 -225.954402)
			(xy 338.258938 -225.904988) (xy 338.254843 -225.85426) (xy 337.936332 -225.85426) (xy 337.935837 -225.878867)
			(xy 337.927942 -225.927444) (xy 337.912358 -225.974125) (xy 337.889487 -226.017702) (xy 337.859922 -226.057046)
			(xy 337.824429 -226.091138) (xy 337.783926 -226.119094) (xy 337.739464 -226.140192) (xy 337.692193 -226.153884)
			(xy 337.643338 -226.159816) (xy 337.594163 -226.157835) (xy 337.545944 -226.147991) (xy 337.499928 -226.130539)
			(xy 337.457307 -226.105932) (xy 337.419186 -226.074807) (xy 337.386551 -226.03797) (xy 337.360248 -225.996374)
			(xy 337.340957 -225.951098) (xy 337.32918 -225.903314) (xy 337.32522 -225.85426) (xy 336.996532 -225.85426)
			(xy 336.996037 -225.878867) (xy 336.988142 -225.927444) (xy 336.972558 -225.974125) (xy 336.949687 -226.017702)
			(xy 336.920122 -226.057046) (xy 336.884629 -226.091138) (xy 336.844126 -226.119094) (xy 336.799664 -226.140192)
			(xy 336.752393 -226.153884) (xy 336.703538 -226.159816) (xy 336.654363 -226.157835) (xy 336.606144 -226.147991)
			(xy 336.560128 -226.130539) (xy 336.517507 -226.105932) (xy 336.479386 -226.074807) (xy 336.446751 -226.03797)
			(xy 336.420448 -225.996374) (xy 336.401157 -225.951098) (xy 336.38938 -225.903314) (xy 336.38542 -225.85426)
			(xy 336.056478 -225.85426) (xy 336.055983 -225.878867) (xy 336.048088 -225.927444) (xy 336.032504 -225.974125)
			(xy 336.009633 -226.017702) (xy 335.980068 -226.057046) (xy 335.944575 -226.091138) (xy 335.904072 -226.119094)
			(xy 335.85961 -226.140192) (xy 335.812339 -226.153884) (xy 335.763484 -226.159816) (xy 335.714309 -226.157835)
			(xy 335.66609 -226.147991) (xy 335.620074 -226.130539) (xy 335.577453 -226.105932) (xy 335.539332 -226.074807)
			(xy 335.506697 -226.03797) (xy 335.480394 -225.996374) (xy 335.461103 -225.951098) (xy 335.449326 -225.903314)
			(xy 335.445366 -225.85426) (xy 335.116968 -225.85426) (xy 335.116971 -225.8543) (xy 335.1128 -225.904643)
			(xy 335.100399 -225.953613) (xy 335.080108 -225.999874) (xy 335.052479 -226.042165) (xy 335.018267 -226.079331)
			(xy 334.978404 -226.110359) (xy 334.933978 -226.134404) (xy 334.8862 -226.150808) (xy 334.836374 -226.159125)
			(xy 334.811116 -226.159568) (xy 334.787545 -226.159133) (xy 334.740962 -226.151895) (xy 334.696044 -226.137589)
			(xy 334.653855 -226.116555) (xy 334.615398 -226.08929) (xy 334.581584 -226.056443) (xy 334.567022 -226.037902)
			(xy 334.56499 -226.035108) (xy 334.55991 -226.030028) (xy 334.553345 -226.023907) (xy 334.537073 -226.016358)
			(xy 334.52816 -226.015296) (xy 334.522572 -226.014788) (xy 334.432148 -226.02698) (xy 334.423227 -226.028523)
			(xy 334.407228 -226.03697) (xy 334.395156 -226.050445) (xy 334.391508 -226.05873) (xy 334.383586 -226.078437)
			(xy 334.365153 -226.116707) (xy 334.354678 -226.135184) (xy 334.312768 -226.20732) (xy 334.311498 -226.209098)
			(xy 334.303878 -226.220528) (xy 334.3021 -226.247706) (xy 334.338676 -226.322128) (xy 334.341552 -226.327461)
			(xy 334.349382 -226.336703) (xy 334.35417 -226.340416) (xy 334.382618 -226.361498) (xy 334.394302 -226.36353)
			(xy 334.417561 -226.368086) (xy 334.462401 -226.383432) (xy 334.504331 -226.405525) (xy 334.542341 -226.433834)
			(xy 334.575518 -226.467678) (xy 334.603066 -226.506244) (xy 334.62432 -226.548604) (xy 334.638772 -226.593741)
			(xy 334.646072 -226.640569) (xy 334.646524 -226.664266) (xy 334.975212 -226.664266) (xy 334.979172 -226.615212)
			(xy 334.990949 -226.567428) (xy 335.01024 -226.522152) (xy 335.036543 -226.480556) (xy 335.069178 -226.443719)
			(xy 335.107299 -226.412594) (xy 335.14992 -226.387987) (xy 335.195936 -226.370535) (xy 335.244155 -226.360691)
			(xy 335.29333 -226.35871) (xy 335.342185 -226.364642) (xy 335.389456 -226.378334) (xy 335.433918 -226.399432)
			(xy 335.474421 -226.427388) (xy 335.509914 -226.46148) (xy 335.539479 -226.500824) (xy 335.56235 -226.544401)
			(xy 335.577934 -226.591082) (xy 335.585829 -226.639659) (xy 335.586324 -226.664266) (xy 335.915266 -226.664266)
			(xy 335.919226 -226.615212) (xy 335.931003 -226.567428) (xy 335.950294 -226.522152) (xy 335.976597 -226.480556)
			(xy 336.009232 -226.443719) (xy 336.047353 -226.412594) (xy 336.089974 -226.387987) (xy 336.13599 -226.370535)
			(xy 336.184209 -226.360691) (xy 336.233384 -226.35871) (xy 336.282239 -226.364642) (xy 336.32951 -226.378334)
			(xy 336.373972 -226.399432) (xy 336.414475 -226.427388) (xy 336.449968 -226.46148) (xy 336.479533 -226.500824)
			(xy 336.502404 -226.544401) (xy 336.517988 -226.591082) (xy 336.525883 -226.639659) (xy 336.526378 -226.664266)
			(xy 336.85532 -226.664266) (xy 336.85928 -226.615212) (xy 336.871057 -226.567428) (xy 336.890348 -226.522152)
			(xy 336.916651 -226.480556) (xy 336.949286 -226.443719) (xy 336.987407 -226.412594) (xy 337.030028 -226.387987)
			(xy 337.076044 -226.370535) (xy 337.124263 -226.360691) (xy 337.173438 -226.35871) (xy 337.222293 -226.364642)
			(xy 337.269564 -226.378334) (xy 337.314026 -226.399432) (xy 337.354529 -226.427388) (xy 337.390022 -226.46148)
			(xy 337.419587 -226.500824) (xy 337.442458 -226.544401) (xy 337.458042 -226.591082) (xy 337.465937 -226.639659)
			(xy 337.466432 -226.664266) (xy 337.795374 -226.664266) (xy 337.799334 -226.615212) (xy 337.811111 -226.567428)
			(xy 337.830402 -226.522152) (xy 337.856705 -226.480556) (xy 337.88934 -226.443719) (xy 337.927461 -226.412594)
			(xy 337.970082 -226.387987) (xy 338.016098 -226.370535) (xy 338.064317 -226.360691) (xy 338.113492 -226.35871)
			(xy 338.162347 -226.364642) (xy 338.209618 -226.378334) (xy 338.25408 -226.399432) (xy 338.294583 -226.427388)
			(xy 338.330076 -226.46148) (xy 338.359641 -226.500824) (xy 338.382512 -226.544401) (xy 338.398096 -226.591082)
			(xy 338.405991 -226.639659) (xy 338.406486 -226.664266) (xy 338.724743 -226.664266) (xy 338.728838 -226.613538)
			(xy 338.741017 -226.564124) (xy 338.760965 -226.517304) (xy 338.788166 -226.47429) (xy 338.821914 -226.436196)
			(xy 338.861336 -226.404009) (xy 338.90541 -226.378563) (xy 338.952996 -226.360516) (xy 339.00286 -226.350336)
			(xy 339.053712 -226.348287) (xy 339.104233 -226.354421) (xy 339.153117 -226.368581) (xy 339.199096 -226.390398)
			(xy 339.24098 -226.419308) (xy 339.277684 -226.454563) (xy 339.308257 -226.495249) (xy 339.331908 -226.540312)
			(xy 339.348024 -226.588586) (xy 339.356188 -226.63882) (xy 339.3567 -226.664266) (xy 339.664797 -226.664266)
			(xy 339.668892 -226.613538) (xy 339.681071 -226.564124) (xy 339.701019 -226.517304) (xy 339.72822 -226.47429)
			(xy 339.761968 -226.436196) (xy 339.80139 -226.404009) (xy 339.845464 -226.378563) (xy 339.89305 -226.360516)
			(xy 339.942914 -226.350336) (xy 339.993766 -226.348287) (xy 340.044287 -226.354421) (xy 340.093171 -226.368581)
			(xy 340.13915 -226.390398) (xy 340.181034 -226.419308) (xy 340.217738 -226.454563) (xy 340.248311 -226.495249)
			(xy 340.271962 -226.540312) (xy 340.288078 -226.588586) (xy 340.296242 -226.63882) (xy 340.296754 -226.664266)
			(xy 340.615282 -226.664266) (xy 340.619242 -226.615212) (xy 340.631019 -226.567428) (xy 340.65031 -226.522152)
			(xy 340.676613 -226.480556) (xy 340.709248 -226.443719) (xy 340.747369 -226.412594) (xy 340.78999 -226.387987)
			(xy 340.836006 -226.370535) (xy 340.884225 -226.360691) (xy 340.9334 -226.35871) (xy 340.982255 -226.364642)
			(xy 341.029526 -226.378334) (xy 341.073988 -226.399432) (xy 341.114491 -226.427388) (xy 341.149984 -226.46148)
			(xy 341.179549 -226.500824) (xy 341.20242 -226.544401) (xy 341.218004 -226.591082) (xy 341.225899 -226.639659)
			(xy 341.226394 -226.664266) (xy 341.544905 -226.664266) (xy 341.549 -226.613538) (xy 341.561179 -226.564124)
			(xy 341.581127 -226.517304) (xy 341.608328 -226.47429) (xy 341.642076 -226.436196) (xy 341.681498 -226.404009)
			(xy 341.725572 -226.378563) (xy 341.773158 -226.360516) (xy 341.823022 -226.350336) (xy 341.873874 -226.348287)
			(xy 341.924395 -226.354421) (xy 341.973279 -226.368581) (xy 342.019258 -226.390398) (xy 342.061142 -226.419308)
			(xy 342.097846 -226.454563) (xy 342.128419 -226.495249) (xy 342.15207 -226.540312) (xy 342.168186 -226.588586)
			(xy 342.17635 -226.63882) (xy 342.176862 -226.664266) (xy 342.49539 -226.664266) (xy 342.49935 -226.615212)
			(xy 342.511127 -226.567428) (xy 342.530418 -226.522152) (xy 342.556721 -226.480556) (xy 342.589356 -226.443719)
			(xy 342.627477 -226.412594) (xy 342.670098 -226.387987) (xy 342.716114 -226.370535) (xy 342.764333 -226.360691)
			(xy 342.813508 -226.35871) (xy 342.862363 -226.364642) (xy 342.909634 -226.378334) (xy 342.954096 -226.399432)
			(xy 342.994599 -226.427388) (xy 343.030092 -226.46148) (xy 343.059657 -226.500824) (xy 343.082528 -226.544401)
			(xy 343.098112 -226.591082) (xy 343.106007 -226.639659) (xy 343.106502 -226.664266) (xy 343.106007 -226.688873)
			(xy 343.098112 -226.73745) (xy 343.082528 -226.784131) (xy 343.059657 -226.827708) (xy 343.030092 -226.867052)
			(xy 342.994599 -226.901144) (xy 342.954096 -226.9291) (xy 342.909634 -226.950198) (xy 342.862363 -226.96389)
			(xy 342.813508 -226.969822) (xy 342.764333 -226.967841) (xy 342.716114 -226.957997) (xy 342.670098 -226.940545)
			(xy 342.627477 -226.915938) (xy 342.589356 -226.884813) (xy 342.556721 -226.847976) (xy 342.530418 -226.80638)
			(xy 342.511127 -226.761104) (xy 342.49935 -226.71332) (xy 342.49539 -226.664266) (xy 342.176862 -226.664266)
			(xy 342.17635 -226.689712) (xy 342.168186 -226.739946) (xy 342.15207 -226.78822) (xy 342.128419 -226.833283)
			(xy 342.097846 -226.873969) (xy 342.061142 -226.909224) (xy 342.019258 -226.938134) (xy 341.973279 -226.959951)
			(xy 341.924395 -226.974111) (xy 341.873874 -226.980245) (xy 341.823022 -226.978196) (xy 341.773158 -226.968016)
			(xy 341.725572 -226.949969) (xy 341.681498 -226.924523) (xy 341.642076 -226.892336) (xy 341.608328 -226.854242)
			(xy 341.581127 -226.811228) (xy 341.561179 -226.764408) (xy 341.549 -226.714994) (xy 341.544905 -226.664266)
			(xy 341.226394 -226.664266) (xy 341.225899 -226.688873) (xy 341.218004 -226.73745) (xy 341.20242 -226.784131)
			(xy 341.179549 -226.827708) (xy 341.149984 -226.867052) (xy 341.114491 -226.901144) (xy 341.073988 -226.9291)
			(xy 341.029526 -226.950198) (xy 340.982255 -226.96389) (xy 340.9334 -226.969822) (xy 340.884225 -226.967841)
			(xy 340.836006 -226.957997) (xy 340.78999 -226.940545) (xy 340.747369 -226.915938) (xy 340.709248 -226.884813)
			(xy 340.676613 -226.847976) (xy 340.65031 -226.80638) (xy 340.631019 -226.761104) (xy 340.619242 -226.71332)
			(xy 340.615282 -226.664266) (xy 340.296754 -226.664266) (xy 340.296242 -226.689712) (xy 340.288078 -226.739946)
			(xy 340.271962 -226.78822) (xy 340.248311 -226.833283) (xy 340.217738 -226.873969) (xy 340.181034 -226.909224)
			(xy 340.13915 -226.938134) (xy 340.093171 -226.959951) (xy 340.044287 -226.974111) (xy 339.993766 -226.980245)
			(xy 339.942914 -226.978196) (xy 339.89305 -226.968016) (xy 339.845464 -226.949969) (xy 339.80139 -226.924523)
			(xy 339.761968 -226.892336) (xy 339.72822 -226.854242) (xy 339.701019 -226.811228) (xy 339.681071 -226.764408)
			(xy 339.668892 -226.714994) (xy 339.664797 -226.664266) (xy 339.3567 -226.664266) (xy 339.356188 -226.689712)
			(xy 339.348024 -226.739946) (xy 339.331908 -226.78822) (xy 339.308257 -226.833283) (xy 339.277684 -226.873969)
			(xy 339.24098 -226.909224) (xy 339.199096 -226.938134) (xy 339.153117 -226.959951) (xy 339.104233 -226.974111)
			(xy 339.053712 -226.980245) (xy 339.00286 -226.978196) (xy 338.952996 -226.968016) (xy 338.90541 -226.949969)
			(xy 338.861336 -226.924523) (xy 338.821914 -226.892336) (xy 338.788166 -226.854242) (xy 338.760965 -226.811228)
			(xy 338.741017 -226.764408) (xy 338.728838 -226.714994) (xy 338.724743 -226.664266) (xy 338.406486 -226.664266)
			(xy 338.405991 -226.688873) (xy 338.398096 -226.73745) (xy 338.382512 -226.784131) (xy 338.359641 -226.827708)
			(xy 338.330076 -226.867052) (xy 338.294583 -226.901144) (xy 338.25408 -226.9291) (xy 338.209618 -226.950198)
			(xy 338.162347 -226.96389) (xy 338.113492 -226.969822) (xy 338.064317 -226.967841) (xy 338.016098 -226.957997)
			(xy 337.970082 -226.940545) (xy 337.927461 -226.915938) (xy 337.88934 -226.884813) (xy 337.856705 -226.847976)
			(xy 337.830402 -226.80638) (xy 337.811111 -226.761104) (xy 337.799334 -226.71332) (xy 337.795374 -226.664266)
			(xy 337.466432 -226.664266) (xy 337.465937 -226.688873) (xy 337.458042 -226.73745) (xy 337.442458 -226.784131)
			(xy 337.419587 -226.827708) (xy 337.390022 -226.867052) (xy 337.354529 -226.901144) (xy 337.314026 -226.9291)
			(xy 337.269564 -226.950198) (xy 337.222293 -226.96389) (xy 337.173438 -226.969822) (xy 337.124263 -226.967841)
			(xy 337.076044 -226.957997) (xy 337.030028 -226.940545) (xy 336.987407 -226.915938) (xy 336.949286 -226.884813)
			(xy 336.916651 -226.847976) (xy 336.890348 -226.80638) (xy 336.871057 -226.761104) (xy 336.85928 -226.71332)
			(xy 336.85532 -226.664266) (xy 336.526378 -226.664266) (xy 336.525883 -226.688873) (xy 336.517988 -226.73745)
			(xy 336.502404 -226.784131) (xy 336.479533 -226.827708) (xy 336.449968 -226.867052) (xy 336.414475 -226.901144)
			(xy 336.373972 -226.9291) (xy 336.32951 -226.950198) (xy 336.282239 -226.96389) (xy 336.233384 -226.969822)
			(xy 336.184209 -226.967841) (xy 336.13599 -226.957997) (xy 336.089974 -226.940545) (xy 336.047353 -226.915938)
			(xy 336.009232 -226.884813) (xy 335.976597 -226.847976) (xy 335.950294 -226.80638) (xy 335.931003 -226.761104)
			(xy 335.919226 -226.71332) (xy 335.915266 -226.664266) (xy 335.586324 -226.664266) (xy 335.585829 -226.688873)
			(xy 335.577934 -226.73745) (xy 335.56235 -226.784131) (xy 335.539479 -226.827708) (xy 335.509914 -226.867052)
			(xy 335.474421 -226.901144) (xy 335.433918 -226.9291) (xy 335.389456 -226.950198) (xy 335.342185 -226.96389)
			(xy 335.29333 -226.969822) (xy 335.244155 -226.967841) (xy 335.195936 -226.957997) (xy 335.14992 -226.940545)
			(xy 335.107299 -226.915938) (xy 335.069178 -226.884813) (xy 335.036543 -226.847976) (xy 335.01024 -226.80638)
			(xy 334.990949 -226.761104) (xy 334.979172 -226.71332) (xy 334.975212 -226.664266) (xy 334.646524 -226.664266)
			(xy 334.64608 -226.688261) (xy 334.638578 -226.735662) (xy 334.623753 -226.781305) (xy 334.601969 -226.824067)
			(xy 334.573765 -226.862895) (xy 334.539833 -226.896832) (xy 334.50101 -226.925043) (xy 334.458251 -226.946833)
			(xy 334.412611 -226.961666) (xy 334.365211 -226.969176) (xy 334.341216 -226.969574) (xy 334.309466 -226.967796)
			(xy 334.306672 -226.967542) (xy 334.304132 -226.967542) (xy 334.29411 -226.967957) (xy 334.275589 -226.975622)
			(xy 334.261417 -226.989797) (xy 334.253755 -227.008319) (xy 334.253332 -227.018342) (xy 334.253332 -227.038662)
			(xy 334.254094 -227.047552) (xy 334.255364 -227.05441) (xy 334.256965 -227.062024) (xy 334.264077 -227.075853)
			(xy 334.269334 -227.081588) (xy 334.269588 -227.081842) (xy 334.274922 -227.08743) (xy 334.298193 -227.112458)
			(xy 334.339099 -227.167207) (xy 334.37301 -227.226543) (xy 334.386682 -227.257864) (xy 334.389222 -227.26396)
			(xy 334.396842 -227.27412) (xy 334.421226 -227.29317) (xy 334.426701 -227.297129) (xy 334.43919 -227.302273)
			(xy 334.445864 -227.30333) (xy 334.516984 -227.312982) (xy 334.522959 -227.3136) (xy 334.534901 -227.312321)
			(xy 334.540606 -227.310442) (xy 334.551782 -227.306632) (xy 334.56499 -227.293424) (xy 334.567022 -227.29063)
			(xy 334.581568 -227.272079) (xy 334.6154 -227.239252) (xy 334.653865 -227.212002) (xy 334.696054 -227.190972)
			(xy 334.740968 -227.176659) (xy 334.787546 -227.169403) (xy 334.811116 -227.168964) (xy 334.836373 -227.169487)
			(xy 334.886197 -227.177804) (xy 334.933973 -227.194207) (xy 334.978397 -227.218251) (xy 335.018259 -227.249278)
			(xy 335.05247 -227.286443) (xy 335.080097 -227.328732) (xy 335.100388 -227.374991) (xy 335.112788 -227.423959)
			(xy 335.116957 -227.474272) (xy 335.445366 -227.474272) (xy 335.449326 -227.425218) (xy 335.461103 -227.377434)
			(xy 335.480394 -227.332158) (xy 335.506697 -227.290562) (xy 335.539332 -227.253725) (xy 335.577453 -227.2226)
			(xy 335.620074 -227.197993) (xy 335.66609 -227.180541) (xy 335.714309 -227.170697) (xy 335.763484 -227.168716)
			(xy 335.812339 -227.174648) (xy 335.85961 -227.18834) (xy 335.904072 -227.209438) (xy 335.944575 -227.237394)
			(xy 335.980068 -227.271486) (xy 336.009633 -227.31083) (xy 336.032504 -227.354407) (xy 336.048088 -227.401088)
			(xy 336.055983 -227.449665) (xy 336.056478 -227.474272) (xy 336.38542 -227.474272) (xy 336.38938 -227.425218)
			(xy 336.401157 -227.377434) (xy 336.420448 -227.332158) (xy 336.446751 -227.290562) (xy 336.479386 -227.253725)
			(xy 336.517507 -227.2226) (xy 336.560128 -227.197993) (xy 336.606144 -227.180541) (xy 336.654363 -227.170697)
			(xy 336.703538 -227.168716) (xy 336.752393 -227.174648) (xy 336.799664 -227.18834) (xy 336.844126 -227.209438)
			(xy 336.884629 -227.237394) (xy 336.920122 -227.271486) (xy 336.949687 -227.31083) (xy 336.972558 -227.354407)
			(xy 336.988142 -227.401088) (xy 336.996037 -227.449665) (xy 336.996532 -227.474272) (xy 337.32522 -227.474272)
			(xy 337.32918 -227.425218) (xy 337.340957 -227.377434) (xy 337.360248 -227.332158) (xy 337.386551 -227.290562)
			(xy 337.419186 -227.253725) (xy 337.457307 -227.2226) (xy 337.499928 -227.197993) (xy 337.545944 -227.180541)
			(xy 337.594163 -227.170697) (xy 337.643338 -227.168716) (xy 337.692193 -227.174648) (xy 337.739464 -227.18834)
			(xy 337.783926 -227.209438) (xy 337.824429 -227.237394) (xy 337.859922 -227.271486) (xy 337.889487 -227.31083)
			(xy 337.912358 -227.354407) (xy 337.927942 -227.401088) (xy 337.935837 -227.449665) (xy 337.936332 -227.474272)
			(xy 338.254843 -227.474272) (xy 338.258938 -227.423544) (xy 338.271117 -227.37413) (xy 338.291065 -227.32731)
			(xy 338.318266 -227.284296) (xy 338.352014 -227.246202) (xy 338.391436 -227.214015) (xy 338.43551 -227.188569)
			(xy 338.483096 -227.170522) (xy 338.53296 -227.160342) (xy 338.583812 -227.158293) (xy 338.634333 -227.164427)
			(xy 338.683217 -227.178587) (xy 338.729196 -227.200404) (xy 338.77108 -227.229314) (xy 338.807784 -227.264569)
			(xy 338.838357 -227.305255) (xy 338.862008 -227.350318) (xy 338.878124 -227.398592) (xy 338.886288 -227.448826)
			(xy 338.8868 -227.474272) (xy 339.205328 -227.474272) (xy 339.209288 -227.425218) (xy 339.221065 -227.377434)
			(xy 339.240356 -227.332158) (xy 339.266659 -227.290562) (xy 339.299294 -227.253725) (xy 339.337415 -227.2226)
			(xy 339.380036 -227.197993) (xy 339.426052 -227.180541) (xy 339.474271 -227.170697) (xy 339.523446 -227.168716)
			(xy 339.572301 -227.174648) (xy 339.619572 -227.18834) (xy 339.664034 -227.209438) (xy 339.704537 -227.237394)
			(xy 339.74003 -227.271486) (xy 339.769595 -227.31083) (xy 339.792466 -227.354407) (xy 339.80805 -227.401088)
			(xy 339.815945 -227.449665) (xy 339.81644 -227.474272) (xy 340.134951 -227.474272) (xy 340.139046 -227.423544)
			(xy 340.151225 -227.37413) (xy 340.171173 -227.32731) (xy 340.198374 -227.284296) (xy 340.232122 -227.246202)
			(xy 340.271544 -227.214015) (xy 340.315618 -227.188569) (xy 340.363204 -227.170522) (xy 340.413068 -227.160342)
			(xy 340.46392 -227.158293) (xy 340.514441 -227.164427) (xy 340.563325 -227.178587) (xy 340.609304 -227.200404)
			(xy 340.651188 -227.229314) (xy 340.687892 -227.264569) (xy 340.718465 -227.305255) (xy 340.742116 -227.350318)
			(xy 340.758232 -227.398592) (xy 340.766396 -227.448826) (xy 340.766908 -227.474272) (xy 341.085182 -227.474272)
			(xy 341.089142 -227.425218) (xy 341.100919 -227.377434) (xy 341.12021 -227.332158) (xy 341.146513 -227.290562)
			(xy 341.179148 -227.253725) (xy 341.217269 -227.2226) (xy 341.25989 -227.197993) (xy 341.305906 -227.180541)
			(xy 341.354125 -227.170697) (xy 341.4033 -227.168716) (xy 341.452155 -227.174648) (xy 341.499426 -227.18834)
			(xy 341.543888 -227.209438) (xy 341.584391 -227.237394) (xy 341.619884 -227.271486) (xy 341.649449 -227.31083)
			(xy 341.67232 -227.354407) (xy 341.687904 -227.401088) (xy 341.695799 -227.449665) (xy 341.696294 -227.474272)
			(xy 342.014805 -227.474272) (xy 342.0189 -227.423544) (xy 342.031079 -227.37413) (xy 342.051027 -227.32731)
			(xy 342.078228 -227.284296) (xy 342.111976 -227.246202) (xy 342.151398 -227.214015) (xy 342.195472 -227.188569)
			(xy 342.243058 -227.170522) (xy 342.292922 -227.160342) (xy 342.343774 -227.158293) (xy 342.394295 -227.164427)
			(xy 342.443179 -227.178587) (xy 342.489158 -227.200404) (xy 342.531042 -227.229314) (xy 342.567746 -227.264569)
			(xy 342.598319 -227.305255) (xy 342.62197 -227.350318) (xy 342.638086 -227.398592) (xy 342.64625 -227.448826)
			(xy 342.646762 -227.474272) (xy 342.64625 -227.499718) (xy 342.638086 -227.549952) (xy 342.62197 -227.598226)
			(xy 342.598319 -227.643289) (xy 342.567746 -227.683975) (xy 342.531042 -227.71923) (xy 342.489158 -227.74814)
			(xy 342.443179 -227.769957) (xy 342.394295 -227.784117) (xy 342.343774 -227.790251) (xy 342.292922 -227.788202)
			(xy 342.243058 -227.778022) (xy 342.195472 -227.759975) (xy 342.151398 -227.734529) (xy 342.111976 -227.702342)
			(xy 342.078228 -227.664248) (xy 342.051027 -227.621234) (xy 342.031079 -227.574414) (xy 342.0189 -227.525)
			(xy 342.014805 -227.474272) (xy 341.696294 -227.474272) (xy 341.695799 -227.498879) (xy 341.687904 -227.547456)
			(xy 341.67232 -227.594137) (xy 341.649449 -227.637714) (xy 341.619884 -227.677058) (xy 341.584391 -227.71115)
			(xy 341.543888 -227.739106) (xy 341.499426 -227.760204) (xy 341.452155 -227.773896) (xy 341.4033 -227.779828)
			(xy 341.354125 -227.777847) (xy 341.305906 -227.768003) (xy 341.25989 -227.750551) (xy 341.217269 -227.725944)
			(xy 341.179148 -227.694819) (xy 341.146513 -227.657982) (xy 341.12021 -227.616386) (xy 341.100919 -227.57111)
			(xy 341.089142 -227.523326) (xy 341.085182 -227.474272) (xy 340.766908 -227.474272) (xy 340.766396 -227.499718)
			(xy 340.758232 -227.549952) (xy 340.742116 -227.598226) (xy 340.718465 -227.643289) (xy 340.687892 -227.683975)
			(xy 340.651188 -227.71923) (xy 340.609304 -227.74814) (xy 340.563325 -227.769957) (xy 340.514441 -227.784117)
			(xy 340.46392 -227.790251) (xy 340.413068 -227.788202) (xy 340.363204 -227.778022) (xy 340.315618 -227.759975)
			(xy 340.271544 -227.734529) (xy 340.232122 -227.702342) (xy 340.198374 -227.664248) (xy 340.171173 -227.621234)
			(xy 340.151225 -227.574414) (xy 340.139046 -227.525) (xy 340.134951 -227.474272) (xy 339.81644 -227.474272)
			(xy 339.815945 -227.498879) (xy 339.80805 -227.547456) (xy 339.792466 -227.594137) (xy 339.769595 -227.637714)
			(xy 339.74003 -227.677058) (xy 339.704537 -227.71115) (xy 339.664034 -227.739106) (xy 339.619572 -227.760204)
			(xy 339.572301 -227.773896) (xy 339.523446 -227.779828) (xy 339.474271 -227.777847) (xy 339.426052 -227.768003)
			(xy 339.380036 -227.750551) (xy 339.337415 -227.725944) (xy 339.299294 -227.694819) (xy 339.266659 -227.657982)
			(xy 339.240356 -227.616386) (xy 339.221065 -227.57111) (xy 339.209288 -227.523326) (xy 339.205328 -227.474272)
			(xy 338.8868 -227.474272) (xy 338.886288 -227.499718) (xy 338.878124 -227.549952) (xy 338.862008 -227.598226)
			(xy 338.838357 -227.643289) (xy 338.807784 -227.683975) (xy 338.77108 -227.71923) (xy 338.729196 -227.74814)
			(xy 338.683217 -227.769957) (xy 338.634333 -227.784117) (xy 338.583812 -227.790251) (xy 338.53296 -227.788202)
			(xy 338.483096 -227.778022) (xy 338.43551 -227.759975) (xy 338.391436 -227.734529) (xy 338.352014 -227.702342)
			(xy 338.318266 -227.664248) (xy 338.291065 -227.621234) (xy 338.271117 -227.574414) (xy 338.258938 -227.525)
			(xy 338.254843 -227.474272) (xy 337.936332 -227.474272) (xy 337.935837 -227.498879) (xy 337.927942 -227.547456)
			(xy 337.912358 -227.594137) (xy 337.889487 -227.637714) (xy 337.859922 -227.677058) (xy 337.824429 -227.71115)
			(xy 337.783926 -227.739106) (xy 337.739464 -227.760204) (xy 337.692193 -227.773896) (xy 337.643338 -227.779828)
			(xy 337.594163 -227.777847) (xy 337.545944 -227.768003) (xy 337.499928 -227.750551) (xy 337.457307 -227.725944)
			(xy 337.419186 -227.694819) (xy 337.386551 -227.657982) (xy 337.360248 -227.616386) (xy 337.340957 -227.57111)
			(xy 337.32918 -227.523326) (xy 337.32522 -227.474272) (xy 336.996532 -227.474272) (xy 336.996037 -227.498879)
			(xy 336.988142 -227.547456) (xy 336.972558 -227.594137) (xy 336.949687 -227.637714) (xy 336.920122 -227.677058)
			(xy 336.884629 -227.71115) (xy 336.844126 -227.739106) (xy 336.799664 -227.760204) (xy 336.752393 -227.773896)
			(xy 336.703538 -227.779828) (xy 336.654363 -227.777847) (xy 336.606144 -227.768003) (xy 336.560128 -227.750551)
			(xy 336.517507 -227.725944) (xy 336.479386 -227.694819) (xy 336.446751 -227.657982) (xy 336.420448 -227.616386)
			(xy 336.401157 -227.57111) (xy 336.38938 -227.523326) (xy 336.38542 -227.474272) (xy 336.056478 -227.474272)
			(xy 336.055983 -227.498879) (xy 336.048088 -227.547456) (xy 336.032504 -227.594137) (xy 336.009633 -227.637714)
			(xy 335.980068 -227.677058) (xy 335.944575 -227.71115) (xy 335.904072 -227.739106) (xy 335.85961 -227.760204)
			(xy 335.812339 -227.773896) (xy 335.763484 -227.779828) (xy 335.714309 -227.777847) (xy 335.66609 -227.768003)
			(xy 335.620074 -227.750551) (xy 335.577453 -227.725944) (xy 335.539332 -227.694819) (xy 335.506697 -227.657982)
			(xy 335.480394 -227.616386) (xy 335.461103 -227.57111) (xy 335.449326 -227.523326) (xy 335.445366 -227.474272)
			(xy 335.116957 -227.474272) (xy 335.116959 -227.4743) (xy 335.112788 -227.524641) (xy 335.100388 -227.573609)
			(xy 335.080097 -227.619868) (xy 335.05247 -227.662157) (xy 335.018259 -227.699322) (xy 334.978397 -227.730349)
			(xy 334.933973 -227.754393) (xy 334.886197 -227.770796) (xy 334.836373 -227.779113) (xy 334.811116 -227.77958)
			(xy 334.787545 -227.779145) (xy 334.740962 -227.771907) (xy 334.696043 -227.757602) (xy 334.653854 -227.736568)
			(xy 334.615396 -227.709304) (xy 334.581581 -227.676457) (xy 334.567022 -227.657914) (xy 334.56499 -227.65512)
			(xy 334.55991 -227.65004) (xy 334.553345 -227.643918) (xy 334.537074 -227.636367) (xy 334.52816 -227.635308)
			(xy 334.522572 -227.6348) (xy 334.432148 -227.646992) (xy 334.423228 -227.648536) (xy 334.40723 -227.656983)
			(xy 334.395161 -227.670459) (xy 334.391508 -227.678742) (xy 334.383586 -227.698449) (xy 334.365152 -227.736718)
			(xy 334.354678 -227.755196) (xy 334.312768 -227.827332) (xy 334.311498 -227.82911) (xy 334.303878 -227.84054)
			(xy 334.3021 -227.867718) (xy 334.338676 -227.94214) (xy 334.341553 -227.947472) (xy 334.349384 -227.956713)
			(xy 334.35417 -227.960428) (xy 334.382618 -227.98151) (xy 334.394302 -227.983542) (xy 334.417561 -227.988098)
			(xy 334.4624 -228.003445) (xy 334.504329 -228.025538) (xy 334.542338 -228.053847) (xy 334.575514 -228.087691)
			(xy 334.60306 -228.126257) (xy 334.624313 -228.168617) (xy 334.638763 -228.213754) (xy 334.646061 -228.260581)
			(xy 334.646524 -228.284278) (xy 334.975212 -228.284278) (xy 334.979172 -228.235224) (xy 334.990949 -228.18744)
			(xy 335.01024 -228.142164) (xy 335.036543 -228.100568) (xy 335.069178 -228.063731) (xy 335.107299 -228.032606)
			(xy 335.14992 -228.007999) (xy 335.195936 -227.990547) (xy 335.244155 -227.980703) (xy 335.29333 -227.978722)
			(xy 335.342185 -227.984654) (xy 335.389456 -227.998346) (xy 335.433918 -228.019444) (xy 335.474421 -228.0474)
			(xy 335.509914 -228.081492) (xy 335.539479 -228.120836) (xy 335.56235 -228.164413) (xy 335.577934 -228.211094)
			(xy 335.585829 -228.259671) (xy 335.586324 -228.284278) (xy 335.915266 -228.284278) (xy 335.919226 -228.235224)
			(xy 335.931003 -228.18744) (xy 335.950294 -228.142164) (xy 335.976597 -228.100568) (xy 336.009232 -228.063731)
			(xy 336.047353 -228.032606) (xy 336.089974 -228.007999) (xy 336.13599 -227.990547) (xy 336.184209 -227.980703)
			(xy 336.233384 -227.978722) (xy 336.282239 -227.984654) (xy 336.32951 -227.998346) (xy 336.373972 -228.019444)
			(xy 336.414475 -228.0474) (xy 336.449968 -228.081492) (xy 336.479533 -228.120836) (xy 336.502404 -228.164413)
			(xy 336.517988 -228.211094) (xy 336.525883 -228.259671) (xy 336.526378 -228.284278) (xy 336.85532 -228.284278)
			(xy 336.85928 -228.235224) (xy 336.871057 -228.18744) (xy 336.890348 -228.142164) (xy 336.916651 -228.100568)
			(xy 336.949286 -228.063731) (xy 336.987407 -228.032606) (xy 337.030028 -228.007999) (xy 337.076044 -227.990547)
			(xy 337.124263 -227.980703) (xy 337.173438 -227.978722) (xy 337.222293 -227.984654) (xy 337.269564 -227.998346)
			(xy 337.314026 -228.019444) (xy 337.354529 -228.0474) (xy 337.390022 -228.081492) (xy 337.419587 -228.120836)
			(xy 337.442458 -228.164413) (xy 337.458042 -228.211094) (xy 337.465937 -228.259671) (xy 337.466432 -228.284278)
			(xy 337.795374 -228.284278) (xy 337.799334 -228.235224) (xy 337.811111 -228.18744) (xy 337.830402 -228.142164)
			(xy 337.856705 -228.100568) (xy 337.88934 -228.063731) (xy 337.927461 -228.032606) (xy 337.970082 -228.007999)
			(xy 338.016098 -227.990547) (xy 338.064317 -227.980703) (xy 338.113492 -227.978722) (xy 338.162347 -227.984654)
			(xy 338.209618 -227.998346) (xy 338.25408 -228.019444) (xy 338.294583 -228.0474) (xy 338.330076 -228.081492)
			(xy 338.359641 -228.120836) (xy 338.382512 -228.164413) (xy 338.398096 -228.211094) (xy 338.405991 -228.259671)
			(xy 338.406486 -228.284278) (xy 338.724743 -228.284278) (xy 338.728838 -228.23355) (xy 338.741017 -228.184136)
			(xy 338.760965 -228.137316) (xy 338.788166 -228.094302) (xy 338.821914 -228.056208) (xy 338.861336 -228.024021)
			(xy 338.90541 -227.998575) (xy 338.952996 -227.980528) (xy 339.00286 -227.970348) (xy 339.053712 -227.968299)
			(xy 339.104233 -227.974433) (xy 339.153117 -227.988593) (xy 339.199096 -228.01041) (xy 339.24098 -228.03932)
			(xy 339.277684 -228.074575) (xy 339.308257 -228.115261) (xy 339.331908 -228.160324) (xy 339.348024 -228.208598)
			(xy 339.356188 -228.258832) (xy 339.3567 -228.284278) (xy 339.664797 -228.284278) (xy 339.668892 -228.23355)
			(xy 339.681071 -228.184136) (xy 339.701019 -228.137316) (xy 339.72822 -228.094302) (xy 339.761968 -228.056208)
			(xy 339.80139 -228.024021) (xy 339.845464 -227.998575) (xy 339.89305 -227.980528) (xy 339.942914 -227.970348)
			(xy 339.993766 -227.968299) (xy 340.044287 -227.974433) (xy 340.093171 -227.988593) (xy 340.13915 -228.01041)
			(xy 340.181034 -228.03932) (xy 340.217738 -228.074575) (xy 340.248311 -228.115261) (xy 340.271962 -228.160324)
			(xy 340.288078 -228.208598) (xy 340.296242 -228.258832) (xy 340.296754 -228.284278) (xy 340.615282 -228.284278)
			(xy 340.619242 -228.235224) (xy 340.631019 -228.18744) (xy 340.65031 -228.142164) (xy 340.676613 -228.100568)
			(xy 340.709248 -228.063731) (xy 340.747369 -228.032606) (xy 340.78999 -228.007999) (xy 340.836006 -227.990547)
			(xy 340.884225 -227.980703) (xy 340.9334 -227.978722) (xy 340.982255 -227.984654) (xy 341.029526 -227.998346)
			(xy 341.073988 -228.019444) (xy 341.114491 -228.0474) (xy 341.149984 -228.081492) (xy 341.179549 -228.120836)
			(xy 341.20242 -228.164413) (xy 341.218004 -228.211094) (xy 341.225899 -228.259671) (xy 341.226394 -228.284278)
			(xy 341.544905 -228.284278) (xy 341.549 -228.23355) (xy 341.561179 -228.184136) (xy 341.581127 -228.137316)
			(xy 341.608328 -228.094302) (xy 341.642076 -228.056208) (xy 341.681498 -228.024021) (xy 341.725572 -227.998575)
			(xy 341.773158 -227.980528) (xy 341.823022 -227.970348) (xy 341.873874 -227.968299) (xy 341.924395 -227.974433)
			(xy 341.973279 -227.988593) (xy 342.019258 -228.01041) (xy 342.061142 -228.03932) (xy 342.097846 -228.074575)
			(xy 342.128419 -228.115261) (xy 342.15207 -228.160324) (xy 342.168186 -228.208598) (xy 342.17635 -228.258832)
			(xy 342.176862 -228.284278) (xy 342.49539 -228.284278) (xy 342.49935 -228.235224) (xy 342.511127 -228.18744)
			(xy 342.530418 -228.142164) (xy 342.556721 -228.100568) (xy 342.589356 -228.063731) (xy 342.627477 -228.032606)
			(xy 342.670098 -228.007999) (xy 342.716114 -227.990547) (xy 342.764333 -227.980703) (xy 342.813508 -227.978722)
			(xy 342.862363 -227.984654) (xy 342.909634 -227.998346) (xy 342.954096 -228.019444) (xy 342.994599 -228.0474)
			(xy 343.030092 -228.081492) (xy 343.059657 -228.120836) (xy 343.082528 -228.164413) (xy 343.098112 -228.211094)
			(xy 343.106007 -228.259671) (xy 343.106502 -228.284278) (xy 343.106007 -228.308885) (xy 343.098112 -228.357462)
			(xy 343.082528 -228.404143) (xy 343.059657 -228.44772) (xy 343.030092 -228.487064) (xy 342.994599 -228.521156)
			(xy 342.954096 -228.549112) (xy 342.909634 -228.57021) (xy 342.862363 -228.583902) (xy 342.813508 -228.589834)
			(xy 342.764333 -228.587853) (xy 342.716114 -228.578009) (xy 342.670098 -228.560557) (xy 342.627477 -228.53595)
			(xy 342.589356 -228.504825) (xy 342.556721 -228.467988) (xy 342.530418 -228.426392) (xy 342.511127 -228.381116)
			(xy 342.49935 -228.333332) (xy 342.49539 -228.284278) (xy 342.176862 -228.284278) (xy 342.17635 -228.309724)
			(xy 342.168186 -228.359958) (xy 342.15207 -228.408232) (xy 342.128419 -228.453295) (xy 342.097846 -228.493981)
			(xy 342.061142 -228.529236) (xy 342.019258 -228.558146) (xy 341.973279 -228.579963) (xy 341.924395 -228.594123)
			(xy 341.873874 -228.600257) (xy 341.823022 -228.598208) (xy 341.773158 -228.588028) (xy 341.725572 -228.569981)
			(xy 341.681498 -228.544535) (xy 341.642076 -228.512348) (xy 341.608328 -228.474254) (xy 341.581127 -228.43124)
			(xy 341.561179 -228.38442) (xy 341.549 -228.335006) (xy 341.544905 -228.284278) (xy 341.226394 -228.284278)
			(xy 341.225899 -228.308885) (xy 341.218004 -228.357462) (xy 341.20242 -228.404143) (xy 341.179549 -228.44772)
			(xy 341.149984 -228.487064) (xy 341.114491 -228.521156) (xy 341.073988 -228.549112) (xy 341.029526 -228.57021)
			(xy 340.982255 -228.583902) (xy 340.9334 -228.589834) (xy 340.884225 -228.587853) (xy 340.836006 -228.578009)
			(xy 340.78999 -228.560557) (xy 340.747369 -228.53595) (xy 340.709248 -228.504825) (xy 340.676613 -228.467988)
			(xy 340.65031 -228.426392) (xy 340.631019 -228.381116) (xy 340.619242 -228.333332) (xy 340.615282 -228.284278)
			(xy 340.296754 -228.284278) (xy 340.296242 -228.309724) (xy 340.288078 -228.359958) (xy 340.271962 -228.408232)
			(xy 340.248311 -228.453295) (xy 340.217738 -228.493981) (xy 340.181034 -228.529236) (xy 340.13915 -228.558146)
			(xy 340.093171 -228.579963) (xy 340.044287 -228.594123) (xy 339.993766 -228.600257) (xy 339.942914 -228.598208)
			(xy 339.89305 -228.588028) (xy 339.845464 -228.569981) (xy 339.80139 -228.544535) (xy 339.761968 -228.512348)
			(xy 339.72822 -228.474254) (xy 339.701019 -228.43124) (xy 339.681071 -228.38442) (xy 339.668892 -228.335006)
			(xy 339.664797 -228.284278) (xy 339.3567 -228.284278) (xy 339.356188 -228.309724) (xy 339.348024 -228.359958)
			(xy 339.331908 -228.408232) (xy 339.308257 -228.453295) (xy 339.277684 -228.493981) (xy 339.24098 -228.529236)
			(xy 339.199096 -228.558146) (xy 339.153117 -228.579963) (xy 339.104233 -228.594123) (xy 339.053712 -228.600257)
			(xy 339.00286 -228.598208) (xy 338.952996 -228.588028) (xy 338.90541 -228.569981) (xy 338.861336 -228.544535)
			(xy 338.821914 -228.512348) (xy 338.788166 -228.474254) (xy 338.760965 -228.43124) (xy 338.741017 -228.38442)
			(xy 338.728838 -228.335006) (xy 338.724743 -228.284278) (xy 338.406486 -228.284278) (xy 338.405991 -228.308885)
			(xy 338.398096 -228.357462) (xy 338.382512 -228.404143) (xy 338.359641 -228.44772) (xy 338.330076 -228.487064)
			(xy 338.294583 -228.521156) (xy 338.25408 -228.549112) (xy 338.209618 -228.57021) (xy 338.162347 -228.583902)
			(xy 338.113492 -228.589834) (xy 338.064317 -228.587853) (xy 338.016098 -228.578009) (xy 337.970082 -228.560557)
			(xy 337.927461 -228.53595) (xy 337.88934 -228.504825) (xy 337.856705 -228.467988) (xy 337.830402 -228.426392)
			(xy 337.811111 -228.381116) (xy 337.799334 -228.333332) (xy 337.795374 -228.284278) (xy 337.466432 -228.284278)
			(xy 337.465937 -228.308885) (xy 337.458042 -228.357462) (xy 337.442458 -228.404143) (xy 337.419587 -228.44772)
			(xy 337.390022 -228.487064) (xy 337.354529 -228.521156) (xy 337.314026 -228.549112) (xy 337.269564 -228.57021)
			(xy 337.222293 -228.583902) (xy 337.173438 -228.589834) (xy 337.124263 -228.587853) (xy 337.076044 -228.578009)
			(xy 337.030028 -228.560557) (xy 336.987407 -228.53595) (xy 336.949286 -228.504825) (xy 336.916651 -228.467988)
			(xy 336.890348 -228.426392) (xy 336.871057 -228.381116) (xy 336.85928 -228.333332) (xy 336.85532 -228.284278)
			(xy 336.526378 -228.284278) (xy 336.525883 -228.308885) (xy 336.517988 -228.357462) (xy 336.502404 -228.404143)
			(xy 336.479533 -228.44772) (xy 336.449968 -228.487064) (xy 336.414475 -228.521156) (xy 336.373972 -228.549112)
			(xy 336.32951 -228.57021) (xy 336.282239 -228.583902) (xy 336.233384 -228.589834) (xy 336.184209 -228.587853)
			(xy 336.13599 -228.578009) (xy 336.089974 -228.560557) (xy 336.047353 -228.53595) (xy 336.009232 -228.504825)
			(xy 335.976597 -228.467988) (xy 335.950294 -228.426392) (xy 335.931003 -228.381116) (xy 335.919226 -228.333332)
			(xy 335.915266 -228.284278) (xy 335.586324 -228.284278) (xy 335.585829 -228.308885) (xy 335.577934 -228.357462)
			(xy 335.56235 -228.404143) (xy 335.539479 -228.44772) (xy 335.509914 -228.487064) (xy 335.474421 -228.521156)
			(xy 335.433918 -228.549112) (xy 335.389456 -228.57021) (xy 335.342185 -228.583902) (xy 335.29333 -228.589834)
			(xy 335.244155 -228.587853) (xy 335.195936 -228.578009) (xy 335.14992 -228.560557) (xy 335.107299 -228.53595)
			(xy 335.069178 -228.504825) (xy 335.036543 -228.467988) (xy 335.01024 -228.426392) (xy 334.990949 -228.381116)
			(xy 334.979172 -228.333332) (xy 334.975212 -228.284278) (xy 334.646524 -228.284278) (xy 334.646079 -228.308273)
			(xy 334.638576 -228.355672) (xy 334.623749 -228.401313) (xy 334.601965 -228.444074) (xy 334.57376 -228.4829)
			(xy 334.539829 -228.516836) (xy 334.501006 -228.545045) (xy 334.458249 -228.566835) (xy 334.412609 -228.581667)
			(xy 334.365211 -228.589176) (xy 334.341216 -228.589586) (xy 334.309466 -228.587808) (xy 334.306672 -228.587554)
			(xy 334.304132 -228.587554) (xy 334.294117 -228.588036) (xy 334.275606 -228.595688) (xy 334.261432 -228.609841)
			(xy 334.253751 -228.628339) (xy 334.253332 -228.638354) (xy 334.253332 -228.658674) (xy 334.254094 -228.667564)
			(xy 334.255364 -228.674422) (xy 334.256966 -228.682035) (xy 334.264081 -228.695861) (xy 334.269334 -228.7016)
			(xy 334.269588 -228.701854) (xy 334.274922 -228.707442) (xy 334.298193 -228.73247) (xy 334.339098 -228.787219)
			(xy 334.373008 -228.846556) (xy 334.386682 -228.877876) (xy 334.389222 -228.883972) (xy 334.396842 -228.894132)
			(xy 334.421226 -228.913182) (xy 334.426702 -228.91714) (xy 334.439191 -228.922283) (xy 334.445864 -228.923342)
			(xy 334.516984 -228.932994) (xy 334.522959 -228.933612) (xy 334.534901 -228.932333) (xy 334.540606 -228.930454)
			(xy 334.551782 -228.926644) (xy 334.56499 -228.913436) (xy 334.567022 -228.910642) (xy 334.581568 -228.89209)
			(xy 334.615399 -228.859263) (xy 334.653864 -228.832011) (xy 334.696053 -228.81098) (xy 334.740968 -228.796667)
			(xy 334.787546 -228.78941) (xy 334.811116 -228.788976) (xy 334.836372 -228.789499) (xy 334.886194 -228.797815)
			(xy 334.933968 -228.814218) (xy 334.978391 -228.838261) (xy 335.018251 -228.869287) (xy 335.05246 -228.90645)
			(xy 335.080087 -228.948737) (xy 335.100376 -228.994995) (xy 335.112776 -229.043961) (xy 335.116946 -229.094284)
			(xy 335.445366 -229.094284) (xy 335.449326 -229.04523) (xy 335.461103 -228.997446) (xy 335.480394 -228.95217)
			(xy 335.506697 -228.910574) (xy 335.539332 -228.873737) (xy 335.577453 -228.842612) (xy 335.620074 -228.818005)
			(xy 335.66609 -228.800553) (xy 335.714309 -228.790709) (xy 335.763484 -228.788728) (xy 335.812339 -228.79466)
			(xy 335.85961 -228.808352) (xy 335.904072 -228.82945) (xy 335.944575 -228.857406) (xy 335.980068 -228.891498)
			(xy 336.009633 -228.930842) (xy 336.032504 -228.974419) (xy 336.048088 -229.0211) (xy 336.055983 -229.069677)
			(xy 336.056478 -229.094284) (xy 336.38542 -229.094284) (xy 336.38938 -229.04523) (xy 336.401157 -228.997446)
			(xy 336.420448 -228.95217) (xy 336.446751 -228.910574) (xy 336.479386 -228.873737) (xy 336.517507 -228.842612)
			(xy 336.560128 -228.818005) (xy 336.606144 -228.800553) (xy 336.654363 -228.790709) (xy 336.703538 -228.788728)
			(xy 336.752393 -228.79466) (xy 336.799664 -228.808352) (xy 336.844126 -228.82945) (xy 336.884629 -228.857406)
			(xy 336.920122 -228.891498) (xy 336.949687 -228.930842) (xy 336.972558 -228.974419) (xy 336.988142 -229.0211)
			(xy 336.996037 -229.069677) (xy 336.996532 -229.094284) (xy 337.32522 -229.094284) (xy 337.32918 -229.04523)
			(xy 337.340957 -228.997446) (xy 337.360248 -228.95217) (xy 337.386551 -228.910574) (xy 337.419186 -228.873737)
			(xy 337.457307 -228.842612) (xy 337.499928 -228.818005) (xy 337.545944 -228.800553) (xy 337.594163 -228.790709)
			(xy 337.643338 -228.788728) (xy 337.692193 -228.79466) (xy 337.739464 -228.808352) (xy 337.783926 -228.82945)
			(xy 337.824429 -228.857406) (xy 337.859922 -228.891498) (xy 337.889487 -228.930842) (xy 337.912358 -228.974419)
			(xy 337.927942 -229.0211) (xy 337.935837 -229.069677) (xy 337.936332 -229.094284) (xy 338.254843 -229.094284)
			(xy 338.258938 -229.043556) (xy 338.271117 -228.994142) (xy 338.291065 -228.947322) (xy 338.318266 -228.904308)
			(xy 338.352014 -228.866214) (xy 338.391436 -228.834027) (xy 338.43551 -228.808581) (xy 338.483096 -228.790534)
			(xy 338.53296 -228.780354) (xy 338.583812 -228.778305) (xy 338.634333 -228.784439) (xy 338.683217 -228.798599)
			(xy 338.729196 -228.820416) (xy 338.77108 -228.849326) (xy 338.807784 -228.884581) (xy 338.838357 -228.925267)
			(xy 338.862008 -228.97033) (xy 338.878124 -229.018604) (xy 338.886288 -229.068838) (xy 338.8868 -229.094284)
			(xy 339.205328 -229.094284) (xy 339.209288 -229.04523) (xy 339.221065 -228.997446) (xy 339.240356 -228.95217)
			(xy 339.266659 -228.910574) (xy 339.299294 -228.873737) (xy 339.337415 -228.842612) (xy 339.380036 -228.818005)
			(xy 339.426052 -228.800553) (xy 339.474271 -228.790709) (xy 339.523446 -228.788728) (xy 339.572301 -228.79466)
			(xy 339.619572 -228.808352) (xy 339.664034 -228.82945) (xy 339.704537 -228.857406) (xy 339.74003 -228.891498)
			(xy 339.769595 -228.930842) (xy 339.792466 -228.974419) (xy 339.80805 -229.0211) (xy 339.815945 -229.069677)
			(xy 339.81644 -229.094284) (xy 340.134951 -229.094284) (xy 340.139046 -229.043556) (xy 340.151225 -228.994142)
			(xy 340.171173 -228.947322) (xy 340.198374 -228.904308) (xy 340.232122 -228.866214) (xy 340.271544 -228.834027)
			(xy 340.315618 -228.808581) (xy 340.363204 -228.790534) (xy 340.413068 -228.780354) (xy 340.46392 -228.778305)
			(xy 340.514441 -228.784439) (xy 340.563325 -228.798599) (xy 340.609304 -228.820416) (xy 340.651188 -228.849326)
			(xy 340.687892 -228.884581) (xy 340.718465 -228.925267) (xy 340.742116 -228.97033) (xy 340.758232 -229.018604)
			(xy 340.766396 -229.068838) (xy 340.766908 -229.094284) (xy 341.085182 -229.094284) (xy 341.089142 -229.04523)
			(xy 341.100919 -228.997446) (xy 341.12021 -228.95217) (xy 341.146513 -228.910574) (xy 341.179148 -228.873737)
			(xy 341.217269 -228.842612) (xy 341.25989 -228.818005) (xy 341.305906 -228.800553) (xy 341.354125 -228.790709)
			(xy 341.4033 -228.788728) (xy 341.452155 -228.79466) (xy 341.499426 -228.808352) (xy 341.543888 -228.82945)
			(xy 341.584391 -228.857406) (xy 341.619884 -228.891498) (xy 341.649449 -228.930842) (xy 341.67232 -228.974419)
			(xy 341.687904 -229.0211) (xy 341.695799 -229.069677) (xy 341.696294 -229.094284) (xy 342.014805 -229.094284)
			(xy 342.0189 -229.043556) (xy 342.031079 -228.994142) (xy 342.051027 -228.947322) (xy 342.078228 -228.904308)
			(xy 342.111976 -228.866214) (xy 342.151398 -228.834027) (xy 342.195472 -228.808581) (xy 342.243058 -228.790534)
			(xy 342.292922 -228.780354) (xy 342.343774 -228.778305) (xy 342.394295 -228.784439) (xy 342.443179 -228.798599)
			(xy 342.489158 -228.820416) (xy 342.531042 -228.849326) (xy 342.567746 -228.884581) (xy 342.598319 -228.925267)
			(xy 342.62197 -228.97033) (xy 342.638086 -229.018604) (xy 342.64625 -229.068838) (xy 342.646762 -229.094284)
			(xy 342.64625 -229.11973) (xy 342.638086 -229.169964) (xy 342.62197 -229.218238) (xy 342.598319 -229.263301)
			(xy 342.567746 -229.303987) (xy 342.531042 -229.339242) (xy 342.489158 -229.368152) (xy 342.443179 -229.389969)
			(xy 342.394295 -229.404129) (xy 342.343774 -229.410263) (xy 342.292922 -229.408214) (xy 342.243058 -229.398034)
			(xy 342.195472 -229.379987) (xy 342.151398 -229.354541) (xy 342.111976 -229.322354) (xy 342.078228 -229.28426)
			(xy 342.051027 -229.241246) (xy 342.031079 -229.194426) (xy 342.0189 -229.145012) (xy 342.014805 -229.094284)
			(xy 341.696294 -229.094284) (xy 341.695799 -229.118891) (xy 341.687904 -229.167468) (xy 341.67232 -229.214149)
			(xy 341.649449 -229.257726) (xy 341.619884 -229.29707) (xy 341.584391 -229.331162) (xy 341.543888 -229.359118)
			(xy 341.499426 -229.380216) (xy 341.452155 -229.393908) (xy 341.4033 -229.39984) (xy 341.354125 -229.397859)
			(xy 341.305906 -229.388015) (xy 341.25989 -229.370563) (xy 341.217269 -229.345956) (xy 341.179148 -229.314831)
			(xy 341.146513 -229.277994) (xy 341.12021 -229.236398) (xy 341.100919 -229.191122) (xy 341.089142 -229.143338)
			(xy 341.085182 -229.094284) (xy 340.766908 -229.094284) (xy 340.766396 -229.11973) (xy 340.758232 -229.169964)
			(xy 340.742116 -229.218238) (xy 340.718465 -229.263301) (xy 340.687892 -229.303987) (xy 340.651188 -229.339242)
			(xy 340.609304 -229.368152) (xy 340.563325 -229.389969) (xy 340.514441 -229.404129) (xy 340.46392 -229.410263)
			(xy 340.413068 -229.408214) (xy 340.363204 -229.398034) (xy 340.315618 -229.379987) (xy 340.271544 -229.354541)
			(xy 340.232122 -229.322354) (xy 340.198374 -229.28426) (xy 340.171173 -229.241246) (xy 340.151225 -229.194426)
			(xy 340.139046 -229.145012) (xy 340.134951 -229.094284) (xy 339.81644 -229.094284) (xy 339.815945 -229.118891)
			(xy 339.80805 -229.167468) (xy 339.792466 -229.214149) (xy 339.769595 -229.257726) (xy 339.74003 -229.29707)
			(xy 339.704537 -229.331162) (xy 339.664034 -229.359118) (xy 339.619572 -229.380216) (xy 339.572301 -229.393908)
			(xy 339.523446 -229.39984) (xy 339.474271 -229.397859) (xy 339.426052 -229.388015) (xy 339.380036 -229.370563)
			(xy 339.337415 -229.345956) (xy 339.299294 -229.314831) (xy 339.266659 -229.277994) (xy 339.240356 -229.236398)
			(xy 339.221065 -229.191122) (xy 339.209288 -229.143338) (xy 339.205328 -229.094284) (xy 338.8868 -229.094284)
			(xy 338.886288 -229.11973) (xy 338.878124 -229.169964) (xy 338.862008 -229.218238) (xy 338.838357 -229.263301)
			(xy 338.807784 -229.303987) (xy 338.77108 -229.339242) (xy 338.729196 -229.368152) (xy 338.683217 -229.389969)
			(xy 338.634333 -229.404129) (xy 338.583812 -229.410263) (xy 338.53296 -229.408214) (xy 338.483096 -229.398034)
			(xy 338.43551 -229.379987) (xy 338.391436 -229.354541) (xy 338.352014 -229.322354) (xy 338.318266 -229.28426)
			(xy 338.291065 -229.241246) (xy 338.271117 -229.194426) (xy 338.258938 -229.145012) (xy 338.254843 -229.094284)
			(xy 337.936332 -229.094284) (xy 337.935837 -229.118891) (xy 337.927942 -229.167468) (xy 337.912358 -229.214149)
			(xy 337.889487 -229.257726) (xy 337.859922 -229.29707) (xy 337.824429 -229.331162) (xy 337.783926 -229.359118)
			(xy 337.739464 -229.380216) (xy 337.692193 -229.393908) (xy 337.643338 -229.39984) (xy 337.594163 -229.397859)
			(xy 337.545944 -229.388015) (xy 337.499928 -229.370563) (xy 337.457307 -229.345956) (xy 337.419186 -229.314831)
			(xy 337.386551 -229.277994) (xy 337.360248 -229.236398) (xy 337.340957 -229.191122) (xy 337.32918 -229.143338)
			(xy 337.32522 -229.094284) (xy 336.996532 -229.094284) (xy 336.996037 -229.118891) (xy 336.988142 -229.167468)
			(xy 336.972558 -229.214149) (xy 336.949687 -229.257726) (xy 336.920122 -229.29707) (xy 336.884629 -229.331162)
			(xy 336.844126 -229.359118) (xy 336.799664 -229.380216) (xy 336.752393 -229.393908) (xy 336.703538 -229.39984)
			(xy 336.654363 -229.397859) (xy 336.606144 -229.388015) (xy 336.560128 -229.370563) (xy 336.517507 -229.345956)
			(xy 336.479386 -229.314831) (xy 336.446751 -229.277994) (xy 336.420448 -229.236398) (xy 336.401157 -229.191122)
			(xy 336.38938 -229.143338) (xy 336.38542 -229.094284) (xy 336.056478 -229.094284) (xy 336.055983 -229.118891)
			(xy 336.048088 -229.167468) (xy 336.032504 -229.214149) (xy 336.009633 -229.257726) (xy 335.980068 -229.29707)
			(xy 335.944575 -229.331162) (xy 335.904072 -229.359118) (xy 335.85961 -229.380216) (xy 335.812339 -229.393908)
			(xy 335.763484 -229.39984) (xy 335.714309 -229.397859) (xy 335.66609 -229.388015) (xy 335.620074 -229.370563)
			(xy 335.577453 -229.345956) (xy 335.539332 -229.314831) (xy 335.506697 -229.277994) (xy 335.480394 -229.236398)
			(xy 335.461103 -229.191122) (xy 335.449326 -229.143338) (xy 335.445366 -229.094284) (xy 335.116946 -229.094284)
			(xy 335.116947 -229.0943) (xy 335.112776 -229.144639) (xy 335.100376 -229.193605) (xy 335.080087 -229.239863)
			(xy 335.05246 -229.28215) (xy 335.018251 -229.319313) (xy 334.978391 -229.350339) (xy 334.933968 -229.374382)
			(xy 334.886194 -229.390785) (xy 334.836372 -229.399101) (xy 334.811116 -229.399592) (xy 334.787545 -229.399157)
			(xy 334.740962 -229.39192) (xy 334.696042 -229.377615) (xy 334.653853 -229.356581) (xy 334.615394 -229.329318)
			(xy 334.581577 -229.296472) (xy 334.567022 -229.277926) (xy 334.56499 -229.275132) (xy 334.55991 -229.270052)
			(xy 334.553346 -229.263928) (xy 334.537075 -229.256375) (xy 334.52816 -229.25532) (xy 334.522572 -229.254812)
			(xy 334.432148 -229.267004) (xy 334.423228 -229.268548) (xy 334.407232 -229.276996) (xy 334.395166 -229.290474)
			(xy 334.391508 -229.298754) (xy 334.383586 -229.318461) (xy 334.36515 -229.35673) (xy 334.354678 -229.375208)
			(xy 334.310228 -229.451916) (xy 334.303624 -229.463092) (xy 334.302862 -229.488238) (xy 334.344518 -229.573582)
			(xy 334.350575 -229.584535) (xy 334.370829 -229.599187) (xy 334.383126 -229.601522) (xy 334.407161 -229.605324)
			(xy 334.453692 -229.619553) (xy 334.497377 -229.640983) (xy 334.537109 -229.669072) (xy 334.571882 -229.703108)
			(xy 334.600815 -229.74223) (xy 334.623175 -229.785445) (xy 334.638397 -229.831661) (xy 334.646095 -229.879707)
			(xy 334.646524 -229.904036) (xy 334.975212 -229.904036) (xy 334.979172 -229.854982) (xy 334.990949 -229.807198)
			(xy 335.01024 -229.761922) (xy 335.036543 -229.720326) (xy 335.069178 -229.683489) (xy 335.107299 -229.652364)
			(xy 335.14992 -229.627757) (xy 335.195936 -229.610305) (xy 335.244155 -229.600461) (xy 335.29333 -229.59848)
			(xy 335.342185 -229.604412) (xy 335.389456 -229.618104) (xy 335.433918 -229.639202) (xy 335.474421 -229.667158)
			(xy 335.509914 -229.70125) (xy 335.539479 -229.740594) (xy 335.56235 -229.784171) (xy 335.577934 -229.830852)
			(xy 335.585829 -229.879429) (xy 335.586324 -229.904036) (xy 335.915266 -229.904036) (xy 335.919226 -229.854982)
			(xy 335.931003 -229.807198) (xy 335.950294 -229.761922) (xy 335.976597 -229.720326) (xy 336.009232 -229.683489)
			(xy 336.047353 -229.652364) (xy 336.089974 -229.627757) (xy 336.13599 -229.610305) (xy 336.184209 -229.600461)
			(xy 336.233384 -229.59848) (xy 336.282239 -229.604412) (xy 336.32951 -229.618104) (xy 336.373972 -229.639202)
			(xy 336.414475 -229.667158) (xy 336.449968 -229.70125) (xy 336.479533 -229.740594) (xy 336.502404 -229.784171)
			(xy 336.517988 -229.830852) (xy 336.525883 -229.879429) (xy 336.526378 -229.904036) (xy 336.85532 -229.904036)
			(xy 336.85928 -229.854982) (xy 336.871057 -229.807198) (xy 336.890348 -229.761922) (xy 336.916651 -229.720326)
			(xy 336.949286 -229.683489) (xy 336.987407 -229.652364) (xy 337.030028 -229.627757) (xy 337.076044 -229.610305)
			(xy 337.124263 -229.600461) (xy 337.173438 -229.59848) (xy 337.222293 -229.604412) (xy 337.269564 -229.618104)
			(xy 337.314026 -229.639202) (xy 337.354529 -229.667158) (xy 337.390022 -229.70125) (xy 337.419587 -229.740594)
			(xy 337.442458 -229.784171) (xy 337.458042 -229.830852) (xy 337.465937 -229.879429) (xy 337.466432 -229.904036)
			(xy 337.795374 -229.904036) (xy 337.799334 -229.854982) (xy 337.811111 -229.807198) (xy 337.830402 -229.761922)
			(xy 337.856705 -229.720326) (xy 337.88934 -229.683489) (xy 337.927461 -229.652364) (xy 337.970082 -229.627757)
			(xy 338.016098 -229.610305) (xy 338.064317 -229.600461) (xy 338.113492 -229.59848) (xy 338.162347 -229.604412)
			(xy 338.209618 -229.618104) (xy 338.25408 -229.639202) (xy 338.294583 -229.667158) (xy 338.330076 -229.70125)
			(xy 338.359641 -229.740594) (xy 338.382512 -229.784171) (xy 338.398096 -229.830852) (xy 338.405991 -229.879429)
			(xy 338.406486 -229.904036) (xy 338.724743 -229.904036) (xy 338.728838 -229.853308) (xy 338.741017 -229.803894)
			(xy 338.760965 -229.757074) (xy 338.788166 -229.71406) (xy 338.821914 -229.675966) (xy 338.861336 -229.643779)
			(xy 338.90541 -229.618333) (xy 338.952996 -229.600286) (xy 339.00286 -229.590106) (xy 339.053712 -229.588057)
			(xy 339.104233 -229.594191) (xy 339.153117 -229.608351) (xy 339.199096 -229.630168) (xy 339.24098 -229.659078)
			(xy 339.277684 -229.694333) (xy 339.308257 -229.735019) (xy 339.331908 -229.780082) (xy 339.348024 -229.828356)
			(xy 339.356188 -229.87859) (xy 339.3567 -229.904036) (xy 339.664797 -229.904036) (xy 339.668892 -229.853308)
			(xy 339.681071 -229.803894) (xy 339.701019 -229.757074) (xy 339.72822 -229.71406) (xy 339.761968 -229.675966)
			(xy 339.80139 -229.643779) (xy 339.845464 -229.618333) (xy 339.89305 -229.600286) (xy 339.942914 -229.590106)
			(xy 339.993766 -229.588057) (xy 340.044287 -229.594191) (xy 340.093171 -229.608351) (xy 340.13915 -229.630168)
			(xy 340.181034 -229.659078) (xy 340.217738 -229.694333) (xy 340.248311 -229.735019) (xy 340.271962 -229.780082)
			(xy 340.288078 -229.828356) (xy 340.296242 -229.87859) (xy 340.296754 -229.904036) (xy 340.615282 -229.904036)
			(xy 340.619242 -229.854982) (xy 340.631019 -229.807198) (xy 340.65031 -229.761922) (xy 340.676613 -229.720326)
			(xy 340.709248 -229.683489) (xy 340.747369 -229.652364) (xy 340.78999 -229.627757) (xy 340.836006 -229.610305)
			(xy 340.884225 -229.600461) (xy 340.9334 -229.59848) (xy 340.982255 -229.604412) (xy 341.029526 -229.618104)
			(xy 341.073988 -229.639202) (xy 341.114491 -229.667158) (xy 341.149984 -229.70125) (xy 341.179549 -229.740594)
			(xy 341.20242 -229.784171) (xy 341.218004 -229.830852) (xy 341.225899 -229.879429) (xy 341.226394 -229.904036)
			(xy 341.544905 -229.904036) (xy 341.549 -229.853308) (xy 341.561179 -229.803894) (xy 341.581127 -229.757074)
			(xy 341.608328 -229.71406) (xy 341.642076 -229.675966) (xy 341.681498 -229.643779) (xy 341.725572 -229.618333)
			(xy 341.773158 -229.600286) (xy 341.823022 -229.590106) (xy 341.873874 -229.588057) (xy 341.924395 -229.594191)
			(xy 341.973279 -229.608351) (xy 342.019258 -229.630168) (xy 342.061142 -229.659078) (xy 342.097846 -229.694333)
			(xy 342.128419 -229.735019) (xy 342.15207 -229.780082) (xy 342.168186 -229.828356) (xy 342.17635 -229.87859)
			(xy 342.176862 -229.904036) (xy 342.49539 -229.904036) (xy 342.49935 -229.854982) (xy 342.511127 -229.807198)
			(xy 342.530418 -229.761922) (xy 342.556721 -229.720326) (xy 342.589356 -229.683489) (xy 342.627477 -229.652364)
			(xy 342.670098 -229.627757) (xy 342.716114 -229.610305) (xy 342.764333 -229.600461) (xy 342.813508 -229.59848)
			(xy 342.862363 -229.604412) (xy 342.909634 -229.618104) (xy 342.954096 -229.639202) (xy 342.994599 -229.667158)
			(xy 343.030092 -229.70125) (xy 343.059657 -229.740594) (xy 343.082528 -229.784171) (xy 343.098112 -229.830852)
			(xy 343.106007 -229.879429) (xy 343.106502 -229.904036) (xy 343.106007 -229.928643) (xy 343.098112 -229.97722)
			(xy 343.082528 -230.023901) (xy 343.059657 -230.067478) (xy 343.030092 -230.106822) (xy 342.994599 -230.140914)
			(xy 342.954096 -230.16887) (xy 342.909634 -230.189968) (xy 342.862363 -230.20366) (xy 342.813508 -230.209592)
			(xy 342.764333 -230.207611) (xy 342.716114 -230.197767) (xy 342.670098 -230.180315) (xy 342.627477 -230.155708)
			(xy 342.589356 -230.124583) (xy 342.556721 -230.087746) (xy 342.530418 -230.04615) (xy 342.511127 -230.000874)
			(xy 342.49935 -229.95309) (xy 342.49539 -229.904036) (xy 342.176862 -229.904036) (xy 342.17635 -229.929482)
			(xy 342.168186 -229.979716) (xy 342.15207 -230.02799) (xy 342.128419 -230.073053) (xy 342.097846 -230.113739)
			(xy 342.061142 -230.148994) (xy 342.019258 -230.177904) (xy 341.973279 -230.199721) (xy 341.924395 -230.213881)
			(xy 341.873874 -230.220015) (xy 341.823022 -230.217966) (xy 341.773158 -230.207786) (xy 341.725572 -230.189739)
			(xy 341.681498 -230.164293) (xy 341.642076 -230.132106) (xy 341.608328 -230.094012) (xy 341.581127 -230.050998)
			(xy 341.561179 -230.004178) (xy 341.549 -229.954764) (xy 341.544905 -229.904036) (xy 341.226394 -229.904036)
			(xy 341.225899 -229.928643) (xy 341.218004 -229.97722) (xy 341.20242 -230.023901) (xy 341.179549 -230.067478)
			(xy 341.149984 -230.106822) (xy 341.114491 -230.140914) (xy 341.073988 -230.16887) (xy 341.029526 -230.189968)
			(xy 340.982255 -230.20366) (xy 340.9334 -230.209592) (xy 340.884225 -230.207611) (xy 340.836006 -230.197767)
			(xy 340.78999 -230.180315) (xy 340.747369 -230.155708) (xy 340.709248 -230.124583) (xy 340.676613 -230.087746)
			(xy 340.65031 -230.04615) (xy 340.631019 -230.000874) (xy 340.619242 -229.95309) (xy 340.615282 -229.904036)
			(xy 340.296754 -229.904036) (xy 340.296242 -229.929482) (xy 340.288078 -229.979716) (xy 340.271962 -230.02799)
			(xy 340.248311 -230.073053) (xy 340.217738 -230.113739) (xy 340.181034 -230.148994) (xy 340.13915 -230.177904)
			(xy 340.093171 -230.199721) (xy 340.044287 -230.213881) (xy 339.993766 -230.220015) (xy 339.942914 -230.217966)
			(xy 339.89305 -230.207786) (xy 339.845464 -230.189739) (xy 339.80139 -230.164293) (xy 339.761968 -230.132106)
			(xy 339.72822 -230.094012) (xy 339.701019 -230.050998) (xy 339.681071 -230.004178) (xy 339.668892 -229.954764)
			(xy 339.664797 -229.904036) (xy 339.3567 -229.904036) (xy 339.356188 -229.929482) (xy 339.348024 -229.979716)
			(xy 339.331908 -230.02799) (xy 339.308257 -230.073053) (xy 339.277684 -230.113739) (xy 339.24098 -230.148994)
			(xy 339.199096 -230.177904) (xy 339.153117 -230.199721) (xy 339.104233 -230.213881) (xy 339.053712 -230.220015)
			(xy 339.00286 -230.217966) (xy 338.952996 -230.207786) (xy 338.90541 -230.189739) (xy 338.861336 -230.164293)
			(xy 338.821914 -230.132106) (xy 338.788166 -230.094012) (xy 338.760965 -230.050998) (xy 338.741017 -230.004178)
			(xy 338.728838 -229.954764) (xy 338.724743 -229.904036) (xy 338.406486 -229.904036) (xy 338.405991 -229.928643)
			(xy 338.398096 -229.97722) (xy 338.382512 -230.023901) (xy 338.359641 -230.067478) (xy 338.330076 -230.106822)
			(xy 338.294583 -230.140914) (xy 338.25408 -230.16887) (xy 338.209618 -230.189968) (xy 338.162347 -230.20366)
			(xy 338.113492 -230.209592) (xy 338.064317 -230.207611) (xy 338.016098 -230.197767) (xy 337.970082 -230.180315)
			(xy 337.927461 -230.155708) (xy 337.88934 -230.124583) (xy 337.856705 -230.087746) (xy 337.830402 -230.04615)
			(xy 337.811111 -230.000874) (xy 337.799334 -229.95309) (xy 337.795374 -229.904036) (xy 337.466432 -229.904036)
			(xy 337.465937 -229.928643) (xy 337.458042 -229.97722) (xy 337.442458 -230.023901) (xy 337.419587 -230.067478)
			(xy 337.390022 -230.106822) (xy 337.354529 -230.140914) (xy 337.314026 -230.16887) (xy 337.269564 -230.189968)
			(xy 337.222293 -230.20366) (xy 337.173438 -230.209592) (xy 337.124263 -230.207611) (xy 337.076044 -230.197767)
			(xy 337.030028 -230.180315) (xy 336.987407 -230.155708) (xy 336.949286 -230.124583) (xy 336.916651 -230.087746)
			(xy 336.890348 -230.04615) (xy 336.871057 -230.000874) (xy 336.85928 -229.95309) (xy 336.85532 -229.904036)
			(xy 336.526378 -229.904036) (xy 336.525883 -229.928643) (xy 336.517988 -229.97722) (xy 336.502404 -230.023901)
			(xy 336.479533 -230.067478) (xy 336.449968 -230.106822) (xy 336.414475 -230.140914) (xy 336.373972 -230.16887)
			(xy 336.32951 -230.189968) (xy 336.282239 -230.20366) (xy 336.233384 -230.209592) (xy 336.184209 -230.207611)
			(xy 336.13599 -230.197767) (xy 336.089974 -230.180315) (xy 336.047353 -230.155708) (xy 336.009232 -230.124583)
			(xy 335.976597 -230.087746) (xy 335.950294 -230.04615) (xy 335.931003 -230.000874) (xy 335.919226 -229.95309)
			(xy 335.915266 -229.904036) (xy 335.586324 -229.904036) (xy 335.585829 -229.928643) (xy 335.577934 -229.97722)
			(xy 335.56235 -230.023901) (xy 335.539479 -230.067478) (xy 335.509914 -230.106822) (xy 335.474421 -230.140914)
			(xy 335.433918 -230.16887) (xy 335.389456 -230.189968) (xy 335.342185 -230.20366) (xy 335.29333 -230.209592)
			(xy 335.244155 -230.207611) (xy 335.195936 -230.197767) (xy 335.14992 -230.180315) (xy 335.107299 -230.155708)
			(xy 335.069178 -230.124583) (xy 335.036543 -230.087746) (xy 335.01024 -230.04615) (xy 334.990949 -230.000874)
			(xy 334.979172 -229.95309) (xy 334.975212 -229.904036) (xy 334.646524 -229.904036) (xy 334.646051 -229.928026)
			(xy 334.63854 -229.975414) (xy 334.62371 -230.021044) (xy 334.601925 -230.063793) (xy 334.573721 -230.102608)
			(xy 334.539793 -230.136534) (xy 334.500976 -230.164735) (xy 334.458226 -230.186518) (xy 334.412595 -230.201345)
			(xy 334.365206 -230.208852) (xy 334.341216 -230.209344) (xy 334.309466 -230.207566) (xy 334.306672 -230.207312)
			(xy 334.304132 -230.207312) (xy 334.294107 -230.207726) (xy 334.275581 -230.215391) (xy 334.261402 -230.229565)
			(xy 334.25373 -230.248087) (xy 334.253332 -230.258112) (xy 334.253332 -230.278686) (xy 334.254094 -230.287576)
			(xy 334.255364 -230.294434) (xy 334.256968 -230.302046) (xy 334.264085 -230.31587) (xy 334.269334 -230.321612)
			(xy 334.269588 -230.321866) (xy 334.274922 -230.327454) (xy 334.298192 -230.352483) (xy 334.339096 -230.407232)
			(xy 334.373005 -230.466569) (xy 334.386682 -230.497888) (xy 334.389222 -230.503984) (xy 334.396842 -230.514144)
			(xy 334.421226 -230.533194) (xy 334.426702 -230.537151) (xy 334.439191 -230.542293) (xy 334.445864 -230.543354)
			(xy 334.516984 -230.553006) (xy 334.522959 -230.553624) (xy 334.5349 -230.552343) (xy 334.540606 -230.550466)
			(xy 334.551782 -230.546656) (xy 334.56499 -230.533448) (xy 334.567022 -230.530654) (xy 334.581567 -230.512102)
			(xy 334.615398 -230.479273) (xy 334.653863 -230.45202) (xy 334.696052 -230.430988) (xy 334.740967 -230.416674)
			(xy 334.787546 -230.409418) (xy 334.811116 -230.408988) (xy 334.836371 -230.409511) (xy 334.886191 -230.417827)
			(xy 334.933963 -230.434229) (xy 334.978384 -230.458271) (xy 335.018243 -230.489296) (xy 335.052451 -230.526458)
			(xy 335.080076 -230.568743) (xy 335.100365 -230.614999) (xy 335.112764 -230.663963) (xy 335.116935 -230.714296)
			(xy 335.445366 -230.714296) (xy 335.449326 -230.665242) (xy 335.461103 -230.617458) (xy 335.480394 -230.572182)
			(xy 335.506697 -230.530586) (xy 335.539332 -230.493749) (xy 335.577453 -230.462624) (xy 335.620074 -230.438017)
			(xy 335.66609 -230.420565) (xy 335.714309 -230.410721) (xy 335.763484 -230.40874) (xy 335.812339 -230.414672)
			(xy 335.85961 -230.428364) (xy 335.904072 -230.449462) (xy 335.944575 -230.477418) (xy 335.980068 -230.51151)
			(xy 336.009633 -230.550854) (xy 336.032504 -230.594431) (xy 336.048088 -230.641112) (xy 336.055983 -230.689689)
			(xy 336.056478 -230.714296) (xy 336.38542 -230.714296) (xy 336.38938 -230.665242) (xy 336.401157 -230.617458)
			(xy 336.420448 -230.572182) (xy 336.446751 -230.530586) (xy 336.479386 -230.493749) (xy 336.517507 -230.462624)
			(xy 336.560128 -230.438017) (xy 336.606144 -230.420565) (xy 336.654363 -230.410721) (xy 336.703538 -230.40874)
			(xy 336.752393 -230.414672) (xy 336.799664 -230.428364) (xy 336.844126 -230.449462) (xy 336.884629 -230.477418)
			(xy 336.920122 -230.51151) (xy 336.949687 -230.550854) (xy 336.972558 -230.594431) (xy 336.988142 -230.641112)
			(xy 336.996037 -230.689689) (xy 336.996527 -230.714042) (xy 337.32522 -230.714042) (xy 337.32918 -230.664988)
			(xy 337.340957 -230.617204) (xy 337.360248 -230.571928) (xy 337.386551 -230.530332) (xy 337.419186 -230.493495)
			(xy 337.457307 -230.46237) (xy 337.499928 -230.437763) (xy 337.545944 -230.420311) (xy 337.594163 -230.410467)
			(xy 337.643338 -230.408486) (xy 337.692193 -230.414418) (xy 337.739464 -230.42811) (xy 337.783926 -230.449208)
			(xy 337.824429 -230.477164) (xy 337.859922 -230.511256) (xy 337.889487 -230.5506) (xy 337.912358 -230.594177)
			(xy 337.927942 -230.640858) (xy 337.935837 -230.689435) (xy 337.936332 -230.714042) (xy 337.936327 -230.714296)
			(xy 338.254843 -230.714296) (xy 338.258938 -230.663568) (xy 338.271117 -230.614154) (xy 338.291065 -230.567334)
			(xy 338.318266 -230.52432) (xy 338.352014 -230.486226) (xy 338.391436 -230.454039) (xy 338.43551 -230.428593)
			(xy 338.483096 -230.410546) (xy 338.53296 -230.400366) (xy 338.583812 -230.398317) (xy 338.634333 -230.404451)
			(xy 338.683217 -230.418611) (xy 338.729196 -230.440428) (xy 338.77108 -230.469338) (xy 338.807784 -230.504593)
			(xy 338.838357 -230.545279) (xy 338.862008 -230.590342) (xy 338.878124 -230.638616) (xy 338.886288 -230.68885)
			(xy 338.8868 -230.714296) (xy 339.205328 -230.714296) (xy 339.209288 -230.665242) (xy 339.221065 -230.617458)
			(xy 339.240356 -230.572182) (xy 339.266659 -230.530586) (xy 339.299294 -230.493749) (xy 339.337415 -230.462624)
			(xy 339.380036 -230.438017) (xy 339.426052 -230.420565) (xy 339.474271 -230.410721) (xy 339.523446 -230.40874)
			(xy 339.572301 -230.414672) (xy 339.619572 -230.428364) (xy 339.664034 -230.449462) (xy 339.704537 -230.477418)
			(xy 339.74003 -230.51151) (xy 339.769595 -230.550854) (xy 339.792466 -230.594431) (xy 339.80805 -230.641112)
			(xy 339.815945 -230.689689) (xy 339.81644 -230.714296) (xy 340.134951 -230.714296) (xy 340.139046 -230.663568)
			(xy 340.151225 -230.614154) (xy 340.171173 -230.567334) (xy 340.198374 -230.52432) (xy 340.232122 -230.486226)
			(xy 340.271544 -230.454039) (xy 340.315618 -230.428593) (xy 340.363204 -230.410546) (xy 340.413068 -230.400366)
			(xy 340.46392 -230.398317) (xy 340.514441 -230.404451) (xy 340.563325 -230.418611) (xy 340.609304 -230.440428)
			(xy 340.651188 -230.469338) (xy 340.687892 -230.504593) (xy 340.718465 -230.545279) (xy 340.742116 -230.590342)
			(xy 340.758232 -230.638616) (xy 340.766396 -230.68885) (xy 340.766903 -230.714042) (xy 341.085182 -230.714042)
			(xy 341.089142 -230.664988) (xy 341.100919 -230.617204) (xy 341.12021 -230.571928) (xy 341.146513 -230.530332)
			(xy 341.179148 -230.493495) (xy 341.217269 -230.46237) (xy 341.25989 -230.437763) (xy 341.305906 -230.420311)
			(xy 341.354125 -230.410467) (xy 341.4033 -230.408486) (xy 341.452155 -230.414418) (xy 341.499426 -230.42811)
			(xy 341.543888 -230.449208) (xy 341.584391 -230.477164) (xy 341.619884 -230.511256) (xy 341.649449 -230.5506)
			(xy 341.67232 -230.594177) (xy 341.687904 -230.640858) (xy 341.695799 -230.689435) (xy 341.696294 -230.714042)
			(xy 341.696289 -230.714296) (xy 342.014805 -230.714296) (xy 342.0189 -230.663568) (xy 342.031079 -230.614154)
			(xy 342.051027 -230.567334) (xy 342.078228 -230.52432) (xy 342.111976 -230.486226) (xy 342.151398 -230.454039)
			(xy 342.195472 -230.428593) (xy 342.243058 -230.410546) (xy 342.292922 -230.400366) (xy 342.343774 -230.398317)
			(xy 342.394295 -230.404451) (xy 342.443179 -230.418611) (xy 342.489158 -230.440428) (xy 342.531042 -230.469338)
			(xy 342.567746 -230.504593) (xy 342.598319 -230.545279) (xy 342.62197 -230.590342) (xy 342.638086 -230.638616)
			(xy 342.64625 -230.68885) (xy 342.646762 -230.714296) (xy 342.64625 -230.739742) (xy 342.638086 -230.789976)
			(xy 342.62197 -230.83825) (xy 342.598319 -230.883313) (xy 342.567746 -230.923999) (xy 342.531042 -230.959254)
			(xy 342.489158 -230.988164) (xy 342.443179 -231.009981) (xy 342.394295 -231.024141) (xy 342.343774 -231.030275)
			(xy 342.292922 -231.028226) (xy 342.243058 -231.018046) (xy 342.195472 -230.999999) (xy 342.151398 -230.974553)
			(xy 342.111976 -230.942366) (xy 342.078228 -230.904272) (xy 342.051027 -230.861258) (xy 342.031079 -230.814438)
			(xy 342.0189 -230.765024) (xy 342.014805 -230.714296) (xy 341.696289 -230.714296) (xy 341.695799 -230.738649)
			(xy 341.687904 -230.787226) (xy 341.67232 -230.833907) (xy 341.649449 -230.877484) (xy 341.619884 -230.916828)
			(xy 341.584391 -230.95092) (xy 341.543888 -230.978876) (xy 341.499426 -230.999974) (xy 341.452155 -231.013666)
			(xy 341.4033 -231.019598) (xy 341.354125 -231.017617) (xy 341.305906 -231.007773) (xy 341.25989 -230.990321)
			(xy 341.217269 -230.965714) (xy 341.179148 -230.934589) (xy 341.146513 -230.897752) (xy 341.12021 -230.856156)
			(xy 341.100919 -230.81088) (xy 341.089142 -230.763096) (xy 341.085182 -230.714042) (xy 340.766903 -230.714042)
			(xy 340.766908 -230.714296) (xy 340.766396 -230.739742) (xy 340.758232 -230.789976) (xy 340.742116 -230.83825)
			(xy 340.718465 -230.883313) (xy 340.687892 -230.923999) (xy 340.651188 -230.959254) (xy 340.609304 -230.988164)
			(xy 340.563325 -231.009981) (xy 340.514441 -231.024141) (xy 340.46392 -231.030275) (xy 340.413068 -231.028226)
			(xy 340.363204 -231.018046) (xy 340.315618 -230.999999) (xy 340.271544 -230.974553) (xy 340.232122 -230.942366)
			(xy 340.198374 -230.904272) (xy 340.171173 -230.861258) (xy 340.151225 -230.814438) (xy 340.139046 -230.765024)
			(xy 340.134951 -230.714296) (xy 339.81644 -230.714296) (xy 339.815945 -230.738903) (xy 339.80805 -230.78748)
			(xy 339.792466 -230.834161) (xy 339.769595 -230.877738) (xy 339.74003 -230.917082) (xy 339.704537 -230.951174)
			(xy 339.664034 -230.97913) (xy 339.619572 -231.000228) (xy 339.572301 -231.01392) (xy 339.523446 -231.019852)
			(xy 339.474271 -231.017871) (xy 339.426052 -231.008027) (xy 339.380036 -230.990575) (xy 339.337415 -230.965968)
			(xy 339.299294 -230.934843) (xy 339.266659 -230.898006) (xy 339.240356 -230.85641) (xy 339.221065 -230.811134)
			(xy 339.209288 -230.76335) (xy 339.205328 -230.714296) (xy 338.8868 -230.714296) (xy 338.886288 -230.739742)
			(xy 338.878124 -230.789976) (xy 338.862008 -230.83825) (xy 338.838357 -230.883313) (xy 338.807784 -230.923999)
			(xy 338.77108 -230.959254) (xy 338.729196 -230.988164) (xy 338.683217 -231.009981) (xy 338.634333 -231.024141)
			(xy 338.583812 -231.030275) (xy 338.53296 -231.028226) (xy 338.483096 -231.018046) (xy 338.43551 -230.999999)
			(xy 338.391436 -230.974553) (xy 338.352014 -230.942366) (xy 338.318266 -230.904272) (xy 338.291065 -230.861258)
			(xy 338.271117 -230.814438) (xy 338.258938 -230.765024) (xy 338.254843 -230.714296) (xy 337.936327 -230.714296)
			(xy 337.935837 -230.738649) (xy 337.927942 -230.787226) (xy 337.912358 -230.833907) (xy 337.889487 -230.877484)
			(xy 337.859922 -230.916828) (xy 337.824429 -230.95092) (xy 337.783926 -230.978876) (xy 337.739464 -230.999974)
			(xy 337.692193 -231.013666) (xy 337.643338 -231.019598) (xy 337.594163 -231.017617) (xy 337.545944 -231.007773)
			(xy 337.499928 -230.990321) (xy 337.457307 -230.965714) (xy 337.419186 -230.934589) (xy 337.386551 -230.897752)
			(xy 337.360248 -230.856156) (xy 337.340957 -230.81088) (xy 337.32918 -230.763096) (xy 337.32522 -230.714042)
			(xy 336.996527 -230.714042) (xy 336.996532 -230.714296) (xy 336.996037 -230.738903) (xy 336.988142 -230.78748)
			(xy 336.972558 -230.834161) (xy 336.949687 -230.877738) (xy 336.920122 -230.917082) (xy 336.884629 -230.951174)
			(xy 336.844126 -230.97913) (xy 336.799664 -231.000228) (xy 336.752393 -231.01392) (xy 336.703538 -231.019852)
			(xy 336.654363 -231.017871) (xy 336.606144 -231.008027) (xy 336.560128 -230.990575) (xy 336.517507 -230.965968)
			(xy 336.479386 -230.934843) (xy 336.446751 -230.898006) (xy 336.420448 -230.85641) (xy 336.401157 -230.811134)
			(xy 336.38938 -230.76335) (xy 336.38542 -230.714296) (xy 336.056478 -230.714296) (xy 336.055983 -230.738903)
			(xy 336.048088 -230.78748) (xy 336.032504 -230.834161) (xy 336.009633 -230.877738) (xy 335.980068 -230.917082)
			(xy 335.944575 -230.951174) (xy 335.904072 -230.97913) (xy 335.85961 -231.000228) (xy 335.812339 -231.01392)
			(xy 335.763484 -231.019852) (xy 335.714309 -231.017871) (xy 335.66609 -231.008027) (xy 335.620074 -230.990575)
			(xy 335.577453 -230.965968) (xy 335.539332 -230.934843) (xy 335.506697 -230.898006) (xy 335.480394 -230.85641)
			(xy 335.461103 -230.811134) (xy 335.449326 -230.76335) (xy 335.445366 -230.714296) (xy 335.116935 -230.714296)
			(xy 335.116935 -230.7143) (xy 335.112764 -230.764637) (xy 335.100365 -230.813601) (xy 335.080076 -230.859857)
			(xy 335.052451 -230.902142) (xy 335.018243 -230.939304) (xy 334.978384 -230.970329) (xy 334.933963 -230.994371)
			(xy 334.886191 -231.010773) (xy 334.836371 -231.019089) (xy 334.811116 -231.019604) (xy 334.787545 -231.019169)
			(xy 334.740961 -231.011932) (xy 334.696041 -230.997627) (xy 334.653851 -230.976594) (xy 334.615391 -230.949332)
			(xy 334.581574 -230.916486) (xy 334.567022 -230.897938) (xy 334.56499 -230.895144) (xy 334.55991 -230.890064)
			(xy 334.553347 -230.883939) (xy 334.537075 -230.876384) (xy 334.52816 -230.875332) (xy 334.522572 -230.874824)
			(xy 334.432148 -230.887016) (xy 334.423229 -230.888561) (xy 334.407235 -230.89701) (xy 334.395171 -230.910488)
			(xy 334.391508 -230.918766) (xy 334.383585 -230.938473) (xy 334.365149 -230.976741) (xy 334.354678 -230.99522)
			(xy 334.310228 -231.071928) (xy 334.303624 -231.083104) (xy 334.302862 -231.10825) (xy 334.344518 -231.193594)
			(xy 334.350576 -231.204545) (xy 334.370831 -231.219194) (xy 334.383126 -231.221534) (xy 334.40716 -231.225336)
			(xy 334.453691 -231.239565) (xy 334.497375 -231.260996) (xy 334.537105 -231.289085) (xy 334.571877 -231.323121)
			(xy 334.600809 -231.362243) (xy 334.623168 -231.405458) (xy 334.638388 -231.451674) (xy 334.646084 -231.499719)
			(xy 334.646524 -231.524048) (xy 334.975212 -231.524048) (xy 334.979172 -231.474994) (xy 334.990949 -231.42721)
			(xy 335.01024 -231.381934) (xy 335.036543 -231.340338) (xy 335.069178 -231.303501) (xy 335.107299 -231.272376)
			(xy 335.14992 -231.247769) (xy 335.195936 -231.230317) (xy 335.244155 -231.220473) (xy 335.29333 -231.218492)
			(xy 335.342185 -231.224424) (xy 335.389456 -231.238116) (xy 335.433918 -231.259214) (xy 335.474421 -231.28717)
			(xy 335.509914 -231.321262) (xy 335.539479 -231.360606) (xy 335.56235 -231.404183) (xy 335.577934 -231.450864)
			(xy 335.585829 -231.499441) (xy 335.586324 -231.524048) (xy 335.915266 -231.524048) (xy 335.919226 -231.474994)
			(xy 335.931003 -231.42721) (xy 335.950294 -231.381934) (xy 335.976597 -231.340338) (xy 336.009232 -231.303501)
			(xy 336.047353 -231.272376) (xy 336.089974 -231.247769) (xy 336.13599 -231.230317) (xy 336.184209 -231.220473)
			(xy 336.233384 -231.218492) (xy 336.282239 -231.224424) (xy 336.32951 -231.238116) (xy 336.373972 -231.259214)
			(xy 336.414475 -231.28717) (xy 336.449968 -231.321262) (xy 336.479533 -231.360606) (xy 336.502404 -231.404183)
			(xy 336.517988 -231.450864) (xy 336.525883 -231.499441) (xy 336.526378 -231.524048) (xy 336.85532 -231.524048)
			(xy 336.85928 -231.474994) (xy 336.871057 -231.42721) (xy 336.890348 -231.381934) (xy 336.916651 -231.340338)
			(xy 336.949286 -231.303501) (xy 336.987407 -231.272376) (xy 337.030028 -231.247769) (xy 337.076044 -231.230317)
			(xy 337.124263 -231.220473) (xy 337.173438 -231.218492) (xy 337.222293 -231.224424) (xy 337.269564 -231.238116)
			(xy 337.314026 -231.259214) (xy 337.354529 -231.28717) (xy 337.390022 -231.321262) (xy 337.419587 -231.360606)
			(xy 337.442458 -231.404183) (xy 337.458042 -231.450864) (xy 337.465937 -231.499441) (xy 337.466432 -231.524048)
			(xy 337.795374 -231.524048) (xy 337.799334 -231.474994) (xy 337.811111 -231.42721) (xy 337.830402 -231.381934)
			(xy 337.856705 -231.340338) (xy 337.88934 -231.303501) (xy 337.927461 -231.272376) (xy 337.970082 -231.247769)
			(xy 338.016098 -231.230317) (xy 338.064317 -231.220473) (xy 338.113492 -231.218492) (xy 338.162347 -231.224424)
			(xy 338.209618 -231.238116) (xy 338.25408 -231.259214) (xy 338.294583 -231.28717) (xy 338.330076 -231.321262)
			(xy 338.359641 -231.360606) (xy 338.382512 -231.404183) (xy 338.398096 -231.450864) (xy 338.405991 -231.499441)
			(xy 338.406486 -231.524048) (xy 338.724743 -231.524048) (xy 338.728838 -231.47332) (xy 338.741017 -231.423906)
			(xy 338.760965 -231.377086) (xy 338.788166 -231.334072) (xy 338.821914 -231.295978) (xy 338.861336 -231.263791)
			(xy 338.90541 -231.238345) (xy 338.952996 -231.220298) (xy 339.00286 -231.210118) (xy 339.053712 -231.208069)
			(xy 339.104233 -231.214203) (xy 339.153117 -231.228363) (xy 339.199096 -231.25018) (xy 339.24098 -231.27909)
			(xy 339.277684 -231.314345) (xy 339.308257 -231.355031) (xy 339.331908 -231.400094) (xy 339.348024 -231.448368)
			(xy 339.356188 -231.498602) (xy 339.3567 -231.524048) (xy 339.664797 -231.524048) (xy 339.668892 -231.47332)
			(xy 339.681071 -231.423906) (xy 339.701019 -231.377086) (xy 339.72822 -231.334072) (xy 339.761968 -231.295978)
			(xy 339.80139 -231.263791) (xy 339.845464 -231.238345) (xy 339.89305 -231.220298) (xy 339.942914 -231.210118)
			(xy 339.993766 -231.208069) (xy 340.044287 -231.214203) (xy 340.093171 -231.228363) (xy 340.13915 -231.25018)
			(xy 340.181034 -231.27909) (xy 340.217738 -231.314345) (xy 340.248311 -231.355031) (xy 340.271962 -231.400094)
			(xy 340.288078 -231.448368) (xy 340.296242 -231.498602) (xy 340.296754 -231.524048) (xy 340.615282 -231.524048)
			(xy 340.619242 -231.474994) (xy 340.631019 -231.42721) (xy 340.65031 -231.381934) (xy 340.676613 -231.340338)
			(xy 340.709248 -231.303501) (xy 340.747369 -231.272376) (xy 340.78999 -231.247769) (xy 340.836006 -231.230317)
			(xy 340.884225 -231.220473) (xy 340.9334 -231.218492) (xy 340.982255 -231.224424) (xy 341.029526 -231.238116)
			(xy 341.073988 -231.259214) (xy 341.114491 -231.28717) (xy 341.149984 -231.321262) (xy 341.179549 -231.360606)
			(xy 341.20242 -231.404183) (xy 341.218004 -231.450864) (xy 341.225899 -231.499441) (xy 341.226394 -231.524048)
			(xy 341.544905 -231.524048) (xy 341.549 -231.47332) (xy 341.561179 -231.423906) (xy 341.581127 -231.377086)
			(xy 341.608328 -231.334072) (xy 341.642076 -231.295978) (xy 341.681498 -231.263791) (xy 341.725572 -231.238345)
			(xy 341.773158 -231.220298) (xy 341.823022 -231.210118) (xy 341.873874 -231.208069) (xy 341.924395 -231.214203)
			(xy 341.973279 -231.228363) (xy 342.019258 -231.25018) (xy 342.061142 -231.27909) (xy 342.097846 -231.314345)
			(xy 342.128419 -231.355031) (xy 342.15207 -231.400094) (xy 342.168186 -231.448368) (xy 342.17635 -231.498602)
			(xy 342.176862 -231.524048) (xy 342.49539 -231.524048) (xy 342.49935 -231.474994) (xy 342.511127 -231.42721)
			(xy 342.530418 -231.381934) (xy 342.556721 -231.340338) (xy 342.589356 -231.303501) (xy 342.627477 -231.272376)
			(xy 342.670098 -231.247769) (xy 342.716114 -231.230317) (xy 342.764333 -231.220473) (xy 342.813508 -231.218492)
			(xy 342.862363 -231.224424) (xy 342.909634 -231.238116) (xy 342.954096 -231.259214) (xy 342.994599 -231.28717)
			(xy 343.030092 -231.321262) (xy 343.059657 -231.360606) (xy 343.082528 -231.404183) (xy 343.098112 -231.450864)
			(xy 343.106007 -231.499441) (xy 343.106502 -231.524048) (xy 343.106007 -231.548655) (xy 343.098112 -231.597232)
			(xy 343.082528 -231.643913) (xy 343.059657 -231.68749) (xy 343.030092 -231.726834) (xy 342.994599 -231.760926)
			(xy 342.954096 -231.788882) (xy 342.909634 -231.80998) (xy 342.862363 -231.823672) (xy 342.813508 -231.829604)
			(xy 342.764333 -231.827623) (xy 342.716114 -231.817779) (xy 342.670098 -231.800327) (xy 342.627477 -231.77572)
			(xy 342.589356 -231.744595) (xy 342.556721 -231.707758) (xy 342.530418 -231.666162) (xy 342.511127 -231.620886)
			(xy 342.49935 -231.573102) (xy 342.49539 -231.524048) (xy 342.176862 -231.524048) (xy 342.17635 -231.549494)
			(xy 342.168186 -231.599728) (xy 342.15207 -231.648002) (xy 342.128419 -231.693065) (xy 342.097846 -231.733751)
			(xy 342.061142 -231.769006) (xy 342.019258 -231.797916) (xy 341.973279 -231.819733) (xy 341.924395 -231.833893)
			(xy 341.873874 -231.840027) (xy 341.823022 -231.837978) (xy 341.773158 -231.827798) (xy 341.725572 -231.809751)
			(xy 341.681498 -231.784305) (xy 341.642076 -231.752118) (xy 341.608328 -231.714024) (xy 341.581127 -231.67101)
			(xy 341.561179 -231.62419) (xy 341.549 -231.574776) (xy 341.544905 -231.524048) (xy 341.226394 -231.524048)
			(xy 341.225899 -231.548655) (xy 341.218004 -231.597232) (xy 341.20242 -231.643913) (xy 341.179549 -231.68749)
			(xy 341.149984 -231.726834) (xy 341.114491 -231.760926) (xy 341.073988 -231.788882) (xy 341.029526 -231.80998)
			(xy 340.982255 -231.823672) (xy 340.9334 -231.829604) (xy 340.884225 -231.827623) (xy 340.836006 -231.817779)
			(xy 340.78999 -231.800327) (xy 340.747369 -231.77572) (xy 340.709248 -231.744595) (xy 340.676613 -231.707758)
			(xy 340.65031 -231.666162) (xy 340.631019 -231.620886) (xy 340.619242 -231.573102) (xy 340.615282 -231.524048)
			(xy 340.296754 -231.524048) (xy 340.296242 -231.549494) (xy 340.288078 -231.599728) (xy 340.271962 -231.648002)
			(xy 340.248311 -231.693065) (xy 340.217738 -231.733751) (xy 340.181034 -231.769006) (xy 340.13915 -231.797916)
			(xy 340.093171 -231.819733) (xy 340.044287 -231.833893) (xy 339.993766 -231.840027) (xy 339.942914 -231.837978)
			(xy 339.89305 -231.827798) (xy 339.845464 -231.809751) (xy 339.80139 -231.784305) (xy 339.761968 -231.752118)
			(xy 339.72822 -231.714024) (xy 339.701019 -231.67101) (xy 339.681071 -231.62419) (xy 339.668892 -231.574776)
			(xy 339.664797 -231.524048) (xy 339.3567 -231.524048) (xy 339.356188 -231.549494) (xy 339.348024 -231.599728)
			(xy 339.331908 -231.648002) (xy 339.308257 -231.693065) (xy 339.277684 -231.733751) (xy 339.24098 -231.769006)
			(xy 339.199096 -231.797916) (xy 339.153117 -231.819733) (xy 339.104233 -231.833893) (xy 339.053712 -231.840027)
			(xy 339.00286 -231.837978) (xy 338.952996 -231.827798) (xy 338.90541 -231.809751) (xy 338.861336 -231.784305)
			(xy 338.821914 -231.752118) (xy 338.788166 -231.714024) (xy 338.760965 -231.67101) (xy 338.741017 -231.62419)
			(xy 338.728838 -231.574776) (xy 338.724743 -231.524048) (xy 338.406486 -231.524048) (xy 338.405991 -231.548655)
			(xy 338.398096 -231.597232) (xy 338.382512 -231.643913) (xy 338.359641 -231.68749) (xy 338.330076 -231.726834)
			(xy 338.294583 -231.760926) (xy 338.25408 -231.788882) (xy 338.209618 -231.80998) (xy 338.162347 -231.823672)
			(xy 338.113492 -231.829604) (xy 338.064317 -231.827623) (xy 338.016098 -231.817779) (xy 337.970082 -231.800327)
			(xy 337.927461 -231.77572) (xy 337.88934 -231.744595) (xy 337.856705 -231.707758) (xy 337.830402 -231.666162)
			(xy 337.811111 -231.620886) (xy 337.799334 -231.573102) (xy 337.795374 -231.524048) (xy 337.466432 -231.524048)
			(xy 337.465937 -231.548655) (xy 337.458042 -231.597232) (xy 337.442458 -231.643913) (xy 337.419587 -231.68749)
			(xy 337.390022 -231.726834) (xy 337.354529 -231.760926) (xy 337.314026 -231.788882) (xy 337.269564 -231.80998)
			(xy 337.222293 -231.823672) (xy 337.173438 -231.829604) (xy 337.124263 -231.827623) (xy 337.076044 -231.817779)
			(xy 337.030028 -231.800327) (xy 336.987407 -231.77572) (xy 336.949286 -231.744595) (xy 336.916651 -231.707758)
			(xy 336.890348 -231.666162) (xy 336.871057 -231.620886) (xy 336.85928 -231.573102) (xy 336.85532 -231.524048)
			(xy 336.526378 -231.524048) (xy 336.525883 -231.548655) (xy 336.517988 -231.597232) (xy 336.502404 -231.643913)
			(xy 336.479533 -231.68749) (xy 336.449968 -231.726834) (xy 336.414475 -231.760926) (xy 336.373972 -231.788882)
			(xy 336.32951 -231.80998) (xy 336.282239 -231.823672) (xy 336.233384 -231.829604) (xy 336.184209 -231.827623)
			(xy 336.13599 -231.817779) (xy 336.089974 -231.800327) (xy 336.047353 -231.77572) (xy 336.009232 -231.744595)
			(xy 335.976597 -231.707758) (xy 335.950294 -231.666162) (xy 335.931003 -231.620886) (xy 335.919226 -231.573102)
			(xy 335.915266 -231.524048) (xy 335.586324 -231.524048) (xy 335.585829 -231.548655) (xy 335.577934 -231.597232)
			(xy 335.56235 -231.643913) (xy 335.539479 -231.68749) (xy 335.509914 -231.726834) (xy 335.474421 -231.760926)
			(xy 335.433918 -231.788882) (xy 335.389456 -231.80998) (xy 335.342185 -231.823672) (xy 335.29333 -231.829604)
			(xy 335.244155 -231.827623) (xy 335.195936 -231.817779) (xy 335.14992 -231.800327) (xy 335.107299 -231.77572)
			(xy 335.069178 -231.744595) (xy 335.036543 -231.707758) (xy 335.01024 -231.666162) (xy 334.990949 -231.620886)
			(xy 334.979172 -231.573102) (xy 334.975212 -231.524048) (xy 334.646524 -231.524048) (xy 334.64605 -231.548037)
			(xy 334.638538 -231.595424) (xy 334.623706 -231.641053) (xy 334.601921 -231.6838) (xy 334.573717 -231.722613)
			(xy 334.539789 -231.756537) (xy 334.500973 -231.784737) (xy 334.458223 -231.806519) (xy 334.412593 -231.821345)
			(xy 334.365205 -231.828852) (xy 334.341216 -231.829356) (xy 334.309466 -231.827578) (xy 334.306672 -231.827324)
			(xy 334.304132 -231.827324) (xy 334.294108 -231.827739) (xy 334.275585 -231.835404) (xy 334.261408 -231.849578)
			(xy 334.25374 -231.8681) (xy 334.253332 -231.878124) (xy 334.253332 -231.898444) (xy 334.254094 -231.907334)
			(xy 334.255364 -231.914192) (xy 334.256962 -231.921807) (xy 334.264071 -231.935639) (xy 334.269334 -231.94137)
			(xy 334.269588 -231.941624) (xy 334.274922 -231.947212) (xy 334.298194 -231.97224) (xy 334.339102 -232.026987)
			(xy 334.373014 -232.086323) (xy 334.386682 -232.117646) (xy 334.389222 -232.123742) (xy 334.396842 -232.133902)
			(xy 334.421226 -232.152952) (xy 334.426701 -232.156912) (xy 334.439189 -232.162058) (xy 334.445864 -232.163112)
			(xy 334.516984 -232.172764) (xy 334.522959 -232.173382) (xy 334.5349 -232.172103) (xy 334.540606 -232.170224)
			(xy 334.551782 -232.166414) (xy 334.56499 -232.153206) (xy 334.567022 -232.150412) (xy 334.581565 -232.131857)
			(xy 334.615394 -232.099022) (xy 334.653858 -232.071764) (xy 334.696047 -232.050728) (xy 334.740964 -232.036411)
			(xy 334.787545 -232.029153) (xy 334.811116 -232.028746) (xy 334.836374 -232.029268) (xy 334.886202 -232.037586)
			(xy 334.93398 -232.05399) (xy 334.978408 -232.078035) (xy 335.018271 -232.109064) (xy 335.052484 -232.146231)
			(xy 335.080114 -232.188523) (xy 335.100405 -232.234785) (xy 335.112806 -232.283756) (xy 335.116974 -232.334054)
			(xy 335.445366 -232.334054) (xy 335.449326 -232.285) (xy 335.461103 -232.237216) (xy 335.480394 -232.19194)
			(xy 335.506697 -232.150344) (xy 335.539332 -232.113507) (xy 335.577453 -232.082382) (xy 335.620074 -232.057775)
			(xy 335.66609 -232.040323) (xy 335.714309 -232.030479) (xy 335.763484 -232.028498) (xy 335.812339 -232.03443)
			(xy 335.85961 -232.048122) (xy 335.904072 -232.06922) (xy 335.944575 -232.097176) (xy 335.980068 -232.131268)
			(xy 336.009633 -232.170612) (xy 336.032504 -232.214189) (xy 336.048088 -232.26087) (xy 336.055983 -232.309447)
			(xy 336.056478 -232.334054) (xy 336.38542 -232.334054) (xy 336.38938 -232.285) (xy 336.401157 -232.237216)
			(xy 336.420448 -232.19194) (xy 336.446751 -232.150344) (xy 336.479386 -232.113507) (xy 336.517507 -232.082382)
			(xy 336.560128 -232.057775) (xy 336.606144 -232.040323) (xy 336.654363 -232.030479) (xy 336.703538 -232.028498)
			(xy 336.752393 -232.03443) (xy 336.799664 -232.048122) (xy 336.844126 -232.06922) (xy 336.884629 -232.097176)
			(xy 336.920122 -232.131268) (xy 336.949687 -232.170612) (xy 336.972558 -232.214189) (xy 336.988142 -232.26087)
			(xy 336.996037 -232.309447) (xy 336.996532 -232.334054) (xy 337.32522 -232.334054) (xy 337.32918 -232.285)
			(xy 337.340957 -232.237216) (xy 337.360248 -232.19194) (xy 337.386551 -232.150344) (xy 337.419186 -232.113507)
			(xy 337.457307 -232.082382) (xy 337.499928 -232.057775) (xy 337.545944 -232.040323) (xy 337.594163 -232.030479)
			(xy 337.643338 -232.028498) (xy 337.692193 -232.03443) (xy 337.739464 -232.048122) (xy 337.783926 -232.06922)
			(xy 337.824429 -232.097176) (xy 337.859922 -232.131268) (xy 337.889487 -232.170612) (xy 337.912358 -232.214189)
			(xy 337.927942 -232.26087) (xy 337.935837 -232.309447) (xy 337.936332 -232.334054) (xy 338.254843 -232.334054)
			(xy 338.258938 -232.283326) (xy 338.271117 -232.233912) (xy 338.291065 -232.187092) (xy 338.318266 -232.144078)
			(xy 338.352014 -232.105984) (xy 338.391436 -232.073797) (xy 338.43551 -232.048351) (xy 338.483096 -232.030304)
			(xy 338.53296 -232.020124) (xy 338.583812 -232.018075) (xy 338.634333 -232.024209) (xy 338.683217 -232.038369)
			(xy 338.729196 -232.060186) (xy 338.77108 -232.089096) (xy 338.807784 -232.124351) (xy 338.838357 -232.165037)
			(xy 338.862008 -232.2101) (xy 338.878124 -232.258374) (xy 338.886288 -232.308608) (xy 338.8868 -232.334054)
			(xy 339.205328 -232.334054) (xy 339.209288 -232.285) (xy 339.221065 -232.237216) (xy 339.240356 -232.19194)
			(xy 339.266659 -232.150344) (xy 339.299294 -232.113507) (xy 339.337415 -232.082382) (xy 339.380036 -232.057775)
			(xy 339.426052 -232.040323) (xy 339.474271 -232.030479) (xy 339.523446 -232.028498) (xy 339.572301 -232.03443)
			(xy 339.619572 -232.048122) (xy 339.664034 -232.06922) (xy 339.704537 -232.097176) (xy 339.74003 -232.131268)
			(xy 339.769595 -232.170612) (xy 339.792466 -232.214189) (xy 339.80805 -232.26087) (xy 339.815945 -232.309447)
			(xy 339.81644 -232.334054) (xy 340.134951 -232.334054) (xy 340.139046 -232.283326) (xy 340.151225 -232.233912)
			(xy 340.171173 -232.187092) (xy 340.198374 -232.144078) (xy 340.232122 -232.105984) (xy 340.271544 -232.073797)
			(xy 340.315618 -232.048351) (xy 340.363204 -232.030304) (xy 340.413068 -232.020124) (xy 340.46392 -232.018075)
			(xy 340.514441 -232.024209) (xy 340.563325 -232.038369) (xy 340.609304 -232.060186) (xy 340.651188 -232.089096)
			(xy 340.687892 -232.124351) (xy 340.718465 -232.165037) (xy 340.742116 -232.2101) (xy 340.758232 -232.258374)
			(xy 340.766396 -232.308608) (xy 340.766908 -232.334054) (xy 341.085182 -232.334054) (xy 341.089142 -232.285)
			(xy 341.100919 -232.237216) (xy 341.12021 -232.19194) (xy 341.146513 -232.150344) (xy 341.179148 -232.113507)
			(xy 341.217269 -232.082382) (xy 341.25989 -232.057775) (xy 341.305906 -232.040323) (xy 341.354125 -232.030479)
			(xy 341.4033 -232.028498) (xy 341.452155 -232.03443) (xy 341.499426 -232.048122) (xy 341.543888 -232.06922)
			(xy 341.584391 -232.097176) (xy 341.619884 -232.131268) (xy 341.649449 -232.170612) (xy 341.67232 -232.214189)
			(xy 341.687904 -232.26087) (xy 341.695799 -232.309447) (xy 341.696294 -232.334054) (xy 342.014805 -232.334054)
			(xy 342.0189 -232.283326) (xy 342.031079 -232.233912) (xy 342.051027 -232.187092) (xy 342.078228 -232.144078)
			(xy 342.111976 -232.105984) (xy 342.151398 -232.073797) (xy 342.195472 -232.048351) (xy 342.243058 -232.030304)
			(xy 342.292922 -232.020124) (xy 342.343774 -232.018075) (xy 342.394295 -232.024209) (xy 342.443179 -232.038369)
			(xy 342.489158 -232.060186) (xy 342.531042 -232.089096) (xy 342.567746 -232.124351) (xy 342.598319 -232.165037)
			(xy 342.62197 -232.2101) (xy 342.638086 -232.258374) (xy 342.64625 -232.308608) (xy 342.646762 -232.334054)
			(xy 342.64625 -232.3595) (xy 342.638086 -232.409734) (xy 342.62197 -232.458008) (xy 342.598319 -232.503071)
			(xy 342.567746 -232.543757) (xy 342.531042 -232.579012) (xy 342.489158 -232.607922) (xy 342.443179 -232.629739)
			(xy 342.394295 -232.643899) (xy 342.343774 -232.650033) (xy 342.292922 -232.647984) (xy 342.243058 -232.637804)
			(xy 342.195472 -232.619757) (xy 342.151398 -232.594311) (xy 342.111976 -232.562124) (xy 342.078228 -232.52403)
			(xy 342.051027 -232.481016) (xy 342.031079 -232.434196) (xy 342.0189 -232.384782) (xy 342.014805 -232.334054)
			(xy 341.696294 -232.334054) (xy 341.695799 -232.358661) (xy 341.687904 -232.407238) (xy 341.67232 -232.453919)
			(xy 341.649449 -232.497496) (xy 341.619884 -232.53684) (xy 341.584391 -232.570932) (xy 341.543888 -232.598888)
			(xy 341.499426 -232.619986) (xy 341.452155 -232.633678) (xy 341.4033 -232.63961) (xy 341.354125 -232.637629)
			(xy 341.305906 -232.627785) (xy 341.25989 -232.610333) (xy 341.217269 -232.585726) (xy 341.179148 -232.554601)
			(xy 341.146513 -232.517764) (xy 341.12021 -232.476168) (xy 341.100919 -232.430892) (xy 341.089142 -232.383108)
			(xy 341.085182 -232.334054) (xy 340.766908 -232.334054) (xy 340.766396 -232.3595) (xy 340.758232 -232.409734)
			(xy 340.742116 -232.458008) (xy 340.718465 -232.503071) (xy 340.687892 -232.543757) (xy 340.651188 -232.579012)
			(xy 340.609304 -232.607922) (xy 340.563325 -232.629739) (xy 340.514441 -232.643899) (xy 340.46392 -232.650033)
			(xy 340.413068 -232.647984) (xy 340.363204 -232.637804) (xy 340.315618 -232.619757) (xy 340.271544 -232.594311)
			(xy 340.232122 -232.562124) (xy 340.198374 -232.52403) (xy 340.171173 -232.481016) (xy 340.151225 -232.434196)
			(xy 340.139046 -232.384782) (xy 340.134951 -232.334054) (xy 339.81644 -232.334054) (xy 339.815945 -232.358661)
			(xy 339.80805 -232.407238) (xy 339.792466 -232.453919) (xy 339.769595 -232.497496) (xy 339.74003 -232.53684)
			(xy 339.704537 -232.570932) (xy 339.664034 -232.598888) (xy 339.619572 -232.619986) (xy 339.572301 -232.633678)
			(xy 339.523446 -232.63961) (xy 339.474271 -232.637629) (xy 339.426052 -232.627785) (xy 339.380036 -232.610333)
			(xy 339.337415 -232.585726) (xy 339.299294 -232.554601) (xy 339.266659 -232.517764) (xy 339.240356 -232.476168)
			(xy 339.221065 -232.430892) (xy 339.209288 -232.383108) (xy 339.205328 -232.334054) (xy 338.8868 -232.334054)
			(xy 338.886288 -232.3595) (xy 338.878124 -232.409734) (xy 338.862008 -232.458008) (xy 338.838357 -232.503071)
			(xy 338.807784 -232.543757) (xy 338.77108 -232.579012) (xy 338.729196 -232.607922) (xy 338.683217 -232.629739)
			(xy 338.634333 -232.643899) (xy 338.583812 -232.650033) (xy 338.53296 -232.647984) (xy 338.483096 -232.637804)
			(xy 338.43551 -232.619757) (xy 338.391436 -232.594311) (xy 338.352014 -232.562124) (xy 338.318266 -232.52403)
			(xy 338.291065 -232.481016) (xy 338.271117 -232.434196) (xy 338.258938 -232.384782) (xy 338.254843 -232.334054)
			(xy 337.936332 -232.334054) (xy 337.935837 -232.358661) (xy 337.927942 -232.407238) (xy 337.912358 -232.453919)
			(xy 337.889487 -232.497496) (xy 337.859922 -232.53684) (xy 337.824429 -232.570932) (xy 337.783926 -232.598888)
			(xy 337.739464 -232.619986) (xy 337.692193 -232.633678) (xy 337.643338 -232.63961) (xy 337.594163 -232.637629)
			(xy 337.545944 -232.627785) (xy 337.499928 -232.610333) (xy 337.457307 -232.585726) (xy 337.419186 -232.554601)
			(xy 337.386551 -232.517764) (xy 337.360248 -232.476168) (xy 337.340957 -232.430892) (xy 337.32918 -232.383108)
			(xy 337.32522 -232.334054) (xy 336.996532 -232.334054) (xy 336.996037 -232.358661) (xy 336.988142 -232.407238)
			(xy 336.972558 -232.453919) (xy 336.949687 -232.497496) (xy 336.920122 -232.53684) (xy 336.884629 -232.570932)
			(xy 336.844126 -232.598888) (xy 336.799664 -232.619986) (xy 336.752393 -232.633678) (xy 336.703538 -232.63961)
			(xy 336.654363 -232.637629) (xy 336.606144 -232.627785) (xy 336.560128 -232.610333) (xy 336.517507 -232.585726)
			(xy 336.479386 -232.554601) (xy 336.446751 -232.517764) (xy 336.420448 -232.476168) (xy 336.401157 -232.430892)
			(xy 336.38938 -232.383108) (xy 336.38542 -232.334054) (xy 336.056478 -232.334054) (xy 336.055983 -232.358661)
			(xy 336.048088 -232.407238) (xy 336.032504 -232.453919) (xy 336.009633 -232.497496) (xy 335.980068 -232.53684)
			(xy 335.944575 -232.570932) (xy 335.904072 -232.598888) (xy 335.85961 -232.619986) (xy 335.812339 -232.633678)
			(xy 335.763484 -232.63961) (xy 335.714309 -232.637629) (xy 335.66609 -232.627785) (xy 335.620074 -232.610333)
			(xy 335.577453 -232.585726) (xy 335.539332 -232.554601) (xy 335.506697 -232.517764) (xy 335.480394 -232.476168)
			(xy 335.461103 -232.430892) (xy 335.449326 -232.383108) (xy 335.445366 -232.334054) (xy 335.116974 -232.334054)
			(xy 335.116978 -232.3341) (xy 335.112806 -232.384444) (xy 335.100405 -232.433415) (xy 335.080114 -232.479677)
			(xy 335.052484 -232.521969) (xy 335.018271 -232.559136) (xy 334.978408 -232.590165) (xy 334.93398 -232.61421)
			(xy 334.886202 -232.630614) (xy 334.836374 -232.638932) (xy 334.811116 -232.639362) (xy 334.787545 -232.638927)
			(xy 334.740963 -232.631689) (xy 334.696044 -232.617383) (xy 334.653856 -232.596348) (xy 334.615399 -232.569083)
			(xy 334.581585 -232.536236) (xy 334.567022 -232.517696) (xy 334.56499 -232.514902) (xy 334.55991 -232.509822)
			(xy 334.553344 -232.503701) (xy 334.537073 -232.496153) (xy 334.52816 -232.49509) (xy 334.522572 -232.494582)
			(xy 334.432148 -232.506774) (xy 334.423227 -232.508317) (xy 334.407227 -232.516763) (xy 334.395153 -232.530237)
			(xy 334.391508 -232.538524) (xy 334.383587 -232.558231) (xy 334.365153 -232.596501) (xy 334.354678 -232.614978)
			(xy 334.312768 -232.687114) (xy 334.311498 -232.688892) (xy 334.303878 -232.700322) (xy 334.3021 -232.7275)
			(xy 334.338676 -232.801922) (xy 334.341552 -232.807255) (xy 334.349381 -232.816498) (xy 334.35417 -232.82021)
			(xy 334.382618 -232.841292) (xy 334.394302 -232.843324) (xy 334.417561 -232.84788) (xy 334.462402 -232.863226)
			(xy 334.504332 -232.885319) (xy 334.542343 -232.913628) (xy 334.575521 -232.947472) (xy 334.603069 -232.986037)
			(xy 334.624324 -233.028398) (xy 334.638776 -233.073534) (xy 334.646078 -233.120363) (xy 334.646524 -233.14406)
			(xy 334.975212 -233.14406) (xy 334.979172 -233.095006) (xy 334.990949 -233.047222) (xy 335.01024 -233.001946)
			(xy 335.036543 -232.96035) (xy 335.069178 -232.923513) (xy 335.107299 -232.892388) (xy 335.14992 -232.867781)
			(xy 335.195936 -232.850329) (xy 335.244155 -232.840485) (xy 335.29333 -232.838504) (xy 335.342185 -232.844436)
			(xy 335.389456 -232.858128) (xy 335.433918 -232.879226) (xy 335.474421 -232.907182) (xy 335.509914 -232.941274)
			(xy 335.539479 -232.980618) (xy 335.56235 -233.024195) (xy 335.577934 -233.070876) (xy 335.585829 -233.119453)
			(xy 335.586324 -233.14406) (xy 335.915266 -233.14406) (xy 335.919226 -233.095006) (xy 335.931003 -233.047222)
			(xy 335.950294 -233.001946) (xy 335.976597 -232.96035) (xy 336.009232 -232.923513) (xy 336.047353 -232.892388)
			(xy 336.089974 -232.867781) (xy 336.13599 -232.850329) (xy 336.184209 -232.840485) (xy 336.233384 -232.838504)
			(xy 336.282239 -232.844436) (xy 336.32951 -232.858128) (xy 336.373972 -232.879226) (xy 336.414475 -232.907182)
			(xy 336.449968 -232.941274) (xy 336.479533 -232.980618) (xy 336.502404 -233.024195) (xy 336.517988 -233.070876)
			(xy 336.525883 -233.119453) (xy 336.526378 -233.14406) (xy 336.85532 -233.14406) (xy 336.85928 -233.095006)
			(xy 336.871057 -233.047222) (xy 336.890348 -233.001946) (xy 336.916651 -232.96035) (xy 336.949286 -232.923513)
			(xy 336.987407 -232.892388) (xy 337.030028 -232.867781) (xy 337.076044 -232.850329) (xy 337.124263 -232.840485)
			(xy 337.173438 -232.838504) (xy 337.222293 -232.844436) (xy 337.269564 -232.858128) (xy 337.314026 -232.879226)
			(xy 337.354529 -232.907182) (xy 337.390022 -232.941274) (xy 337.419587 -232.980618) (xy 337.442458 -233.024195)
			(xy 337.458042 -233.070876) (xy 337.465937 -233.119453) (xy 337.466432 -233.14406) (xy 337.795374 -233.14406)
			(xy 337.799334 -233.095006) (xy 337.811111 -233.047222) (xy 337.830402 -233.001946) (xy 337.856705 -232.96035)
			(xy 337.88934 -232.923513) (xy 337.927461 -232.892388) (xy 337.970082 -232.867781) (xy 338.016098 -232.850329)
			(xy 338.064317 -232.840485) (xy 338.113492 -232.838504) (xy 338.162347 -232.844436) (xy 338.209618 -232.858128)
			(xy 338.25408 -232.879226) (xy 338.294583 -232.907182) (xy 338.330076 -232.941274) (xy 338.359641 -232.980618)
			(xy 338.382512 -233.024195) (xy 338.398096 -233.070876) (xy 338.405991 -233.119453) (xy 338.406486 -233.14406)
			(xy 338.724743 -233.14406) (xy 338.728838 -233.093332) (xy 338.741017 -233.043918) (xy 338.760965 -232.997098)
			(xy 338.788166 -232.954084) (xy 338.821914 -232.91599) (xy 338.861336 -232.883803) (xy 338.90541 -232.858357)
			(xy 338.952996 -232.84031) (xy 339.00286 -232.83013) (xy 339.053712 -232.828081) (xy 339.104233 -232.834215)
			(xy 339.153117 -232.848375) (xy 339.199096 -232.870192) (xy 339.24098 -232.899102) (xy 339.277684 -232.934357)
			(xy 339.308257 -232.975043) (xy 339.331908 -233.020106) (xy 339.348024 -233.06838) (xy 339.356188 -233.118614)
			(xy 339.3567 -233.14406) (xy 339.664797 -233.14406) (xy 339.668892 -233.093332) (xy 339.681071 -233.043918)
			(xy 339.701019 -232.997098) (xy 339.72822 -232.954084) (xy 339.761968 -232.91599) (xy 339.80139 -232.883803)
			(xy 339.845464 -232.858357) (xy 339.89305 -232.84031) (xy 339.942914 -232.83013) (xy 339.993766 -232.828081)
			(xy 340.044287 -232.834215) (xy 340.093171 -232.848375) (xy 340.13915 -232.870192) (xy 340.181034 -232.899102)
			(xy 340.217738 -232.934357) (xy 340.248311 -232.975043) (xy 340.271962 -233.020106) (xy 340.288078 -233.06838)
			(xy 340.296242 -233.118614) (xy 340.296754 -233.14406) (xy 340.615282 -233.14406) (xy 340.619242 -233.095006)
			(xy 340.631019 -233.047222) (xy 340.65031 -233.001946) (xy 340.676613 -232.96035) (xy 340.709248 -232.923513)
			(xy 340.747369 -232.892388) (xy 340.78999 -232.867781) (xy 340.836006 -232.850329) (xy 340.884225 -232.840485)
			(xy 340.9334 -232.838504) (xy 340.982255 -232.844436) (xy 341.029526 -232.858128) (xy 341.073988 -232.879226)
			(xy 341.114491 -232.907182) (xy 341.149984 -232.941274) (xy 341.179549 -232.980618) (xy 341.20242 -233.024195)
			(xy 341.218004 -233.070876) (xy 341.225899 -233.119453) (xy 341.226394 -233.14406) (xy 341.544905 -233.14406)
			(xy 341.549 -233.093332) (xy 341.561179 -233.043918) (xy 341.581127 -232.997098) (xy 341.608328 -232.954084)
			(xy 341.642076 -232.91599) (xy 341.681498 -232.883803) (xy 341.725572 -232.858357) (xy 341.773158 -232.84031)
			(xy 341.823022 -232.83013) (xy 341.873874 -232.828081) (xy 341.924395 -232.834215) (xy 341.973279 -232.848375)
			(xy 342.019258 -232.870192) (xy 342.061142 -232.899102) (xy 342.097846 -232.934357) (xy 342.128419 -232.975043)
			(xy 342.15207 -233.020106) (xy 342.168186 -233.06838) (xy 342.17635 -233.118614) (xy 342.176862 -233.14406)
			(xy 342.49539 -233.14406) (xy 342.49935 -233.095006) (xy 342.511127 -233.047222) (xy 342.530418 -233.001946)
			(xy 342.556721 -232.96035) (xy 342.589356 -232.923513) (xy 342.627477 -232.892388) (xy 342.670098 -232.867781)
			(xy 342.716114 -232.850329) (xy 342.764333 -232.840485) (xy 342.813508 -232.838504) (xy 342.862363 -232.844436)
			(xy 342.909634 -232.858128) (xy 342.954096 -232.879226) (xy 342.994599 -232.907182) (xy 343.030092 -232.941274)
			(xy 343.059657 -232.980618) (xy 343.082528 -233.024195) (xy 343.098112 -233.070876) (xy 343.106007 -233.119453)
			(xy 343.106502 -233.14406) (xy 343.106007 -233.168667) (xy 343.098112 -233.217244) (xy 343.082528 -233.263925)
			(xy 343.059657 -233.307502) (xy 343.030092 -233.346846) (xy 342.994599 -233.380938) (xy 342.954096 -233.408894)
			(xy 342.909634 -233.429992) (xy 342.862363 -233.443684) (xy 342.813508 -233.449616) (xy 342.764333 -233.447635)
			(xy 342.716114 -233.437791) (xy 342.670098 -233.420339) (xy 342.627477 -233.395732) (xy 342.589356 -233.364607)
			(xy 342.556721 -233.32777) (xy 342.530418 -233.286174) (xy 342.511127 -233.240898) (xy 342.49935 -233.193114)
			(xy 342.49539 -233.14406) (xy 342.176862 -233.14406) (xy 342.17635 -233.169506) (xy 342.168186 -233.21974)
			(xy 342.15207 -233.268014) (xy 342.128419 -233.313077) (xy 342.097846 -233.353763) (xy 342.061142 -233.389018)
			(xy 342.019258 -233.417928) (xy 341.973279 -233.439745) (xy 341.924395 -233.453905) (xy 341.873874 -233.460039)
			(xy 341.823022 -233.45799) (xy 341.773158 -233.44781) (xy 341.725572 -233.429763) (xy 341.681498 -233.404317)
			(xy 341.642076 -233.37213) (xy 341.608328 -233.334036) (xy 341.581127 -233.291022) (xy 341.561179 -233.244202)
			(xy 341.549 -233.194788) (xy 341.544905 -233.14406) (xy 341.226394 -233.14406) (xy 341.225899 -233.168667)
			(xy 341.218004 -233.217244) (xy 341.20242 -233.263925) (xy 341.179549 -233.307502) (xy 341.149984 -233.346846)
			(xy 341.114491 -233.380938) (xy 341.073988 -233.408894) (xy 341.029526 -233.429992) (xy 340.982255 -233.443684)
			(xy 340.9334 -233.449616) (xy 340.884225 -233.447635) (xy 340.836006 -233.437791) (xy 340.78999 -233.420339)
			(xy 340.747369 -233.395732) (xy 340.709248 -233.364607) (xy 340.676613 -233.32777) (xy 340.65031 -233.286174)
			(xy 340.631019 -233.240898) (xy 340.619242 -233.193114) (xy 340.615282 -233.14406) (xy 340.296754 -233.14406)
			(xy 340.296242 -233.169506) (xy 340.288078 -233.21974) (xy 340.271962 -233.268014) (xy 340.248311 -233.313077)
			(xy 340.217738 -233.353763) (xy 340.181034 -233.389018) (xy 340.13915 -233.417928) (xy 340.093171 -233.439745)
			(xy 340.044287 -233.453905) (xy 339.993766 -233.460039) (xy 339.942914 -233.45799) (xy 339.89305 -233.44781)
			(xy 339.845464 -233.429763) (xy 339.80139 -233.404317) (xy 339.761968 -233.37213) (xy 339.72822 -233.334036)
			(xy 339.701019 -233.291022) (xy 339.681071 -233.244202) (xy 339.668892 -233.194788) (xy 339.664797 -233.14406)
			(xy 339.3567 -233.14406) (xy 339.356188 -233.169506) (xy 339.348024 -233.21974) (xy 339.331908 -233.268014)
			(xy 339.308257 -233.313077) (xy 339.277684 -233.353763) (xy 339.24098 -233.389018) (xy 339.199096 -233.417928)
			(xy 339.153117 -233.439745) (xy 339.104233 -233.453905) (xy 339.053712 -233.460039) (xy 339.00286 -233.45799)
			(xy 338.952996 -233.44781) (xy 338.90541 -233.429763) (xy 338.861336 -233.404317) (xy 338.821914 -233.37213)
			(xy 338.788166 -233.334036) (xy 338.760965 -233.291022) (xy 338.741017 -233.244202) (xy 338.728838 -233.194788)
			(xy 338.724743 -233.14406) (xy 338.406486 -233.14406) (xy 338.405991 -233.168667) (xy 338.398096 -233.217244)
			(xy 338.382512 -233.263925) (xy 338.359641 -233.307502) (xy 338.330076 -233.346846) (xy 338.294583 -233.380938)
			(xy 338.25408 -233.408894) (xy 338.209618 -233.429992) (xy 338.162347 -233.443684) (xy 338.113492 -233.449616)
			(xy 338.064317 -233.447635) (xy 338.016098 -233.437791) (xy 337.970082 -233.420339) (xy 337.927461 -233.395732)
			(xy 337.88934 -233.364607) (xy 337.856705 -233.32777) (xy 337.830402 -233.286174) (xy 337.811111 -233.240898)
			(xy 337.799334 -233.193114) (xy 337.795374 -233.14406) (xy 337.466432 -233.14406) (xy 337.465937 -233.168667)
			(xy 337.458042 -233.217244) (xy 337.442458 -233.263925) (xy 337.419587 -233.307502) (xy 337.390022 -233.346846)
			(xy 337.354529 -233.380938) (xy 337.314026 -233.408894) (xy 337.269564 -233.429992) (xy 337.222293 -233.443684)
			(xy 337.173438 -233.449616) (xy 337.124263 -233.447635) (xy 337.076044 -233.437791) (xy 337.030028 -233.420339)
			(xy 336.987407 -233.395732) (xy 336.949286 -233.364607) (xy 336.916651 -233.32777) (xy 336.890348 -233.286174)
			(xy 336.871057 -233.240898) (xy 336.85928 -233.193114) (xy 336.85532 -233.14406) (xy 336.526378 -233.14406)
			(xy 336.525883 -233.168667) (xy 336.517988 -233.217244) (xy 336.502404 -233.263925) (xy 336.479533 -233.307502)
			(xy 336.449968 -233.346846) (xy 336.414475 -233.380938) (xy 336.373972 -233.408894) (xy 336.32951 -233.429992)
			(xy 336.282239 -233.443684) (xy 336.233384 -233.449616) (xy 336.184209 -233.447635) (xy 336.13599 -233.437791)
			(xy 336.089974 -233.420339) (xy 336.047353 -233.395732) (xy 336.009232 -233.364607) (xy 335.976597 -233.32777)
			(xy 335.950294 -233.286174) (xy 335.931003 -233.240898) (xy 335.919226 -233.193114) (xy 335.915266 -233.14406)
			(xy 335.586324 -233.14406) (xy 335.585829 -233.168667) (xy 335.577934 -233.217244) (xy 335.56235 -233.263925)
			(xy 335.539479 -233.307502) (xy 335.509914 -233.346846) (xy 335.474421 -233.380938) (xy 335.433918 -233.408894)
			(xy 335.389456 -233.429992) (xy 335.342185 -233.443684) (xy 335.29333 -233.449616) (xy 335.244155 -233.447635)
			(xy 335.195936 -233.437791) (xy 335.14992 -233.420339) (xy 335.107299 -233.395732) (xy 335.069178 -233.364607)
			(xy 335.036543 -233.32777) (xy 335.01024 -233.286174) (xy 334.990949 -233.240898) (xy 334.979172 -233.193114)
			(xy 334.975212 -233.14406) (xy 334.646524 -233.14406) (xy 334.646081 -233.168056) (xy 334.638579 -233.215457)
			(xy 334.623754 -233.261101) (xy 334.601971 -233.303864) (xy 334.573767 -233.342692) (xy 334.539835 -233.37663)
			(xy 334.501012 -233.404842) (xy 334.458253 -233.426633) (xy 334.412611 -233.441466) (xy 334.365212 -233.448976)
			(xy 334.341216 -233.449368) (xy 334.309466 -233.44759) (xy 334.306672 -233.447336) (xy 334.304132 -233.447336)
			(xy 334.294109 -233.447751) (xy 334.275587 -233.455416) (xy 334.261414 -233.469591) (xy 334.25375 -233.488113)
			(xy 334.253332 -233.498136) (xy 334.253332 -233.518456) (xy 334.254094 -233.527346) (xy 334.255364 -233.534204)
			(xy 334.256964 -233.541818) (xy 334.264075 -233.555648) (xy 334.269334 -233.561382) (xy 334.269588 -233.561636)
			(xy 334.274922 -233.567224) (xy 334.298193 -233.592252) (xy 334.3391 -233.647) (xy 334.373012 -233.706336)
			(xy 334.386682 -233.737658) (xy 334.389222 -233.743754) (xy 334.396842 -233.753914) (xy 334.421226 -233.772964)
			(xy 334.426701 -233.776923) (xy 334.43919 -233.782068) (xy 334.445864 -233.783124) (xy 334.516984 -233.792776)
			(xy 334.522959 -233.793394) (xy 334.5349 -233.792115) (xy 334.540606 -233.790236) (xy 334.551782 -233.786426)
			(xy 334.56499 -233.773218) (xy 334.567022 -233.770424) (xy 334.581568 -233.751873) (xy 334.6154 -233.719047)
			(xy 334.653866 -233.691797) (xy 334.696054 -233.670768) (xy 334.740969 -233.656455) (xy 334.787546 -233.649199)
			(xy 334.811116 -233.648758) (xy 334.836373 -233.649281) (xy 334.886199 -233.657598) (xy 334.933975 -233.674002)
			(xy 334.978401 -233.698046) (xy 335.018263 -233.729074) (xy 335.052475 -233.766239) (xy 335.080103 -233.808529)
			(xy 335.100393 -233.854789) (xy 335.112794 -233.903758) (xy 335.116962 -233.954066) (xy 335.445366 -233.954066)
			(xy 335.449326 -233.905012) (xy 335.461103 -233.857228) (xy 335.480394 -233.811952) (xy 335.506697 -233.770356)
			(xy 335.539332 -233.733519) (xy 335.577453 -233.702394) (xy 335.620074 -233.677787) (xy 335.66609 -233.660335)
			(xy 335.714309 -233.650491) (xy 335.763484 -233.64851) (xy 335.812339 -233.654442) (xy 335.85961 -233.668134)
			(xy 335.904072 -233.689232) (xy 335.944575 -233.717188) (xy 335.980068 -233.75128) (xy 336.009633 -233.790624)
			(xy 336.032504 -233.834201) (xy 336.048088 -233.880882) (xy 336.055983 -233.929459) (xy 336.056478 -233.954066)
			(xy 336.38542 -233.954066) (xy 336.38938 -233.905012) (xy 336.401157 -233.857228) (xy 336.420448 -233.811952)
			(xy 336.446751 -233.770356) (xy 336.479386 -233.733519) (xy 336.517507 -233.702394) (xy 336.560128 -233.677787)
			(xy 336.606144 -233.660335) (xy 336.654363 -233.650491) (xy 336.703538 -233.64851) (xy 336.752393 -233.654442)
			(xy 336.799664 -233.668134) (xy 336.844126 -233.689232) (xy 336.884629 -233.717188) (xy 336.920122 -233.75128)
			(xy 336.949687 -233.790624) (xy 336.972558 -233.834201) (xy 336.988142 -233.880882) (xy 336.996037 -233.929459)
			(xy 336.996532 -233.954066) (xy 337.32522 -233.954066) (xy 337.32918 -233.905012) (xy 337.340957 -233.857228)
			(xy 337.360248 -233.811952) (xy 337.386551 -233.770356) (xy 337.419186 -233.733519) (xy 337.457307 -233.702394)
			(xy 337.499928 -233.677787) (xy 337.545944 -233.660335) (xy 337.594163 -233.650491) (xy 337.643338 -233.64851)
			(xy 337.692193 -233.654442) (xy 337.739464 -233.668134) (xy 337.783926 -233.689232) (xy 337.824429 -233.717188)
			(xy 337.859922 -233.75128) (xy 337.889487 -233.790624) (xy 337.912358 -233.834201) (xy 337.927942 -233.880882)
			(xy 337.935837 -233.929459) (xy 337.936332 -233.954066) (xy 338.254843 -233.954066) (xy 338.258938 -233.903338)
			(xy 338.271117 -233.853924) (xy 338.291065 -233.807104) (xy 338.318266 -233.76409) (xy 338.352014 -233.725996)
			(xy 338.391436 -233.693809) (xy 338.43551 -233.668363) (xy 338.483096 -233.650316) (xy 338.53296 -233.640136)
			(xy 338.583812 -233.638087) (xy 338.634333 -233.644221) (xy 338.683217 -233.658381) (xy 338.729196 -233.680198)
			(xy 338.77108 -233.709108) (xy 338.807784 -233.744363) (xy 338.838357 -233.785049) (xy 338.862008 -233.830112)
			(xy 338.878124 -233.878386) (xy 338.886288 -233.92862) (xy 338.8868 -233.954066) (xy 339.205328 -233.954066)
			(xy 339.209288 -233.905012) (xy 339.221065 -233.857228) (xy 339.240356 -233.811952) (xy 339.266659 -233.770356)
			(xy 339.299294 -233.733519) (xy 339.337415 -233.702394) (xy 339.380036 -233.677787) (xy 339.426052 -233.660335)
			(xy 339.474271 -233.650491) (xy 339.523446 -233.64851) (xy 339.572301 -233.654442) (xy 339.619572 -233.668134)
			(xy 339.664034 -233.689232) (xy 339.704537 -233.717188) (xy 339.74003 -233.75128) (xy 339.769595 -233.790624)
			(xy 339.792466 -233.834201) (xy 339.80805 -233.880882) (xy 339.815945 -233.929459) (xy 339.81644 -233.954066)
			(xy 340.134951 -233.954066) (xy 340.139046 -233.903338) (xy 340.151225 -233.853924) (xy 340.171173 -233.807104)
			(xy 340.198374 -233.76409) (xy 340.232122 -233.725996) (xy 340.271544 -233.693809) (xy 340.315618 -233.668363)
			(xy 340.363204 -233.650316) (xy 340.413068 -233.640136) (xy 340.46392 -233.638087) (xy 340.514441 -233.644221)
			(xy 340.563325 -233.658381) (xy 340.609304 -233.680198) (xy 340.651188 -233.709108) (xy 340.687892 -233.744363)
			(xy 340.718465 -233.785049) (xy 340.742116 -233.830112) (xy 340.758232 -233.878386) (xy 340.766396 -233.92862)
			(xy 340.766908 -233.954066) (xy 341.085182 -233.954066) (xy 341.089142 -233.905012) (xy 341.100919 -233.857228)
			(xy 341.12021 -233.811952) (xy 341.146513 -233.770356) (xy 341.179148 -233.733519) (xy 341.217269 -233.702394)
			(xy 341.25989 -233.677787) (xy 341.305906 -233.660335) (xy 341.354125 -233.650491) (xy 341.4033 -233.64851)
			(xy 341.452155 -233.654442) (xy 341.499426 -233.668134) (xy 341.543888 -233.689232) (xy 341.584391 -233.717188)
			(xy 341.619884 -233.75128) (xy 341.649449 -233.790624) (xy 341.67232 -233.834201) (xy 341.687904 -233.880882)
			(xy 341.695799 -233.929459) (xy 341.696294 -233.954066) (xy 342.014805 -233.954066) (xy 342.0189 -233.903338)
			(xy 342.031079 -233.853924) (xy 342.051027 -233.807104) (xy 342.078228 -233.76409) (xy 342.111976 -233.725996)
			(xy 342.151398 -233.693809) (xy 342.195472 -233.668363) (xy 342.243058 -233.650316) (xy 342.292922 -233.640136)
			(xy 342.343774 -233.638087) (xy 342.394295 -233.644221) (xy 342.443179 -233.658381) (xy 342.489158 -233.680198)
			(xy 342.531042 -233.709108) (xy 342.567746 -233.744363) (xy 342.598319 -233.785049) (xy 342.62197 -233.830112)
			(xy 342.638086 -233.878386) (xy 342.64625 -233.92862) (xy 342.646762 -233.954066) (xy 342.64625 -233.979512)
			(xy 342.638086 -234.029746) (xy 342.62197 -234.07802) (xy 342.598319 -234.123083) (xy 342.567746 -234.163769)
			(xy 342.531042 -234.199024) (xy 342.489158 -234.227934) (xy 342.443179 -234.249751) (xy 342.394295 -234.263911)
			(xy 342.343774 -234.270045) (xy 342.292922 -234.267996) (xy 342.243058 -234.257816) (xy 342.195472 -234.239769)
			(xy 342.151398 -234.214323) (xy 342.111976 -234.182136) (xy 342.078228 -234.144042) (xy 342.051027 -234.101028)
			(xy 342.031079 -234.054208) (xy 342.0189 -234.004794) (xy 342.014805 -233.954066) (xy 341.696294 -233.954066)
			(xy 341.695799 -233.978673) (xy 341.687904 -234.02725) (xy 341.67232 -234.073931) (xy 341.649449 -234.117508)
			(xy 341.619884 -234.156852) (xy 341.584391 -234.190944) (xy 341.543888 -234.2189) (xy 341.499426 -234.239998)
			(xy 341.452155 -234.25369) (xy 341.4033 -234.259622) (xy 341.354125 -234.257641) (xy 341.305906 -234.247797)
			(xy 341.25989 -234.230345) (xy 341.217269 -234.205738) (xy 341.179148 -234.174613) (xy 341.146513 -234.137776)
			(xy 341.12021 -234.09618) (xy 341.100919 -234.050904) (xy 341.089142 -234.00312) (xy 341.085182 -233.954066)
			(xy 340.766908 -233.954066) (xy 340.766396 -233.979512) (xy 340.758232 -234.029746) (xy 340.742116 -234.07802)
			(xy 340.718465 -234.123083) (xy 340.687892 -234.163769) (xy 340.651188 -234.199024) (xy 340.609304 -234.227934)
			(xy 340.563325 -234.249751) (xy 340.514441 -234.263911) (xy 340.46392 -234.270045) (xy 340.413068 -234.267996)
			(xy 340.363204 -234.257816) (xy 340.315618 -234.239769) (xy 340.271544 -234.214323) (xy 340.232122 -234.182136)
			(xy 340.198374 -234.144042) (xy 340.171173 -234.101028) (xy 340.151225 -234.054208) (xy 340.139046 -234.004794)
			(xy 340.134951 -233.954066) (xy 339.81644 -233.954066) (xy 339.815945 -233.978673) (xy 339.80805 -234.02725)
			(xy 339.792466 -234.073931) (xy 339.769595 -234.117508) (xy 339.74003 -234.156852) (xy 339.704537 -234.190944)
			(xy 339.664034 -234.2189) (xy 339.619572 -234.239998) (xy 339.572301 -234.25369) (xy 339.523446 -234.259622)
			(xy 339.474271 -234.257641) (xy 339.426052 -234.247797) (xy 339.380036 -234.230345) (xy 339.337415 -234.205738)
			(xy 339.299294 -234.174613) (xy 339.266659 -234.137776) (xy 339.240356 -234.09618) (xy 339.221065 -234.050904)
			(xy 339.209288 -234.00312) (xy 339.205328 -233.954066) (xy 338.8868 -233.954066) (xy 338.886288 -233.979512)
			(xy 338.878124 -234.029746) (xy 338.862008 -234.07802) (xy 338.838357 -234.123083) (xy 338.807784 -234.163769)
			(xy 338.77108 -234.199024) (xy 338.729196 -234.227934) (xy 338.683217 -234.249751) (xy 338.634333 -234.263911)
			(xy 338.583812 -234.270045) (xy 338.53296 -234.267996) (xy 338.483096 -234.257816) (xy 338.43551 -234.239769)
			(xy 338.391436 -234.214323) (xy 338.352014 -234.182136) (xy 338.318266 -234.144042) (xy 338.291065 -234.101028)
			(xy 338.271117 -234.054208) (xy 338.258938 -234.004794) (xy 338.254843 -233.954066) (xy 337.936332 -233.954066)
			(xy 337.935837 -233.978673) (xy 337.927942 -234.02725) (xy 337.912358 -234.073931) (xy 337.889487 -234.117508)
			(xy 337.859922 -234.156852) (xy 337.824429 -234.190944) (xy 337.783926 -234.2189) (xy 337.739464 -234.239998)
			(xy 337.692193 -234.25369) (xy 337.643338 -234.259622) (xy 337.594163 -234.257641) (xy 337.545944 -234.247797)
			(xy 337.499928 -234.230345) (xy 337.457307 -234.205738) (xy 337.419186 -234.174613) (xy 337.386551 -234.137776)
			(xy 337.360248 -234.09618) (xy 337.340957 -234.050904) (xy 337.32918 -234.00312) (xy 337.32522 -233.954066)
			(xy 336.996532 -233.954066) (xy 336.996037 -233.978673) (xy 336.988142 -234.02725) (xy 336.972558 -234.073931)
			(xy 336.949687 -234.117508) (xy 336.920122 -234.156852) (xy 336.884629 -234.190944) (xy 336.844126 -234.2189)
			(xy 336.799664 -234.239998) (xy 336.752393 -234.25369) (xy 336.703538 -234.259622) (xy 336.654363 -234.257641)
			(xy 336.606144 -234.247797) (xy 336.560128 -234.230345) (xy 336.517507 -234.205738) (xy 336.479386 -234.174613)
			(xy 336.446751 -234.137776) (xy 336.420448 -234.09618) (xy 336.401157 -234.050904) (xy 336.38938 -234.00312)
			(xy 336.38542 -233.954066) (xy 336.056478 -233.954066) (xy 336.055983 -233.978673) (xy 336.048088 -234.02725)
			(xy 336.032504 -234.073931) (xy 336.009633 -234.117508) (xy 335.980068 -234.156852) (xy 335.944575 -234.190944)
			(xy 335.904072 -234.2189) (xy 335.85961 -234.239998) (xy 335.812339 -234.25369) (xy 335.763484 -234.259622)
			(xy 335.714309 -234.257641) (xy 335.66609 -234.247797) (xy 335.620074 -234.230345) (xy 335.577453 -234.205738)
			(xy 335.539332 -234.174613) (xy 335.506697 -234.137776) (xy 335.480394 -234.09618) (xy 335.461103 -234.050904)
			(xy 335.449326 -234.00312) (xy 335.445366 -233.954066) (xy 335.116962 -233.954066) (xy 335.116965 -233.9541)
			(xy 335.112794 -234.004442) (xy 335.100393 -234.053411) (xy 335.080103 -234.099671) (xy 335.052475 -234.141961)
			(xy 335.018263 -234.179126) (xy 334.978401 -234.210154) (xy 334.933975 -234.234198) (xy 334.886199 -234.250602)
			(xy 334.836373 -234.258919) (xy 334.811116 -234.259374) (xy 334.787545 -234.258939) (xy 334.740962 -234.251701)
			(xy 334.696043 -234.237396) (xy 334.653855 -234.216361) (xy 334.615397 -234.189097) (xy 334.581582 -234.15625)
			(xy 334.567022 -234.137708) (xy 334.56499 -234.134914) (xy 334.55991 -234.129834) (xy 334.553345 -234.123712)
			(xy 334.537074 -234.116162) (xy 334.52816 -234.115102) (xy 334.522572 -234.114594) (xy 334.432148 -234.126786)
			(xy 334.423228 -234.12833) (xy 334.407229 -234.136776) (xy 334.395158 -234.150252) (xy 334.391508 -234.158536)
			(xy 334.383586 -234.178243) (xy 334.365152 -234.216512) (xy 334.354678 -234.23499) (xy 334.312768 -234.307126)
			(xy 334.311498 -234.308904) (xy 334.303878 -234.320334) (xy 334.3021 -234.347512) (xy 334.338676 -234.421934)
			(xy 334.341553 -234.427266) (xy 334.349383 -234.436508) (xy 334.35417 -234.440222) (xy 334.382618 -234.461304)
			(xy 334.394302 -234.463336) (xy 334.417561 -234.467892) (xy 334.462401 -234.483239) (xy 334.50433 -234.505332)
			(xy 334.542339 -234.53364) (xy 334.575516 -234.567485) (xy 334.603063 -234.60605) (xy 334.624317 -234.648411)
			(xy 334.638767 -234.693547) (xy 334.646067 -234.740375) (xy 334.646524 -234.764072) (xy 334.975212 -234.764072)
			(xy 334.979172 -234.715018) (xy 334.990949 -234.667234) (xy 335.01024 -234.621958) (xy 335.036543 -234.580362)
			(xy 335.069178 -234.543525) (xy 335.107299 -234.5124) (xy 335.14992 -234.487793) (xy 335.195936 -234.470341)
			(xy 335.244155 -234.460497) (xy 335.29333 -234.458516) (xy 335.342185 -234.464448) (xy 335.389456 -234.47814)
			(xy 335.433918 -234.499238) (xy 335.474421 -234.527194) (xy 335.509914 -234.561286) (xy 335.539479 -234.60063)
			(xy 335.56235 -234.644207) (xy 335.577934 -234.690888) (xy 335.585829 -234.739465) (xy 335.586324 -234.764072)
			(xy 335.915266 -234.764072) (xy 335.919226 -234.715018) (xy 335.931003 -234.667234) (xy 335.950294 -234.621958)
			(xy 335.976597 -234.580362) (xy 336.009232 -234.543525) (xy 336.047353 -234.5124) (xy 336.089974 -234.487793)
			(xy 336.13599 -234.470341) (xy 336.184209 -234.460497) (xy 336.233384 -234.458516) (xy 336.282239 -234.464448)
			(xy 336.32951 -234.47814) (xy 336.373972 -234.499238) (xy 336.414475 -234.527194) (xy 336.449968 -234.561286)
			(xy 336.479533 -234.60063) (xy 336.502404 -234.644207) (xy 336.517988 -234.690888) (xy 336.525883 -234.739465)
			(xy 336.526378 -234.764072) (xy 336.85532 -234.764072) (xy 336.85928 -234.715018) (xy 336.871057 -234.667234)
			(xy 336.890348 -234.621958) (xy 336.916651 -234.580362) (xy 336.949286 -234.543525) (xy 336.987407 -234.5124)
			(xy 337.030028 -234.487793) (xy 337.076044 -234.470341) (xy 337.124263 -234.460497) (xy 337.173438 -234.458516)
			(xy 337.222293 -234.464448) (xy 337.269564 -234.47814) (xy 337.314026 -234.499238) (xy 337.354529 -234.527194)
			(xy 337.390022 -234.561286) (xy 337.419587 -234.60063) (xy 337.442458 -234.644207) (xy 337.458042 -234.690888)
			(xy 337.465937 -234.739465) (xy 337.466432 -234.764072) (xy 337.795374 -234.764072) (xy 337.799334 -234.715018)
			(xy 337.811111 -234.667234) (xy 337.830402 -234.621958) (xy 337.856705 -234.580362) (xy 337.88934 -234.543525)
			(xy 337.927461 -234.5124) (xy 337.970082 -234.487793) (xy 338.016098 -234.470341) (xy 338.064317 -234.460497)
			(xy 338.113492 -234.458516) (xy 338.162347 -234.464448) (xy 338.209618 -234.47814) (xy 338.25408 -234.499238)
			(xy 338.294583 -234.527194) (xy 338.330076 -234.561286) (xy 338.359641 -234.60063) (xy 338.382512 -234.644207)
			(xy 338.398096 -234.690888) (xy 338.405991 -234.739465) (xy 338.406486 -234.764072) (xy 338.724743 -234.764072)
			(xy 338.728838 -234.713344) (xy 338.741017 -234.66393) (xy 338.760965 -234.61711) (xy 338.788166 -234.574096)
			(xy 338.821914 -234.536002) (xy 338.861336 -234.503815) (xy 338.90541 -234.478369) (xy 338.952996 -234.460322)
			(xy 339.00286 -234.450142) (xy 339.053712 -234.448093) (xy 339.104233 -234.454227) (xy 339.153117 -234.468387)
			(xy 339.199096 -234.490204) (xy 339.24098 -234.519114) (xy 339.277684 -234.554369) (xy 339.308257 -234.595055)
			(xy 339.331908 -234.640118) (xy 339.348024 -234.688392) (xy 339.356188 -234.738626) (xy 339.3567 -234.764072)
			(xy 339.664797 -234.764072) (xy 339.668892 -234.713344) (xy 339.681071 -234.66393) (xy 339.701019 -234.61711)
			(xy 339.72822 -234.574096) (xy 339.761968 -234.536002) (xy 339.80139 -234.503815) (xy 339.845464 -234.478369)
			(xy 339.89305 -234.460322) (xy 339.942914 -234.450142) (xy 339.993766 -234.448093) (xy 340.044287 -234.454227)
			(xy 340.093171 -234.468387) (xy 340.13915 -234.490204) (xy 340.181034 -234.519114) (xy 340.217738 -234.554369)
			(xy 340.248311 -234.595055) (xy 340.271962 -234.640118) (xy 340.288078 -234.688392) (xy 340.296242 -234.738626)
			(xy 340.296754 -234.764072) (xy 340.615282 -234.764072) (xy 340.619242 -234.715018) (xy 340.631019 -234.667234)
			(xy 340.65031 -234.621958) (xy 340.676613 -234.580362) (xy 340.709248 -234.543525) (xy 340.747369 -234.5124)
			(xy 340.78999 -234.487793) (xy 340.836006 -234.470341) (xy 340.884225 -234.460497) (xy 340.9334 -234.458516)
			(xy 340.982255 -234.464448) (xy 341.029526 -234.47814) (xy 341.073988 -234.499238) (xy 341.114491 -234.527194)
			(xy 341.149984 -234.561286) (xy 341.179549 -234.60063) (xy 341.20242 -234.644207) (xy 341.218004 -234.690888)
			(xy 341.225899 -234.739465) (xy 341.226394 -234.764072) (xy 341.544905 -234.764072) (xy 341.549 -234.713344)
			(xy 341.561179 -234.66393) (xy 341.581127 -234.61711) (xy 341.608328 -234.574096) (xy 341.642076 -234.536002)
			(xy 341.681498 -234.503815) (xy 341.725572 -234.478369) (xy 341.773158 -234.460322) (xy 341.823022 -234.450142)
			(xy 341.873874 -234.448093) (xy 341.924395 -234.454227) (xy 341.973279 -234.468387) (xy 342.019258 -234.490204)
			(xy 342.061142 -234.519114) (xy 342.097846 -234.554369) (xy 342.128419 -234.595055) (xy 342.15207 -234.640118)
			(xy 342.168186 -234.688392) (xy 342.17635 -234.738626) (xy 342.176862 -234.764072) (xy 342.49539 -234.764072)
			(xy 342.49935 -234.715018) (xy 342.511127 -234.667234) (xy 342.530418 -234.621958) (xy 342.556721 -234.580362)
			(xy 342.589356 -234.543525) (xy 342.627477 -234.5124) (xy 342.670098 -234.487793) (xy 342.716114 -234.470341)
			(xy 342.764333 -234.460497) (xy 342.813508 -234.458516) (xy 342.862363 -234.464448) (xy 342.909634 -234.47814)
			(xy 342.954096 -234.499238) (xy 342.994599 -234.527194) (xy 343.030092 -234.561286) (xy 343.059657 -234.60063)
			(xy 343.082528 -234.644207) (xy 343.098112 -234.690888) (xy 343.106007 -234.739465) (xy 343.106502 -234.764072)
			(xy 343.106007 -234.788679) (xy 343.098112 -234.837256) (xy 343.082528 -234.883937) (xy 343.059657 -234.927514)
			(xy 343.030092 -234.966858) (xy 342.994599 -235.00095) (xy 342.954096 -235.028906) (xy 342.909634 -235.050004)
			(xy 342.862363 -235.063696) (xy 342.813508 -235.069628) (xy 342.764333 -235.067647) (xy 342.716114 -235.057803)
			(xy 342.670098 -235.040351) (xy 342.627477 -235.015744) (xy 342.589356 -234.984619) (xy 342.556721 -234.947782)
			(xy 342.530418 -234.906186) (xy 342.511127 -234.86091) (xy 342.49935 -234.813126) (xy 342.49539 -234.764072)
			(xy 342.176862 -234.764072) (xy 342.17635 -234.789518) (xy 342.168186 -234.839752) (xy 342.15207 -234.888026)
			(xy 342.128419 -234.933089) (xy 342.097846 -234.973775) (xy 342.061142 -235.00903) (xy 342.019258 -235.03794)
			(xy 341.973279 -235.059757) (xy 341.924395 -235.073917) (xy 341.873874 -235.080051) (xy 341.823022 -235.078002)
			(xy 341.773158 -235.067822) (xy 341.725572 -235.049775) (xy 341.681498 -235.024329) (xy 341.642076 -234.992142)
			(xy 341.608328 -234.954048) (xy 341.581127 -234.911034) (xy 341.561179 -234.864214) (xy 341.549 -234.8148)
			(xy 341.544905 -234.764072) (xy 341.226394 -234.764072) (xy 341.225899 -234.788679) (xy 341.218004 -234.837256)
			(xy 341.20242 -234.883937) (xy 341.179549 -234.927514) (xy 341.149984 -234.966858) (xy 341.114491 -235.00095)
			(xy 341.073988 -235.028906) (xy 341.029526 -235.050004) (xy 340.982255 -235.063696) (xy 340.9334 -235.069628)
			(xy 340.884225 -235.067647) (xy 340.836006 -235.057803) (xy 340.78999 -235.040351) (xy 340.747369 -235.015744)
			(xy 340.709248 -234.984619) (xy 340.676613 -234.947782) (xy 340.65031 -234.906186) (xy 340.631019 -234.86091)
			(xy 340.619242 -234.813126) (xy 340.615282 -234.764072) (xy 340.296754 -234.764072) (xy 340.296242 -234.789518)
			(xy 340.288078 -234.839752) (xy 340.271962 -234.888026) (xy 340.248311 -234.933089) (xy 340.217738 -234.973775)
			(xy 340.181034 -235.00903) (xy 340.13915 -235.03794) (xy 340.093171 -235.059757) (xy 340.044287 -235.073917)
			(xy 339.993766 -235.080051) (xy 339.942914 -235.078002) (xy 339.89305 -235.067822) (xy 339.845464 -235.049775)
			(xy 339.80139 -235.024329) (xy 339.761968 -234.992142) (xy 339.72822 -234.954048) (xy 339.701019 -234.911034)
			(xy 339.681071 -234.864214) (xy 339.668892 -234.8148) (xy 339.664797 -234.764072) (xy 339.3567 -234.764072)
			(xy 339.356188 -234.789518) (xy 339.348024 -234.839752) (xy 339.331908 -234.888026) (xy 339.308257 -234.933089)
			(xy 339.277684 -234.973775) (xy 339.24098 -235.00903) (xy 339.199096 -235.03794) (xy 339.153117 -235.059757)
			(xy 339.104233 -235.073917) (xy 339.053712 -235.080051) (xy 339.00286 -235.078002) (xy 338.952996 -235.067822)
			(xy 338.90541 -235.049775) (xy 338.861336 -235.024329) (xy 338.821914 -234.992142) (xy 338.788166 -234.954048)
			(xy 338.760965 -234.911034) (xy 338.741017 -234.864214) (xy 338.728838 -234.8148) (xy 338.724743 -234.764072)
			(xy 338.406486 -234.764072) (xy 338.405991 -234.788679) (xy 338.398096 -234.837256) (xy 338.382512 -234.883937)
			(xy 338.359641 -234.927514) (xy 338.330076 -234.966858) (xy 338.294583 -235.00095) (xy 338.25408 -235.028906)
			(xy 338.209618 -235.050004) (xy 338.162347 -235.063696) (xy 338.113492 -235.069628) (xy 338.064317 -235.067647)
			(xy 338.016098 -235.057803) (xy 337.970082 -235.040351) (xy 337.927461 -235.015744) (xy 337.88934 -234.984619)
			(xy 337.856705 -234.947782) (xy 337.830402 -234.906186) (xy 337.811111 -234.86091) (xy 337.799334 -234.813126)
			(xy 337.795374 -234.764072) (xy 337.466432 -234.764072) (xy 337.465937 -234.788679) (xy 337.458042 -234.837256)
			(xy 337.442458 -234.883937) (xy 337.419587 -234.927514) (xy 337.390022 -234.966858) (xy 337.354529 -235.00095)
			(xy 337.314026 -235.028906) (xy 337.269564 -235.050004) (xy 337.222293 -235.063696) (xy 337.173438 -235.069628)
			(xy 337.124263 -235.067647) (xy 337.076044 -235.057803) (xy 337.030028 -235.040351) (xy 336.987407 -235.015744)
			(xy 336.949286 -234.984619) (xy 336.916651 -234.947782) (xy 336.890348 -234.906186) (xy 336.871057 -234.86091)
			(xy 336.85928 -234.813126) (xy 336.85532 -234.764072) (xy 336.526378 -234.764072) (xy 336.525883 -234.788679)
			(xy 336.517988 -234.837256) (xy 336.502404 -234.883937) (xy 336.479533 -234.927514) (xy 336.449968 -234.966858)
			(xy 336.414475 -235.00095) (xy 336.373972 -235.028906) (xy 336.32951 -235.050004) (xy 336.282239 -235.063696)
			(xy 336.233384 -235.069628) (xy 336.184209 -235.067647) (xy 336.13599 -235.057803) (xy 336.089974 -235.040351)
			(xy 336.047353 -235.015744) (xy 336.009232 -234.984619) (xy 335.976597 -234.947782) (xy 335.950294 -234.906186)
			(xy 335.931003 -234.86091) (xy 335.919226 -234.813126) (xy 335.915266 -234.764072) (xy 335.586324 -234.764072)
			(xy 335.585829 -234.788679) (xy 335.577934 -234.837256) (xy 335.56235 -234.883937) (xy 335.539479 -234.927514)
			(xy 335.509914 -234.966858) (xy 335.474421 -235.00095) (xy 335.433918 -235.028906) (xy 335.389456 -235.050004)
			(xy 335.342185 -235.063696) (xy 335.29333 -235.069628) (xy 335.244155 -235.067647) (xy 335.195936 -235.057803)
			(xy 335.14992 -235.040351) (xy 335.107299 -235.015744) (xy 335.069178 -234.984619) (xy 335.036543 -234.947782)
			(xy 335.01024 -234.906186) (xy 334.990949 -234.86091) (xy 334.979172 -234.813126) (xy 334.975212 -234.764072)
			(xy 334.646524 -234.764072) (xy 334.64608 -234.788067) (xy 334.638577 -234.835467) (xy 334.623751 -234.881109)
			(xy 334.601967 -234.92387) (xy 334.573762 -234.962697) (xy 334.539831 -234.996634) (xy 334.501008 -235.024844)
			(xy 334.45825 -235.046634) (xy 334.41261 -235.061466) (xy 334.365211 -235.068976) (xy 334.341216 -235.06938)
			(xy 334.309466 -235.067602) (xy 334.306672 -235.067348) (xy 334.304132 -235.067348) (xy 334.29411 -235.067763)
			(xy 334.27559 -235.075429) (xy 334.26142 -235.089604) (xy 334.25376 -235.108126) (xy 334.253332 -235.118148)
			(xy 334.253332 -235.138468) (xy 334.254094 -235.147358) (xy 334.255364 -235.154216) (xy 334.256966 -235.161829)
			(xy 334.264079 -235.175657) (xy 334.269334 -235.181394) (xy 334.269588 -235.181648) (xy 334.274922 -235.187236)
			(xy 334.298193 -235.212264) (xy 334.339099 -235.267013) (xy 334.373009 -235.326349) (xy 334.386682 -235.35767)
			(xy 334.389222 -235.363766) (xy 334.396842 -235.373926) (xy 334.421226 -235.392976) (xy 334.426702 -235.396935)
			(xy 334.43919 -235.402078) (xy 334.445864 -235.403136) (xy 334.516984 -235.412788) (xy 334.522959 -235.413406)
			(xy 334.534901 -235.412127) (xy 334.540606 -235.410248) (xy 334.551782 -235.406438) (xy 334.56499 -235.39323)
			(xy 334.567022 -235.390436) (xy 334.581568 -235.371885) (xy 334.615399 -235.339058) (xy 334.653864 -235.311806)
			(xy 334.696053 -235.290776) (xy 334.740968 -235.276463) (xy 334.787546 -235.269207) (xy 334.811116 -235.26877)
			(xy 334.836372 -235.269293) (xy 334.886196 -235.277609) (xy 334.933971 -235.294013) (xy 334.978394 -235.318056)
			(xy 335.018255 -235.349082) (xy 335.052465 -235.386247) (xy 335.080092 -235.428535) (xy 335.100382 -235.474793)
			(xy 335.112782 -235.52376) (xy 335.116951 -235.574078) (xy 335.445366 -235.574078) (xy 335.449326 -235.525024)
			(xy 335.461103 -235.47724) (xy 335.480394 -235.431964) (xy 335.506697 -235.390368) (xy 335.539332 -235.353531)
			(xy 335.577453 -235.322406) (xy 335.620074 -235.297799) (xy 335.66609 -235.280347) (xy 335.714309 -235.270503)
			(xy 335.763484 -235.268522) (xy 335.812339 -235.274454) (xy 335.85961 -235.288146) (xy 335.904072 -235.309244)
			(xy 335.944575 -235.3372) (xy 335.980068 -235.371292) (xy 336.009633 -235.410636) (xy 336.032504 -235.454213)
			(xy 336.048088 -235.500894) (xy 336.055983 -235.549471) (xy 336.056478 -235.574078) (xy 336.38542 -235.574078)
			(xy 336.38938 -235.525024) (xy 336.401157 -235.47724) (xy 336.420448 -235.431964) (xy 336.446751 -235.390368)
			(xy 336.479386 -235.353531) (xy 336.517507 -235.322406) (xy 336.560128 -235.297799) (xy 336.606144 -235.280347)
			(xy 336.654363 -235.270503) (xy 336.703538 -235.268522) (xy 336.752393 -235.274454) (xy 336.799664 -235.288146)
			(xy 336.844126 -235.309244) (xy 336.884629 -235.3372) (xy 336.920122 -235.371292) (xy 336.949687 -235.410636)
			(xy 336.972558 -235.454213) (xy 336.988142 -235.500894) (xy 336.996037 -235.549471) (xy 336.996532 -235.574078)
			(xy 337.32522 -235.574078) (xy 337.32918 -235.525024) (xy 337.340957 -235.47724) (xy 337.360248 -235.431964)
			(xy 337.386551 -235.390368) (xy 337.419186 -235.353531) (xy 337.457307 -235.322406) (xy 337.499928 -235.297799)
			(xy 337.545944 -235.280347) (xy 337.594163 -235.270503) (xy 337.643338 -235.268522) (xy 337.692193 -235.274454)
			(xy 337.739464 -235.288146) (xy 337.783926 -235.309244) (xy 337.824429 -235.3372) (xy 337.859922 -235.371292)
			(xy 337.889487 -235.410636) (xy 337.912358 -235.454213) (xy 337.927942 -235.500894) (xy 337.935837 -235.549471)
			(xy 337.936332 -235.574078) (xy 338.254843 -235.574078) (xy 338.258938 -235.52335) (xy 338.271117 -235.473936)
			(xy 338.291065 -235.427116) (xy 338.318266 -235.384102) (xy 338.352014 -235.346008) (xy 338.391436 -235.313821)
			(xy 338.43551 -235.288375) (xy 338.483096 -235.270328) (xy 338.53296 -235.260148) (xy 338.583812 -235.258099)
			(xy 338.634333 -235.264233) (xy 338.683217 -235.278393) (xy 338.729196 -235.30021) (xy 338.77108 -235.32912)
			(xy 338.807784 -235.364375) (xy 338.838357 -235.405061) (xy 338.862008 -235.450124) (xy 338.878124 -235.498398)
			(xy 338.886288 -235.548632) (xy 338.8868 -235.574078) (xy 339.205328 -235.574078) (xy 339.209288 -235.525024)
			(xy 339.221065 -235.47724) (xy 339.240356 -235.431964) (xy 339.266659 -235.390368) (xy 339.299294 -235.353531)
			(xy 339.337415 -235.322406) (xy 339.380036 -235.297799) (xy 339.426052 -235.280347) (xy 339.474271 -235.270503)
			(xy 339.523446 -235.268522) (xy 339.572301 -235.274454) (xy 339.619572 -235.288146) (xy 339.664034 -235.309244)
			(xy 339.704537 -235.3372) (xy 339.74003 -235.371292) (xy 339.769595 -235.410636) (xy 339.792466 -235.454213)
			(xy 339.80805 -235.500894) (xy 339.815945 -235.549471) (xy 339.81644 -235.574078) (xy 340.134951 -235.574078)
			(xy 340.139046 -235.52335) (xy 340.151225 -235.473936) (xy 340.171173 -235.427116) (xy 340.198374 -235.384102)
			(xy 340.232122 -235.346008) (xy 340.271544 -235.313821) (xy 340.315618 -235.288375) (xy 340.363204 -235.270328)
			(xy 340.413068 -235.260148) (xy 340.46392 -235.258099) (xy 340.514441 -235.264233) (xy 340.563325 -235.278393)
			(xy 340.609304 -235.30021) (xy 340.651188 -235.32912) (xy 340.687892 -235.364375) (xy 340.718465 -235.405061)
			(xy 340.742116 -235.450124) (xy 340.758232 -235.498398) (xy 340.766396 -235.548632) (xy 340.766908 -235.574078)
			(xy 341.085182 -235.574078) (xy 341.089142 -235.525024) (xy 341.100919 -235.47724) (xy 341.12021 -235.431964)
			(xy 341.146513 -235.390368) (xy 341.179148 -235.353531) (xy 341.217269 -235.322406) (xy 341.25989 -235.297799)
			(xy 341.305906 -235.280347) (xy 341.354125 -235.270503) (xy 341.4033 -235.268522) (xy 341.452155 -235.274454)
			(xy 341.499426 -235.288146) (xy 341.543888 -235.309244) (xy 341.584391 -235.3372) (xy 341.619884 -235.371292)
			(xy 341.649449 -235.410636) (xy 341.67232 -235.454213) (xy 341.687904 -235.500894) (xy 341.695799 -235.549471)
			(xy 341.696294 -235.574078) (xy 342.014805 -235.574078) (xy 342.0189 -235.52335) (xy 342.031079 -235.473936)
			(xy 342.051027 -235.427116) (xy 342.078228 -235.384102) (xy 342.111976 -235.346008) (xy 342.151398 -235.313821)
			(xy 342.195472 -235.288375) (xy 342.243058 -235.270328) (xy 342.292922 -235.260148) (xy 342.343774 -235.258099)
			(xy 342.394295 -235.264233) (xy 342.443179 -235.278393) (xy 342.489158 -235.30021) (xy 342.531042 -235.32912)
			(xy 342.567746 -235.364375) (xy 342.598319 -235.405061) (xy 342.62197 -235.450124) (xy 342.638086 -235.498398)
			(xy 342.64625 -235.548632) (xy 342.646762 -235.574078) (xy 342.64625 -235.599524) (xy 342.638086 -235.649758)
			(xy 342.62197 -235.698032) (xy 342.598319 -235.743095) (xy 342.567746 -235.783781) (xy 342.531042 -235.819036)
			(xy 342.489158 -235.847946) (xy 342.443179 -235.869763) (xy 342.394295 -235.883923) (xy 342.343774 -235.890057)
			(xy 342.292922 -235.888008) (xy 342.243058 -235.877828) (xy 342.195472 -235.859781) (xy 342.151398 -235.834335)
			(xy 342.111976 -235.802148) (xy 342.078228 -235.764054) (xy 342.051027 -235.72104) (xy 342.031079 -235.67422)
			(xy 342.0189 -235.624806) (xy 342.014805 -235.574078) (xy 341.696294 -235.574078) (xy 341.695799 -235.598685)
			(xy 341.687904 -235.647262) (xy 341.67232 -235.693943) (xy 341.649449 -235.73752) (xy 341.619884 -235.776864)
			(xy 341.584391 -235.810956) (xy 341.543888 -235.838912) (xy 341.499426 -235.86001) (xy 341.452155 -235.873702)
			(xy 341.4033 -235.879634) (xy 341.354125 -235.877653) (xy 341.305906 -235.867809) (xy 341.25989 -235.850357)
			(xy 341.217269 -235.82575) (xy 341.179148 -235.794625) (xy 341.146513 -235.757788) (xy 341.12021 -235.716192)
			(xy 341.100919 -235.670916) (xy 341.089142 -235.623132) (xy 341.085182 -235.574078) (xy 340.766908 -235.574078)
			(xy 340.766396 -235.599524) (xy 340.758232 -235.649758) (xy 340.742116 -235.698032) (xy 340.718465 -235.743095)
			(xy 340.687892 -235.783781) (xy 340.651188 -235.819036) (xy 340.609304 -235.847946) (xy 340.563325 -235.869763)
			(xy 340.514441 -235.883923) (xy 340.46392 -235.890057) (xy 340.413068 -235.888008) (xy 340.363204 -235.877828)
			(xy 340.315618 -235.859781) (xy 340.271544 -235.834335) (xy 340.232122 -235.802148) (xy 340.198374 -235.764054)
			(xy 340.171173 -235.72104) (xy 340.151225 -235.67422) (xy 340.139046 -235.624806) (xy 340.134951 -235.574078)
			(xy 339.81644 -235.574078) (xy 339.815945 -235.598685) (xy 339.80805 -235.647262) (xy 339.792466 -235.693943)
			(xy 339.769595 -235.73752) (xy 339.74003 -235.776864) (xy 339.704537 -235.810956) (xy 339.664034 -235.838912)
			(xy 339.619572 -235.86001) (xy 339.572301 -235.873702) (xy 339.523446 -235.879634) (xy 339.474271 -235.877653)
			(xy 339.426052 -235.867809) (xy 339.380036 -235.850357) (xy 339.337415 -235.82575) (xy 339.299294 -235.794625)
			(xy 339.266659 -235.757788) (xy 339.240356 -235.716192) (xy 339.221065 -235.670916) (xy 339.209288 -235.623132)
			(xy 339.205328 -235.574078) (xy 338.8868 -235.574078) (xy 338.886288 -235.599524) (xy 338.878124 -235.649758)
			(xy 338.862008 -235.698032) (xy 338.838357 -235.743095) (xy 338.807784 -235.783781) (xy 338.77108 -235.819036)
			(xy 338.729196 -235.847946) (xy 338.683217 -235.869763) (xy 338.634333 -235.883923) (xy 338.583812 -235.890057)
			(xy 338.53296 -235.888008) (xy 338.483096 -235.877828) (xy 338.43551 -235.859781) (xy 338.391436 -235.834335)
			(xy 338.352014 -235.802148) (xy 338.318266 -235.764054) (xy 338.291065 -235.72104) (xy 338.271117 -235.67422)
			(xy 338.258938 -235.624806) (xy 338.254843 -235.574078) (xy 337.936332 -235.574078) (xy 337.935837 -235.598685)
			(xy 337.927942 -235.647262) (xy 337.912358 -235.693943) (xy 337.889487 -235.73752) (xy 337.859922 -235.776864)
			(xy 337.824429 -235.810956) (xy 337.783926 -235.838912) (xy 337.739464 -235.86001) (xy 337.692193 -235.873702)
			(xy 337.643338 -235.879634) (xy 337.594163 -235.877653) (xy 337.545944 -235.867809) (xy 337.499928 -235.850357)
			(xy 337.457307 -235.82575) (xy 337.419186 -235.794625) (xy 337.386551 -235.757788) (xy 337.360248 -235.716192)
			(xy 337.340957 -235.670916) (xy 337.32918 -235.623132) (xy 337.32522 -235.574078) (xy 336.996532 -235.574078)
			(xy 336.996037 -235.598685) (xy 336.988142 -235.647262) (xy 336.972558 -235.693943) (xy 336.949687 -235.73752)
			(xy 336.920122 -235.776864) (xy 336.884629 -235.810956) (xy 336.844126 -235.838912) (xy 336.799664 -235.86001)
			(xy 336.752393 -235.873702) (xy 336.703538 -235.879634) (xy 336.654363 -235.877653) (xy 336.606144 -235.867809)
			(xy 336.560128 -235.850357) (xy 336.517507 -235.82575) (xy 336.479386 -235.794625) (xy 336.446751 -235.757788)
			(xy 336.420448 -235.716192) (xy 336.401157 -235.670916) (xy 336.38938 -235.623132) (xy 336.38542 -235.574078)
			(xy 336.056478 -235.574078) (xy 336.055983 -235.598685) (xy 336.048088 -235.647262) (xy 336.032504 -235.693943)
			(xy 336.009633 -235.73752) (xy 335.980068 -235.776864) (xy 335.944575 -235.810956) (xy 335.904072 -235.838912)
			(xy 335.85961 -235.86001) (xy 335.812339 -235.873702) (xy 335.763484 -235.879634) (xy 335.714309 -235.877653)
			(xy 335.66609 -235.867809) (xy 335.620074 -235.850357) (xy 335.577453 -235.82575) (xy 335.539332 -235.794625)
			(xy 335.506697 -235.757788) (xy 335.480394 -235.716192) (xy 335.461103 -235.670916) (xy 335.449326 -235.623132)
			(xy 335.445366 -235.574078) (xy 335.116951 -235.574078) (xy 335.116953 -235.5741) (xy 335.112782 -235.62444)
			(xy 335.100382 -235.673407) (xy 335.080092 -235.719665) (xy 335.052465 -235.761953) (xy 335.018255 -235.799118)
			(xy 334.978394 -235.830144) (xy 334.933971 -235.854187) (xy 334.886196 -235.870591) (xy 334.836372 -235.878907)
			(xy 334.811116 -235.879386) (xy 334.787545 -235.878951) (xy 334.740962 -235.871713) (xy 334.696043 -235.857408)
			(xy 334.653853 -235.836374) (xy 334.615395 -235.809111) (xy 334.581579 -235.776265) (xy 334.567022 -235.75772)
			(xy 334.56499 -235.754926) (xy 334.55991 -235.749846) (xy 334.553346 -235.743723) (xy 334.537074 -235.736171)
			(xy 334.52816 -235.735114) (xy 334.522572 -235.734606) (xy 334.432148 -235.746798) (xy 334.423228 -235.748342)
			(xy 334.407231 -235.75679) (xy 334.395163 -235.770266) (xy 334.391508 -235.778548) (xy 334.383586 -235.798255)
			(xy 334.365151 -235.836524) (xy 334.354678 -235.855002) (xy 334.312768 -235.927138) (xy 334.311498 -235.928916)
			(xy 334.303878 -235.940346) (xy 334.3021 -235.967524) (xy 334.338676 -236.041946) (xy 334.341554 -236.047277)
			(xy 334.349385 -236.056517) (xy 334.35417 -236.060234) (xy 334.382618 -236.081316) (xy 334.394302 -236.083348)
			(xy 334.41756 -236.087904) (xy 334.4624 -236.103251) (xy 334.504327 -236.125344) (xy 334.542336 -236.153653)
			(xy 334.575512 -236.187498) (xy 334.603057 -236.226063) (xy 334.624309 -236.268424) (xy 334.638758 -236.31356)
			(xy 334.646056 -236.360387) (xy 334.646524 -236.384084) (xy 334.975212 -236.384084) (xy 334.979172 -236.33503)
			(xy 334.990949 -236.287246) (xy 335.01024 -236.24197) (xy 335.036543 -236.200374) (xy 335.069178 -236.163537)
			(xy 335.107299 -236.132412) (xy 335.14992 -236.107805) (xy 335.195936 -236.090353) (xy 335.244155 -236.080509)
			(xy 335.29333 -236.078528) (xy 335.342185 -236.08446) (xy 335.389456 -236.098152) (xy 335.433918 -236.11925)
			(xy 335.474421 -236.147206) (xy 335.509914 -236.181298) (xy 335.539479 -236.220642) (xy 335.56235 -236.264219)
			(xy 335.577934 -236.3109) (xy 335.585829 -236.359477) (xy 335.586324 -236.384084) (xy 335.915266 -236.384084)
			(xy 335.919226 -236.33503) (xy 335.931003 -236.287246) (xy 335.950294 -236.24197) (xy 335.976597 -236.200374)
			(xy 336.009232 -236.163537) (xy 336.047353 -236.132412) (xy 336.089974 -236.107805) (xy 336.13599 -236.090353)
			(xy 336.184209 -236.080509) (xy 336.233384 -236.078528) (xy 336.282239 -236.08446) (xy 336.32951 -236.098152)
			(xy 336.373972 -236.11925) (xy 336.414475 -236.147206) (xy 336.449968 -236.181298) (xy 336.479533 -236.220642)
			(xy 336.502404 -236.264219) (xy 336.517988 -236.3109) (xy 336.525883 -236.359477) (xy 336.526378 -236.384084)
			(xy 336.85532 -236.384084) (xy 336.85928 -236.33503) (xy 336.871057 -236.287246) (xy 336.890348 -236.24197)
			(xy 336.916651 -236.200374) (xy 336.949286 -236.163537) (xy 336.987407 -236.132412) (xy 337.030028 -236.107805)
			(xy 337.076044 -236.090353) (xy 337.124263 -236.080509) (xy 337.173438 -236.078528) (xy 337.222293 -236.08446)
			(xy 337.269564 -236.098152) (xy 337.314026 -236.11925) (xy 337.354529 -236.147206) (xy 337.390022 -236.181298)
			(xy 337.419587 -236.220642) (xy 337.442458 -236.264219) (xy 337.458042 -236.3109) (xy 337.465937 -236.359477)
			(xy 337.466432 -236.384084) (xy 337.795374 -236.384084) (xy 337.799334 -236.33503) (xy 337.811111 -236.287246)
			(xy 337.830402 -236.24197) (xy 337.856705 -236.200374) (xy 337.88934 -236.163537) (xy 337.927461 -236.132412)
			(xy 337.970082 -236.107805) (xy 338.016098 -236.090353) (xy 338.064317 -236.080509) (xy 338.113492 -236.078528)
			(xy 338.162347 -236.08446) (xy 338.209618 -236.098152) (xy 338.25408 -236.11925) (xy 338.294583 -236.147206)
			(xy 338.330076 -236.181298) (xy 338.359641 -236.220642) (xy 338.382512 -236.264219) (xy 338.398096 -236.3109)
			(xy 338.405991 -236.359477) (xy 338.406486 -236.384084) (xy 338.724743 -236.384084) (xy 338.728838 -236.333356)
			(xy 338.741017 -236.283942) (xy 338.760965 -236.237122) (xy 338.788166 -236.194108) (xy 338.821914 -236.156014)
			(xy 338.861336 -236.123827) (xy 338.90541 -236.098381) (xy 338.952996 -236.080334) (xy 339.00286 -236.070154)
			(xy 339.053712 -236.068105) (xy 339.104233 -236.074239) (xy 339.153117 -236.088399) (xy 339.199096 -236.110216)
			(xy 339.24098 -236.139126) (xy 339.277684 -236.174381) (xy 339.308257 -236.215067) (xy 339.331908 -236.26013)
			(xy 339.348024 -236.308404) (xy 339.356188 -236.358638) (xy 339.3567 -236.384084) (xy 339.664797 -236.384084)
			(xy 339.668892 -236.333356) (xy 339.681071 -236.283942) (xy 339.701019 -236.237122) (xy 339.72822 -236.194108)
			(xy 339.761968 -236.156014) (xy 339.80139 -236.123827) (xy 339.845464 -236.098381) (xy 339.89305 -236.080334)
			(xy 339.942914 -236.070154) (xy 339.993766 -236.068105) (xy 340.044287 -236.074239) (xy 340.093171 -236.088399)
			(xy 340.13915 -236.110216) (xy 340.181034 -236.139126) (xy 340.217738 -236.174381) (xy 340.248311 -236.215067)
			(xy 340.271962 -236.26013) (xy 340.288078 -236.308404) (xy 340.296242 -236.358638) (xy 340.296754 -236.384084)
			(xy 340.615282 -236.384084) (xy 340.619242 -236.33503) (xy 340.631019 -236.287246) (xy 340.65031 -236.24197)
			(xy 340.676613 -236.200374) (xy 340.709248 -236.163537) (xy 340.747369 -236.132412) (xy 340.78999 -236.107805)
			(xy 340.836006 -236.090353) (xy 340.884225 -236.080509) (xy 340.9334 -236.078528) (xy 340.982255 -236.08446)
			(xy 341.029526 -236.098152) (xy 341.073988 -236.11925) (xy 341.114491 -236.147206) (xy 341.149984 -236.181298)
			(xy 341.179549 -236.220642) (xy 341.20242 -236.264219) (xy 341.218004 -236.3109) (xy 341.225899 -236.359477)
			(xy 341.226394 -236.384084) (xy 341.544905 -236.384084) (xy 341.549 -236.333356) (xy 341.561179 -236.283942)
			(xy 341.581127 -236.237122) (xy 341.608328 -236.194108) (xy 341.642076 -236.156014) (xy 341.681498 -236.123827)
			(xy 341.725572 -236.098381) (xy 341.773158 -236.080334) (xy 341.823022 -236.070154) (xy 341.873874 -236.068105)
			(xy 341.924395 -236.074239) (xy 341.973279 -236.088399) (xy 342.019258 -236.110216) (xy 342.061142 -236.139126)
			(xy 342.097846 -236.174381) (xy 342.128419 -236.215067) (xy 342.15207 -236.26013) (xy 342.168186 -236.308404)
			(xy 342.17635 -236.358638) (xy 342.176862 -236.384084) (xy 342.49539 -236.384084) (xy 342.49935 -236.33503)
			(xy 342.511127 -236.287246) (xy 342.530418 -236.24197) (xy 342.556721 -236.200374) (xy 342.589356 -236.163537)
			(xy 342.627477 -236.132412) (xy 342.670098 -236.107805) (xy 342.716114 -236.090353) (xy 342.764333 -236.080509)
			(xy 342.813508 -236.078528) (xy 342.862363 -236.08446) (xy 342.909634 -236.098152) (xy 342.954096 -236.11925)
			(xy 342.994599 -236.147206) (xy 343.030092 -236.181298) (xy 343.059657 -236.220642) (xy 343.082528 -236.264219)
			(xy 343.098112 -236.3109) (xy 343.106007 -236.359477) (xy 343.106502 -236.384084) (xy 343.106007 -236.408691)
			(xy 343.098112 -236.457268) (xy 343.082528 -236.503949) (xy 343.059657 -236.547526) (xy 343.030092 -236.58687)
			(xy 342.994599 -236.620962) (xy 342.954096 -236.648918) (xy 342.909634 -236.670016) (xy 342.862363 -236.683708)
			(xy 342.813508 -236.68964) (xy 342.764333 -236.687659) (xy 342.716114 -236.677815) (xy 342.670098 -236.660363)
			(xy 342.627477 -236.635756) (xy 342.589356 -236.604631) (xy 342.556721 -236.567794) (xy 342.530418 -236.526198)
			(xy 342.511127 -236.480922) (xy 342.49935 -236.433138) (xy 342.49539 -236.384084) (xy 342.176862 -236.384084)
			(xy 342.17635 -236.40953) (xy 342.168186 -236.459764) (xy 342.15207 -236.508038) (xy 342.128419 -236.553101)
			(xy 342.097846 -236.593787) (xy 342.061142 -236.629042) (xy 342.019258 -236.657952) (xy 341.973279 -236.679769)
			(xy 341.924395 -236.693929) (xy 341.873874 -236.700063) (xy 341.823022 -236.698014) (xy 341.773158 -236.687834)
			(xy 341.725572 -236.669787) (xy 341.681498 -236.644341) (xy 341.642076 -236.612154) (xy 341.608328 -236.57406)
			(xy 341.581127 -236.531046) (xy 341.561179 -236.484226) (xy 341.549 -236.434812) (xy 341.544905 -236.384084)
			(xy 341.226394 -236.384084) (xy 341.225899 -236.408691) (xy 341.218004 -236.457268) (xy 341.20242 -236.503949)
			(xy 341.179549 -236.547526) (xy 341.149984 -236.58687) (xy 341.114491 -236.620962) (xy 341.073988 -236.648918)
			(xy 341.029526 -236.670016) (xy 340.982255 -236.683708) (xy 340.9334 -236.68964) (xy 340.884225 -236.687659)
			(xy 340.836006 -236.677815) (xy 340.78999 -236.660363) (xy 340.747369 -236.635756) (xy 340.709248 -236.604631)
			(xy 340.676613 -236.567794) (xy 340.65031 -236.526198) (xy 340.631019 -236.480922) (xy 340.619242 -236.433138)
			(xy 340.615282 -236.384084) (xy 340.296754 -236.384084) (xy 340.296242 -236.40953) (xy 340.288078 -236.459764)
			(xy 340.271962 -236.508038) (xy 340.248311 -236.553101) (xy 340.217738 -236.593787) (xy 340.181034 -236.629042)
			(xy 340.13915 -236.657952) (xy 340.093171 -236.679769) (xy 340.044287 -236.693929) (xy 339.993766 -236.700063)
			(xy 339.942914 -236.698014) (xy 339.89305 -236.687834) (xy 339.845464 -236.669787) (xy 339.80139 -236.644341)
			(xy 339.761968 -236.612154) (xy 339.72822 -236.57406) (xy 339.701019 -236.531046) (xy 339.681071 -236.484226)
			(xy 339.668892 -236.434812) (xy 339.664797 -236.384084) (xy 339.3567 -236.384084) (xy 339.356188 -236.40953)
			(xy 339.348024 -236.459764) (xy 339.331908 -236.508038) (xy 339.308257 -236.553101) (xy 339.277684 -236.593787)
			(xy 339.24098 -236.629042) (xy 339.199096 -236.657952) (xy 339.153117 -236.679769) (xy 339.104233 -236.693929)
			(xy 339.053712 -236.700063) (xy 339.00286 -236.698014) (xy 338.952996 -236.687834) (xy 338.90541 -236.669787)
			(xy 338.861336 -236.644341) (xy 338.821914 -236.612154) (xy 338.788166 -236.57406) (xy 338.760965 -236.531046)
			(xy 338.741017 -236.484226) (xy 338.728838 -236.434812) (xy 338.724743 -236.384084) (xy 338.406486 -236.384084)
			(xy 338.405991 -236.408691) (xy 338.398096 -236.457268) (xy 338.382512 -236.503949) (xy 338.359641 -236.547526)
			(xy 338.330076 -236.58687) (xy 338.294583 -236.620962) (xy 338.25408 -236.648918) (xy 338.209618 -236.670016)
			(xy 338.162347 -236.683708) (xy 338.113492 -236.68964) (xy 338.064317 -236.687659) (xy 338.016098 -236.677815)
			(xy 337.970082 -236.660363) (xy 337.927461 -236.635756) (xy 337.88934 -236.604631) (xy 337.856705 -236.567794)
			(xy 337.830402 -236.526198) (xy 337.811111 -236.480922) (xy 337.799334 -236.433138) (xy 337.795374 -236.384084)
			(xy 337.466432 -236.384084) (xy 337.465937 -236.408691) (xy 337.458042 -236.457268) (xy 337.442458 -236.503949)
			(xy 337.419587 -236.547526) (xy 337.390022 -236.58687) (xy 337.354529 -236.620962) (xy 337.314026 -236.648918)
			(xy 337.269564 -236.670016) (xy 337.222293 -236.683708) (xy 337.173438 -236.68964) (xy 337.124263 -236.687659)
			(xy 337.076044 -236.677815) (xy 337.030028 -236.660363) (xy 336.987407 -236.635756) (xy 336.949286 -236.604631)
			(xy 336.916651 -236.567794) (xy 336.890348 -236.526198) (xy 336.871057 -236.480922) (xy 336.85928 -236.433138)
			(xy 336.85532 -236.384084) (xy 336.526378 -236.384084) (xy 336.525883 -236.408691) (xy 336.517988 -236.457268)
			(xy 336.502404 -236.503949) (xy 336.479533 -236.547526) (xy 336.449968 -236.58687) (xy 336.414475 -236.620962)
			(xy 336.373972 -236.648918) (xy 336.32951 -236.670016) (xy 336.282239 -236.683708) (xy 336.233384 -236.68964)
			(xy 336.184209 -236.687659) (xy 336.13599 -236.677815) (xy 336.089974 -236.660363) (xy 336.047353 -236.635756)
			(xy 336.009232 -236.604631) (xy 335.976597 -236.567794) (xy 335.950294 -236.526198) (xy 335.931003 -236.480922)
			(xy 335.919226 -236.433138) (xy 335.915266 -236.384084) (xy 335.586324 -236.384084) (xy 335.585829 -236.408691)
			(xy 335.577934 -236.457268) (xy 335.56235 -236.503949) (xy 335.539479 -236.547526) (xy 335.509914 -236.58687)
			(xy 335.474421 -236.620962) (xy 335.433918 -236.648918) (xy 335.389456 -236.670016) (xy 335.342185 -236.683708)
			(xy 335.29333 -236.68964) (xy 335.244155 -236.687659) (xy 335.195936 -236.677815) (xy 335.14992 -236.660363)
			(xy 335.107299 -236.635756) (xy 335.069178 -236.604631) (xy 335.036543 -236.567794) (xy 335.01024 -236.526198)
			(xy 334.990949 -236.480922) (xy 334.979172 -236.433138) (xy 334.975212 -236.384084) (xy 334.646524 -236.384084)
			(xy 334.646055 -236.408077) (xy 334.638551 -236.455471) (xy 334.623725 -236.501108) (xy 334.601942 -236.543864)
			(xy 334.57374 -236.582686) (xy 334.539811 -236.616619) (xy 334.500992 -236.644826) (xy 334.458238 -236.666613)
			(xy 334.412602 -236.681443) (xy 334.365208 -236.688952) (xy 334.341216 -236.689392) (xy 334.309466 -236.687614)
			(xy 334.306672 -236.68736) (xy 334.304132 -236.68736) (xy 334.294117 -236.687842) (xy 334.275608 -236.695494)
			(xy 334.261435 -236.709647) (xy 334.253756 -236.728146) (xy 334.253332 -236.73816) (xy 334.253332 -236.75848)
			(xy 334.254094 -236.76737) (xy 334.255364 -236.774228) (xy 334.256967 -236.78184) (xy 334.264083 -236.795666)
			(xy 334.269334 -236.801406) (xy 334.269588 -236.80166) (xy 334.274922 -236.807248) (xy 334.298193 -236.832276)
			(xy 334.339097 -236.887026) (xy 334.373006 -236.946363) (xy 334.386682 -236.977682) (xy 334.389222 -236.983778)
			(xy 334.396842 -236.993938) (xy 334.421226 -237.012988) (xy 334.426702 -237.016946) (xy 334.439191 -237.022088)
			(xy 334.445864 -237.023148) (xy 334.516984 -237.0328) (xy 334.522959 -237.033418) (xy 334.5349 -237.032137)
			(xy 334.540606 -237.03026) (xy 334.551782 -237.02645) (xy 334.56499 -237.013242) (xy 334.567022 -237.010448)
			(xy 334.581567 -236.991896) (xy 334.615398 -236.959068) (xy 334.653863 -236.931816) (xy 334.696052 -236.910784)
			(xy 334.740967 -236.896471) (xy 334.787546 -236.889214) (xy 334.811116 -236.888782) (xy 334.836371 -236.889305)
			(xy 334.886193 -236.897621) (xy 334.933966 -236.914024) (xy 334.978388 -236.938066) (xy 335.018247 -236.969091)
			(xy 335.052456 -237.006254) (xy 335.080082 -237.04854) (xy 335.100371 -237.094797) (xy 335.11277 -237.143762)
			(xy 335.11694 -237.19409) (xy 335.445366 -237.19409) (xy 335.449326 -237.145036) (xy 335.461103 -237.097252)
			(xy 335.480394 -237.051976) (xy 335.506697 -237.01038) (xy 335.539332 -236.973543) (xy 335.577453 -236.942418)
			(xy 335.620074 -236.917811) (xy 335.66609 -236.900359) (xy 335.714309 -236.890515) (xy 335.763484 -236.888534)
			(xy 335.812339 -236.894466) (xy 335.85961 -236.908158) (xy 335.904072 -236.929256) (xy 335.944575 -236.957212)
			(xy 335.980068 -236.991304) (xy 336.009633 -237.030648) (xy 336.032504 -237.074225) (xy 336.048088 -237.120906)
			(xy 336.055983 -237.169483) (xy 336.056478 -237.19409) (xy 336.38542 -237.19409) (xy 336.38938 -237.145036)
			(xy 336.401157 -237.097252) (xy 336.420448 -237.051976) (xy 336.446751 -237.01038) (xy 336.479386 -236.973543)
			(xy 336.517507 -236.942418) (xy 336.560128 -236.917811) (xy 336.606144 -236.900359) (xy 336.654363 -236.890515)
			(xy 336.703538 -236.888534) (xy 336.752393 -236.894466) (xy 336.799664 -236.908158) (xy 336.844126 -236.929256)
			(xy 336.884629 -236.957212) (xy 336.920122 -236.991304) (xy 336.949687 -237.030648) (xy 336.972558 -237.074225)
			(xy 336.988142 -237.120906) (xy 336.996037 -237.169483) (xy 336.996532 -237.19409) (xy 337.32522 -237.19409)
			(xy 337.32918 -237.145036) (xy 337.340957 -237.097252) (xy 337.360248 -237.051976) (xy 337.386551 -237.01038)
			(xy 337.419186 -236.973543) (xy 337.457307 -236.942418) (xy 337.499928 -236.917811) (xy 337.545944 -236.900359)
			(xy 337.594163 -236.890515) (xy 337.643338 -236.888534) (xy 337.692193 -236.894466) (xy 337.739464 -236.908158)
			(xy 337.783926 -236.929256) (xy 337.824429 -236.957212) (xy 337.859922 -236.991304) (xy 337.889487 -237.030648)
			(xy 337.912358 -237.074225) (xy 337.927942 -237.120906) (xy 337.935837 -237.169483) (xy 337.936332 -237.19409)
			(xy 338.254843 -237.19409) (xy 338.258938 -237.143362) (xy 338.271117 -237.093948) (xy 338.291065 -237.047128)
			(xy 338.318266 -237.004114) (xy 338.352014 -236.96602) (xy 338.391436 -236.933833) (xy 338.43551 -236.908387)
			(xy 338.483096 -236.89034) (xy 338.53296 -236.88016) (xy 338.583812 -236.878111) (xy 338.634333 -236.884245)
			(xy 338.683217 -236.898405) (xy 338.729196 -236.920222) (xy 338.77108 -236.949132) (xy 338.807784 -236.984387)
			(xy 338.838357 -237.025073) (xy 338.862008 -237.070136) (xy 338.878124 -237.11841) (xy 338.886288 -237.168644)
			(xy 338.8868 -237.19409) (xy 339.205328 -237.19409) (xy 339.209288 -237.145036) (xy 339.221065 -237.097252)
			(xy 339.240356 -237.051976) (xy 339.266659 -237.01038) (xy 339.299294 -236.973543) (xy 339.337415 -236.942418)
			(xy 339.380036 -236.917811) (xy 339.426052 -236.900359) (xy 339.474271 -236.890515) (xy 339.523446 -236.888534)
			(xy 339.572301 -236.894466) (xy 339.619572 -236.908158) (xy 339.664034 -236.929256) (xy 339.704537 -236.957212)
			(xy 339.74003 -236.991304) (xy 339.769595 -237.030648) (xy 339.792466 -237.074225) (xy 339.80805 -237.120906)
			(xy 339.815945 -237.169483) (xy 339.81644 -237.19409) (xy 340.134951 -237.19409) (xy 340.139046 -237.143362)
			(xy 340.151225 -237.093948) (xy 340.171173 -237.047128) (xy 340.198374 -237.004114) (xy 340.232122 -236.96602)
			(xy 340.271544 -236.933833) (xy 340.315618 -236.908387) (xy 340.363204 -236.89034) (xy 340.413068 -236.88016)
			(xy 340.46392 -236.878111) (xy 340.514441 -236.884245) (xy 340.563325 -236.898405) (xy 340.609304 -236.920222)
			(xy 340.651188 -236.949132) (xy 340.687892 -236.984387) (xy 340.718465 -237.025073) (xy 340.742116 -237.070136)
			(xy 340.758232 -237.11841) (xy 340.766396 -237.168644) (xy 340.766908 -237.19409) (xy 341.085182 -237.19409)
			(xy 341.089142 -237.145036) (xy 341.100919 -237.097252) (xy 341.12021 -237.051976) (xy 341.146513 -237.01038)
			(xy 341.179148 -236.973543) (xy 341.217269 -236.942418) (xy 341.25989 -236.917811) (xy 341.305906 -236.900359)
			(xy 341.354125 -236.890515) (xy 341.4033 -236.888534) (xy 341.452155 -236.894466) (xy 341.499426 -236.908158)
			(xy 341.543888 -236.929256) (xy 341.584391 -236.957212) (xy 341.619884 -236.991304) (xy 341.649449 -237.030648)
			(xy 341.67232 -237.074225) (xy 341.687904 -237.120906) (xy 341.695799 -237.169483) (xy 341.696294 -237.19409)
			(xy 342.014805 -237.19409) (xy 342.0189 -237.143362) (xy 342.031079 -237.093948) (xy 342.051027 -237.047128)
			(xy 342.078228 -237.004114) (xy 342.111976 -236.96602) (xy 342.151398 -236.933833) (xy 342.195472 -236.908387)
			(xy 342.243058 -236.89034) (xy 342.292922 -236.88016) (xy 342.343774 -236.878111) (xy 342.394295 -236.884245)
			(xy 342.443179 -236.898405) (xy 342.489158 -236.920222) (xy 342.531042 -236.949132) (xy 342.567746 -236.984387)
			(xy 342.598319 -237.025073) (xy 342.62197 -237.070136) (xy 342.638086 -237.11841) (xy 342.64625 -237.168644)
			(xy 342.646762 -237.19409) (xy 342.64625 -237.219536) (xy 342.638086 -237.26977) (xy 342.62197 -237.318044)
			(xy 342.598319 -237.363107) (xy 342.567746 -237.403793) (xy 342.531042 -237.439048) (xy 342.489158 -237.467958)
			(xy 342.443179 -237.489775) (xy 342.394295 -237.503935) (xy 342.343774 -237.510069) (xy 342.292922 -237.50802)
			(xy 342.243058 -237.49784) (xy 342.195472 -237.479793) (xy 342.151398 -237.454347) (xy 342.111976 -237.42216)
			(xy 342.078228 -237.384066) (xy 342.051027 -237.341052) (xy 342.031079 -237.294232) (xy 342.0189 -237.244818)
			(xy 342.014805 -237.19409) (xy 341.696294 -237.19409) (xy 341.695799 -237.218697) (xy 341.687904 -237.267274)
			(xy 341.67232 -237.313955) (xy 341.649449 -237.357532) (xy 341.619884 -237.396876) (xy 341.584391 -237.430968)
			(xy 341.543888 -237.458924) (xy 341.499426 -237.480022) (xy 341.452155 -237.493714) (xy 341.4033 -237.499646)
			(xy 341.354125 -237.497665) (xy 341.305906 -237.487821) (xy 341.25989 -237.470369) (xy 341.217269 -237.445762)
			(xy 341.179148 -237.414637) (xy 341.146513 -237.3778) (xy 341.12021 -237.336204) (xy 341.100919 -237.290928)
			(xy 341.089142 -237.243144) (xy 341.085182 -237.19409) (xy 340.766908 -237.19409) (xy 340.766396 -237.219536)
			(xy 340.758232 -237.26977) (xy 340.742116 -237.318044) (xy 340.718465 -237.363107) (xy 340.687892 -237.403793)
			(xy 340.651188 -237.439048) (xy 340.609304 -237.467958) (xy 340.563325 -237.489775) (xy 340.514441 -237.503935)
			(xy 340.46392 -237.510069) (xy 340.413068 -237.50802) (xy 340.363204 -237.49784) (xy 340.315618 -237.479793)
			(xy 340.271544 -237.454347) (xy 340.232122 -237.42216) (xy 340.198374 -237.384066) (xy 340.171173 -237.341052)
			(xy 340.151225 -237.294232) (xy 340.139046 -237.244818) (xy 340.134951 -237.19409) (xy 339.81644 -237.19409)
			(xy 339.815945 -237.218697) (xy 339.80805 -237.267274) (xy 339.792466 -237.313955) (xy 339.769595 -237.357532)
			(xy 339.74003 -237.396876) (xy 339.704537 -237.430968) (xy 339.664034 -237.458924) (xy 339.619572 -237.480022)
			(xy 339.572301 -237.493714) (xy 339.523446 -237.499646) (xy 339.474271 -237.497665) (xy 339.426052 -237.487821)
			(xy 339.380036 -237.470369) (xy 339.337415 -237.445762) (xy 339.299294 -237.414637) (xy 339.266659 -237.3778)
			(xy 339.240356 -237.336204) (xy 339.221065 -237.290928) (xy 339.209288 -237.243144) (xy 339.205328 -237.19409)
			(xy 338.8868 -237.19409) (xy 338.886288 -237.219536) (xy 338.878124 -237.26977) (xy 338.862008 -237.318044)
			(xy 338.838357 -237.363107) (xy 338.807784 -237.403793) (xy 338.77108 -237.439048) (xy 338.729196 -237.467958)
			(xy 338.683217 -237.489775) (xy 338.634333 -237.503935) (xy 338.583812 -237.510069) (xy 338.53296 -237.50802)
			(xy 338.483096 -237.49784) (xy 338.43551 -237.479793) (xy 338.391436 -237.454347) (xy 338.352014 -237.42216)
			(xy 338.318266 -237.384066) (xy 338.291065 -237.341052) (xy 338.271117 -237.294232) (xy 338.258938 -237.244818)
			(xy 338.254843 -237.19409) (xy 337.936332 -237.19409) (xy 337.935837 -237.218697) (xy 337.927942 -237.267274)
			(xy 337.912358 -237.313955) (xy 337.889487 -237.357532) (xy 337.859922 -237.396876) (xy 337.824429 -237.430968)
			(xy 337.783926 -237.458924) (xy 337.739464 -237.480022) (xy 337.692193 -237.493714) (xy 337.643338 -237.499646)
			(xy 337.594163 -237.497665) (xy 337.545944 -237.487821) (xy 337.499928 -237.470369) (xy 337.457307 -237.445762)
			(xy 337.419186 -237.414637) (xy 337.386551 -237.3778) (xy 337.360248 -237.336204) (xy 337.340957 -237.290928)
			(xy 337.32918 -237.243144) (xy 337.32522 -237.19409) (xy 336.996532 -237.19409) (xy 336.996037 -237.218697)
			(xy 336.988142 -237.267274) (xy 336.972558 -237.313955) (xy 336.949687 -237.357532) (xy 336.920122 -237.396876)
			(xy 336.884629 -237.430968) (xy 336.844126 -237.458924) (xy 336.799664 -237.480022) (xy 336.752393 -237.493714)
			(xy 336.703538 -237.499646) (xy 336.654363 -237.497665) (xy 336.606144 -237.487821) (xy 336.560128 -237.470369)
			(xy 336.517507 -237.445762) (xy 336.479386 -237.414637) (xy 336.446751 -237.3778) (xy 336.420448 -237.336204)
			(xy 336.401157 -237.290928) (xy 336.38938 -237.243144) (xy 336.38542 -237.19409) (xy 336.056478 -237.19409)
			(xy 336.055983 -237.218697) (xy 336.048088 -237.267274) (xy 336.032504 -237.313955) (xy 336.009633 -237.357532)
			(xy 335.980068 -237.396876) (xy 335.944575 -237.430968) (xy 335.904072 -237.458924) (xy 335.85961 -237.480022)
			(xy 335.812339 -237.493714) (xy 335.763484 -237.499646) (xy 335.714309 -237.497665) (xy 335.66609 -237.487821)
			(xy 335.620074 -237.470369) (xy 335.577453 -237.445762) (xy 335.539332 -237.414637) (xy 335.506697 -237.3778)
			(xy 335.480394 -237.336204) (xy 335.461103 -237.290928) (xy 335.449326 -237.243144) (xy 335.445366 -237.19409)
			(xy 335.11694 -237.19409) (xy 335.116941 -237.1941) (xy 335.11277 -237.244438) (xy 335.100371 -237.293403)
			(xy 335.080082 -237.33966) (xy 335.052456 -237.381946) (xy 335.018247 -237.419109) (xy 334.978388 -237.450134)
			(xy 334.933966 -237.474176) (xy 334.886193 -237.490579) (xy 334.836371 -237.498895) (xy 334.811116 -237.499398)
			(xy 334.787545 -237.498963) (xy 334.740961 -237.491726) (xy 334.696042 -237.477421) (xy 334.653852 -237.456387)
			(xy 334.615392 -237.429125) (xy 334.581576 -237.396279) (xy 334.567022 -237.377732) (xy 334.56499 -237.374938)
			(xy 334.55991 -237.369858) (xy 334.553346 -237.363734) (xy 334.537075 -237.35618) (xy 334.52816 -237.355126)
			(xy 334.522572 -237.354618) (xy 334.432148 -237.36681) (xy 334.423229 -237.368355) (xy 334.407234 -237.376803)
			(xy 334.395169 -237.390281) (xy 334.391508 -237.39856) (xy 334.383585 -237.418267) (xy 334.36515 -237.456535)
			(xy 334.354678 -237.475014) (xy 334.312768 -237.54715) (xy 334.311498 -237.548928) (xy 334.303878 -237.560358)
			(xy 334.3021 -237.587536) (xy 334.338676 -237.661958) (xy 334.341555 -237.667289) (xy 334.349387 -237.676527)
			(xy 334.35417 -237.680246) (xy 334.382618 -237.701328) (xy 334.394302 -237.70336) (xy 334.41756 -237.707917)
			(xy 334.462398 -237.723263) (xy 334.504325 -237.745357) (xy 334.542333 -237.773666) (xy 334.575507 -237.807511)
			(xy 334.603051 -237.846076) (xy 334.624302 -237.888437) (xy 334.638749 -237.933573) (xy 334.646045 -237.9804)
			(xy 334.646524 -238.004096) (xy 334.975212 -238.004096) (xy 334.979172 -237.955042) (xy 334.990949 -237.907258)
			(xy 335.01024 -237.861982) (xy 335.036543 -237.820386) (xy 335.069178 -237.783549) (xy 335.107299 -237.752424)
			(xy 335.14992 -237.727817) (xy 335.195936 -237.710365) (xy 335.244155 -237.700521) (xy 335.29333 -237.69854)
			(xy 335.342185 -237.704472) (xy 335.389456 -237.718164) (xy 335.433918 -237.739262) (xy 335.474421 -237.767218)
			(xy 335.509914 -237.80131) (xy 335.539479 -237.840654) (xy 335.56235 -237.884231) (xy 335.577934 -237.930912)
			(xy 335.585829 -237.979489) (xy 335.586324 -238.004096) (xy 335.915266 -238.004096) (xy 335.919226 -237.955042)
			(xy 335.931003 -237.907258) (xy 335.950294 -237.861982) (xy 335.976597 -237.820386) (xy 336.009232 -237.783549)
			(xy 336.047353 -237.752424) (xy 336.089974 -237.727817) (xy 336.13599 -237.710365) (xy 336.184209 -237.700521)
			(xy 336.233384 -237.69854) (xy 336.282239 -237.704472) (xy 336.32951 -237.718164) (xy 336.373972 -237.739262)
			(xy 336.414475 -237.767218) (xy 336.449968 -237.80131) (xy 336.479533 -237.840654) (xy 336.502404 -237.884231)
			(xy 336.517988 -237.930912) (xy 336.525883 -237.979489) (xy 336.526378 -238.004096) (xy 336.85532 -238.004096)
			(xy 336.85928 -237.955042) (xy 336.871057 -237.907258) (xy 336.890348 -237.861982) (xy 336.916651 -237.820386)
			(xy 336.949286 -237.783549) (xy 336.987407 -237.752424) (xy 337.030028 -237.727817) (xy 337.076044 -237.710365)
			(xy 337.124263 -237.700521) (xy 337.173438 -237.69854) (xy 337.222293 -237.704472) (xy 337.269564 -237.718164)
			(xy 337.314026 -237.739262) (xy 337.354529 -237.767218) (xy 337.390022 -237.80131) (xy 337.419587 -237.840654)
			(xy 337.442458 -237.884231) (xy 337.458042 -237.930912) (xy 337.465937 -237.979489) (xy 337.466432 -238.004096)
			(xy 337.795374 -238.004096) (xy 337.799334 -237.955042) (xy 337.811111 -237.907258) (xy 337.830402 -237.861982)
			(xy 337.856705 -237.820386) (xy 337.88934 -237.783549) (xy 337.927461 -237.752424) (xy 337.970082 -237.727817)
			(xy 338.016098 -237.710365) (xy 338.064317 -237.700521) (xy 338.113492 -237.69854) (xy 338.162347 -237.704472)
			(xy 338.209618 -237.718164) (xy 338.25408 -237.739262) (xy 338.294583 -237.767218) (xy 338.330076 -237.80131)
			(xy 338.359641 -237.840654) (xy 338.382512 -237.884231) (xy 338.398096 -237.930912) (xy 338.405991 -237.979489)
			(xy 338.406486 -238.004096) (xy 338.724743 -238.004096) (xy 338.728838 -237.953368) (xy 338.741017 -237.903954)
			(xy 338.760965 -237.857134) (xy 338.788166 -237.81412) (xy 338.821914 -237.776026) (xy 338.861336 -237.743839)
			(xy 338.90541 -237.718393) (xy 338.952996 -237.700346) (xy 339.00286 -237.690166) (xy 339.053712 -237.688117)
			(xy 339.104233 -237.694251) (xy 339.153117 -237.708411) (xy 339.199096 -237.730228) (xy 339.24098 -237.759138)
			(xy 339.277684 -237.794393) (xy 339.308257 -237.835079) (xy 339.331908 -237.880142) (xy 339.348024 -237.928416)
			(xy 339.356188 -237.97865) (xy 339.3567 -238.004096) (xy 339.664797 -238.004096) (xy 339.668892 -237.953368)
			(xy 339.681071 -237.903954) (xy 339.701019 -237.857134) (xy 339.72822 -237.81412) (xy 339.761968 -237.776026)
			(xy 339.80139 -237.743839) (xy 339.845464 -237.718393) (xy 339.89305 -237.700346) (xy 339.942914 -237.690166)
			(xy 339.993766 -237.688117) (xy 340.044287 -237.694251) (xy 340.093171 -237.708411) (xy 340.13915 -237.730228)
			(xy 340.181034 -237.759138) (xy 340.217738 -237.794393) (xy 340.248311 -237.835079) (xy 340.271962 -237.880142)
			(xy 340.288078 -237.928416) (xy 340.296242 -237.97865) (xy 340.296754 -238.004096) (xy 340.615282 -238.004096)
			(xy 340.619242 -237.955042) (xy 340.631019 -237.907258) (xy 340.65031 -237.861982) (xy 340.676613 -237.820386)
			(xy 340.709248 -237.783549) (xy 340.747369 -237.752424) (xy 340.78999 -237.727817) (xy 340.836006 -237.710365)
			(xy 340.884225 -237.700521) (xy 340.9334 -237.69854) (xy 340.982255 -237.704472) (xy 341.029526 -237.718164)
			(xy 341.073988 -237.739262) (xy 341.114491 -237.767218) (xy 341.149984 -237.80131) (xy 341.179549 -237.840654)
			(xy 341.20242 -237.884231) (xy 341.218004 -237.930912) (xy 341.225899 -237.979489) (xy 341.226394 -238.004096)
			(xy 341.544905 -238.004096) (xy 341.549 -237.953368) (xy 341.561179 -237.903954) (xy 341.581127 -237.857134)
			(xy 341.608328 -237.81412) (xy 341.642076 -237.776026) (xy 341.681498 -237.743839) (xy 341.725572 -237.718393)
			(xy 341.773158 -237.700346) (xy 341.823022 -237.690166) (xy 341.873874 -237.688117) (xy 341.924395 -237.694251)
			(xy 341.973279 -237.708411) (xy 342.019258 -237.730228) (xy 342.061142 -237.759138) (xy 342.097846 -237.794393)
			(xy 342.128419 -237.835079) (xy 342.15207 -237.880142) (xy 342.168186 -237.928416) (xy 342.17635 -237.97865)
			(xy 342.176862 -238.004096) (xy 342.49539 -238.004096) (xy 342.49935 -237.955042) (xy 342.511127 -237.907258)
			(xy 342.530418 -237.861982) (xy 342.556721 -237.820386) (xy 342.589356 -237.783549) (xy 342.627477 -237.752424)
			(xy 342.670098 -237.727817) (xy 342.716114 -237.710365) (xy 342.764333 -237.700521) (xy 342.813508 -237.69854)
			(xy 342.862363 -237.704472) (xy 342.909634 -237.718164) (xy 342.954096 -237.739262) (xy 342.994599 -237.767218)
			(xy 343.030092 -237.80131) (xy 343.059657 -237.840654) (xy 343.082528 -237.884231) (xy 343.098112 -237.930912)
			(xy 343.106007 -237.979489) (xy 343.106502 -238.004096) (xy 343.106007 -238.028703) (xy 343.098112 -238.07728)
			(xy 343.082528 -238.123961) (xy 343.059657 -238.167538) (xy 343.030092 -238.206882) (xy 342.994599 -238.240974)
			(xy 342.954096 -238.26893) (xy 342.909634 -238.290028) (xy 342.862363 -238.30372) (xy 342.813508 -238.309652)
			(xy 342.764333 -238.307671) (xy 342.716114 -238.297827) (xy 342.670098 -238.280375) (xy 342.627477 -238.255768)
			(xy 342.589356 -238.224643) (xy 342.556721 -238.187806) (xy 342.530418 -238.14621) (xy 342.511127 -238.100934)
			(xy 342.49935 -238.05315) (xy 342.49539 -238.004096) (xy 342.176862 -238.004096) (xy 342.17635 -238.029542)
			(xy 342.168186 -238.079776) (xy 342.15207 -238.12805) (xy 342.128419 -238.173113) (xy 342.097846 -238.213799)
			(xy 342.061142 -238.249054) (xy 342.019258 -238.277964) (xy 341.973279 -238.299781) (xy 341.924395 -238.313941)
			(xy 341.873874 -238.320075) (xy 341.823022 -238.318026) (xy 341.773158 -238.307846) (xy 341.725572 -238.289799)
			(xy 341.681498 -238.264353) (xy 341.642076 -238.232166) (xy 341.608328 -238.194072) (xy 341.581127 -238.151058)
			(xy 341.561179 -238.104238) (xy 341.549 -238.054824) (xy 341.544905 -238.004096) (xy 341.226394 -238.004096)
			(xy 341.225899 -238.028703) (xy 341.218004 -238.07728) (xy 341.20242 -238.123961) (xy 341.179549 -238.167538)
			(xy 341.149984 -238.206882) (xy 341.114491 -238.240974) (xy 341.073988 -238.26893) (xy 341.029526 -238.290028)
			(xy 340.982255 -238.30372) (xy 340.9334 -238.309652) (xy 340.884225 -238.307671) (xy 340.836006 -238.297827)
			(xy 340.78999 -238.280375) (xy 340.747369 -238.255768) (xy 340.709248 -238.224643) (xy 340.676613 -238.187806)
			(xy 340.65031 -238.14621) (xy 340.631019 -238.100934) (xy 340.619242 -238.05315) (xy 340.615282 -238.004096)
			(xy 340.296754 -238.004096) (xy 340.296242 -238.029542) (xy 340.288078 -238.079776) (xy 340.271962 -238.12805)
			(xy 340.248311 -238.173113) (xy 340.217738 -238.213799) (xy 340.181034 -238.249054) (xy 340.13915 -238.277964)
			(xy 340.093171 -238.299781) (xy 340.044287 -238.313941) (xy 339.993766 -238.320075) (xy 339.942914 -238.318026)
			(xy 339.89305 -238.307846) (xy 339.845464 -238.289799) (xy 339.80139 -238.264353) (xy 339.761968 -238.232166)
			(xy 339.72822 -238.194072) (xy 339.701019 -238.151058) (xy 339.681071 -238.104238) (xy 339.668892 -238.054824)
			(xy 339.664797 -238.004096) (xy 339.3567 -238.004096) (xy 339.356188 -238.029542) (xy 339.348024 -238.079776)
			(xy 339.331908 -238.12805) (xy 339.308257 -238.173113) (xy 339.277684 -238.213799) (xy 339.24098 -238.249054)
			(xy 339.199096 -238.277964) (xy 339.153117 -238.299781) (xy 339.104233 -238.313941) (xy 339.053712 -238.320075)
			(xy 339.00286 -238.318026) (xy 338.952996 -238.307846) (xy 338.90541 -238.289799) (xy 338.861336 -238.264353)
			(xy 338.821914 -238.232166) (xy 338.788166 -238.194072) (xy 338.760965 -238.151058) (xy 338.741017 -238.104238)
			(xy 338.728838 -238.054824) (xy 338.724743 -238.004096) (xy 338.406486 -238.004096) (xy 338.405991 -238.028703)
			(xy 338.398096 -238.07728) (xy 338.382512 -238.123961) (xy 338.359641 -238.167538) (xy 338.330076 -238.206882)
			(xy 338.294583 -238.240974) (xy 338.25408 -238.26893) (xy 338.209618 -238.290028) (xy 338.162347 -238.30372)
			(xy 338.113492 -238.309652) (xy 338.064317 -238.307671) (xy 338.016098 -238.297827) (xy 337.970082 -238.280375)
			(xy 337.927461 -238.255768) (xy 337.88934 -238.224643) (xy 337.856705 -238.187806) (xy 337.830402 -238.14621)
			(xy 337.811111 -238.100934) (xy 337.799334 -238.05315) (xy 337.795374 -238.004096) (xy 337.466432 -238.004096)
			(xy 337.465937 -238.028703) (xy 337.458042 -238.07728) (xy 337.442458 -238.123961) (xy 337.419587 -238.167538)
			(xy 337.390022 -238.206882) (xy 337.354529 -238.240974) (xy 337.314026 -238.26893) (xy 337.269564 -238.290028)
			(xy 337.222293 -238.30372) (xy 337.173438 -238.309652) (xy 337.124263 -238.307671) (xy 337.076044 -238.297827)
			(xy 337.030028 -238.280375) (xy 336.987407 -238.255768) (xy 336.949286 -238.224643) (xy 336.916651 -238.187806)
			(xy 336.890348 -238.14621) (xy 336.871057 -238.100934) (xy 336.85928 -238.05315) (xy 336.85532 -238.004096)
			(xy 336.526378 -238.004096) (xy 336.525883 -238.028703) (xy 336.517988 -238.07728) (xy 336.502404 -238.123961)
			(xy 336.479533 -238.167538) (xy 336.449968 -238.206882) (xy 336.414475 -238.240974) (xy 336.373972 -238.26893)
			(xy 336.32951 -238.290028) (xy 336.282239 -238.30372) (xy 336.233384 -238.309652) (xy 336.184209 -238.307671)
			(xy 336.13599 -238.297827) (xy 336.089974 -238.280375) (xy 336.047353 -238.255768) (xy 336.009232 -238.224643)
			(xy 335.976597 -238.187806) (xy 335.950294 -238.14621) (xy 335.931003 -238.100934) (xy 335.919226 -238.05315)
			(xy 335.915266 -238.004096) (xy 335.586324 -238.004096) (xy 335.585829 -238.028703) (xy 335.577934 -238.07728)
			(xy 335.56235 -238.123961) (xy 335.539479 -238.167538) (xy 335.509914 -238.206882) (xy 335.474421 -238.240974)
			(xy 335.433918 -238.26893) (xy 335.389456 -238.290028) (xy 335.342185 -238.30372) (xy 335.29333 -238.309652)
			(xy 335.244155 -238.307671) (xy 335.195936 -238.297827) (xy 335.14992 -238.280375) (xy 335.107299 -238.255768)
			(xy 335.069178 -238.224643) (xy 335.036543 -238.187806) (xy 335.01024 -238.14621) (xy 334.990949 -238.100934)
			(xy 334.979172 -238.05315) (xy 334.975212 -238.004096) (xy 334.646524 -238.004096) (xy 334.646054 -238.028088)
			(xy 334.638548 -238.075481) (xy 334.623721 -238.121117) (xy 334.601938 -238.163871) (xy 334.573735 -238.202691)
			(xy 334.539807 -238.236622) (xy 334.500988 -238.264828) (xy 334.458235 -238.286614) (xy 334.4126 -238.301444)
			(xy 334.365208 -238.308952) (xy 334.341216 -238.309404) (xy 334.309466 -238.307626) (xy 334.306672 -238.307372)
			(xy 334.304132 -238.307372) (xy 334.294104 -238.307785) (xy 334.275572 -238.315449) (xy 334.261382 -238.329621)
			(xy 334.253697 -238.348145) (xy 334.253332 -238.358172) (xy 334.253332 -238.378492) (xy 334.254094 -238.387382)
			(xy 334.255364 -238.39424) (xy 334.256969 -238.401851) (xy 334.264087 -238.415675) (xy 334.269334 -238.421418)
			(xy 334.269588 -238.421672) (xy 334.274922 -238.42726) (xy 334.298192 -238.452289) (xy 334.339096 -238.507039)
			(xy 334.373003 -238.566376) (xy 334.386682 -238.597694) (xy 334.389222 -238.60379) (xy 334.396842 -238.61395)
			(xy 334.421226 -238.633) (xy 334.426702 -238.636957) (xy 334.439191 -238.642098) (xy 334.445864 -238.64316)
			(xy 334.516984 -238.652812) (xy 334.522959 -238.65343) (xy 334.5349 -238.65215) (xy 334.540606 -238.650272)
			(xy 334.551782 -238.646462) (xy 334.56499 -238.633254) (xy 334.567022 -238.63046) (xy 334.581567 -238.611907)
			(xy 334.615398 -238.579078) (xy 334.653862 -238.551825) (xy 334.696051 -238.530792) (xy 334.740967 -238.516478)
			(xy 334.787546 -238.509221) (xy 334.811116 -238.508794) (xy 334.83637 -238.509317) (xy 334.88619 -238.517633)
			(xy 334.933961 -238.534035) (xy 334.978381 -238.558076) (xy 335.018239 -238.5891) (xy 335.052446 -238.626261)
			(xy 335.080071 -238.668546) (xy 335.100359 -238.714801) (xy 335.112758 -238.763764) (xy 335.116929 -238.8141)
			(xy 335.116929 -238.814102) (xy 335.445366 -238.814102) (xy 335.449326 -238.765048) (xy 335.461103 -238.717264)
			(xy 335.480394 -238.671988) (xy 335.506697 -238.630392) (xy 335.539332 -238.593555) (xy 335.577453 -238.56243)
			(xy 335.620074 -238.537823) (xy 335.66609 -238.520371) (xy 335.714309 -238.510527) (xy 335.763484 -238.508546)
			(xy 335.812339 -238.514478) (xy 335.85961 -238.52817) (xy 335.904072 -238.549268) (xy 335.944575 -238.577224)
			(xy 335.980068 -238.611316) (xy 336.009633 -238.65066) (xy 336.032504 -238.694237) (xy 336.048088 -238.740918)
			(xy 336.055983 -238.789495) (xy 336.056478 -238.814102) (xy 336.38542 -238.814102) (xy 336.38938 -238.765048)
			(xy 336.401157 -238.717264) (xy 336.420448 -238.671988) (xy 336.446751 -238.630392) (xy 336.479386 -238.593555)
			(xy 336.517507 -238.56243) (xy 336.560128 -238.537823) (xy 336.606144 -238.520371) (xy 336.654363 -238.510527)
			(xy 336.703538 -238.508546) (xy 336.752393 -238.514478) (xy 336.799664 -238.52817) (xy 336.844126 -238.549268)
			(xy 336.884629 -238.577224) (xy 336.920122 -238.611316) (xy 336.949687 -238.65066) (xy 336.972558 -238.694237)
			(xy 336.988142 -238.740918) (xy 336.996037 -238.789495) (xy 336.996532 -238.814102) (xy 337.32522 -238.814102)
			(xy 337.32918 -238.765048) (xy 337.340957 -238.717264) (xy 337.360248 -238.671988) (xy 337.386551 -238.630392)
			(xy 337.419186 -238.593555) (xy 337.457307 -238.56243) (xy 337.499928 -238.537823) (xy 337.545944 -238.520371)
			(xy 337.594163 -238.510527) (xy 337.643338 -238.508546) (xy 337.692193 -238.514478) (xy 337.739464 -238.52817)
			(xy 337.783926 -238.549268) (xy 337.824429 -238.577224) (xy 337.859922 -238.611316) (xy 337.889487 -238.65066)
			(xy 337.912358 -238.694237) (xy 337.927942 -238.740918) (xy 337.935837 -238.789495) (xy 337.936332 -238.814102)
			(xy 338.254843 -238.814102) (xy 338.258938 -238.763374) (xy 338.271117 -238.71396) (xy 338.291065 -238.66714)
			(xy 338.318266 -238.624126) (xy 338.352014 -238.586032) (xy 338.391436 -238.553845) (xy 338.43551 -238.528399)
			(xy 338.483096 -238.510352) (xy 338.53296 -238.500172) (xy 338.583812 -238.498123) (xy 338.634333 -238.504257)
			(xy 338.683217 -238.518417) (xy 338.729196 -238.540234) (xy 338.77108 -238.569144) (xy 338.807784 -238.604399)
			(xy 338.838357 -238.645085) (xy 338.862008 -238.690148) (xy 338.878124 -238.738422) (xy 338.886288 -238.788656)
			(xy 338.8868 -238.814102) (xy 339.205328 -238.814102) (xy 339.209288 -238.765048) (xy 339.221065 -238.717264)
			(xy 339.240356 -238.671988) (xy 339.266659 -238.630392) (xy 339.299294 -238.593555) (xy 339.337415 -238.56243)
			(xy 339.380036 -238.537823) (xy 339.426052 -238.520371) (xy 339.474271 -238.510527) (xy 339.523446 -238.508546)
			(xy 339.572301 -238.514478) (xy 339.619572 -238.52817) (xy 339.664034 -238.549268) (xy 339.704537 -238.577224)
			(xy 339.74003 -238.611316) (xy 339.769595 -238.65066) (xy 339.792466 -238.694237) (xy 339.80805 -238.740918)
			(xy 339.815945 -238.789495) (xy 339.81644 -238.814102) (xy 340.134951 -238.814102) (xy 340.139046 -238.763374)
			(xy 340.151225 -238.71396) (xy 340.171173 -238.66714) (xy 340.198374 -238.624126) (xy 340.232122 -238.586032)
			(xy 340.271544 -238.553845) (xy 340.315618 -238.528399) (xy 340.363204 -238.510352) (xy 340.413068 -238.500172)
			(xy 340.46392 -238.498123) (xy 340.514441 -238.504257) (xy 340.563325 -238.518417) (xy 340.609304 -238.540234)
			(xy 340.651188 -238.569144) (xy 340.687892 -238.604399) (xy 340.718465 -238.645085) (xy 340.742116 -238.690148)
			(xy 340.758232 -238.738422) (xy 340.766396 -238.788656) (xy 340.766908 -238.814102) (xy 341.085182 -238.814102)
			(xy 341.089142 -238.765048) (xy 341.100919 -238.717264) (xy 341.12021 -238.671988) (xy 341.146513 -238.630392)
			(xy 341.179148 -238.593555) (xy 341.217269 -238.56243) (xy 341.25989 -238.537823) (xy 341.305906 -238.520371)
			(xy 341.354125 -238.510527) (xy 341.4033 -238.508546) (xy 341.452155 -238.514478) (xy 341.499426 -238.52817)
			(xy 341.543888 -238.549268) (xy 341.584391 -238.577224) (xy 341.619884 -238.611316) (xy 341.649449 -238.65066)
			(xy 341.67232 -238.694237) (xy 341.687904 -238.740918) (xy 341.695799 -238.789495) (xy 341.696294 -238.814102)
			(xy 342.014805 -238.814102) (xy 342.0189 -238.763374) (xy 342.031079 -238.71396) (xy 342.051027 -238.66714)
			(xy 342.078228 -238.624126) (xy 342.111976 -238.586032) (xy 342.151398 -238.553845) (xy 342.195472 -238.528399)
			(xy 342.243058 -238.510352) (xy 342.292922 -238.500172) (xy 342.343774 -238.498123) (xy 342.394295 -238.504257)
			(xy 342.443179 -238.518417) (xy 342.489158 -238.540234) (xy 342.531042 -238.569144) (xy 342.567746 -238.604399)
			(xy 342.598319 -238.645085) (xy 342.62197 -238.690148) (xy 342.638086 -238.738422) (xy 342.64625 -238.788656)
			(xy 342.646762 -238.814102) (xy 342.64625 -238.839548) (xy 342.638086 -238.889782) (xy 342.62197 -238.938056)
			(xy 342.598319 -238.983119) (xy 342.567746 -239.023805) (xy 342.531042 -239.05906) (xy 342.489158 -239.08797)
			(xy 342.443179 -239.109787) (xy 342.394295 -239.123947) (xy 342.343774 -239.130081) (xy 342.292922 -239.128032)
			(xy 342.243058 -239.117852) (xy 342.195472 -239.099805) (xy 342.151398 -239.074359) (xy 342.111976 -239.042172)
			(xy 342.078228 -239.004078) (xy 342.051027 -238.961064) (xy 342.031079 -238.914244) (xy 342.0189 -238.86483)
			(xy 342.014805 -238.814102) (xy 341.696294 -238.814102) (xy 341.695799 -238.838709) (xy 341.687904 -238.887286)
			(xy 341.67232 -238.933967) (xy 341.649449 -238.977544) (xy 341.619884 -239.016888) (xy 341.584391 -239.05098)
			(xy 341.543888 -239.078936) (xy 341.499426 -239.100034) (xy 341.452155 -239.113726) (xy 341.4033 -239.119658)
			(xy 341.354125 -239.117677) (xy 341.305906 -239.107833) (xy 341.25989 -239.090381) (xy 341.217269 -239.065774)
			(xy 341.179148 -239.034649) (xy 341.146513 -238.997812) (xy 341.12021 -238.956216) (xy 341.100919 -238.91094)
			(xy 341.089142 -238.863156) (xy 341.085182 -238.814102) (xy 340.766908 -238.814102) (xy 340.766396 -238.839548)
			(xy 340.758232 -238.889782) (xy 340.742116 -238.938056) (xy 340.718465 -238.983119) (xy 340.687892 -239.023805)
			(xy 340.651188 -239.05906) (xy 340.609304 -239.08797) (xy 340.563325 -239.109787) (xy 340.514441 -239.123947)
			(xy 340.46392 -239.130081) (xy 340.413068 -239.128032) (xy 340.363204 -239.117852) (xy 340.315618 -239.099805)
			(xy 340.271544 -239.074359) (xy 340.232122 -239.042172) (xy 340.198374 -239.004078) (xy 340.171173 -238.961064)
			(xy 340.151225 -238.914244) (xy 340.139046 -238.86483) (xy 340.134951 -238.814102) (xy 339.81644 -238.814102)
			(xy 339.815945 -238.838709) (xy 339.80805 -238.887286) (xy 339.792466 -238.933967) (xy 339.769595 -238.977544)
			(xy 339.74003 -239.016888) (xy 339.704537 -239.05098) (xy 339.664034 -239.078936) (xy 339.619572 -239.100034)
			(xy 339.572301 -239.113726) (xy 339.523446 -239.119658) (xy 339.474271 -239.117677) (xy 339.426052 -239.107833)
			(xy 339.380036 -239.090381) (xy 339.337415 -239.065774) (xy 339.299294 -239.034649) (xy 339.266659 -238.997812)
			(xy 339.240356 -238.956216) (xy 339.221065 -238.91094) (xy 339.209288 -238.863156) (xy 339.205328 -238.814102)
			(xy 338.8868 -238.814102) (xy 338.886288 -238.839548) (xy 338.878124 -238.889782) (xy 338.862008 -238.938056)
			(xy 338.838357 -238.983119) (xy 338.807784 -239.023805) (xy 338.77108 -239.05906) (xy 338.729196 -239.08797)
			(xy 338.683217 -239.109787) (xy 338.634333 -239.123947) (xy 338.583812 -239.130081) (xy 338.53296 -239.128032)
			(xy 338.483096 -239.117852) (xy 338.43551 -239.099805) (xy 338.391436 -239.074359) (xy 338.352014 -239.042172)
			(xy 338.318266 -239.004078) (xy 338.291065 -238.961064) (xy 338.271117 -238.914244) (xy 338.258938 -238.86483)
			(xy 338.254843 -238.814102) (xy 337.936332 -238.814102) (xy 337.935837 -238.838709) (xy 337.927942 -238.887286)
			(xy 337.912358 -238.933967) (xy 337.889487 -238.977544) (xy 337.859922 -239.016888) (xy 337.824429 -239.05098)
			(xy 337.783926 -239.078936) (xy 337.739464 -239.100034) (xy 337.692193 -239.113726) (xy 337.643338 -239.119658)
			(xy 337.594163 -239.117677) (xy 337.545944 -239.107833) (xy 337.499928 -239.090381) (xy 337.457307 -239.065774)
			(xy 337.419186 -239.034649) (xy 337.386551 -238.997812) (xy 337.360248 -238.956216) (xy 337.340957 -238.91094)
			(xy 337.32918 -238.863156) (xy 337.32522 -238.814102) (xy 336.996532 -238.814102) (xy 336.996037 -238.838709)
			(xy 336.988142 -238.887286) (xy 336.972558 -238.933967) (xy 336.949687 -238.977544) (xy 336.920122 -239.016888)
			(xy 336.884629 -239.05098) (xy 336.844126 -239.078936) (xy 336.799664 -239.100034) (xy 336.752393 -239.113726)
			(xy 336.703538 -239.119658) (xy 336.654363 -239.117677) (xy 336.606144 -239.107833) (xy 336.560128 -239.090381)
			(xy 336.517507 -239.065774) (xy 336.479386 -239.034649) (xy 336.446751 -238.997812) (xy 336.420448 -238.956216)
			(xy 336.401157 -238.91094) (xy 336.38938 -238.863156) (xy 336.38542 -238.814102) (xy 336.056478 -238.814102)
			(xy 336.055983 -238.838709) (xy 336.048088 -238.887286) (xy 336.032504 -238.933967) (xy 336.009633 -238.977544)
			(xy 335.980068 -239.016888) (xy 335.944575 -239.05098) (xy 335.904072 -239.078936) (xy 335.85961 -239.100034)
			(xy 335.812339 -239.113726) (xy 335.763484 -239.119658) (xy 335.714309 -239.117677) (xy 335.66609 -239.107833)
			(xy 335.620074 -239.090381) (xy 335.577453 -239.065774) (xy 335.539332 -239.034649) (xy 335.506697 -238.997812)
			(xy 335.480394 -238.956216) (xy 335.461103 -238.91094) (xy 335.449326 -238.863156) (xy 335.445366 -238.814102)
			(xy 335.116929 -238.814102) (xy 335.112758 -238.864436) (xy 335.100359 -238.913399) (xy 335.080071 -238.959654)
			(xy 335.052446 -239.001939) (xy 335.018239 -239.0391) (xy 334.978381 -239.070124) (xy 334.933961 -239.094165)
			(xy 334.88619 -239.110567) (xy 334.83637 -239.118883) (xy 334.811116 -239.11941) (xy 334.787545 -239.118975)
			(xy 334.740961 -239.111738) (xy 334.696041 -239.097433) (xy 334.653851 -239.076401) (xy 334.61539 -239.049139)
			(xy 334.581573 -239.016294) (xy 334.567022 -238.997744) (xy 334.56499 -238.99495) (xy 334.55991 -238.98987)
			(xy 334.553347 -238.983745) (xy 334.537075 -238.976189) (xy 334.52816 -238.975138) (xy 334.522572 -238.97463)
			(xy 334.432148 -238.986822) (xy 334.423229 -238.988367) (xy 334.407236 -238.996817) (xy 334.395174 -239.010296)
			(xy 334.391508 -239.018572) (xy 334.383585 -239.038279) (xy 334.365149 -239.076547) (xy 334.354678 -239.095026)
			(xy 334.312768 -239.167162) (xy 334.311498 -239.16894) (xy 334.303878 -239.18037) (xy 334.3021 -239.207548)
			(xy 334.338676 -239.28197) (xy 334.341556 -239.2873) (xy 334.34939 -239.296536) (xy 334.35417 -239.300258)
			(xy 334.382618 -239.32134) (xy 334.394302 -239.323372) (xy 334.417563 -239.327928) (xy 334.462407 -239.343273)
			(xy 334.504341 -239.365365) (xy 334.542357 -239.393672) (xy 334.57554 -239.427515) (xy 334.603094 -239.466081)
			(xy 334.624356 -239.508441) (xy 334.638816 -239.553579) (xy 334.646125 -239.600409) (xy 334.646524 -239.624108)
			(xy 334.975212 -239.624108) (xy 334.979172 -239.575054) (xy 334.990949 -239.52727) (xy 335.01024 -239.481994)
			(xy 335.036543 -239.440398) (xy 335.069178 -239.403561) (xy 335.107299 -239.372436) (xy 335.14992 -239.347829)
			(xy 335.195936 -239.330377) (xy 335.244155 -239.320533) (xy 335.29333 -239.318552) (xy 335.342185 -239.324484)
			(xy 335.389456 -239.338176) (xy 335.433918 -239.359274) (xy 335.474421 -239.38723) (xy 335.509914 -239.421322)
			(xy 335.539479 -239.460666) (xy 335.56235 -239.504243) (xy 335.577934 -239.550924) (xy 335.585829 -239.599501)
			(xy 335.586324 -239.624108) (xy 335.915266 -239.624108) (xy 335.919226 -239.575054) (xy 335.931003 -239.52727)
			(xy 335.950294 -239.481994) (xy 335.976597 -239.440398) (xy 336.009232 -239.403561) (xy 336.047353 -239.372436)
			(xy 336.089974 -239.347829) (xy 336.13599 -239.330377) (xy 336.184209 -239.320533) (xy 336.233384 -239.318552)
			(xy 336.282239 -239.324484) (xy 336.32951 -239.338176) (xy 336.373972 -239.359274) (xy 336.414475 -239.38723)
			(xy 336.449968 -239.421322) (xy 336.479533 -239.460666) (xy 336.502404 -239.504243) (xy 336.517988 -239.550924)
			(xy 336.525883 -239.599501) (xy 336.526378 -239.624108) (xy 336.85532 -239.624108) (xy 336.85928 -239.575054)
			(xy 336.871057 -239.52727) (xy 336.890348 -239.481994) (xy 336.916651 -239.440398) (xy 336.949286 -239.403561)
			(xy 336.987407 -239.372436) (xy 337.030028 -239.347829) (xy 337.076044 -239.330377) (xy 337.124263 -239.320533)
			(xy 337.173438 -239.318552) (xy 337.222293 -239.324484) (xy 337.269564 -239.338176) (xy 337.314026 -239.359274)
			(xy 337.354529 -239.38723) (xy 337.390022 -239.421322) (xy 337.419587 -239.460666) (xy 337.442458 -239.504243)
			(xy 337.458042 -239.550924) (xy 337.465937 -239.599501) (xy 337.466432 -239.624108) (xy 337.795374 -239.624108)
			(xy 337.799334 -239.575054) (xy 337.811111 -239.52727) (xy 337.830402 -239.481994) (xy 337.856705 -239.440398)
			(xy 337.88934 -239.403561) (xy 337.927461 -239.372436) (xy 337.970082 -239.347829) (xy 338.016098 -239.330377)
			(xy 338.064317 -239.320533) (xy 338.113492 -239.318552) (xy 338.162347 -239.324484) (xy 338.209618 -239.338176)
			(xy 338.25408 -239.359274) (xy 338.294583 -239.38723) (xy 338.330076 -239.421322) (xy 338.359641 -239.460666)
			(xy 338.382512 -239.504243) (xy 338.398096 -239.550924) (xy 338.405991 -239.599501) (xy 338.406486 -239.624108)
			(xy 338.724743 -239.624108) (xy 338.728838 -239.57338) (xy 338.741017 -239.523966) (xy 338.760965 -239.477146)
			(xy 338.788166 -239.434132) (xy 338.821914 -239.396038) (xy 338.861336 -239.363851) (xy 338.90541 -239.338405)
			(xy 338.952996 -239.320358) (xy 339.00286 -239.310178) (xy 339.053712 -239.308129) (xy 339.104233 -239.314263)
			(xy 339.153117 -239.328423) (xy 339.199096 -239.35024) (xy 339.24098 -239.37915) (xy 339.277684 -239.414405)
			(xy 339.308257 -239.455091) (xy 339.331908 -239.500154) (xy 339.348024 -239.548428) (xy 339.356188 -239.598662)
			(xy 339.3567 -239.624108) (xy 339.664797 -239.624108) (xy 339.668892 -239.57338) (xy 339.681071 -239.523966)
			(xy 339.701019 -239.477146) (xy 339.72822 -239.434132) (xy 339.761968 -239.396038) (xy 339.80139 -239.363851)
			(xy 339.845464 -239.338405) (xy 339.89305 -239.320358) (xy 339.942914 -239.310178) (xy 339.993766 -239.308129)
			(xy 340.044287 -239.314263) (xy 340.093171 -239.328423) (xy 340.13915 -239.35024) (xy 340.181034 -239.37915)
			(xy 340.217738 -239.414405) (xy 340.248311 -239.455091) (xy 340.271962 -239.500154) (xy 340.288078 -239.548428)
			(xy 340.296242 -239.598662) (xy 340.296754 -239.624108) (xy 340.615282 -239.624108) (xy 340.619242 -239.575054)
			(xy 340.631019 -239.52727) (xy 340.65031 -239.481994) (xy 340.676613 -239.440398) (xy 340.709248 -239.403561)
			(xy 340.747369 -239.372436) (xy 340.78999 -239.347829) (xy 340.836006 -239.330377) (xy 340.884225 -239.320533)
			(xy 340.9334 -239.318552) (xy 340.982255 -239.324484) (xy 341.029526 -239.338176) (xy 341.073988 -239.359274)
			(xy 341.114491 -239.38723) (xy 341.149984 -239.421322) (xy 341.179549 -239.460666) (xy 341.20242 -239.504243)
			(xy 341.218004 -239.550924) (xy 341.225899 -239.599501) (xy 341.226394 -239.624108) (xy 341.544905 -239.624108)
			(xy 341.549 -239.57338) (xy 341.561179 -239.523966) (xy 341.581127 -239.477146) (xy 341.608328 -239.434132)
			(xy 341.642076 -239.396038) (xy 341.681498 -239.363851) (xy 341.725572 -239.338405) (xy 341.773158 -239.320358)
			(xy 341.823022 -239.310178) (xy 341.873874 -239.308129) (xy 341.924395 -239.314263) (xy 341.973279 -239.328423)
			(xy 342.019258 -239.35024) (xy 342.061142 -239.37915) (xy 342.097846 -239.414405) (xy 342.128419 -239.455091)
			(xy 342.15207 -239.500154) (xy 342.168186 -239.548428) (xy 342.17635 -239.598662) (xy 342.176862 -239.624108)
			(xy 342.49539 -239.624108) (xy 342.49935 -239.575054) (xy 342.511127 -239.52727) (xy 342.530418 -239.481994)
			(xy 342.556721 -239.440398) (xy 342.589356 -239.403561) (xy 342.627477 -239.372436) (xy 342.670098 -239.347829)
			(xy 342.716114 -239.330377) (xy 342.764333 -239.320533) (xy 342.813508 -239.318552) (xy 342.862363 -239.324484)
			(xy 342.909634 -239.338176) (xy 342.954096 -239.359274) (xy 342.994599 -239.38723) (xy 343.030092 -239.421322)
			(xy 343.059657 -239.460666) (xy 343.082528 -239.504243) (xy 343.098112 -239.550924) (xy 343.106007 -239.599501)
			(xy 343.106502 -239.624108) (xy 343.106007 -239.648715) (xy 343.098112 -239.697292) (xy 343.082528 -239.743973)
			(xy 343.059657 -239.78755) (xy 343.030092 -239.826894) (xy 342.994599 -239.860986) (xy 342.954096 -239.888942)
			(xy 342.909634 -239.91004) (xy 342.862363 -239.923732) (xy 342.813508 -239.929664) (xy 342.764333 -239.927683)
			(xy 342.716114 -239.917839) (xy 342.670098 -239.900387) (xy 342.627477 -239.87578) (xy 342.589356 -239.844655)
			(xy 342.556721 -239.807818) (xy 342.530418 -239.766222) (xy 342.511127 -239.720946) (xy 342.49935 -239.673162)
			(xy 342.49539 -239.624108) (xy 342.176862 -239.624108) (xy 342.17635 -239.649554) (xy 342.168186 -239.699788)
			(xy 342.15207 -239.748062) (xy 342.128419 -239.793125) (xy 342.097846 -239.833811) (xy 342.061142 -239.869066)
			(xy 342.019258 -239.897976) (xy 341.973279 -239.919793) (xy 341.924395 -239.933953) (xy 341.873874 -239.940087)
			(xy 341.823022 -239.938038) (xy 341.773158 -239.927858) (xy 341.725572 -239.909811) (xy 341.681498 -239.884365)
			(xy 341.642076 -239.852178) (xy 341.608328 -239.814084) (xy 341.581127 -239.77107) (xy 341.561179 -239.72425)
			(xy 341.549 -239.674836) (xy 341.544905 -239.624108) (xy 341.226394 -239.624108) (xy 341.225899 -239.648715)
			(xy 341.218004 -239.697292) (xy 341.20242 -239.743973) (xy 341.179549 -239.78755) (xy 341.149984 -239.826894)
			(xy 341.114491 -239.860986) (xy 341.073988 -239.888942) (xy 341.029526 -239.91004) (xy 340.982255 -239.923732)
			(xy 340.9334 -239.929664) (xy 340.884225 -239.927683) (xy 340.836006 -239.917839) (xy 340.78999 -239.900387)
			(xy 340.747369 -239.87578) (xy 340.709248 -239.844655) (xy 340.676613 -239.807818) (xy 340.65031 -239.766222)
			(xy 340.631019 -239.720946) (xy 340.619242 -239.673162) (xy 340.615282 -239.624108) (xy 340.296754 -239.624108)
			(xy 340.296242 -239.649554) (xy 340.288078 -239.699788) (xy 340.271962 -239.748062) (xy 340.248311 -239.793125)
			(xy 340.217738 -239.833811) (xy 340.181034 -239.869066) (xy 340.13915 -239.897976) (xy 340.093171 -239.919793)
			(xy 340.044287 -239.933953) (xy 339.993766 -239.940087) (xy 339.942914 -239.938038) (xy 339.89305 -239.927858)
			(xy 339.845464 -239.909811) (xy 339.80139 -239.884365) (xy 339.761968 -239.852178) (xy 339.72822 -239.814084)
			(xy 339.701019 -239.77107) (xy 339.681071 -239.72425) (xy 339.668892 -239.674836) (xy 339.664797 -239.624108)
			(xy 339.3567 -239.624108) (xy 339.356188 -239.649554) (xy 339.348024 -239.699788) (xy 339.331908 -239.748062)
			(xy 339.308257 -239.793125) (xy 339.277684 -239.833811) (xy 339.24098 -239.869066) (xy 339.199096 -239.897976)
			(xy 339.153117 -239.919793) (xy 339.104233 -239.933953) (xy 339.053712 -239.940087) (xy 339.00286 -239.938038)
			(xy 338.952996 -239.927858) (xy 338.90541 -239.909811) (xy 338.861336 -239.884365) (xy 338.821914 -239.852178)
			(xy 338.788166 -239.814084) (xy 338.760965 -239.77107) (xy 338.741017 -239.72425) (xy 338.728838 -239.674836)
			(xy 338.724743 -239.624108) (xy 338.406486 -239.624108) (xy 338.405991 -239.648715) (xy 338.398096 -239.697292)
			(xy 338.382512 -239.743973) (xy 338.359641 -239.78755) (xy 338.330076 -239.826894) (xy 338.294583 -239.860986)
			(xy 338.25408 -239.888942) (xy 338.209618 -239.91004) (xy 338.162347 -239.923732) (xy 338.113492 -239.929664)
			(xy 338.064317 -239.927683) (xy 338.016098 -239.917839) (xy 337.970082 -239.900387) (xy 337.927461 -239.87578)
			(xy 337.88934 -239.844655) (xy 337.856705 -239.807818) (xy 337.830402 -239.766222) (xy 337.811111 -239.720946)
			(xy 337.799334 -239.673162) (xy 337.795374 -239.624108) (xy 337.466432 -239.624108) (xy 337.465937 -239.648715)
			(xy 337.458042 -239.697292) (xy 337.442458 -239.743973) (xy 337.419587 -239.78755) (xy 337.390022 -239.826894)
			(xy 337.354529 -239.860986) (xy 337.314026 -239.888942) (xy 337.269564 -239.91004) (xy 337.222293 -239.923732)
			(xy 337.173438 -239.929664) (xy 337.124263 -239.927683) (xy 337.076044 -239.917839) (xy 337.030028 -239.900387)
			(xy 336.987407 -239.87578) (xy 336.949286 -239.844655) (xy 336.916651 -239.807818) (xy 336.890348 -239.766222)
			(xy 336.871057 -239.720946) (xy 336.85928 -239.673162) (xy 336.85532 -239.624108) (xy 336.526378 -239.624108)
			(xy 336.525883 -239.648715) (xy 336.517988 -239.697292) (xy 336.502404 -239.743973) (xy 336.479533 -239.78755)
			(xy 336.449968 -239.826894) (xy 336.414475 -239.860986) (xy 336.373972 -239.888942) (xy 336.32951 -239.91004)
			(xy 336.282239 -239.923732) (xy 336.233384 -239.929664) (xy 336.184209 -239.927683) (xy 336.13599 -239.917839)
			(xy 336.089974 -239.900387) (xy 336.047353 -239.87578) (xy 336.009232 -239.844655) (xy 335.976597 -239.807818)
			(xy 335.950294 -239.766222) (xy 335.931003 -239.720946) (xy 335.919226 -239.673162) (xy 335.915266 -239.624108)
			(xy 335.586324 -239.624108) (xy 335.585829 -239.648715) (xy 335.577934 -239.697292) (xy 335.56235 -239.743973)
			(xy 335.539479 -239.78755) (xy 335.509914 -239.826894) (xy 335.474421 -239.860986) (xy 335.433918 -239.888942)
			(xy 335.389456 -239.91004) (xy 335.342185 -239.923732) (xy 335.29333 -239.929664) (xy 335.244155 -239.927683)
			(xy 335.195936 -239.917839) (xy 335.14992 -239.900387) (xy 335.107299 -239.87578) (xy 335.069178 -239.844655)
			(xy 335.036543 -239.807818) (xy 335.01024 -239.766222) (xy 334.990949 -239.720946) (xy 334.979172 -239.673162)
			(xy 334.975212 -239.624108) (xy 334.646524 -239.624108) (xy 334.646053 -239.648099) (xy 334.638546 -239.695491)
			(xy 334.623718 -239.741125) (xy 334.601934 -239.783878) (xy 334.573731 -239.822696) (xy 334.539803 -239.856626)
			(xy 334.500984 -239.88483) (xy 334.458232 -239.906615) (xy 334.412599 -239.921444) (xy 334.365207 -239.928952)
			(xy 334.341216 -239.929416) (xy 334.309466 -239.927638) (xy 334.306672 -239.927384) (xy 334.304132 -239.927384)
			(xy 334.294105 -239.927798) (xy 334.275575 -239.935462) (xy 334.261389 -239.949634) (xy 334.253707 -239.968158)
			(xy 334.253332 -239.978184) (xy 334.253332 -239.998504) (xy 334.254094 -240.007394) (xy 334.255364 -240.014252)
			(xy 334.25697 -240.021863) (xy 334.26409 -240.035684) (xy 334.269334 -240.04143) (xy 334.269588 -240.041684)
			(xy 334.274922 -240.047272) (xy 334.298192 -240.072301) (xy 334.339094 -240.127051) (xy 334.373001 -240.186389)
			(xy 334.386682 -240.217706) (xy 334.389222 -240.223802) (xy 334.396842 -240.233962) (xy 334.421226 -240.253012)
			(xy 334.426703 -240.256968) (xy 334.439192 -240.262108) (xy 334.445864 -240.263172) (xy 334.516984 -240.272824)
			(xy 334.522959 -240.273442) (xy 334.5349 -240.272162) (xy 334.540606 -240.270284) (xy 334.551782 -240.266474)
			(xy 334.56499 -240.253266) (xy 334.567022 -240.250472) (xy 334.581567 -240.231919) (xy 334.615397 -240.199088)
			(xy 334.653861 -240.171834) (xy 334.69605 -240.1508) (xy 334.740966 -240.136486) (xy 334.787545 -240.129228)
			(xy 334.811116 -240.128806) (xy 334.836369 -240.129329) (xy 334.886187 -240.137644) (xy 334.933956 -240.154046)
			(xy 334.978375 -240.178086) (xy 335.01823 -240.209109) (xy 335.052437 -240.246269) (xy 335.08006 -240.288552)
			(xy 335.100348 -240.334805) (xy 335.112746 -240.383766) (xy 335.116917 -240.4341) (xy 335.116916 -240.434114)
			(xy 335.445366 -240.434114) (xy 335.449326 -240.38506) (xy 335.461103 -240.337276) (xy 335.480394 -240.292)
			(xy 335.506697 -240.250404) (xy 335.539332 -240.213567) (xy 335.577453 -240.182442) (xy 335.620074 -240.157835)
			(xy 335.66609 -240.140383) (xy 335.714309 -240.130539) (xy 335.763484 -240.128558) (xy 335.812339 -240.13449)
			(xy 335.85961 -240.148182) (xy 335.904072 -240.16928) (xy 335.944575 -240.197236) (xy 335.980068 -240.231328)
			(xy 336.009633 -240.270672) (xy 336.032504 -240.314249) (xy 336.048088 -240.36093) (xy 336.055983 -240.409507)
			(xy 336.056478 -240.434114) (xy 336.38542 -240.434114) (xy 336.38938 -240.38506) (xy 336.401157 -240.337276)
			(xy 336.420448 -240.292) (xy 336.446751 -240.250404) (xy 336.479386 -240.213567) (xy 336.517507 -240.182442)
			(xy 336.560128 -240.157835) (xy 336.606144 -240.140383) (xy 336.654363 -240.130539) (xy 336.703538 -240.128558)
			(xy 336.752393 -240.13449) (xy 336.799664 -240.148182) (xy 336.844126 -240.16928) (xy 336.884629 -240.197236)
			(xy 336.920122 -240.231328) (xy 336.949687 -240.270672) (xy 336.972558 -240.314249) (xy 336.988142 -240.36093)
			(xy 336.996037 -240.409507) (xy 336.996532 -240.434114) (xy 337.32522 -240.434114) (xy 337.32918 -240.38506)
			(xy 337.340957 -240.337276) (xy 337.360248 -240.292) (xy 337.386551 -240.250404) (xy 337.419186 -240.213567)
			(xy 337.457307 -240.182442) (xy 337.499928 -240.157835) (xy 337.545944 -240.140383) (xy 337.594163 -240.130539)
			(xy 337.643338 -240.128558) (xy 337.692193 -240.13449) (xy 337.739464 -240.148182) (xy 337.783926 -240.16928)
			(xy 337.824429 -240.197236) (xy 337.859922 -240.231328) (xy 337.889487 -240.270672) (xy 337.912358 -240.314249)
			(xy 337.927942 -240.36093) (xy 337.935837 -240.409507) (xy 337.936332 -240.434114) (xy 338.254843 -240.434114)
			(xy 338.258938 -240.383386) (xy 338.271117 -240.333972) (xy 338.291065 -240.287152) (xy 338.318266 -240.244138)
			(xy 338.352014 -240.206044) (xy 338.391436 -240.173857) (xy 338.43551 -240.148411) (xy 338.483096 -240.130364)
			(xy 338.53296 -240.120184) (xy 338.583812 -240.118135) (xy 338.634333 -240.124269) (xy 338.683217 -240.138429)
			(xy 338.729196 -240.160246) (xy 338.77108 -240.189156) (xy 338.807784 -240.224411) (xy 338.838357 -240.265097)
			(xy 338.862008 -240.31016) (xy 338.878124 -240.358434) (xy 338.886288 -240.408668) (xy 338.8868 -240.434114)
			(xy 339.205328 -240.434114) (xy 339.209288 -240.38506) (xy 339.221065 -240.337276) (xy 339.240356 -240.292)
			(xy 339.266659 -240.250404) (xy 339.299294 -240.213567) (xy 339.337415 -240.182442) (xy 339.380036 -240.157835)
			(xy 339.426052 -240.140383) (xy 339.474271 -240.130539) (xy 339.523446 -240.128558) (xy 339.572301 -240.13449)
			(xy 339.619572 -240.148182) (xy 339.664034 -240.16928) (xy 339.704537 -240.197236) (xy 339.74003 -240.231328)
			(xy 339.769595 -240.270672) (xy 339.792466 -240.314249) (xy 339.80805 -240.36093) (xy 339.815945 -240.409507)
			(xy 339.81644 -240.434114) (xy 340.134951 -240.434114) (xy 340.139046 -240.383386) (xy 340.151225 -240.333972)
			(xy 340.171173 -240.287152) (xy 340.198374 -240.244138) (xy 340.232122 -240.206044) (xy 340.271544 -240.173857)
			(xy 340.315618 -240.148411) (xy 340.363204 -240.130364) (xy 340.413068 -240.120184) (xy 340.46392 -240.118135)
			(xy 340.514441 -240.124269) (xy 340.563325 -240.138429) (xy 340.609304 -240.160246) (xy 340.651188 -240.189156)
			(xy 340.687892 -240.224411) (xy 340.718465 -240.265097) (xy 340.742116 -240.31016) (xy 340.758232 -240.358434)
			(xy 340.766396 -240.408668) (xy 340.766908 -240.434114) (xy 341.085182 -240.434114) (xy 341.089142 -240.38506)
			(xy 341.100919 -240.337276) (xy 341.12021 -240.292) (xy 341.146513 -240.250404) (xy 341.179148 -240.213567)
			(xy 341.217269 -240.182442) (xy 341.25989 -240.157835) (xy 341.305906 -240.140383) (xy 341.354125 -240.130539)
			(xy 341.4033 -240.128558) (xy 341.452155 -240.13449) (xy 341.499426 -240.148182) (xy 341.543888 -240.16928)
			(xy 341.584391 -240.197236) (xy 341.619884 -240.231328) (xy 341.649449 -240.270672) (xy 341.67232 -240.314249)
			(xy 341.687904 -240.36093) (xy 341.695799 -240.409507) (xy 341.696294 -240.434114) (xy 342.014805 -240.434114)
			(xy 342.0189 -240.383386) (xy 342.031079 -240.333972) (xy 342.051027 -240.287152) (xy 342.078228 -240.244138)
			(xy 342.111976 -240.206044) (xy 342.151398 -240.173857) (xy 342.195472 -240.148411) (xy 342.243058 -240.130364)
			(xy 342.292922 -240.120184) (xy 342.343774 -240.118135) (xy 342.394295 -240.124269) (xy 342.443179 -240.138429)
			(xy 342.489158 -240.160246) (xy 342.531042 -240.189156) (xy 342.567746 -240.224411) (xy 342.598319 -240.265097)
			(xy 342.62197 -240.31016) (xy 342.638086 -240.358434) (xy 342.64625 -240.408668) (xy 342.646762 -240.434114)
			(xy 342.64625 -240.45956) (xy 342.638086 -240.509794) (xy 342.62197 -240.558068) (xy 342.598319 -240.603131)
			(xy 342.567746 -240.643817) (xy 342.531042 -240.679072) (xy 342.489158 -240.707982) (xy 342.443179 -240.729799)
			(xy 342.394295 -240.743959) (xy 342.343774 -240.750093) (xy 342.292922 -240.748044) (xy 342.243058 -240.737864)
			(xy 342.195472 -240.719817) (xy 342.151398 -240.694371) (xy 342.111976 -240.662184) (xy 342.078228 -240.62409)
			(xy 342.051027 -240.581076) (xy 342.031079 -240.534256) (xy 342.0189 -240.484842) (xy 342.014805 -240.434114)
			(xy 341.696294 -240.434114) (xy 341.695799 -240.458721) (xy 341.687904 -240.507298) (xy 341.67232 -240.553979)
			(xy 341.649449 -240.597556) (xy 341.619884 -240.6369) (xy 341.584391 -240.670992) (xy 341.543888 -240.698948)
			(xy 341.499426 -240.720046) (xy 341.452155 -240.733738) (xy 341.4033 -240.73967) (xy 341.354125 -240.737689)
			(xy 341.305906 -240.727845) (xy 341.25989 -240.710393) (xy 341.217269 -240.685786) (xy 341.179148 -240.654661)
			(xy 341.146513 -240.617824) (xy 341.12021 -240.576228) (xy 341.100919 -240.530952) (xy 341.089142 -240.483168)
			(xy 341.085182 -240.434114) (xy 340.766908 -240.434114) (xy 340.766396 -240.45956) (xy 340.758232 -240.509794)
			(xy 340.742116 -240.558068) (xy 340.718465 -240.603131) (xy 340.687892 -240.643817) (xy 340.651188 -240.679072)
			(xy 340.609304 -240.707982) (xy 340.563325 -240.729799) (xy 340.514441 -240.743959) (xy 340.46392 -240.750093)
			(xy 340.413068 -240.748044) (xy 340.363204 -240.737864) (xy 340.315618 -240.719817) (xy 340.271544 -240.694371)
			(xy 340.232122 -240.662184) (xy 340.198374 -240.62409) (xy 340.171173 -240.581076) (xy 340.151225 -240.534256)
			(xy 340.139046 -240.484842) (xy 340.134951 -240.434114) (xy 339.81644 -240.434114) (xy 339.815945 -240.458721)
			(xy 339.80805 -240.507298) (xy 339.792466 -240.553979) (xy 339.769595 -240.597556) (xy 339.74003 -240.6369)
			(xy 339.704537 -240.670992) (xy 339.664034 -240.698948) (xy 339.619572 -240.720046) (xy 339.572301 -240.733738)
			(xy 339.523446 -240.73967) (xy 339.474271 -240.737689) (xy 339.426052 -240.727845) (xy 339.380036 -240.710393)
			(xy 339.337415 -240.685786) (xy 339.299294 -240.654661) (xy 339.266659 -240.617824) (xy 339.240356 -240.576228)
			(xy 339.221065 -240.530952) (xy 339.209288 -240.483168) (xy 339.205328 -240.434114) (xy 338.8868 -240.434114)
			(xy 338.886288 -240.45956) (xy 338.878124 -240.509794) (xy 338.862008 -240.558068) (xy 338.838357 -240.603131)
			(xy 338.807784 -240.643817) (xy 338.77108 -240.679072) (xy 338.729196 -240.707982) (xy 338.683217 -240.729799)
			(xy 338.634333 -240.743959) (xy 338.583812 -240.750093) (xy 338.53296 -240.748044) (xy 338.483096 -240.737864)
			(xy 338.43551 -240.719817) (xy 338.391436 -240.694371) (xy 338.352014 -240.662184) (xy 338.318266 -240.62409)
			(xy 338.291065 -240.581076) (xy 338.271117 -240.534256) (xy 338.258938 -240.484842) (xy 338.254843 -240.434114)
			(xy 337.936332 -240.434114) (xy 337.935837 -240.458721) (xy 337.927942 -240.507298) (xy 337.912358 -240.553979)
			(xy 337.889487 -240.597556) (xy 337.859922 -240.6369) (xy 337.824429 -240.670992) (xy 337.783926 -240.698948)
			(xy 337.739464 -240.720046) (xy 337.692193 -240.733738) (xy 337.643338 -240.73967) (xy 337.594163 -240.737689)
			(xy 337.545944 -240.727845) (xy 337.499928 -240.710393) (xy 337.457307 -240.685786) (xy 337.419186 -240.654661)
			(xy 337.386551 -240.617824) (xy 337.360248 -240.576228) (xy 337.340957 -240.530952) (xy 337.32918 -240.483168)
			(xy 337.32522 -240.434114) (xy 336.996532 -240.434114) (xy 336.996037 -240.458721) (xy 336.988142 -240.507298)
			(xy 336.972558 -240.553979) (xy 336.949687 -240.597556) (xy 336.920122 -240.6369) (xy 336.884629 -240.670992)
			(xy 336.844126 -240.698948) (xy 336.799664 -240.720046) (xy 336.752393 -240.733738) (xy 336.703538 -240.73967)
			(xy 336.654363 -240.737689) (xy 336.606144 -240.727845) (xy 336.560128 -240.710393) (xy 336.517507 -240.685786)
			(xy 336.479386 -240.654661) (xy 336.446751 -240.617824) (xy 336.420448 -240.576228) (xy 336.401157 -240.530952)
			(xy 336.38938 -240.483168) (xy 336.38542 -240.434114) (xy 336.056478 -240.434114) (xy 336.055983 -240.458721)
			(xy 336.048088 -240.507298) (xy 336.032504 -240.553979) (xy 336.009633 -240.597556) (xy 335.980068 -240.6369)
			(xy 335.944575 -240.670992) (xy 335.904072 -240.698948) (xy 335.85961 -240.720046) (xy 335.812339 -240.733738)
			(xy 335.763484 -240.73967) (xy 335.714309 -240.737689) (xy 335.66609 -240.727845) (xy 335.620074 -240.710393)
			(xy 335.577453 -240.685786) (xy 335.539332 -240.654661) (xy 335.506697 -240.617824) (xy 335.480394 -240.576228)
			(xy 335.461103 -240.530952) (xy 335.449326 -240.483168) (xy 335.445366 -240.434114) (xy 335.116916 -240.434114)
			(xy 335.112746 -240.484434) (xy 335.100348 -240.533395) (xy 335.08006 -240.579648) (xy 335.052437 -240.621931)
			(xy 335.01823 -240.659091) (xy 334.978375 -240.690114) (xy 334.933956 -240.714154) (xy 334.886187 -240.730556)
			(xy 334.836369 -240.738871) (xy 334.811116 -240.739422) (xy 334.787545 -240.738987) (xy 334.740961 -240.73175)
			(xy 334.69604 -240.717446) (xy 334.653849 -240.696414) (xy 334.615388 -240.669152) (xy 334.581569 -240.636308)
			(xy 334.567022 -240.617756) (xy 334.56499 -240.614962) (xy 334.55991 -240.609882) (xy 334.553347 -240.603756)
			(xy 334.537076 -240.596198) (xy 334.52816 -240.59515) (xy 334.522572 -240.594642) (xy 334.432148 -240.606834)
			(xy 334.42323 -240.608379) (xy 334.407238 -240.61683) (xy 334.395179 -240.63031) (xy 334.391508 -240.638584)
			(xy 334.383585 -240.65829) (xy 334.365148 -240.696558) (xy 334.354678 -240.715038) (xy 334.312768 -240.787174)
			(xy 334.311498 -240.788952) (xy 334.303878 -240.800382) (xy 334.3021 -240.82756) (xy 334.338676 -240.901982)
			(xy 334.341549 -240.907318) (xy 334.349374 -240.916567) (xy 334.35417 -240.92027) (xy 334.382618 -240.941352)
			(xy 334.394302 -240.943384) (xy 334.417563 -240.94794) (xy 334.462406 -240.963285) (xy 334.504339 -240.985377)
			(xy 334.542354 -241.013685) (xy 334.575536 -241.047528) (xy 334.603088 -241.086094) (xy 334.624349 -241.128454)
			(xy 334.638807 -241.173592) (xy 334.646114 -241.220422) (xy 334.646524 -241.24412) (xy 334.975212 -241.24412)
			(xy 334.979172 -241.195066) (xy 334.990949 -241.147282) (xy 335.01024 -241.102006) (xy 335.036543 -241.06041)
			(xy 335.069178 -241.023573) (xy 335.107299 -240.992448) (xy 335.14992 -240.967841) (xy 335.195936 -240.950389)
			(xy 335.244155 -240.940545) (xy 335.29333 -240.938564) (xy 335.342185 -240.944496) (xy 335.389456 -240.958188)
			(xy 335.433918 -240.979286) (xy 335.474421 -241.007242) (xy 335.509914 -241.041334) (xy 335.539479 -241.080678)
			(xy 335.56235 -241.124255) (xy 335.577934 -241.170936) (xy 335.585829 -241.219513) (xy 335.586324 -241.24412)
			(xy 335.915266 -241.24412) (xy 335.919226 -241.195066) (xy 335.931003 -241.147282) (xy 335.950294 -241.102006)
			(xy 335.976597 -241.06041) (xy 336.009232 -241.023573) (xy 336.047353 -240.992448) (xy 336.089974 -240.967841)
			(xy 336.13599 -240.950389) (xy 336.184209 -240.940545) (xy 336.233384 -240.938564) (xy 336.282239 -240.944496)
			(xy 336.32951 -240.958188) (xy 336.373972 -240.979286) (xy 336.414475 -241.007242) (xy 336.449968 -241.041334)
			(xy 336.479533 -241.080678) (xy 336.502404 -241.124255) (xy 336.517988 -241.170936) (xy 336.525883 -241.219513)
			(xy 336.526378 -241.24412) (xy 336.85532 -241.24412) (xy 336.85928 -241.195066) (xy 336.871057 -241.147282)
			(xy 336.890348 -241.102006) (xy 336.916651 -241.06041) (xy 336.949286 -241.023573) (xy 336.987407 -240.992448)
			(xy 337.030028 -240.967841) (xy 337.076044 -240.950389) (xy 337.124263 -240.940545) (xy 337.173438 -240.938564)
			(xy 337.222293 -240.944496) (xy 337.269564 -240.958188) (xy 337.314026 -240.979286) (xy 337.354529 -241.007242)
			(xy 337.390022 -241.041334) (xy 337.419587 -241.080678) (xy 337.442458 -241.124255) (xy 337.458042 -241.170936)
			(xy 337.465937 -241.219513) (xy 337.466432 -241.24412) (xy 337.795374 -241.24412) (xy 337.799334 -241.195066)
			(xy 337.811111 -241.147282) (xy 337.830402 -241.102006) (xy 337.856705 -241.06041) (xy 337.88934 -241.023573)
			(xy 337.927461 -240.992448) (xy 337.970082 -240.967841) (xy 338.016098 -240.950389) (xy 338.064317 -240.940545)
			(xy 338.113492 -240.938564) (xy 338.162347 -240.944496) (xy 338.209618 -240.958188) (xy 338.25408 -240.979286)
			(xy 338.294583 -241.007242) (xy 338.330076 -241.041334) (xy 338.359641 -241.080678) (xy 338.382512 -241.124255)
			(xy 338.398096 -241.170936) (xy 338.405991 -241.219513) (xy 338.406486 -241.24412) (xy 338.724743 -241.24412)
			(xy 338.728838 -241.193392) (xy 338.741017 -241.143978) (xy 338.760965 -241.097158) (xy 338.788166 -241.054144)
			(xy 338.821914 -241.01605) (xy 338.861336 -240.983863) (xy 338.90541 -240.958417) (xy 338.952996 -240.94037)
			(xy 339.00286 -240.93019) (xy 339.053712 -240.928141) (xy 339.104233 -240.934275) (xy 339.153117 -240.948435)
			(xy 339.199096 -240.970252) (xy 339.24098 -240.999162) (xy 339.277684 -241.034417) (xy 339.308257 -241.075103)
			(xy 339.331908 -241.120166) (xy 339.348024 -241.16844) (xy 339.356188 -241.218674) (xy 339.3567 -241.24412)
			(xy 339.664797 -241.24412) (xy 339.668892 -241.193392) (xy 339.681071 -241.143978) (xy 339.701019 -241.097158)
			(xy 339.72822 -241.054144) (xy 339.761968 -241.01605) (xy 339.80139 -240.983863) (xy 339.845464 -240.958417)
			(xy 339.89305 -240.94037) (xy 339.942914 -240.93019) (xy 339.993766 -240.928141) (xy 340.044287 -240.934275)
			(xy 340.093171 -240.948435) (xy 340.13915 -240.970252) (xy 340.181034 -240.999162) (xy 340.217738 -241.034417)
			(xy 340.248311 -241.075103) (xy 340.271962 -241.120166) (xy 340.288078 -241.16844) (xy 340.296242 -241.218674)
			(xy 340.296754 -241.24412) (xy 340.615282 -241.24412) (xy 340.619242 -241.195066) (xy 340.631019 -241.147282)
			(xy 340.65031 -241.102006) (xy 340.676613 -241.06041) (xy 340.709248 -241.023573) (xy 340.747369 -240.992448)
			(xy 340.78999 -240.967841) (xy 340.836006 -240.950389) (xy 340.884225 -240.940545) (xy 340.9334 -240.938564)
			(xy 340.982255 -240.944496) (xy 341.029526 -240.958188) (xy 341.073988 -240.979286) (xy 341.114491 -241.007242)
			(xy 341.149984 -241.041334) (xy 341.179549 -241.080678) (xy 341.20242 -241.124255) (xy 341.218004 -241.170936)
			(xy 341.225899 -241.219513) (xy 341.226394 -241.24412) (xy 341.544905 -241.24412) (xy 341.549 -241.193392)
			(xy 341.561179 -241.143978) (xy 341.581127 -241.097158) (xy 341.608328 -241.054144) (xy 341.642076 -241.01605)
			(xy 341.681498 -240.983863) (xy 341.725572 -240.958417) (xy 341.773158 -240.94037) (xy 341.823022 -240.93019)
			(xy 341.873874 -240.928141) (xy 341.924395 -240.934275) (xy 341.973279 -240.948435) (xy 342.019258 -240.970252)
			(xy 342.061142 -240.999162) (xy 342.097846 -241.034417) (xy 342.128419 -241.075103) (xy 342.15207 -241.120166)
			(xy 342.168186 -241.16844) (xy 342.17635 -241.218674) (xy 342.176862 -241.24412) (xy 342.49539 -241.24412)
			(xy 342.49935 -241.195066) (xy 342.511127 -241.147282) (xy 342.530418 -241.102006) (xy 342.556721 -241.06041)
			(xy 342.589356 -241.023573) (xy 342.627477 -240.992448) (xy 342.670098 -240.967841) (xy 342.716114 -240.950389)
			(xy 342.764333 -240.940545) (xy 342.813508 -240.938564) (xy 342.862363 -240.944496) (xy 342.909634 -240.958188)
			(xy 342.954096 -240.979286) (xy 342.994599 -241.007242) (xy 343.030092 -241.041334) (xy 343.059657 -241.080678)
			(xy 343.082528 -241.124255) (xy 343.098112 -241.170936) (xy 343.106007 -241.219513) (xy 343.106502 -241.24412)
			(xy 343.106007 -241.268727) (xy 343.098112 -241.317304) (xy 343.082528 -241.363985) (xy 343.059657 -241.407562)
			(xy 343.030092 -241.446906) (xy 342.994599 -241.480998) (xy 342.954096 -241.508954) (xy 342.909634 -241.530052)
			(xy 342.862363 -241.543744) (xy 342.813508 -241.549676) (xy 342.764333 -241.547695) (xy 342.716114 -241.537851)
			(xy 342.670098 -241.520399) (xy 342.627477 -241.495792) (xy 342.589356 -241.464667) (xy 342.556721 -241.42783)
			(xy 342.530418 -241.386234) (xy 342.511127 -241.340958) (xy 342.49935 -241.293174) (xy 342.49539 -241.24412)
			(xy 342.176862 -241.24412) (xy 342.17635 -241.269566) (xy 342.168186 -241.3198) (xy 342.15207 -241.368074)
			(xy 342.128419 -241.413137) (xy 342.097846 -241.453823) (xy 342.061142 -241.489078) (xy 342.019258 -241.517988)
			(xy 341.973279 -241.539805) (xy 341.924395 -241.553965) (xy 341.873874 -241.560099) (xy 341.823022 -241.55805)
			(xy 341.773158 -241.54787) (xy 341.725572 -241.529823) (xy 341.681498 -241.504377) (xy 341.642076 -241.47219)
			(xy 341.608328 -241.434096) (xy 341.581127 -241.391082) (xy 341.561179 -241.344262) (xy 341.549 -241.294848)
			(xy 341.544905 -241.24412) (xy 341.226394 -241.24412) (xy 341.225899 -241.268727) (xy 341.218004 -241.317304)
			(xy 341.20242 -241.363985) (xy 341.179549 -241.407562) (xy 341.149984 -241.446906) (xy 341.114491 -241.480998)
			(xy 341.073988 -241.508954) (xy 341.029526 -241.530052) (xy 340.982255 -241.543744) (xy 340.9334 -241.549676)
			(xy 340.884225 -241.547695) (xy 340.836006 -241.537851) (xy 340.78999 -241.520399) (xy 340.747369 -241.495792)
			(xy 340.709248 -241.464667) (xy 340.676613 -241.42783) (xy 340.65031 -241.386234) (xy 340.631019 -241.340958)
			(xy 340.619242 -241.293174) (xy 340.615282 -241.24412) (xy 340.296754 -241.24412) (xy 340.296242 -241.269566)
			(xy 340.288078 -241.3198) (xy 340.271962 -241.368074) (xy 340.248311 -241.413137) (xy 340.217738 -241.453823)
			(xy 340.181034 -241.489078) (xy 340.13915 -241.517988) (xy 340.093171 -241.539805) (xy 340.044287 -241.553965)
			(xy 339.993766 -241.560099) (xy 339.942914 -241.55805) (xy 339.89305 -241.54787) (xy 339.845464 -241.529823)
			(xy 339.80139 -241.504377) (xy 339.761968 -241.47219) (xy 339.72822 -241.434096) (xy 339.701019 -241.391082)
			(xy 339.681071 -241.344262) (xy 339.668892 -241.294848) (xy 339.664797 -241.24412) (xy 339.3567 -241.24412)
			(xy 339.356188 -241.269566) (xy 339.348024 -241.3198) (xy 339.331908 -241.368074) (xy 339.308257 -241.413137)
			(xy 339.277684 -241.453823) (xy 339.24098 -241.489078) (xy 339.199096 -241.517988) (xy 339.153117 -241.539805)
			(xy 339.104233 -241.553965) (xy 339.053712 -241.560099) (xy 339.00286 -241.55805) (xy 338.952996 -241.54787)
			(xy 338.90541 -241.529823) (xy 338.861336 -241.504377) (xy 338.821914 -241.47219) (xy 338.788166 -241.434096)
			(xy 338.760965 -241.391082) (xy 338.741017 -241.344262) (xy 338.728838 -241.294848) (xy 338.724743 -241.24412)
			(xy 338.406486 -241.24412) (xy 338.405991 -241.268727) (xy 338.398096 -241.317304) (xy 338.382512 -241.363985)
			(xy 338.359641 -241.407562) (xy 338.330076 -241.446906) (xy 338.294583 -241.480998) (xy 338.25408 -241.508954)
			(xy 338.209618 -241.530052) (xy 338.162347 -241.543744) (xy 338.113492 -241.549676) (xy 338.064317 -241.547695)
			(xy 338.016098 -241.537851) (xy 337.970082 -241.520399) (xy 337.927461 -241.495792) (xy 337.88934 -241.464667)
			(xy 337.856705 -241.42783) (xy 337.830402 -241.386234) (xy 337.811111 -241.340958) (xy 337.799334 -241.293174)
			(xy 337.795374 -241.24412) (xy 337.466432 -241.24412) (xy 337.465937 -241.268727) (xy 337.458042 -241.317304)
			(xy 337.442458 -241.363985) (xy 337.419587 -241.407562) (xy 337.390022 -241.446906) (xy 337.354529 -241.480998)
			(xy 337.314026 -241.508954) (xy 337.269564 -241.530052) (xy 337.222293 -241.543744) (xy 337.173438 -241.549676)
			(xy 337.124263 -241.547695) (xy 337.076044 -241.537851) (xy 337.030028 -241.520399) (xy 336.987407 -241.495792)
			(xy 336.949286 -241.464667) (xy 336.916651 -241.42783) (xy 336.890348 -241.386234) (xy 336.871057 -241.340958)
			(xy 336.85928 -241.293174) (xy 336.85532 -241.24412) (xy 336.526378 -241.24412) (xy 336.525883 -241.268727)
			(xy 336.517988 -241.317304) (xy 336.502404 -241.363985) (xy 336.479533 -241.407562) (xy 336.449968 -241.446906)
			(xy 336.414475 -241.480998) (xy 336.373972 -241.508954) (xy 336.32951 -241.530052) (xy 336.282239 -241.543744)
			(xy 336.233384 -241.549676) (xy 336.184209 -241.547695) (xy 336.13599 -241.537851) (xy 336.089974 -241.520399)
			(xy 336.047353 -241.495792) (xy 336.009232 -241.464667) (xy 335.976597 -241.42783) (xy 335.950294 -241.386234)
			(xy 335.931003 -241.340958) (xy 335.919226 -241.293174) (xy 335.915266 -241.24412) (xy 335.586324 -241.24412)
			(xy 335.585829 -241.268727) (xy 335.577934 -241.317304) (xy 335.56235 -241.363985) (xy 335.539479 -241.407562)
			(xy 335.509914 -241.446906) (xy 335.474421 -241.480998) (xy 335.433918 -241.508954) (xy 335.389456 -241.530052)
			(xy 335.342185 -241.543744) (xy 335.29333 -241.549676) (xy 335.244155 -241.547695) (xy 335.195936 -241.537851)
			(xy 335.14992 -241.520399) (xy 335.107299 -241.495792) (xy 335.069178 -241.464667) (xy 335.036543 -241.42783)
			(xy 335.01024 -241.386234) (xy 334.990949 -241.340958) (xy 334.979172 -241.293174) (xy 334.975212 -241.24412)
			(xy 334.646524 -241.24412) (xy 334.646052 -241.268111) (xy 334.638543 -241.315501) (xy 334.623714 -241.361133)
			(xy 334.60193 -241.403884) (xy 334.573727 -241.442702) (xy 334.539798 -241.476629) (xy 334.500981 -241.504832)
			(xy 334.45823 -241.526616) (xy 334.412597 -241.541444) (xy 334.365207 -241.548952) (xy 334.341216 -241.549428)
			(xy 334.309466 -241.54765) (xy 334.306672 -241.547396) (xy 334.304132 -241.547396) (xy 334.294106 -241.54781)
			(xy 334.275578 -241.555474) (xy 334.261394 -241.569647) (xy 334.253717 -241.58817) (xy 334.253332 -241.598196)
			(xy 334.253332 -241.618516) (xy 334.254094 -241.627406) (xy 334.255364 -241.634264) (xy 334.256971 -241.641874)
			(xy 334.264094 -241.655693) (xy 334.269334 -241.661442) (xy 334.269588 -241.661696) (xy 334.274922 -241.667284)
			(xy 334.298191 -241.692313) (xy 334.339092 -241.747064) (xy 334.372998 -241.806402) (xy 334.386682 -241.837718)
			(xy 334.389222 -241.843814) (xy 334.396842 -241.853974) (xy 334.421226 -241.873024) (xy 334.426703 -241.876979)
			(xy 334.439192 -241.882118) (xy 334.445864 -241.883184) (xy 334.516984 -241.892836) (xy 334.522959 -241.893455)
			(xy 334.5349 -241.892174) (xy 334.540606 -241.890296) (xy 334.551782 -241.886486) (xy 334.56499 -241.873278)
			(xy 334.567022 -241.870484) (xy 334.581566 -241.85193) (xy 334.615396 -241.819098) (xy 334.65386 -241.791843)
			(xy 334.696049 -241.770809) (xy 334.740965 -241.756493) (xy 334.787545 -241.749236) (xy 334.811116 -241.748818)
			(xy 334.836368 -241.749341) (xy 334.886184 -241.757656) (xy 334.933951 -241.774057) (xy 334.978368 -241.798096)
			(xy 335.018222 -241.829118) (xy 335.052427 -241.866276) (xy 335.08005 -241.908557) (xy 335.100337 -241.954808)
			(xy 335.112734 -242.003768) (xy 335.116905 -242.0541) (xy 335.116903 -242.054126) (xy 335.445366 -242.054126)
			(xy 335.449326 -242.005072) (xy 335.461103 -241.957288) (xy 335.480394 -241.912012) (xy 335.506697 -241.870416)
			(xy 335.539332 -241.833579) (xy 335.577453 -241.802454) (xy 335.620074 -241.777847) (xy 335.66609 -241.760395)
			(xy 335.714309 -241.750551) (xy 335.763484 -241.74857) (xy 335.812339 -241.754502) (xy 335.85961 -241.768194)
			(xy 335.904072 -241.789292) (xy 335.944575 -241.817248) (xy 335.980068 -241.85134) (xy 336.009633 -241.890684)
			(xy 336.032504 -241.934261) (xy 336.048088 -241.980942) (xy 336.055983 -242.029519) (xy 336.056478 -242.054126)
			(xy 336.38542 -242.054126) (xy 336.38938 -242.005072) (xy 336.401157 -241.957288) (xy 336.420448 -241.912012)
			(xy 336.446751 -241.870416) (xy 336.479386 -241.833579) (xy 336.517507 -241.802454) (xy 336.560128 -241.777847)
			(xy 336.606144 -241.760395) (xy 336.654363 -241.750551) (xy 336.703538 -241.74857) (xy 336.752393 -241.754502)
			(xy 336.799664 -241.768194) (xy 336.844126 -241.789292) (xy 336.884629 -241.817248) (xy 336.920122 -241.85134)
			(xy 336.949687 -241.890684) (xy 336.972558 -241.934261) (xy 336.988142 -241.980942) (xy 336.996037 -242.029519)
			(xy 336.996532 -242.054126) (xy 337.32522 -242.054126) (xy 337.32918 -242.005072) (xy 337.340957 -241.957288)
			(xy 337.360248 -241.912012) (xy 337.386551 -241.870416) (xy 337.419186 -241.833579) (xy 337.457307 -241.802454)
			(xy 337.499928 -241.777847) (xy 337.545944 -241.760395) (xy 337.594163 -241.750551) (xy 337.643338 -241.74857)
			(xy 337.692193 -241.754502) (xy 337.739464 -241.768194) (xy 337.783926 -241.789292) (xy 337.824429 -241.817248)
			(xy 337.859922 -241.85134) (xy 337.889487 -241.890684) (xy 337.912358 -241.934261) (xy 337.927942 -241.980942)
			(xy 337.935837 -242.029519) (xy 337.936332 -242.054126) (xy 338.254843 -242.054126) (xy 338.258938 -242.003398)
			(xy 338.271117 -241.953984) (xy 338.291065 -241.907164) (xy 338.318266 -241.86415) (xy 338.352014 -241.826056)
			(xy 338.391436 -241.793869) (xy 338.43551 -241.768423) (xy 338.483096 -241.750376) (xy 338.53296 -241.740196)
			(xy 338.583812 -241.738147) (xy 338.634333 -241.744281) (xy 338.683217 -241.758441) (xy 338.729196 -241.780258)
			(xy 338.77108 -241.809168) (xy 338.807784 -241.844423) (xy 338.838357 -241.885109) (xy 338.862008 -241.930172)
			(xy 338.878124 -241.978446) (xy 338.886288 -242.02868) (xy 338.8868 -242.054126) (xy 339.205328 -242.054126)
			(xy 339.209288 -242.005072) (xy 339.221065 -241.957288) (xy 339.240356 -241.912012) (xy 339.266659 -241.870416)
			(xy 339.299294 -241.833579) (xy 339.337415 -241.802454) (xy 339.380036 -241.777847) (xy 339.426052 -241.760395)
			(xy 339.474271 -241.750551) (xy 339.523446 -241.74857) (xy 339.572301 -241.754502) (xy 339.619572 -241.768194)
			(xy 339.664034 -241.789292) (xy 339.704537 -241.817248) (xy 339.74003 -241.85134) (xy 339.769595 -241.890684)
			(xy 339.792466 -241.934261) (xy 339.80805 -241.980942) (xy 339.815945 -242.029519) (xy 339.81644 -242.054126)
			(xy 340.134951 -242.054126) (xy 340.139046 -242.003398) (xy 340.151225 -241.953984) (xy 340.171173 -241.907164)
			(xy 340.198374 -241.86415) (xy 340.232122 -241.826056) (xy 340.271544 -241.793869) (xy 340.315618 -241.768423)
			(xy 340.363204 -241.750376) (xy 340.413068 -241.740196) (xy 340.46392 -241.738147) (xy 340.514441 -241.744281)
			(xy 340.563325 -241.758441) (xy 340.609304 -241.780258) (xy 340.651188 -241.809168) (xy 340.687892 -241.844423)
			(xy 340.718465 -241.885109) (xy 340.742116 -241.930172) (xy 340.758232 -241.978446) (xy 340.766396 -242.02868)
			(xy 340.766908 -242.054126) (xy 341.085182 -242.054126) (xy 341.089142 -242.005072) (xy 341.100919 -241.957288)
			(xy 341.12021 -241.912012) (xy 341.146513 -241.870416) (xy 341.179148 -241.833579) (xy 341.217269 -241.802454)
			(xy 341.25989 -241.777847) (xy 341.305906 -241.760395) (xy 341.354125 -241.750551) (xy 341.4033 -241.74857)
			(xy 341.452155 -241.754502) (xy 341.499426 -241.768194) (xy 341.543888 -241.789292) (xy 341.584391 -241.817248)
			(xy 341.619884 -241.85134) (xy 341.649449 -241.890684) (xy 341.67232 -241.934261) (xy 341.687904 -241.980942)
			(xy 341.695799 -242.029519) (xy 341.696294 -242.054126) (xy 342.014805 -242.054126) (xy 342.0189 -242.003398)
			(xy 342.031079 -241.953984) (xy 342.051027 -241.907164) (xy 342.078228 -241.86415) (xy 342.111976 -241.826056)
			(xy 342.151398 -241.793869) (xy 342.195472 -241.768423) (xy 342.243058 -241.750376) (xy 342.292922 -241.740196)
			(xy 342.343774 -241.738147) (xy 342.394295 -241.744281) (xy 342.443179 -241.758441) (xy 342.489158 -241.780258)
			(xy 342.531042 -241.809168) (xy 342.567746 -241.844423) (xy 342.598319 -241.885109) (xy 342.62197 -241.930172)
			(xy 342.638086 -241.978446) (xy 342.64625 -242.02868) (xy 342.646762 -242.054126) (xy 342.64625 -242.079572)
			(xy 342.638086 -242.129806) (xy 342.62197 -242.17808) (xy 342.598319 -242.223143) (xy 342.567746 -242.263829)
			(xy 342.531042 -242.299084) (xy 342.489158 -242.327994) (xy 342.443179 -242.349811) (xy 342.394295 -242.363971)
			(xy 342.343774 -242.370105) (xy 342.292922 -242.368056) (xy 342.243058 -242.357876) (xy 342.195472 -242.339829)
			(xy 342.151398 -242.314383) (xy 342.111976 -242.282196) (xy 342.078228 -242.244102) (xy 342.051027 -242.201088)
			(xy 342.031079 -242.154268) (xy 342.0189 -242.104854) (xy 342.014805 -242.054126) (xy 341.696294 -242.054126)
			(xy 341.695799 -242.078733) (xy 341.687904 -242.12731) (xy 341.67232 -242.173991) (xy 341.649449 -242.217568)
			(xy 341.619884 -242.256912) (xy 341.584391 -242.291004) (xy 341.543888 -242.31896) (xy 341.499426 -242.340058)
			(xy 341.452155 -242.35375) (xy 341.4033 -242.359682) (xy 341.354125 -242.357701) (xy 341.305906 -242.347857)
			(xy 341.25989 -242.330405) (xy 341.217269 -242.305798) (xy 341.179148 -242.274673) (xy 341.146513 -242.237836)
			(xy 341.12021 -242.19624) (xy 341.100919 -242.150964) (xy 341.089142 -242.10318) (xy 341.085182 -242.054126)
			(xy 340.766908 -242.054126) (xy 340.766396 -242.079572) (xy 340.758232 -242.129806) (xy 340.742116 -242.17808)
			(xy 340.718465 -242.223143) (xy 340.687892 -242.263829) (xy 340.651188 -242.299084) (xy 340.609304 -242.327994)
			(xy 340.563325 -242.349811) (xy 340.514441 -242.363971) (xy 340.46392 -242.370105) (xy 340.413068 -242.368056)
			(xy 340.363204 -242.357876) (xy 340.315618 -242.339829) (xy 340.271544 -242.314383) (xy 340.232122 -242.282196)
			(xy 340.198374 -242.244102) (xy 340.171173 -242.201088) (xy 340.151225 -242.154268) (xy 340.139046 -242.104854)
			(xy 340.134951 -242.054126) (xy 339.81644 -242.054126) (xy 339.815945 -242.078733) (xy 339.80805 -242.12731)
			(xy 339.792466 -242.173991) (xy 339.769595 -242.217568) (xy 339.74003 -242.256912) (xy 339.704537 -242.291004)
			(xy 339.664034 -242.31896) (xy 339.619572 -242.340058) (xy 339.572301 -242.35375) (xy 339.523446 -242.359682)
			(xy 339.474271 -242.357701) (xy 339.426052 -242.347857) (xy 339.380036 -242.330405) (xy 339.337415 -242.305798)
			(xy 339.299294 -242.274673) (xy 339.266659 -242.237836) (xy 339.240356 -242.19624) (xy 339.221065 -242.150964)
			(xy 339.209288 -242.10318) (xy 339.205328 -242.054126) (xy 338.8868 -242.054126) (xy 338.886288 -242.079572)
			(xy 338.878124 -242.129806) (xy 338.862008 -242.17808) (xy 338.838357 -242.223143) (xy 338.807784 -242.263829)
			(xy 338.77108 -242.299084) (xy 338.729196 -242.327994) (xy 338.683217 -242.349811) (xy 338.634333 -242.363971)
			(xy 338.583812 -242.370105) (xy 338.53296 -242.368056) (xy 338.483096 -242.357876) (xy 338.43551 -242.339829)
			(xy 338.391436 -242.314383) (xy 338.352014 -242.282196) (xy 338.318266 -242.244102) (xy 338.291065 -242.201088)
			(xy 338.271117 -242.154268) (xy 338.258938 -242.104854) (xy 338.254843 -242.054126) (xy 337.936332 -242.054126)
			(xy 337.935837 -242.078733) (xy 337.927942 -242.12731) (xy 337.912358 -242.173991) (xy 337.889487 -242.217568)
			(xy 337.859922 -242.256912) (xy 337.824429 -242.291004) (xy 337.783926 -242.31896) (xy 337.739464 -242.340058)
			(xy 337.692193 -242.35375) (xy 337.643338 -242.359682) (xy 337.594163 -242.357701) (xy 337.545944 -242.347857)
			(xy 337.499928 -242.330405) (xy 337.457307 -242.305798) (xy 337.419186 -242.274673) (xy 337.386551 -242.237836)
			(xy 337.360248 -242.19624) (xy 337.340957 -242.150964) (xy 337.32918 -242.10318) (xy 337.32522 -242.054126)
			(xy 336.996532 -242.054126) (xy 336.996037 -242.078733) (xy 336.988142 -242.12731) (xy 336.972558 -242.173991)
			(xy 336.949687 -242.217568) (xy 336.920122 -242.256912) (xy 336.884629 -242.291004) (xy 336.844126 -242.31896)
			(xy 336.799664 -242.340058) (xy 336.752393 -242.35375) (xy 336.703538 -242.359682) (xy 336.654363 -242.357701)
			(xy 336.606144 -242.347857) (xy 336.560128 -242.330405) (xy 336.517507 -242.305798) (xy 336.479386 -242.274673)
			(xy 336.446751 -242.237836) (xy 336.420448 -242.19624) (xy 336.401157 -242.150964) (xy 336.38938 -242.10318)
			(xy 336.38542 -242.054126) (xy 336.056478 -242.054126) (xy 336.055983 -242.078733) (xy 336.048088 -242.12731)
			(xy 336.032504 -242.173991) (xy 336.009633 -242.217568) (xy 335.980068 -242.256912) (xy 335.944575 -242.291004)
			(xy 335.904072 -242.31896) (xy 335.85961 -242.340058) (xy 335.812339 -242.35375) (xy 335.763484 -242.359682)
			(xy 335.714309 -242.357701) (xy 335.66609 -242.347857) (xy 335.620074 -242.330405) (xy 335.577453 -242.305798)
			(xy 335.539332 -242.274673) (xy 335.506697 -242.237836) (xy 335.480394 -242.19624) (xy 335.461103 -242.150964)
			(xy 335.449326 -242.10318) (xy 335.445366 -242.054126) (xy 335.116903 -242.054126) (xy 335.112734 -242.104432)
			(xy 335.100337 -242.153392) (xy 335.08005 -242.199643) (xy 335.052427 -242.241924) (xy 335.018222 -242.279082)
			(xy 334.978368 -242.310104) (xy 334.933951 -242.334143) (xy 334.886184 -242.350544) (xy 334.836368 -242.358859)
			(xy 334.811116 -242.359434) (xy 334.787546 -242.358999) (xy 334.740964 -242.35176) (xy 334.696046 -242.337454)
			(xy 334.653859 -242.316417) (xy 334.615404 -242.289151) (xy 334.581593 -242.256302) (xy 334.567022 -242.237768)
			(xy 334.56499 -242.234974) (xy 334.55991 -242.229894) (xy 334.553343 -242.223776) (xy 334.537072 -242.216233)
			(xy 334.52816 -242.215162) (xy 334.522572 -242.214654) (xy 334.432148 -242.226846) (xy 334.423231 -242.228392)
			(xy 334.407241 -242.236843) (xy 334.395184 -242.250324) (xy 334.391508 -242.258596) (xy 334.383584 -242.278302)
			(xy 334.365147 -242.316569) (xy 334.354678 -242.33505) (xy 334.312768 -242.407186) (xy 334.311498 -242.408964)
			(xy 334.303878 -242.420394) (xy 334.3021 -242.447572) (xy 334.338676 -242.521994) (xy 334.34155 -242.527329)
			(xy 334.349376 -242.536576) (xy 334.35417 -242.540282) (xy 334.382618 -242.561364) (xy 334.394302 -242.563396)
			(xy 334.417562 -242.567952) (xy 334.462405 -242.583297) (xy 334.504337 -242.60539) (xy 334.54235 -242.633698)
			(xy 334.575531 -242.667541) (xy 334.603082 -242.706107) (xy 334.624342 -242.748467) (xy 334.638798 -242.793605)
			(xy 334.646103 -242.840434) (xy 334.646524 -242.864132) (xy 334.975212 -242.864132) (xy 334.979172 -242.815078)
			(xy 334.990949 -242.767294) (xy 335.01024 -242.722018) (xy 335.036543 -242.680422) (xy 335.069178 -242.643585)
			(xy 335.107299 -242.61246) (xy 335.14992 -242.587853) (xy 335.195936 -242.570401) (xy 335.244155 -242.560557)
			(xy 335.29333 -242.558576) (xy 335.342185 -242.564508) (xy 335.389456 -242.5782) (xy 335.433918 -242.599298)
			(xy 335.474421 -242.627254) (xy 335.509914 -242.661346) (xy 335.539479 -242.70069) (xy 335.56235 -242.744267)
			(xy 335.577934 -242.790948) (xy 335.585829 -242.839525) (xy 335.586324 -242.864132) (xy 335.915266 -242.864132)
			(xy 335.919226 -242.815078) (xy 335.931003 -242.767294) (xy 335.950294 -242.722018) (xy 335.976597 -242.680422)
			(xy 336.009232 -242.643585) (xy 336.047353 -242.61246) (xy 336.089974 -242.587853) (xy 336.13599 -242.570401)
			(xy 336.184209 -242.560557) (xy 336.233384 -242.558576) (xy 336.282239 -242.564508) (xy 336.32951 -242.5782)
			(xy 336.373972 -242.599298) (xy 336.414475 -242.627254) (xy 336.449968 -242.661346) (xy 336.479533 -242.70069)
			(xy 336.502404 -242.744267) (xy 336.517988 -242.790948) (xy 336.525883 -242.839525) (xy 336.526378 -242.864132)
			(xy 336.85532 -242.864132) (xy 336.85928 -242.815078) (xy 336.871057 -242.767294) (xy 336.890348 -242.722018)
			(xy 336.916651 -242.680422) (xy 336.949286 -242.643585) (xy 336.987407 -242.61246) (xy 337.030028 -242.587853)
			(xy 337.076044 -242.570401) (xy 337.124263 -242.560557) (xy 337.173438 -242.558576) (xy 337.222293 -242.564508)
			(xy 337.269564 -242.5782) (xy 337.314026 -242.599298) (xy 337.354529 -242.627254) (xy 337.390022 -242.661346)
			(xy 337.419587 -242.70069) (xy 337.442458 -242.744267) (xy 337.458042 -242.790948) (xy 337.465937 -242.839525)
			(xy 337.466432 -242.864132) (xy 337.795374 -242.864132) (xy 337.799334 -242.815078) (xy 337.811111 -242.767294)
			(xy 337.830402 -242.722018) (xy 337.856705 -242.680422) (xy 337.88934 -242.643585) (xy 337.927461 -242.61246)
			(xy 337.970082 -242.587853) (xy 338.016098 -242.570401) (xy 338.064317 -242.560557) (xy 338.113492 -242.558576)
			(xy 338.162347 -242.564508) (xy 338.209618 -242.5782) (xy 338.25408 -242.599298) (xy 338.294583 -242.627254)
			(xy 338.330076 -242.661346) (xy 338.359641 -242.70069) (xy 338.382512 -242.744267) (xy 338.398096 -242.790948)
			(xy 338.405991 -242.839525) (xy 338.406486 -242.864132) (xy 338.724743 -242.864132) (xy 338.728838 -242.813404)
			(xy 338.741017 -242.76399) (xy 338.760965 -242.71717) (xy 338.788166 -242.674156) (xy 338.821914 -242.636062)
			(xy 338.861336 -242.603875) (xy 338.90541 -242.578429) (xy 338.952996 -242.560382) (xy 339.00286 -242.550202)
			(xy 339.053712 -242.548153) (xy 339.104233 -242.554287) (xy 339.153117 -242.568447) (xy 339.199096 -242.590264)
			(xy 339.24098 -242.619174) (xy 339.277684 -242.654429) (xy 339.308257 -242.695115) (xy 339.331908 -242.740178)
			(xy 339.348024 -242.788452) (xy 339.356188 -242.838686) (xy 339.3567 -242.864132) (xy 339.664797 -242.864132)
			(xy 339.668892 -242.813404) (xy 339.681071 -242.76399) (xy 339.701019 -242.71717) (xy 339.72822 -242.674156)
			(xy 339.761968 -242.636062) (xy 339.80139 -242.603875) (xy 339.845464 -242.578429) (xy 339.89305 -242.560382)
			(xy 339.942914 -242.550202) (xy 339.993766 -242.548153) (xy 340.044287 -242.554287) (xy 340.093171 -242.568447)
			(xy 340.13915 -242.590264) (xy 340.181034 -242.619174) (xy 340.217738 -242.654429) (xy 340.248311 -242.695115)
			(xy 340.271962 -242.740178) (xy 340.288078 -242.788452) (xy 340.296242 -242.838686) (xy 340.296754 -242.864132)
			(xy 340.615282 -242.864132) (xy 340.619242 -242.815078) (xy 340.631019 -242.767294) (xy 340.65031 -242.722018)
			(xy 340.676613 -242.680422) (xy 340.709248 -242.643585) (xy 340.747369 -242.61246) (xy 340.78999 -242.587853)
			(xy 340.836006 -242.570401) (xy 340.884225 -242.560557) (xy 340.9334 -242.558576) (xy 340.982255 -242.564508)
			(xy 341.029526 -242.5782) (xy 341.073988 -242.599298) (xy 341.114491 -242.627254) (xy 341.149984 -242.661346)
			(xy 341.179549 -242.70069) (xy 341.20242 -242.744267) (xy 341.218004 -242.790948) (xy 341.225899 -242.839525)
			(xy 341.226394 -242.864132) (xy 341.544905 -242.864132) (xy 341.549 -242.813404) (xy 341.561179 -242.76399)
			(xy 341.581127 -242.71717) (xy 341.608328 -242.674156) (xy 341.642076 -242.636062) (xy 341.681498 -242.603875)
			(xy 341.725572 -242.578429) (xy 341.773158 -242.560382) (xy 341.823022 -242.550202) (xy 341.873874 -242.548153)
			(xy 341.924395 -242.554287) (xy 341.973279 -242.568447) (xy 342.019258 -242.590264) (xy 342.061142 -242.619174)
			(xy 342.097846 -242.654429) (xy 342.128419 -242.695115) (xy 342.15207 -242.740178) (xy 342.168186 -242.788452)
			(xy 342.17635 -242.838686) (xy 342.176862 -242.864132) (xy 342.49539 -242.864132) (xy 342.49935 -242.815078)
			(xy 342.511127 -242.767294) (xy 342.530418 -242.722018) (xy 342.556721 -242.680422) (xy 342.589356 -242.643585)
			(xy 342.627477 -242.61246) (xy 342.670098 -242.587853) (xy 342.716114 -242.570401) (xy 342.764333 -242.560557)
			(xy 342.813508 -242.558576) (xy 342.862363 -242.564508) (xy 342.909634 -242.5782) (xy 342.954096 -242.599298)
			(xy 342.994599 -242.627254) (xy 343.030092 -242.661346) (xy 343.059657 -242.70069) (xy 343.082528 -242.744267)
			(xy 343.098112 -242.790948) (xy 343.106007 -242.839525) (xy 343.106502 -242.864132) (xy 343.106007 -242.888739)
			(xy 343.098112 -242.937316) (xy 343.082528 -242.983997) (xy 343.059657 -243.027574) (xy 343.030092 -243.066918)
			(xy 342.994599 -243.10101) (xy 342.954096 -243.128966) (xy 342.909634 -243.150064) (xy 342.862363 -243.163756)
			(xy 342.813508 -243.169688) (xy 342.764333 -243.167707) (xy 342.716114 -243.157863) (xy 342.670098 -243.140411)
			(xy 342.627477 -243.115804) (xy 342.589356 -243.084679) (xy 342.556721 -243.047842) (xy 342.530418 -243.006246)
			(xy 342.511127 -242.96097) (xy 342.49935 -242.913186) (xy 342.49539 -242.864132) (xy 342.176862 -242.864132)
			(xy 342.17635 -242.889578) (xy 342.168186 -242.939812) (xy 342.15207 -242.988086) (xy 342.128419 -243.033149)
			(xy 342.097846 -243.073835) (xy 342.061142 -243.10909) (xy 342.019258 -243.138) (xy 341.973279 -243.159817)
			(xy 341.924395 -243.173977) (xy 341.873874 -243.180111) (xy 341.823022 -243.178062) (xy 341.773158 -243.167882)
			(xy 341.725572 -243.149835) (xy 341.681498 -243.124389) (xy 341.642076 -243.092202) (xy 341.608328 -243.054108)
			(xy 341.581127 -243.011094) (xy 341.561179 -242.964274) (xy 341.549 -242.91486) (xy 341.544905 -242.864132)
			(xy 341.226394 -242.864132) (xy 341.225899 -242.888739) (xy 341.218004 -242.937316) (xy 341.20242 -242.983997)
			(xy 341.179549 -243.027574) (xy 341.149984 -243.066918) (xy 341.114491 -243.10101) (xy 341.073988 -243.128966)
			(xy 341.029526 -243.150064) (xy 340.982255 -243.163756) (xy 340.9334 -243.169688) (xy 340.884225 -243.167707)
			(xy 340.836006 -243.157863) (xy 340.78999 -243.140411) (xy 340.747369 -243.115804) (xy 340.709248 -243.084679)
			(xy 340.676613 -243.047842) (xy 340.65031 -243.006246) (xy 340.631019 -242.96097) (xy 340.619242 -242.913186)
			(xy 340.615282 -242.864132) (xy 340.296754 -242.864132) (xy 340.296242 -242.889578) (xy 340.288078 -242.939812)
			(xy 340.271962 -242.988086) (xy 340.248311 -243.033149) (xy 340.217738 -243.073835) (xy 340.181034 -243.10909)
			(xy 340.13915 -243.138) (xy 340.093171 -243.159817) (xy 340.044287 -243.173977) (xy 339.993766 -243.180111)
			(xy 339.942914 -243.178062) (xy 339.89305 -243.167882) (xy 339.845464 -243.149835) (xy 339.80139 -243.124389)
			(xy 339.761968 -243.092202) (xy 339.72822 -243.054108) (xy 339.701019 -243.011094) (xy 339.681071 -242.964274)
			(xy 339.668892 -242.91486) (xy 339.664797 -242.864132) (xy 339.3567 -242.864132) (xy 339.356188 -242.889578)
			(xy 339.348024 -242.939812) (xy 339.331908 -242.988086) (xy 339.308257 -243.033149) (xy 339.277684 -243.073835)
			(xy 339.24098 -243.10909) (xy 339.199096 -243.138) (xy 339.153117 -243.159817) (xy 339.104233 -243.173977)
			(xy 339.053712 -243.180111) (xy 339.00286 -243.178062) (xy 338.952996 -243.167882) (xy 338.90541 -243.149835)
			(xy 338.861336 -243.124389) (xy 338.821914 -243.092202) (xy 338.788166 -243.054108) (xy 338.760965 -243.011094)
			(xy 338.741017 -242.964274) (xy 338.728838 -242.91486) (xy 338.724743 -242.864132) (xy 338.406486 -242.864132)
			(xy 338.405991 -242.888739) (xy 338.398096 -242.937316) (xy 338.382512 -242.983997) (xy 338.359641 -243.027574)
			(xy 338.330076 -243.066918) (xy 338.294583 -243.10101) (xy 338.25408 -243.128966) (xy 338.209618 -243.150064)
			(xy 338.162347 -243.163756) (xy 338.113492 -243.169688) (xy 338.064317 -243.167707) (xy 338.016098 -243.157863)
			(xy 337.970082 -243.140411) (xy 337.927461 -243.115804) (xy 337.88934 -243.084679) (xy 337.856705 -243.047842)
			(xy 337.830402 -243.006246) (xy 337.811111 -242.96097) (xy 337.799334 -242.913186) (xy 337.795374 -242.864132)
			(xy 337.466432 -242.864132) (xy 337.465937 -242.888739) (xy 337.458042 -242.937316) (xy 337.442458 -242.983997)
			(xy 337.419587 -243.027574) (xy 337.390022 -243.066918) (xy 337.354529 -243.10101) (xy 337.314026 -243.128966)
			(xy 337.269564 -243.150064) (xy 337.222293 -243.163756) (xy 337.173438 -243.169688) (xy 337.124263 -243.167707)
			(xy 337.076044 -243.157863) (xy 337.030028 -243.140411) (xy 336.987407 -243.115804) (xy 336.949286 -243.084679)
			(xy 336.916651 -243.047842) (xy 336.890348 -243.006246) (xy 336.871057 -242.96097) (xy 336.85928 -242.913186)
			(xy 336.85532 -242.864132) (xy 336.526378 -242.864132) (xy 336.525883 -242.888739) (xy 336.517988 -242.937316)
			(xy 336.502404 -242.983997) (xy 336.479533 -243.027574) (xy 336.449968 -243.066918) (xy 336.414475 -243.10101)
			(xy 336.373972 -243.128966) (xy 336.32951 -243.150064) (xy 336.282239 -243.163756) (xy 336.233384 -243.169688)
			(xy 336.184209 -243.167707) (xy 336.13599 -243.157863) (xy 336.089974 -243.140411) (xy 336.047353 -243.115804)
			(xy 336.009232 -243.084679) (xy 335.976597 -243.047842) (xy 335.950294 -243.006246) (xy 335.931003 -242.96097)
			(xy 335.919226 -242.913186) (xy 335.915266 -242.864132) (xy 335.586324 -242.864132) (xy 335.585829 -242.888739)
			(xy 335.577934 -242.937316) (xy 335.56235 -242.983997) (xy 335.539479 -243.027574) (xy 335.509914 -243.066918)
			(xy 335.474421 -243.10101) (xy 335.433918 -243.128966) (xy 335.389456 -243.150064) (xy 335.342185 -243.163756)
			(xy 335.29333 -243.169688) (xy 335.244155 -243.167707) (xy 335.195936 -243.157863) (xy 335.14992 -243.140411)
			(xy 335.107299 -243.115804) (xy 335.069178 -243.084679) (xy 335.036543 -243.047842) (xy 335.01024 -243.006246)
			(xy 334.990949 -242.96097) (xy 334.979172 -242.913186) (xy 334.975212 -242.864132) (xy 334.646524 -242.864132)
			(xy 334.646051 -242.888122) (xy 334.638541 -242.935511) (xy 334.623711 -242.981142) (xy 334.601926 -243.023891)
			(xy 334.573722 -243.062707) (xy 334.539794 -243.096633) (xy 334.500977 -243.124834) (xy 334.458227 -243.146617)
			(xy 334.412595 -243.161445) (xy 334.365206 -243.168952) (xy 334.341216 -243.16944) (xy 334.309466 -243.167662)
			(xy 334.306672 -243.167408) (xy 334.304132 -243.167408) (xy 334.294107 -243.167822) (xy 334.27558 -243.175487)
			(xy 334.2614 -243.18966) (xy 334.253727 -243.208183) (xy 334.253332 -243.218208) (xy 334.253332 -243.238528)
			(xy 334.254094 -243.247418) (xy 334.255364 -243.254276) (xy 334.25696 -243.261892) (xy 334.264066 -243.275727)
			(xy 334.269334 -243.281454) (xy 334.269588 -243.281708) (xy 334.274922 -243.287296) (xy 334.298191 -243.312326)
			(xy 334.339091 -243.367077) (xy 334.372995 -243.426416) (xy 334.386682 -243.45773) (xy 334.389222 -243.463826)
			(xy 334.396842 -243.473986) (xy 334.421226 -243.493036) (xy 334.4267 -243.496997) (xy 334.439189 -243.502145)
			(xy 334.445864 -243.503196) (xy 334.516984 -243.512848) (xy 334.522959 -243.513466) (xy 334.5349 -243.512187)
			(xy 334.540606 -243.510308) (xy 334.551782 -243.506498) (xy 334.56499 -243.49329) (xy 334.567022 -243.490496)
			(xy 334.581566 -243.471941) (xy 334.615395 -243.439108) (xy 334.653859 -243.411852) (xy 334.696048 -243.390817)
			(xy 334.740965 -243.376501) (xy 334.787545 -243.369243) (xy 334.811116 -243.36883) (xy 334.836367 -243.369353)
			(xy 334.886181 -243.377667) (xy 334.933946 -243.394068) (xy 334.978361 -243.418106) (xy 335.018214 -243.449126)
			(xy 335.052418 -243.486283) (xy 335.080039 -243.528563) (xy 335.100325 -243.574812) (xy 335.112723 -243.62377)
			(xy 335.116893 -243.6741) (xy 335.11689 -243.674138) (xy 335.445366 -243.674138) (xy 335.449326 -243.625084)
			(xy 335.461103 -243.5773) (xy 335.480394 -243.532024) (xy 335.506697 -243.490428) (xy 335.539332 -243.453591)
			(xy 335.577453 -243.422466) (xy 335.620074 -243.397859) (xy 335.66609 -243.380407) (xy 335.714309 -243.370563)
			(xy 335.763484 -243.368582) (xy 335.812339 -243.374514) (xy 335.85961 -243.388206) (xy 335.904072 -243.409304)
			(xy 335.944575 -243.43726) (xy 335.980068 -243.471352) (xy 336.009633 -243.510696) (xy 336.032504 -243.554273)
			(xy 336.048088 -243.600954) (xy 336.055983 -243.649531) (xy 336.056478 -243.674138) (xy 336.38542 -243.674138)
			(xy 336.38938 -243.625084) (xy 336.401157 -243.5773) (xy 336.420448 -243.532024) (xy 336.446751 -243.490428)
			(xy 336.479386 -243.453591) (xy 336.517507 -243.422466) (xy 336.560128 -243.397859) (xy 336.606144 -243.380407)
			(xy 336.654363 -243.370563) (xy 336.703538 -243.368582) (xy 336.752393 -243.374514) (xy 336.799664 -243.388206)
			(xy 336.844126 -243.409304) (xy 336.884629 -243.43726) (xy 336.920122 -243.471352) (xy 336.949687 -243.510696)
			(xy 336.972558 -243.554273) (xy 336.988142 -243.600954) (xy 336.996037 -243.649531) (xy 336.996532 -243.674138)
			(xy 337.32522 -243.674138) (xy 337.32918 -243.625084) (xy 337.340957 -243.5773) (xy 337.360248 -243.532024)
			(xy 337.386551 -243.490428) (xy 337.419186 -243.453591) (xy 337.457307 -243.422466) (xy 337.499928 -243.397859)
			(xy 337.545944 -243.380407) (xy 337.594163 -243.370563) (xy 337.643338 -243.368582) (xy 337.692193 -243.374514)
			(xy 337.739464 -243.388206) (xy 337.783926 -243.409304) (xy 337.824429 -243.43726) (xy 337.859922 -243.471352)
			(xy 337.889487 -243.510696) (xy 337.912358 -243.554273) (xy 337.927942 -243.600954) (xy 337.935837 -243.649531)
			(xy 337.936332 -243.674138) (xy 338.254843 -243.674138) (xy 338.258938 -243.62341) (xy 338.271117 -243.573996)
			(xy 338.291065 -243.527176) (xy 338.318266 -243.484162) (xy 338.352014 -243.446068) (xy 338.391436 -243.413881)
			(xy 338.43551 -243.388435) (xy 338.483096 -243.370388) (xy 338.53296 -243.360208) (xy 338.583812 -243.358159)
			(xy 338.634333 -243.364293) (xy 338.683217 -243.378453) (xy 338.729196 -243.40027) (xy 338.77108 -243.42918)
			(xy 338.807784 -243.464435) (xy 338.838357 -243.505121) (xy 338.862008 -243.550184) (xy 338.878124 -243.598458)
			(xy 338.886288 -243.648692) (xy 338.8868 -243.674138) (xy 339.205328 -243.674138) (xy 339.209288 -243.625084)
			(xy 339.221065 -243.5773) (xy 339.240356 -243.532024) (xy 339.266659 -243.490428) (xy 339.299294 -243.453591)
			(xy 339.337415 -243.422466) (xy 339.380036 -243.397859) (xy 339.426052 -243.380407) (xy 339.474271 -243.370563)
			(xy 339.523446 -243.368582) (xy 339.572301 -243.374514) (xy 339.619572 -243.388206) (xy 339.664034 -243.409304)
			(xy 339.704537 -243.43726) (xy 339.74003 -243.471352) (xy 339.769595 -243.510696) (xy 339.792466 -243.554273)
			(xy 339.80805 -243.600954) (xy 339.815945 -243.649531) (xy 339.81644 -243.674138) (xy 340.134951 -243.674138)
			(xy 340.139046 -243.62341) (xy 340.151225 -243.573996) (xy 340.171173 -243.527176) (xy 340.198374 -243.484162)
			(xy 340.232122 -243.446068) (xy 340.271544 -243.413881) (xy 340.315618 -243.388435) (xy 340.363204 -243.370388)
			(xy 340.413068 -243.360208) (xy 340.46392 -243.358159) (xy 340.514441 -243.364293) (xy 340.563325 -243.378453)
			(xy 340.609304 -243.40027) (xy 340.651188 -243.42918) (xy 340.687892 -243.464435) (xy 340.718465 -243.505121)
			(xy 340.742116 -243.550184) (xy 340.758232 -243.598458) (xy 340.766396 -243.648692) (xy 340.766908 -243.674138)
			(xy 341.085182 -243.674138) (xy 341.089142 -243.625084) (xy 341.100919 -243.5773) (xy 341.12021 -243.532024)
			(xy 341.146513 -243.490428) (xy 341.179148 -243.453591) (xy 341.217269 -243.422466) (xy 341.25989 -243.397859)
			(xy 341.305906 -243.380407) (xy 341.354125 -243.370563) (xy 341.4033 -243.368582) (xy 341.452155 -243.374514)
			(xy 341.499426 -243.388206) (xy 341.543888 -243.409304) (xy 341.584391 -243.43726) (xy 341.619884 -243.471352)
			(xy 341.649449 -243.510696) (xy 341.67232 -243.554273) (xy 341.687904 -243.600954) (xy 341.695799 -243.649531)
			(xy 341.696294 -243.674138) (xy 342.014805 -243.674138) (xy 342.0189 -243.62341) (xy 342.031079 -243.573996)
			(xy 342.051027 -243.527176) (xy 342.078228 -243.484162) (xy 342.111976 -243.446068) (xy 342.151398 -243.413881)
			(xy 342.195472 -243.388435) (xy 342.243058 -243.370388) (xy 342.292922 -243.360208) (xy 342.343774 -243.358159)
			(xy 342.394295 -243.364293) (xy 342.443179 -243.378453) (xy 342.489158 -243.40027) (xy 342.531042 -243.42918)
			(xy 342.567746 -243.464435) (xy 342.598319 -243.505121) (xy 342.62197 -243.550184) (xy 342.638086 -243.598458)
			(xy 342.64625 -243.648692) (xy 342.646762 -243.674138) (xy 342.64625 -243.699584) (xy 342.638086 -243.749818)
			(xy 342.62197 -243.798092) (xy 342.598319 -243.843155) (xy 342.567746 -243.883841) (xy 342.531042 -243.919096)
			(xy 342.489158 -243.948006) (xy 342.443179 -243.969823) (xy 342.394295 -243.983983) (xy 342.343774 -243.990117)
			(xy 342.292922 -243.988068) (xy 342.243058 -243.977888) (xy 342.195472 -243.959841) (xy 342.151398 -243.934395)
			(xy 342.111976 -243.902208) (xy 342.078228 -243.864114) (xy 342.051027 -243.8211) (xy 342.031079 -243.77428)
			(xy 342.0189 -243.724866) (xy 342.014805 -243.674138) (xy 341.696294 -243.674138) (xy 341.695799 -243.698745)
			(xy 341.687904 -243.747322) (xy 341.67232 -243.794003) (xy 341.649449 -243.83758) (xy 341.619884 -243.876924)
			(xy 341.584391 -243.911016) (xy 341.543888 -243.938972) (xy 341.499426 -243.96007) (xy 341.452155 -243.973762)
			(xy 341.4033 -243.979694) (xy 341.354125 -243.977713) (xy 341.305906 -243.967869) (xy 341.25989 -243.950417)
			(xy 341.217269 -243.92581) (xy 341.179148 -243.894685) (xy 341.146513 -243.857848) (xy 341.12021 -243.816252)
			(xy 341.100919 -243.770976) (xy 341.089142 -243.723192) (xy 341.085182 -243.674138) (xy 340.766908 -243.674138)
			(xy 340.766396 -243.699584) (xy 340.758232 -243.749818) (xy 340.742116 -243.798092) (xy 340.718465 -243.843155)
			(xy 340.687892 -243.883841) (xy 340.651188 -243.919096) (xy 340.609304 -243.948006) (xy 340.563325 -243.969823)
			(xy 340.514441 -243.983983) (xy 340.46392 -243.990117) (xy 340.413068 -243.988068) (xy 340.363204 -243.977888)
			(xy 340.315618 -243.959841) (xy 340.271544 -243.934395) (xy 340.232122 -243.902208) (xy 340.198374 -243.864114)
			(xy 340.171173 -243.8211) (xy 340.151225 -243.77428) (xy 340.139046 -243.724866) (xy 340.134951 -243.674138)
			(xy 339.81644 -243.674138) (xy 339.815945 -243.698745) (xy 339.80805 -243.747322) (xy 339.792466 -243.794003)
			(xy 339.769595 -243.83758) (xy 339.74003 -243.876924) (xy 339.704537 -243.911016) (xy 339.664034 -243.938972)
			(xy 339.619572 -243.96007) (xy 339.572301 -243.973762) (xy 339.523446 -243.979694) (xy 339.474271 -243.977713)
			(xy 339.426052 -243.967869) (xy 339.380036 -243.950417) (xy 339.337415 -243.92581) (xy 339.299294 -243.894685)
			(xy 339.266659 -243.857848) (xy 339.240356 -243.816252) (xy 339.221065 -243.770976) (xy 339.209288 -243.723192)
			(xy 339.205328 -243.674138) (xy 338.8868 -243.674138) (xy 338.886288 -243.699584) (xy 338.878124 -243.749818)
			(xy 338.862008 -243.798092) (xy 338.838357 -243.843155) (xy 338.807784 -243.883841) (xy 338.77108 -243.919096)
			(xy 338.729196 -243.948006) (xy 338.683217 -243.969823) (xy 338.634333 -243.983983) (xy 338.583812 -243.990117)
			(xy 338.53296 -243.988068) (xy 338.483096 -243.977888) (xy 338.43551 -243.959841) (xy 338.391436 -243.934395)
			(xy 338.352014 -243.902208) (xy 338.318266 -243.864114) (xy 338.291065 -243.8211) (xy 338.271117 -243.77428)
			(xy 338.258938 -243.724866) (xy 338.254843 -243.674138) (xy 337.936332 -243.674138) (xy 337.935837 -243.698745)
			(xy 337.927942 -243.747322) (xy 337.912358 -243.794003) (xy 337.889487 -243.83758) (xy 337.859922 -243.876924)
			(xy 337.824429 -243.911016) (xy 337.783926 -243.938972) (xy 337.739464 -243.96007) (xy 337.692193 -243.973762)
			(xy 337.643338 -243.979694) (xy 337.594163 -243.977713) (xy 337.545944 -243.967869) (xy 337.499928 -243.950417)
			(xy 337.457307 -243.92581) (xy 337.419186 -243.894685) (xy 337.386551 -243.857848) (xy 337.360248 -243.816252)
			(xy 337.340957 -243.770976) (xy 337.32918 -243.723192) (xy 337.32522 -243.674138) (xy 336.996532 -243.674138)
			(xy 336.996037 -243.698745) (xy 336.988142 -243.747322) (xy 336.972558 -243.794003) (xy 336.949687 -243.83758)
			(xy 336.920122 -243.876924) (xy 336.884629 -243.911016) (xy 336.844126 -243.938972) (xy 336.799664 -243.96007)
			(xy 336.752393 -243.973762) (xy 336.703538 -243.979694) (xy 336.654363 -243.977713) (xy 336.606144 -243.967869)
			(xy 336.560128 -243.950417) (xy 336.517507 -243.92581) (xy 336.479386 -243.894685) (xy 336.446751 -243.857848)
			(xy 336.420448 -243.816252) (xy 336.401157 -243.770976) (xy 336.38938 -243.723192) (xy 336.38542 -243.674138)
			(xy 336.056478 -243.674138) (xy 336.055983 -243.698745) (xy 336.048088 -243.747322) (xy 336.032504 -243.794003)
			(xy 336.009633 -243.83758) (xy 335.980068 -243.876924) (xy 335.944575 -243.911016) (xy 335.904072 -243.938972)
			(xy 335.85961 -243.96007) (xy 335.812339 -243.973762) (xy 335.763484 -243.979694) (xy 335.714309 -243.977713)
			(xy 335.66609 -243.967869) (xy 335.620074 -243.950417) (xy 335.577453 -243.92581) (xy 335.539332 -243.894685)
			(xy 335.506697 -243.857848) (xy 335.480394 -243.816252) (xy 335.461103 -243.770976) (xy 335.449326 -243.723192)
			(xy 335.445366 -243.674138) (xy 335.11689 -243.674138) (xy 335.112723 -243.72443) (xy 335.100325 -243.773388)
			(xy 335.080039 -243.819637) (xy 335.052418 -243.861917) (xy 335.018214 -243.899074) (xy 334.978361 -243.930094)
			(xy 334.933946 -243.954132) (xy 334.886181 -243.970533) (xy 334.836367 -243.978847) (xy 334.811116 -243.979446)
			(xy 334.787545 -243.979011) (xy 334.740963 -243.971773) (xy 334.696045 -243.957466) (xy 334.653858 -243.93643)
			(xy 334.615402 -243.909165) (xy 334.58159 -243.876316) (xy 334.567022 -243.85778) (xy 334.56499 -243.854986)
			(xy 334.55991 -243.849906) (xy 334.553344 -243.843787) (xy 334.537072 -243.836241) (xy 334.52816 -243.835174)
			(xy 334.522572 -243.834666) (xy 334.432148 -243.846858) (xy 334.423231 -243.848404) (xy 334.407243 -243.856857)
			(xy 334.395189 -243.870339) (xy 334.391508 -243.878608) (xy 334.383584 -243.898314) (xy 334.365146 -243.936581)
			(xy 334.354678 -243.955062) (xy 334.312768 -244.027198) (xy 334.311498 -244.028976) (xy 334.303878 -244.040406)
			(xy 334.3021 -244.067584) (xy 334.338676 -244.142006) (xy 334.341551 -244.14734) (xy 334.349378 -244.156586)
			(xy 334.35417 -244.160294) (xy 334.382618 -244.181376) (xy 334.394302 -244.183408) (xy 334.417562 -244.187964)
			(xy 334.462404 -244.20331) (xy 334.504335 -244.225402) (xy 334.542347 -244.253711) (xy 334.575527 -244.287554)
			(xy 334.603077 -244.32612) (xy 334.624334 -244.36848) (xy 334.638788 -244.413617) (xy 334.646092 -244.460446)
			(xy 334.646524 -244.484144) (xy 334.975212 -244.484144) (xy 334.979172 -244.43509) (xy 334.990949 -244.387306)
			(xy 335.01024 -244.34203) (xy 335.036543 -244.300434) (xy 335.069178 -244.263597) (xy 335.107299 -244.232472)
			(xy 335.14992 -244.207865) (xy 335.195936 -244.190413) (xy 335.244155 -244.180569) (xy 335.29333 -244.178588)
			(xy 335.342185 -244.18452) (xy 335.389456 -244.198212) (xy 335.433918 -244.21931) (xy 335.474421 -244.247266)
			(xy 335.509914 -244.281358) (xy 335.539479 -244.320702) (xy 335.56235 -244.364279) (xy 335.577934 -244.41096)
			(xy 335.585829 -244.459537) (xy 335.586324 -244.484144) (xy 335.915266 -244.484144) (xy 335.919226 -244.43509)
			(xy 335.931003 -244.387306) (xy 335.950294 -244.34203) (xy 335.976597 -244.300434) (xy 336.009232 -244.263597)
			(xy 336.047353 -244.232472) (xy 336.089974 -244.207865) (xy 336.13599 -244.190413) (xy 336.184209 -244.180569)
			(xy 336.233384 -244.178588) (xy 336.282239 -244.18452) (xy 336.32951 -244.198212) (xy 336.373972 -244.21931)
			(xy 336.414475 -244.247266) (xy 336.449968 -244.281358) (xy 336.479533 -244.320702) (xy 336.502404 -244.364279)
			(xy 336.517988 -244.41096) (xy 336.525883 -244.459537) (xy 336.526378 -244.484144) (xy 336.85532 -244.484144)
			(xy 336.85928 -244.43509) (xy 336.871057 -244.387306) (xy 336.890348 -244.34203) (xy 336.916651 -244.300434)
			(xy 336.949286 -244.263597) (xy 336.987407 -244.232472) (xy 337.030028 -244.207865) (xy 337.076044 -244.190413)
			(xy 337.124263 -244.180569) (xy 337.173438 -244.178588) (xy 337.222293 -244.18452) (xy 337.269564 -244.198212)
			(xy 337.314026 -244.21931) (xy 337.354529 -244.247266) (xy 337.390022 -244.281358) (xy 337.419587 -244.320702)
			(xy 337.442458 -244.364279) (xy 337.458042 -244.41096) (xy 337.465937 -244.459537) (xy 337.466432 -244.484144)
			(xy 337.795374 -244.484144) (xy 337.799334 -244.43509) (xy 337.811111 -244.387306) (xy 337.830402 -244.34203)
			(xy 337.856705 -244.300434) (xy 337.88934 -244.263597) (xy 337.927461 -244.232472) (xy 337.970082 -244.207865)
			(xy 338.016098 -244.190413) (xy 338.064317 -244.180569) (xy 338.113492 -244.178588) (xy 338.162347 -244.18452)
			(xy 338.209618 -244.198212) (xy 338.25408 -244.21931) (xy 338.294583 -244.247266) (xy 338.330076 -244.281358)
			(xy 338.359641 -244.320702) (xy 338.382512 -244.364279) (xy 338.398096 -244.41096) (xy 338.405991 -244.459537)
			(xy 338.406486 -244.484144) (xy 338.724743 -244.484144) (xy 338.728838 -244.433416) (xy 338.741017 -244.384002)
			(xy 338.760965 -244.337182) (xy 338.788166 -244.294168) (xy 338.821914 -244.256074) (xy 338.861336 -244.223887)
			(xy 338.90541 -244.198441) (xy 338.952996 -244.180394) (xy 339.00286 -244.170214) (xy 339.053712 -244.168165)
			(xy 339.104233 -244.174299) (xy 339.153117 -244.188459) (xy 339.199096 -244.210276) (xy 339.24098 -244.239186)
			(xy 339.277684 -244.274441) (xy 339.308257 -244.315127) (xy 339.331908 -244.36019) (xy 339.348024 -244.408464)
			(xy 339.356188 -244.458698) (xy 339.3567 -244.484144) (xy 339.664797 -244.484144) (xy 339.668892 -244.433416)
			(xy 339.681071 -244.384002) (xy 339.701019 -244.337182) (xy 339.72822 -244.294168) (xy 339.761968 -244.256074)
			(xy 339.80139 -244.223887) (xy 339.845464 -244.198441) (xy 339.89305 -244.180394) (xy 339.942914 -244.170214)
			(xy 339.993766 -244.168165) (xy 340.044287 -244.174299) (xy 340.093171 -244.188459) (xy 340.13915 -244.210276)
			(xy 340.181034 -244.239186) (xy 340.217738 -244.274441) (xy 340.248311 -244.315127) (xy 340.271962 -244.36019)
			(xy 340.288078 -244.408464) (xy 340.296242 -244.458698) (xy 340.296754 -244.484144) (xy 340.615282 -244.484144)
			(xy 340.619242 -244.43509) (xy 340.631019 -244.387306) (xy 340.65031 -244.34203) (xy 340.676613 -244.300434)
			(xy 340.709248 -244.263597) (xy 340.747369 -244.232472) (xy 340.78999 -244.207865) (xy 340.836006 -244.190413)
			(xy 340.884225 -244.180569) (xy 340.9334 -244.178588) (xy 340.982255 -244.18452) (xy 341.029526 -244.198212)
			(xy 341.073988 -244.21931) (xy 341.114491 -244.247266) (xy 341.149984 -244.281358) (xy 341.179549 -244.320702)
			(xy 341.20242 -244.364279) (xy 341.218004 -244.41096) (xy 341.225899 -244.459537) (xy 341.226394 -244.484144)
			(xy 341.544905 -244.484144) (xy 341.549 -244.433416) (xy 341.561179 -244.384002) (xy 341.581127 -244.337182)
			(xy 341.608328 -244.294168) (xy 341.642076 -244.256074) (xy 341.681498 -244.223887) (xy 341.725572 -244.198441)
			(xy 341.773158 -244.180394) (xy 341.823022 -244.170214) (xy 341.873874 -244.168165) (xy 341.924395 -244.174299)
			(xy 341.973279 -244.188459) (xy 342.019258 -244.210276) (xy 342.061142 -244.239186) (xy 342.097846 -244.274441)
			(xy 342.128419 -244.315127) (xy 342.15207 -244.36019) (xy 342.168186 -244.408464) (xy 342.17635 -244.458698)
			(xy 342.176862 -244.484144) (xy 342.49539 -244.484144) (xy 342.49935 -244.43509) (xy 342.511127 -244.387306)
			(xy 342.530418 -244.34203) (xy 342.556721 -244.300434) (xy 342.589356 -244.263597) (xy 342.627477 -244.232472)
			(xy 342.670098 -244.207865) (xy 342.716114 -244.190413) (xy 342.764333 -244.180569) (xy 342.813508 -244.178588)
			(xy 342.862363 -244.18452) (xy 342.909634 -244.198212) (xy 342.954096 -244.21931) (xy 342.994599 -244.247266)
			(xy 343.030092 -244.281358) (xy 343.059657 -244.320702) (xy 343.082528 -244.364279) (xy 343.098112 -244.41096)
			(xy 343.106007 -244.459537) (xy 343.106502 -244.484144) (xy 343.106007 -244.508751) (xy 343.098112 -244.557328)
			(xy 343.082528 -244.604009) (xy 343.059657 -244.647586) (xy 343.030092 -244.68693) (xy 342.994599 -244.721022)
			(xy 342.954096 -244.748978) (xy 342.909634 -244.770076) (xy 342.862363 -244.783768) (xy 342.813508 -244.7897)
			(xy 342.764333 -244.787719) (xy 342.716114 -244.777875) (xy 342.670098 -244.760423) (xy 342.627477 -244.735816)
			(xy 342.589356 -244.704691) (xy 342.556721 -244.667854) (xy 342.530418 -244.626258) (xy 342.511127 -244.580982)
			(xy 342.49935 -244.533198) (xy 342.49539 -244.484144) (xy 342.176862 -244.484144) (xy 342.17635 -244.50959)
			(xy 342.168186 -244.559824) (xy 342.15207 -244.608098) (xy 342.128419 -244.653161) (xy 342.097846 -244.693847)
			(xy 342.061142 -244.729102) (xy 342.019258 -244.758012) (xy 341.973279 -244.779829) (xy 341.924395 -244.793989)
			(xy 341.873874 -244.800123) (xy 341.823022 -244.798074) (xy 341.773158 -244.787894) (xy 341.725572 -244.769847)
			(xy 341.681498 -244.744401) (xy 341.642076 -244.712214) (xy 341.608328 -244.67412) (xy 341.581127 -244.631106)
			(xy 341.561179 -244.584286) (xy 341.549 -244.534872) (xy 341.544905 -244.484144) (xy 341.226394 -244.484144)
			(xy 341.225899 -244.508751) (xy 341.218004 -244.557328) (xy 341.20242 -244.604009) (xy 341.179549 -244.647586)
			(xy 341.149984 -244.68693) (xy 341.114491 -244.721022) (xy 341.073988 -244.748978) (xy 341.029526 -244.770076)
			(xy 340.982255 -244.783768) (xy 340.9334 -244.7897) (xy 340.884225 -244.787719) (xy 340.836006 -244.777875)
			(xy 340.78999 -244.760423) (xy 340.747369 -244.735816) (xy 340.709248 -244.704691) (xy 340.676613 -244.667854)
			(xy 340.65031 -244.626258) (xy 340.631019 -244.580982) (xy 340.619242 -244.533198) (xy 340.615282 -244.484144)
			(xy 340.296754 -244.484144) (xy 340.296242 -244.50959) (xy 340.288078 -244.559824) (xy 340.271962 -244.608098)
			(xy 340.248311 -244.653161) (xy 340.217738 -244.693847) (xy 340.181034 -244.729102) (xy 340.13915 -244.758012)
			(xy 340.093171 -244.779829) (xy 340.044287 -244.793989) (xy 339.993766 -244.800123) (xy 339.942914 -244.798074)
			(xy 339.89305 -244.787894) (xy 339.845464 -244.769847) (xy 339.80139 -244.744401) (xy 339.761968 -244.712214)
			(xy 339.72822 -244.67412) (xy 339.701019 -244.631106) (xy 339.681071 -244.584286) (xy 339.668892 -244.534872)
			(xy 339.664797 -244.484144) (xy 339.3567 -244.484144) (xy 339.356188 -244.50959) (xy 339.348024 -244.559824)
			(xy 339.331908 -244.608098) (xy 339.308257 -244.653161) (xy 339.277684 -244.693847) (xy 339.24098 -244.729102)
			(xy 339.199096 -244.758012) (xy 339.153117 -244.779829) (xy 339.104233 -244.793989) (xy 339.053712 -244.800123)
			(xy 339.00286 -244.798074) (xy 338.952996 -244.787894) (xy 338.90541 -244.769847) (xy 338.861336 -244.744401)
			(xy 338.821914 -244.712214) (xy 338.788166 -244.67412) (xy 338.760965 -244.631106) (xy 338.741017 -244.584286)
			(xy 338.728838 -244.534872) (xy 338.724743 -244.484144) (xy 338.406486 -244.484144) (xy 338.405991 -244.508751)
			(xy 338.398096 -244.557328) (xy 338.382512 -244.604009) (xy 338.359641 -244.647586) (xy 338.330076 -244.68693)
			(xy 338.294583 -244.721022) (xy 338.25408 -244.748978) (xy 338.209618 -244.770076) (xy 338.162347 -244.783768)
			(xy 338.113492 -244.7897) (xy 338.064317 -244.787719) (xy 338.016098 -244.777875) (xy 337.970082 -244.760423)
			(xy 337.927461 -244.735816) (xy 337.88934 -244.704691) (xy 337.856705 -244.667854) (xy 337.830402 -244.626258)
			(xy 337.811111 -244.580982) (xy 337.799334 -244.533198) (xy 337.795374 -244.484144) (xy 337.466432 -244.484144)
			(xy 337.465937 -244.508751) (xy 337.458042 -244.557328) (xy 337.442458 -244.604009) (xy 337.419587 -244.647586)
			(xy 337.390022 -244.68693) (xy 337.354529 -244.721022) (xy 337.314026 -244.748978) (xy 337.269564 -244.770076)
			(xy 337.222293 -244.783768) (xy 337.173438 -244.7897) (xy 337.124263 -244.787719) (xy 337.076044 -244.777875)
			(xy 337.030028 -244.760423) (xy 336.987407 -244.735816) (xy 336.949286 -244.704691) (xy 336.916651 -244.667854)
			(xy 336.890348 -244.626258) (xy 336.871057 -244.580982) (xy 336.85928 -244.533198) (xy 336.85532 -244.484144)
			(xy 336.526378 -244.484144) (xy 336.525883 -244.508751) (xy 336.517988 -244.557328) (xy 336.502404 -244.604009)
			(xy 336.479533 -244.647586) (xy 336.449968 -244.68693) (xy 336.414475 -244.721022) (xy 336.373972 -244.748978)
			(xy 336.32951 -244.770076) (xy 336.282239 -244.783768) (xy 336.233384 -244.7897) (xy 336.184209 -244.787719)
			(xy 336.13599 -244.777875) (xy 336.089974 -244.760423) (xy 336.047353 -244.735816) (xy 336.009232 -244.704691)
			(xy 335.976597 -244.667854) (xy 335.950294 -244.626258) (xy 335.931003 -244.580982) (xy 335.919226 -244.533198)
			(xy 335.915266 -244.484144) (xy 335.586324 -244.484144) (xy 335.585829 -244.508751) (xy 335.577934 -244.557328)
			(xy 335.56235 -244.604009) (xy 335.539479 -244.647586) (xy 335.509914 -244.68693) (xy 335.474421 -244.721022)
			(xy 335.433918 -244.748978) (xy 335.389456 -244.770076) (xy 335.342185 -244.783768) (xy 335.29333 -244.7897)
			(xy 335.244155 -244.787719) (xy 335.195936 -244.777875) (xy 335.14992 -244.760423) (xy 335.107299 -244.735816)
			(xy 335.069178 -244.704691) (xy 335.036543 -244.667854) (xy 335.01024 -244.626258) (xy 334.990949 -244.580982)
			(xy 334.979172 -244.533198) (xy 334.975212 -244.484144) (xy 334.646524 -244.484144) (xy 334.64605 -244.508133)
			(xy 334.638539 -244.555521) (xy 334.623708 -244.60115) (xy 334.601922 -244.643898) (xy 334.573718 -244.682712)
			(xy 334.53979 -244.716636) (xy 334.500974 -244.744837) (xy 334.458224 -244.766618) (xy 334.412593 -244.781445)
			(xy 334.365205 -244.788952) (xy 334.341216 -244.789452) (xy 334.309466 -244.787674) (xy 334.306672 -244.78742)
			(xy 334.304132 -244.78742) (xy 334.294108 -244.787835) (xy 334.275584 -244.7955) (xy 334.261406 -244.809674)
			(xy 334.253737 -244.828196) (xy 334.253332 -244.83822) (xy 334.253332 -244.85854) (xy 334.254094 -244.86743)
			(xy 334.255364 -244.874288) (xy 334.256962 -244.881903) (xy 334.26407 -244.895736) (xy 334.269334 -244.901466)
			(xy 334.269588 -244.90172) (xy 334.274922 -244.907308) (xy 334.298194 -244.932335) (xy 334.339102 -244.987083)
			(xy 334.373015 -245.046418) (xy 334.386682 -245.077742) (xy 334.389222 -245.083838) (xy 334.396842 -245.093998)
			(xy 334.421226 -245.113048) (xy 334.426701 -245.117009) (xy 334.439189 -245.122155) (xy 334.445864 -245.123208)
			(xy 334.516984 -245.13286) (xy 334.522959 -245.133478) (xy 334.5349 -245.132199) (xy 334.540606 -245.13032)
			(xy 334.551782 -245.12651) (xy 334.56499 -245.113302) (xy 334.567022 -245.110508) (xy 334.581565 -245.091953)
			(xy 334.615394 -245.059119) (xy 334.653858 -245.031861) (xy 334.696047 -245.010825) (xy 334.740964 -244.996509)
			(xy 334.787545 -244.98925) (xy 334.811116 -244.988842) (xy 334.836366 -244.989365) (xy 334.886178 -244.997679)
			(xy 334.933942 -245.014079) (xy 334.978355 -245.038116) (xy 335.018206 -245.069135) (xy 335.052408 -245.106291)
			(xy 335.080029 -245.148569) (xy 335.100314 -245.194816) (xy 335.112711 -245.243772) (xy 335.116881 -245.2941)
			(xy 335.116877 -245.29415) (xy 335.445366 -245.29415) (xy 335.449326 -245.245096) (xy 335.461103 -245.197312)
			(xy 335.480394 -245.152036) (xy 335.506697 -245.11044) (xy 335.539332 -245.073603) (xy 335.577453 -245.042478)
			(xy 335.620074 -245.017871) (xy 335.66609 -245.000419) (xy 335.714309 -244.990575) (xy 335.763484 -244.988594)
			(xy 335.812339 -244.994526) (xy 335.85961 -245.008218) (xy 335.904072 -245.029316) (xy 335.944575 -245.057272)
			(xy 335.980068 -245.091364) (xy 336.009633 -245.130708) (xy 336.032504 -245.174285) (xy 336.048088 -245.220966)
			(xy 336.055983 -245.269543) (xy 336.056478 -245.29415) (xy 336.38542 -245.29415) (xy 336.38938 -245.245096)
			(xy 336.401157 -245.197312) (xy 336.420448 -245.152036) (xy 336.446751 -245.11044) (xy 336.479386 -245.073603)
			(xy 336.517507 -245.042478) (xy 336.560128 -245.017871) (xy 336.606144 -245.000419) (xy 336.654363 -244.990575)
			(xy 336.703538 -244.988594) (xy 336.752393 -244.994526) (xy 336.799664 -245.008218) (xy 336.844126 -245.029316)
			(xy 336.884629 -245.057272) (xy 336.920122 -245.091364) (xy 336.949687 -245.130708) (xy 336.972558 -245.174285)
			(xy 336.988142 -245.220966) (xy 336.996037 -245.269543) (xy 336.996532 -245.29415) (xy 337.32522 -245.29415)
			(xy 337.32918 -245.245096) (xy 337.340957 -245.197312) (xy 337.360248 -245.152036) (xy 337.386551 -245.11044)
			(xy 337.419186 -245.073603) (xy 337.457307 -245.042478) (xy 337.499928 -245.017871) (xy 337.545944 -245.000419)
			(xy 337.594163 -244.990575) (xy 337.643338 -244.988594) (xy 337.692193 -244.994526) (xy 337.739464 -245.008218)
			(xy 337.783926 -245.029316) (xy 337.824429 -245.057272) (xy 337.859922 -245.091364) (xy 337.889487 -245.130708)
			(xy 337.912358 -245.174285) (xy 337.927942 -245.220966) (xy 337.935837 -245.269543) (xy 337.936332 -245.29415)
			(xy 338.254843 -245.29415) (xy 338.258938 -245.243422) (xy 338.271117 -245.194008) (xy 338.291065 -245.147188)
			(xy 338.318266 -245.104174) (xy 338.352014 -245.06608) (xy 338.391436 -245.033893) (xy 338.43551 -245.008447)
			(xy 338.483096 -244.9904) (xy 338.53296 -244.98022) (xy 338.583812 -244.978171) (xy 338.634333 -244.984305)
			(xy 338.683217 -244.998465) (xy 338.729196 -245.020282) (xy 338.77108 -245.049192) (xy 338.807784 -245.084447)
			(xy 338.838357 -245.125133) (xy 338.862008 -245.170196) (xy 338.878124 -245.21847) (xy 338.886288 -245.268704)
			(xy 338.8868 -245.29415) (xy 339.205328 -245.29415) (xy 339.209288 -245.245096) (xy 339.221065 -245.197312)
			(xy 339.240356 -245.152036) (xy 339.266659 -245.11044) (xy 339.299294 -245.073603) (xy 339.337415 -245.042478)
			(xy 339.380036 -245.017871) (xy 339.426052 -245.000419) (xy 339.474271 -244.990575) (xy 339.523446 -244.988594)
			(xy 339.572301 -244.994526) (xy 339.619572 -245.008218) (xy 339.664034 -245.029316) (xy 339.704537 -245.057272)
			(xy 339.74003 -245.091364) (xy 339.769595 -245.130708) (xy 339.792466 -245.174285) (xy 339.80805 -245.220966)
			(xy 339.815945 -245.269543) (xy 339.81644 -245.29415) (xy 340.134951 -245.29415) (xy 340.139046 -245.243422)
			(xy 340.151225 -245.194008) (xy 340.171173 -245.147188) (xy 340.198374 -245.104174) (xy 340.232122 -245.06608)
			(xy 340.271544 -245.033893) (xy 340.315618 -245.008447) (xy 340.363204 -244.9904) (xy 340.413068 -244.98022)
			(xy 340.46392 -244.978171) (xy 340.514441 -244.984305) (xy 340.563325 -244.998465) (xy 340.609304 -245.020282)
			(xy 340.651188 -245.049192) (xy 340.687892 -245.084447) (xy 340.718465 -245.125133) (xy 340.742116 -245.170196)
			(xy 340.758232 -245.21847) (xy 340.766396 -245.268704) (xy 340.766908 -245.29415) (xy 341.085182 -245.29415)
			(xy 341.089142 -245.245096) (xy 341.100919 -245.197312) (xy 341.12021 -245.152036) (xy 341.146513 -245.11044)
			(xy 341.179148 -245.073603) (xy 341.217269 -245.042478) (xy 341.25989 -245.017871) (xy 341.305906 -245.000419)
			(xy 341.354125 -244.990575) (xy 341.4033 -244.988594) (xy 341.452155 -244.994526) (xy 341.499426 -245.008218)
			(xy 341.543888 -245.029316) (xy 341.584391 -245.057272) (xy 341.619884 -245.091364) (xy 341.649449 -245.130708)
			(xy 341.67232 -245.174285) (xy 341.687904 -245.220966) (xy 341.695799 -245.269543) (xy 341.696294 -245.29415)
			(xy 342.014805 -245.29415) (xy 342.0189 -245.243422) (xy 342.031079 -245.194008) (xy 342.051027 -245.147188)
			(xy 342.078228 -245.104174) (xy 342.111976 -245.06608) (xy 342.151398 -245.033893) (xy 342.195472 -245.008447)
			(xy 342.243058 -244.9904) (xy 342.292922 -244.98022) (xy 342.343774 -244.978171) (xy 342.394295 -244.984305)
			(xy 342.443179 -244.998465) (xy 342.489158 -245.020282) (xy 342.531042 -245.049192) (xy 342.567746 -245.084447)
			(xy 342.598319 -245.125133) (xy 342.62197 -245.170196) (xy 342.638086 -245.21847) (xy 342.64625 -245.268704)
			(xy 342.646762 -245.29415) (xy 342.954859 -245.29415) (xy 342.958954 -245.243422) (xy 342.971133 -245.194008)
			(xy 342.991081 -245.147188) (xy 343.018282 -245.104174) (xy 343.05203 -245.06608) (xy 343.091452 -245.033893)
			(xy 343.135526 -245.008447) (xy 343.183112 -244.9904) (xy 343.232976 -244.98022) (xy 343.283828 -244.978171)
			(xy 343.334349 -244.984305) (xy 343.383233 -244.998465) (xy 343.429212 -245.020282) (xy 343.471096 -245.049192)
			(xy 343.5078 -245.084447) (xy 343.538373 -245.125133) (xy 343.562024 -245.170196) (xy 343.57814 -245.21847)
			(xy 343.586304 -245.268704) (xy 343.586816 -245.29415) (xy 343.586304 -245.319596) (xy 343.57814 -245.36983)
			(xy 343.562024 -245.418104) (xy 343.538373 -245.463167) (xy 343.5078 -245.503853) (xy 343.471096 -245.539108)
			(xy 343.429212 -245.568018) (xy 343.383233 -245.589835) (xy 343.334349 -245.603995) (xy 343.283828 -245.610129)
			(xy 343.232976 -245.60808) (xy 343.183112 -245.5979) (xy 343.135526 -245.579853) (xy 343.091452 -245.554407)
			(xy 343.05203 -245.52222) (xy 343.018282 -245.484126) (xy 342.991081 -245.441112) (xy 342.971133 -245.394292)
			(xy 342.958954 -245.344878) (xy 342.954859 -245.29415) (xy 342.646762 -245.29415) (xy 342.64625 -245.319596)
			(xy 342.638086 -245.36983) (xy 342.62197 -245.418104) (xy 342.598319 -245.463167) (xy 342.567746 -245.503853)
			(xy 342.531042 -245.539108) (xy 342.489158 -245.568018) (xy 342.443179 -245.589835) (xy 342.394295 -245.603995)
			(xy 342.343774 -245.610129) (xy 342.292922 -245.60808) (xy 342.243058 -245.5979) (xy 342.195472 -245.579853)
			(xy 342.151398 -245.554407) (xy 342.111976 -245.52222) (xy 342.078228 -245.484126) (xy 342.051027 -245.441112)
			(xy 342.031079 -245.394292) (xy 342.0189 -245.344878) (xy 342.014805 -245.29415) (xy 341.696294 -245.29415)
			(xy 341.695799 -245.318757) (xy 341.687904 -245.367334) (xy 341.67232 -245.414015) (xy 341.649449 -245.457592)
			(xy 341.619884 -245.496936) (xy 341.584391 -245.531028) (xy 341.543888 -245.558984) (xy 341.499426 -245.580082)
			(xy 341.452155 -245.593774) (xy 341.4033 -245.599706) (xy 341.354125 -245.597725) (xy 341.305906 -245.587881)
			(xy 341.25989 -245.570429) (xy 341.217269 -245.545822) (xy 341.179148 -245.514697) (xy 341.146513 -245.47786)
			(xy 341.12021 -245.436264) (xy 341.100919 -245.390988) (xy 341.089142 -245.343204) (xy 341.085182 -245.29415)
			(xy 340.766908 -245.29415) (xy 340.766396 -245.319596) (xy 340.758232 -245.36983) (xy 340.742116 -245.418104)
			(xy 340.718465 -245.463167) (xy 340.687892 -245.503853) (xy 340.651188 -245.539108) (xy 340.609304 -245.568018)
			(xy 340.563325 -245.589835) (xy 340.514441 -245.603995) (xy 340.46392 -245.610129) (xy 340.413068 -245.60808)
			(xy 340.363204 -245.5979) (xy 340.315618 -245.579853) (xy 340.271544 -245.554407) (xy 340.232122 -245.52222)
			(xy 340.198374 -245.484126) (xy 340.171173 -245.441112) (xy 340.151225 -245.394292) (xy 340.139046 -245.344878)
			(xy 340.134951 -245.29415) (xy 339.81644 -245.29415) (xy 339.815945 -245.318757) (xy 339.80805 -245.367334)
			(xy 339.792466 -245.414015) (xy 339.769595 -245.457592) (xy 339.74003 -245.496936) (xy 339.704537 -245.531028)
			(xy 339.664034 -245.558984) (xy 339.619572 -245.580082) (xy 339.572301 -245.593774) (xy 339.523446 -245.599706)
			(xy 339.474271 -245.597725) (xy 339.426052 -245.587881) (xy 339.380036 -245.570429) (xy 339.337415 -245.545822)
			(xy 339.299294 -245.514697) (xy 339.266659 -245.47786) (xy 339.240356 -245.436264) (xy 339.221065 -245.390988)
			(xy 339.209288 -245.343204) (xy 339.205328 -245.29415) (xy 338.8868 -245.29415) (xy 338.886288 -245.319596)
			(xy 338.878124 -245.36983) (xy 338.862008 -245.418104) (xy 338.838357 -245.463167) (xy 338.807784 -245.503853)
			(xy 338.77108 -245.539108) (xy 338.729196 -245.568018) (xy 338.683217 -245.589835) (xy 338.634333 -245.603995)
			(xy 338.583812 -245.610129) (xy 338.53296 -245.60808) (xy 338.483096 -245.5979) (xy 338.43551 -245.579853)
			(xy 338.391436 -245.554407) (xy 338.352014 -245.52222) (xy 338.318266 -245.484126) (xy 338.291065 -245.441112)
			(xy 338.271117 -245.394292) (xy 338.258938 -245.344878) (xy 338.254843 -245.29415) (xy 337.936332 -245.29415)
			(xy 337.935837 -245.318757) (xy 337.927942 -245.367334) (xy 337.912358 -245.414015) (xy 337.889487 -245.457592)
			(xy 337.859922 -245.496936) (xy 337.824429 -245.531028) (xy 337.783926 -245.558984) (xy 337.739464 -245.580082)
			(xy 337.692193 -245.593774) (xy 337.643338 -245.599706) (xy 337.594163 -245.597725) (xy 337.545944 -245.587881)
			(xy 337.499928 -245.570429) (xy 337.457307 -245.545822) (xy 337.419186 -245.514697) (xy 337.386551 -245.47786)
			(xy 337.360248 -245.436264) (xy 337.340957 -245.390988) (xy 337.32918 -245.343204) (xy 337.32522 -245.29415)
			(xy 336.996532 -245.29415) (xy 336.996037 -245.318757) (xy 336.988142 -245.367334) (xy 336.972558 -245.414015)
			(xy 336.949687 -245.457592) (xy 336.920122 -245.496936) (xy 336.884629 -245.531028) (xy 336.844126 -245.558984)
			(xy 336.799664 -245.580082) (xy 336.752393 -245.593774) (xy 336.703538 -245.599706) (xy 336.654363 -245.597725)
			(xy 336.606144 -245.587881) (xy 336.560128 -245.570429) (xy 336.517507 -245.545822) (xy 336.479386 -245.514697)
			(xy 336.446751 -245.47786) (xy 336.420448 -245.436264) (xy 336.401157 -245.390988) (xy 336.38938 -245.343204)
			(xy 336.38542 -245.29415) (xy 336.056478 -245.29415) (xy 336.055983 -245.318757) (xy 336.048088 -245.367334)
			(xy 336.032504 -245.414015) (xy 336.009633 -245.457592) (xy 335.980068 -245.496936) (xy 335.944575 -245.531028)
			(xy 335.904072 -245.558984) (xy 335.85961 -245.580082) (xy 335.812339 -245.593774) (xy 335.763484 -245.599706)
			(xy 335.714309 -245.597725) (xy 335.66609 -245.587881) (xy 335.620074 -245.570429) (xy 335.577453 -245.545822)
			(xy 335.539332 -245.514697) (xy 335.506697 -245.47786) (xy 335.480394 -245.436264) (xy 335.461103 -245.390988)
			(xy 335.449326 -245.343204) (xy 335.445366 -245.29415) (xy 335.116877 -245.29415) (xy 335.112711 -245.344428)
			(xy 335.100314 -245.393384) (xy 335.080029 -245.439631) (xy 335.052408 -245.481909) (xy 335.018206 -245.519065)
			(xy 334.978355 -245.550084) (xy 334.933942 -245.574121) (xy 334.886178 -245.590521) (xy 334.836366 -245.598835)
			(xy 334.811116 -245.599458) (xy 334.787545 -245.599023) (xy 334.740963 -245.591785) (xy 334.696045 -245.577479)
			(xy 334.653856 -245.556444) (xy 334.6154 -245.529179) (xy 334.581586 -245.496331) (xy 334.567022 -245.477792)
			(xy 334.56499 -245.474998) (xy 334.55991 -245.469918) (xy 334.553344 -245.463798) (xy 334.537073 -245.45625)
			(xy 334.52816 -245.455186) (xy 334.522572 -245.454678) (xy 334.432148 -245.46687) (xy 334.423227 -245.468413)
			(xy 334.407226 -245.476858) (xy 334.395151 -245.490333) (xy 334.391508 -245.49862) (xy 334.383587 -245.518327)
			(xy 334.365154 -245.556597) (xy 334.354678 -245.575074) (xy 334.312768 -245.64721) (xy 334.311498 -245.648988)
			(xy 334.303878 -245.660418) (xy 334.3021 -245.687596) (xy 334.338676 -245.762018) (xy 334.341551 -245.767351)
			(xy 334.34938 -245.776595) (xy 334.35417 -245.780306) (xy 334.382618 -245.801388) (xy 334.394302 -245.80342)
			(xy 334.417561 -245.807976) (xy 334.462402 -245.823322) (xy 334.504333 -245.845415) (xy 334.542344 -245.873723)
			(xy 334.575522 -245.907567) (xy 334.603071 -245.946133) (xy 334.624327 -245.988493) (xy 334.638779 -246.03363)
			(xy 334.646081 -246.080459) (xy 334.646524 -246.104156) (xy 334.975212 -246.104156) (xy 334.979172 -246.055102)
			(xy 334.990949 -246.007318) (xy 335.01024 -245.962042) (xy 335.036543 -245.920446) (xy 335.069178 -245.883609)
			(xy 335.107299 -245.852484) (xy 335.14992 -245.827877) (xy 335.195936 -245.810425) (xy 335.244155 -245.800581)
			(xy 335.29333 -245.7986) (xy 335.342185 -245.804532) (xy 335.389456 -245.818224) (xy 335.433918 -245.839322)
			(xy 335.474421 -245.867278) (xy 335.509914 -245.90137) (xy 335.539479 -245.940714) (xy 335.56235 -245.984291)
			(xy 335.577934 -246.030972) (xy 335.585829 -246.079549) (xy 335.586324 -246.104156) (xy 335.915266 -246.104156)
			(xy 335.919226 -246.055102) (xy 335.931003 -246.007318) (xy 335.950294 -245.962042) (xy 335.976597 -245.920446)
			(xy 336.009232 -245.883609) (xy 336.047353 -245.852484) (xy 336.089974 -245.827877) (xy 336.13599 -245.810425)
			(xy 336.184209 -245.800581) (xy 336.233384 -245.7986) (xy 336.282239 -245.804532) (xy 336.32951 -245.818224)
			(xy 336.373972 -245.839322) (xy 336.414475 -245.867278) (xy 336.449968 -245.90137) (xy 336.479533 -245.940714)
			(xy 336.502404 -245.984291) (xy 336.517988 -246.030972) (xy 336.525883 -246.079549) (xy 336.526378 -246.104156)
			(xy 336.85532 -246.104156) (xy 336.85928 -246.055102) (xy 336.871057 -246.007318) (xy 336.890348 -245.962042)
			(xy 336.916651 -245.920446) (xy 336.949286 -245.883609) (xy 336.987407 -245.852484) (xy 337.030028 -245.827877)
			(xy 337.076044 -245.810425) (xy 337.124263 -245.800581) (xy 337.173438 -245.7986) (xy 337.222293 -245.804532)
			(xy 337.269564 -245.818224) (xy 337.314026 -245.839322) (xy 337.354529 -245.867278) (xy 337.390022 -245.90137)
			(xy 337.419587 -245.940714) (xy 337.442458 -245.984291) (xy 337.458042 -246.030972) (xy 337.465937 -246.079549)
			(xy 337.466432 -246.104156) (xy 337.795374 -246.104156) (xy 337.799334 -246.055102) (xy 337.811111 -246.007318)
			(xy 337.830402 -245.962042) (xy 337.856705 -245.920446) (xy 337.88934 -245.883609) (xy 337.927461 -245.852484)
			(xy 337.970082 -245.827877) (xy 338.016098 -245.810425) (xy 338.064317 -245.800581) (xy 338.113492 -245.7986)
			(xy 338.162347 -245.804532) (xy 338.209618 -245.818224) (xy 338.25408 -245.839322) (xy 338.294583 -245.867278)
			(xy 338.330076 -245.90137) (xy 338.359641 -245.940714) (xy 338.382512 -245.984291) (xy 338.398096 -246.030972)
			(xy 338.405991 -246.079549) (xy 338.406486 -246.104156) (xy 338.724743 -246.104156) (xy 338.728838 -246.053428)
			(xy 338.741017 -246.004014) (xy 338.760965 -245.957194) (xy 338.788166 -245.91418) (xy 338.821914 -245.876086)
			(xy 338.861336 -245.843899) (xy 338.90541 -245.818453) (xy 338.952996 -245.800406) (xy 339.00286 -245.790226)
			(xy 339.053712 -245.788177) (xy 339.104233 -245.794311) (xy 339.153117 -245.808471) (xy 339.199096 -245.830288)
			(xy 339.24098 -245.859198) (xy 339.277684 -245.894453) (xy 339.308257 -245.935139) (xy 339.331908 -245.980202)
			(xy 339.348024 -246.028476) (xy 339.356188 -246.07871) (xy 339.3567 -246.104156) (xy 339.664797 -246.104156)
			(xy 339.668892 -246.053428) (xy 339.681071 -246.004014) (xy 339.701019 -245.957194) (xy 339.72822 -245.91418)
			(xy 339.761968 -245.876086) (xy 339.80139 -245.843899) (xy 339.845464 -245.818453) (xy 339.89305 -245.800406)
			(xy 339.942914 -245.790226) (xy 339.993766 -245.788177) (xy 340.044287 -245.794311) (xy 340.093171 -245.808471)
			(xy 340.13915 -245.830288) (xy 340.181034 -245.859198) (xy 340.217738 -245.894453) (xy 340.248311 -245.935139)
			(xy 340.271962 -245.980202) (xy 340.288078 -246.028476) (xy 340.296242 -246.07871) (xy 340.296754 -246.104156)
			(xy 340.615282 -246.104156) (xy 340.619242 -246.055102) (xy 340.631019 -246.007318) (xy 340.65031 -245.962042)
			(xy 340.676613 -245.920446) (xy 340.709248 -245.883609) (xy 340.747369 -245.852484) (xy 340.78999 -245.827877)
			(xy 340.836006 -245.810425) (xy 340.884225 -245.800581) (xy 340.9334 -245.7986) (xy 340.982255 -245.804532)
			(xy 341.029526 -245.818224) (xy 341.073988 -245.839322) (xy 341.114491 -245.867278) (xy 341.149984 -245.90137)
			(xy 341.179549 -245.940714) (xy 341.20242 -245.984291) (xy 341.218004 -246.030972) (xy 341.225899 -246.079549)
			(xy 341.226394 -246.104156) (xy 341.544905 -246.104156) (xy 341.549 -246.053428) (xy 341.561179 -246.004014)
			(xy 341.581127 -245.957194) (xy 341.608328 -245.91418) (xy 341.642076 -245.876086) (xy 341.681498 -245.843899)
			(xy 341.725572 -245.818453) (xy 341.773158 -245.800406) (xy 341.823022 -245.790226) (xy 341.873874 -245.788177)
			(xy 341.924395 -245.794311) (xy 341.973279 -245.808471) (xy 342.019258 -245.830288) (xy 342.061142 -245.859198)
			(xy 342.097846 -245.894453) (xy 342.128419 -245.935139) (xy 342.15207 -245.980202) (xy 342.168186 -246.028476)
			(xy 342.17635 -246.07871) (xy 342.176862 -246.104156) (xy 342.49539 -246.104156) (xy 342.49935 -246.055102)
			(xy 342.511127 -246.007318) (xy 342.530418 -245.962042) (xy 342.556721 -245.920446) (xy 342.589356 -245.883609)
			(xy 342.627477 -245.852484) (xy 342.670098 -245.827877) (xy 342.716114 -245.810425) (xy 342.764333 -245.800581)
			(xy 342.813508 -245.7986) (xy 342.862363 -245.804532) (xy 342.909634 -245.818224) (xy 342.954096 -245.839322)
			(xy 342.994599 -245.867278) (xy 343.030092 -245.90137) (xy 343.059657 -245.940714) (xy 343.082528 -245.984291)
			(xy 343.098112 -246.030972) (xy 343.106007 -246.079549) (xy 343.106502 -246.104156) (xy 343.424759 -246.104156)
			(xy 343.428854 -246.053428) (xy 343.441033 -246.004014) (xy 343.460981 -245.957194) (xy 343.488182 -245.91418)
			(xy 343.52193 -245.876086) (xy 343.561352 -245.843899) (xy 343.605426 -245.818453) (xy 343.653012 -245.800406)
			(xy 343.702876 -245.790226) (xy 343.753728 -245.788177) (xy 343.804249 -245.794311) (xy 343.853133 -245.808471)
			(xy 343.899112 -245.830288) (xy 343.940996 -245.859198) (xy 343.9777 -245.894453) (xy 344.008273 -245.935139)
			(xy 344.031924 -245.980202) (xy 344.04804 -246.028476) (xy 344.056204 -246.07871) (xy 344.056716 -246.104156)
			(xy 344.056204 -246.129602) (xy 344.04804 -246.179836) (xy 344.031924 -246.22811) (xy 344.008273 -246.273173)
			(xy 343.9777 -246.313859) (xy 343.940996 -246.349114) (xy 343.899112 -246.378024) (xy 343.853133 -246.399841)
			(xy 343.804249 -246.414001) (xy 343.753728 -246.420135) (xy 343.702876 -246.418086) (xy 343.653012 -246.407906)
			(xy 343.605426 -246.389859) (xy 343.561352 -246.364413) (xy 343.52193 -246.332226) (xy 343.488182 -246.294132)
			(xy 343.460981 -246.251118) (xy 343.441033 -246.204298) (xy 343.428854 -246.154884) (xy 343.424759 -246.104156)
			(xy 343.106502 -246.104156) (xy 343.106007 -246.128763) (xy 343.098112 -246.17734) (xy 343.082528 -246.224021)
			(xy 343.059657 -246.267598) (xy 343.030092 -246.306942) (xy 342.994599 -246.341034) (xy 342.954096 -246.36899)
			(xy 342.909634 -246.390088) (xy 342.862363 -246.40378) (xy 342.813508 -246.409712) (xy 342.764333 -246.407731)
			(xy 342.716114 -246.397887) (xy 342.670098 -246.380435) (xy 342.627477 -246.355828) (xy 342.589356 -246.324703)
			(xy 342.556721 -246.287866) (xy 342.530418 -246.24627) (xy 342.511127 -246.200994) (xy 342.49935 -246.15321)
			(xy 342.49539 -246.104156) (xy 342.176862 -246.104156) (xy 342.17635 -246.129602) (xy 342.168186 -246.179836)
			(xy 342.15207 -246.22811) (xy 342.128419 -246.273173) (xy 342.097846 -246.313859) (xy 342.061142 -246.349114)
			(xy 342.019258 -246.378024) (xy 341.973279 -246.399841) (xy 341.924395 -246.414001) (xy 341.873874 -246.420135)
			(xy 341.823022 -246.418086) (xy 341.773158 -246.407906) (xy 341.725572 -246.389859) (xy 341.681498 -246.364413)
			(xy 341.642076 -246.332226) (xy 341.608328 -246.294132) (xy 341.581127 -246.251118) (xy 341.561179 -246.204298)
			(xy 341.549 -246.154884) (xy 341.544905 -246.104156) (xy 341.226394 -246.104156) (xy 341.225899 -246.128763)
			(xy 341.218004 -246.17734) (xy 341.20242 -246.224021) (xy 341.179549 -246.267598) (xy 341.149984 -246.306942)
			(xy 341.114491 -246.341034) (xy 341.073988 -246.36899) (xy 341.029526 -246.390088) (xy 340.982255 -246.40378)
			(xy 340.9334 -246.409712) (xy 340.884225 -246.407731) (xy 340.836006 -246.397887) (xy 340.78999 -246.380435)
			(xy 340.747369 -246.355828) (xy 340.709248 -246.324703) (xy 340.676613 -246.287866) (xy 340.65031 -246.24627)
			(xy 340.631019 -246.200994) (xy 340.619242 -246.15321) (xy 340.615282 -246.104156) (xy 340.296754 -246.104156)
			(xy 340.296242 -246.129602) (xy 340.288078 -246.179836) (xy 340.271962 -246.22811) (xy 340.248311 -246.273173)
			(xy 340.217738 -246.313859) (xy 340.181034 -246.349114) (xy 340.13915 -246.378024) (xy 340.093171 -246.399841)
			(xy 340.044287 -246.414001) (xy 339.993766 -246.420135) (xy 339.942914 -246.418086) (xy 339.89305 -246.407906)
			(xy 339.845464 -246.389859) (xy 339.80139 -246.364413) (xy 339.761968 -246.332226) (xy 339.72822 -246.294132)
			(xy 339.701019 -246.251118) (xy 339.681071 -246.204298) (xy 339.668892 -246.154884) (xy 339.664797 -246.104156)
			(xy 339.3567 -246.104156) (xy 339.356188 -246.129602) (xy 339.348024 -246.179836) (xy 339.331908 -246.22811)
			(xy 339.308257 -246.273173) (xy 339.277684 -246.313859) (xy 339.24098 -246.349114) (xy 339.199096 -246.378024)
			(xy 339.153117 -246.399841) (xy 339.104233 -246.414001) (xy 339.053712 -246.420135) (xy 339.00286 -246.418086)
			(xy 338.952996 -246.407906) (xy 338.90541 -246.389859) (xy 338.861336 -246.364413) (xy 338.821914 -246.332226)
			(xy 338.788166 -246.294132) (xy 338.760965 -246.251118) (xy 338.741017 -246.204298) (xy 338.728838 -246.154884)
			(xy 338.724743 -246.104156) (xy 338.406486 -246.104156) (xy 338.405991 -246.128763) (xy 338.398096 -246.17734)
			(xy 338.382512 -246.224021) (xy 338.359641 -246.267598) (xy 338.330076 -246.306942) (xy 338.294583 -246.341034)
			(xy 338.25408 -246.36899) (xy 338.209618 -246.390088) (xy 338.162347 -246.40378) (xy 338.113492 -246.409712)
			(xy 338.064317 -246.407731) (xy 338.016098 -246.397887) (xy 337.970082 -246.380435) (xy 337.927461 -246.355828)
			(xy 337.88934 -246.324703) (xy 337.856705 -246.287866) (xy 337.830402 -246.24627) (xy 337.811111 -246.200994)
			(xy 337.799334 -246.15321) (xy 337.795374 -246.104156) (xy 337.466432 -246.104156) (xy 337.465937 -246.128763)
			(xy 337.458042 -246.17734) (xy 337.442458 -246.224021) (xy 337.419587 -246.267598) (xy 337.390022 -246.306942)
			(xy 337.354529 -246.341034) (xy 337.314026 -246.36899) (xy 337.269564 -246.390088) (xy 337.222293 -246.40378)
			(xy 337.173438 -246.409712) (xy 337.124263 -246.407731) (xy 337.076044 -246.397887) (xy 337.030028 -246.380435)
			(xy 336.987407 -246.355828) (xy 336.949286 -246.324703) (xy 336.916651 -246.287866) (xy 336.890348 -246.24627)
			(xy 336.871057 -246.200994) (xy 336.85928 -246.15321) (xy 336.85532 -246.104156) (xy 336.526378 -246.104156)
			(xy 336.525883 -246.128763) (xy 336.517988 -246.17734) (xy 336.502404 -246.224021) (xy 336.479533 -246.267598)
			(xy 336.449968 -246.306942) (xy 336.414475 -246.341034) (xy 336.373972 -246.36899) (xy 336.32951 -246.390088)
			(xy 336.282239 -246.40378) (xy 336.233384 -246.409712) (xy 336.184209 -246.407731) (xy 336.13599 -246.397887)
			(xy 336.089974 -246.380435) (xy 336.047353 -246.355828) (xy 336.009232 -246.324703) (xy 335.976597 -246.287866)
			(xy 335.950294 -246.24627) (xy 335.931003 -246.200994) (xy 335.919226 -246.15321) (xy 335.915266 -246.104156)
			(xy 335.586324 -246.104156) (xy 335.585829 -246.128763) (xy 335.577934 -246.17734) (xy 335.56235 -246.224021)
			(xy 335.539479 -246.267598) (xy 335.509914 -246.306942) (xy 335.474421 -246.341034) (xy 335.433918 -246.36899)
			(xy 335.389456 -246.390088) (xy 335.342185 -246.40378) (xy 335.29333 -246.409712) (xy 335.244155 -246.407731)
			(xy 335.195936 -246.397887) (xy 335.14992 -246.380435) (xy 335.107299 -246.355828) (xy 335.069178 -246.324703)
			(xy 335.036543 -246.287866) (xy 335.01024 -246.24627) (xy 334.990949 -246.200994) (xy 334.979172 -246.15321)
			(xy 334.975212 -246.104156) (xy 334.646524 -246.104156) (xy 334.646081 -246.128152) (xy 334.63858 -246.175554)
			(xy 334.623755 -246.221198) (xy 334.601973 -246.263962) (xy 334.573768 -246.302791) (xy 334.539836 -246.336729)
			(xy 334.501013 -246.364941) (xy 334.458254 -246.386732) (xy 334.412612 -246.401566) (xy 334.365212 -246.409076)
			(xy 334.341216 -246.409464) (xy 334.309466 -246.407686) (xy 334.306672 -246.407432) (xy 334.304132 -246.407432)
			(xy 334.294109 -246.407847) (xy 334.275587 -246.415512) (xy 334.261412 -246.429687) (xy 334.253747 -246.448209)
			(xy 334.253332 -246.458232) (xy 334.253332 -246.478552) (xy 334.254094 -246.487442) (xy 334.255364 -246.4943)
			(xy 334.256964 -246.501914) (xy 334.264074 -246.515745) (xy 334.269334 -246.521478) (xy 334.269588 -246.521732)
			(xy 334.274922 -246.52732) (xy 334.298194 -246.552348) (xy 334.339101 -246.607096) (xy 334.373013 -246.666432)
			(xy 334.386682 -246.697754) (xy 334.389222 -246.70385) (xy 334.396842 -246.71401) (xy 334.421226 -246.73306)
			(xy 334.426701 -246.73702) (xy 334.43919 -246.742165) (xy 334.445864 -246.74322) (xy 334.516984 -246.752872)
			(xy 334.522959 -246.75349) (xy 334.5349 -246.752211) (xy 334.540606 -246.750332) (xy 334.551782 -246.746522)
			(xy 334.56499 -246.733314) (xy 334.567022 -246.73052) (xy 334.581568 -246.711969) (xy 334.615401 -246.679144)
			(xy 334.653866 -246.651894) (xy 334.696055 -246.630865) (xy 334.740969 -246.616553) (xy 334.787547 -246.609297)
			(xy 334.811116 -246.608854) (xy 334.836374 -246.609377) (xy 334.886199 -246.617694) (xy 334.933977 -246.634098)
			(xy 334.978403 -246.658142) (xy 335.018266 -246.689171) (xy 335.052478 -246.726337) (xy 335.080106 -246.768627)
			(xy 335.100397 -246.814888) (xy 335.112798 -246.863857) (xy 335.116966 -246.914162) (xy 335.445366 -246.914162)
			(xy 335.449326 -246.865108) (xy 335.461103 -246.817324) (xy 335.480394 -246.772048) (xy 335.506697 -246.730452)
			(xy 335.539332 -246.693615) (xy 335.577453 -246.66249) (xy 335.620074 -246.637883) (xy 335.66609 -246.620431)
			(xy 335.714309 -246.610587) (xy 335.763484 -246.608606) (xy 335.812339 -246.614538) (xy 335.85961 -246.62823)
			(xy 335.904072 -246.649328) (xy 335.944575 -246.677284) (xy 335.980068 -246.711376) (xy 336.009633 -246.75072)
			(xy 336.032504 -246.794297) (xy 336.048088 -246.840978) (xy 336.055983 -246.889555) (xy 336.056478 -246.914162)
			(xy 336.38542 -246.914162) (xy 336.38938 -246.865108) (xy 336.401157 -246.817324) (xy 336.420448 -246.772048)
			(xy 336.446751 -246.730452) (xy 336.479386 -246.693615) (xy 336.517507 -246.66249) (xy 336.560128 -246.637883)
			(xy 336.606144 -246.620431) (xy 336.654363 -246.610587) (xy 336.703538 -246.608606) (xy 336.752393 -246.614538)
			(xy 336.799664 -246.62823) (xy 336.844126 -246.649328) (xy 336.884629 -246.677284) (xy 336.920122 -246.711376)
			(xy 336.949687 -246.75072) (xy 336.972558 -246.794297) (xy 336.988142 -246.840978) (xy 336.996037 -246.889555)
			(xy 336.996532 -246.914162) (xy 337.32522 -246.914162) (xy 337.32918 -246.865108) (xy 337.340957 -246.817324)
			(xy 337.360248 -246.772048) (xy 337.386551 -246.730452) (xy 337.419186 -246.693615) (xy 337.457307 -246.66249)
			(xy 337.499928 -246.637883) (xy 337.545944 -246.620431) (xy 337.594163 -246.610587) (xy 337.643338 -246.608606)
			(xy 337.692193 -246.614538) (xy 337.739464 -246.62823) (xy 337.783926 -246.649328) (xy 337.824429 -246.677284)
			(xy 337.859922 -246.711376) (xy 337.889487 -246.75072) (xy 337.912358 -246.794297) (xy 337.927942 -246.840978)
			(xy 337.935837 -246.889555) (xy 337.936332 -246.914162) (xy 338.254843 -246.914162) (xy 338.258938 -246.863434)
			(xy 338.271117 -246.81402) (xy 338.291065 -246.7672) (xy 338.318266 -246.724186) (xy 338.352014 -246.686092)
			(xy 338.391436 -246.653905) (xy 338.43551 -246.628459) (xy 338.483096 -246.610412) (xy 338.53296 -246.600232)
			(xy 338.583812 -246.598183) (xy 338.634333 -246.604317) (xy 338.683217 -246.618477) (xy 338.729196 -246.640294)
			(xy 338.77108 -246.669204) (xy 338.807784 -246.704459) (xy 338.838357 -246.745145) (xy 338.862008 -246.790208)
			(xy 338.878124 -246.838482) (xy 338.886288 -246.888716) (xy 338.8868 -246.914162) (xy 339.205328 -246.914162)
			(xy 339.209288 -246.865108) (xy 339.221065 -246.817324) (xy 339.240356 -246.772048) (xy 339.266659 -246.730452)
			(xy 339.299294 -246.693615) (xy 339.337415 -246.66249) (xy 339.380036 -246.637883) (xy 339.426052 -246.620431)
			(xy 339.474271 -246.610587) (xy 339.523446 -246.608606) (xy 339.572301 -246.614538) (xy 339.619572 -246.62823)
			(xy 339.664034 -246.649328) (xy 339.704537 -246.677284) (xy 339.74003 -246.711376) (xy 339.769595 -246.75072)
			(xy 339.792466 -246.794297) (xy 339.80805 -246.840978) (xy 339.815945 -246.889555) (xy 339.81644 -246.914162)
			(xy 340.134951 -246.914162) (xy 340.139046 -246.863434) (xy 340.151225 -246.81402) (xy 340.171173 -246.7672)
			(xy 340.198374 -246.724186) (xy 340.232122 -246.686092) (xy 340.271544 -246.653905) (xy 340.315618 -246.628459)
			(xy 340.363204 -246.610412) (xy 340.413068 -246.600232) (xy 340.46392 -246.598183) (xy 340.514441 -246.604317)
			(xy 340.563325 -246.618477) (xy 340.609304 -246.640294) (xy 340.651188 -246.669204) (xy 340.687892 -246.704459)
			(xy 340.718465 -246.745145) (xy 340.742116 -246.790208) (xy 340.758232 -246.838482) (xy 340.766396 -246.888716)
			(xy 340.766908 -246.914162) (xy 341.085182 -246.914162) (xy 341.089142 -246.865108) (xy 341.100919 -246.817324)
			(xy 341.12021 -246.772048) (xy 341.146513 -246.730452) (xy 341.179148 -246.693615) (xy 341.217269 -246.66249)
			(xy 341.25989 -246.637883) (xy 341.305906 -246.620431) (xy 341.354125 -246.610587) (xy 341.4033 -246.608606)
			(xy 341.452155 -246.614538) (xy 341.499426 -246.62823) (xy 341.543888 -246.649328) (xy 341.584391 -246.677284)
			(xy 341.619884 -246.711376) (xy 341.649449 -246.75072) (xy 341.67232 -246.794297) (xy 341.687904 -246.840978)
			(xy 341.695799 -246.889555) (xy 341.696294 -246.914162) (xy 342.014805 -246.914162) (xy 342.0189 -246.863434)
			(xy 342.031079 -246.81402) (xy 342.051027 -246.7672) (xy 342.078228 -246.724186) (xy 342.111976 -246.686092)
			(xy 342.151398 -246.653905) (xy 342.195472 -246.628459) (xy 342.243058 -246.610412) (xy 342.292922 -246.600232)
			(xy 342.343774 -246.598183) (xy 342.394295 -246.604317) (xy 342.443179 -246.618477) (xy 342.489158 -246.640294)
			(xy 342.531042 -246.669204) (xy 342.567746 -246.704459) (xy 342.598319 -246.745145) (xy 342.62197 -246.790208)
			(xy 342.638086 -246.838482) (xy 342.64625 -246.888716) (xy 342.646762 -246.914162) (xy 342.954859 -246.914162)
			(xy 342.958954 -246.863434) (xy 342.971133 -246.81402) (xy 342.991081 -246.7672) (xy 343.018282 -246.724186)
			(xy 343.05203 -246.686092) (xy 343.091452 -246.653905) (xy 343.135526 -246.628459) (xy 343.183112 -246.610412)
			(xy 343.232976 -246.600232) (xy 343.283828 -246.598183) (xy 343.334349 -246.604317) (xy 343.383233 -246.618477)
			(xy 343.429212 -246.640294) (xy 343.471096 -246.669204) (xy 343.5078 -246.704459) (xy 343.538373 -246.745145)
			(xy 343.562024 -246.790208) (xy 343.57814 -246.838482) (xy 343.586304 -246.888716) (xy 343.586816 -246.914162)
			(xy 343.586304 -246.939608) (xy 343.57814 -246.989842) (xy 343.562024 -247.038116) (xy 343.538373 -247.083179)
			(xy 343.5078 -247.123865) (xy 343.471096 -247.15912) (xy 343.429212 -247.18803) (xy 343.383233 -247.209847)
			(xy 343.334349 -247.224007) (xy 343.283828 -247.230141) (xy 343.232976 -247.228092) (xy 343.183112 -247.217912)
			(xy 343.135526 -247.199865) (xy 343.091452 -247.174419) (xy 343.05203 -247.142232) (xy 343.018282 -247.104138)
			(xy 342.991081 -247.061124) (xy 342.971133 -247.014304) (xy 342.958954 -246.96489) (xy 342.954859 -246.914162)
			(xy 342.646762 -246.914162) (xy 342.64625 -246.939608) (xy 342.638086 -246.989842) (xy 342.62197 -247.038116)
			(xy 342.598319 -247.083179) (xy 342.567746 -247.123865) (xy 342.531042 -247.15912) (xy 342.489158 -247.18803)
			(xy 342.443179 -247.209847) (xy 342.394295 -247.224007) (xy 342.343774 -247.230141) (xy 342.292922 -247.228092)
			(xy 342.243058 -247.217912) (xy 342.195472 -247.199865) (xy 342.151398 -247.174419) (xy 342.111976 -247.142232)
			(xy 342.078228 -247.104138) (xy 342.051027 -247.061124) (xy 342.031079 -247.014304) (xy 342.0189 -246.96489)
			(xy 342.014805 -246.914162) (xy 341.696294 -246.914162) (xy 341.695799 -246.938769) (xy 341.687904 -246.987346)
			(xy 341.67232 -247.034027) (xy 341.649449 -247.077604) (xy 341.619884 -247.116948) (xy 341.584391 -247.15104)
			(xy 341.543888 -247.178996) (xy 341.499426 -247.200094) (xy 341.452155 -247.213786) (xy 341.4033 -247.219718)
			(xy 341.354125 -247.217737) (xy 341.305906 -247.207893) (xy 341.25989 -247.190441) (xy 341.217269 -247.165834)
			(xy 341.179148 -247.134709) (xy 341.146513 -247.097872) (xy 341.12021 -247.056276) (xy 341.100919 -247.011)
			(xy 341.089142 -246.963216) (xy 341.085182 -246.914162) (xy 340.766908 -246.914162) (xy 340.766396 -246.939608)
			(xy 340.758232 -246.989842) (xy 340.742116 -247.038116) (xy 340.718465 -247.083179) (xy 340.687892 -247.123865)
			(xy 340.651188 -247.15912) (xy 340.609304 -247.18803) (xy 340.563325 -247.209847) (xy 340.514441 -247.224007)
			(xy 340.46392 -247.230141) (xy 340.413068 -247.228092) (xy 340.363204 -247.217912) (xy 340.315618 -247.199865)
			(xy 340.271544 -247.174419) (xy 340.232122 -247.142232) (xy 340.198374 -247.104138) (xy 340.171173 -247.061124)
			(xy 340.151225 -247.014304) (xy 340.139046 -246.96489) (xy 340.134951 -246.914162) (xy 339.81644 -246.914162)
			(xy 339.815945 -246.938769) (xy 339.80805 -246.987346) (xy 339.792466 -247.034027) (xy 339.769595 -247.077604)
			(xy 339.74003 -247.116948) (xy 339.704537 -247.15104) (xy 339.664034 -247.178996) (xy 339.619572 -247.200094)
			(xy 339.572301 -247.213786) (xy 339.523446 -247.219718) (xy 339.474271 -247.217737) (xy 339.426052 -247.207893)
			(xy 339.380036 -247.190441) (xy 339.337415 -247.165834) (xy 339.299294 -247.134709) (xy 339.266659 -247.097872)
			(xy 339.240356 -247.056276) (xy 339.221065 -247.011) (xy 339.209288 -246.963216) (xy 339.205328 -246.914162)
			(xy 338.8868 -246.914162) (xy 338.886288 -246.939608) (xy 338.878124 -246.989842) (xy 338.862008 -247.038116)
			(xy 338.838357 -247.083179) (xy 338.807784 -247.123865) (xy 338.77108 -247.15912) (xy 338.729196 -247.18803)
			(xy 338.683217 -247.209847) (xy 338.634333 -247.224007) (xy 338.583812 -247.230141) (xy 338.53296 -247.228092)
			(xy 338.483096 -247.217912) (xy 338.43551 -247.199865) (xy 338.391436 -247.174419) (xy 338.352014 -247.142232)
			(xy 338.318266 -247.104138) (xy 338.291065 -247.061124) (xy 338.271117 -247.014304) (xy 338.258938 -246.96489)
			(xy 338.254843 -246.914162) (xy 337.936332 -246.914162) (xy 337.935837 -246.938769) (xy 337.927942 -246.987346)
			(xy 337.912358 -247.034027) (xy 337.889487 -247.077604) (xy 337.859922 -247.116948) (xy 337.824429 -247.15104)
			(xy 337.783926 -247.178996) (xy 337.739464 -247.200094) (xy 337.692193 -247.213786) (xy 337.643338 -247.219718)
			(xy 337.594163 -247.217737) (xy 337.545944 -247.207893) (xy 337.499928 -247.190441) (xy 337.457307 -247.165834)
			(xy 337.419186 -247.134709) (xy 337.386551 -247.097872) (xy 337.360248 -247.056276) (xy 337.340957 -247.011)
			(xy 337.32918 -246.963216) (xy 337.32522 -246.914162) (xy 336.996532 -246.914162) (xy 336.996037 -246.938769)
			(xy 336.988142 -246.987346) (xy 336.972558 -247.034027) (xy 336.949687 -247.077604) (xy 336.920122 -247.116948)
			(xy 336.884629 -247.15104) (xy 336.844126 -247.178996) (xy 336.799664 -247.200094) (xy 336.752393 -247.213786)
			(xy 336.703538 -247.219718) (xy 336.654363 -247.217737) (xy 336.606144 -247.207893) (xy 336.560128 -247.190441)
			(xy 336.517507 -247.165834) (xy 336.479386 -247.134709) (xy 336.446751 -247.097872) (xy 336.420448 -247.056276)
			(xy 336.401157 -247.011) (xy 336.38938 -246.963216) (xy 336.38542 -246.914162) (xy 336.056478 -246.914162)
			(xy 336.055983 -246.938769) (xy 336.048088 -246.987346) (xy 336.032504 -247.034027) (xy 336.009633 -247.077604)
			(xy 335.980068 -247.116948) (xy 335.944575 -247.15104) (xy 335.904072 -247.178996) (xy 335.85961 -247.200094)
			(xy 335.812339 -247.213786) (xy 335.763484 -247.219718) (xy 335.714309 -247.217737) (xy 335.66609 -247.207893)
			(xy 335.620074 -247.190441) (xy 335.577453 -247.165834) (xy 335.539332 -247.134709) (xy 335.506697 -247.097872)
			(xy 335.480394 -247.056276) (xy 335.461103 -247.011) (xy 335.449326 -246.963216) (xy 335.445366 -246.914162)
			(xy 335.116966 -246.914162) (xy 335.116969 -246.9142) (xy 335.112798 -246.964543) (xy 335.100397 -247.013512)
			(xy 335.080106 -247.059773) (xy 335.052478 -247.102063) (xy 335.018266 -247.139229) (xy 334.978403 -247.170258)
			(xy 334.933977 -247.194302) (xy 334.886199 -247.210706) (xy 334.836374 -247.219023) (xy 334.811116 -247.21947)
			(xy 334.787545 -247.219035) (xy 334.740962 -247.211797) (xy 334.696044 -247.197491) (xy 334.653855 -247.176457)
			(xy 334.615397 -247.149192) (xy 334.581583 -247.116345) (xy 334.567022 -247.097804) (xy 334.56499 -247.09501)
			(xy 334.55991 -247.08993) (xy 334.553345 -247.083809) (xy 334.537073 -247.076259) (xy 334.52816 -247.075198)
			(xy 334.522572 -247.07469) (xy 334.432148 -247.086882) (xy 334.423227 -247.088426) (xy 334.407228 -247.096872)
			(xy 334.395156 -247.110347) (xy 334.391508 -247.118632) (xy 334.383586 -247.138339) (xy 334.365152 -247.176609)
			(xy 334.354678 -247.195086) (xy 334.312768 -247.267222) (xy 334.311498 -247.269) (xy 334.303878 -247.28043)
			(xy 334.3021 -247.307608) (xy 334.338676 -247.38203) (xy 334.341552 -247.387363) (xy 334.349382 -247.396605)
			(xy 334.35417 -247.400318) (xy 334.382618 -247.4214) (xy 334.394302 -247.423432) (xy 334.417561 -247.427988)
			(xy 334.462401 -247.443334) (xy 334.50433 -247.465427) (xy 334.54234 -247.493736) (xy 334.575518 -247.52758)
			(xy 334.603065 -247.566146) (xy 334.624319 -247.608506) (xy 334.63877 -247.653643) (xy 334.64607 -247.700471)
			(xy 334.646524 -247.724168) (xy 334.975212 -247.724168) (xy 334.979172 -247.675114) (xy 334.990949 -247.62733)
			(xy 335.01024 -247.582054) (xy 335.036543 -247.540458) (xy 335.069178 -247.503621) (xy 335.107299 -247.472496)
			(xy 335.14992 -247.447889) (xy 335.195936 -247.430437) (xy 335.244155 -247.420593) (xy 335.29333 -247.418612)
			(xy 335.342185 -247.424544) (xy 335.389456 -247.438236) (xy 335.433918 -247.459334) (xy 335.474421 -247.48729)
			(xy 335.509914 -247.521382) (xy 335.539479 -247.560726) (xy 335.56235 -247.604303) (xy 335.577934 -247.650984)
			(xy 335.585829 -247.699561) (xy 335.586324 -247.724168) (xy 335.915266 -247.724168) (xy 335.919226 -247.675114)
			(xy 335.931003 -247.62733) (xy 335.950294 -247.582054) (xy 335.976597 -247.540458) (xy 336.009232 -247.503621)
			(xy 336.047353 -247.472496) (xy 336.089974 -247.447889) (xy 336.13599 -247.430437) (xy 336.184209 -247.420593)
			(xy 336.233384 -247.418612) (xy 336.282239 -247.424544) (xy 336.32951 -247.438236) (xy 336.373972 -247.459334)
			(xy 336.414475 -247.48729) (xy 336.449968 -247.521382) (xy 336.479533 -247.560726) (xy 336.502404 -247.604303)
			(xy 336.517988 -247.650984) (xy 336.525883 -247.699561) (xy 336.526378 -247.724168) (xy 336.85532 -247.724168)
			(xy 336.85928 -247.675114) (xy 336.871057 -247.62733) (xy 336.890348 -247.582054) (xy 336.916651 -247.540458)
			(xy 336.949286 -247.503621) (xy 336.987407 -247.472496) (xy 337.030028 -247.447889) (xy 337.076044 -247.430437)
			(xy 337.124263 -247.420593) (xy 337.173438 -247.418612) (xy 337.222293 -247.424544) (xy 337.269564 -247.438236)
			(xy 337.314026 -247.459334) (xy 337.354529 -247.48729) (xy 337.390022 -247.521382) (xy 337.419587 -247.560726)
			(xy 337.442458 -247.604303) (xy 337.458042 -247.650984) (xy 337.465937 -247.699561) (xy 337.466432 -247.724168)
			(xy 337.795374 -247.724168) (xy 337.799334 -247.675114) (xy 337.811111 -247.62733) (xy 337.830402 -247.582054)
			(xy 337.856705 -247.540458) (xy 337.88934 -247.503621) (xy 337.927461 -247.472496) (xy 337.970082 -247.447889)
			(xy 338.016098 -247.430437) (xy 338.064317 -247.420593) (xy 338.113492 -247.418612) (xy 338.162347 -247.424544)
			(xy 338.209618 -247.438236) (xy 338.25408 -247.459334) (xy 338.294583 -247.48729) (xy 338.330076 -247.521382)
			(xy 338.359641 -247.560726) (xy 338.382512 -247.604303) (xy 338.398096 -247.650984) (xy 338.405991 -247.699561)
			(xy 338.406486 -247.724168) (xy 338.724743 -247.724168) (xy 338.728838 -247.67344) (xy 338.741017 -247.624026)
			(xy 338.760965 -247.577206) (xy 338.788166 -247.534192) (xy 338.821914 -247.496098) (xy 338.861336 -247.463911)
			(xy 338.90541 -247.438465) (xy 338.952996 -247.420418) (xy 339.00286 -247.410238) (xy 339.053712 -247.408189)
			(xy 339.104233 -247.414323) (xy 339.153117 -247.428483) (xy 339.199096 -247.4503) (xy 339.24098 -247.47921)
			(xy 339.277684 -247.514465) (xy 339.308257 -247.555151) (xy 339.331908 -247.600214) (xy 339.348024 -247.648488)
			(xy 339.356188 -247.698722) (xy 339.3567 -247.724168) (xy 339.664797 -247.724168) (xy 339.668892 -247.67344)
			(xy 339.681071 -247.624026) (xy 339.701019 -247.577206) (xy 339.72822 -247.534192) (xy 339.761968 -247.496098)
			(xy 339.80139 -247.463911) (xy 339.845464 -247.438465) (xy 339.89305 -247.420418) (xy 339.942914 -247.410238)
			(xy 339.993766 -247.408189) (xy 340.044287 -247.414323) (xy 340.093171 -247.428483) (xy 340.13915 -247.4503)
			(xy 340.181034 -247.47921) (xy 340.217738 -247.514465) (xy 340.248311 -247.555151) (xy 340.271962 -247.600214)
			(xy 340.288078 -247.648488) (xy 340.296242 -247.698722) (xy 340.296754 -247.724168) (xy 340.615282 -247.724168)
			(xy 340.619242 -247.675114) (xy 340.631019 -247.62733) (xy 340.65031 -247.582054) (xy 340.676613 -247.540458)
			(xy 340.709248 -247.503621) (xy 340.747369 -247.472496) (xy 340.78999 -247.447889) (xy 340.836006 -247.430437)
			(xy 340.884225 -247.420593) (xy 340.9334 -247.418612) (xy 340.982255 -247.424544) (xy 341.029526 -247.438236)
			(xy 341.073988 -247.459334) (xy 341.114491 -247.48729) (xy 341.149984 -247.521382) (xy 341.179549 -247.560726)
			(xy 341.20242 -247.604303) (xy 341.218004 -247.650984) (xy 341.225899 -247.699561) (xy 341.226394 -247.724168)
			(xy 341.544905 -247.724168) (xy 341.549 -247.67344) (xy 341.561179 -247.624026) (xy 341.581127 -247.577206)
			(xy 341.608328 -247.534192) (xy 341.642076 -247.496098) (xy 341.681498 -247.463911) (xy 341.725572 -247.438465)
			(xy 341.773158 -247.420418) (xy 341.823022 -247.410238) (xy 341.873874 -247.408189) (xy 341.924395 -247.414323)
			(xy 341.973279 -247.428483) (xy 342.019258 -247.4503) (xy 342.061142 -247.47921) (xy 342.097846 -247.514465)
			(xy 342.128419 -247.555151) (xy 342.15207 -247.600214) (xy 342.168186 -247.648488) (xy 342.17635 -247.698722)
			(xy 342.176862 -247.724168) (xy 342.49539 -247.724168) (xy 342.49935 -247.675114) (xy 342.511127 -247.62733)
			(xy 342.530418 -247.582054) (xy 342.556721 -247.540458) (xy 342.589356 -247.503621) (xy 342.627477 -247.472496)
			(xy 342.670098 -247.447889) (xy 342.716114 -247.430437) (xy 342.764333 -247.420593) (xy 342.813508 -247.418612)
			(xy 342.862363 -247.424544) (xy 342.909634 -247.438236) (xy 342.954096 -247.459334) (xy 342.994599 -247.48729)
			(xy 343.030092 -247.521382) (xy 343.059657 -247.560726) (xy 343.082528 -247.604303) (xy 343.098112 -247.650984)
			(xy 343.106007 -247.699561) (xy 343.106502 -247.724168) (xy 343.424759 -247.724168) (xy 343.428854 -247.67344)
			(xy 343.441033 -247.624026) (xy 343.460981 -247.577206) (xy 343.488182 -247.534192) (xy 343.52193 -247.496098)
			(xy 343.561352 -247.463911) (xy 343.605426 -247.438465) (xy 343.653012 -247.420418) (xy 343.702876 -247.410238)
			(xy 343.753728 -247.408189) (xy 343.804249 -247.414323) (xy 343.853133 -247.428483) (xy 343.899112 -247.4503)
			(xy 343.940996 -247.47921) (xy 343.9777 -247.514465) (xy 344.008273 -247.555151) (xy 344.031924 -247.600214)
			(xy 344.04804 -247.648488) (xy 344.056204 -247.698722) (xy 344.056716 -247.724168) (xy 344.056204 -247.749614)
			(xy 344.04804 -247.799848) (xy 344.031924 -247.848122) (xy 344.008273 -247.893185) (xy 343.9777 -247.933871)
			(xy 343.940996 -247.969126) (xy 343.899112 -247.998036) (xy 343.853133 -248.019853) (xy 343.804249 -248.034013)
			(xy 343.753728 -248.040147) (xy 343.702876 -248.038098) (xy 343.653012 -248.027918) (xy 343.605426 -248.009871)
			(xy 343.561352 -247.984425) (xy 343.52193 -247.952238) (xy 343.488182 -247.914144) (xy 343.460981 -247.87113)
			(xy 343.441033 -247.82431) (xy 343.428854 -247.774896) (xy 343.424759 -247.724168) (xy 343.106502 -247.724168)
			(xy 343.106007 -247.748775) (xy 343.098112 -247.797352) (xy 343.082528 -247.844033) (xy 343.059657 -247.88761)
			(xy 343.030092 -247.926954) (xy 342.994599 -247.961046) (xy 342.954096 -247.989002) (xy 342.909634 -248.0101)
			(xy 342.862363 -248.023792) (xy 342.813508 -248.029724) (xy 342.764333 -248.027743) (xy 342.716114 -248.017899)
			(xy 342.670098 -248.000447) (xy 342.627477 -247.97584) (xy 342.589356 -247.944715) (xy 342.556721 -247.907878)
			(xy 342.530418 -247.866282) (xy 342.511127 -247.821006) (xy 342.49935 -247.773222) (xy 342.49539 -247.724168)
			(xy 342.176862 -247.724168) (xy 342.17635 -247.749614) (xy 342.168186 -247.799848) (xy 342.15207 -247.848122)
			(xy 342.128419 -247.893185) (xy 342.097846 -247.933871) (xy 342.061142 -247.969126) (xy 342.019258 -247.998036)
			(xy 341.973279 -248.019853) (xy 341.924395 -248.034013) (xy 341.873874 -248.040147) (xy 341.823022 -248.038098)
			(xy 341.773158 -248.027918) (xy 341.725572 -248.009871) (xy 341.681498 -247.984425) (xy 341.642076 -247.952238)
			(xy 341.608328 -247.914144) (xy 341.581127 -247.87113) (xy 341.561179 -247.82431) (xy 341.549 -247.774896)
			(xy 341.544905 -247.724168) (xy 341.226394 -247.724168) (xy 341.225899 -247.748775) (xy 341.218004 -247.797352)
			(xy 341.20242 -247.844033) (xy 341.179549 -247.88761) (xy 341.149984 -247.926954) (xy 341.114491 -247.961046)
			(xy 341.073988 -247.989002) (xy 341.029526 -248.0101) (xy 340.982255 -248.023792) (xy 340.9334 -248.029724)
			(xy 340.884225 -248.027743) (xy 340.836006 -248.017899) (xy 340.78999 -248.000447) (xy 340.747369 -247.97584)
			(xy 340.709248 -247.944715) (xy 340.676613 -247.907878) (xy 340.65031 -247.866282) (xy 340.631019 -247.821006)
			(xy 340.619242 -247.773222) (xy 340.615282 -247.724168) (xy 340.296754 -247.724168) (xy 340.296242 -247.749614)
			(xy 340.288078 -247.799848) (xy 340.271962 -247.848122) (xy 340.248311 -247.893185) (xy 340.217738 -247.933871)
			(xy 340.181034 -247.969126) (xy 340.13915 -247.998036) (xy 340.093171 -248.019853) (xy 340.044287 -248.034013)
			(xy 339.993766 -248.040147) (xy 339.942914 -248.038098) (xy 339.89305 -248.027918) (xy 339.845464 -248.009871)
			(xy 339.80139 -247.984425) (xy 339.761968 -247.952238) (xy 339.72822 -247.914144) (xy 339.701019 -247.87113)
			(xy 339.681071 -247.82431) (xy 339.668892 -247.774896) (xy 339.664797 -247.724168) (xy 339.3567 -247.724168)
			(xy 339.356188 -247.749614) (xy 339.348024 -247.799848) (xy 339.331908 -247.848122) (xy 339.308257 -247.893185)
			(xy 339.277684 -247.933871) (xy 339.24098 -247.969126) (xy 339.199096 -247.998036) (xy 339.153117 -248.019853)
			(xy 339.104233 -248.034013) (xy 339.053712 -248.040147) (xy 339.00286 -248.038098) (xy 338.952996 -248.027918)
			(xy 338.90541 -248.009871) (xy 338.861336 -247.984425) (xy 338.821914 -247.952238) (xy 338.788166 -247.914144)
			(xy 338.760965 -247.87113) (xy 338.741017 -247.82431) (xy 338.728838 -247.774896) (xy 338.724743 -247.724168)
			(xy 338.406486 -247.724168) (xy 338.405991 -247.748775) (xy 338.398096 -247.797352) (xy 338.382512 -247.844033)
			(xy 338.359641 -247.88761) (xy 338.330076 -247.926954) (xy 338.294583 -247.961046) (xy 338.25408 -247.989002)
			(xy 338.209618 -248.0101) (xy 338.162347 -248.023792) (xy 338.113492 -248.029724) (xy 338.064317 -248.027743)
			(xy 338.016098 -248.017899) (xy 337.970082 -248.000447) (xy 337.927461 -247.97584) (xy 337.88934 -247.944715)
			(xy 337.856705 -247.907878) (xy 337.830402 -247.866282) (xy 337.811111 -247.821006) (xy 337.799334 -247.773222)
			(xy 337.795374 -247.724168) (xy 337.466432 -247.724168) (xy 337.465937 -247.748775) (xy 337.458042 -247.797352)
			(xy 337.442458 -247.844033) (xy 337.419587 -247.88761) (xy 337.390022 -247.926954) (xy 337.354529 -247.961046)
			(xy 337.314026 -247.989002) (xy 337.269564 -248.0101) (xy 337.222293 -248.023792) (xy 337.173438 -248.029724)
			(xy 337.124263 -248.027743) (xy 337.076044 -248.017899) (xy 337.030028 -248.000447) (xy 336.987407 -247.97584)
			(xy 336.949286 -247.944715) (xy 336.916651 -247.907878) (xy 336.890348 -247.866282) (xy 336.871057 -247.821006)
			(xy 336.85928 -247.773222) (xy 336.85532 -247.724168) (xy 336.526378 -247.724168) (xy 336.525883 -247.748775)
			(xy 336.517988 -247.797352) (xy 336.502404 -247.844033) (xy 336.479533 -247.88761) (xy 336.449968 -247.926954)
			(xy 336.414475 -247.961046) (xy 336.373972 -247.989002) (xy 336.32951 -248.0101) (xy 336.282239 -248.023792)
			(xy 336.233384 -248.029724) (xy 336.184209 -248.027743) (xy 336.13599 -248.017899) (xy 336.089974 -248.000447)
			(xy 336.047353 -247.97584) (xy 336.009232 -247.944715) (xy 335.976597 -247.907878) (xy 335.950294 -247.866282)
			(xy 335.931003 -247.821006) (xy 335.919226 -247.773222) (xy 335.915266 -247.724168) (xy 335.586324 -247.724168)
			(xy 335.585829 -247.748775) (xy 335.577934 -247.797352) (xy 335.56235 -247.844033) (xy 335.539479 -247.88761)
			(xy 335.509914 -247.926954) (xy 335.474421 -247.961046) (xy 335.433918 -247.989002) (xy 335.389456 -248.0101)
			(xy 335.342185 -248.023792) (xy 335.29333 -248.029724) (xy 335.244155 -248.027743) (xy 335.195936 -248.017899)
			(xy 335.14992 -248.000447) (xy 335.107299 -247.97584) (xy 335.069178 -247.944715) (xy 335.036543 -247.907878)
			(xy 335.01024 -247.866282) (xy 334.990949 -247.821006) (xy 334.979172 -247.773222) (xy 334.975212 -247.724168)
			(xy 334.646524 -247.724168) (xy 334.64608 -247.748163) (xy 334.638578 -247.795564) (xy 334.623752 -247.841207)
			(xy 334.601969 -247.883968) (xy 334.573764 -247.922796) (xy 334.539832 -247.956733) (xy 334.501009 -247.984944)
			(xy 334.458251 -248.006734) (xy 334.41261 -248.021566) (xy 334.365211 -248.029076) (xy 334.341216 -248.029476)
			(xy 334.309466 -248.027698) (xy 334.306672 -248.027444) (xy 334.304132 -248.027444) (xy 334.29411 -248.027859)
			(xy 334.275589 -248.035525) (xy 334.261418 -248.049699) (xy 334.253756 -248.068222) (xy 334.253332 -248.078244)
			(xy 334.253332 -248.098564) (xy 334.254094 -248.107454) (xy 334.255364 -248.114312) (xy 334.256965 -248.121925)
			(xy 334.264078 -248.135754) (xy 334.269334 -248.14149) (xy 334.269588 -248.141744) (xy 334.274922 -248.147332)
			(xy 334.298193 -248.17236) (xy 334.339099 -248.227109) (xy 334.37301 -248.286445) (xy 334.386682 -248.317766)
			(xy 334.389222 -248.323862) (xy 334.396842 -248.334022) (xy 334.421226 -248.353072) (xy 334.426701 -248.357031)
			(xy 334.43919 -248.362175) (xy 334.445864 -248.363232) (xy 334.516984 -248.372884) (xy 334.522959 -248.373502)
			(xy 334.534901 -248.372223) (xy 334.540606 -248.370344) (xy 334.551782 -248.366534) (xy 334.56499 -248.353326)
			(xy 334.567022 -248.350532) (xy 334.581568 -248.331981) (xy 334.6154 -248.299154) (xy 334.653865 -248.271903)
			(xy 334.696054 -248.250873) (xy 334.740968 -248.23656) (xy 334.787546 -248.229304) (xy 334.811116 -248.228866)
			(xy 334.836373 -248.229389) (xy 334.886197 -248.237705) (xy 334.933972 -248.254109) (xy 334.978396 -248.278152)
			(xy 335.018258 -248.309179) (xy 335.052468 -248.346344) (xy 335.080096 -248.388633) (xy 335.100386 -248.434892)
			(xy 335.112786 -248.483859) (xy 335.116955 -248.534174) (xy 335.445366 -248.534174) (xy 335.449326 -248.48512)
			(xy 335.461103 -248.437336) (xy 335.480394 -248.39206) (xy 335.506697 -248.350464) (xy 335.539332 -248.313627)
			(xy 335.577453 -248.282502) (xy 335.620074 -248.257895) (xy 335.66609 -248.240443) (xy 335.714309 -248.230599)
			(xy 335.763484 -248.228618) (xy 335.812339 -248.23455) (xy 335.85961 -248.248242) (xy 335.904072 -248.26934)
			(xy 335.944575 -248.297296) (xy 335.980068 -248.331388) (xy 336.009633 -248.370732) (xy 336.032504 -248.414309)
			(xy 336.048088 -248.46099) (xy 336.055983 -248.509567) (xy 336.056478 -248.534174) (xy 336.38542 -248.534174)
			(xy 336.38938 -248.48512) (xy 336.401157 -248.437336) (xy 336.420448 -248.39206) (xy 336.446751 -248.350464)
			(xy 336.479386 -248.313627) (xy 336.517507 -248.282502) (xy 336.560128 -248.257895) (xy 336.606144 -248.240443)
			(xy 336.654363 -248.230599) (xy 336.703538 -248.228618) (xy 336.752393 -248.23455) (xy 336.799664 -248.248242)
			(xy 336.844126 -248.26934) (xy 336.884629 -248.297296) (xy 336.920122 -248.331388) (xy 336.949687 -248.370732)
			(xy 336.972558 -248.414309) (xy 336.988142 -248.46099) (xy 336.996037 -248.509567) (xy 336.996532 -248.534174)
			(xy 337.32522 -248.534174) (xy 337.32918 -248.48512) (xy 337.340957 -248.437336) (xy 337.360248 -248.39206)
			(xy 337.386551 -248.350464) (xy 337.419186 -248.313627) (xy 337.457307 -248.282502) (xy 337.499928 -248.257895)
			(xy 337.545944 -248.240443) (xy 337.594163 -248.230599) (xy 337.643338 -248.228618) (xy 337.692193 -248.23455)
			(xy 337.739464 -248.248242) (xy 337.783926 -248.26934) (xy 337.824429 -248.297296) (xy 337.859922 -248.331388)
			(xy 337.889487 -248.370732) (xy 337.912358 -248.414309) (xy 337.927942 -248.46099) (xy 337.935837 -248.509567)
			(xy 337.936332 -248.534174) (xy 338.254843 -248.534174) (xy 338.258938 -248.483446) (xy 338.271117 -248.434032)
			(xy 338.291065 -248.387212) (xy 338.318266 -248.344198) (xy 338.352014 -248.306104) (xy 338.391436 -248.273917)
			(xy 338.43551 -248.248471) (xy 338.483096 -248.230424) (xy 338.53296 -248.220244) (xy 338.583812 -248.218195)
			(xy 338.634333 -248.224329) (xy 338.683217 -248.238489) (xy 338.729196 -248.260306) (xy 338.77108 -248.289216)
			(xy 338.807784 -248.324471) (xy 338.838357 -248.365157) (xy 338.862008 -248.41022) (xy 338.878124 -248.458494)
			(xy 338.886288 -248.508728) (xy 338.8868 -248.534174) (xy 339.205328 -248.534174) (xy 339.209288 -248.48512)
			(xy 339.221065 -248.437336) (xy 339.240356 -248.39206) (xy 339.266659 -248.350464) (xy 339.299294 -248.313627)
			(xy 339.337415 -248.282502) (xy 339.380036 -248.257895) (xy 339.426052 -248.240443) (xy 339.474271 -248.230599)
			(xy 339.523446 -248.228618) (xy 339.572301 -248.23455) (xy 339.619572 -248.248242) (xy 339.664034 -248.26934)
			(xy 339.704537 -248.297296) (xy 339.74003 -248.331388) (xy 339.769595 -248.370732) (xy 339.792466 -248.414309)
			(xy 339.80805 -248.46099) (xy 339.815945 -248.509567) (xy 339.81644 -248.534174) (xy 340.134951 -248.534174)
			(xy 340.139046 -248.483446) (xy 340.151225 -248.434032) (xy 340.171173 -248.387212) (xy 340.198374 -248.344198)
			(xy 340.232122 -248.306104) (xy 340.271544 -248.273917) (xy 340.315618 -248.248471) (xy 340.363204 -248.230424)
			(xy 340.413068 -248.220244) (xy 340.46392 -248.218195) (xy 340.514441 -248.224329) (xy 340.563325 -248.238489)
			(xy 340.609304 -248.260306) (xy 340.651188 -248.289216) (xy 340.687892 -248.324471) (xy 340.718465 -248.365157)
			(xy 340.742116 -248.41022) (xy 340.758232 -248.458494) (xy 340.766396 -248.508728) (xy 340.766908 -248.534174)
			(xy 341.085182 -248.534174) (xy 341.089142 -248.48512) (xy 341.100919 -248.437336) (xy 341.12021 -248.39206)
			(xy 341.146513 -248.350464) (xy 341.179148 -248.313627) (xy 341.217269 -248.282502) (xy 341.25989 -248.257895)
			(xy 341.305906 -248.240443) (xy 341.354125 -248.230599) (xy 341.4033 -248.228618) (xy 341.452155 -248.23455)
			(xy 341.499426 -248.248242) (xy 341.543888 -248.26934) (xy 341.584391 -248.297296) (xy 341.619884 -248.331388)
			(xy 341.649449 -248.370732) (xy 341.67232 -248.414309) (xy 341.687904 -248.46099) (xy 341.695799 -248.509567)
			(xy 341.696294 -248.534174) (xy 342.014805 -248.534174) (xy 342.0189 -248.483446) (xy 342.031079 -248.434032)
			(xy 342.051027 -248.387212) (xy 342.078228 -248.344198) (xy 342.111976 -248.306104) (xy 342.151398 -248.273917)
			(xy 342.195472 -248.248471) (xy 342.243058 -248.230424) (xy 342.292922 -248.220244) (xy 342.343774 -248.218195)
			(xy 342.394295 -248.224329) (xy 342.443179 -248.238489) (xy 342.489158 -248.260306) (xy 342.531042 -248.289216)
			(xy 342.567746 -248.324471) (xy 342.598319 -248.365157) (xy 342.62197 -248.41022) (xy 342.638086 -248.458494)
			(xy 342.64625 -248.508728) (xy 342.646762 -248.534174) (xy 342.954859 -248.534174) (xy 342.958954 -248.483446)
			(xy 342.971133 -248.434032) (xy 342.991081 -248.387212) (xy 343.018282 -248.344198) (xy 343.05203 -248.306104)
			(xy 343.091452 -248.273917) (xy 343.135526 -248.248471) (xy 343.183112 -248.230424) (xy 343.232976 -248.220244)
			(xy 343.283828 -248.218195) (xy 343.334349 -248.224329) (xy 343.383233 -248.238489) (xy 343.429212 -248.260306)
			(xy 343.471096 -248.289216) (xy 343.5078 -248.324471) (xy 343.538373 -248.365157) (xy 343.562024 -248.41022)
			(xy 343.57814 -248.458494) (xy 343.586304 -248.508728) (xy 343.586816 -248.534174) (xy 343.586304 -248.55962)
			(xy 343.57814 -248.609854) (xy 343.562024 -248.658128) (xy 343.538373 -248.703191) (xy 343.5078 -248.743877)
			(xy 343.471096 -248.779132) (xy 343.429212 -248.808042) (xy 343.383233 -248.829859) (xy 343.334349 -248.844019)
			(xy 343.283828 -248.850153) (xy 343.232976 -248.848104) (xy 343.183112 -248.837924) (xy 343.135526 -248.819877)
			(xy 343.091452 -248.794431) (xy 343.05203 -248.762244) (xy 343.018282 -248.72415) (xy 342.991081 -248.681136)
			(xy 342.971133 -248.634316) (xy 342.958954 -248.584902) (xy 342.954859 -248.534174) (xy 342.646762 -248.534174)
			(xy 342.64625 -248.55962) (xy 342.638086 -248.609854) (xy 342.62197 -248.658128) (xy 342.598319 -248.703191)
			(xy 342.567746 -248.743877) (xy 342.531042 -248.779132) (xy 342.489158 -248.808042) (xy 342.443179 -248.829859)
			(xy 342.394295 -248.844019) (xy 342.343774 -248.850153) (xy 342.292922 -248.848104) (xy 342.243058 -248.837924)
			(xy 342.195472 -248.819877) (xy 342.151398 -248.794431) (xy 342.111976 -248.762244) (xy 342.078228 -248.72415)
			(xy 342.051027 -248.681136) (xy 342.031079 -248.634316) (xy 342.0189 -248.584902) (xy 342.014805 -248.534174)
			(xy 341.696294 -248.534174) (xy 341.695799 -248.558781) (xy 341.687904 -248.607358) (xy 341.67232 -248.654039)
			(xy 341.649449 -248.697616) (xy 341.619884 -248.73696) (xy 341.584391 -248.771052) (xy 341.543888 -248.799008)
			(xy 341.499426 -248.820106) (xy 341.452155 -248.833798) (xy 341.4033 -248.83973) (xy 341.354125 -248.837749)
			(xy 341.305906 -248.827905) (xy 341.25989 -248.810453) (xy 341.217269 -248.785846) (xy 341.179148 -248.754721)
			(xy 341.146513 -248.717884) (xy 341.12021 -248.676288) (xy 341.100919 -248.631012) (xy 341.089142 -248.583228)
			(xy 341.085182 -248.534174) (xy 340.766908 -248.534174) (xy 340.766396 -248.55962) (xy 340.758232 -248.609854)
			(xy 340.742116 -248.658128) (xy 340.718465 -248.703191) (xy 340.687892 -248.743877) (xy 340.651188 -248.779132)
			(xy 340.609304 -248.808042) (xy 340.563325 -248.829859) (xy 340.514441 -248.844019) (xy 340.46392 -248.850153)
			(xy 340.413068 -248.848104) (xy 340.363204 -248.837924) (xy 340.315618 -248.819877) (xy 340.271544 -248.794431)
			(xy 340.232122 -248.762244) (xy 340.198374 -248.72415) (xy 340.171173 -248.681136) (xy 340.151225 -248.634316)
			(xy 340.139046 -248.584902) (xy 340.134951 -248.534174) (xy 339.81644 -248.534174) (xy 339.815945 -248.558781)
			(xy 339.80805 -248.607358) (xy 339.792466 -248.654039) (xy 339.769595 -248.697616) (xy 339.74003 -248.73696)
			(xy 339.704537 -248.771052) (xy 339.664034 -248.799008) (xy 339.619572 -248.820106) (xy 339.572301 -248.833798)
			(xy 339.523446 -248.83973) (xy 339.474271 -248.837749) (xy 339.426052 -248.827905) (xy 339.380036 -248.810453)
			(xy 339.337415 -248.785846) (xy 339.299294 -248.754721) (xy 339.266659 -248.717884) (xy 339.240356 -248.676288)
			(xy 339.221065 -248.631012) (xy 339.209288 -248.583228) (xy 339.205328 -248.534174) (xy 338.8868 -248.534174)
			(xy 338.886288 -248.55962) (xy 338.878124 -248.609854) (xy 338.862008 -248.658128) (xy 338.838357 -248.703191)
			(xy 338.807784 -248.743877) (xy 338.77108 -248.779132) (xy 338.729196 -248.808042) (xy 338.683217 -248.829859)
			(xy 338.634333 -248.844019) (xy 338.583812 -248.850153) (xy 338.53296 -248.848104) (xy 338.483096 -248.837924)
			(xy 338.43551 -248.819877) (xy 338.391436 -248.794431) (xy 338.352014 -248.762244) (xy 338.318266 -248.72415)
			(xy 338.291065 -248.681136) (xy 338.271117 -248.634316) (xy 338.258938 -248.584902) (xy 338.254843 -248.534174)
			(xy 337.936332 -248.534174) (xy 337.935837 -248.558781) (xy 337.927942 -248.607358) (xy 337.912358 -248.654039)
			(xy 337.889487 -248.697616) (xy 337.859922 -248.73696) (xy 337.824429 -248.771052) (xy 337.783926 -248.799008)
			(xy 337.739464 -248.820106) (xy 337.692193 -248.833798) (xy 337.643338 -248.83973) (xy 337.594163 -248.837749)
			(xy 337.545944 -248.827905) (xy 337.499928 -248.810453) (xy 337.457307 -248.785846) (xy 337.419186 -248.754721)
			(xy 337.386551 -248.717884) (xy 337.360248 -248.676288) (xy 337.340957 -248.631012) (xy 337.32918 -248.583228)
			(xy 337.32522 -248.534174) (xy 336.996532 -248.534174) (xy 336.996037 -248.558781) (xy 336.988142 -248.607358)
			(xy 336.972558 -248.654039) (xy 336.949687 -248.697616) (xy 336.920122 -248.73696) (xy 336.884629 -248.771052)
			(xy 336.844126 -248.799008) (xy 336.799664 -248.820106) (xy 336.752393 -248.833798) (xy 336.703538 -248.83973)
			(xy 336.654363 -248.837749) (xy 336.606144 -248.827905) (xy 336.560128 -248.810453) (xy 336.517507 -248.785846)
			(xy 336.479386 -248.754721) (xy 336.446751 -248.717884) (xy 336.420448 -248.676288) (xy 336.401157 -248.631012)
			(xy 336.38938 -248.583228) (xy 336.38542 -248.534174) (xy 336.056478 -248.534174) (xy 336.055983 -248.558781)
			(xy 336.048088 -248.607358) (xy 336.032504 -248.654039) (xy 336.009633 -248.697616) (xy 335.980068 -248.73696)
			(xy 335.944575 -248.771052) (xy 335.904072 -248.799008) (xy 335.85961 -248.820106) (xy 335.812339 -248.833798)
			(xy 335.763484 -248.83973) (xy 335.714309 -248.837749) (xy 335.66609 -248.827905) (xy 335.620074 -248.810453)
			(xy 335.577453 -248.785846) (xy 335.539332 -248.754721) (xy 335.506697 -248.717884) (xy 335.480394 -248.676288)
			(xy 335.461103 -248.631012) (xy 335.449326 -248.583228) (xy 335.445366 -248.534174) (xy 335.116955 -248.534174)
			(xy 335.116957 -248.5342) (xy 335.112786 -248.584541) (xy 335.100386 -248.633508) (xy 335.080096 -248.679767)
			(xy 335.052468 -248.722056) (xy 335.018258 -248.759221) (xy 334.978396 -248.790248) (xy 334.933972 -248.814291)
			(xy 334.886197 -248.830695) (xy 334.836373 -248.839011) (xy 334.811116 -248.839482) (xy 334.787545 -248.839047)
			(xy 334.740962 -248.831809) (xy 334.696043 -248.817504) (xy 334.653854 -248.79647) (xy 334.615395 -248.769206)
			(xy 334.58158 -248.73636) (xy 334.567022 -248.717816) (xy 334.56499 -248.715022) (xy 334.55991 -248.709942)
			(xy 334.553345 -248.703819) (xy 334.537074 -248.696268) (xy 334.52816 -248.69521) (xy 334.522572 -248.694702)
			(xy 334.432148 -248.706894) (xy 334.423228 -248.708438) (xy 334.40723 -248.716885) (xy 334.395162 -248.730362)
			(xy 334.391508 -248.738644) (xy 334.383586 -248.758351) (xy 334.365151 -248.79662) (xy 334.354678 -248.815098)
			(xy 334.312768 -248.887234) (xy 334.311498 -248.889012) (xy 334.303878 -248.900442) (xy 334.3021 -248.92762)
			(xy 334.338676 -249.002042) (xy 334.341553 -249.007374) (xy 334.349385 -249.016614) (xy 334.35417 -249.02033)
			(xy 334.382618 -249.041412) (xy 334.394302 -249.043444) (xy 334.417561 -249.048) (xy 334.4624 -249.063347)
			(xy 334.504328 -249.08544) (xy 334.542337 -249.113749) (xy 334.575513 -249.147593) (xy 334.603059 -249.186159)
			(xy 334.624312 -249.228519) (xy 334.638761 -249.273656) (xy 334.64606 -249.320483) (xy 334.646524 -249.34418)
			(xy 334.975212 -249.34418) (xy 334.979172 -249.295126) (xy 334.990949 -249.247342) (xy 335.01024 -249.202066)
			(xy 335.036543 -249.16047) (xy 335.069178 -249.123633) (xy 335.107299 -249.092508) (xy 335.14992 -249.067901)
			(xy 335.195936 -249.050449) (xy 335.244155 -249.040605) (xy 335.29333 -249.038624) (xy 335.342185 -249.044556)
			(xy 335.389456 -249.058248) (xy 335.433918 -249.079346) (xy 335.474421 -249.107302) (xy 335.509914 -249.141394)
			(xy 335.539479 -249.180738) (xy 335.56235 -249.224315) (xy 335.577934 -249.270996) (xy 335.585829 -249.319573)
			(xy 335.586324 -249.34418) (xy 335.915266 -249.34418) (xy 335.919226 -249.295126) (xy 335.931003 -249.247342)
			(xy 335.950294 -249.202066) (xy 335.976597 -249.16047) (xy 336.009232 -249.123633) (xy 336.047353 -249.092508)
			(xy 336.089974 -249.067901) (xy 336.13599 -249.050449) (xy 336.184209 -249.040605) (xy 336.233384 -249.038624)
			(xy 336.282239 -249.044556) (xy 336.32951 -249.058248) (xy 336.373972 -249.079346) (xy 336.414475 -249.107302)
			(xy 336.449968 -249.141394) (xy 336.479533 -249.180738) (xy 336.502404 -249.224315) (xy 336.517988 -249.270996)
			(xy 336.525883 -249.319573) (xy 336.526378 -249.34418) (xy 336.85532 -249.34418) (xy 336.85928 -249.295126)
			(xy 336.871057 -249.247342) (xy 336.890348 -249.202066) (xy 336.916651 -249.16047) (xy 336.949286 -249.123633)
			(xy 336.987407 -249.092508) (xy 337.030028 -249.067901) (xy 337.076044 -249.050449) (xy 337.124263 -249.040605)
			(xy 337.173438 -249.038624) (xy 337.222293 -249.044556) (xy 337.269564 -249.058248) (xy 337.314026 -249.079346)
			(xy 337.354529 -249.107302) (xy 337.390022 -249.141394) (xy 337.419587 -249.180738) (xy 337.442458 -249.224315)
			(xy 337.458042 -249.270996) (xy 337.465937 -249.319573) (xy 337.466432 -249.34418) (xy 337.795374 -249.34418)
			(xy 337.799334 -249.295126) (xy 337.811111 -249.247342) (xy 337.830402 -249.202066) (xy 337.856705 -249.16047)
			(xy 337.88934 -249.123633) (xy 337.927461 -249.092508) (xy 337.970082 -249.067901) (xy 338.016098 -249.050449)
			(xy 338.064317 -249.040605) (xy 338.113492 -249.038624) (xy 338.162347 -249.044556) (xy 338.209618 -249.058248)
			(xy 338.25408 -249.079346) (xy 338.294583 -249.107302) (xy 338.330076 -249.141394) (xy 338.359641 -249.180738)
			(xy 338.382512 -249.224315) (xy 338.398096 -249.270996) (xy 338.405991 -249.319573) (xy 338.406486 -249.34418)
			(xy 338.735174 -249.34418) (xy 338.739134 -249.295126) (xy 338.750911 -249.247342) (xy 338.770202 -249.202066)
			(xy 338.796505 -249.16047) (xy 338.82914 -249.123633) (xy 338.867261 -249.092508) (xy 338.909882 -249.067901)
			(xy 338.955898 -249.050449) (xy 339.004117 -249.040605) (xy 339.053292 -249.038624) (xy 339.102147 -249.044556)
			(xy 339.149418 -249.058248) (xy 339.19388 -249.079346) (xy 339.234383 -249.107302) (xy 339.269876 -249.141394)
			(xy 339.299441 -249.180738) (xy 339.322312 -249.224315) (xy 339.337896 -249.270996) (xy 339.345791 -249.319573)
			(xy 339.346286 -249.34418) (xy 339.664797 -249.34418) (xy 339.668892 -249.293452) (xy 339.681071 -249.244038)
			(xy 339.701019 -249.197218) (xy 339.72822 -249.154204) (xy 339.761968 -249.11611) (xy 339.80139 -249.083923)
			(xy 339.845464 -249.058477) (xy 339.89305 -249.04043) (xy 339.942914 -249.03025) (xy 339.993766 -249.028201)
			(xy 340.044287 -249.034335) (xy 340.093171 -249.048495) (xy 340.13915 -249.070312) (xy 340.181034 -249.099222)
			(xy 340.217738 -249.134477) (xy 340.248311 -249.175163) (xy 340.271962 -249.220226) (xy 340.288078 -249.2685)
			(xy 340.296242 -249.318734) (xy 340.296754 -249.34418) (xy 340.615282 -249.34418) (xy 340.619242 -249.295126)
			(xy 340.631019 -249.247342) (xy 340.65031 -249.202066) (xy 340.676613 -249.16047) (xy 340.709248 -249.123633)
			(xy 340.747369 -249.092508) (xy 340.78999 -249.067901) (xy 340.836006 -249.050449) (xy 340.884225 -249.040605)
			(xy 340.9334 -249.038624) (xy 340.982255 -249.044556) (xy 341.029526 -249.058248) (xy 341.073988 -249.079346)
			(xy 341.114491 -249.107302) (xy 341.149984 -249.141394) (xy 341.179549 -249.180738) (xy 341.20242 -249.224315)
			(xy 341.218004 -249.270996) (xy 341.225899 -249.319573) (xy 341.226394 -249.34418) (xy 341.555336 -249.34418)
			(xy 341.559296 -249.295126) (xy 341.571073 -249.247342) (xy 341.590364 -249.202066) (xy 341.616667 -249.16047)
			(xy 341.649302 -249.123633) (xy 341.687423 -249.092508) (xy 341.730044 -249.067901) (xy 341.77606 -249.050449)
			(xy 341.824279 -249.040605) (xy 341.873454 -249.038624) (xy 341.922309 -249.044556) (xy 341.96958 -249.058248)
			(xy 342.014042 -249.079346) (xy 342.054545 -249.107302) (xy 342.090038 -249.141394) (xy 342.119603 -249.180738)
			(xy 342.142474 -249.224315) (xy 342.158058 -249.270996) (xy 342.165953 -249.319573) (xy 342.166448 -249.34418)
			(xy 342.49539 -249.34418) (xy 342.49935 -249.295126) (xy 342.511127 -249.247342) (xy 342.530418 -249.202066)
			(xy 342.556721 -249.16047) (xy 342.589356 -249.123633) (xy 342.627477 -249.092508) (xy 342.670098 -249.067901)
			(xy 342.716114 -249.050449) (xy 342.764333 -249.040605) (xy 342.813508 -249.038624) (xy 342.862363 -249.044556)
			(xy 342.909634 -249.058248) (xy 342.954096 -249.079346) (xy 342.994599 -249.107302) (xy 343.030092 -249.141394)
			(xy 343.059657 -249.180738) (xy 343.082528 -249.224315) (xy 343.098112 -249.270996) (xy 343.106007 -249.319573)
			(xy 343.106502 -249.34418) (xy 343.424759 -249.34418) (xy 343.428854 -249.293452) (xy 343.441033 -249.244038)
			(xy 343.460981 -249.197218) (xy 343.488182 -249.154204) (xy 343.52193 -249.11611) (xy 343.561352 -249.083923)
			(xy 343.605426 -249.058477) (xy 343.653012 -249.04043) (xy 343.702876 -249.03025) (xy 343.753728 -249.028201)
			(xy 343.804249 -249.034335) (xy 343.853133 -249.048495) (xy 343.899112 -249.070312) (xy 343.940996 -249.099222)
			(xy 343.9777 -249.134477) (xy 344.008273 -249.175163) (xy 344.031924 -249.220226) (xy 344.04804 -249.2685)
			(xy 344.056204 -249.318734) (xy 344.056716 -249.34418) (xy 344.056204 -249.369626) (xy 344.04804 -249.41986)
			(xy 344.031924 -249.468134) (xy 344.008273 -249.513197) (xy 343.9777 -249.553883) (xy 343.940996 -249.589138)
			(xy 343.899112 -249.618048) (xy 343.853133 -249.639865) (xy 343.804249 -249.654025) (xy 343.753728 -249.660159)
			(xy 343.702876 -249.65811) (xy 343.653012 -249.64793) (xy 343.605426 -249.629883) (xy 343.561352 -249.604437)
			(xy 343.52193 -249.57225) (xy 343.488182 -249.534156) (xy 343.460981 -249.491142) (xy 343.441033 -249.444322)
			(xy 343.428854 -249.394908) (xy 343.424759 -249.34418) (xy 343.106502 -249.34418) (xy 343.106007 -249.368787)
			(xy 343.098112 -249.417364) (xy 343.082528 -249.464045) (xy 343.059657 -249.507622) (xy 343.030092 -249.546966)
			(xy 342.994599 -249.581058) (xy 342.954096 -249.609014) (xy 342.909634 -249.630112) (xy 342.862363 -249.643804)
			(xy 342.813508 -249.649736) (xy 342.764333 -249.647755) (xy 342.716114 -249.637911) (xy 342.670098 -249.620459)
			(xy 342.627477 -249.595852) (xy 342.589356 -249.564727) (xy 342.556721 -249.52789) (xy 342.530418 -249.486294)
			(xy 342.511127 -249.441018) (xy 342.49935 -249.393234) (xy 342.49539 -249.34418) (xy 342.166448 -249.34418)
			(xy 342.165953 -249.368787) (xy 342.158058 -249.417364) (xy 342.142474 -249.464045) (xy 342.119603 -249.507622)
			(xy 342.090038 -249.546966) (xy 342.054545 -249.581058) (xy 342.014042 -249.609014) (xy 341.96958 -249.630112)
			(xy 341.922309 -249.643804) (xy 341.873454 -249.649736) (xy 341.824279 -249.647755) (xy 341.77606 -249.637911)
			(xy 341.730044 -249.620459) (xy 341.687423 -249.595852) (xy 341.649302 -249.564727) (xy 341.616667 -249.52789)
			(xy 341.590364 -249.486294) (xy 341.571073 -249.441018) (xy 341.559296 -249.393234) (xy 341.555336 -249.34418)
			(xy 341.226394 -249.34418) (xy 341.225899 -249.368787) (xy 341.218004 -249.417364) (xy 341.20242 -249.464045)
			(xy 341.179549 -249.507622) (xy 341.149984 -249.546966) (xy 341.114491 -249.581058) (xy 341.073988 -249.609014)
			(xy 341.029526 -249.630112) (xy 340.982255 -249.643804) (xy 340.9334 -249.649736) (xy 340.884225 -249.647755)
			(xy 340.836006 -249.637911) (xy 340.78999 -249.620459) (xy 340.747369 -249.595852) (xy 340.709248 -249.564727)
			(xy 340.676613 -249.52789) (xy 340.65031 -249.486294) (xy 340.631019 -249.441018) (xy 340.619242 -249.393234)
			(xy 340.615282 -249.34418) (xy 340.296754 -249.34418) (xy 340.296242 -249.369626) (xy 340.288078 -249.41986)
			(xy 340.271962 -249.468134) (xy 340.248311 -249.513197) (xy 340.217738 -249.553883) (xy 340.181034 -249.589138)
			(xy 340.13915 -249.618048) (xy 340.093171 -249.639865) (xy 340.044287 -249.654025) (xy 339.993766 -249.660159)
			(xy 339.942914 -249.65811) (xy 339.89305 -249.64793) (xy 339.845464 -249.629883) (xy 339.80139 -249.604437)
			(xy 339.761968 -249.57225) (xy 339.72822 -249.534156) (xy 339.701019 -249.491142) (xy 339.681071 -249.444322)
			(xy 339.668892 -249.394908) (xy 339.664797 -249.34418) (xy 339.346286 -249.34418) (xy 339.345791 -249.368787)
			(xy 339.337896 -249.417364) (xy 339.322312 -249.464045) (xy 339.299441 -249.507622) (xy 339.269876 -249.546966)
			(xy 339.234383 -249.581058) (xy 339.19388 -249.609014) (xy 339.149418 -249.630112) (xy 339.102147 -249.643804)
			(xy 339.053292 -249.649736) (xy 339.004117 -249.647755) (xy 338.955898 -249.637911) (xy 338.909882 -249.620459)
			(xy 338.867261 -249.595852) (xy 338.82914 -249.564727) (xy 338.796505 -249.52789) (xy 338.770202 -249.486294)
			(xy 338.750911 -249.441018) (xy 338.739134 -249.393234) (xy 338.735174 -249.34418) (xy 338.406486 -249.34418)
			(xy 338.405991 -249.368787) (xy 338.398096 -249.417364) (xy 338.382512 -249.464045) (xy 338.359641 -249.507622)
			(xy 338.330076 -249.546966) (xy 338.294583 -249.581058) (xy 338.25408 -249.609014) (xy 338.209618 -249.630112)
			(xy 338.162347 -249.643804) (xy 338.113492 -249.649736) (xy 338.064317 -249.647755) (xy 338.016098 -249.637911)
			(xy 337.970082 -249.620459) (xy 337.927461 -249.595852) (xy 337.88934 -249.564727) (xy 337.856705 -249.52789)
			(xy 337.830402 -249.486294) (xy 337.811111 -249.441018) (xy 337.799334 -249.393234) (xy 337.795374 -249.34418)
			(xy 337.466432 -249.34418) (xy 337.465937 -249.368787) (xy 337.458042 -249.417364) (xy 337.442458 -249.464045)
			(xy 337.419587 -249.507622) (xy 337.390022 -249.546966) (xy 337.354529 -249.581058) (xy 337.314026 -249.609014)
			(xy 337.269564 -249.630112) (xy 337.222293 -249.643804) (xy 337.173438 -249.649736) (xy 337.124263 -249.647755)
			(xy 337.076044 -249.637911) (xy 337.030028 -249.620459) (xy 336.987407 -249.595852) (xy 336.949286 -249.564727)
			(xy 336.916651 -249.52789) (xy 336.890348 -249.486294) (xy 336.871057 -249.441018) (xy 336.85928 -249.393234)
			(xy 336.85532 -249.34418) (xy 336.526378 -249.34418) (xy 336.525883 -249.368787) (xy 336.517988 -249.417364)
			(xy 336.502404 -249.464045) (xy 336.479533 -249.507622) (xy 336.449968 -249.546966) (xy 336.414475 -249.581058)
			(xy 336.373972 -249.609014) (xy 336.32951 -249.630112) (xy 336.282239 -249.643804) (xy 336.233384 -249.649736)
			(xy 336.184209 -249.647755) (xy 336.13599 -249.637911) (xy 336.089974 -249.620459) (xy 336.047353 -249.595852)
			(xy 336.009232 -249.564727) (xy 335.976597 -249.52789) (xy 335.950294 -249.486294) (xy 335.931003 -249.441018)
			(xy 335.919226 -249.393234) (xy 335.915266 -249.34418) (xy 335.586324 -249.34418) (xy 335.585829 -249.368787)
			(xy 335.577934 -249.417364) (xy 335.56235 -249.464045) (xy 335.539479 -249.507622) (xy 335.509914 -249.546966)
			(xy 335.474421 -249.581058) (xy 335.433918 -249.609014) (xy 335.389456 -249.630112) (xy 335.342185 -249.643804)
			(xy 335.29333 -249.649736) (xy 335.244155 -249.647755) (xy 335.195936 -249.637911) (xy 335.14992 -249.620459)
			(xy 335.107299 -249.595852) (xy 335.069178 -249.564727) (xy 335.036543 -249.52789) (xy 335.01024 -249.486294)
			(xy 334.990949 -249.441018) (xy 334.979172 -249.393234) (xy 334.975212 -249.34418) (xy 334.646524 -249.34418)
			(xy 334.646079 -249.368175) (xy 334.638575 -249.415573) (xy 334.623749 -249.461215) (xy 334.601965 -249.503975)
			(xy 334.57376 -249.542801) (xy 334.539828 -249.576736) (xy 334.501006 -249.604946) (xy 334.458248 -249.626735)
			(xy 334.412609 -249.641567) (xy 334.365211 -249.649076) (xy 334.341216 -249.649488) (xy 334.309466 -249.64771)
			(xy 334.306672 -249.647456) (xy 334.304132 -249.647456) (xy 334.294117 -249.647938) (xy 334.275607 -249.65559)
			(xy 334.261433 -249.669743) (xy 334.253753 -249.688242) (xy 334.253332 -249.698256) (xy 334.253332 -249.718576)
			(xy 334.254094 -249.727466) (xy 334.255364 -249.734324) (xy 334.256967 -249.741937) (xy 334.264081 -249.755763)
			(xy 334.269334 -249.761502) (xy 334.269588 -249.761756) (xy 334.274922 -249.767344) (xy 334.298193 -249.792372)
			(xy 334.339098 -249.847122) (xy 334.373007 -249.906458) (xy 334.386682 -249.937778) (xy 334.389222 -249.943874)
			(xy 334.396842 -249.954034) (xy 334.421226 -249.973084) (xy 334.426702 -249.977042) (xy 334.439191 -249.982185)
			(xy 334.445864 -249.983244) (xy 334.516984 -249.992896) (xy 334.522959 -249.993514) (xy 334.5349 -249.992233)
			(xy 334.540606 -249.990356) (xy 334.551782 -249.986546) (xy 334.56499 -249.973338) (xy 334.567022 -249.970544)
			(xy 334.581568 -249.951992) (xy 334.615399 -249.919164) (xy 334.653864 -249.891912) (xy 334.696053 -249.870881)
			(xy 334.740968 -249.856568) (xy 334.787546 -249.849311) (xy 334.811116 -249.848878) (xy 334.836372 -249.849401)
			(xy 334.886194 -249.857717) (xy 334.933967 -249.87412) (xy 334.97839 -249.898162) (xy 335.018249 -249.929188)
			(xy 335.052459 -249.966351) (xy 335.080085 -250.008638) (xy 335.100375 -250.054895) (xy 335.112774 -250.103861)
			(xy 335.116944 -250.154186) (xy 335.445366 -250.154186) (xy 335.449326 -250.105132) (xy 335.461103 -250.057348)
			(xy 335.480394 -250.012072) (xy 335.506697 -249.970476) (xy 335.539332 -249.933639) (xy 335.577453 -249.902514)
			(xy 335.620074 -249.877907) (xy 335.66609 -249.860455) (xy 335.714309 -249.850611) (xy 335.763484 -249.84863)
			(xy 335.812339 -249.854562) (xy 335.85961 -249.868254) (xy 335.904072 -249.889352) (xy 335.944575 -249.917308)
			(xy 335.980068 -249.9514) (xy 336.009633 -249.990744) (xy 336.032504 -250.034321) (xy 336.048088 -250.081002)
			(xy 336.055983 -250.129579) (xy 336.056478 -250.154186) (xy 336.38542 -250.154186) (xy 336.38938 -250.105132)
			(xy 336.401157 -250.057348) (xy 336.420448 -250.012072) (xy 336.446751 -249.970476) (xy 336.479386 -249.933639)
			(xy 336.517507 -249.902514) (xy 336.560128 -249.877907) (xy 336.606144 -249.860455) (xy 336.654363 -249.850611)
			(xy 336.703538 -249.84863) (xy 336.752393 -249.854562) (xy 336.799664 -249.868254) (xy 336.844126 -249.889352)
			(xy 336.884629 -249.917308) (xy 336.920122 -249.9514) (xy 336.949687 -249.990744) (xy 336.972558 -250.034321)
			(xy 336.988142 -250.081002) (xy 336.996037 -250.129579) (xy 336.996532 -250.154186) (xy 337.32522 -250.154186)
			(xy 337.32918 -250.105132) (xy 337.340957 -250.057348) (xy 337.360248 -250.012072) (xy 337.386551 -249.970476)
			(xy 337.419186 -249.933639) (xy 337.457307 -249.902514) (xy 337.499928 -249.877907) (xy 337.545944 -249.860455)
			(xy 337.594163 -249.850611) (xy 337.643338 -249.84863) (xy 337.692193 -249.854562) (xy 337.739464 -249.868254)
			(xy 337.783926 -249.889352) (xy 337.824429 -249.917308) (xy 337.859922 -249.9514) (xy 337.889487 -249.990744)
			(xy 337.912358 -250.034321) (xy 337.927942 -250.081002) (xy 337.935837 -250.129579) (xy 337.936332 -250.154186)
			(xy 338.265274 -250.154186) (xy 338.269234 -250.105132) (xy 338.281011 -250.057348) (xy 338.300302 -250.012072)
			(xy 338.326605 -249.970476) (xy 338.35924 -249.933639) (xy 338.397361 -249.902514) (xy 338.439982 -249.877907)
			(xy 338.485998 -249.860455) (xy 338.534217 -249.850611) (xy 338.583392 -249.84863) (xy 338.632247 -249.854562)
			(xy 338.679518 -249.868254) (xy 338.72398 -249.889352) (xy 338.764483 -249.917308) (xy 338.799976 -249.9514)
			(xy 338.829541 -249.990744) (xy 338.852412 -250.034321) (xy 338.867996 -250.081002) (xy 338.875891 -250.129579)
			(xy 338.876386 -250.154186) (xy 339.205328 -250.154186) (xy 339.209288 -250.105132) (xy 339.221065 -250.057348)
			(xy 339.240356 -250.012072) (xy 339.266659 -249.970476) (xy 339.299294 -249.933639) (xy 339.337415 -249.902514)
			(xy 339.380036 -249.877907) (xy 339.426052 -249.860455) (xy 339.474271 -249.850611) (xy 339.523446 -249.84863)
			(xy 339.572301 -249.854562) (xy 339.619572 -249.868254) (xy 339.664034 -249.889352) (xy 339.704537 -249.917308)
			(xy 339.74003 -249.9514) (xy 339.769595 -249.990744) (xy 339.792466 -250.034321) (xy 339.80805 -250.081002)
			(xy 339.815945 -250.129579) (xy 339.81644 -250.154186) (xy 340.134951 -250.154186) (xy 340.139046 -250.103458)
			(xy 340.151225 -250.054044) (xy 340.171173 -250.007224) (xy 340.198374 -249.96421) (xy 340.232122 -249.926116)
			(xy 340.271544 -249.893929) (xy 340.315618 -249.868483) (xy 340.363204 -249.850436) (xy 340.413068 -249.840256)
			(xy 340.46392 -249.838207) (xy 340.514441 -249.844341) (xy 340.563325 -249.858501) (xy 340.609304 -249.880318)
			(xy 340.651188 -249.909228) (xy 340.687892 -249.944483) (xy 340.718465 -249.985169) (xy 340.742116 -250.030232)
			(xy 340.758232 -250.078506) (xy 340.766396 -250.12874) (xy 340.766908 -250.154186) (xy 341.085182 -250.154186)
			(xy 341.089142 -250.105132) (xy 341.100919 -250.057348) (xy 341.12021 -250.012072) (xy 341.146513 -249.970476)
			(xy 341.179148 -249.933639) (xy 341.217269 -249.902514) (xy 341.25989 -249.877907) (xy 341.305906 -249.860455)
			(xy 341.354125 -249.850611) (xy 341.4033 -249.84863) (xy 341.452155 -249.854562) (xy 341.499426 -249.868254)
			(xy 341.543888 -249.889352) (xy 341.584391 -249.917308) (xy 341.619884 -249.9514) (xy 341.649449 -249.990744)
			(xy 341.67232 -250.034321) (xy 341.687904 -250.081002) (xy 341.695799 -250.129579) (xy 341.696294 -250.154186)
			(xy 342.025236 -250.154186) (xy 342.029196 -250.105132) (xy 342.040973 -250.057348) (xy 342.060264 -250.012072)
			(xy 342.086567 -249.970476) (xy 342.119202 -249.933639) (xy 342.157323 -249.902514) (xy 342.199944 -249.877907)
			(xy 342.24596 -249.860455) (xy 342.294179 -249.850611) (xy 342.343354 -249.84863) (xy 342.392209 -249.854562)
			(xy 342.43948 -249.868254) (xy 342.483942 -249.889352) (xy 342.524445 -249.917308) (xy 342.559938 -249.9514)
			(xy 342.589503 -249.990744) (xy 342.612374 -250.034321) (xy 342.627958 -250.081002) (xy 342.635853 -250.129579)
			(xy 342.636348 -250.154186) (xy 342.954859 -250.154186) (xy 342.958954 -250.103458) (xy 342.971133 -250.054044)
			(xy 342.991081 -250.007224) (xy 343.018282 -249.96421) (xy 343.05203 -249.926116) (xy 343.091452 -249.893929)
			(xy 343.135526 -249.868483) (xy 343.183112 -249.850436) (xy 343.232976 -249.840256) (xy 343.283828 -249.838207)
			(xy 343.334349 -249.844341) (xy 343.383233 -249.858501) (xy 343.429212 -249.880318) (xy 343.471096 -249.909228)
			(xy 343.5078 -249.944483) (xy 343.538373 -249.985169) (xy 343.562024 -250.030232) (xy 343.57814 -250.078506)
			(xy 343.586304 -250.12874) (xy 343.586816 -250.154186) (xy 343.905344 -250.154186) (xy 343.909304 -250.105132)
			(xy 343.921081 -250.057348) (xy 343.940372 -250.012072) (xy 343.966675 -249.970476) (xy 343.99931 -249.933639)
			(xy 344.037431 -249.902514) (xy 344.080052 -249.877907) (xy 344.126068 -249.860455) (xy 344.174287 -249.850611)
			(xy 344.223462 -249.84863) (xy 344.272317 -249.854562) (xy 344.319588 -249.868254) (xy 344.36405 -249.889352)
			(xy 344.404553 -249.917308) (xy 344.440046 -249.9514) (xy 344.469611 -249.990744) (xy 344.492482 -250.034321)
			(xy 344.508066 -250.081002) (xy 344.515961 -250.129579) (xy 344.516456 -250.154186) (xy 345.785198 -250.154186)
			(xy 345.789158 -250.105132) (xy 345.800935 -250.057348) (xy 345.820226 -250.012072) (xy 345.846529 -249.970476)
			(xy 345.879164 -249.933639) (xy 345.917285 -249.902514) (xy 345.959906 -249.877907) (xy 346.005922 -249.860455)
			(xy 346.054141 -249.850611) (xy 346.103316 -249.84863) (xy 346.152171 -249.854562) (xy 346.199442 -249.868254)
			(xy 346.243904 -249.889352) (xy 346.284407 -249.917308) (xy 346.3199 -249.9514) (xy 346.349465 -249.990744)
			(xy 346.372336 -250.034321) (xy 346.38792 -250.081002) (xy 346.395815 -250.129579) (xy 346.39631 -250.154186)
			(xy 346.395815 -250.178793) (xy 346.38792 -250.22737) (xy 346.372336 -250.274051) (xy 346.349465 -250.317628)
			(xy 346.3199 -250.356972) (xy 346.284407 -250.391064) (xy 346.243904 -250.41902) (xy 346.199442 -250.440118)
			(xy 346.152171 -250.45381) (xy 346.103316 -250.459742) (xy 346.054141 -250.457761) (xy 346.005922 -250.447917)
			(xy 345.959906 -250.430465) (xy 345.917285 -250.405858) (xy 345.879164 -250.374733) (xy 345.846529 -250.337896)
			(xy 345.820226 -250.2963) (xy 345.800935 -250.251024) (xy 345.789158 -250.20324) (xy 345.785198 -250.154186)
			(xy 344.516456 -250.154186) (xy 344.515961 -250.178793) (xy 344.508066 -250.22737) (xy 344.492482 -250.274051)
			(xy 344.469611 -250.317628) (xy 344.440046 -250.356972) (xy 344.404553 -250.391064) (xy 344.36405 -250.41902)
			(xy 344.319588 -250.440118) (xy 344.272317 -250.45381) (xy 344.223462 -250.459742) (xy 344.174287 -250.457761)
			(xy 344.126068 -250.447917) (xy 344.080052 -250.430465) (xy 344.037431 -250.405858) (xy 343.99931 -250.374733)
			(xy 343.966675 -250.337896) (xy 343.940372 -250.2963) (xy 343.921081 -250.251024) (xy 343.909304 -250.20324)
			(xy 343.905344 -250.154186) (xy 343.586816 -250.154186) (xy 343.586304 -250.179632) (xy 343.57814 -250.229866)
			(xy 343.562024 -250.27814) (xy 343.538373 -250.323203) (xy 343.5078 -250.363889) (xy 343.471096 -250.399144)
			(xy 343.429212 -250.428054) (xy 343.383233 -250.449871) (xy 343.334349 -250.464031) (xy 343.283828 -250.470165)
			(xy 343.232976 -250.468116) (xy 343.183112 -250.457936) (xy 343.135526 -250.439889) (xy 343.091452 -250.414443)
			(xy 343.05203 -250.382256) (xy 343.018282 -250.344162) (xy 342.991081 -250.301148) (xy 342.971133 -250.254328)
			(xy 342.958954 -250.204914) (xy 342.954859 -250.154186) (xy 342.636348 -250.154186) (xy 342.635853 -250.178793)
			(xy 342.627958 -250.22737) (xy 342.612374 -250.274051) (xy 342.589503 -250.317628) (xy 342.559938 -250.356972)
			(xy 342.524445 -250.391064) (xy 342.483942 -250.41902) (xy 342.43948 -250.440118) (xy 342.392209 -250.45381)
			(xy 342.343354 -250.459742) (xy 342.294179 -250.457761) (xy 342.24596 -250.447917) (xy 342.199944 -250.430465)
			(xy 342.157323 -250.405858) (xy 342.119202 -250.374733) (xy 342.086567 -250.337896) (xy 342.060264 -250.2963)
			(xy 342.040973 -250.251024) (xy 342.029196 -250.20324) (xy 342.025236 -250.154186) (xy 341.696294 -250.154186)
			(xy 341.695799 -250.178793) (xy 341.687904 -250.22737) (xy 341.67232 -250.274051) (xy 341.649449 -250.317628)
			(xy 341.619884 -250.356972) (xy 341.584391 -250.391064) (xy 341.543888 -250.41902) (xy 341.499426 -250.440118)
			(xy 341.452155 -250.45381) (xy 341.4033 -250.459742) (xy 341.354125 -250.457761) (xy 341.305906 -250.447917)
			(xy 341.25989 -250.430465) (xy 341.217269 -250.405858) (xy 341.179148 -250.374733) (xy 341.146513 -250.337896)
			(xy 341.12021 -250.2963) (xy 341.100919 -250.251024) (xy 341.089142 -250.20324) (xy 341.085182 -250.154186)
			(xy 340.766908 -250.154186) (xy 340.766396 -250.179632) (xy 340.758232 -250.229866) (xy 340.742116 -250.27814)
			(xy 340.718465 -250.323203) (xy 340.687892 -250.363889) (xy 340.651188 -250.399144) (xy 340.609304 -250.428054)
			(xy 340.563325 -250.449871) (xy 340.514441 -250.464031) (xy 340.46392 -250.470165) (xy 340.413068 -250.468116)
			(xy 340.363204 -250.457936) (xy 340.315618 -250.439889) (xy 340.271544 -250.414443) (xy 340.232122 -250.382256)
			(xy 340.198374 -250.344162) (xy 340.171173 -250.301148) (xy 340.151225 -250.254328) (xy 340.139046 -250.204914)
			(xy 340.134951 -250.154186) (xy 339.81644 -250.154186) (xy 339.815945 -250.178793) (xy 339.80805 -250.22737)
			(xy 339.792466 -250.274051) (xy 339.769595 -250.317628) (xy 339.74003 -250.356972) (xy 339.704537 -250.391064)
			(xy 339.664034 -250.41902) (xy 339.619572 -250.440118) (xy 339.572301 -250.45381) (xy 339.523446 -250.459742)
			(xy 339.474271 -250.457761) (xy 339.426052 -250.447917) (xy 339.380036 -250.430465) (xy 339.337415 -250.405858)
			(xy 339.299294 -250.374733) (xy 339.266659 -250.337896) (xy 339.240356 -250.2963) (xy 339.221065 -250.251024)
			(xy 339.209288 -250.20324) (xy 339.205328 -250.154186) (xy 338.876386 -250.154186) (xy 338.875891 -250.178793)
			(xy 338.867996 -250.22737) (xy 338.852412 -250.274051) (xy 338.829541 -250.317628) (xy 338.799976 -250.356972)
			(xy 338.764483 -250.391064) (xy 338.72398 -250.41902) (xy 338.679518 -250.440118) (xy 338.632247 -250.45381)
			(xy 338.583392 -250.459742) (xy 338.534217 -250.457761) (xy 338.485998 -250.447917) (xy 338.439982 -250.430465)
			(xy 338.397361 -250.405858) (xy 338.35924 -250.374733) (xy 338.326605 -250.337896) (xy 338.300302 -250.2963)
			(xy 338.281011 -250.251024) (xy 338.269234 -250.20324) (xy 338.265274 -250.154186) (xy 337.936332 -250.154186)
			(xy 337.935837 -250.178793) (xy 337.927942 -250.22737) (xy 337.912358 -250.274051) (xy 337.889487 -250.317628)
			(xy 337.859922 -250.356972) (xy 337.824429 -250.391064) (xy 337.783926 -250.41902) (xy 337.739464 -250.440118)
			(xy 337.692193 -250.45381) (xy 337.643338 -250.459742) (xy 337.594163 -250.457761) (xy 337.545944 -250.447917)
			(xy 337.499928 -250.430465) (xy 337.457307 -250.405858) (xy 337.419186 -250.374733) (xy 337.386551 -250.337896)
			(xy 337.360248 -250.2963) (xy 337.340957 -250.251024) (xy 337.32918 -250.20324) (xy 337.32522 -250.154186)
			(xy 336.996532 -250.154186) (xy 336.996037 -250.178793) (xy 336.988142 -250.22737) (xy 336.972558 -250.274051)
			(xy 336.949687 -250.317628) (xy 336.920122 -250.356972) (xy 336.884629 -250.391064) (xy 336.844126 -250.41902)
			(xy 336.799664 -250.440118) (xy 336.752393 -250.45381) (xy 336.703538 -250.459742) (xy 336.654363 -250.457761)
			(xy 336.606144 -250.447917) (xy 336.560128 -250.430465) (xy 336.517507 -250.405858) (xy 336.479386 -250.374733)
			(xy 336.446751 -250.337896) (xy 336.420448 -250.2963) (xy 336.401157 -250.251024) (xy 336.38938 -250.20324)
			(xy 336.38542 -250.154186) (xy 336.056478 -250.154186) (xy 336.055983 -250.178793) (xy 336.048088 -250.22737)
			(xy 336.032504 -250.274051) (xy 336.009633 -250.317628) (xy 335.980068 -250.356972) (xy 335.944575 -250.391064)
			(xy 335.904072 -250.41902) (xy 335.85961 -250.440118) (xy 335.812339 -250.45381) (xy 335.763484 -250.459742)
			(xy 335.714309 -250.457761) (xy 335.66609 -250.447917) (xy 335.620074 -250.430465) (xy 335.577453 -250.405858)
			(xy 335.539332 -250.374733) (xy 335.506697 -250.337896) (xy 335.480394 -250.2963) (xy 335.461103 -250.251024)
			(xy 335.449326 -250.20324) (xy 335.445366 -250.154186) (xy 335.116944 -250.154186) (xy 335.116945 -250.1542)
			(xy 335.112774 -250.204539) (xy 335.100375 -250.253505) (xy 335.080085 -250.299762) (xy 335.052459 -250.342049)
			(xy 335.018249 -250.379212) (xy 334.97839 -250.410238) (xy 334.933967 -250.43428) (xy 334.886194 -250.450683)
			(xy 334.836372 -250.458999) (xy 334.811116 -250.459494) (xy 334.787545 -250.459059) (xy 334.740962 -250.451822)
			(xy 334.696042 -250.437517) (xy 334.653852 -250.416483) (xy 334.615393 -250.38922) (xy 334.581577 -250.356374)
			(xy 334.567022 -250.337828) (xy 334.56499 -250.335034) (xy 334.55991 -250.329954) (xy 334.553346 -250.32383)
			(xy 334.537075 -250.316277) (xy 334.52816 -250.315222) (xy 334.522572 -250.314714) (xy 334.432148 -250.326906)
			(xy 334.423229 -250.328451) (xy 334.407233 -250.336899) (xy 334.395167 -250.350376) (xy 334.391508 -250.358656)
			(xy 334.383586 -250.378363) (xy 334.36515 -250.416631) (xy 334.354678 -250.43511) (xy 334.312768 -250.507246)
			(xy 334.311498 -250.509024) (xy 334.303878 -250.520454) (xy 334.3021 -250.547632) (xy 334.338676 -250.622054)
			(xy 334.341554 -250.627385) (xy 334.349387 -250.636624) (xy 334.35417 -250.640342) (xy 334.382618 -250.661424)
			(xy 334.394302 -250.663456) (xy 334.41756 -250.668012) (xy 334.462399 -250.683359) (xy 334.504326 -250.705453)
			(xy 334.542334 -250.733762) (xy 334.575509 -250.767606) (xy 334.603053 -250.806172) (xy 334.624304 -250.848532)
			(xy 334.638752 -250.893669) (xy 334.646049 -250.940496) (xy 334.646524 -250.964192) (xy 334.975212 -250.964192)
			(xy 334.979172 -250.915138) (xy 334.990949 -250.867354) (xy 335.01024 -250.822078) (xy 335.036543 -250.780482)
			(xy 335.069178 -250.743645) (xy 335.107299 -250.71252) (xy 335.14992 -250.687913) (xy 335.195936 -250.670461)
			(xy 335.244155 -250.660617) (xy 335.29333 -250.658636) (xy 335.342185 -250.664568) (xy 335.389456 -250.67826)
			(xy 335.433918 -250.699358) (xy 335.474421 -250.727314) (xy 335.509914 -250.761406) (xy 335.539479 -250.80075)
			(xy 335.56235 -250.844327) (xy 335.577934 -250.891008) (xy 335.585829 -250.939585) (xy 335.586324 -250.964192)
			(xy 335.915266 -250.964192) (xy 335.919226 -250.915138) (xy 335.931003 -250.867354) (xy 335.950294 -250.822078)
			(xy 335.976597 -250.780482) (xy 336.009232 -250.743645) (xy 336.047353 -250.71252) (xy 336.089974 -250.687913)
			(xy 336.13599 -250.670461) (xy 336.184209 -250.660617) (xy 336.233384 -250.658636) (xy 336.282239 -250.664568)
			(xy 336.32951 -250.67826) (xy 336.373972 -250.699358) (xy 336.414475 -250.727314) (xy 336.449968 -250.761406)
			(xy 336.479533 -250.80075) (xy 336.502404 -250.844327) (xy 336.517988 -250.891008) (xy 336.525883 -250.939585)
			(xy 336.526378 -250.964192) (xy 336.85532 -250.964192) (xy 336.85928 -250.915138) (xy 336.871057 -250.867354)
			(xy 336.890348 -250.822078) (xy 336.916651 -250.780482) (xy 336.949286 -250.743645) (xy 336.987407 -250.71252)
			(xy 337.030028 -250.687913) (xy 337.076044 -250.670461) (xy 337.124263 -250.660617) (xy 337.173438 -250.658636)
			(xy 337.222293 -250.664568) (xy 337.269564 -250.67826) (xy 337.314026 -250.699358) (xy 337.354529 -250.727314)
			(xy 337.390022 -250.761406) (xy 337.419587 -250.80075) (xy 337.442458 -250.844327) (xy 337.458042 -250.891008)
			(xy 337.465937 -250.939585) (xy 337.466432 -250.964192) (xy 337.795374 -250.964192) (xy 337.799334 -250.915138)
			(xy 337.811111 -250.867354) (xy 337.830402 -250.822078) (xy 337.856705 -250.780482) (xy 337.88934 -250.743645)
			(xy 337.927461 -250.71252) (xy 337.970082 -250.687913) (xy 338.016098 -250.670461) (xy 338.064317 -250.660617)
			(xy 338.113492 -250.658636) (xy 338.162347 -250.664568) (xy 338.209618 -250.67826) (xy 338.25408 -250.699358)
			(xy 338.294583 -250.727314) (xy 338.330076 -250.761406) (xy 338.359641 -250.80075) (xy 338.382512 -250.844327)
			(xy 338.398096 -250.891008) (xy 338.405991 -250.939585) (xy 338.406486 -250.964192) (xy 338.735428 -250.964192)
			(xy 338.739388 -250.915138) (xy 338.751165 -250.867354) (xy 338.770456 -250.822078) (xy 338.796759 -250.780482)
			(xy 338.829394 -250.743645) (xy 338.867515 -250.71252) (xy 338.910136 -250.687913) (xy 338.956152 -250.670461)
			(xy 339.004371 -250.660617) (xy 339.053546 -250.658636) (xy 339.102401 -250.664568) (xy 339.149672 -250.67826)
			(xy 339.194134 -250.699358) (xy 339.234637 -250.727314) (xy 339.27013 -250.761406) (xy 339.299695 -250.80075)
			(xy 339.322566 -250.844327) (xy 339.33815 -250.891008) (xy 339.346045 -250.939585) (xy 339.34654 -250.964192)
			(xy 339.664797 -250.964192) (xy 339.668892 -250.913464) (xy 339.681071 -250.86405) (xy 339.701019 -250.81723)
			(xy 339.72822 -250.774216) (xy 339.761968 -250.736122) (xy 339.80139 -250.703935) (xy 339.845464 -250.678489)
			(xy 339.89305 -250.660442) (xy 339.942914 -250.650262) (xy 339.993766 -250.648213) (xy 340.044287 -250.654347)
			(xy 340.093171 -250.668507) (xy 340.13915 -250.690324) (xy 340.181034 -250.719234) (xy 340.217738 -250.754489)
			(xy 340.248311 -250.795175) (xy 340.271962 -250.840238) (xy 340.288078 -250.888512) (xy 340.296242 -250.938746)
			(xy 340.296754 -250.964192) (xy 340.615282 -250.964192) (xy 340.619242 -250.915138) (xy 340.631019 -250.867354)
			(xy 340.65031 -250.822078) (xy 340.676613 -250.780482) (xy 340.709248 -250.743645) (xy 340.747369 -250.71252)
			(xy 340.78999 -250.687913) (xy 340.836006 -250.670461) (xy 340.884225 -250.660617) (xy 340.9334 -250.658636)
			(xy 340.982255 -250.664568) (xy 341.029526 -250.67826) (xy 341.073988 -250.699358) (xy 341.114491 -250.727314)
			(xy 341.149984 -250.761406) (xy 341.179549 -250.80075) (xy 341.20242 -250.844327) (xy 341.218004 -250.891008)
			(xy 341.225899 -250.939585) (xy 341.226394 -250.964192) (xy 341.555336 -250.964192) (xy 341.559296 -250.915138)
			(xy 341.571073 -250.867354) (xy 341.590364 -250.822078) (xy 341.616667 -250.780482) (xy 341.649302 -250.743645)
			(xy 341.687423 -250.71252) (xy 341.730044 -250.687913) (xy 341.77606 -250.670461) (xy 341.824279 -250.660617)
			(xy 341.873454 -250.658636) (xy 341.922309 -250.664568) (xy 341.96958 -250.67826) (xy 342.014042 -250.699358)
			(xy 342.054545 -250.727314) (xy 342.090038 -250.761406) (xy 342.119603 -250.80075) (xy 342.142474 -250.844327)
			(xy 342.158058 -250.891008) (xy 342.165953 -250.939585) (xy 342.166448 -250.964192) (xy 342.49539 -250.964192)
			(xy 342.49935 -250.915138) (xy 342.511127 -250.867354) (xy 342.530418 -250.822078) (xy 342.556721 -250.780482)
			(xy 342.589356 -250.743645) (xy 342.627477 -250.71252) (xy 342.670098 -250.687913) (xy 342.716114 -250.670461)
			(xy 342.764333 -250.660617) (xy 342.813508 -250.658636) (xy 342.862363 -250.664568) (xy 342.909634 -250.67826)
			(xy 342.954096 -250.699358) (xy 342.994599 -250.727314) (xy 343.030092 -250.761406) (xy 343.059657 -250.80075)
			(xy 343.082528 -250.844327) (xy 343.098112 -250.891008) (xy 343.106007 -250.939585) (xy 343.106502 -250.964192)
			(xy 343.424759 -250.964192) (xy 343.428854 -250.913464) (xy 343.441033 -250.86405) (xy 343.460981 -250.81723)
			(xy 343.488182 -250.774216) (xy 343.52193 -250.736122) (xy 343.561352 -250.703935) (xy 343.605426 -250.678489)
			(xy 343.653012 -250.660442) (xy 343.702876 -250.650262) (xy 343.753728 -250.648213) (xy 343.804249 -250.654347)
			(xy 343.853133 -250.668507) (xy 343.899112 -250.690324) (xy 343.940996 -250.719234) (xy 343.9777 -250.754489)
			(xy 344.008273 -250.795175) (xy 344.031924 -250.840238) (xy 344.04804 -250.888512) (xy 344.056204 -250.938746)
			(xy 344.056716 -250.964192) (xy 345.315298 -250.964192) (xy 345.319258 -250.915138) (xy 345.331035 -250.867354)
			(xy 345.350326 -250.822078) (xy 345.376629 -250.780482) (xy 345.409264 -250.743645) (xy 345.447385 -250.71252)
			(xy 345.490006 -250.687913) (xy 345.536022 -250.670461) (xy 345.584241 -250.660617) (xy 345.633416 -250.658636)
			(xy 345.682271 -250.664568) (xy 345.729542 -250.67826) (xy 345.774004 -250.699358) (xy 345.814507 -250.727314)
			(xy 345.85 -250.761406) (xy 345.879565 -250.80075) (xy 345.902436 -250.844327) (xy 345.91802 -250.891008)
			(xy 345.925915 -250.939585) (xy 345.92641 -250.964192) (xy 347.195406 -250.964192) (xy 347.199366 -250.915138)
			(xy 347.211143 -250.867354) (xy 347.230434 -250.822078) (xy 347.256737 -250.780482) (xy 347.289372 -250.743645)
			(xy 347.327493 -250.71252) (xy 347.370114 -250.687913) (xy 347.41613 -250.670461) (xy 347.464349 -250.660617)
			(xy 347.513524 -250.658636) (xy 347.562379 -250.664568) (xy 347.60965 -250.67826) (xy 347.654112 -250.699358)
			(xy 347.694615 -250.727314) (xy 347.730108 -250.761406) (xy 347.759673 -250.80075) (xy 347.782544 -250.844327)
			(xy 347.798128 -250.891008) (xy 347.806023 -250.939585) (xy 347.806518 -250.964192) (xy 347.806023 -250.988799)
			(xy 347.798128 -251.037376) (xy 347.782544 -251.084057) (xy 347.759673 -251.127634) (xy 347.730108 -251.166978)
			(xy 347.694615 -251.20107) (xy 347.654112 -251.229026) (xy 347.60965 -251.250124) (xy 347.562379 -251.263816)
			(xy 347.513524 -251.269748) (xy 347.464349 -251.267767) (xy 347.41613 -251.257923) (xy 347.370114 -251.240471)
			(xy 347.327493 -251.215864) (xy 347.289372 -251.184739) (xy 347.256737 -251.147902) (xy 347.230434 -251.106306)
			(xy 347.211143 -251.06103) (xy 347.199366 -251.013246) (xy 347.195406 -250.964192) (xy 345.92641 -250.964192)
			(xy 345.925915 -250.988799) (xy 345.91802 -251.037376) (xy 345.902436 -251.084057) (xy 345.879565 -251.127634)
			(xy 345.85 -251.166978) (xy 345.814507 -251.20107) (xy 345.774004 -251.229026) (xy 345.729542 -251.250124)
			(xy 345.682271 -251.263816) (xy 345.633416 -251.269748) (xy 345.584241 -251.267767) (xy 345.536022 -251.257923)
			(xy 345.490006 -251.240471) (xy 345.447385 -251.215864) (xy 345.409264 -251.184739) (xy 345.376629 -251.147902)
			(xy 345.350326 -251.106306) (xy 345.331035 -251.06103) (xy 345.319258 -251.013246) (xy 345.315298 -250.964192)
			(xy 344.056716 -250.964192) (xy 344.056204 -250.989638) (xy 344.04804 -251.039872) (xy 344.031924 -251.088146)
			(xy 344.008273 -251.133209) (xy 343.9777 -251.173895) (xy 343.940996 -251.20915) (xy 343.899112 -251.23806)
			(xy 343.853133 -251.259877) (xy 343.804249 -251.274037) (xy 343.753728 -251.280171) (xy 343.702876 -251.278122)
			(xy 343.653012 -251.267942) (xy 343.605426 -251.249895) (xy 343.561352 -251.224449) (xy 343.52193 -251.192262)
			(xy 343.488182 -251.154168) (xy 343.460981 -251.111154) (xy 343.441033 -251.064334) (xy 343.428854 -251.01492)
			(xy 343.424759 -250.964192) (xy 343.106502 -250.964192) (xy 343.106007 -250.988799) (xy 343.098112 -251.037376)
			(xy 343.082528 -251.084057) (xy 343.059657 -251.127634) (xy 343.030092 -251.166978) (xy 342.994599 -251.20107)
			(xy 342.954096 -251.229026) (xy 342.909634 -251.250124) (xy 342.862363 -251.263816) (xy 342.813508 -251.269748)
			(xy 342.764333 -251.267767) (xy 342.716114 -251.257923) (xy 342.670098 -251.240471) (xy 342.627477 -251.215864)
			(xy 342.589356 -251.184739) (xy 342.556721 -251.147902) (xy 342.530418 -251.106306) (xy 342.511127 -251.06103)
			(xy 342.49935 -251.013246) (xy 342.49539 -250.964192) (xy 342.166448 -250.964192) (xy 342.165953 -250.988799)
			(xy 342.158058 -251.037376) (xy 342.142474 -251.084057) (xy 342.119603 -251.127634) (xy 342.090038 -251.166978)
			(xy 342.054545 -251.20107) (xy 342.014042 -251.229026) (xy 341.96958 -251.250124) (xy 341.922309 -251.263816)
			(xy 341.873454 -251.269748) (xy 341.824279 -251.267767) (xy 341.77606 -251.257923) (xy 341.730044 -251.240471)
			(xy 341.687423 -251.215864) (xy 341.649302 -251.184739) (xy 341.616667 -251.147902) (xy 341.590364 -251.106306)
			(xy 341.571073 -251.06103) (xy 341.559296 -251.013246) (xy 341.555336 -250.964192) (xy 341.226394 -250.964192)
			(xy 341.225899 -250.988799) (xy 341.218004 -251.037376) (xy 341.20242 -251.084057) (xy 341.179549 -251.127634)
			(xy 341.149984 -251.166978) (xy 341.114491 -251.20107) (xy 341.073988 -251.229026) (xy 341.029526 -251.250124)
			(xy 340.982255 -251.263816) (xy 340.9334 -251.269748) (xy 340.884225 -251.267767) (xy 340.836006 -251.257923)
			(xy 340.78999 -251.240471) (xy 340.747369 -251.215864) (xy 340.709248 -251.184739) (xy 340.676613 -251.147902)
			(xy 340.65031 -251.106306) (xy 340.631019 -251.06103) (xy 340.619242 -251.013246) (xy 340.615282 -250.964192)
			(xy 340.296754 -250.964192) (xy 340.296242 -250.989638) (xy 340.288078 -251.039872) (xy 340.271962 -251.088146)
			(xy 340.248311 -251.133209) (xy 340.217738 -251.173895) (xy 340.181034 -251.20915) (xy 340.13915 -251.23806)
			(xy 340.093171 -251.259877) (xy 340.044287 -251.274037) (xy 339.993766 -251.280171) (xy 339.942914 -251.278122)
			(xy 339.89305 -251.267942) (xy 339.845464 -251.249895) (xy 339.80139 -251.224449) (xy 339.761968 -251.192262)
			(xy 339.72822 -251.154168) (xy 339.701019 -251.111154) (xy 339.681071 -251.064334) (xy 339.668892 -251.01492)
			(xy 339.664797 -250.964192) (xy 339.34654 -250.964192) (xy 339.346045 -250.988799) (xy 339.33815 -251.037376)
			(xy 339.322566 -251.084057) (xy 339.299695 -251.127634) (xy 339.27013 -251.166978) (xy 339.234637 -251.20107)
			(xy 339.194134 -251.229026) (xy 339.149672 -251.250124) (xy 339.102401 -251.263816) (xy 339.053546 -251.269748)
			(xy 339.004371 -251.267767) (xy 338.956152 -251.257923) (xy 338.910136 -251.240471) (xy 338.867515 -251.215864)
			(xy 338.829394 -251.184739) (xy 338.796759 -251.147902) (xy 338.770456 -251.106306) (xy 338.751165 -251.06103)
			(xy 338.739388 -251.013246) (xy 338.735428 -250.964192) (xy 338.406486 -250.964192) (xy 338.405991 -250.988799)
			(xy 338.398096 -251.037376) (xy 338.382512 -251.084057) (xy 338.359641 -251.127634) (xy 338.330076 -251.166978)
			(xy 338.294583 -251.20107) (xy 338.25408 -251.229026) (xy 338.209618 -251.250124) (xy 338.162347 -251.263816)
			(xy 338.113492 -251.269748) (xy 338.064317 -251.267767) (xy 338.016098 -251.257923) (xy 337.970082 -251.240471)
			(xy 337.927461 -251.215864) (xy 337.88934 -251.184739) (xy 337.856705 -251.147902) (xy 337.830402 -251.106306)
			(xy 337.811111 -251.06103) (xy 337.799334 -251.013246) (xy 337.795374 -250.964192) (xy 337.466432 -250.964192)
			(xy 337.465937 -250.988799) (xy 337.458042 -251.037376) (xy 337.442458 -251.084057) (xy 337.419587 -251.127634)
			(xy 337.390022 -251.166978) (xy 337.354529 -251.20107) (xy 337.314026 -251.229026) (xy 337.269564 -251.250124)
			(xy 337.222293 -251.263816) (xy 337.173438 -251.269748) (xy 337.124263 -251.267767) (xy 337.076044 -251.257923)
			(xy 337.030028 -251.240471) (xy 336.987407 -251.215864) (xy 336.949286 -251.184739) (xy 336.916651 -251.147902)
			(xy 336.890348 -251.106306) (xy 336.871057 -251.06103) (xy 336.85928 -251.013246) (xy 336.85532 -250.964192)
			(xy 336.526378 -250.964192) (xy 336.525883 -250.988799) (xy 336.517988 -251.037376) (xy 336.502404 -251.084057)
			(xy 336.479533 -251.127634) (xy 336.449968 -251.166978) (xy 336.414475 -251.20107) (xy 336.373972 -251.229026)
			(xy 336.32951 -251.250124) (xy 336.282239 -251.263816) (xy 336.233384 -251.269748) (xy 336.184209 -251.267767)
			(xy 336.13599 -251.257923) (xy 336.089974 -251.240471) (xy 336.047353 -251.215864) (xy 336.009232 -251.184739)
			(xy 335.976597 -251.147902) (xy 335.950294 -251.106306) (xy 335.931003 -251.06103) (xy 335.919226 -251.013246)
			(xy 335.915266 -250.964192) (xy 335.586324 -250.964192) (xy 335.585829 -250.988799) (xy 335.577934 -251.037376)
			(xy 335.56235 -251.084057) (xy 335.539479 -251.127634) (xy 335.509914 -251.166978) (xy 335.474421 -251.20107)
			(xy 335.433918 -251.229026) (xy 335.389456 -251.250124) (xy 335.342185 -251.263816) (xy 335.29333 -251.269748)
			(xy 335.244155 -251.267767) (xy 335.195936 -251.257923) (xy 335.14992 -251.240471) (xy 335.107299 -251.215864)
			(xy 335.069178 -251.184739) (xy 335.036543 -251.147902) (xy 335.01024 -251.106306) (xy 334.990949 -251.06103)
			(xy 334.979172 -251.013246) (xy 334.975212 -250.964192) (xy 334.646524 -250.964192) (xy 334.646 -250.989839)
			(xy 334.637433 -251.040411) (xy 334.620538 -251.088842) (xy 334.59579 -251.13377) (xy 334.563885 -251.173933)
			(xy 334.525719 -251.208202) (xy 334.482365 -251.235614) (xy 334.435041 -251.255398) (xy 334.385077 -251.266999)
			(xy 334.359504 -251.268992) (xy 334.354984 -251.269401) (xy 334.346175 -251.271581) (xy 334.341978 -251.27331)
			(xy 334.32496 -251.280676) (xy 334.320515 -251.282773) (xy 334.312463 -251.288406) (xy 334.308958 -251.291852)
			(xy 334.267556 -251.334524) (xy 334.261071 -251.341874) (xy 334.253748 -251.360037) (xy 334.253332 -251.36983)
			(xy 334.253332 -251.774198) (xy 334.505312 -251.774198) (xy 334.509272 -251.725144) (xy 334.521049 -251.67736)
			(xy 334.54034 -251.632084) (xy 334.566643 -251.590488) (xy 334.599278 -251.553651) (xy 334.637399 -251.522526)
			(xy 334.68002 -251.497919) (xy 334.726036 -251.480467) (xy 334.774255 -251.470623) (xy 334.82343 -251.468642)
			(xy 334.872285 -251.474574) (xy 334.919556 -251.488266) (xy 334.964018 -251.509364) (xy 335.004521 -251.53732)
			(xy 335.040014 -251.571412) (xy 335.069579 -251.610756) (xy 335.09245 -251.654333) (xy 335.108034 -251.701014)
			(xy 335.115929 -251.749591) (xy 335.116424 -251.774198) (xy 335.445366 -251.774198) (xy 335.449326 -251.725144)
			(xy 335.461103 -251.67736) (xy 335.480394 -251.632084) (xy 335.506697 -251.590488) (xy 335.539332 -251.553651)
			(xy 335.577453 -251.522526) (xy 335.620074 -251.497919) (xy 335.66609 -251.480467) (xy 335.714309 -251.470623)
			(xy 335.763484 -251.468642) (xy 335.812339 -251.474574) (xy 335.85961 -251.488266) (xy 335.904072 -251.509364)
			(xy 335.944575 -251.53732) (xy 335.980068 -251.571412) (xy 336.009633 -251.610756) (xy 336.032504 -251.654333)
			(xy 336.048088 -251.701014) (xy 336.055983 -251.749591) (xy 336.056478 -251.774198) (xy 336.38542 -251.774198)
			(xy 336.38938 -251.725144) (xy 336.401157 -251.67736) (xy 336.420448 -251.632084) (xy 336.446751 -251.590488)
			(xy 336.479386 -251.553651) (xy 336.517507 -251.522526) (xy 336.560128 -251.497919) (xy 336.606144 -251.480467)
			(xy 336.654363 -251.470623) (xy 336.703538 -251.468642) (xy 336.752393 -251.474574) (xy 336.799664 -251.488266)
			(xy 336.844126 -251.509364) (xy 336.884629 -251.53732) (xy 336.920122 -251.571412) (xy 336.949687 -251.610756)
			(xy 336.972558 -251.654333) (xy 336.988142 -251.701014) (xy 336.996037 -251.749591) (xy 336.996532 -251.774198)
			(xy 337.32522 -251.774198) (xy 337.32918 -251.725144) (xy 337.340957 -251.67736) (xy 337.360248 -251.632084)
			(xy 337.386551 -251.590488) (xy 337.419186 -251.553651) (xy 337.457307 -251.522526) (xy 337.499928 -251.497919)
			(xy 337.545944 -251.480467) (xy 337.594163 -251.470623) (xy 337.643338 -251.468642) (xy 337.692193 -251.474574)
			(xy 337.739464 -251.488266) (xy 337.783926 -251.509364) (xy 337.824429 -251.53732) (xy 337.859922 -251.571412)
			(xy 337.889487 -251.610756) (xy 337.912358 -251.654333) (xy 337.927942 -251.701014) (xy 337.935837 -251.749591)
			(xy 337.936332 -251.774198) (xy 338.254843 -251.774198) (xy 338.258938 -251.72347) (xy 338.271117 -251.674056)
			(xy 338.291065 -251.627236) (xy 338.318266 -251.584222) (xy 338.352014 -251.546128) (xy 338.391436 -251.513941)
			(xy 338.43551 -251.488495) (xy 338.483096 -251.470448) (xy 338.53296 -251.460268) (xy 338.583812 -251.458219)
			(xy 338.634333 -251.464353) (xy 338.683217 -251.478513) (xy 338.729196 -251.50033) (xy 338.77108 -251.52924)
			(xy 338.807784 -251.564495) (xy 338.838357 -251.605181) (xy 338.862008 -251.650244) (xy 338.878124 -251.698518)
			(xy 338.886288 -251.748752) (xy 338.8868 -251.774198) (xy 339.205328 -251.774198) (xy 339.209288 -251.725144)
			(xy 339.221065 -251.67736) (xy 339.240356 -251.632084) (xy 339.266659 -251.590488) (xy 339.299294 -251.553651)
			(xy 339.337415 -251.522526) (xy 339.380036 -251.497919) (xy 339.426052 -251.480467) (xy 339.474271 -251.470623)
			(xy 339.523446 -251.468642) (xy 339.572301 -251.474574) (xy 339.619572 -251.488266) (xy 339.664034 -251.509364)
			(xy 339.704537 -251.53732) (xy 339.74003 -251.571412) (xy 339.769595 -251.610756) (xy 339.792466 -251.654333)
			(xy 339.80805 -251.701014) (xy 339.815945 -251.749591) (xy 339.81644 -251.774198) (xy 340.145382 -251.774198)
			(xy 340.149342 -251.725144) (xy 340.161119 -251.67736) (xy 340.18041 -251.632084) (xy 340.206713 -251.590488)
			(xy 340.239348 -251.553651) (xy 340.277469 -251.522526) (xy 340.32009 -251.497919) (xy 340.366106 -251.480467)
			(xy 340.414325 -251.470623) (xy 340.4635 -251.468642) (xy 340.512355 -251.474574) (xy 340.559626 -251.488266)
			(xy 340.604088 -251.509364) (xy 340.644591 -251.53732) (xy 340.680084 -251.571412) (xy 340.709649 -251.610756)
			(xy 340.73252 -251.654333) (xy 340.748104 -251.701014) (xy 340.755999 -251.749591) (xy 340.756494 -251.774198)
			(xy 341.085182 -251.774198) (xy 341.089142 -251.725144) (xy 341.100919 -251.67736) (xy 341.12021 -251.632084)
			(xy 341.146513 -251.590488) (xy 341.179148 -251.553651) (xy 341.217269 -251.522526) (xy 341.25989 -251.497919)
			(xy 341.305906 -251.480467) (xy 341.354125 -251.470623) (xy 341.4033 -251.468642) (xy 341.452155 -251.474574)
			(xy 341.499426 -251.488266) (xy 341.543888 -251.509364) (xy 341.584391 -251.53732) (xy 341.619884 -251.571412)
			(xy 341.649449 -251.610756) (xy 341.67232 -251.654333) (xy 341.687904 -251.701014) (xy 341.695799 -251.749591)
			(xy 341.696294 -251.774198) (xy 342.014805 -251.774198) (xy 342.0189 -251.72347) (xy 342.031079 -251.674056)
			(xy 342.051027 -251.627236) (xy 342.078228 -251.584222) (xy 342.111976 -251.546128) (xy 342.151398 -251.513941)
			(xy 342.195472 -251.488495) (xy 342.243058 -251.470448) (xy 342.292922 -251.460268) (xy 342.343774 -251.458219)
			(xy 342.394295 -251.464353) (xy 342.443179 -251.478513) (xy 342.489158 -251.50033) (xy 342.531042 -251.52924)
			(xy 342.567746 -251.564495) (xy 342.598319 -251.605181) (xy 342.62197 -251.650244) (xy 342.638086 -251.698518)
			(xy 342.64625 -251.748752) (xy 342.646762 -251.774198) (xy 342.96529 -251.774198) (xy 342.96925 -251.725144)
			(xy 342.981027 -251.67736) (xy 343.000318 -251.632084) (xy 343.026621 -251.590488) (xy 343.059256 -251.553651)
			(xy 343.097377 -251.522526) (xy 343.139998 -251.497919) (xy 343.186014 -251.480467) (xy 343.234233 -251.470623)
			(xy 343.283408 -251.468642) (xy 343.332263 -251.474574) (xy 343.379534 -251.488266) (xy 343.423996 -251.509364)
			(xy 343.464499 -251.53732) (xy 343.499992 -251.571412) (xy 343.529557 -251.610756) (xy 343.552428 -251.654333)
			(xy 343.568012 -251.701014) (xy 343.575907 -251.749591) (xy 343.576402 -251.774198) (xy 343.905344 -251.774198)
			(xy 343.909304 -251.725144) (xy 343.921081 -251.67736) (xy 343.940372 -251.632084) (xy 343.966675 -251.590488)
			(xy 343.99931 -251.553651) (xy 344.037431 -251.522526) (xy 344.080052 -251.497919) (xy 344.126068 -251.480467)
			(xy 344.174287 -251.470623) (xy 344.223462 -251.468642) (xy 344.272317 -251.474574) (xy 344.319588 -251.488266)
			(xy 344.36405 -251.509364) (xy 344.404553 -251.53732) (xy 344.440046 -251.571412) (xy 344.469611 -251.610756)
			(xy 344.492482 -251.654333) (xy 344.508066 -251.701014) (xy 344.515961 -251.749591) (xy 344.516456 -251.774198)
			(xy 345.785198 -251.774198) (xy 345.789158 -251.725144) (xy 345.800935 -251.67736) (xy 345.820226 -251.632084)
			(xy 345.846529 -251.590488) (xy 345.879164 -251.553651) (xy 345.917285 -251.522526) (xy 345.959906 -251.497919)
			(xy 346.005922 -251.480467) (xy 346.054141 -251.470623) (xy 346.103316 -251.468642) (xy 346.152171 -251.474574)
			(xy 346.199442 -251.488266) (xy 346.243904 -251.509364) (xy 346.284407 -251.53732) (xy 346.3199 -251.571412)
			(xy 346.349465 -251.610756) (xy 346.372336 -251.654333) (xy 346.38792 -251.701014) (xy 346.395815 -251.749591)
			(xy 346.39631 -251.774198) (xy 347.665306 -251.774198) (xy 347.669266 -251.725144) (xy 347.681043 -251.67736)
			(xy 347.700334 -251.632084) (xy 347.726637 -251.590488) (xy 347.759272 -251.553651) (xy 347.797393 -251.522526)
			(xy 347.840014 -251.497919) (xy 347.88603 -251.480467) (xy 347.934249 -251.470623) (xy 347.983424 -251.468642)
			(xy 348.032279 -251.474574) (xy 348.07955 -251.488266) (xy 348.124012 -251.509364) (xy 348.164515 -251.53732)
			(xy 348.200008 -251.571412) (xy 348.229573 -251.610756) (xy 348.252444 -251.654333) (xy 348.268028 -251.701014)
			(xy 348.275923 -251.749591) (xy 348.276418 -251.774198) (xy 348.275923 -251.798805) (xy 348.268028 -251.847382)
			(xy 348.252444 -251.894063) (xy 348.229573 -251.93764) (xy 348.200008 -251.976984) (xy 348.164515 -252.011076)
			(xy 348.124012 -252.039032) (xy 348.07955 -252.06013) (xy 348.032279 -252.073822) (xy 347.983424 -252.079754)
			(xy 347.934249 -252.077773) (xy 347.88603 -252.067929) (xy 347.840014 -252.050477) (xy 347.797393 -252.02587)
			(xy 347.759272 -251.994745) (xy 347.726637 -251.957908) (xy 347.700334 -251.916312) (xy 347.681043 -251.871036)
			(xy 347.669266 -251.823252) (xy 347.665306 -251.774198) (xy 346.39631 -251.774198) (xy 346.395815 -251.798805)
			(xy 346.38792 -251.847382) (xy 346.372336 -251.894063) (xy 346.349465 -251.93764) (xy 346.3199 -251.976984)
			(xy 346.284407 -252.011076) (xy 346.243904 -252.039032) (xy 346.199442 -252.06013) (xy 346.152171 -252.073822)
			(xy 346.103316 -252.079754) (xy 346.054141 -252.077773) (xy 346.005922 -252.067929) (xy 345.959906 -252.050477)
			(xy 345.917285 -252.02587) (xy 345.879164 -251.994745) (xy 345.846529 -251.957908) (xy 345.820226 -251.916312)
			(xy 345.800935 -251.871036) (xy 345.789158 -251.823252) (xy 345.785198 -251.774198) (xy 344.516456 -251.774198)
			(xy 344.515961 -251.798805) (xy 344.508066 -251.847382) (xy 344.492482 -251.894063) (xy 344.469611 -251.93764)
			(xy 344.440046 -251.976984) (xy 344.404553 -252.011076) (xy 344.36405 -252.039032) (xy 344.319588 -252.06013)
			(xy 344.272317 -252.073822) (xy 344.223462 -252.079754) (xy 344.174287 -252.077773) (xy 344.126068 -252.067929)
			(xy 344.080052 -252.050477) (xy 344.037431 -252.02587) (xy 343.99931 -251.994745) (xy 343.966675 -251.957908)
			(xy 343.940372 -251.916312) (xy 343.921081 -251.871036) (xy 343.909304 -251.823252) (xy 343.905344 -251.774198)
			(xy 343.576402 -251.774198) (xy 343.575907 -251.798805) (xy 343.568012 -251.847382) (xy 343.552428 -251.894063)
			(xy 343.529557 -251.93764) (xy 343.499992 -251.976984) (xy 343.464499 -252.011076) (xy 343.423996 -252.039032)
			(xy 343.379534 -252.06013) (xy 343.332263 -252.073822) (xy 343.283408 -252.079754) (xy 343.234233 -252.077773)
			(xy 343.186014 -252.067929) (xy 343.139998 -252.050477) (xy 343.097377 -252.02587) (xy 343.059256 -251.994745)
			(xy 343.026621 -251.957908) (xy 343.000318 -251.916312) (xy 342.981027 -251.871036) (xy 342.96925 -251.823252)
			(xy 342.96529 -251.774198) (xy 342.646762 -251.774198) (xy 342.64625 -251.799644) (xy 342.638086 -251.849878)
			(xy 342.62197 -251.898152) (xy 342.598319 -251.943215) (xy 342.567746 -251.983901) (xy 342.531042 -252.019156)
			(xy 342.489158 -252.048066) (xy 342.443179 -252.069883) (xy 342.394295 -252.084043) (xy 342.343774 -252.090177)
			(xy 342.292922 -252.088128) (xy 342.243058 -252.077948) (xy 342.195472 -252.059901) (xy 342.151398 -252.034455)
			(xy 342.111976 -252.002268) (xy 342.078228 -251.964174) (xy 342.051027 -251.92116) (xy 342.031079 -251.87434)
			(xy 342.0189 -251.824926) (xy 342.014805 -251.774198) (xy 341.696294 -251.774198) (xy 341.695799 -251.798805)
			(xy 341.687904 -251.847382) (xy 341.67232 -251.894063) (xy 341.649449 -251.93764) (xy 341.619884 -251.976984)
			(xy 341.584391 -252.011076) (xy 341.543888 -252.039032) (xy 341.499426 -252.06013) (xy 341.452155 -252.073822)
			(xy 341.4033 -252.079754) (xy 341.354125 -252.077773) (xy 341.305906 -252.067929) (xy 341.25989 -252.050477)
			(xy 341.217269 -252.02587) (xy 341.179148 -251.994745) (xy 341.146513 -251.957908) (xy 341.12021 -251.916312)
			(xy 341.100919 -251.871036) (xy 341.089142 -251.823252) (xy 341.085182 -251.774198) (xy 340.756494 -251.774198)
			(xy 340.755999 -251.798805) (xy 340.748104 -251.847382) (xy 340.73252 -251.894063) (xy 340.709649 -251.93764)
			(xy 340.680084 -251.976984) (xy 340.644591 -252.011076) (xy 340.604088 -252.039032) (xy 340.559626 -252.06013)
			(xy 340.512355 -252.073822) (xy 340.4635 -252.079754) (xy 340.414325 -252.077773) (xy 340.366106 -252.067929)
			(xy 340.32009 -252.050477) (xy 340.277469 -252.02587) (xy 340.239348 -251.994745) (xy 340.206713 -251.957908)
			(xy 340.18041 -251.916312) (xy 340.161119 -251.871036) (xy 340.149342 -251.823252) (xy 340.145382 -251.774198)
			(xy 339.81644 -251.774198) (xy 339.815945 -251.798805) (xy 339.80805 -251.847382) (xy 339.792466 -251.894063)
			(xy 339.769595 -251.93764) (xy 339.74003 -251.976984) (xy 339.704537 -252.011076) (xy 339.664034 -252.039032)
			(xy 339.619572 -252.06013) (xy 339.572301 -252.073822) (xy 339.523446 -252.079754) (xy 339.474271 -252.077773)
			(xy 339.426052 -252.067929) (xy 339.380036 -252.050477) (xy 339.337415 -252.02587) (xy 339.299294 -251.994745)
			(xy 339.266659 -251.957908) (xy 339.240356 -251.916312) (xy 339.221065 -251.871036) (xy 339.209288 -251.823252)
			(xy 339.205328 -251.774198) (xy 338.8868 -251.774198) (xy 338.886288 -251.799644) (xy 338.878124 -251.849878)
			(xy 338.862008 -251.898152) (xy 338.838357 -251.943215) (xy 338.807784 -251.983901) (xy 338.77108 -252.019156)
			(xy 338.729196 -252.048066) (xy 338.683217 -252.069883) (xy 338.634333 -252.084043) (xy 338.583812 -252.090177)
			(xy 338.53296 -252.088128) (xy 338.483096 -252.077948) (xy 338.43551 -252.059901) (xy 338.391436 -252.034455)
			(xy 338.352014 -252.002268) (xy 338.318266 -251.964174) (xy 338.291065 -251.92116) (xy 338.271117 -251.87434)
			(xy 338.258938 -251.824926) (xy 338.254843 -251.774198) (xy 337.936332 -251.774198) (xy 337.935837 -251.798805)
			(xy 337.927942 -251.847382) (xy 337.912358 -251.894063) (xy 337.889487 -251.93764) (xy 337.859922 -251.976984)
			(xy 337.824429 -252.011076) (xy 337.783926 -252.039032) (xy 337.739464 -252.06013) (xy 337.692193 -252.073822)
			(xy 337.643338 -252.079754) (xy 337.594163 -252.077773) (xy 337.545944 -252.067929) (xy 337.499928 -252.050477)
			(xy 337.457307 -252.02587) (xy 337.419186 -251.994745) (xy 337.386551 -251.957908) (xy 337.360248 -251.916312)
			(xy 337.340957 -251.871036) (xy 337.32918 -251.823252) (xy 337.32522 -251.774198) (xy 336.996532 -251.774198)
			(xy 336.996037 -251.798805) (xy 336.988142 -251.847382) (xy 336.972558 -251.894063) (xy 336.949687 -251.93764)
			(xy 336.920122 -251.976984) (xy 336.884629 -252.011076) (xy 336.844126 -252.039032) (xy 336.799664 -252.06013)
			(xy 336.752393 -252.073822) (xy 336.703538 -252.079754) (xy 336.654363 -252.077773) (xy 336.606144 -252.067929)
			(xy 336.560128 -252.050477) (xy 336.517507 -252.02587) (xy 336.479386 -251.994745) (xy 336.446751 -251.957908)
			(xy 336.420448 -251.916312) (xy 336.401157 -251.871036) (xy 336.38938 -251.823252) (xy 336.38542 -251.774198)
			(xy 336.056478 -251.774198) (xy 336.055983 -251.798805) (xy 336.048088 -251.847382) (xy 336.032504 -251.894063)
			(xy 336.009633 -251.93764) (xy 335.980068 -251.976984) (xy 335.944575 -252.011076) (xy 335.904072 -252.039032)
			(xy 335.85961 -252.06013) (xy 335.812339 -252.073822) (xy 335.763484 -252.079754) (xy 335.714309 -252.077773)
			(xy 335.66609 -252.067929) (xy 335.620074 -252.050477) (xy 335.577453 -252.02587) (xy 335.539332 -251.994745)
			(xy 335.506697 -251.957908) (xy 335.480394 -251.916312) (xy 335.461103 -251.871036) (xy 335.449326 -251.823252)
			(xy 335.445366 -251.774198) (xy 335.116424 -251.774198) (xy 335.115929 -251.798805) (xy 335.108034 -251.847382)
			(xy 335.09245 -251.894063) (xy 335.069579 -251.93764) (xy 335.040014 -251.976984) (xy 335.004521 -252.011076)
			(xy 334.964018 -252.039032) (xy 334.919556 -252.06013) (xy 334.872285 -252.073822) (xy 334.82343 -252.079754)
			(xy 334.774255 -252.077773) (xy 334.726036 -252.067929) (xy 334.68002 -252.050477) (xy 334.637399 -252.02587)
			(xy 334.599278 -251.994745) (xy 334.566643 -251.957908) (xy 334.54034 -251.916312) (xy 334.521049 -251.871036)
			(xy 334.509272 -251.823252) (xy 334.505312 -251.774198) (xy 334.253332 -251.774198) (xy 334.253332 -252.173232)
			(xy 334.254348 -252.183138) (xy 334.255618 -252.189742) (xy 334.257204 -252.196905) (xy 334.263916 -252.209944)
			(xy 334.268826 -252.215396) (xy 334.322674 -252.270768) (xy 334.340708 -252.278642) (xy 334.350614 -252.27915)
			(xy 334.374103 -252.280315) (xy 334.420326 -252.288969) (xy 334.464678 -252.304605) (xy 334.506108 -252.326856)
			(xy 334.543637 -252.355194) (xy 334.576379 -252.388951) (xy 334.603559 -252.427327) (xy 334.624535 -252.469417)
			(xy 334.638811 -252.514224) (xy 334.64605 -252.560691) (xy 334.646524 -252.584204) (xy 334.975212 -252.584204)
			(xy 334.979172 -252.53515) (xy 334.990949 -252.487366) (xy 335.01024 -252.44209) (xy 335.036543 -252.400494)
			(xy 335.069178 -252.363657) (xy 335.107299 -252.332532) (xy 335.14992 -252.307925) (xy 335.195936 -252.290473)
			(xy 335.244155 -252.280629) (xy 335.29333 -252.278648) (xy 335.342185 -252.28458) (xy 335.389456 -252.298272)
			(xy 335.433918 -252.31937) (xy 335.474421 -252.347326) (xy 335.509914 -252.381418) (xy 335.539479 -252.420762)
			(xy 335.56235 -252.464339) (xy 335.577934 -252.51102) (xy 335.585829 -252.559597) (xy 335.586324 -252.584204)
			(xy 335.915266 -252.584204) (xy 335.919226 -252.53515) (xy 335.931003 -252.487366) (xy 335.950294 -252.44209)
			(xy 335.976597 -252.400494) (xy 336.009232 -252.363657) (xy 336.047353 -252.332532) (xy 336.089974 -252.307925)
			(xy 336.13599 -252.290473) (xy 336.184209 -252.280629) (xy 336.233384 -252.278648) (xy 336.282239 -252.28458)
			(xy 336.32951 -252.298272) (xy 336.373972 -252.31937) (xy 336.414475 -252.347326) (xy 336.449968 -252.381418)
			(xy 336.479533 -252.420762) (xy 336.502404 -252.464339) (xy 336.517988 -252.51102) (xy 336.525883 -252.559597)
			(xy 336.526378 -252.584204) (xy 336.85532 -252.584204) (xy 336.85928 -252.53515) (xy 336.871057 -252.487366)
			(xy 336.890348 -252.44209) (xy 336.916651 -252.400494) (xy 336.949286 -252.363657) (xy 336.987407 -252.332532)
			(xy 337.030028 -252.307925) (xy 337.076044 -252.290473) (xy 337.124263 -252.280629) (xy 337.173438 -252.278648)
			(xy 337.222293 -252.28458) (xy 337.269564 -252.298272) (xy 337.314026 -252.31937) (xy 337.354529 -252.347326)
			(xy 337.390022 -252.381418) (xy 337.419587 -252.420762) (xy 337.442458 -252.464339) (xy 337.458042 -252.51102)
			(xy 337.465937 -252.559597) (xy 337.466432 -252.584204) (xy 337.795374 -252.584204) (xy 337.799334 -252.53515)
			(xy 337.811111 -252.487366) (xy 337.830402 -252.44209) (xy 337.856705 -252.400494) (xy 337.88934 -252.363657)
			(xy 337.927461 -252.332532) (xy 337.970082 -252.307925) (xy 338.016098 -252.290473) (xy 338.064317 -252.280629)
			(xy 338.113492 -252.278648) (xy 338.162347 -252.28458) (xy 338.209618 -252.298272) (xy 338.25408 -252.31937)
			(xy 338.294583 -252.347326) (xy 338.330076 -252.381418) (xy 338.359641 -252.420762) (xy 338.382512 -252.464339)
			(xy 338.398096 -252.51102) (xy 338.405991 -252.559597) (xy 338.406486 -252.584204) (xy 338.724743 -252.584204)
			(xy 338.728838 -252.533476) (xy 338.741017 -252.484062) (xy 338.760965 -252.437242) (xy 338.788166 -252.394228)
			(xy 338.821914 -252.356134) (xy 338.861336 -252.323947) (xy 338.90541 -252.298501) (xy 338.952996 -252.280454)
			(xy 339.00286 -252.270274) (xy 339.053712 -252.268225) (xy 339.104233 -252.274359) (xy 339.153117 -252.288519)
			(xy 339.199096 -252.310336) (xy 339.24098 -252.339246) (xy 339.277684 -252.374501) (xy 339.308257 -252.415187)
			(xy 339.331908 -252.46025) (xy 339.348024 -252.508524) (xy 339.356188 -252.558758) (xy 339.3567 -252.584204)
			(xy 339.664797 -252.584204) (xy 339.668892 -252.533476) (xy 339.681071 -252.484062) (xy 339.701019 -252.437242)
			(xy 339.72822 -252.394228) (xy 339.761968 -252.356134) (xy 339.80139 -252.323947) (xy 339.845464 -252.298501)
			(xy 339.89305 -252.280454) (xy 339.942914 -252.270274) (xy 339.993766 -252.268225) (xy 340.044287 -252.274359)
			(xy 340.093171 -252.288519) (xy 340.13915 -252.310336) (xy 340.181034 -252.339246) (xy 340.217738 -252.374501)
			(xy 340.248311 -252.415187) (xy 340.271962 -252.46025) (xy 340.288078 -252.508524) (xy 340.296242 -252.558758)
			(xy 340.296754 -252.584204) (xy 340.615282 -252.584204) (xy 340.619242 -252.53515) (xy 340.631019 -252.487366)
			(xy 340.65031 -252.44209) (xy 340.676613 -252.400494) (xy 340.709248 -252.363657) (xy 340.747369 -252.332532)
			(xy 340.78999 -252.307925) (xy 340.836006 -252.290473) (xy 340.884225 -252.280629) (xy 340.9334 -252.278648)
			(xy 340.982255 -252.28458) (xy 341.029526 -252.298272) (xy 341.073988 -252.31937) (xy 341.114491 -252.347326)
			(xy 341.149984 -252.381418) (xy 341.179549 -252.420762) (xy 341.20242 -252.464339) (xy 341.218004 -252.51102)
			(xy 341.225899 -252.559597) (xy 341.226394 -252.584204) (xy 341.544905 -252.584204) (xy 341.549 -252.533476)
			(xy 341.561179 -252.484062) (xy 341.581127 -252.437242) (xy 341.608328 -252.394228) (xy 341.642076 -252.356134)
			(xy 341.681498 -252.323947) (xy 341.725572 -252.298501) (xy 341.773158 -252.280454) (xy 341.823022 -252.270274)
			(xy 341.873874 -252.268225) (xy 341.924395 -252.274359) (xy 341.973279 -252.288519) (xy 342.019258 -252.310336)
			(xy 342.061142 -252.339246) (xy 342.097846 -252.374501) (xy 342.128419 -252.415187) (xy 342.15207 -252.46025)
			(xy 342.168186 -252.508524) (xy 342.17635 -252.558758) (xy 342.176862 -252.584204) (xy 342.49539 -252.584204)
			(xy 342.49935 -252.53515) (xy 342.511127 -252.487366) (xy 342.530418 -252.44209) (xy 342.556721 -252.400494)
			(xy 342.589356 -252.363657) (xy 342.627477 -252.332532) (xy 342.670098 -252.307925) (xy 342.716114 -252.290473)
			(xy 342.764333 -252.280629) (xy 342.813508 -252.278648) (xy 342.862363 -252.28458) (xy 342.909634 -252.298272)
			(xy 342.954096 -252.31937) (xy 342.994599 -252.347326) (xy 343.030092 -252.381418) (xy 343.059657 -252.420762)
			(xy 343.082528 -252.464339) (xy 343.098112 -252.51102) (xy 343.106007 -252.559597) (xy 343.106502 -252.584204)
			(xy 343.424759 -252.584204) (xy 343.428854 -252.533476) (xy 343.441033 -252.484062) (xy 343.460981 -252.437242)
			(xy 343.488182 -252.394228) (xy 343.52193 -252.356134) (xy 343.561352 -252.323947) (xy 343.605426 -252.298501)
			(xy 343.653012 -252.280454) (xy 343.702876 -252.270274) (xy 343.753728 -252.268225) (xy 343.804249 -252.274359)
			(xy 343.853133 -252.288519) (xy 343.899112 -252.310336) (xy 343.940996 -252.339246) (xy 343.9777 -252.374501)
			(xy 344.008273 -252.415187) (xy 344.031924 -252.46025) (xy 344.04804 -252.508524) (xy 344.056204 -252.558758)
			(xy 344.056716 -252.584204) (xy 345.315298 -252.584204) (xy 345.319258 -252.53515) (xy 345.331035 -252.487366)
			(xy 345.350326 -252.44209) (xy 345.376629 -252.400494) (xy 345.409264 -252.363657) (xy 345.447385 -252.332532)
			(xy 345.490006 -252.307925) (xy 345.536022 -252.290473) (xy 345.584241 -252.280629) (xy 345.633416 -252.278648)
			(xy 345.682271 -252.28458) (xy 345.729542 -252.298272) (xy 345.774004 -252.31937) (xy 345.814507 -252.347326)
			(xy 345.85 -252.381418) (xy 345.879565 -252.420762) (xy 345.902436 -252.464339) (xy 345.91802 -252.51102)
			(xy 345.925915 -252.559597) (xy 345.92641 -252.584204) (xy 347.195406 -252.584204) (xy 347.199366 -252.53515)
			(xy 347.211143 -252.487366) (xy 347.230434 -252.44209) (xy 347.256737 -252.400494) (xy 347.289372 -252.363657)
			(xy 347.327493 -252.332532) (xy 347.370114 -252.307925) (xy 347.41613 -252.290473) (xy 347.464349 -252.280629)
			(xy 347.513524 -252.278648) (xy 347.562379 -252.28458) (xy 347.60965 -252.298272) (xy 347.654112 -252.31937)
			(xy 347.694615 -252.347326) (xy 347.730108 -252.381418) (xy 347.759673 -252.420762) (xy 347.782544 -252.464339)
			(xy 347.798128 -252.51102) (xy 347.806023 -252.559597) (xy 347.806518 -252.584204) (xy 349.07526 -252.584204)
			(xy 349.07922 -252.53515) (xy 349.090997 -252.487366) (xy 349.110288 -252.44209) (xy 349.136591 -252.400494)
			(xy 349.169226 -252.363657) (xy 349.207347 -252.332532) (xy 349.249968 -252.307925) (xy 349.295984 -252.290473)
			(xy 349.344203 -252.280629) (xy 349.393378 -252.278648) (xy 349.442233 -252.28458) (xy 349.489504 -252.298272)
			(xy 349.533966 -252.31937) (xy 349.574469 -252.347326) (xy 349.609962 -252.381418) (xy 349.639527 -252.420762)
			(xy 349.662398 -252.464339) (xy 349.677982 -252.51102) (xy 349.685877 -252.559597) (xy 349.686372 -252.584204)
			(xy 349.685877 -252.608811) (xy 349.677982 -252.657388) (xy 349.662398 -252.704069) (xy 349.639527 -252.747646)
			(xy 349.609962 -252.78699) (xy 349.574469 -252.821082) (xy 349.533966 -252.849038) (xy 349.489504 -252.870136)
			(xy 349.442233 -252.883828) (xy 349.393378 -252.88976) (xy 349.344203 -252.887779) (xy 349.295984 -252.877935)
			(xy 349.249968 -252.860483) (xy 349.207347 -252.835876) (xy 349.169226 -252.804751) (xy 349.136591 -252.767914)
			(xy 349.110288 -252.726318) (xy 349.090997 -252.681042) (xy 349.07922 -252.633258) (xy 349.07526 -252.584204)
			(xy 347.806518 -252.584204) (xy 347.806023 -252.608811) (xy 347.798128 -252.657388) (xy 347.782544 -252.704069)
			(xy 347.759673 -252.747646) (xy 347.730108 -252.78699) (xy 347.694615 -252.821082) (xy 347.654112 -252.849038)
			(xy 347.60965 -252.870136) (xy 347.562379 -252.883828) (xy 347.513524 -252.88976) (xy 347.464349 -252.887779)
			(xy 347.41613 -252.877935) (xy 347.370114 -252.860483) (xy 347.327493 -252.835876) (xy 347.289372 -252.804751)
			(xy 347.256737 -252.767914) (xy 347.230434 -252.726318) (xy 347.211143 -252.681042) (xy 347.199366 -252.633258)
			(xy 347.195406 -252.584204) (xy 345.92641 -252.584204) (xy 345.925915 -252.608811) (xy 345.91802 -252.657388)
			(xy 345.902436 -252.704069) (xy 345.879565 -252.747646) (xy 345.85 -252.78699) (xy 345.814507 -252.821082)
			(xy 345.774004 -252.849038) (xy 345.729542 -252.870136) (xy 345.682271 -252.883828) (xy 345.633416 -252.88976)
			(xy 345.584241 -252.887779) (xy 345.536022 -252.877935) (xy 345.490006 -252.860483) (xy 345.447385 -252.835876)
			(xy 345.409264 -252.804751) (xy 345.376629 -252.767914) (xy 345.350326 -252.726318) (xy 345.331035 -252.681042)
			(xy 345.319258 -252.633258) (xy 345.315298 -252.584204) (xy 344.056716 -252.584204) (xy 344.056204 -252.60965)
			(xy 344.04804 -252.659884) (xy 344.031924 -252.708158) (xy 344.008273 -252.753221) (xy 343.9777 -252.793907)
			(xy 343.940996 -252.829162) (xy 343.899112 -252.858072) (xy 343.853133 -252.879889) (xy 343.804249 -252.894049)
			(xy 343.753728 -252.900183) (xy 343.702876 -252.898134) (xy 343.653012 -252.887954) (xy 343.605426 -252.869907)
			(xy 343.561352 -252.844461) (xy 343.52193 -252.812274) (xy 343.488182 -252.77418) (xy 343.460981 -252.731166)
			(xy 343.441033 -252.684346) (xy 343.428854 -252.634932) (xy 343.424759 -252.584204) (xy 343.106502 -252.584204)
			(xy 343.106007 -252.608811) (xy 343.098112 -252.657388) (xy 343.082528 -252.704069) (xy 343.059657 -252.747646)
			(xy 343.030092 -252.78699) (xy 342.994599 -252.821082) (xy 342.954096 -252.849038) (xy 342.909634 -252.870136)
			(xy 342.862363 -252.883828) (xy 342.813508 -252.88976) (xy 342.764333 -252.887779) (xy 342.716114 -252.877935)
			(xy 342.670098 -252.860483) (xy 342.627477 -252.835876) (xy 342.589356 -252.804751) (xy 342.556721 -252.767914)
			(xy 342.530418 -252.726318) (xy 342.511127 -252.681042) (xy 342.49935 -252.633258) (xy 342.49539 -252.584204)
			(xy 342.176862 -252.584204) (xy 342.17635 -252.60965) (xy 342.168186 -252.659884) (xy 342.15207 -252.708158)
			(xy 342.128419 -252.753221) (xy 342.097846 -252.793907) (xy 342.061142 -252.829162) (xy 342.019258 -252.858072)
			(xy 341.973279 -252.879889) (xy 341.924395 -252.894049) (xy 341.873874 -252.900183) (xy 341.823022 -252.898134)
			(xy 341.773158 -252.887954) (xy 341.725572 -252.869907) (xy 341.681498 -252.844461) (xy 341.642076 -252.812274)
			(xy 341.608328 -252.77418) (xy 341.581127 -252.731166) (xy 341.561179 -252.684346) (xy 341.549 -252.634932)
			(xy 341.544905 -252.584204) (xy 341.226394 -252.584204) (xy 341.225899 -252.608811) (xy 341.218004 -252.657388)
			(xy 341.20242 -252.704069) (xy 341.179549 -252.747646) (xy 341.149984 -252.78699) (xy 341.114491 -252.821082)
			(xy 341.073988 -252.849038) (xy 341.029526 -252.870136) (xy 340.982255 -252.883828) (xy 340.9334 -252.88976)
			(xy 340.884225 -252.887779) (xy 340.836006 -252.877935) (xy 340.78999 -252.860483) (xy 340.747369 -252.835876)
			(xy 340.709248 -252.804751) (xy 340.676613 -252.767914) (xy 340.65031 -252.726318) (xy 340.631019 -252.681042)
			(xy 340.619242 -252.633258) (xy 340.615282 -252.584204) (xy 340.296754 -252.584204) (xy 340.296242 -252.60965)
			(xy 340.288078 -252.659884) (xy 340.271962 -252.708158) (xy 340.248311 -252.753221) (xy 340.217738 -252.793907)
			(xy 340.181034 -252.829162) (xy 340.13915 -252.858072) (xy 340.093171 -252.879889) (xy 340.044287 -252.894049)
			(xy 339.993766 -252.900183) (xy 339.942914 -252.898134) (xy 339.89305 -252.887954) (xy 339.845464 -252.869907)
			(xy 339.80139 -252.844461) (xy 339.761968 -252.812274) (xy 339.72822 -252.77418) (xy 339.701019 -252.731166)
			(xy 339.681071 -252.684346) (xy 339.668892 -252.634932) (xy 339.664797 -252.584204) (xy 339.3567 -252.584204)
			(xy 339.356188 -252.60965) (xy 339.348024 -252.659884) (xy 339.331908 -252.708158) (xy 339.308257 -252.753221)
			(xy 339.277684 -252.793907) (xy 339.24098 -252.829162) (xy 339.199096 -252.858072) (xy 339.153117 -252.879889)
			(xy 339.104233 -252.894049) (xy 339.053712 -252.900183) (xy 339.00286 -252.898134) (xy 338.952996 -252.887954)
			(xy 338.90541 -252.869907) (xy 338.861336 -252.844461) (xy 338.821914 -252.812274) (xy 338.788166 -252.77418)
			(xy 338.760965 -252.731166) (xy 338.741017 -252.684346) (xy 338.728838 -252.634932) (xy 338.724743 -252.584204)
			(xy 338.406486 -252.584204) (xy 338.405991 -252.608811) (xy 338.398096 -252.657388) (xy 338.382512 -252.704069)
			(xy 338.359641 -252.747646) (xy 338.330076 -252.78699) (xy 338.294583 -252.821082) (xy 338.25408 -252.849038)
			(xy 338.209618 -252.870136) (xy 338.162347 -252.883828) (xy 338.113492 -252.88976) (xy 338.064317 -252.887779)
			(xy 338.016098 -252.877935) (xy 337.970082 -252.860483) (xy 337.927461 -252.835876) (xy 337.88934 -252.804751)
			(xy 337.856705 -252.767914) (xy 337.830402 -252.726318) (xy 337.811111 -252.681042) (xy 337.799334 -252.633258)
			(xy 337.795374 -252.584204) (xy 337.466432 -252.584204) (xy 337.465937 -252.608811) (xy 337.458042 -252.657388)
			(xy 337.442458 -252.704069) (xy 337.419587 -252.747646) (xy 337.390022 -252.78699) (xy 337.354529 -252.821082)
			(xy 337.314026 -252.849038) (xy 337.269564 -252.870136) (xy 337.222293 -252.883828) (xy 337.173438 -252.88976)
			(xy 337.124263 -252.887779) (xy 337.076044 -252.877935) (xy 337.030028 -252.860483) (xy 336.987407 -252.835876)
			(xy 336.949286 -252.804751) (xy 336.916651 -252.767914) (xy 336.890348 -252.726318) (xy 336.871057 -252.681042)
			(xy 336.85928 -252.633258) (xy 336.85532 -252.584204) (xy 336.526378 -252.584204) (xy 336.525883 -252.608811)
			(xy 336.517988 -252.657388) (xy 336.502404 -252.704069) (xy 336.479533 -252.747646) (xy 336.449968 -252.78699)
			(xy 336.414475 -252.821082) (xy 336.373972 -252.849038) (xy 336.32951 -252.870136) (xy 336.282239 -252.883828)
			(xy 336.233384 -252.88976) (xy 336.184209 -252.887779) (xy 336.13599 -252.877935) (xy 336.089974 -252.860483)
			(xy 336.047353 -252.835876) (xy 336.009232 -252.804751) (xy 335.976597 -252.767914) (xy 335.950294 -252.726318)
			(xy 335.931003 -252.681042) (xy 335.919226 -252.633258) (xy 335.915266 -252.584204) (xy 335.586324 -252.584204)
			(xy 335.585829 -252.608811) (xy 335.577934 -252.657388) (xy 335.56235 -252.704069) (xy 335.539479 -252.747646)
			(xy 335.509914 -252.78699) (xy 335.474421 -252.821082) (xy 335.433918 -252.849038) (xy 335.389456 -252.870136)
			(xy 335.342185 -252.883828) (xy 335.29333 -252.88976) (xy 335.244155 -252.887779) (xy 335.195936 -252.877935)
			(xy 335.14992 -252.860483) (xy 335.107299 -252.835876) (xy 335.069178 -252.804751) (xy 335.036543 -252.767914)
			(xy 335.01024 -252.726318) (xy 334.990949 -252.681042) (xy 334.979172 -252.633258) (xy 334.975212 -252.584204)
			(xy 334.646524 -252.584204) (xy 334.646053 -252.608195) (xy 334.638547 -252.655588) (xy 334.623719 -252.701222)
			(xy 334.601936 -252.743975) (xy 334.573732 -252.782795) (xy 334.539804 -252.816725) (xy 334.500986 -252.844929)
			(xy 334.458233 -252.866714) (xy 334.412599 -252.881544) (xy 334.365207 -252.889052) (xy 334.341216 -252.889512)
			(xy 334.309466 -252.887734) (xy 334.306672 -252.88748) (xy 334.304132 -252.88748) (xy 334.294105 -252.887894)
			(xy 334.275574 -252.895557) (xy 334.261387 -252.90973) (xy 334.253704 -252.928253) (xy 334.253332 -252.93828)
			(xy 334.253332 -252.9586) (xy 334.254094 -252.96749) (xy 334.255364 -252.974348) (xy 334.256969 -252.981959)
			(xy 334.264089 -252.995781) (xy 334.269334 -253.001526) (xy 334.269588 -253.00178) (xy 334.274922 -253.007368)
			(xy 334.298192 -253.032397) (xy 334.339095 -253.087147) (xy 334.373002 -253.146485) (xy 334.386682 -253.177802)
			(xy 334.389222 -253.183898) (xy 334.396842 -253.194058) (xy 334.421226 -253.213108) (xy 334.426702 -253.217064)
			(xy 334.439191 -253.222205) (xy 334.445864 -253.223268) (xy 334.516984 -253.23292) (xy 334.522959 -253.233538)
			(xy 334.5349 -253.232258) (xy 334.540606 -253.23038) (xy 334.551782 -253.22657) (xy 334.56499 -253.213362)
			(xy 334.567022 -253.210568) (xy 334.581567 -253.192015) (xy 334.615397 -253.159185) (xy 334.653862 -253.131931)
			(xy 334.696051 -253.110898) (xy 334.740966 -253.096583) (xy 334.787546 -253.089326) (xy 334.811116 -253.088902)
			(xy 334.83637 -253.089425) (xy 334.886188 -253.09774) (xy 334.933958 -253.114142) (xy 334.978377 -253.138182)
			(xy 335.018233 -253.169206) (xy 335.05244 -253.206366) (xy 335.080064 -253.24865) (xy 335.100352 -253.294903)
			(xy 335.11275 -253.343865) (xy 335.116921 -253.3942) (xy 335.11692 -253.39421) (xy 335.445366 -253.39421)
			(xy 335.449326 -253.345156) (xy 335.461103 -253.297372) (xy 335.480394 -253.252096) (xy 335.506697 -253.2105)
			(xy 335.539332 -253.173663) (xy 335.577453 -253.142538) (xy 335.620074 -253.117931) (xy 335.66609 -253.100479)
			(xy 335.714309 -253.090635) (xy 335.763484 -253.088654) (xy 335.812339 -253.094586) (xy 335.85961 -253.108278)
			(xy 335.904072 -253.129376) (xy 335.944575 -253.157332) (xy 335.980068 -253.191424) (xy 336.009633 -253.230768)
			(xy 336.032504 -253.274345) (xy 336.048088 -253.321026) (xy 336.055983 -253.369603) (xy 336.056478 -253.39421)
			(xy 336.38542 -253.39421) (xy 336.38938 -253.345156) (xy 336.401157 -253.297372) (xy 336.420448 -253.252096)
			(xy 336.446751 -253.2105) (xy 336.479386 -253.173663) (xy 336.517507 -253.142538) (xy 336.560128 -253.117931)
			(xy 336.606144 -253.100479) (xy 336.654363 -253.090635) (xy 336.703538 -253.088654) (xy 336.752393 -253.094586)
			(xy 336.799664 -253.108278) (xy 336.844126 -253.129376) (xy 336.884629 -253.157332) (xy 336.920122 -253.191424)
			(xy 336.949687 -253.230768) (xy 336.972558 -253.274345) (xy 336.988142 -253.321026) (xy 336.996037 -253.369603)
			(xy 336.996532 -253.39421) (xy 337.32522 -253.39421) (xy 337.32918 -253.345156) (xy 337.340957 -253.297372)
			(xy 337.360248 -253.252096) (xy 337.386551 -253.2105) (xy 337.419186 -253.173663) (xy 337.457307 -253.142538)
			(xy 337.499928 -253.117931) (xy 337.545944 -253.100479) (xy 337.594163 -253.090635) (xy 337.643338 -253.088654)
			(xy 337.692193 -253.094586) (xy 337.739464 -253.108278) (xy 337.783926 -253.129376) (xy 337.824429 -253.157332)
			(xy 337.859922 -253.191424) (xy 337.889487 -253.230768) (xy 337.912358 -253.274345) (xy 337.927942 -253.321026)
			(xy 337.935837 -253.369603) (xy 337.936332 -253.39421) (xy 338.254843 -253.39421) (xy 338.258938 -253.343482)
			(xy 338.271117 -253.294068) (xy 338.291065 -253.247248) (xy 338.318266 -253.204234) (xy 338.352014 -253.16614)
			(xy 338.391436 -253.133953) (xy 338.43551 -253.108507) (xy 338.483096 -253.09046) (xy 338.53296 -253.08028)
			(xy 338.583812 -253.078231) (xy 338.634333 -253.084365) (xy 338.683217 -253.098525) (xy 338.729196 -253.120342)
			(xy 338.77108 -253.149252) (xy 338.807784 -253.184507) (xy 338.838357 -253.225193) (xy 338.862008 -253.270256)
			(xy 338.878124 -253.31853) (xy 338.886288 -253.368764) (xy 338.8868 -253.39421) (xy 339.205328 -253.39421)
			(xy 339.209288 -253.345156) (xy 339.221065 -253.297372) (xy 339.240356 -253.252096) (xy 339.266659 -253.2105)
			(xy 339.299294 -253.173663) (xy 339.337415 -253.142538) (xy 339.380036 -253.117931) (xy 339.426052 -253.100479)
			(xy 339.474271 -253.090635) (xy 339.523446 -253.088654) (xy 339.572301 -253.094586) (xy 339.619572 -253.108278)
			(xy 339.664034 -253.129376) (xy 339.704537 -253.157332) (xy 339.74003 -253.191424) (xy 339.769595 -253.230768)
			(xy 339.792466 -253.274345) (xy 339.80805 -253.321026) (xy 339.815945 -253.369603) (xy 339.81644 -253.39421)
			(xy 340.134951 -253.39421) (xy 340.139046 -253.343482) (xy 340.151225 -253.294068) (xy 340.171173 -253.247248)
			(xy 340.198374 -253.204234) (xy 340.232122 -253.16614) (xy 340.271544 -253.133953) (xy 340.315618 -253.108507)
			(xy 340.363204 -253.09046) (xy 340.413068 -253.08028) (xy 340.46392 -253.078231) (xy 340.514441 -253.084365)
			(xy 340.563325 -253.098525) (xy 340.609304 -253.120342) (xy 340.651188 -253.149252) (xy 340.687892 -253.184507)
			(xy 340.718465 -253.225193) (xy 340.742116 -253.270256) (xy 340.758232 -253.31853) (xy 340.766396 -253.368764)
			(xy 340.766908 -253.39421) (xy 341.085182 -253.39421) (xy 341.089142 -253.345156) (xy 341.100919 -253.297372)
			(xy 341.12021 -253.252096) (xy 341.146513 -253.2105) (xy 341.179148 -253.173663) (xy 341.217269 -253.142538)
			(xy 341.25989 -253.117931) (xy 341.305906 -253.100479) (xy 341.354125 -253.090635) (xy 341.4033 -253.088654)
			(xy 341.452155 -253.094586) (xy 341.499426 -253.108278) (xy 341.543888 -253.129376) (xy 341.584391 -253.157332)
			(xy 341.619884 -253.191424) (xy 341.649449 -253.230768) (xy 341.67232 -253.274345) (xy 341.687904 -253.321026)
			(xy 341.695799 -253.369603) (xy 341.696294 -253.39421) (xy 342.014805 -253.39421) (xy 342.0189 -253.343482)
			(xy 342.031079 -253.294068) (xy 342.051027 -253.247248) (xy 342.078228 -253.204234) (xy 342.111976 -253.16614)
			(xy 342.151398 -253.133953) (xy 342.195472 -253.108507) (xy 342.243058 -253.09046) (xy 342.292922 -253.08028)
			(xy 342.343774 -253.078231) (xy 342.394295 -253.084365) (xy 342.443179 -253.098525) (xy 342.489158 -253.120342)
			(xy 342.531042 -253.149252) (xy 342.567746 -253.184507) (xy 342.598319 -253.225193) (xy 342.62197 -253.270256)
			(xy 342.638086 -253.31853) (xy 342.64625 -253.368764) (xy 342.646762 -253.39421) (xy 342.954859 -253.39421)
			(xy 342.958954 -253.343482) (xy 342.971133 -253.294068) (xy 342.991081 -253.247248) (xy 343.018282 -253.204234)
			(xy 343.05203 -253.16614) (xy 343.091452 -253.133953) (xy 343.135526 -253.108507) (xy 343.183112 -253.09046)
			(xy 343.232976 -253.08028) (xy 343.283828 -253.078231) (xy 343.334349 -253.084365) (xy 343.383233 -253.098525)
			(xy 343.429212 -253.120342) (xy 343.471096 -253.149252) (xy 343.5078 -253.184507) (xy 343.538373 -253.225193)
			(xy 343.562024 -253.270256) (xy 343.57814 -253.31853) (xy 343.586304 -253.368764) (xy 343.586816 -253.39421)
			(xy 343.905344 -253.39421) (xy 343.909304 -253.345156) (xy 343.921081 -253.297372) (xy 343.940372 -253.252096)
			(xy 343.966675 -253.2105) (xy 343.99931 -253.173663) (xy 344.037431 -253.142538) (xy 344.080052 -253.117931)
			(xy 344.126068 -253.100479) (xy 344.174287 -253.090635) (xy 344.223462 -253.088654) (xy 344.272317 -253.094586)
			(xy 344.319588 -253.108278) (xy 344.36405 -253.129376) (xy 344.404553 -253.157332) (xy 344.440046 -253.191424)
			(xy 344.469611 -253.230768) (xy 344.492482 -253.274345) (xy 344.508066 -253.321026) (xy 344.515961 -253.369603)
			(xy 344.516456 -253.39421) (xy 345.785198 -253.39421) (xy 345.789158 -253.345156) (xy 345.800935 -253.297372)
			(xy 345.820226 -253.252096) (xy 345.846529 -253.2105) (xy 345.879164 -253.173663) (xy 345.917285 -253.142538)
			(xy 345.959906 -253.117931) (xy 346.005922 -253.100479) (xy 346.054141 -253.090635) (xy 346.103316 -253.088654)
			(xy 346.152171 -253.094586) (xy 346.199442 -253.108278) (xy 346.243904 -253.129376) (xy 346.284407 -253.157332)
			(xy 346.3199 -253.191424) (xy 346.349465 -253.230768) (xy 346.372336 -253.274345) (xy 346.38792 -253.321026)
			(xy 346.395815 -253.369603) (xy 346.39631 -253.39421) (xy 347.665306 -253.39421) (xy 347.669266 -253.345156)
			(xy 347.681043 -253.297372) (xy 347.700334 -253.252096) (xy 347.726637 -253.2105) (xy 347.759272 -253.173663)
			(xy 347.797393 -253.142538) (xy 347.840014 -253.117931) (xy 347.88603 -253.100479) (xy 347.934249 -253.090635)
			(xy 347.983424 -253.088654) (xy 348.032279 -253.094586) (xy 348.07955 -253.108278) (xy 348.124012 -253.129376)
			(xy 348.164515 -253.157332) (xy 348.200008 -253.191424) (xy 348.229573 -253.230768) (xy 348.252444 -253.274345)
			(xy 348.268028 -253.321026) (xy 348.275923 -253.369603) (xy 348.276418 -253.39421) (xy 348.60536 -253.39421)
			(xy 348.60932 -253.345156) (xy 348.621097 -253.297372) (xy 348.640388 -253.252096) (xy 348.666691 -253.2105)
			(xy 348.699326 -253.173663) (xy 348.737447 -253.142538) (xy 348.780068 -253.117931) (xy 348.826084 -253.100479)
			(xy 348.874303 -253.090635) (xy 348.923478 -253.088654) (xy 348.972333 -253.094586) (xy 349.019604 -253.108278)
			(xy 349.064066 -253.129376) (xy 349.104569 -253.157332) (xy 349.140062 -253.191424) (xy 349.169627 -253.230768)
			(xy 349.192498 -253.274345) (xy 349.208082 -253.321026) (xy 349.215977 -253.369603) (xy 349.216472 -253.39421)
			(xy 349.545414 -253.39421) (xy 349.549374 -253.345156) (xy 349.561151 -253.297372) (xy 349.580442 -253.252096)
			(xy 349.606745 -253.2105) (xy 349.63938 -253.173663) (xy 349.677501 -253.142538) (xy 349.720122 -253.117931)
			(xy 349.766138 -253.100479) (xy 349.814357 -253.090635) (xy 349.863532 -253.088654) (xy 349.912387 -253.094586)
			(xy 349.959658 -253.108278) (xy 350.00412 -253.129376) (xy 350.044623 -253.157332) (xy 350.080116 -253.191424)
			(xy 350.109681 -253.230768) (xy 350.132552 -253.274345) (xy 350.148136 -253.321026) (xy 350.156031 -253.369603)
			(xy 350.156526 -253.39421) (xy 350.156031 -253.418817) (xy 350.148136 -253.467394) (xy 350.132552 -253.514075)
			(xy 350.109681 -253.557652) (xy 350.080116 -253.596996) (xy 350.044623 -253.631088) (xy 350.00412 -253.659044)
			(xy 349.959658 -253.680142) (xy 349.912387 -253.693834) (xy 349.863532 -253.699766) (xy 349.814357 -253.697785)
			(xy 349.766138 -253.687941) (xy 349.720122 -253.670489) (xy 349.677501 -253.645882) (xy 349.63938 -253.614757)
			(xy 349.606745 -253.57792) (xy 349.580442 -253.536324) (xy 349.561151 -253.491048) (xy 349.549374 -253.443264)
			(xy 349.545414 -253.39421) (xy 349.216472 -253.39421) (xy 349.215977 -253.418817) (xy 349.208082 -253.467394)
			(xy 349.192498 -253.514075) (xy 349.169627 -253.557652) (xy 349.140062 -253.596996) (xy 349.104569 -253.631088)
			(xy 349.064066 -253.659044) (xy 349.019604 -253.680142) (xy 348.972333 -253.693834) (xy 348.923478 -253.699766)
			(xy 348.874303 -253.697785) (xy 348.826084 -253.687941) (xy 348.780068 -253.670489) (xy 348.737447 -253.645882)
			(xy 348.699326 -253.614757) (xy 348.666691 -253.57792) (xy 348.640388 -253.536324) (xy 348.621097 -253.491048)
			(xy 348.60932 -253.443264) (xy 348.60536 -253.39421) (xy 348.276418 -253.39421) (xy 348.275923 -253.418817)
			(xy 348.268028 -253.467394) (xy 348.252444 -253.514075) (xy 348.229573 -253.557652) (xy 348.200008 -253.596996)
			(xy 348.164515 -253.631088) (xy 348.124012 -253.659044) (xy 348.07955 -253.680142) (xy 348.032279 -253.693834)
			(xy 347.983424 -253.699766) (xy 347.934249 -253.697785) (xy 347.88603 -253.687941) (xy 347.840014 -253.670489)
			(xy 347.797393 -253.645882) (xy 347.759272 -253.614757) (xy 347.726637 -253.57792) (xy 347.700334 -253.536324)
			(xy 347.681043 -253.491048) (xy 347.669266 -253.443264) (xy 347.665306 -253.39421) (xy 346.39631 -253.39421)
			(xy 346.395815 -253.418817) (xy 346.38792 -253.467394) (xy 346.372336 -253.514075) (xy 346.349465 -253.557652)
			(xy 346.3199 -253.596996) (xy 346.284407 -253.631088) (xy 346.243904 -253.659044) (xy 346.199442 -253.680142)
			(xy 346.152171 -253.693834) (xy 346.103316 -253.699766) (xy 346.054141 -253.697785) (xy 346.005922 -253.687941)
			(xy 345.959906 -253.670489) (xy 345.917285 -253.645882) (xy 345.879164 -253.614757) (xy 345.846529 -253.57792)
			(xy 345.820226 -253.536324) (xy 345.800935 -253.491048) (xy 345.789158 -253.443264) (xy 345.785198 -253.39421)
			(xy 344.516456 -253.39421) (xy 344.515961 -253.418817) (xy 344.508066 -253.467394) (xy 344.492482 -253.514075)
			(xy 344.469611 -253.557652) (xy 344.440046 -253.596996) (xy 344.404553 -253.631088) (xy 344.36405 -253.659044)
			(xy 344.319588 -253.680142) (xy 344.272317 -253.693834) (xy 344.223462 -253.699766) (xy 344.174287 -253.697785)
			(xy 344.126068 -253.687941) (xy 344.080052 -253.670489) (xy 344.037431 -253.645882) (xy 343.99931 -253.614757)
			(xy 343.966675 -253.57792) (xy 343.940372 -253.536324) (xy 343.921081 -253.491048) (xy 343.909304 -253.443264)
			(xy 343.905344 -253.39421) (xy 343.586816 -253.39421) (xy 343.586304 -253.419656) (xy 343.57814 -253.46989)
			(xy 343.562024 -253.518164) (xy 343.538373 -253.563227) (xy 343.5078 -253.603913) (xy 343.471096 -253.639168)
			(xy 343.429212 -253.668078) (xy 343.383233 -253.689895) (xy 343.334349 -253.704055) (xy 343.283828 -253.710189)
			(xy 343.232976 -253.70814) (xy 343.183112 -253.69796) (xy 343.135526 -253.679913) (xy 343.091452 -253.654467)
			(xy 343.05203 -253.62228) (xy 343.018282 -253.584186) (xy 342.991081 -253.541172) (xy 342.971133 -253.494352)
			(xy 342.958954 -253.444938) (xy 342.954859 -253.39421) (xy 342.646762 -253.39421) (xy 342.64625 -253.419656)
			(xy 342.638086 -253.46989) (xy 342.62197 -253.518164) (xy 342.598319 -253.563227) (xy 342.567746 -253.603913)
			(xy 342.531042 -253.639168) (xy 342.489158 -253.668078) (xy 342.443179 -253.689895) (xy 342.394295 -253.704055)
			(xy 342.343774 -253.710189) (xy 342.292922 -253.70814) (xy 342.243058 -253.69796) (xy 342.195472 -253.679913)
			(xy 342.151398 -253.654467) (xy 342.111976 -253.62228) (xy 342.078228 -253.584186) (xy 342.051027 -253.541172)
			(xy 342.031079 -253.494352) (xy 342.0189 -253.444938) (xy 342.014805 -253.39421) (xy 341.696294 -253.39421)
			(xy 341.695799 -253.418817) (xy 341.687904 -253.467394) (xy 341.67232 -253.514075) (xy 341.649449 -253.557652)
			(xy 341.619884 -253.596996) (xy 341.584391 -253.631088) (xy 341.543888 -253.659044) (xy 341.499426 -253.680142)
			(xy 341.452155 -253.693834) (xy 341.4033 -253.699766) (xy 341.354125 -253.697785) (xy 341.305906 -253.687941)
			(xy 341.25989 -253.670489) (xy 341.217269 -253.645882) (xy 341.179148 -253.614757) (xy 341.146513 -253.57792)
			(xy 341.12021 -253.536324) (xy 341.100919 -253.491048) (xy 341.089142 -253.443264) (xy 341.085182 -253.39421)
			(xy 340.766908 -253.39421) (xy 340.766396 -253.419656) (xy 340.758232 -253.46989) (xy 340.742116 -253.518164)
			(xy 340.718465 -253.563227) (xy 340.687892 -253.603913) (xy 340.651188 -253.639168) (xy 340.609304 -253.668078)
			(xy 340.563325 -253.689895) (xy 340.514441 -253.704055) (xy 340.46392 -253.710189) (xy 340.413068 -253.70814)
			(xy 340.363204 -253.69796) (xy 340.315618 -253.679913) (xy 340.271544 -253.654467) (xy 340.232122 -253.62228)
			(xy 340.198374 -253.584186) (xy 340.171173 -253.541172) (xy 340.151225 -253.494352) (xy 340.139046 -253.444938)
			(xy 340.134951 -253.39421) (xy 339.81644 -253.39421) (xy 339.815945 -253.418817) (xy 339.80805 -253.467394)
			(xy 339.792466 -253.514075) (xy 339.769595 -253.557652) (xy 339.74003 -253.596996) (xy 339.704537 -253.631088)
			(xy 339.664034 -253.659044) (xy 339.619572 -253.680142) (xy 339.572301 -253.693834) (xy 339.523446 -253.699766)
			(xy 339.474271 -253.697785) (xy 339.426052 -253.687941) (xy 339.380036 -253.670489) (xy 339.337415 -253.645882)
			(xy 339.299294 -253.614757) (xy 339.266659 -253.57792) (xy 339.240356 -253.536324) (xy 339.221065 -253.491048)
			(xy 339.209288 -253.443264) (xy 339.205328 -253.39421) (xy 338.8868 -253.39421) (xy 338.886288 -253.419656)
			(xy 338.878124 -253.46989) (xy 338.862008 -253.518164) (xy 338.838357 -253.563227) (xy 338.807784 -253.603913)
			(xy 338.77108 -253.639168) (xy 338.729196 -253.668078) (xy 338.683217 -253.689895) (xy 338.634333 -253.704055)
			(xy 338.583812 -253.710189) (xy 338.53296 -253.70814) (xy 338.483096 -253.69796) (xy 338.43551 -253.679913)
			(xy 338.391436 -253.654467) (xy 338.352014 -253.62228) (xy 338.318266 -253.584186) (xy 338.291065 -253.541172)
			(xy 338.271117 -253.494352) (xy 338.258938 -253.444938) (xy 338.254843 -253.39421) (xy 337.936332 -253.39421)
			(xy 337.935837 -253.418817) (xy 337.927942 -253.467394) (xy 337.912358 -253.514075) (xy 337.889487 -253.557652)
			(xy 337.859922 -253.596996) (xy 337.824429 -253.631088) (xy 337.783926 -253.659044) (xy 337.739464 -253.680142)
			(xy 337.692193 -253.693834) (xy 337.643338 -253.699766) (xy 337.594163 -253.697785) (xy 337.545944 -253.687941)
			(xy 337.499928 -253.670489) (xy 337.457307 -253.645882) (xy 337.419186 -253.614757) (xy 337.386551 -253.57792)
			(xy 337.360248 -253.536324) (xy 337.340957 -253.491048) (xy 337.32918 -253.443264) (xy 337.32522 -253.39421)
			(xy 336.996532 -253.39421) (xy 336.996037 -253.418817) (xy 336.988142 -253.467394) (xy 336.972558 -253.514075)
			(xy 336.949687 -253.557652) (xy 336.920122 -253.596996) (xy 336.884629 -253.631088) (xy 336.844126 -253.659044)
			(xy 336.799664 -253.680142) (xy 336.752393 -253.693834) (xy 336.703538 -253.699766) (xy 336.654363 -253.697785)
			(xy 336.606144 -253.687941) (xy 336.560128 -253.670489) (xy 336.517507 -253.645882) (xy 336.479386 -253.614757)
			(xy 336.446751 -253.57792) (xy 336.420448 -253.536324) (xy 336.401157 -253.491048) (xy 336.38938 -253.443264)
			(xy 336.38542 -253.39421) (xy 336.056478 -253.39421) (xy 336.055983 -253.418817) (xy 336.048088 -253.467394)
			(xy 336.032504 -253.514075) (xy 336.009633 -253.557652) (xy 335.980068 -253.596996) (xy 335.944575 -253.631088)
			(xy 335.904072 -253.659044) (xy 335.85961 -253.680142) (xy 335.812339 -253.693834) (xy 335.763484 -253.699766)
			(xy 335.714309 -253.697785) (xy 335.66609 -253.687941) (xy 335.620074 -253.670489) (xy 335.577453 -253.645882)
			(xy 335.539332 -253.614757) (xy 335.506697 -253.57792) (xy 335.480394 -253.536324) (xy 335.461103 -253.491048)
			(xy 335.449326 -253.443264) (xy 335.445366 -253.39421) (xy 335.11692 -253.39421) (xy 335.11275 -253.444535)
			(xy 335.100352 -253.493497) (xy 335.080064 -253.53975) (xy 335.05244 -253.582034) (xy 335.018233 -253.619194)
			(xy 334.978377 -253.650218) (xy 334.933958 -253.674258) (xy 334.886188 -253.69066) (xy 334.83637 -253.698975)
			(xy 334.811116 -253.699518) (xy 334.787545 -253.699083) (xy 334.740961 -253.691846) (xy 334.696041 -253.677542)
			(xy 334.65385 -253.656509) (xy 334.615389 -253.629248) (xy 334.581571 -253.596403) (xy 334.567022 -253.577852)
			(xy 334.56499 -253.575058) (xy 334.55991 -253.569978) (xy 334.553347 -253.563852) (xy 334.537076 -253.556295)
			(xy 334.52816 -253.555246) (xy 334.522572 -253.554738) (xy 334.432148 -253.56693) (xy 334.42323 -253.568475)
			(xy 334.407238 -253.576925) (xy 334.395177 -253.590405) (xy 334.391508 -253.59868) (xy 334.383585 -253.618386)
			(xy 334.365148 -253.656654) (xy 334.354678 -253.675134) (xy 334.312768 -253.74727) (xy 334.311498 -253.749048)
			(xy 334.303878 -253.760478) (xy 334.3021 -253.787656) (xy 334.338676 -253.862078) (xy 334.341548 -253.867414)
			(xy 334.349373 -253.876664) (xy 334.35417 -253.880366) (xy 334.382618 -253.901448) (xy 334.394302 -253.90348)
			(xy 334.417563 -253.908036) (xy 334.462407 -253.923381) (xy 334.50434 -253.945473) (xy 334.542355 -253.973781)
			(xy 334.575537 -254.007624) (xy 334.60309 -254.046189) (xy 334.624351 -254.08855) (xy 334.63881 -254.133687)
			(xy 334.646118 -254.180517) (xy 334.646524 -254.204216) (xy 334.975212 -254.204216) (xy 334.979172 -254.155162)
			(xy 334.990949 -254.107378) (xy 335.01024 -254.062102) (xy 335.036543 -254.020506) (xy 335.069178 -253.983669)
			(xy 335.107299 -253.952544) (xy 335.14992 -253.927937) (xy 335.195936 -253.910485) (xy 335.244155 -253.900641)
			(xy 335.29333 -253.89866) (xy 335.342185 -253.904592) (xy 335.389456 -253.918284) (xy 335.433918 -253.939382)
			(xy 335.474421 -253.967338) (xy 335.509914 -254.00143) (xy 335.539479 -254.040774) (xy 335.56235 -254.084351)
			(xy 335.577934 -254.131032) (xy 335.585829 -254.179609) (xy 335.586324 -254.204216) (xy 335.915266 -254.204216)
			(xy 335.919226 -254.155162) (xy 335.931003 -254.107378) (xy 335.950294 -254.062102) (xy 335.976597 -254.020506)
			(xy 336.009232 -253.983669) (xy 336.047353 -253.952544) (xy 336.089974 -253.927937) (xy 336.13599 -253.910485)
			(xy 336.184209 -253.900641) (xy 336.233384 -253.89866) (xy 336.282239 -253.904592) (xy 336.32951 -253.918284)
			(xy 336.373972 -253.939382) (xy 336.414475 -253.967338) (xy 336.449968 -254.00143) (xy 336.479533 -254.040774)
			(xy 336.502404 -254.084351) (xy 336.517988 -254.131032) (xy 336.525883 -254.179609) (xy 336.526378 -254.204216)
			(xy 336.85532 -254.204216) (xy 336.85928 -254.155162) (xy 336.871057 -254.107378) (xy 336.890348 -254.062102)
			(xy 336.916651 -254.020506) (xy 336.949286 -253.983669) (xy 336.987407 -253.952544) (xy 337.030028 -253.927937)
			(xy 337.076044 -253.910485) (xy 337.124263 -253.900641) (xy 337.173438 -253.89866) (xy 337.222293 -253.904592)
			(xy 337.269564 -253.918284) (xy 337.314026 -253.939382) (xy 337.354529 -253.967338) (xy 337.390022 -254.00143)
			(xy 337.419587 -254.040774) (xy 337.442458 -254.084351) (xy 337.458042 -254.131032) (xy 337.465937 -254.179609)
			(xy 337.466432 -254.204216) (xy 337.795374 -254.204216) (xy 337.799334 -254.155162) (xy 337.811111 -254.107378)
			(xy 337.830402 -254.062102) (xy 337.856705 -254.020506) (xy 337.88934 -253.983669) (xy 337.927461 -253.952544)
			(xy 337.970082 -253.927937) (xy 338.016098 -253.910485) (xy 338.064317 -253.900641) (xy 338.113492 -253.89866)
			(xy 338.162347 -253.904592) (xy 338.209618 -253.918284) (xy 338.25408 -253.939382) (xy 338.294583 -253.967338)
			(xy 338.330076 -254.00143) (xy 338.359641 -254.040774) (xy 338.382512 -254.084351) (xy 338.398096 -254.131032)
			(xy 338.405991 -254.179609) (xy 338.406486 -254.204216) (xy 338.724743 -254.204216) (xy 338.728838 -254.153488)
			(xy 338.741017 -254.104074) (xy 338.760965 -254.057254) (xy 338.788166 -254.01424) (xy 338.821914 -253.976146)
			(xy 338.861336 -253.943959) (xy 338.90541 -253.918513) (xy 338.952996 -253.900466) (xy 339.00286 -253.890286)
			(xy 339.053712 -253.888237) (xy 339.104233 -253.894371) (xy 339.153117 -253.908531) (xy 339.199096 -253.930348)
			(xy 339.24098 -253.959258) (xy 339.277684 -253.994513) (xy 339.308257 -254.035199) (xy 339.331908 -254.080262)
			(xy 339.348024 -254.128536) (xy 339.356188 -254.17877) (xy 339.3567 -254.204216) (xy 339.664797 -254.204216)
			(xy 339.668892 -254.153488) (xy 339.681071 -254.104074) (xy 339.701019 -254.057254) (xy 339.72822 -254.01424)
			(xy 339.761968 -253.976146) (xy 339.80139 -253.943959) (xy 339.845464 -253.918513) (xy 339.89305 -253.900466)
			(xy 339.942914 -253.890286) (xy 339.993766 -253.888237) (xy 340.044287 -253.894371) (xy 340.093171 -253.908531)
			(xy 340.13915 -253.930348) (xy 340.181034 -253.959258) (xy 340.217738 -253.994513) (xy 340.248311 -254.035199)
			(xy 340.271962 -254.080262) (xy 340.288078 -254.128536) (xy 340.296242 -254.17877) (xy 340.296754 -254.204216)
			(xy 340.615282 -254.204216) (xy 340.619242 -254.155162) (xy 340.631019 -254.107378) (xy 340.65031 -254.062102)
			(xy 340.676613 -254.020506) (xy 340.709248 -253.983669) (xy 340.747369 -253.952544) (xy 340.78999 -253.927937)
			(xy 340.836006 -253.910485) (xy 340.884225 -253.900641) (xy 340.9334 -253.89866) (xy 340.982255 -253.904592)
			(xy 341.029526 -253.918284) (xy 341.073988 -253.939382) (xy 341.114491 -253.967338) (xy 341.149984 -254.00143)
			(xy 341.179549 -254.040774) (xy 341.20242 -254.084351) (xy 341.218004 -254.131032) (xy 341.225899 -254.179609)
			(xy 341.226394 -254.204216) (xy 341.544905 -254.204216) (xy 341.549 -254.153488) (xy 341.561179 -254.104074)
			(xy 341.581127 -254.057254) (xy 341.608328 -254.01424) (xy 341.642076 -253.976146) (xy 341.681498 -253.943959)
			(xy 341.725572 -253.918513) (xy 341.773158 -253.900466) (xy 341.823022 -253.890286) (xy 341.873874 -253.888237)
			(xy 341.924395 -253.894371) (xy 341.973279 -253.908531) (xy 342.019258 -253.930348) (xy 342.061142 -253.959258)
			(xy 342.097846 -253.994513) (xy 342.128419 -254.035199) (xy 342.15207 -254.080262) (xy 342.168186 -254.128536)
			(xy 342.17635 -254.17877) (xy 342.176862 -254.204216) (xy 342.49539 -254.204216) (xy 342.49935 -254.155162)
			(xy 342.511127 -254.107378) (xy 342.530418 -254.062102) (xy 342.556721 -254.020506) (xy 342.589356 -253.983669)
			(xy 342.627477 -253.952544) (xy 342.670098 -253.927937) (xy 342.716114 -253.910485) (xy 342.764333 -253.900641)
			(xy 342.813508 -253.89866) (xy 342.862363 -253.904592) (xy 342.909634 -253.918284) (xy 342.954096 -253.939382)
			(xy 342.994599 -253.967338) (xy 343.030092 -254.00143) (xy 343.059657 -254.040774) (xy 343.082528 -254.084351)
			(xy 343.098112 -254.131032) (xy 343.106007 -254.179609) (xy 343.106502 -254.204216) (xy 343.424759 -254.204216)
			(xy 343.428854 -254.153488) (xy 343.441033 -254.104074) (xy 343.460981 -254.057254) (xy 343.488182 -254.01424)
			(xy 343.52193 -253.976146) (xy 343.561352 -253.943959) (xy 343.605426 -253.918513) (xy 343.653012 -253.900466)
			(xy 343.702876 -253.890286) (xy 343.753728 -253.888237) (xy 343.804249 -253.894371) (xy 343.853133 -253.908531)
			(xy 343.899112 -253.930348) (xy 343.940996 -253.959258) (xy 343.9777 -253.994513) (xy 344.008273 -254.035199)
			(xy 344.031924 -254.080262) (xy 344.04804 -254.128536) (xy 344.056204 -254.17877) (xy 344.056716 -254.204216)
			(xy 345.315298 -254.204216) (xy 345.319258 -254.155162) (xy 345.331035 -254.107378) (xy 345.350326 -254.062102)
			(xy 345.376629 -254.020506) (xy 345.409264 -253.983669) (xy 345.447385 -253.952544) (xy 345.490006 -253.927937)
			(xy 345.536022 -253.910485) (xy 345.584241 -253.900641) (xy 345.633416 -253.89866) (xy 345.682271 -253.904592)
			(xy 345.729542 -253.918284) (xy 345.774004 -253.939382) (xy 345.814507 -253.967338) (xy 345.85 -254.00143)
			(xy 345.879565 -254.040774) (xy 345.902436 -254.084351) (xy 345.91802 -254.131032) (xy 345.925915 -254.179609)
			(xy 345.92641 -254.204216) (xy 347.195406 -254.204216) (xy 347.199366 -254.155162) (xy 347.211143 -254.107378)
			(xy 347.230434 -254.062102) (xy 347.256737 -254.020506) (xy 347.289372 -253.983669) (xy 347.327493 -253.952544)
			(xy 347.370114 -253.927937) (xy 347.41613 -253.910485) (xy 347.464349 -253.900641) (xy 347.513524 -253.89866)
			(xy 347.562379 -253.904592) (xy 347.60965 -253.918284) (xy 347.654112 -253.939382) (xy 347.694615 -253.967338)
			(xy 347.730108 -254.00143) (xy 347.759673 -254.040774) (xy 347.782544 -254.084351) (xy 347.798128 -254.131032)
			(xy 347.806023 -254.179609) (xy 347.806518 -254.204216) (xy 349.07526 -254.204216) (xy 349.07922 -254.155162)
			(xy 349.090997 -254.107378) (xy 349.110288 -254.062102) (xy 349.136591 -254.020506) (xy 349.169226 -253.983669)
			(xy 349.207347 -253.952544) (xy 349.249968 -253.927937) (xy 349.295984 -253.910485) (xy 349.344203 -253.900641)
			(xy 349.393378 -253.89866) (xy 349.442233 -253.904592) (xy 349.489504 -253.918284) (xy 349.533966 -253.939382)
			(xy 349.574469 -253.967338) (xy 349.609962 -254.00143) (xy 349.639527 -254.040774) (xy 349.662398 -254.084351)
			(xy 349.677982 -254.131032) (xy 349.685877 -254.179609) (xy 349.686372 -254.204216) (xy 350.015314 -254.204216)
			(xy 350.019274 -254.155162) (xy 350.031051 -254.107378) (xy 350.050342 -254.062102) (xy 350.076645 -254.020506)
			(xy 350.10928 -253.983669) (xy 350.147401 -253.952544) (xy 350.190022 -253.927937) (xy 350.236038 -253.910485)
			(xy 350.284257 -253.900641) (xy 350.333432 -253.89866) (xy 350.382287 -253.904592) (xy 350.429558 -253.918284)
			(xy 350.47402 -253.939382) (xy 350.514523 -253.967338) (xy 350.550016 -254.00143) (xy 350.579581 -254.040774)
			(xy 350.602452 -254.084351) (xy 350.618036 -254.131032) (xy 350.625931 -254.179609) (xy 350.626426 -254.204216)
			(xy 350.625931 -254.228823) (xy 350.618036 -254.2774) (xy 350.602452 -254.324081) (xy 350.579581 -254.367658)
			(xy 350.550016 -254.407002) (xy 350.514523 -254.441094) (xy 350.47402 -254.46905) (xy 350.429558 -254.490148)
			(xy 350.382287 -254.50384) (xy 350.333432 -254.509772) (xy 350.284257 -254.507791) (xy 350.236038 -254.497947)
			(xy 350.190022 -254.480495) (xy 350.147401 -254.455888) (xy 350.10928 -254.424763) (xy 350.076645 -254.387926)
			(xy 350.050342 -254.34633) (xy 350.031051 -254.301054) (xy 350.019274 -254.25327) (xy 350.015314 -254.204216)
			(xy 349.686372 -254.204216) (xy 349.685877 -254.228823) (xy 349.677982 -254.2774) (xy 349.662398 -254.324081)
			(xy 349.639527 -254.367658) (xy 349.609962 -254.407002) (xy 349.574469 -254.441094) (xy 349.533966 -254.46905)
			(xy 349.489504 -254.490148) (xy 349.442233 -254.50384) (xy 349.393378 -254.509772) (xy 349.344203 -254.507791)
			(xy 349.295984 -254.497947) (xy 349.249968 -254.480495) (xy 349.207347 -254.455888) (xy 349.169226 -254.424763)
			(xy 349.136591 -254.387926) (xy 349.110288 -254.34633) (xy 349.090997 -254.301054) (xy 349.07922 -254.25327)
			(xy 349.07526 -254.204216) (xy 347.806518 -254.204216) (xy 347.806023 -254.228823) (xy 347.798128 -254.2774)
			(xy 347.782544 -254.324081) (xy 347.759673 -254.367658) (xy 347.730108 -254.407002) (xy 347.694615 -254.441094)
			(xy 347.654112 -254.46905) (xy 347.60965 -254.490148) (xy 347.562379 -254.50384) (xy 347.513524 -254.509772)
			(xy 347.464349 -254.507791) (xy 347.41613 -254.497947) (xy 347.370114 -254.480495) (xy 347.327493 -254.455888)
			(xy 347.289372 -254.424763) (xy 347.256737 -254.387926) (xy 347.230434 -254.34633) (xy 347.211143 -254.301054)
			(xy 347.199366 -254.25327) (xy 347.195406 -254.204216) (xy 345.92641 -254.204216) (xy 345.925915 -254.228823)
			(xy 345.91802 -254.2774) (xy 345.902436 -254.324081) (xy 345.879565 -254.367658) (xy 345.85 -254.407002)
			(xy 345.814507 -254.441094) (xy 345.774004 -254.46905) (xy 345.729542 -254.490148) (xy 345.682271 -254.50384)
			(xy 345.633416 -254.509772) (xy 345.584241 -254.507791) (xy 345.536022 -254.497947) (xy 345.490006 -254.480495)
			(xy 345.447385 -254.455888) (xy 345.409264 -254.424763) (xy 345.376629 -254.387926) (xy 345.350326 -254.34633)
			(xy 345.331035 -254.301054) (xy 345.319258 -254.25327) (xy 345.315298 -254.204216) (xy 344.056716 -254.204216)
			(xy 344.056204 -254.229662) (xy 344.04804 -254.279896) (xy 344.031924 -254.32817) (xy 344.008273 -254.373233)
			(xy 343.9777 -254.413919) (xy 343.940996 -254.449174) (xy 343.899112 -254.478084) (xy 343.853133 -254.499901)
			(xy 343.804249 -254.514061) (xy 343.753728 -254.520195) (xy 343.702876 -254.518146) (xy 343.653012 -254.507966)
			(xy 343.605426 -254.489919) (xy 343.561352 -254.464473) (xy 343.52193 -254.432286) (xy 343.488182 -254.394192)
			(xy 343.460981 -254.351178) (xy 343.441033 -254.304358) (xy 343.428854 -254.254944) (xy 343.424759 -254.204216)
			(xy 343.106502 -254.204216) (xy 343.106007 -254.228823) (xy 343.098112 -254.2774) (xy 343.082528 -254.324081)
			(xy 343.059657 -254.367658) (xy 343.030092 -254.407002) (xy 342.994599 -254.441094) (xy 342.954096 -254.46905)
			(xy 342.909634 -254.490148) (xy 342.862363 -254.50384) (xy 342.813508 -254.509772) (xy 342.764333 -254.507791)
			(xy 342.716114 -254.497947) (xy 342.670098 -254.480495) (xy 342.627477 -254.455888) (xy 342.589356 -254.424763)
			(xy 342.556721 -254.387926) (xy 342.530418 -254.34633) (xy 342.511127 -254.301054) (xy 342.49935 -254.25327)
			(xy 342.49539 -254.204216) (xy 342.176862 -254.204216) (xy 342.17635 -254.229662) (xy 342.168186 -254.279896)
			(xy 342.15207 -254.32817) (xy 342.128419 -254.373233) (xy 342.097846 -254.413919) (xy 342.061142 -254.449174)
			(xy 342.019258 -254.478084) (xy 341.973279 -254.499901) (xy 341.924395 -254.514061) (xy 341.873874 -254.520195)
			(xy 341.823022 -254.518146) (xy 341.773158 -254.507966) (xy 341.725572 -254.489919) (xy 341.681498 -254.464473)
			(xy 341.642076 -254.432286) (xy 341.608328 -254.394192) (xy 341.581127 -254.351178) (xy 341.561179 -254.304358)
			(xy 341.549 -254.254944) (xy 341.544905 -254.204216) (xy 341.226394 -254.204216) (xy 341.225899 -254.228823)
			(xy 341.218004 -254.2774) (xy 341.20242 -254.324081) (xy 341.179549 -254.367658) (xy 341.149984 -254.407002)
			(xy 341.114491 -254.441094) (xy 341.073988 -254.46905) (xy 341.029526 -254.490148) (xy 340.982255 -254.50384)
			(xy 340.9334 -254.509772) (xy 340.884225 -254.507791) (xy 340.836006 -254.497947) (xy 340.78999 -254.480495)
			(xy 340.747369 -254.455888) (xy 340.709248 -254.424763) (xy 340.676613 -254.387926) (xy 340.65031 -254.34633)
			(xy 340.631019 -254.301054) (xy 340.619242 -254.25327) (xy 340.615282 -254.204216) (xy 340.296754 -254.204216)
			(xy 340.296242 -254.229662) (xy 340.288078 -254.279896) (xy 340.271962 -254.32817) (xy 340.248311 -254.373233)
			(xy 340.217738 -254.413919) (xy 340.181034 -254.449174) (xy 340.13915 -254.478084) (xy 340.093171 -254.499901)
			(xy 340.044287 -254.514061) (xy 339.993766 -254.520195) (xy 339.942914 -254.518146) (xy 339.89305 -254.507966)
			(xy 339.845464 -254.489919) (xy 339.80139 -254.464473) (xy 339.761968 -254.432286) (xy 339.72822 -254.394192)
			(xy 339.701019 -254.351178) (xy 339.681071 -254.304358) (xy 339.668892 -254.254944) (xy 339.664797 -254.204216)
			(xy 339.3567 -254.204216) (xy 339.356188 -254.229662) (xy 339.348024 -254.279896) (xy 339.331908 -254.32817)
			(xy 339.308257 -254.373233) (xy 339.277684 -254.413919) (xy 339.24098 -254.449174) (xy 339.199096 -254.478084)
			(xy 339.153117 -254.499901) (xy 339.104233 -254.514061) (xy 339.053712 -254.520195) (xy 339.00286 -254.518146)
			(xy 338.952996 -254.507966) (xy 338.90541 -254.489919) (xy 338.861336 -254.464473) (xy 338.821914 -254.432286)
			(xy 338.788166 -254.394192) (xy 338.760965 -254.351178) (xy 338.741017 -254.304358) (xy 338.728838 -254.254944)
			(xy 338.724743 -254.204216) (xy 338.406486 -254.204216) (xy 338.405991 -254.228823) (xy 338.398096 -254.2774)
			(xy 338.382512 -254.324081) (xy 338.359641 -254.367658) (xy 338.330076 -254.407002) (xy 338.294583 -254.441094)
			(xy 338.25408 -254.46905) (xy 338.209618 -254.490148) (xy 338.162347 -254.50384) (xy 338.113492 -254.509772)
			(xy 338.064317 -254.507791) (xy 338.016098 -254.497947) (xy 337.970082 -254.480495) (xy 337.927461 -254.455888)
			(xy 337.88934 -254.424763) (xy 337.856705 -254.387926) (xy 337.830402 -254.34633) (xy 337.811111 -254.301054)
			(xy 337.799334 -254.25327) (xy 337.795374 -254.204216) (xy 337.466432 -254.204216) (xy 337.465937 -254.228823)
			(xy 337.458042 -254.2774) (xy 337.442458 -254.324081) (xy 337.419587 -254.367658) (xy 337.390022 -254.407002)
			(xy 337.354529 -254.441094) (xy 337.314026 -254.46905) (xy 337.269564 -254.490148) (xy 337.222293 -254.50384)
			(xy 337.173438 -254.509772) (xy 337.124263 -254.507791) (xy 337.076044 -254.497947) (xy 337.030028 -254.480495)
			(xy 336.987407 -254.455888) (xy 336.949286 -254.424763) (xy 336.916651 -254.387926) (xy 336.890348 -254.34633)
			(xy 336.871057 -254.301054) (xy 336.85928 -254.25327) (xy 336.85532 -254.204216) (xy 336.526378 -254.204216)
			(xy 336.525883 -254.228823) (xy 336.517988 -254.2774) (xy 336.502404 -254.324081) (xy 336.479533 -254.367658)
			(xy 336.449968 -254.407002) (xy 336.414475 -254.441094) (xy 336.373972 -254.46905) (xy 336.32951 -254.490148)
			(xy 336.282239 -254.50384) (xy 336.233384 -254.509772) (xy 336.184209 -254.507791) (xy 336.13599 -254.497947)
			(xy 336.089974 -254.480495) (xy 336.047353 -254.455888) (xy 336.009232 -254.424763) (xy 335.976597 -254.387926)
			(xy 335.950294 -254.34633) (xy 335.931003 -254.301054) (xy 335.919226 -254.25327) (xy 335.915266 -254.204216)
			(xy 335.586324 -254.204216) (xy 335.585829 -254.228823) (xy 335.577934 -254.2774) (xy 335.56235 -254.324081)
			(xy 335.539479 -254.367658) (xy 335.509914 -254.407002) (xy 335.474421 -254.441094) (xy 335.433918 -254.46905)
			(xy 335.389456 -254.490148) (xy 335.342185 -254.50384) (xy 335.29333 -254.509772) (xy 335.244155 -254.507791)
			(xy 335.195936 -254.497947) (xy 335.14992 -254.480495) (xy 335.107299 -254.455888) (xy 335.069178 -254.424763)
			(xy 335.036543 -254.387926) (xy 335.01024 -254.34633) (xy 334.990949 -254.301054) (xy 334.979172 -254.25327)
			(xy 334.975212 -254.204216) (xy 334.646524 -254.204216) (xy 334.646052 -254.228207) (xy 334.638544 -254.275598)
			(xy 334.623716 -254.32123) (xy 334.601931 -254.363982) (xy 334.573728 -254.4028) (xy 334.5398 -254.436728)
			(xy 334.500982 -254.464931) (xy 334.45823 -254.486716) (xy 334.412598 -254.501544) (xy 334.365207 -254.509052)
			(xy 334.341216 -254.509524) (xy 334.309466 -254.507746) (xy 334.306672 -254.507492) (xy 334.304132 -254.507492)
			(xy 334.294106 -254.507906) (xy 334.275577 -254.51557) (xy 334.261392 -254.529743) (xy 334.253714 -254.548266)
			(xy 334.253332 -254.558292) (xy 334.253332 -254.578612) (xy 334.254094 -254.587502) (xy 334.255364 -254.59436)
			(xy 334.256971 -254.60197) (xy 334.264093 -254.61579) (xy 334.269334 -254.621538) (xy 334.269588 -254.621792)
			(xy 334.274922 -254.62738) (xy 334.298191 -254.652409) (xy 334.339093 -254.70716) (xy 334.372999 -254.766498)
			(xy 334.386682 -254.797814) (xy 334.389222 -254.80391) (xy 334.396842 -254.81407) (xy 334.421226 -254.83312)
			(xy 334.426703 -254.837076) (xy 334.439192 -254.842215) (xy 334.445864 -254.84328) (xy 334.516984 -254.852932)
			(xy 334.522959 -254.85355) (xy 334.5349 -254.85227) (xy 334.540606 -254.850392) (xy 334.551782 -254.846582)
			(xy 334.56499 -254.833374) (xy 334.567022 -254.83058) (xy 334.581566 -254.812026) (xy 334.615396 -254.779195)
			(xy 334.65386 -254.75194) (xy 334.69605 -254.730906) (xy 334.740965 -254.716591) (xy 334.787545 -254.709333)
			(xy 334.811116 -254.708914) (xy 334.836369 -254.709437) (xy 334.886185 -254.717752) (xy 334.933953 -254.734153)
			(xy 334.97837 -254.758192) (xy 335.018225 -254.789215) (xy 335.05243 -254.826374) (xy 335.080053 -254.868655)
			(xy 335.100341 -254.914907) (xy 335.112738 -254.963867) (xy 335.116909 -255.0142) (xy 335.116907 -255.014222)
			(xy 335.445366 -255.014222) (xy 335.449326 -254.965168) (xy 335.461103 -254.917384) (xy 335.480394 -254.872108)
			(xy 335.506697 -254.830512) (xy 335.539332 -254.793675) (xy 335.577453 -254.76255) (xy 335.620074 -254.737943)
			(xy 335.66609 -254.720491) (xy 335.714309 -254.710647) (xy 335.763484 -254.708666) (xy 335.812339 -254.714598)
			(xy 335.85961 -254.72829) (xy 335.904072 -254.749388) (xy 335.944575 -254.777344) (xy 335.980068 -254.811436)
			(xy 336.009633 -254.85078) (xy 336.032504 -254.894357) (xy 336.048088 -254.941038) (xy 336.055983 -254.989615)
			(xy 336.056478 -255.014222) (xy 336.38542 -255.014222) (xy 336.38938 -254.965168) (xy 336.401157 -254.917384)
			(xy 336.420448 -254.872108) (xy 336.446751 -254.830512) (xy 336.479386 -254.793675) (xy 336.517507 -254.76255)
			(xy 336.560128 -254.737943) (xy 336.606144 -254.720491) (xy 336.654363 -254.710647) (xy 336.703538 -254.708666)
			(xy 336.752393 -254.714598) (xy 336.799664 -254.72829) (xy 336.844126 -254.749388) (xy 336.884629 -254.777344)
			(xy 336.920122 -254.811436) (xy 336.949687 -254.85078) (xy 336.972558 -254.894357) (xy 336.988142 -254.941038)
			(xy 336.996037 -254.989615) (xy 336.996532 -255.014222) (xy 337.32522 -255.014222) (xy 337.32918 -254.965168)
			(xy 337.340957 -254.917384) (xy 337.360248 -254.872108) (xy 337.386551 -254.830512) (xy 337.419186 -254.793675)
			(xy 337.457307 -254.76255) (xy 337.499928 -254.737943) (xy 337.545944 -254.720491) (xy 337.594163 -254.710647)
			(xy 337.643338 -254.708666) (xy 337.692193 -254.714598) (xy 337.739464 -254.72829) (xy 337.783926 -254.749388)
			(xy 337.824429 -254.777344) (xy 337.859922 -254.811436) (xy 337.889487 -254.85078) (xy 337.912358 -254.894357)
			(xy 337.927942 -254.941038) (xy 337.935837 -254.989615) (xy 337.936332 -255.014222) (xy 338.254843 -255.014222)
			(xy 338.258938 -254.963494) (xy 338.271117 -254.91408) (xy 338.291065 -254.86726) (xy 338.318266 -254.824246)
			(xy 338.352014 -254.786152) (xy 338.391436 -254.753965) (xy 338.43551 -254.728519) (xy 338.483096 -254.710472)
			(xy 338.53296 -254.700292) (xy 338.583812 -254.698243) (xy 338.634333 -254.704377) (xy 338.683217 -254.718537)
			(xy 338.729196 -254.740354) (xy 338.77108 -254.769264) (xy 338.807784 -254.804519) (xy 338.838357 -254.845205)
			(xy 338.862008 -254.890268) (xy 338.878124 -254.938542) (xy 338.886288 -254.988776) (xy 338.8868 -255.014222)
			(xy 339.205328 -255.014222) (xy 339.209288 -254.965168) (xy 339.221065 -254.917384) (xy 339.240356 -254.872108)
			(xy 339.266659 -254.830512) (xy 339.299294 -254.793675) (xy 339.337415 -254.76255) (xy 339.380036 -254.737943)
			(xy 339.426052 -254.720491) (xy 339.474271 -254.710647) (xy 339.523446 -254.708666) (xy 339.572301 -254.714598)
			(xy 339.619572 -254.72829) (xy 339.664034 -254.749388) (xy 339.704537 -254.777344) (xy 339.74003 -254.811436)
			(xy 339.769595 -254.85078) (xy 339.792466 -254.894357) (xy 339.80805 -254.941038) (xy 339.815945 -254.989615)
			(xy 339.81644 -255.014222) (xy 340.134951 -255.014222) (xy 340.139046 -254.963494) (xy 340.151225 -254.91408)
			(xy 340.171173 -254.86726) (xy 340.198374 -254.824246) (xy 340.232122 -254.786152) (xy 340.271544 -254.753965)
			(xy 340.315618 -254.728519) (xy 340.363204 -254.710472) (xy 340.413068 -254.700292) (xy 340.46392 -254.698243)
			(xy 340.514441 -254.704377) (xy 340.563325 -254.718537) (xy 340.609304 -254.740354) (xy 340.651188 -254.769264)
			(xy 340.687892 -254.804519) (xy 340.718465 -254.845205) (xy 340.742116 -254.890268) (xy 340.758232 -254.938542)
			(xy 340.766396 -254.988776) (xy 340.766908 -255.014222) (xy 341.085182 -255.014222) (xy 341.089142 -254.965168)
			(xy 341.100919 -254.917384) (xy 341.12021 -254.872108) (xy 341.146513 -254.830512) (xy 341.179148 -254.793675)
			(xy 341.217269 -254.76255) (xy 341.25989 -254.737943) (xy 341.305906 -254.720491) (xy 341.354125 -254.710647)
			(xy 341.4033 -254.708666) (xy 341.452155 -254.714598) (xy 341.499426 -254.72829) (xy 341.543888 -254.749388)
			(xy 341.584391 -254.777344) (xy 341.619884 -254.811436) (xy 341.649449 -254.85078) (xy 341.67232 -254.894357)
			(xy 341.687904 -254.941038) (xy 341.695799 -254.989615) (xy 341.696294 -255.014222) (xy 342.014805 -255.014222)
			(xy 342.0189 -254.963494) (xy 342.031079 -254.91408) (xy 342.051027 -254.86726) (xy 342.078228 -254.824246)
			(xy 342.111976 -254.786152) (xy 342.151398 -254.753965) (xy 342.195472 -254.728519) (xy 342.243058 -254.710472)
			(xy 342.292922 -254.700292) (xy 342.343774 -254.698243) (xy 342.394295 -254.704377) (xy 342.443179 -254.718537)
			(xy 342.489158 -254.740354) (xy 342.531042 -254.769264) (xy 342.567746 -254.804519) (xy 342.598319 -254.845205)
			(xy 342.62197 -254.890268) (xy 342.638086 -254.938542) (xy 342.64625 -254.988776) (xy 342.646762 -255.014222)
			(xy 342.954859 -255.014222) (xy 342.958954 -254.963494) (xy 342.971133 -254.91408) (xy 342.991081 -254.86726)
			(xy 343.018282 -254.824246) (xy 343.05203 -254.786152) (xy 343.091452 -254.753965) (xy 343.135526 -254.728519)
			(xy 343.183112 -254.710472) (xy 343.232976 -254.700292) (xy 343.283828 -254.698243) (xy 343.334349 -254.704377)
			(xy 343.383233 -254.718537) (xy 343.429212 -254.740354) (xy 343.471096 -254.769264) (xy 343.5078 -254.804519)
			(xy 343.538373 -254.845205) (xy 343.562024 -254.890268) (xy 343.57814 -254.938542) (xy 343.586304 -254.988776)
			(xy 343.586816 -255.014222) (xy 343.905344 -255.014222) (xy 343.909304 -254.965168) (xy 343.921081 -254.917384)
			(xy 343.940372 -254.872108) (xy 343.966675 -254.830512) (xy 343.99931 -254.793675) (xy 344.037431 -254.76255)
			(xy 344.080052 -254.737943) (xy 344.126068 -254.720491) (xy 344.174287 -254.710647) (xy 344.223462 -254.708666)
			(xy 344.272317 -254.714598) (xy 344.319588 -254.72829) (xy 344.36405 -254.749388) (xy 344.404553 -254.777344)
			(xy 344.440046 -254.811436) (xy 344.469611 -254.85078) (xy 344.492482 -254.894357) (xy 344.508066 -254.941038)
			(xy 344.515961 -254.989615) (xy 344.516456 -255.014222) (xy 345.785198 -255.014222) (xy 345.789158 -254.965168)
			(xy 345.800935 -254.917384) (xy 345.820226 -254.872108) (xy 345.846529 -254.830512) (xy 345.879164 -254.793675)
			(xy 345.917285 -254.76255) (xy 345.959906 -254.737943) (xy 346.005922 -254.720491) (xy 346.054141 -254.710647)
			(xy 346.103316 -254.708666) (xy 346.152171 -254.714598) (xy 346.199442 -254.72829) (xy 346.243904 -254.749388)
			(xy 346.284407 -254.777344) (xy 346.3199 -254.811436) (xy 346.349465 -254.85078) (xy 346.372336 -254.894357)
			(xy 346.38792 -254.941038) (xy 346.395815 -254.989615) (xy 346.39631 -255.014222) (xy 347.665306 -255.014222)
			(xy 347.669266 -254.965168) (xy 347.681043 -254.917384) (xy 347.700334 -254.872108) (xy 347.726637 -254.830512)
			(xy 347.759272 -254.793675) (xy 347.797393 -254.76255) (xy 347.840014 -254.737943) (xy 347.88603 -254.720491)
			(xy 347.934249 -254.710647) (xy 347.983424 -254.708666) (xy 348.032279 -254.714598) (xy 348.07955 -254.72829)
			(xy 348.124012 -254.749388) (xy 348.164515 -254.777344) (xy 348.200008 -254.811436) (xy 348.229573 -254.85078)
			(xy 348.252444 -254.894357) (xy 348.268028 -254.941038) (xy 348.275923 -254.989615) (xy 348.276418 -255.014222)
			(xy 348.60536 -255.014222) (xy 348.60932 -254.965168) (xy 348.621097 -254.917384) (xy 348.640388 -254.872108)
			(xy 348.666691 -254.830512) (xy 348.699326 -254.793675) (xy 348.737447 -254.76255) (xy 348.780068 -254.737943)
			(xy 348.826084 -254.720491) (xy 348.874303 -254.710647) (xy 348.923478 -254.708666) (xy 348.972333 -254.714598)
			(xy 349.019604 -254.72829) (xy 349.064066 -254.749388) (xy 349.104569 -254.777344) (xy 349.140062 -254.811436)
			(xy 349.169627 -254.85078) (xy 349.192498 -254.894357) (xy 349.208082 -254.941038) (xy 349.215977 -254.989615)
			(xy 349.216472 -255.014222) (xy 349.545414 -255.014222) (xy 349.549374 -254.965168) (xy 349.561151 -254.917384)
			(xy 349.580442 -254.872108) (xy 349.606745 -254.830512) (xy 349.63938 -254.793675) (xy 349.677501 -254.76255)
			(xy 349.720122 -254.737943) (xy 349.766138 -254.720491) (xy 349.814357 -254.710647) (xy 349.863532 -254.708666)
			(xy 349.912387 -254.714598) (xy 349.959658 -254.72829) (xy 350.00412 -254.749388) (xy 350.044623 -254.777344)
			(xy 350.080116 -254.811436) (xy 350.109681 -254.85078) (xy 350.132552 -254.894357) (xy 350.148136 -254.941038)
			(xy 350.156031 -254.989615) (xy 350.156526 -255.014222) (xy 350.156031 -255.038829) (xy 350.148136 -255.087406)
			(xy 350.132552 -255.134087) (xy 350.109681 -255.177664) (xy 350.080116 -255.217008) (xy 350.044623 -255.2511)
			(xy 350.00412 -255.279056) (xy 349.959658 -255.300154) (xy 349.912387 -255.313846) (xy 349.863532 -255.319778)
			(xy 349.814357 -255.317797) (xy 349.766138 -255.307953) (xy 349.720122 -255.290501) (xy 349.677501 -255.265894)
			(xy 349.63938 -255.234769) (xy 349.606745 -255.197932) (xy 349.580442 -255.156336) (xy 349.561151 -255.11106)
			(xy 349.549374 -255.063276) (xy 349.545414 -255.014222) (xy 349.216472 -255.014222) (xy 349.215977 -255.038829)
			(xy 349.208082 -255.087406) (xy 349.192498 -255.134087) (xy 349.169627 -255.177664) (xy 349.140062 -255.217008)
			(xy 349.104569 -255.2511) (xy 349.064066 -255.279056) (xy 349.019604 -255.300154) (xy 348.972333 -255.313846)
			(xy 348.923478 -255.319778) (xy 348.874303 -255.317797) (xy 348.826084 -255.307953) (xy 348.780068 -255.290501)
			(xy 348.737447 -255.265894) (xy 348.699326 -255.234769) (xy 348.666691 -255.197932) (xy 348.640388 -255.156336)
			(xy 348.621097 -255.11106) (xy 348.60932 -255.063276) (xy 348.60536 -255.014222) (xy 348.276418 -255.014222)
			(xy 348.275923 -255.038829) (xy 348.268028 -255.087406) (xy 348.252444 -255.134087) (xy 348.229573 -255.177664)
			(xy 348.200008 -255.217008) (xy 348.164515 -255.2511) (xy 348.124012 -255.279056) (xy 348.07955 -255.300154)
			(xy 348.032279 -255.313846) (xy 347.983424 -255.319778) (xy 347.934249 -255.317797) (xy 347.88603 -255.307953)
			(xy 347.840014 -255.290501) (xy 347.797393 -255.265894) (xy 347.759272 -255.234769) (xy 347.726637 -255.197932)
			(xy 347.700334 -255.156336) (xy 347.681043 -255.11106) (xy 347.669266 -255.063276) (xy 347.665306 -255.014222)
			(xy 346.39631 -255.014222) (xy 346.395815 -255.038829) (xy 346.38792 -255.087406) (xy 346.372336 -255.134087)
			(xy 346.349465 -255.177664) (xy 346.3199 -255.217008) (xy 346.284407 -255.2511) (xy 346.243904 -255.279056)
			(xy 346.199442 -255.300154) (xy 346.152171 -255.313846) (xy 346.103316 -255.319778) (xy 346.054141 -255.317797)
			(xy 346.005922 -255.307953) (xy 345.959906 -255.290501) (xy 345.917285 -255.265894) (xy 345.879164 -255.234769)
			(xy 345.846529 -255.197932) (xy 345.820226 -255.156336) (xy 345.800935 -255.11106) (xy 345.789158 -255.063276)
			(xy 345.785198 -255.014222) (xy 344.516456 -255.014222) (xy 344.515961 -255.038829) (xy 344.508066 -255.087406)
			(xy 344.492482 -255.134087) (xy 344.469611 -255.177664) (xy 344.440046 -255.217008) (xy 344.404553 -255.2511)
			(xy 344.36405 -255.279056) (xy 344.319588 -255.300154) (xy 344.272317 -255.313846) (xy 344.223462 -255.319778)
			(xy 344.174287 -255.317797) (xy 344.126068 -255.307953) (xy 344.080052 -255.290501) (xy 344.037431 -255.265894)
			(xy 343.99931 -255.234769) (xy 343.966675 -255.197932) (xy 343.940372 -255.156336) (xy 343.921081 -255.11106)
			(xy 343.909304 -255.063276) (xy 343.905344 -255.014222) (xy 343.586816 -255.014222) (xy 343.586304 -255.039668)
			(xy 343.57814 -255.089902) (xy 343.562024 -255.138176) (xy 343.538373 -255.183239) (xy 343.5078 -255.223925)
			(xy 343.471096 -255.25918) (xy 343.429212 -255.28809) (xy 343.383233 -255.309907) (xy 343.334349 -255.324067)
			(xy 343.283828 -255.330201) (xy 343.232976 -255.328152) (xy 343.183112 -255.317972) (xy 343.135526 -255.299925)
			(xy 343.091452 -255.274479) (xy 343.05203 -255.242292) (xy 343.018282 -255.204198) (xy 342.991081 -255.161184)
			(xy 342.971133 -255.114364) (xy 342.958954 -255.06495) (xy 342.954859 -255.014222) (xy 342.646762 -255.014222)
			(xy 342.64625 -255.039668) (xy 342.638086 -255.089902) (xy 342.62197 -255.138176) (xy 342.598319 -255.183239)
			(xy 342.567746 -255.223925) (xy 342.531042 -255.25918) (xy 342.489158 -255.28809) (xy 342.443179 -255.309907)
			(xy 342.394295 -255.324067) (xy 342.343774 -255.330201) (xy 342.292922 -255.328152) (xy 342.243058 -255.317972)
			(xy 342.195472 -255.299925) (xy 342.151398 -255.274479) (xy 342.111976 -255.242292) (xy 342.078228 -255.204198)
			(xy 342.051027 -255.161184) (xy 342.031079 -255.114364) (xy 342.0189 -255.06495) (xy 342.014805 -255.014222)
			(xy 341.696294 -255.014222) (xy 341.695799 -255.038829) (xy 341.687904 -255.087406) (xy 341.67232 -255.134087)
			(xy 341.649449 -255.177664) (xy 341.619884 -255.217008) (xy 341.584391 -255.2511) (xy 341.543888 -255.279056)
			(xy 341.499426 -255.300154) (xy 341.452155 -255.313846) (xy 341.4033 -255.319778) (xy 341.354125 -255.317797)
			(xy 341.305906 -255.307953) (xy 341.25989 -255.290501) (xy 341.217269 -255.265894) (xy 341.179148 -255.234769)
			(xy 341.146513 -255.197932) (xy 341.12021 -255.156336) (xy 341.100919 -255.11106) (xy 341.089142 -255.063276)
			(xy 341.085182 -255.014222) (xy 340.766908 -255.014222) (xy 340.766396 -255.039668) (xy 340.758232 -255.089902)
			(xy 340.742116 -255.138176) (xy 340.718465 -255.183239) (xy 340.687892 -255.223925) (xy 340.651188 -255.25918)
			(xy 340.609304 -255.28809) (xy 340.563325 -255.309907) (xy 340.514441 -255.324067) (xy 340.46392 -255.330201)
			(xy 340.413068 -255.328152) (xy 340.363204 -255.317972) (xy 340.315618 -255.299925) (xy 340.271544 -255.274479)
			(xy 340.232122 -255.242292) (xy 340.198374 -255.204198) (xy 340.171173 -255.161184) (xy 340.151225 -255.114364)
			(xy 340.139046 -255.06495) (xy 340.134951 -255.014222) (xy 339.81644 -255.014222) (xy 339.815945 -255.038829)
			(xy 339.80805 -255.087406) (xy 339.792466 -255.134087) (xy 339.769595 -255.177664) (xy 339.74003 -255.217008)
			(xy 339.704537 -255.2511) (xy 339.664034 -255.279056) (xy 339.619572 -255.300154) (xy 339.572301 -255.313846)
			(xy 339.523446 -255.319778) (xy 339.474271 -255.317797) (xy 339.426052 -255.307953) (xy 339.380036 -255.290501)
			(xy 339.337415 -255.265894) (xy 339.299294 -255.234769) (xy 339.266659 -255.197932) (xy 339.240356 -255.156336)
			(xy 339.221065 -255.11106) (xy 339.209288 -255.063276) (xy 339.205328 -255.014222) (xy 338.8868 -255.014222)
			(xy 338.886288 -255.039668) (xy 338.878124 -255.089902) (xy 338.862008 -255.138176) (xy 338.838357 -255.183239)
			(xy 338.807784 -255.223925) (xy 338.77108 -255.25918) (xy 338.729196 -255.28809) (xy 338.683217 -255.309907)
			(xy 338.634333 -255.324067) (xy 338.583812 -255.330201) (xy 338.53296 -255.328152) (xy 338.483096 -255.317972)
			(xy 338.43551 -255.299925) (xy 338.391436 -255.274479) (xy 338.352014 -255.242292) (xy 338.318266 -255.204198)
			(xy 338.291065 -255.161184) (xy 338.271117 -255.114364) (xy 338.258938 -255.06495) (xy 338.254843 -255.014222)
			(xy 337.936332 -255.014222) (xy 337.935837 -255.038829) (xy 337.927942 -255.087406) (xy 337.912358 -255.134087)
			(xy 337.889487 -255.177664) (xy 337.859922 -255.217008) (xy 337.824429 -255.2511) (xy 337.783926 -255.279056)
			(xy 337.739464 -255.300154) (xy 337.692193 -255.313846) (xy 337.643338 -255.319778) (xy 337.594163 -255.317797)
			(xy 337.545944 -255.307953) (xy 337.499928 -255.290501) (xy 337.457307 -255.265894) (xy 337.419186 -255.234769)
			(xy 337.386551 -255.197932) (xy 337.360248 -255.156336) (xy 337.340957 -255.11106) (xy 337.32918 -255.063276)
			(xy 337.32522 -255.014222) (xy 336.996532 -255.014222) (xy 336.996037 -255.038829) (xy 336.988142 -255.087406)
			(xy 336.972558 -255.134087) (xy 336.949687 -255.177664) (xy 336.920122 -255.217008) (xy 336.884629 -255.2511)
			(xy 336.844126 -255.279056) (xy 336.799664 -255.300154) (xy 336.752393 -255.313846) (xy 336.703538 -255.319778)
			(xy 336.654363 -255.317797) (xy 336.606144 -255.307953) (xy 336.560128 -255.290501) (xy 336.517507 -255.265894)
			(xy 336.479386 -255.234769) (xy 336.446751 -255.197932) (xy 336.420448 -255.156336) (xy 336.401157 -255.11106)
			(xy 336.38938 -255.063276) (xy 336.38542 -255.014222) (xy 336.056478 -255.014222) (xy 336.055983 -255.038829)
			(xy 336.048088 -255.087406) (xy 336.032504 -255.134087) (xy 336.009633 -255.177664) (xy 335.980068 -255.217008)
			(xy 335.944575 -255.2511) (xy 335.904072 -255.279056) (xy 335.85961 -255.300154) (xy 335.812339 -255.313846)
			(xy 335.763484 -255.319778) (xy 335.714309 -255.317797) (xy 335.66609 -255.307953) (xy 335.620074 -255.290501)
			(xy 335.577453 -255.265894) (xy 335.539332 -255.234769) (xy 335.506697 -255.197932) (xy 335.480394 -255.156336)
			(xy 335.461103 -255.11106) (xy 335.449326 -255.063276) (xy 335.445366 -255.014222) (xy 335.116907 -255.014222)
			(xy 335.112738 -255.064533) (xy 335.100341 -255.113493) (xy 335.080053 -255.159745) (xy 335.05243 -255.202026)
			(xy 335.018225 -255.239185) (xy 334.97837 -255.270208) (xy 334.933953 -255.294247) (xy 334.886185 -255.310648)
			(xy 334.836369 -255.318963) (xy 334.811116 -255.31953) (xy 334.787546 -255.319095) (xy 334.740964 -255.311856)
			(xy 334.696046 -255.297549) (xy 334.65386 -255.276513) (xy 334.615405 -255.249246) (xy 334.581594 -255.216397)
			(xy 334.567022 -255.197864) (xy 334.56499 -255.19507) (xy 334.55991 -255.18999) (xy 334.553343 -255.183873)
			(xy 334.537071 -255.17633) (xy 334.52816 -255.175258) (xy 334.522572 -255.17475) (xy 334.432148 -255.186942)
			(xy 334.42323 -255.188488) (xy 334.40724 -255.196939) (xy 334.395182 -255.21042) (xy 334.391508 -255.218692)
			(xy 334.383584 -255.238398) (xy 334.365147 -255.276666) (xy 334.354678 -255.295146) (xy 334.312768 -255.367282)
			(xy 334.311498 -255.36906) (xy 334.303878 -255.38049) (xy 334.3021 -255.407668) (xy 334.338676 -255.48209)
			(xy 334.341549 -255.487425) (xy 334.349375 -255.496673) (xy 334.35417 -255.500378) (xy 334.382618 -255.52146)
			(xy 334.394302 -255.523492) (xy 334.417453 -255.52802) (xy 334.462094 -255.543259) (xy 334.503859 -255.565184)
			(xy 334.541754 -255.593274) (xy 334.574878 -255.626858) (xy 334.60244 -255.665139) (xy 334.623785 -255.707203)
			(xy 334.638406 -255.752051) (xy 334.645953 -255.798614) (xy 334.646524 -255.822196) (xy 334.646524 -255.823466)
			(xy 334.645995 -255.850749) (xy 334.636436 -255.90447) (xy 334.617476 -255.955633) (xy 334.604106 -255.979422)
			(xy 334.60055 -255.985518) (xy 334.596486 -256.00025) (xy 334.594602 -256.008934) (xy 334.596201 -256.026617)
			(xy 334.603703 -256.04271) (xy 334.609694 -256.049272) (xy 334.640936 -256.080514) (xy 334.641444 -256.081022)
			(xy 334.648823 -256.087609) (xy 334.667123 -256.095068) (xy 334.677004 -256.0955) (xy 334.91297 -256.0955)
			(xy 334.921519 -256.095178) (xy 334.937665 -256.089558) (xy 334.951061 -256.078934) (xy 334.955896 -256.071878)
			(xy 335.007712 -255.990598) (xy 335.00949 -255.964944) (xy 335.003902 -255.953006) (xy 334.994993 -255.932853)
			(xy 334.982428 -255.890622) (xy 334.976087 -255.84702) (xy 334.975708 -255.82499) (xy 334.975708 -255.824228)
			(xy 334.97623 -255.798973) (xy 334.984543 -255.749151) (xy 335.000944 -255.701377) (xy 335.024985 -255.656954)
			(xy 335.056009 -255.617094) (xy 335.093171 -255.582884) (xy 335.135457 -255.555258) (xy 335.181713 -255.534968)
			(xy 335.230678 -255.522568) (xy 335.281016 -255.518397) (xy 335.331354 -255.522568) (xy 335.380319 -255.534968)
			(xy 335.426575 -255.555258) (xy 335.468861 -255.582884) (xy 335.506023 -255.617094) (xy 335.537047 -255.656954)
			(xy 335.561088 -255.701377) (xy 335.577489 -255.749151) (xy 335.585802 -255.798973) (xy 335.586324 -255.824228)
			(xy 335.586324 -255.82499) (xy 335.585914 -255.847017) (xy 335.57955 -255.89061) (xy 335.567008 -255.932843)
			(xy 335.55813 -255.953006) (xy 335.552542 -255.964944) (xy 335.55432 -255.990598) (xy 335.606136 -256.071878)
			(xy 335.610962 -256.078482) (xy 335.617594 -256.085309) (xy 335.634558 -256.09391) (xy 335.643982 -256.095246)
			(xy 335.648808 -256.0955) (xy 335.853024 -256.0955) (xy 335.861568 -256.09517) (xy 335.877702 -256.089538)
			(xy 335.891083 -256.07891) (xy 335.89595 -256.071878) (xy 335.947766 -255.990598) (xy 335.949544 -255.964944)
			(xy 335.943956 -255.953006) (xy 335.935049 -255.932853) (xy 335.922485 -255.890622) (xy 335.916146 -255.84702)
			(xy 335.915762 -255.82499) (xy 335.915762 -255.824228) (xy 335.916284 -255.798973) (xy 335.924597 -255.749151)
			(xy 335.940998 -255.701377) (xy 335.965039 -255.656954) (xy 335.996063 -255.617094) (xy 336.033225 -255.582884)
			(xy 336.075511 -255.555258) (xy 336.121767 -255.534968) (xy 336.170732 -255.522568) (xy 336.22107 -255.518397)
			(xy 336.271408 -255.522568) (xy 336.320373 -255.534968) (xy 336.366629 -255.555258) (xy 336.408915 -255.582884)
			(xy 336.446077 -255.617094) (xy 336.477101 -255.656954) (xy 336.501142 -255.701377) (xy 336.517543 -255.749151)
			(xy 336.525856 -255.798973) (xy 336.526378 -255.824228) (xy 336.526378 -255.82499) (xy 336.525968 -255.847017)
			(xy 336.519605 -255.890611) (xy 336.507065 -255.932844) (xy 336.498184 -255.953006) (xy 336.492596 -255.964944)
			(xy 336.494374 -255.990598) (xy 336.54619 -256.071878) (xy 336.551016 -256.078482) (xy 336.557646 -256.085315)
			(xy 336.574607 -256.093931) (xy 336.584036 -256.095246) (xy 336.588862 -256.0955) (xy 336.793078 -256.0955)
			(xy 336.801626 -256.095177) (xy 336.817771 -256.089555) (xy 336.831164 -256.078931) (xy 336.836004 -256.071878)
			(xy 336.88782 -255.990598) (xy 336.889598 -255.964944) (xy 336.88401 -255.953006) (xy 336.875104 -255.932853)
			(xy 336.862543 -255.890622) (xy 336.856204 -255.84702) (xy 336.855816 -255.82499) (xy 336.855816 -255.824228)
			(xy 336.856338 -255.798973) (xy 336.864651 -255.749151) (xy 336.881052 -255.701377) (xy 336.905093 -255.656954)
			(xy 336.936117 -255.617094) (xy 336.973279 -255.582884) (xy 337.015565 -255.555258) (xy 337.061821 -255.534968)
			(xy 337.110786 -255.522568) (xy 337.161124 -255.518397) (xy 337.211462 -255.522568) (xy 337.260427 -255.534968)
			(xy 337.306683 -255.555258) (xy 337.348969 -255.582884) (xy 337.386131 -255.617094) (xy 337.417155 -255.656954)
			(xy 337.441196 -255.701377) (xy 337.457597 -255.749151) (xy 337.46591 -255.798973) (xy 337.466432 -255.824228)
			(xy 337.466432 -255.82499) (xy 337.466022 -255.847017) (xy 337.459658 -255.89061) (xy 337.447116 -255.932843)
			(xy 337.438238 -255.953006) (xy 337.43265 -255.964944) (xy 337.434428 -255.990598) (xy 337.486244 -256.071878)
			(xy 337.49107 -256.078482) (xy 337.497703 -256.085307) (xy 337.514667 -256.093906) (xy 337.52409 -256.095246)
			(xy 337.528916 -256.0955) (xy 337.733132 -256.0955) (xy 337.741675 -256.095169) (xy 337.757807 -256.089535)
			(xy 337.771186 -256.078906) (xy 337.776058 -256.071878) (xy 337.827874 -255.990598) (xy 337.829652 -255.964944)
			(xy 337.824064 -255.953006) (xy 337.815156 -255.932853) (xy 337.802593 -255.890622) (xy 337.796253 -255.84702)
			(xy 337.79587 -255.82499) (xy 337.79587 -255.824228) (xy 337.796392 -255.798973) (xy 337.804705 -255.749151)
			(xy 337.821106 -255.701377) (xy 337.845147 -255.656954) (xy 337.876171 -255.617094) (xy 337.913333 -255.582884)
			(xy 337.955619 -255.555258) (xy 338.001875 -255.534968) (xy 338.05084 -255.522568) (xy 338.101178 -255.518397)
			(xy 338.151516 -255.522568) (xy 338.200481 -255.534968) (xy 338.246737 -255.555258) (xy 338.289023 -255.582884)
			(xy 338.326185 -255.617094) (xy 338.357209 -255.656954) (xy 338.38125 -255.701377) (xy 338.397651 -255.749151)
			(xy 338.405964 -255.798973) (xy 338.406486 -255.824228) (xy 338.406486 -255.82499) (xy 338.406076 -255.847017)
			(xy 338.399711 -255.89061) (xy 338.387167 -255.932842) (xy 338.378292 -255.953006) (xy 338.372704 -255.964944)
			(xy 338.374482 -255.990598) (xy 338.426298 -256.071878) (xy 338.431124 -256.078482) (xy 338.437754 -256.085314)
			(xy 338.454716 -256.093928) (xy 338.464144 -256.095246) (xy 338.46897 -256.0955) (xy 338.673186 -256.0955)
			(xy 338.683458 -256.094982) (xy 338.702337 -256.086867) (xy 338.709762 -256.079752) (xy 338.733384 -256.055114)
			(xy 338.73059 -256.048764) (xy 338.761578 -256.00025) (xy 338.762848 -255.974088) (xy 338.757006 -255.96215)
			(xy 338.746989 -255.940553) (xy 338.732845 -255.895096) (xy 338.725689 -255.848031) (xy 338.725256 -255.824228)
			(xy 338.725743 -255.799418) (xy 338.733505 -255.75041) (xy 338.748838 -255.70322) (xy 338.771365 -255.659009)
			(xy 338.80053 -255.618866) (xy 338.835616 -255.58378) (xy 338.875759 -255.554615) (xy 338.91997 -255.532088)
			(xy 338.96716 -255.516755) (xy 339.016168 -255.508993) (xy 339.065788 -255.508993) (xy 339.114796 -255.516755)
			(xy 339.161986 -255.532088) (xy 339.206197 -255.554615) (xy 339.24634 -255.58378) (xy 339.281426 -255.618866)
			(xy 339.310591 -255.659009) (xy 339.333118 -255.70322) (xy 339.348451 -255.75041) (xy 339.356213 -255.799418)
			(xy 339.3567 -255.824228) (xy 339.356264 -255.84803) (xy 339.349105 -255.895094) (xy 339.334955 -255.940548)
			(xy 339.32495 -255.96215) (xy 339.319108 -255.974088) (xy 339.320632 -256.00025) (xy 339.365844 -256.071878)
			(xy 339.372448 -256.080006) (xy 339.378927 -256.086203) (xy 339.395065 -256.093988) (xy 339.403944 -256.095246)
			(xy 339.40877 -256.0955) (xy 339.61324 -256.0955) (xy 339.623507 -256.094972) (xy 339.642372 -256.086843)
			(xy 339.649816 -256.079752) (xy 339.673438 -256.055114) (xy 339.670644 -256.048764) (xy 339.701632 -256.000504)
			(xy 339.703156 -255.974342) (xy 339.697314 -255.96215) (xy 339.687297 -255.940553) (xy 339.673152 -255.895096)
			(xy 339.665997 -255.848031) (xy 339.665564 -255.824228) (xy 339.66605 -255.799438) (xy 339.673806 -255.75047)
			(xy 339.689127 -255.703317) (xy 339.711636 -255.659142) (xy 339.740778 -255.619031) (xy 339.775835 -255.583974)
			(xy 339.815946 -255.554832) (xy 339.860121 -255.532323) (xy 339.907274 -255.517002) (xy 339.956242 -255.509246)
			(xy 340.005822 -255.509246) (xy 340.05479 -255.517002) (xy 340.101943 -255.532323) (xy 340.146118 -255.554832)
			(xy 340.186229 -255.583974) (xy 340.221286 -255.619031) (xy 340.250428 -255.659142) (xy 340.272937 -255.703317)
			(xy 340.288258 -255.75047) (xy 340.296014 -255.799438) (xy 340.2965 -255.824228) (xy 340.296103 -255.848022)
			(xy 340.28903 -255.895079) (xy 340.274971 -255.940541) (xy 340.265004 -255.96215) (xy 340.259162 -255.974088)
			(xy 340.260686 -256.00025) (xy 340.305898 -256.071878) (xy 340.312502 -256.080006) (xy 340.318979 -256.086209)
			(xy 340.335115 -256.094009) (xy 340.343998 -256.095246) (xy 340.348824 -256.0955) (xy 340.55304 -256.0955)
			(xy 340.561583 -256.095167) (xy 340.577713 -256.089532) (xy 340.59109 -256.078902) (xy 340.595966 -256.071878)
			(xy 340.647782 -255.990598) (xy 340.64956 -255.964944) (xy 340.643972 -255.953006) (xy 340.635064 -255.932853)
			(xy 340.6225 -255.890622) (xy 340.61616 -255.84702) (xy 340.615778 -255.82499) (xy 340.615778 -255.824228)
			(xy 340.6163 -255.798973) (xy 340.624613 -255.749151) (xy 340.641014 -255.701377) (xy 340.665055 -255.656954)
			(xy 340.696079 -255.617094) (xy 340.733241 -255.582884) (xy 340.775527 -255.555258) (xy 340.821783 -255.534968)
			(xy 340.870748 -255.522568) (xy 340.921086 -255.518397) (xy 340.971424 -255.522568) (xy 341.020389 -255.534968)
			(xy 341.066645 -255.555258) (xy 341.108931 -255.582884) (xy 341.146093 -255.617094) (xy 341.177117 -255.656954)
			(xy 341.201158 -255.701377) (xy 341.217559 -255.749151) (xy 341.225872 -255.798973) (xy 341.226394 -255.824228)
			(xy 341.226394 -255.82499) (xy 341.225984 -255.847017) (xy 341.219619 -255.89061) (xy 341.207076 -255.932842)
			(xy 341.1982 -255.953006) (xy 341.192612 -255.964944) (xy 341.19439 -255.990598) (xy 341.246206 -256.071878)
			(xy 341.251032 -256.078482) (xy 341.257662 -256.085312) (xy 341.274625 -256.093924) (xy 341.284052 -256.095246)
			(xy 341.288878 -256.0955) (xy 341.493348 -256.0955) (xy 341.503615 -256.09497) (xy 341.522477 -256.08684)
			(xy 341.529924 -256.079752) (xy 341.553546 -256.055114) (xy 341.550752 -256.048764) (xy 341.58174 -256.000504)
			(xy 341.583264 -255.974342) (xy 341.577422 -255.96215) (xy 341.567405 -255.940553) (xy 341.55326 -255.895097)
			(xy 341.546104 -255.848031) (xy 341.545672 -255.824228) (xy 341.546158 -255.799438) (xy 341.553914 -255.75047)
			(xy 341.569235 -255.703317) (xy 341.591744 -255.659142) (xy 341.620886 -255.619031) (xy 341.655943 -255.583974)
			(xy 341.696054 -255.554832) (xy 341.740229 -255.532323) (xy 341.787382 -255.517002) (xy 341.83635 -255.509246)
			(xy 341.88593 -255.509246) (xy 341.934898 -255.517002) (xy 341.982051 -255.532323) (xy 342.026226 -255.554832)
			(xy 342.066337 -255.583974) (xy 342.101394 -255.619031) (xy 342.130536 -255.659142) (xy 342.153045 -255.703317)
			(xy 342.168366 -255.75047) (xy 342.176122 -255.799438) (xy 342.176608 -255.824228) (xy 342.176211 -255.848021)
			(xy 342.169135 -255.895078) (xy 342.155073 -255.940538) (xy 342.145112 -255.96215) (xy 342.13927 -255.974088)
			(xy 342.140794 -256.00025) (xy 342.186006 -256.071878) (xy 342.19261 -256.080006) (xy 342.199087 -256.086208)
			(xy 342.215224 -256.094006) (xy 342.224106 -256.095246) (xy 342.228932 -256.0955) (xy 342.433148 -256.0955)
			(xy 342.44169 -256.095166) (xy 342.457818 -256.089529) (xy 342.471193 -256.078899) (xy 342.476074 -256.071878)
			(xy 342.52789 -255.990598) (xy 342.529668 -255.964944) (xy 342.52408 -255.953006) (xy 342.515172 -255.932853)
			(xy 342.502608 -255.890622) (xy 342.496267 -255.84702) (xy 342.495886 -255.82499) (xy 342.495886 -255.824228)
			(xy 342.496408 -255.798973) (xy 342.504721 -255.749151) (xy 342.521122 -255.701377) (xy 342.545163 -255.656954)
			(xy 342.576187 -255.617094) (xy 342.613349 -255.582884) (xy 342.655635 -255.555258) (xy 342.701891 -255.534968)
			(xy 342.750856 -255.522568) (xy 342.801194 -255.518397) (xy 342.851532 -255.522568) (xy 342.900497 -255.534968)
			(xy 342.946753 -255.555258) (xy 342.989039 -255.582884) (xy 343.026201 -255.617094) (xy 343.057225 -255.656954)
			(xy 343.081266 -255.701377) (xy 343.097667 -255.749151) (xy 343.10598 -255.798973) (xy 343.106502 -255.824228)
			(xy 343.106502 -255.82499) (xy 343.106092 -255.847017) (xy 343.099727 -255.89061) (xy 343.087184 -255.932842)
			(xy 343.078308 -255.953006) (xy 343.07272 -255.964944) (xy 343.074498 -255.990598) (xy 343.126314 -256.071878)
			(xy 343.13114 -256.078482) (xy 343.137771 -256.085311) (xy 343.154734 -256.09392) (xy 343.16416 -256.095246)
			(xy 343.168986 -256.0955) (xy 343.373202 -256.0955) (xy 343.383472 -256.094979) (xy 343.402347 -256.08686)
			(xy 343.409778 -256.079752) (xy 343.4334 -256.055114) (xy 343.430606 -256.048764) (xy 343.461594 -256.00025)
			(xy 343.462864 -255.974088) (xy 343.457022 -255.96215) (xy 343.447005 -255.940553) (xy 343.43286 -255.895097)
			(xy 343.425704 -255.848031) (xy 343.425272 -255.824228) (xy 343.425759 -255.799418) (xy 343.433521 -255.75041)
			(xy 343.448854 -255.70322) (xy 343.471381 -255.659009) (xy 343.500546 -255.618866) (xy 343.535632 -255.58378)
			(xy 343.575775 -255.554615) (xy 343.619986 -255.532088) (xy 343.667176 -255.516755) (xy 343.716184 -255.508993)
			(xy 343.765804 -255.508993) (xy 343.814812 -255.516755) (xy 343.862002 -255.532088) (xy 343.906213 -255.554615)
			(xy 343.946356 -255.58378) (xy 343.981442 -255.618866) (xy 344.010607 -255.659009) (xy 344.033134 -255.70322)
			(xy 344.048467 -255.75041) (xy 344.056229 -255.799418) (xy 344.056716 -255.824228) (xy 344.05628 -255.848031)
			(xy 344.049122 -255.895094) (xy 344.034972 -255.940548) (xy 344.024966 -255.96215) (xy 344.019124 -255.974088)
			(xy 344.020648 -256.00025) (xy 344.06586 -256.071878) (xy 344.072464 -256.080006) (xy 344.078939 -256.086214)
			(xy 344.095074 -256.094026) (xy 344.10396 -256.095246) (xy 344.108786 -256.0955) (xy 344.442542 -256.0955)
			(xy 344.446352 -256.09931) (xy 345.254834 -256.09931) (xy 345.263378 -256.098978) (xy 345.27951 -256.093345)
			(xy 345.29289 -256.082717) (xy 345.29776 -256.075688) (xy 345.349576 -255.9939) (xy 345.351354 -255.967738)
			(xy 345.345512 -255.9558) (xy 345.336135 -255.935148) (xy 345.322897 -255.891766) (xy 345.316211 -255.846906)
			(xy 345.315794 -255.824228) (xy 345.315794 -255.81864) (xy 345.316748 -255.793687) (xy 345.325772 -255.744578)
			(xy 345.342665 -255.69759) (xy 345.366978 -255.653977) (xy 345.398063 -255.614901) (xy 345.435091 -255.581403)
			(xy 345.477075 -255.554375) (xy 345.522897 -255.534538) (xy 345.571337 -255.522421) (xy 345.621102 -255.518345)
			(xy 345.670867 -255.522421) (xy 345.719307 -255.534538) (xy 345.765129 -255.554375) (xy 345.807113 -255.581403)
			(xy 345.844141 -255.614901) (xy 345.875226 -255.653977) (xy 345.899539 -255.69759) (xy 345.916432 -255.744578)
			(xy 345.925456 -255.793687) (xy 345.92641 -255.81864) (xy 345.92641 -255.820926) (xy 345.92641 -255.824228)
			(xy 345.926021 -255.846909) (xy 345.919351 -255.891777) (xy 345.906103 -255.93516) (xy 345.896692 -255.9558)
			(xy 345.89085 -255.967738) (xy 345.892628 -255.9939) (xy 345.944444 -256.075688) (xy 345.949292 -256.082737)
			(xy 345.96268 -256.09337) (xy 345.978822 -256.099006) (xy 345.98737 -256.09931) (xy 347.134942 -256.09931)
			(xy 347.143485 -256.098977) (xy 347.159615 -256.093342) (xy 347.172993 -256.082713) (xy 347.177868 -256.075688)
			(xy 347.229684 -255.9939) (xy 347.231462 -255.967738) (xy 347.22562 -255.9558) (xy 347.216242 -255.935148)
			(xy 347.203005 -255.891766) (xy 347.196318 -255.846906) (xy 347.195902 -255.824228) (xy 347.195902 -255.81864)
			(xy 347.196856 -255.793687) (xy 347.20588 -255.744578) (xy 347.222773 -255.69759) (xy 347.247086 -255.653977)
			(xy 347.278171 -255.614901) (xy 347.315199 -255.581403) (xy 347.357183 -255.554375) (xy 347.403005 -255.534538)
			(xy 347.451445 -255.522421) (xy 347.50121 -255.518345) (xy 347.550975 -255.522421) (xy 347.599415 -255.534538)
			(xy 347.645237 -255.554375) (xy 347.687221 -255.581403) (xy 347.724249 -255.614901) (xy 347.755334 -255.653977)
			(xy 347.779647 -255.69759) (xy 347.79654 -255.744578) (xy 347.805564 -255.793687) (xy 347.806518 -255.81864)
			(xy 347.806518 -255.820926) (xy 347.806518 -255.824228) (xy 348.135206 -255.824228) (xy 348.139166 -255.775174)
			(xy 348.150943 -255.72739) (xy 348.170234 -255.682114) (xy 348.196537 -255.640518) (xy 348.229172 -255.603681)
			(xy 348.267293 -255.572556) (xy 348.309914 -255.547949) (xy 348.35593 -255.530497) (xy 348.404149 -255.520653)
			(xy 348.453324 -255.518672) (xy 348.502179 -255.524604) (xy 348.54945 -255.538296) (xy 348.593912 -255.559394)
			(xy 348.634415 -255.58735) (xy 348.669908 -255.621442) (xy 348.699473 -255.660786) (xy 348.722344 -255.704363)
			(xy 348.737928 -255.751044) (xy 348.745823 -255.799621) (xy 348.746318 -255.824228) (xy 349.07526 -255.824228)
			(xy 349.07922 -255.775174) (xy 349.090997 -255.72739) (xy 349.110288 -255.682114) (xy 349.136591 -255.640518)
			(xy 349.169226 -255.603681) (xy 349.207347 -255.572556) (xy 349.249968 -255.547949) (xy 349.295984 -255.530497)
			(xy 349.344203 -255.520653) (xy 349.393378 -255.518672) (xy 349.442233 -255.524604) (xy 349.489504 -255.538296)
			(xy 349.533966 -255.559394) (xy 349.574469 -255.58735) (xy 349.609962 -255.621442) (xy 349.639527 -255.660786)
			(xy 349.662398 -255.704363) (xy 349.677982 -255.751044) (xy 349.685877 -255.799621) (xy 349.686372 -255.824228)
			(xy 350.015314 -255.824228) (xy 350.019274 -255.775174) (xy 350.031051 -255.72739) (xy 350.050342 -255.682114)
			(xy 350.076645 -255.640518) (xy 350.10928 -255.603681) (xy 350.147401 -255.572556) (xy 350.190022 -255.547949)
			(xy 350.236038 -255.530497) (xy 350.284257 -255.520653) (xy 350.333432 -255.518672) (xy 350.382287 -255.524604)
			(xy 350.429558 -255.538296) (xy 350.47402 -255.559394) (xy 350.514523 -255.58735) (xy 350.550016 -255.621442)
			(xy 350.579581 -255.660786) (xy 350.602452 -255.704363) (xy 350.618036 -255.751044) (xy 350.625931 -255.799621)
			(xy 350.626385 -255.822196) (xy 350.952066 -255.822196) (xy 350.956026 -255.773142) (xy 350.967803 -255.725358)
			(xy 350.987094 -255.680082) (xy 351.013397 -255.638486) (xy 351.046032 -255.601649) (xy 351.084153 -255.570524)
			(xy 351.126774 -255.545917) (xy 351.17279 -255.528465) (xy 351.221009 -255.518621) (xy 351.270184 -255.51664)
			(xy 351.319039 -255.522572) (xy 351.36631 -255.536264) (xy 351.410772 -255.557362) (xy 351.451275 -255.585318)
			(xy 351.486768 -255.61941) (xy 351.516333 -255.658754) (xy 351.539204 -255.702331) (xy 351.554788 -255.749012)
			(xy 351.562683 -255.797589) (xy 351.563178 -255.822196) (xy 351.89212 -255.822196) (xy 351.89608 -255.773142)
			(xy 351.907857 -255.725358) (xy 351.927148 -255.680082) (xy 351.953451 -255.638486) (xy 351.986086 -255.601649)
			(xy 352.024207 -255.570524) (xy 352.066828 -255.545917) (xy 352.112844 -255.528465) (xy 352.161063 -255.518621)
			(xy 352.210238 -255.51664) (xy 352.259093 -255.522572) (xy 352.285069 -255.530096) (xy 354.001327 -255.530096)
			(xy 354.005357 -255.477598) (xy 354.017354 -255.42633) (xy 354.037037 -255.377495) (xy 354.063943 -255.332236)
			(xy 354.097443 -255.291615) (xy 354.136751 -255.256584) (xy 354.180946 -255.227964) (xy 354.228991 -255.206425)
			(xy 354.279762 -255.192473) (xy 354.332067 -255.186435) (xy 354.384681 -255.188452) (xy 354.436371 -255.198476)
			(xy 354.485924 -255.216274) (xy 354.53218 -255.241427) (xy 354.574054 -255.273346) (xy 354.610566 -255.311284)
			(xy 354.640858 -255.35435) (xy 354.664221 -255.401535) (xy 354.680107 -255.451734) (xy 354.688144 -255.50377)
			(xy 354.688648 -255.530096) (xy 354.688144 -255.556422) (xy 354.680107 -255.608458) (xy 354.664221 -255.658657)
			(xy 354.640858 -255.705842) (xy 354.610566 -255.748908) (xy 354.574054 -255.786846) (xy 354.53218 -255.818765)
			(xy 354.485924 -255.843918) (xy 354.436371 -255.861716) (xy 354.384681 -255.87174) (xy 354.332067 -255.873757)
			(xy 354.279762 -255.867719) (xy 354.228991 -255.853767) (xy 354.180946 -255.832228) (xy 354.136751 -255.803608)
			(xy 354.097443 -255.768577) (xy 354.063943 -255.727956) (xy 354.037037 -255.682697) (xy 354.017354 -255.633862)
			(xy 354.005357 -255.582594) (xy 354.001327 -255.530096) (xy 352.285069 -255.530096) (xy 352.306364 -255.536264)
			(xy 352.350826 -255.557362) (xy 352.391329 -255.585318) (xy 352.426822 -255.61941) (xy 352.456387 -255.658754)
			(xy 352.479258 -255.702331) (xy 352.494842 -255.749012) (xy 352.502737 -255.797589) (xy 352.503232 -255.822196)
			(xy 352.502737 -255.846803) (xy 352.494842 -255.89538) (xy 352.479258 -255.942061) (xy 352.456387 -255.985638)
			(xy 352.426822 -256.024982) (xy 352.391329 -256.059074) (xy 352.350826 -256.08703) (xy 352.306364 -256.108128)
			(xy 352.259093 -256.12182) (xy 352.210238 -256.127752) (xy 352.161063 -256.125771) (xy 352.112844 -256.115927)
			(xy 352.066828 -256.098475) (xy 352.024207 -256.073868) (xy 351.986086 -256.042743) (xy 351.953451 -256.005906)
			(xy 351.927148 -255.96431) (xy 351.907857 -255.919034) (xy 351.89608 -255.87125) (xy 351.89212 -255.822196)
			(xy 351.563178 -255.822196) (xy 351.562683 -255.846803) (xy 351.554788 -255.89538) (xy 351.539204 -255.942061)
			(xy 351.516333 -255.985638) (xy 351.486768 -256.024982) (xy 351.451275 -256.059074) (xy 351.410772 -256.08703)
			(xy 351.36631 -256.108128) (xy 351.319039 -256.12182) (xy 351.270184 -256.127752) (xy 351.221009 -256.125771)
			(xy 351.17279 -256.115927) (xy 351.126774 -256.098475) (xy 351.084153 -256.073868) (xy 351.046032 -256.042743)
			(xy 351.013397 -256.005906) (xy 350.987094 -255.96431) (xy 350.967803 -255.919034) (xy 350.956026 -255.87125)
			(xy 350.952066 -255.822196) (xy 350.626385 -255.822196) (xy 350.626426 -255.824228) (xy 350.625931 -255.848835)
			(xy 350.618036 -255.897412) (xy 350.602452 -255.944093) (xy 350.579581 -255.98767) (xy 350.550016 -256.027014)
			(xy 350.514523 -256.061106) (xy 350.47402 -256.089062) (xy 350.429558 -256.11016) (xy 350.382287 -256.123852)
			(xy 350.333432 -256.129784) (xy 350.284257 -256.127803) (xy 350.236038 -256.117959) (xy 350.190022 -256.100507)
			(xy 350.147401 -256.0759) (xy 350.10928 -256.044775) (xy 350.076645 -256.007938) (xy 350.050342 -255.966342)
			(xy 350.031051 -255.921066) (xy 350.019274 -255.873282) (xy 350.015314 -255.824228) (xy 349.686372 -255.824228)
			(xy 349.685877 -255.848835) (xy 349.677982 -255.897412) (xy 349.662398 -255.944093) (xy 349.639527 -255.98767)
			(xy 349.609962 -256.027014) (xy 349.574469 -256.061106) (xy 349.533966 -256.089062) (xy 349.489504 -256.11016)
			(xy 349.442233 -256.123852) (xy 349.393378 -256.129784) (xy 349.344203 -256.127803) (xy 349.295984 -256.117959)
			(xy 349.249968 -256.100507) (xy 349.207347 -256.0759) (xy 349.169226 -256.044775) (xy 349.136591 -256.007938)
			(xy 349.110288 -255.966342) (xy 349.090997 -255.921066) (xy 349.07922 -255.873282) (xy 349.07526 -255.824228)
			(xy 348.746318 -255.824228) (xy 348.745823 -255.848835) (xy 348.737928 -255.897412) (xy 348.722344 -255.944093)
			(xy 348.699473 -255.98767) (xy 348.669908 -256.027014) (xy 348.634415 -256.061106) (xy 348.593912 -256.089062)
			(xy 348.54945 -256.11016) (xy 348.502179 -256.123852) (xy 348.453324 -256.129784) (xy 348.404149 -256.127803)
			(xy 348.35593 -256.117959) (xy 348.309914 -256.100507) (xy 348.267293 -256.0759) (xy 348.229172 -256.044775)
			(xy 348.196537 -256.007938) (xy 348.170234 -255.966342) (xy 348.150943 -255.921066) (xy 348.139166 -255.873282)
			(xy 348.135206 -255.824228) (xy 347.806518 -255.824228) (xy 347.806129 -255.846909) (xy 347.799459 -255.891777)
			(xy 347.786212 -255.935161) (xy 347.7768 -255.9558) (xy 347.770958 -255.967738) (xy 347.772736 -255.9939)
			(xy 347.824552 -256.075688) (xy 347.8294 -256.082736) (xy 347.842789 -256.093367) (xy 347.85893 -256.099)
			(xy 347.867478 -256.09931) (xy 347.98508 -256.09931) (xy 347.994916 -256.099848) (xy 348.013074 -256.107439)
			(xy 348.020386 -256.114042) (xy 348.462854 -256.55651) (xy 348.472309 -256.564932) (xy 348.496558 -256.572106)
			(xy 348.509082 -256.570226) (xy 348.589854 -256.553208) (xy 348.60096 -256.550231) (xy 348.619171 -256.536249)
			(xy 348.624906 -256.526284) (xy 348.62643 -256.523236) (xy 348.627192 -256.521204) (xy 348.637338 -256.497235)
			(xy 348.664559 -256.452876) (xy 348.698896 -256.413765) (xy 348.739359 -256.381032) (xy 348.784779 -256.35562)
			(xy 348.833845 -256.338264) (xy 348.885141 -256.329465) (xy 348.911164 -256.328926) (xy 348.937124 -256.329443)
			(xy 348.988296 -256.338216) (xy 349.037249 -256.355514) (xy 349.082572 -256.380841) (xy 349.12296 -256.413466)
			(xy 349.15725 -256.452451) (xy 349.184455 -256.496671) (xy 349.203791 -256.544855) (xy 349.214702 -256.595615)
			(xy 349.216218 -256.621534) (xy 349.216472 -256.62763) (xy 349.216472 -256.634234) (xy 349.216038 -256.657414)
			(xy 349.209021 -256.703241) (xy 349.195152 -256.747478) (xy 349.174753 -256.789109) (xy 349.14829 -256.827176)
			(xy 349.132652 -256.844292) (xy 349.132398 -256.844546) (xy 349.12597 -256.852092) (xy 349.118881 -256.870583)
			(xy 349.119264 -256.890383) (xy 349.122746 -256.899664) (xy 349.15856 -256.982976) (xy 349.1629 -256.99189)
			(xy 349.177041 -257.005757) (xy 349.195391 -257.013212) (xy 349.205296 -257.01371) (xy 349.557086 -257.01371)
			(xy 349.566986 -257.013232) (xy 349.585311 -257.005732) (xy 349.599452 -256.991873) (xy 349.603822 -256.982976)
			(xy 349.639636 -256.899664) (xy 349.643167 -256.890389) (xy 349.643593 -256.870568) (xy 349.636452 -256.852073)
			(xy 349.629984 -256.844546) (xy 349.62973 -256.844292) (xy 349.614082 -256.827184) (xy 349.587616 -256.789118)
			(xy 349.567217 -256.747485) (xy 349.553354 -256.703244) (xy 349.546347 -256.657415) (xy 349.54591 -256.634234)
			(xy 349.54591 -256.62763) (xy 349.546164 -256.621534) (xy 349.54768 -256.596989) (xy 349.557573 -256.548822)
			(xy 349.575058 -256.502863) (xy 349.599684 -256.4603) (xy 349.630812 -256.422234) (xy 349.667639 -256.38965)
			(xy 349.709213 -256.363389) (xy 349.754458 -256.34413) (xy 349.802204 -256.332373) (xy 349.851218 -256.328419)
			(xy 349.900232 -256.332373) (xy 349.947978 -256.34413) (xy 349.993223 -256.363389) (xy 350.034797 -256.38965)
			(xy 350.071624 -256.422234) (xy 350.102752 -256.4603) (xy 350.127378 -256.502863) (xy 350.144863 -256.548822)
			(xy 350.154756 -256.596989) (xy 350.156272 -256.621534) (xy 350.156526 -256.62763) (xy 350.156526 -256.634234)
			(xy 350.156092 -256.657414) (xy 350.149074 -256.70324) (xy 350.135204 -256.747476) (xy 350.114802 -256.789105)
			(xy 350.088337 -256.827169) (xy 350.072706 -256.844292) (xy 350.072452 -256.844546) (xy 350.066018 -256.85209)
			(xy 350.058921 -256.870582) (xy 350.059306 -256.890386) (xy 350.0628 -256.899664) (xy 350.098614 -256.982976)
			(xy 350.102951 -256.991895) (xy 350.117091 -257.005775) (xy 350.135442 -257.013246) (xy 350.14535 -257.01371)
			(xy 350.497902 -257.01371) (xy 350.510546 -257.013036) (xy 350.532809 -257.001043) (xy 350.54032 -256.99085)
			(xy 350.543114 -256.986532) (xy 350.586294 -256.884932) (xy 350.580706 -256.855214) (xy 350.570038 -256.844038)
			(xy 350.554209 -256.82687) (xy 350.527421 -256.788623) (xy 350.506768 -256.746745) (xy 350.492731 -256.70221)
			(xy 350.485636 -256.656057) (xy 350.485202 -256.63271) (xy 350.485724 -256.607455) (xy 350.494037 -256.557633)
			(xy 350.510438 -256.509859) (xy 350.534479 -256.465436) (xy 350.565503 -256.425576) (xy 350.602665 -256.391366)
			(xy 350.644951 -256.36374) (xy 350.691207 -256.34345) (xy 350.740172 -256.33105) (xy 350.79051 -256.326879)
			(xy 350.840848 -256.33105) (xy 350.889813 -256.34345) (xy 350.936069 -256.36374) (xy 350.978355 -256.391366)
			(xy 351.015517 -256.425576) (xy 351.046541 -256.465436) (xy 351.054453 -256.480056) (xy 354.001327 -256.480056)
			(xy 354.005357 -256.427558) (xy 354.017354 -256.37629) (xy 354.037037 -256.327455) (xy 354.063943 -256.282196)
			(xy 354.097443 -256.241575) (xy 354.136751 -256.206544) (xy 354.180946 -256.177924) (xy 354.228991 -256.156385)
			(xy 354.279762 -256.142433) (xy 354.332067 -256.136395) (xy 354.384681 -256.138412) (xy 354.436371 -256.148436)
			(xy 354.485924 -256.166234) (xy 354.53218 -256.191387) (xy 354.574054 -256.223306) (xy 354.610566 -256.261244)
			(xy 354.640858 -256.30431) (xy 354.664221 -256.351495) (xy 354.675566 -256.387346) (xy 355.244149 -256.387346)
			(xy 355.248179 -256.334848) (xy 355.260176 -256.28358) (xy 355.279859 -256.234745) (xy 355.306765 -256.189486)
			(xy 355.340265 -256.148865) (xy 355.379573 -256.113834) (xy 355.423768 -256.085214) (xy 355.471813 -256.063675)
			(xy 355.522584 -256.049723) (xy 355.574889 -256.043685) (xy 355.627503 -256.045702) (xy 355.679193 -256.055726)
			(xy 355.728746 -256.073524) (xy 355.775002 -256.098677) (xy 355.816876 -256.130596) (xy 355.853388 -256.168534)
			(xy 355.88368 -256.2116) (xy 355.907043 -256.258785) (xy 355.922929 -256.308984) (xy 355.930966 -256.36102)
			(xy 355.93147 -256.387346) (xy 356.194109 -256.387346) (xy 356.198139 -256.334848) (xy 356.210136 -256.28358)
			(xy 356.229819 -256.234745) (xy 356.256725 -256.189486) (xy 356.290225 -256.148865) (xy 356.329533 -256.113834)
			(xy 356.373728 -256.085214) (xy 356.421773 -256.063675) (xy 356.472544 -256.049723) (xy 356.524849 -256.043685)
			(xy 356.577463 -256.045702) (xy 356.629153 -256.055726) (xy 356.678706 -256.073524) (xy 356.724962 -256.098677)
			(xy 356.766836 -256.130596) (xy 356.803348 -256.168534) (xy 356.83364 -256.2116) (xy 356.857003 -256.258785)
			(xy 356.872889 -256.308984) (xy 356.880926 -256.36102) (xy 356.88143 -256.387346) (xy 357.144069 -256.387346)
			(xy 357.148099 -256.334848) (xy 357.160096 -256.28358) (xy 357.179779 -256.234745) (xy 357.206685 -256.189486)
			(xy 357.240185 -256.148865) (xy 357.279493 -256.113834) (xy 357.323688 -256.085214) (xy 357.371733 -256.063675)
			(xy 357.422504 -256.049723) (xy 357.474809 -256.043685) (xy 357.527423 -256.045702) (xy 357.579113 -256.055726)
			(xy 357.628666 -256.073524) (xy 357.674922 -256.098677) (xy 357.716796 -256.130596) (xy 357.753308 -256.168534)
			(xy 357.7836 -256.2116) (xy 357.806963 -256.258785) (xy 357.822849 -256.308984) (xy 357.830886 -256.36102)
			(xy 357.83139 -256.387346) (xy 358.094029 -256.387346) (xy 358.098059 -256.334848) (xy 358.110056 -256.28358)
			(xy 358.129739 -256.234745) (xy 358.156645 -256.189486) (xy 358.190145 -256.148865) (xy 358.229453 -256.113834)
			(xy 358.273648 -256.085214) (xy 358.321693 -256.063675) (xy 358.372464 -256.049723) (xy 358.424769 -256.043685)
			(xy 358.477383 -256.045702) (xy 358.529073 -256.055726) (xy 358.578626 -256.073524) (xy 358.624882 -256.098677)
			(xy 358.666756 -256.130596) (xy 358.703268 -256.168534) (xy 358.73356 -256.2116) (xy 358.756923 -256.258785)
			(xy 358.772809 -256.308984) (xy 358.780846 -256.36102) (xy 358.78135 -256.387346) (xy 359.043989 -256.387346)
			(xy 359.048019 -256.334848) (xy 359.060016 -256.28358) (xy 359.079699 -256.234745) (xy 359.106605 -256.189486)
			(xy 359.140105 -256.148865) (xy 359.179413 -256.113834) (xy 359.223608 -256.085214) (xy 359.271653 -256.063675)
			(xy 359.322424 -256.049723) (xy 359.374729 -256.043685) (xy 359.427343 -256.045702) (xy 359.479033 -256.055726)
			(xy 359.528586 -256.073524) (xy 359.574842 -256.098677) (xy 359.616716 -256.130596) (xy 359.653228 -256.168534)
			(xy 359.68352 -256.2116) (xy 359.706883 -256.258785) (xy 359.722769 -256.308984) (xy 359.730806 -256.36102)
			(xy 359.73131 -256.387346) (xy 359.730806 -256.413672) (xy 359.722769 -256.465708) (xy 359.706883 -256.515907)
			(xy 359.68352 -256.563092) (xy 359.653228 -256.606158) (xy 359.616716 -256.644096) (xy 359.574842 -256.676015)
			(xy 359.528586 -256.701168) (xy 359.479033 -256.718966) (xy 359.427343 -256.72899) (xy 359.374729 -256.731007)
			(xy 359.322424 -256.724969) (xy 359.271653 -256.711017) (xy 359.223608 -256.689478) (xy 359.179413 -256.660858)
			(xy 359.140105 -256.625827) (xy 359.106605 -256.585206) (xy 359.079699 -256.539947) (xy 359.060016 -256.491112)
			(xy 359.048019 -256.439844) (xy 359.043989 -256.387346) (xy 358.78135 -256.387346) (xy 358.780846 -256.413672)
			(xy 358.772809 -256.465708) (xy 358.756923 -256.515907) (xy 358.73356 -256.563092) (xy 358.703268 -256.606158)
			(xy 358.666756 -256.644096) (xy 358.624882 -256.676015) (xy 358.578626 -256.701168) (xy 358.529073 -256.718966)
			(xy 358.477383 -256.72899) (xy 358.424769 -256.731007) (xy 358.372464 -256.724969) (xy 358.321693 -256.711017)
			(xy 358.273648 -256.689478) (xy 358.229453 -256.660858) (xy 358.190145 -256.625827) (xy 358.156645 -256.585206)
			(xy 358.129739 -256.539947) (xy 358.110056 -256.491112) (xy 358.098059 -256.439844) (xy 358.094029 -256.387346)
			(xy 357.83139 -256.387346) (xy 357.830886 -256.413672) (xy 357.822849 -256.465708) (xy 357.806963 -256.515907)
			(xy 357.7836 -256.563092) (xy 357.753308 -256.606158) (xy 357.716796 -256.644096) (xy 357.674922 -256.676015)
			(xy 357.628666 -256.701168) (xy 357.579113 -256.718966) (xy 357.527423 -256.72899) (xy 357.474809 -256.731007)
			(xy 357.422504 -256.724969) (xy 357.371733 -256.711017) (xy 357.323688 -256.689478) (xy 357.279493 -256.660858)
			(xy 357.240185 -256.625827) (xy 357.206685 -256.585206) (xy 357.179779 -256.539947) (xy 357.160096 -256.491112)
			(xy 357.148099 -256.439844) (xy 357.144069 -256.387346) (xy 356.88143 -256.387346) (xy 356.880926 -256.413672)
			(xy 356.872889 -256.465708) (xy 356.857003 -256.515907) (xy 356.83364 -256.563092) (xy 356.803348 -256.606158)
			(xy 356.766836 -256.644096) (xy 356.724962 -256.676015) (xy 356.678706 -256.701168) (xy 356.629153 -256.718966)
			(xy 356.577463 -256.72899) (xy 356.524849 -256.731007) (xy 356.472544 -256.724969) (xy 356.421773 -256.711017)
			(xy 356.373728 -256.689478) (xy 356.329533 -256.660858) (xy 356.290225 -256.625827) (xy 356.256725 -256.585206)
			(xy 356.229819 -256.539947) (xy 356.210136 -256.491112) (xy 356.198139 -256.439844) (xy 356.194109 -256.387346)
			(xy 355.93147 -256.387346) (xy 355.930966 -256.413672) (xy 355.922929 -256.465708) (xy 355.907043 -256.515907)
			(xy 355.88368 -256.563092) (xy 355.853388 -256.606158) (xy 355.816876 -256.644096) (xy 355.775002 -256.676015)
			(xy 355.728746 -256.701168) (xy 355.679193 -256.718966) (xy 355.627503 -256.72899) (xy 355.574889 -256.731007)
			(xy 355.522584 -256.724969) (xy 355.471813 -256.711017) (xy 355.423768 -256.689478) (xy 355.379573 -256.660858)
			(xy 355.340265 -256.625827) (xy 355.306765 -256.585206) (xy 355.279859 -256.539947) (xy 355.260176 -256.491112)
			(xy 355.248179 -256.439844) (xy 355.244149 -256.387346) (xy 354.675566 -256.387346) (xy 354.680107 -256.401694)
			(xy 354.688144 -256.45373) (xy 354.688648 -256.480056) (xy 354.688144 -256.506382) (xy 354.680107 -256.558418)
			(xy 354.664221 -256.608617) (xy 354.640858 -256.655802) (xy 354.610566 -256.698868) (xy 354.574054 -256.736806)
			(xy 354.53218 -256.768725) (xy 354.485924 -256.793878) (xy 354.436371 -256.811676) (xy 354.384681 -256.8217)
			(xy 354.332067 -256.823717) (xy 354.279762 -256.817679) (xy 354.228991 -256.803727) (xy 354.180946 -256.782188)
			(xy 354.136751 -256.753568) (xy 354.097443 -256.718537) (xy 354.063943 -256.677916) (xy 354.037037 -256.632657)
			(xy 354.017354 -256.583822) (xy 354.005357 -256.532554) (xy 354.001327 -256.480056) (xy 351.054453 -256.480056)
			(xy 351.070582 -256.509859) (xy 351.086983 -256.557633) (xy 351.095296 -256.607455) (xy 351.095818 -256.63271)
			(xy 351.095376 -256.656057) (xy 351.088274 -256.702207) (xy 351.074237 -256.746741) (xy 351.053591 -256.788622)
			(xy 351.026816 -256.826876) (xy 351.010982 -256.844038) (xy 351.00006 -256.855214) (xy 350.994726 -256.884932)
			(xy 351.036382 -256.982722) (xy 351.040702 -256.991674) (xy 351.054827 -257.005634) (xy 351.07319 -257.013194)
			(xy 351.083118 -257.01371) (xy 353.85248 -257.01371) (xy 353.862316 -257.014248) (xy 353.880474 -257.021839)
			(xy 353.887786 -257.028442) (xy 354.024438 -257.165094) (xy 354.031771 -257.171806) (xy 354.050073 -257.179512)
			(xy 354.059998 -257.18008) (xy 354.081334 -257.180334) (xy 354.08601 -257.180253) (xy 354.095214 -257.178595)
			(xy 354.099622 -257.177032) (xy 354.122228 -257.16865) (xy 354.128832 -257.163316) (xy 354.151951 -257.145332)
			(xy 354.203037 -257.116689) (xy 354.258237 -257.097117) (xy 354.315956 -257.087183) (xy 354.34524 -257.086608)
			(xy 354.370936 -257.087091) (xy 354.421753 -257.094756) (xy 354.47086 -257.109908) (xy 354.51716 -257.13221)
			(xy 354.55962 -257.161163) (xy 354.59729 -257.196121) (xy 354.62933 -257.236302) (xy 354.655024 -257.280809)
			(xy 354.673798 -257.328649) (xy 354.685233 -257.378752) (xy 354.689074 -257.43) (xy 354.685233 -257.481248)
			(xy 354.673798 -257.531351) (xy 354.655024 -257.579191) (xy 354.62933 -257.623698) (xy 354.59729 -257.663879)
			(xy 354.55962 -257.698837) (xy 354.51716 -257.72779) (xy 354.481481 -257.744976) (xy 356.428297 -257.744976)
			(xy 356.432327 -257.692478) (xy 356.444324 -257.64121) (xy 356.464007 -257.592375) (xy 356.490913 -257.547116)
			(xy 356.524413 -257.506495) (xy 356.563721 -257.471464) (xy 356.607916 -257.442844) (xy 356.655961 -257.421305)
			(xy 356.706732 -257.407353) (xy 356.759037 -257.401315) (xy 356.811651 -257.403332) (xy 356.863341 -257.413356)
			(xy 356.912894 -257.431154) (xy 356.95915 -257.456307) (xy 357.001024 -257.488226) (xy 357.037536 -257.526164)
			(xy 357.067828 -257.56923) (xy 357.091191 -257.616415) (xy 357.107077 -257.666614) (xy 357.115114 -257.71865)
			(xy 357.115618 -257.744976) (xy 358.014019 -257.744976) (xy 358.018049 -257.692478) (xy 358.030046 -257.64121)
			(xy 358.049729 -257.592375) (xy 358.076635 -257.547116) (xy 358.110135 -257.506495) (xy 358.149443 -257.471464)
			(xy 358.193638 -257.442844) (xy 358.241683 -257.421305) (xy 358.292454 -257.407353) (xy 358.344759 -257.401315)
			(xy 358.397373 -257.403332) (xy 358.449063 -257.413356) (xy 358.498616 -257.431154) (xy 358.544872 -257.456307)
			(xy 358.586746 -257.488226) (xy 358.623258 -257.526164) (xy 358.65355 -257.56923) (xy 358.676913 -257.616415)
			(xy 358.692799 -257.666614) (xy 358.700836 -257.71865) (xy 358.70134 -257.744976) (xy 358.928419 -257.744976)
			(xy 358.932449 -257.692478) (xy 358.944446 -257.64121) (xy 358.964129 -257.592375) (xy 358.991035 -257.547116)
			(xy 359.024535 -257.506495) (xy 359.063843 -257.471464) (xy 359.108038 -257.442844) (xy 359.156083 -257.421305)
			(xy 359.206854 -257.407353) (xy 359.259159 -257.401315) (xy 359.311773 -257.403332) (xy 359.363463 -257.413356)
			(xy 359.413016 -257.431154) (xy 359.459272 -257.456307) (xy 359.501146 -257.488226) (xy 359.537658 -257.526164)
			(xy 359.56795 -257.56923) (xy 359.591313 -257.616415) (xy 359.607199 -257.666614) (xy 359.615236 -257.71865)
			(xy 359.61574 -257.744976) (xy 359.615236 -257.771302) (xy 359.607199 -257.823338) (xy 359.591313 -257.873537)
			(xy 359.56795 -257.920722) (xy 359.537658 -257.963788) (xy 359.501146 -258.001726) (xy 359.459272 -258.033645)
			(xy 359.413016 -258.058798) (xy 359.363463 -258.076596) (xy 359.311773 -258.08662) (xy 359.259159 -258.088637)
			(xy 359.206854 -258.082599) (xy 359.156083 -258.068647) (xy 359.108038 -258.047108) (xy 359.063843 -258.018488)
			(xy 359.024535 -257.983457) (xy 358.991035 -257.942836) (xy 358.964129 -257.897577) (xy 358.944446 -257.848742)
			(xy 358.932449 -257.797474) (xy 358.928419 -257.744976) (xy 358.70134 -257.744976) (xy 358.700836 -257.771302)
			(xy 358.692799 -257.823338) (xy 358.676913 -257.873537) (xy 358.65355 -257.920722) (xy 358.623258 -257.963788)
			(xy 358.586746 -258.001726) (xy 358.544872 -258.033645) (xy 358.498616 -258.058798) (xy 358.449063 -258.076596)
			(xy 358.397373 -258.08662) (xy 358.344759 -258.088637) (xy 358.292454 -258.082599) (xy 358.241683 -258.068647)
			(xy 358.193638 -258.047108) (xy 358.149443 -258.018488) (xy 358.110135 -257.983457) (xy 358.076635 -257.942836)
			(xy 358.049729 -257.897577) (xy 358.030046 -257.848742) (xy 358.018049 -257.797474) (xy 358.014019 -257.744976)
			(xy 357.115618 -257.744976) (xy 357.115114 -257.771302) (xy 357.107077 -257.823338) (xy 357.091191 -257.873537)
			(xy 357.067828 -257.920722) (xy 357.037536 -257.963788) (xy 357.001024 -258.001726) (xy 356.95915 -258.033645)
			(xy 356.912894 -258.058798) (xy 356.863341 -258.076596) (xy 356.811651 -258.08662) (xy 356.759037 -258.088637)
			(xy 356.706732 -258.082599) (xy 356.655961 -258.068647) (xy 356.607916 -258.047108) (xy 356.563721 -258.018488)
			(xy 356.524413 -257.983457) (xy 356.490913 -257.942836) (xy 356.464007 -257.897577) (xy 356.444324 -257.848742)
			(xy 356.432327 -257.797474) (xy 356.428297 -257.744976) (xy 354.481481 -257.744976) (xy 354.47086 -257.750092)
			(xy 354.421753 -257.765244) (xy 354.370936 -257.772909) (xy 354.34524 -257.773424) (xy 354.344732 -257.773424)
			(xy 354.321717 -257.773069) (xy 354.276097 -257.766948) (xy 354.2538 -257.761232) (xy 354.24237 -257.75793)
			(xy 354.219256 -257.762502) (xy 354.14712 -257.817366) (xy 354.13813 -257.824957) (xy 354.127668 -257.846002)
			(xy 354.127054 -257.857752) (xy 354.127054 -257.881628) (xy 354.127484 -257.891695) (xy 354.135211 -257.910287)
			(xy 354.14204 -257.917696) (xy 354.249736 -258.025392) (xy 354.257136 -258.032234) (xy 354.275734 -258.039956)
			(xy 354.285804 -258.040378) (xy 354.29444 -258.040378) (xy 354.298504 -258.03987) (xy 354.309497 -258.038413)
			(xy 354.331613 -258.036759) (xy 354.3427 -258.036568) (xy 354.34397 -258.036568) (xy 354.34524 -258.036568)
			(xy 354.372241 -258.037066) (xy 354.425579 -258.045511) (xy 354.476938 -258.062202) (xy 354.52505 -258.086727)
			(xy 354.56873 -258.118481) (xy 354.6069 -258.156682) (xy 354.638619 -258.200387) (xy 354.663105 -258.248519)
			(xy 354.671884 -258.274058) (xy 354.676964 -258.289806) (xy 354.703634 -258.30911) (xy 356.01148 -258.30911)
			(xy 356.021316 -258.309648) (xy 356.039474 -258.317239) (xy 356.046786 -258.323842) (xy 356.347522 -258.624578)
			(xy 356.352156 -258.629488) (xy 356.358848 -258.641208) (xy 356.36073 -258.647692) (xy 356.365048 -258.664964)
			(xy 356.392226 -258.686046) (xy 356.411784 -258.686046) (xy 356.4215 -258.685619) (xy 356.439543 -258.678404)
			(xy 356.453612 -258.664999) (xy 356.458012 -258.656328) (xy 356.458266 -258.65582) (xy 356.458266 -258.655566)
			(xy 356.468725 -258.633123) (xy 356.495137 -258.591242) (xy 356.527285 -258.553584) (xy 356.564503 -258.520929)
			(xy 356.606022 -258.493952) (xy 356.650983 -258.473211) (xy 356.698454 -258.459137) (xy 356.747453 -258.452019)
			(xy 356.77221 -258.451604) (xy 356.799196 -258.452107) (xy 356.852505 -258.460551) (xy 356.903835 -258.477232)
			(xy 356.951925 -258.501736) (xy 356.995589 -258.533462) (xy 357.033752 -258.571628) (xy 357.065475 -258.615294)
			(xy 357.089977 -258.663385) (xy 357.106654 -258.714717) (xy 357.115095 -258.768026) (xy 357.115618 -258.795012)
			(xy 358.014019 -258.795012) (xy 358.018049 -258.742514) (xy 358.030046 -258.691246) (xy 358.049729 -258.642411)
			(xy 358.076635 -258.597152) (xy 358.110135 -258.556531) (xy 358.149443 -258.5215) (xy 358.193638 -258.49288)
			(xy 358.241683 -258.471341) (xy 358.292454 -258.457389) (xy 358.344759 -258.451351) (xy 358.397373 -258.453368)
			(xy 358.449063 -258.463392) (xy 358.498616 -258.48119) (xy 358.544872 -258.506343) (xy 358.586746 -258.538262)
			(xy 358.623258 -258.5762) (xy 358.65355 -258.619266) (xy 358.676913 -258.666451) (xy 358.692799 -258.71665)
			(xy 358.700836 -258.768686) (xy 358.70134 -258.795012) (xy 358.928419 -258.795012) (xy 358.932449 -258.742514)
			(xy 358.944446 -258.691246) (xy 358.964129 -258.642411) (xy 358.991035 -258.597152) (xy 359.024535 -258.556531)
			(xy 359.063843 -258.5215) (xy 359.108038 -258.49288) (xy 359.156083 -258.471341) (xy 359.206854 -258.457389)
			(xy 359.259159 -258.451351) (xy 359.311773 -258.453368) (xy 359.363463 -258.463392) (xy 359.413016 -258.48119)
			(xy 359.459272 -258.506343) (xy 359.501146 -258.538262) (xy 359.537658 -258.5762) (xy 359.56795 -258.619266)
			(xy 359.591313 -258.666451) (xy 359.607199 -258.71665) (xy 359.615236 -258.768686) (xy 359.61574 -258.795012)
			(xy 359.615236 -258.821338) (xy 359.607199 -258.873374) (xy 359.591313 -258.923573) (xy 359.56795 -258.970758)
			(xy 359.537658 -259.013824) (xy 359.501146 -259.051762) (xy 359.459272 -259.083681) (xy 359.413016 -259.108834)
			(xy 359.363463 -259.126632) (xy 359.311773 -259.136656) (xy 359.259159 -259.138673) (xy 359.206854 -259.132635)
			(xy 359.156083 -259.118683) (xy 359.108038 -259.097144) (xy 359.063843 -259.068524) (xy 359.024535 -259.033493)
			(xy 358.991035 -258.992872) (xy 358.964129 -258.947613) (xy 358.944446 -258.898778) (xy 358.932449 -258.84751)
			(xy 358.928419 -258.795012) (xy 358.70134 -258.795012) (xy 358.700836 -258.821338) (xy 358.692799 -258.873374)
			(xy 358.676913 -258.923573) (xy 358.65355 -258.970758) (xy 358.623258 -259.013824) (xy 358.586746 -259.051762)
			(xy 358.544872 -259.083681) (xy 358.498616 -259.108834) (xy 358.449063 -259.126632) (xy 358.397373 -259.136656)
			(xy 358.344759 -259.138673) (xy 358.292454 -259.132635) (xy 358.241683 -259.118683) (xy 358.193638 -259.097144)
			(xy 358.149443 -259.068524) (xy 358.110135 -259.033493) (xy 358.076635 -258.992872) (xy 358.049729 -258.947613)
			(xy 358.030046 -258.898778) (xy 358.018049 -258.84751) (xy 358.014019 -258.795012) (xy 357.115618 -258.795012)
			(xy 357.115116 -258.821554) (xy 357.106935 -258.874003) (xy 357.090786 -258.92457) (xy 357.067052 -258.972052)
			(xy 357.036299 -259.01532) (xy 356.999257 -259.053343) (xy 356.956809 -259.085218) (xy 356.909964 -259.110185)
			(xy 356.859836 -259.127652) (xy 356.807619 -259.137201) (xy 356.7811 -259.13842) (xy 356.772718 -259.13842)
			(xy 356.746185 -259.137959) (xy 356.69374 -259.129865) (xy 356.643163 -259.113805) (xy 356.595656 -259.09016)
			(xy 356.552349 -259.059493) (xy 356.532942 -259.041392) (xy 356.532688 -259.041138) (xy 356.531926 -259.04063)
			(xy 356.526538 -259.035881) (xy 356.513776 -259.029302) (xy 356.50678 -259.027676) (xy 356.506526 -259.027676)
			(xy 356.499083 -259.026507) (xy 356.484102 -259.028042) (xy 356.477062 -259.030724) (xy 356.393242 -259.065776)
			(xy 356.384245 -259.070113) (xy 356.370231 -259.084316) (xy 356.362687 -259.102788) (xy 356.362254 -259.112766)
			(xy 356.362254 -259.527548) (xy 356.362792 -259.539946) (xy 356.374231 -259.561935) (xy 356.384098 -259.569458)
			(xy 356.405688 -259.584444) (xy 356.412038 -259.582158) (xy 356.49154 -259.615432) (xy 356.521512 -259.609844)
			(xy 356.532434 -259.599176) (xy 356.551792 -259.58099) (xy 356.595071 -259.550205) (xy 356.642577 -259.526453)
			(xy 356.693173 -259.510303) (xy 356.745654 -259.502139) (xy 356.77221 -259.50164) (xy 356.799195 -259.502143)
			(xy 356.852501 -259.510588) (xy 356.90383 -259.527268) (xy 356.951917 -259.551773) (xy 356.995578 -259.5835)
			(xy 357.033738 -259.621666) (xy 357.065457 -259.665333) (xy 357.089954 -259.713424) (xy 357.106626 -259.764755)
			(xy 357.115062 -259.818062) (xy 357.115618 -259.845048) (xy 358.014019 -259.845048) (xy 358.018049 -259.79255)
			(xy 358.030046 -259.741282) (xy 358.049729 -259.692447) (xy 358.076635 -259.647188) (xy 358.110135 -259.606567)
			(xy 358.149443 -259.571536) (xy 358.193638 -259.542916) (xy 358.241683 -259.521377) (xy 358.292454 -259.507425)
			(xy 358.344759 -259.501387) (xy 358.397373 -259.503404) (xy 358.449063 -259.513428) (xy 358.498616 -259.531226)
			(xy 358.544872 -259.556379) (xy 358.586746 -259.588298) (xy 358.623258 -259.626236) (xy 358.65355 -259.669302)
			(xy 358.676913 -259.716487) (xy 358.692799 -259.766686) (xy 358.700836 -259.818722) (xy 358.70134 -259.845048)
			(xy 358.928419 -259.845048) (xy 358.932449 -259.79255) (xy 358.944446 -259.741282) (xy 358.964129 -259.692447)
			(xy 358.991035 -259.647188) (xy 359.024535 -259.606567) (xy 359.063843 -259.571536) (xy 359.108038 -259.542916)
			(xy 359.156083 -259.521377) (xy 359.206854 -259.507425) (xy 359.259159 -259.501387) (xy 359.311773 -259.503404)
			(xy 359.363463 -259.513428) (xy 359.413016 -259.531226) (xy 359.459272 -259.556379) (xy 359.501146 -259.588298)
			(xy 359.537658 -259.626236) (xy 359.56795 -259.669302) (xy 359.591313 -259.716487) (xy 359.607199 -259.766686)
			(xy 359.615236 -259.818722) (xy 359.61574 -259.845048) (xy 360.263951 -259.845048) (xy 360.267981 -259.79255)
			(xy 360.279978 -259.741282) (xy 360.299661 -259.692447) (xy 360.326567 -259.647188) (xy 360.360067 -259.606567)
			(xy 360.399375 -259.571536) (xy 360.44357 -259.542916) (xy 360.491615 -259.521377) (xy 360.542386 -259.507425)
			(xy 360.594691 -259.501387) (xy 360.647305 -259.503404) (xy 360.698995 -259.513428) (xy 360.748548 -259.531226)
			(xy 360.794804 -259.556379) (xy 360.836678 -259.588298) (xy 360.87319 -259.626236) (xy 360.903482 -259.669302)
			(xy 360.926845 -259.716487) (xy 360.942731 -259.766686) (xy 360.950768 -259.818722) (xy 360.951272 -259.845048)
			(xy 361.178351 -259.845048) (xy 361.182381 -259.79255) (xy 361.194378 -259.741282) (xy 361.214061 -259.692447)
			(xy 361.240967 -259.647188) (xy 361.274467 -259.606567) (xy 361.313775 -259.571536) (xy 361.35797 -259.542916)
			(xy 361.406015 -259.521377) (xy 361.456786 -259.507425) (xy 361.509091 -259.501387) (xy 361.561705 -259.503404)
			(xy 361.613395 -259.513428) (xy 361.662948 -259.531226) (xy 361.709204 -259.556379) (xy 361.751078 -259.588298)
			(xy 361.78759 -259.626236) (xy 361.817882 -259.669302) (xy 361.841245 -259.716487) (xy 361.857131 -259.766686)
			(xy 361.865168 -259.818722) (xy 361.865672 -259.845048) (xy 362.863895 -259.845048) (xy 362.867925 -259.79255)
			(xy 362.879922 -259.741282) (xy 362.899605 -259.692447) (xy 362.926511 -259.647188) (xy 362.960011 -259.606567)
			(xy 362.999319 -259.571536) (xy 363.043514 -259.542916) (xy 363.091559 -259.521377) (xy 363.14233 -259.507425)
			(xy 363.194635 -259.501387) (xy 363.247249 -259.503404) (xy 363.298939 -259.513428) (xy 363.348492 -259.531226)
			(xy 363.394748 -259.556379) (xy 363.436622 -259.588298) (xy 363.473134 -259.626236) (xy 363.503426 -259.669302)
			(xy 363.526789 -259.716487) (xy 363.542675 -259.766686) (xy 363.550712 -259.818722) (xy 363.551216 -259.845048)
			(xy 363.778295 -259.845048) (xy 363.782325 -259.79255) (xy 363.794322 -259.741282) (xy 363.814005 -259.692447)
			(xy 363.840911 -259.647188) (xy 363.874411 -259.606567) (xy 363.913719 -259.571536) (xy 363.957914 -259.542916)
			(xy 364.005959 -259.521377) (xy 364.05673 -259.507425) (xy 364.109035 -259.501387) (xy 364.161649 -259.503404)
			(xy 364.213339 -259.513428) (xy 364.262892 -259.531226) (xy 364.309148 -259.556379) (xy 364.351022 -259.588298)
			(xy 364.387534 -259.626236) (xy 364.417826 -259.669302) (xy 364.441189 -259.716487) (xy 364.457075 -259.766686)
			(xy 364.465112 -259.818722) (xy 364.465616 -259.845048) (xy 364.465112 -259.871374) (xy 364.457075 -259.92341)
			(xy 364.441189 -259.973609) (xy 364.417826 -260.020794) (xy 364.387534 -260.06386) (xy 364.351022 -260.101798)
			(xy 364.309148 -260.133717) (xy 364.262892 -260.15887) (xy 364.213339 -260.176668) (xy 364.161649 -260.186692)
			(xy 364.109035 -260.188709) (xy 364.05673 -260.182671) (xy 364.005959 -260.168719) (xy 363.957914 -260.14718)
			(xy 363.913719 -260.11856) (xy 363.874411 -260.083529) (xy 363.840911 -260.042908) (xy 363.814005 -259.997649)
			(xy 363.794322 -259.948814) (xy 363.782325 -259.897546) (xy 363.778295 -259.845048) (xy 363.551216 -259.845048)
			(xy 363.550712 -259.871374) (xy 363.542675 -259.92341) (xy 363.526789 -259.973609) (xy 363.503426 -260.020794)
			(xy 363.473134 -260.06386) (xy 363.436622 -260.101798) (xy 363.394748 -260.133717) (xy 363.348492 -260.15887)
			(xy 363.298939 -260.176668) (xy 363.247249 -260.186692) (xy 363.194635 -260.188709) (xy 363.14233 -260.182671)
			(xy 363.091559 -260.168719) (xy 363.043514 -260.14718) (xy 362.999319 -260.11856) (xy 362.960011 -260.083529)
			(xy 362.926511 -260.042908) (xy 362.899605 -259.997649) (xy 362.879922 -259.948814) (xy 362.867925 -259.897546)
			(xy 362.863895 -259.845048) (xy 361.865672 -259.845048) (xy 361.865168 -259.871374) (xy 361.857131 -259.92341)
			(xy 361.841245 -259.973609) (xy 361.817882 -260.020794) (xy 361.78759 -260.06386) (xy 361.751078 -260.101798)
			(xy 361.709204 -260.133717) (xy 361.662948 -260.15887) (xy 361.613395 -260.176668) (xy 361.561705 -260.186692)
			(xy 361.509091 -260.188709) (xy 361.456786 -260.182671) (xy 361.406015 -260.168719) (xy 361.35797 -260.14718)
			(xy 361.313775 -260.11856) (xy 361.274467 -260.083529) (xy 361.240967 -260.042908) (xy 361.214061 -259.997649)
			(xy 361.194378 -259.948814) (xy 361.182381 -259.897546) (xy 361.178351 -259.845048) (xy 360.951272 -259.845048)
			(xy 360.950768 -259.871374) (xy 360.942731 -259.92341) (xy 360.926845 -259.973609) (xy 360.903482 -260.020794)
			(xy 360.87319 -260.06386) (xy 360.836678 -260.101798) (xy 360.794804 -260.133717) (xy 360.748548 -260.15887)
			(xy 360.698995 -260.176668) (xy 360.647305 -260.186692) (xy 360.594691 -260.188709) (xy 360.542386 -260.182671)
			(xy 360.491615 -260.168719) (xy 360.44357 -260.14718) (xy 360.399375 -260.11856) (xy 360.360067 -260.083529)
			(xy 360.326567 -260.042908) (xy 360.299661 -259.997649) (xy 360.279978 -259.948814) (xy 360.267981 -259.897546)
			(xy 360.263951 -259.845048) (xy 359.61574 -259.845048) (xy 359.615236 -259.871374) (xy 359.607199 -259.92341)
			(xy 359.591313 -259.973609) (xy 359.56795 -260.020794) (xy 359.537658 -260.06386) (xy 359.501146 -260.101798)
			(xy 359.459272 -260.133717) (xy 359.413016 -260.15887) (xy 359.363463 -260.176668) (xy 359.311773 -260.186692)
			(xy 359.259159 -260.188709) (xy 359.206854 -260.182671) (xy 359.156083 -260.168719) (xy 359.108038 -260.14718)
			(xy 359.063843 -260.11856) (xy 359.024535 -260.083529) (xy 358.991035 -260.042908) (xy 358.964129 -259.997649)
			(xy 358.944446 -259.948814) (xy 358.932449 -259.897546) (xy 358.928419 -259.845048) (xy 358.70134 -259.845048)
			(xy 358.700836 -259.871374) (xy 358.692799 -259.92341) (xy 358.676913 -259.973609) (xy 358.65355 -260.020794)
			(xy 358.623258 -260.06386) (xy 358.586746 -260.101798) (xy 358.544872 -260.133717) (xy 358.498616 -260.15887)
			(xy 358.449063 -260.176668) (xy 358.397373 -260.186692) (xy 358.344759 -260.188709) (xy 358.292454 -260.182671)
			(xy 358.241683 -260.168719) (xy 358.193638 -260.14718) (xy 358.149443 -260.11856) (xy 358.110135 -260.083529)
			(xy 358.076635 -260.042908) (xy 358.049729 -259.997649) (xy 358.030046 -259.948814) (xy 358.018049 -259.897546)
			(xy 358.014019 -259.845048) (xy 357.115618 -259.845048) (xy 357.115121 -259.871593) (xy 357.106948 -259.92405)
			(xy 357.090804 -259.974625) (xy 357.067074 -260.022116) (xy 357.036322 -260.065392) (xy 356.99928 -260.103424)
			(xy 356.956829 -260.135305) (xy 356.90998 -260.160278) (xy 356.859847 -260.177749) (xy 356.807624 -260.187301)
			(xy 356.7811 -260.188456) (xy 356.772718 -260.188456) (xy 356.746184 -260.187996) (xy 356.693739 -260.179902)
			(xy 356.643161 -260.163843) (xy 356.595653 -260.1402) (xy 356.552344 -260.109535) (xy 356.532942 -260.091428)
			(xy 356.532688 -260.091174) (xy 356.531926 -260.090666) (xy 356.526539 -260.085914) (xy 356.513778 -260.079331)
			(xy 356.50678 -260.077712) (xy 356.506526 -260.077712) (xy 356.499083 -260.076542) (xy 356.484102 -260.078078)
			(xy 356.477062 -260.08076) (xy 356.393242 -260.115812) (xy 356.384249 -260.120151) (xy 356.370245 -260.134356)
			(xy 356.362713 -260.152826) (xy 356.362254 -260.162802) (xy 356.362254 -260.885432) (xy 356.362721 -260.896087)
			(xy 356.371419 -260.915539) (xy 356.379018 -260.923024) (xy 356.379526 -260.923786) (xy 356.446582 -260.980428)
			(xy 356.467918 -260.98627) (xy 356.47884 -260.984492) (xy 356.479094 -260.984492) (xy 356.483158 -260.98373)
			(xy 356.496781 -260.981681) (xy 356.524246 -260.979521) (xy 356.538022 -260.979412) (xy 356.565005 -260.979943)
			(xy 356.618307 -260.988389) (xy 356.669632 -261.005069) (xy 356.717715 -261.029572) (xy 356.761374 -261.061296)
			(xy 356.799532 -261.099458) (xy 356.83125 -261.14312) (xy 356.855748 -261.191207) (xy 356.872421 -261.242533)
			(xy 356.88086 -261.295836) (xy 356.88143 -261.32282) (xy 357.144069 -261.32282) (xy 357.148099 -261.270322)
			(xy 357.160096 -261.219054) (xy 357.179779 -261.170219) (xy 357.206685 -261.12496) (xy 357.240185 -261.084339)
			(xy 357.279493 -261.049308) (xy 357.323688 -261.020688) (xy 357.371733 -260.999149) (xy 357.422504 -260.985197)
			(xy 357.474809 -260.979159) (xy 357.527423 -260.981176) (xy 357.579113 -260.9912) (xy 357.628666 -261.008998)
			(xy 357.674922 -261.034151) (xy 357.716796 -261.06607) (xy 357.753308 -261.104008) (xy 357.7836 -261.147074)
			(xy 357.806963 -261.194259) (xy 357.822849 -261.244458) (xy 357.830886 -261.296494) (xy 357.83139 -261.32282)
			(xy 358.094029 -261.32282) (xy 358.098059 -261.270322) (xy 358.110056 -261.219054) (xy 358.129739 -261.170219)
			(xy 358.156645 -261.12496) (xy 358.190145 -261.084339) (xy 358.229453 -261.049308) (xy 358.273648 -261.020688)
			(xy 358.321693 -260.999149) (xy 358.372464 -260.985197) (xy 358.424769 -260.979159) (xy 358.477383 -260.981176)
			(xy 358.529073 -260.9912) (xy 358.578626 -261.008998) (xy 358.624882 -261.034151) (xy 358.666756 -261.06607)
			(xy 358.703268 -261.104008) (xy 358.73356 -261.147074) (xy 358.756923 -261.194259) (xy 358.772809 -261.244458)
			(xy 358.780846 -261.296494) (xy 358.78135 -261.32282) (xy 359.043989 -261.32282) (xy 359.048019 -261.270322)
			(xy 359.060016 -261.219054) (xy 359.079699 -261.170219) (xy 359.106605 -261.12496) (xy 359.140105 -261.084339)
			(xy 359.179413 -261.049308) (xy 359.223608 -261.020688) (xy 359.271653 -260.999149) (xy 359.322424 -260.985197)
			(xy 359.374729 -260.979159) (xy 359.427343 -260.981176) (xy 359.479033 -260.9912) (xy 359.528586 -261.008998)
			(xy 359.574842 -261.034151) (xy 359.616716 -261.06607) (xy 359.653228 -261.104008) (xy 359.68352 -261.147074)
			(xy 359.706883 -261.194259) (xy 359.722769 -261.244458) (xy 359.730806 -261.296494) (xy 359.73131 -261.32282)
			(xy 359.993949 -261.32282) (xy 359.997979 -261.270322) (xy 360.009976 -261.219054) (xy 360.029659 -261.170219)
			(xy 360.056565 -261.12496) (xy 360.090065 -261.084339) (xy 360.129373 -261.049308) (xy 360.173568 -261.020688)
			(xy 360.221613 -260.999149) (xy 360.272384 -260.985197) (xy 360.324689 -260.979159) (xy 360.377303 -260.981176)
			(xy 360.428993 -260.9912) (xy 360.478546 -261.008998) (xy 360.524802 -261.034151) (xy 360.566676 -261.06607)
			(xy 360.603188 -261.104008) (xy 360.63348 -261.147074) (xy 360.656843 -261.194259) (xy 360.672729 -261.244458)
			(xy 360.680766 -261.296494) (xy 360.68127 -261.32282) (xy 360.944163 -261.32282) (xy 360.948193 -261.270322)
			(xy 360.96019 -261.219054) (xy 360.979873 -261.170219) (xy 361.006779 -261.12496) (xy 361.040279 -261.084339)
			(xy 361.079587 -261.049308) (xy 361.123782 -261.020688) (xy 361.171827 -260.999149) (xy 361.222598 -260.985197)
			(xy 361.274903 -260.979159) (xy 361.327517 -260.981176) (xy 361.379207 -260.9912) (xy 361.42876 -261.008998)
			(xy 361.475016 -261.034151) (xy 361.51689 -261.06607) (xy 361.553402 -261.104008) (xy 361.583694 -261.147074)
			(xy 361.607057 -261.194259) (xy 361.622943 -261.244458) (xy 361.63098 -261.296494) (xy 361.631484 -261.32282)
			(xy 361.894123 -261.32282) (xy 361.898153 -261.270322) (xy 361.91015 -261.219054) (xy 361.929833 -261.170219)
			(xy 361.956739 -261.12496) (xy 361.990239 -261.084339) (xy 362.029547 -261.049308) (xy 362.073742 -261.020688)
			(xy 362.121787 -260.999149) (xy 362.172558 -260.985197) (xy 362.224863 -260.979159) (xy 362.277477 -260.981176)
			(xy 362.329167 -260.9912) (xy 362.37872 -261.008998) (xy 362.424976 -261.034151) (xy 362.46685 -261.06607)
			(xy 362.503362 -261.104008) (xy 362.533654 -261.147074) (xy 362.557017 -261.194259) (xy 362.572903 -261.244458)
			(xy 362.58094 -261.296494) (xy 362.581444 -261.32282) (xy 362.844083 -261.32282) (xy 362.848113 -261.270322)
			(xy 362.86011 -261.219054) (xy 362.879793 -261.170219) (xy 362.906699 -261.12496) (xy 362.940199 -261.084339)
			(xy 362.979507 -261.049308) (xy 363.023702 -261.020688) (xy 363.071747 -260.999149) (xy 363.122518 -260.985197)
			(xy 363.174823 -260.979159) (xy 363.227437 -260.981176) (xy 363.279127 -260.9912) (xy 363.32868 -261.008998)
			(xy 363.374936 -261.034151) (xy 363.41681 -261.06607) (xy 363.453322 -261.104008) (xy 363.483614 -261.147074)
			(xy 363.506977 -261.194259) (xy 363.522863 -261.244458) (xy 363.5309 -261.296494) (xy 363.531404 -261.32282)
			(xy 363.794043 -261.32282) (xy 363.798073 -261.270322) (xy 363.81007 -261.219054) (xy 363.829753 -261.170219)
			(xy 363.856659 -261.12496) (xy 363.890159 -261.084339) (xy 363.929467 -261.049308) (xy 363.973662 -261.020688)
			(xy 364.021707 -260.999149) (xy 364.072478 -260.985197) (xy 364.124783 -260.979159) (xy 364.177397 -260.981176)
			(xy 364.229087 -260.9912) (xy 364.27864 -261.008998) (xy 364.324896 -261.034151) (xy 364.36677 -261.06607)
			(xy 364.403282 -261.104008) (xy 364.433574 -261.147074) (xy 364.456937 -261.194259) (xy 364.468282 -261.23011)
			(xy 365.036865 -261.23011) (xy 365.040895 -261.177612) (xy 365.052892 -261.126344) (xy 365.072575 -261.077509)
			(xy 365.099481 -261.03225) (xy 365.132981 -260.991629) (xy 365.172289 -260.956598) (xy 365.216484 -260.927978)
			(xy 365.264529 -260.906439) (xy 365.3153 -260.892487) (xy 365.367605 -260.886449) (xy 365.420219 -260.888466)
			(xy 365.471909 -260.89849) (xy 365.521462 -260.916288) (xy 365.567718 -260.941441) (xy 365.609592 -260.97336)
			(xy 365.646104 -261.011298) (xy 365.676396 -261.054364) (xy 365.699759 -261.101549) (xy 365.715645 -261.151748)
			(xy 365.723682 -261.203784) (xy 365.724186 -261.23011) (xy 365.951265 -261.23011) (xy 365.955295 -261.177612)
			(xy 365.967292 -261.126344) (xy 365.986975 -261.077509) (xy 366.013881 -261.03225) (xy 366.047381 -260.991629)
			(xy 366.086689 -260.956598) (xy 366.130884 -260.927978) (xy 366.178929 -260.906439) (xy 366.2297 -260.892487)
			(xy 366.282005 -260.886449) (xy 366.334619 -260.888466) (xy 366.386309 -260.89849) (xy 366.435862 -260.916288)
			(xy 366.482118 -260.941441) (xy 366.523992 -260.97336) (xy 366.560504 -261.011298) (xy 366.590796 -261.054364)
			(xy 366.614159 -261.101549) (xy 366.630045 -261.151748) (xy 366.638082 -261.203784) (xy 366.638586 -261.23011)
			(xy 366.638082 -261.256436) (xy 366.630045 -261.308472) (xy 366.614159 -261.358671) (xy 366.590796 -261.405856)
			(xy 366.560504 -261.448922) (xy 366.523992 -261.48686) (xy 366.482118 -261.518779) (xy 366.435862 -261.543932)
			(xy 366.386309 -261.56173) (xy 366.334619 -261.571754) (xy 366.282005 -261.573771) (xy 366.2297 -261.567733)
			(xy 366.178929 -261.553781) (xy 366.130884 -261.532242) (xy 366.086689 -261.503622) (xy 366.047381 -261.468591)
			(xy 366.013881 -261.42797) (xy 365.986975 -261.382711) (xy 365.967292 -261.333876) (xy 365.955295 -261.282608)
			(xy 365.951265 -261.23011) (xy 365.724186 -261.23011) (xy 365.723682 -261.256436) (xy 365.715645 -261.308472)
			(xy 365.699759 -261.358671) (xy 365.676396 -261.405856) (xy 365.646104 -261.448922) (xy 365.609592 -261.48686)
			(xy 365.567718 -261.518779) (xy 365.521462 -261.543932) (xy 365.471909 -261.56173) (xy 365.420219 -261.571754)
			(xy 365.367605 -261.573771) (xy 365.3153 -261.567733) (xy 365.264529 -261.553781) (xy 365.216484 -261.532242)
			(xy 365.172289 -261.503622) (xy 365.132981 -261.468591) (xy 365.099481 -261.42797) (xy 365.072575 -261.382711)
			(xy 365.052892 -261.333876) (xy 365.040895 -261.282608) (xy 365.036865 -261.23011) (xy 364.468282 -261.23011)
			(xy 364.472823 -261.244458) (xy 364.48086 -261.296494) (xy 364.481364 -261.32282) (xy 364.48086 -261.349146)
			(xy 364.472823 -261.401182) (xy 364.456937 -261.451381) (xy 364.433574 -261.498566) (xy 364.403282 -261.541632)
			(xy 364.36677 -261.57957) (xy 364.324896 -261.611489) (xy 364.27864 -261.636642) (xy 364.229087 -261.65444)
			(xy 364.177397 -261.664464) (xy 364.124783 -261.666481) (xy 364.072478 -261.660443) (xy 364.021707 -261.646491)
			(xy 363.973662 -261.624952) (xy 363.929467 -261.596332) (xy 363.890159 -261.561301) (xy 363.856659 -261.52068)
			(xy 363.829753 -261.475421) (xy 363.81007 -261.426586) (xy 363.798073 -261.375318) (xy 363.794043 -261.32282)
			(xy 363.531404 -261.32282) (xy 363.5309 -261.349146) (xy 363.522863 -261.401182) (xy 363.506977 -261.451381)
			(xy 363.483614 -261.498566) (xy 363.453322 -261.541632) (xy 363.41681 -261.57957) (xy 363.374936 -261.611489)
			(xy 363.32868 -261.636642) (xy 363.279127 -261.65444) (xy 363.227437 -261.664464) (xy 363.174823 -261.666481)
			(xy 363.122518 -261.660443) (xy 363.071747 -261.646491) (xy 363.023702 -261.624952) (xy 362.979507 -261.596332)
			(xy 362.940199 -261.561301) (xy 362.906699 -261.52068) (xy 362.879793 -261.475421) (xy 362.86011 -261.426586)
			(xy 362.848113 -261.375318) (xy 362.844083 -261.32282) (xy 362.581444 -261.32282) (xy 362.58094 -261.349146)
			(xy 362.572903 -261.401182) (xy 362.557017 -261.451381) (xy 362.533654 -261.498566) (xy 362.503362 -261.541632)
			(xy 362.46685 -261.57957) (xy 362.424976 -261.611489) (xy 362.37872 -261.636642) (xy 362.329167 -261.65444)
			(xy 362.277477 -261.664464) (xy 362.224863 -261.666481) (xy 362.172558 -261.660443) (xy 362.121787 -261.646491)
			(xy 362.073742 -261.624952) (xy 362.029547 -261.596332) (xy 361.990239 -261.561301) (xy 361.956739 -261.52068)
			(xy 361.929833 -261.475421) (xy 361.91015 -261.426586) (xy 361.898153 -261.375318) (xy 361.894123 -261.32282)
			(xy 361.631484 -261.32282) (xy 361.63098 -261.349146) (xy 361.622943 -261.401182) (xy 361.607057 -261.451381)
			(xy 361.583694 -261.498566) (xy 361.553402 -261.541632) (xy 361.51689 -261.57957) (xy 361.475016 -261.611489)
			(xy 361.42876 -261.636642) (xy 361.379207 -261.65444) (xy 361.327517 -261.664464) (xy 361.274903 -261.666481)
			(xy 361.222598 -261.660443) (xy 361.171827 -261.646491) (xy 361.123782 -261.624952) (xy 361.079587 -261.596332)
			(xy 361.040279 -261.561301) (xy 361.006779 -261.52068) (xy 360.979873 -261.475421) (xy 360.96019 -261.426586)
			(xy 360.948193 -261.375318) (xy 360.944163 -261.32282) (xy 360.68127 -261.32282) (xy 360.680766 -261.349146)
			(xy 360.672729 -261.401182) (xy 360.656843 -261.451381) (xy 360.63348 -261.498566) (xy 360.603188 -261.541632)
			(xy 360.566676 -261.57957) (xy 360.524802 -261.611489) (xy 360.478546 -261.636642) (xy 360.428993 -261.65444)
			(xy 360.377303 -261.664464) (xy 360.324689 -261.666481) (xy 360.272384 -261.660443) (xy 360.221613 -261.646491)
			(xy 360.173568 -261.624952) (xy 360.129373 -261.596332) (xy 360.090065 -261.561301) (xy 360.056565 -261.52068)
			(xy 360.029659 -261.475421) (xy 360.009976 -261.426586) (xy 359.997979 -261.375318) (xy 359.993949 -261.32282)
			(xy 359.73131 -261.32282) (xy 359.730806 -261.349146) (xy 359.722769 -261.401182) (xy 359.706883 -261.451381)
			(xy 359.68352 -261.498566) (xy 359.653228 -261.541632) (xy 359.616716 -261.57957) (xy 359.574842 -261.611489)
			(xy 359.528586 -261.636642) (xy 359.479033 -261.65444) (xy 359.427343 -261.664464) (xy 359.374729 -261.666481)
			(xy 359.322424 -261.660443) (xy 359.271653 -261.646491) (xy 359.223608 -261.624952) (xy 359.179413 -261.596332)
			(xy 359.140105 -261.561301) (xy 359.106605 -261.52068) (xy 359.079699 -261.475421) (xy 359.060016 -261.426586)
			(xy 359.048019 -261.375318) (xy 359.043989 -261.32282) (xy 358.78135 -261.32282) (xy 358.780846 -261.349146)
			(xy 358.772809 -261.401182) (xy 358.756923 -261.451381) (xy 358.73356 -261.498566) (xy 358.703268 -261.541632)
			(xy 358.666756 -261.57957) (xy 358.624882 -261.611489) (xy 358.578626 -261.636642) (xy 358.529073 -261.65444)
			(xy 358.477383 -261.664464) (xy 358.424769 -261.666481) (xy 358.372464 -261.660443) (xy 358.321693 -261.646491)
			(xy 358.273648 -261.624952) (xy 358.229453 -261.596332) (xy 358.190145 -261.561301) (xy 358.156645 -261.52068)
			(xy 358.129739 -261.475421) (xy 358.110056 -261.426586) (xy 358.098059 -261.375318) (xy 358.094029 -261.32282)
			(xy 357.83139 -261.32282) (xy 357.830886 -261.349146) (xy 357.822849 -261.401182) (xy 357.806963 -261.451381)
			(xy 357.7836 -261.498566) (xy 357.753308 -261.541632) (xy 357.716796 -261.57957) (xy 357.674922 -261.611489)
			(xy 357.628666 -261.636642) (xy 357.579113 -261.65444) (xy 357.527423 -261.664464) (xy 357.474809 -261.666481)
			(xy 357.422504 -261.660443) (xy 357.371733 -261.646491) (xy 357.323688 -261.624952) (xy 357.279493 -261.596332)
			(xy 357.240185 -261.561301) (xy 357.206685 -261.52068) (xy 357.179779 -261.475421) (xy 357.160096 -261.426586)
			(xy 357.148099 -261.375318) (xy 357.144069 -261.32282) (xy 356.88143 -261.32282) (xy 356.880967 -261.348268)
			(xy 356.87345 -261.398606) (xy 356.858585 -261.447282) (xy 356.836696 -261.493231) (xy 356.808264 -261.535445)
			(xy 356.773911 -261.572999) (xy 356.734391 -261.60507) (xy 356.690569 -261.630955) (xy 356.643406 -261.650087)
			(xy 356.618794 -261.656576) (xy 356.611682 -261.658354) (xy 356.599744 -261.664958) (xy 356.594664 -261.670038)
			(xy 356.587844 -261.677415) (xy 356.58013 -261.695948) (xy 356.580124 -261.716023) (xy 356.587828 -261.73456)
			(xy 356.594664 -261.74192) (xy 356.626668 -261.773924) (xy 356.627176 -261.774432) (xy 356.634557 -261.781013)
			(xy 356.652857 -261.788458) (xy 356.662736 -261.78891) (xy 364.52048 -261.78891) (xy 364.530316 -261.789448)
			(xy 364.548474 -261.797039) (xy 364.555786 -261.803642) (xy 364.729522 -261.977378) (xy 364.736239 -261.984615)
			(xy 364.743844 -262.002819) (xy 364.744254 -262.012684) (xy 364.744254 -262.18007) (xy 365.036865 -262.18007)
			(xy 365.040895 -262.127572) (xy 365.052892 -262.076304) (xy 365.072575 -262.027469) (xy 365.099481 -261.98221)
			(xy 365.132981 -261.941589) (xy 365.172289 -261.906558) (xy 365.216484 -261.877938) (xy 365.264529 -261.856399)
			(xy 365.3153 -261.842447) (xy 365.367605 -261.836409) (xy 365.420219 -261.838426) (xy 365.471909 -261.84845)
			(xy 365.521462 -261.866248) (xy 365.567718 -261.891401) (xy 365.609592 -261.92332) (xy 365.646104 -261.961258)
			(xy 365.676396 -262.004324) (xy 365.699759 -262.051509) (xy 365.715645 -262.101708) (xy 365.723682 -262.153744)
			(xy 365.724186 -262.18007) (xy 365.951265 -262.18007) (xy 365.955295 -262.127572) (xy 365.967292 -262.076304)
			(xy 365.986975 -262.027469) (xy 366.013881 -261.98221) (xy 366.047381 -261.941589) (xy 366.086689 -261.906558)
			(xy 366.130884 -261.877938) (xy 366.178929 -261.856399) (xy 366.2297 -261.842447) (xy 366.282005 -261.836409)
			(xy 366.334619 -261.838426) (xy 366.386309 -261.84845) (xy 366.435862 -261.866248) (xy 366.482118 -261.891401)
			(xy 366.523992 -261.92332) (xy 366.536172 -261.935976) (xy 369.109002 -261.935976) (xy 369.112962 -261.886922)
			(xy 369.124739 -261.839138) (xy 369.14403 -261.793862) (xy 369.170333 -261.752266) (xy 369.202968 -261.715429)
			(xy 369.241089 -261.684304) (xy 369.28371 -261.659697) (xy 369.329726 -261.642245) (xy 369.377945 -261.632401)
			(xy 369.42712 -261.63042) (xy 369.475975 -261.636352) (xy 369.523246 -261.650044) (xy 369.567708 -261.671142)
			(xy 369.608211 -261.699098) (xy 369.643704 -261.73319) (xy 369.673269 -261.772534) (xy 369.69614 -261.816111)
			(xy 369.711724 -261.862792) (xy 369.719619 -261.911369) (xy 369.720114 -261.935976) (xy 369.719619 -261.960583)
			(xy 369.711724 -262.00916) (xy 369.69614 -262.055841) (xy 369.673269 -262.099418) (xy 369.643704 -262.138762)
			(xy 369.608211 -262.172854) (xy 369.567708 -262.20081) (xy 369.523246 -262.221908) (xy 369.475975 -262.2356)
			(xy 369.42712 -262.241532) (xy 369.377945 -262.239551) (xy 369.329726 -262.229707) (xy 369.28371 -262.212255)
			(xy 369.241089 -262.187648) (xy 369.202968 -262.156523) (xy 369.170333 -262.119686) (xy 369.14403 -262.07809)
			(xy 369.124739 -262.032814) (xy 369.112962 -261.98503) (xy 369.109002 -261.935976) (xy 366.536172 -261.935976)
			(xy 366.560504 -261.961258) (xy 366.590796 -262.004324) (xy 366.614159 -262.051509) (xy 366.630045 -262.101708)
			(xy 366.638082 -262.153744) (xy 366.638586 -262.18007) (xy 366.638082 -262.206396) (xy 366.630045 -262.258432)
			(xy 366.614159 -262.308631) (xy 366.590796 -262.355816) (xy 366.560504 -262.398882) (xy 366.523992 -262.43682)
			(xy 366.482118 -262.468739) (xy 366.435862 -262.493892) (xy 366.386309 -262.51169) (xy 366.334619 -262.521714)
			(xy 366.282005 -262.523731) (xy 366.2297 -262.517693) (xy 366.178929 -262.503741) (xy 366.130884 -262.482202)
			(xy 366.086689 -262.453582) (xy 366.047381 -262.418551) (xy 366.013881 -262.37793) (xy 365.986975 -262.332671)
			(xy 365.967292 -262.283836) (xy 365.955295 -262.232568) (xy 365.951265 -262.18007) (xy 365.724186 -262.18007)
			(xy 365.723682 -262.206396) (xy 365.715645 -262.258432) (xy 365.699759 -262.308631) (xy 365.676396 -262.355816)
			(xy 365.646104 -262.398882) (xy 365.609592 -262.43682) (xy 365.567718 -262.468739) (xy 365.521462 -262.493892)
			(xy 365.471909 -262.51169) (xy 365.420219 -262.521714) (xy 365.367605 -262.523731) (xy 365.3153 -262.517693)
			(xy 365.264529 -262.503741) (xy 365.216484 -262.482202) (xy 365.172289 -262.453582) (xy 365.132981 -262.418551)
			(xy 365.099481 -262.37793) (xy 365.072575 -262.332671) (xy 365.052892 -262.283836) (xy 365.040895 -262.232568)
			(xy 365.036865 -262.18007) (xy 364.744254 -262.18007) (xy 364.744254 -262.745982) (xy 369.578902 -262.745982)
			(xy 369.582862 -262.696928) (xy 369.594639 -262.649144) (xy 369.61393 -262.603868) (xy 369.640233 -262.562272)
			(xy 369.672868 -262.525435) (xy 369.710989 -262.49431) (xy 369.75361 -262.469703) (xy 369.799626 -262.452251)
			(xy 369.847845 -262.442407) (xy 369.89702 -262.440426) (xy 369.945875 -262.446358) (xy 369.993146 -262.46005)
			(xy 370.037608 -262.481148) (xy 370.078111 -262.509104) (xy 370.113604 -262.543196) (xy 370.143169 -262.58254)
			(xy 370.16604 -262.626117) (xy 370.181624 -262.672798) (xy 370.189519 -262.721375) (xy 370.190014 -262.745982)
			(xy 370.189519 -262.770589) (xy 370.181624 -262.819166) (xy 370.16604 -262.865847) (xy 370.143169 -262.909424)
			(xy 370.113604 -262.948768) (xy 370.078111 -262.98286) (xy 370.037608 -263.010816) (xy 369.993146 -263.031914)
			(xy 369.945875 -263.045606) (xy 369.89702 -263.051538) (xy 369.847845 -263.049557) (xy 369.799626 -263.039713)
			(xy 369.75361 -263.022261) (xy 369.710989 -262.997654) (xy 369.672868 -262.966529) (xy 369.640233 -262.929692)
			(xy 369.61393 -262.888096) (xy 369.594639 -262.84282) (xy 369.582862 -262.795036) (xy 369.578902 -262.745982)
			(xy 364.744254 -262.745982) (xy 364.744254 -263.164828) (xy 364.744684 -263.174895) (xy 364.752411 -263.193487)
			(xy 364.75924 -263.200896) (xy 365.161068 -263.602724) (xy 365.161576 -263.603232) (xy 365.168957 -263.609813)
			(xy 365.187257 -263.617258) (xy 365.197136 -263.61771) (xy 369.021106 -263.61771)
		)
		(stroke
			(width 0)
			(type solid)
		)
		(fill yes)
		(layer "In11.Cu")
		(net "PVDD18_S5_P0")
	)
	(gr_poly
		(pts
			(xy 196.036946 -342.040972) (xy 196.04682 -342.040506) (xy 196.065109 -342.033053) (xy 196.072506 -342.026494)
			(xy 196.07276 -342.02624) (xy 196.266054 -341.832946) (xy 196.266562 -341.832438) (xy 196.273142 -341.825056)
			(xy 196.280588 -341.806757) (xy 196.28104 -341.796878) (xy 196.28104 -326.597264) (xy 196.280609 -326.587198)
			(xy 196.272878 -326.568609) (xy 196.266054 -326.561196) (xy 195.7451 -326.040242) (xy 195.738263 -326.03284)
			(xy 195.730549 -326.014242) (xy 195.730114 -326.004174) (xy 195.10756 -325.38162) (xy 195.102765 -325.376503)
			(xy 195.095943 -325.364256) (xy 195.094098 -325.35749) (xy 195.09232 -325.350632) (xy 195.085716 -325.338694)
			(xy 194.32905 -324.582282) (xy 194.322201 -324.574885) (xy 194.314465 -324.556286) (xy 194.314064 -324.546214)
			(xy 194.314064 -320.512186) (xy 194.313638 -320.502118) (xy 194.305916 -320.48352) (xy 194.299078 -320.476118)
			(xy 194.111626 -320.288666) (xy 194.104514 -320.2813) (xy 194.085718 -320.27368) (xy 157.115002 -320.27368)
			(xy 157.104931 -320.274102) (xy 157.086324 -320.281814) (xy 157.078934 -320.288666) (xy 157.013402 -320.354198)
			(xy 157.010097 -320.357386) (xy 157.002556 -320.362625) (xy 156.998416 -320.364612) (xy 156.948886 -320.387218)
			(xy 156.941774 -320.395092) (xy 156.929582 -320.407792) (xy 156.929328 -320.408046) (xy 155.575254 -321.76212)
			(xy 155.569144 -321.768655) (xy 155.561557 -321.784845) (xy 155.560041 -321.80266) (xy 155.564782 -321.8199)
			(xy 155.569666 -321.827398) (xy 155.583548 -321.846913) (xy 156.657288 -321.846913) (xy 156.657288 -321.782991)
			(xy 156.665299 -321.719573) (xy 156.681196 -321.657659) (xy 156.704728 -321.598226) (xy 156.735522 -321.542211)
			(xy 156.773095 -321.490496) (xy 156.816852 -321.443899) (xy 156.866105 -321.403154) (xy 156.920076 -321.368903)
			(xy 156.977915 -321.341686) (xy 157.038708 -321.321933) (xy 157.101498 -321.309955) (xy 157.165294 -321.305942)
			(xy 157.22909 -321.309955) (xy 157.29188 -321.321933) (xy 157.352673 -321.341686) (xy 157.410512 -321.368903)
			(xy 157.464483 -321.403154) (xy 157.513736 -321.443899) (xy 157.557493 -321.490496) (xy 157.595066 -321.542211)
			(xy 157.62586 -321.598226) (xy 157.649392 -321.657659) (xy 157.665289 -321.719573) (xy 157.6733 -321.782991)
			(xy 157.673802 -321.814952) (xy 157.6733 -321.846913) (xy 157.665289 -321.910331) (xy 157.649392 -321.972245)
			(xy 157.62586 -322.031678) (xy 157.595066 -322.087693) (xy 157.557493 -322.139408) (xy 157.513736 -322.186005)
			(xy 157.464483 -322.22675) (xy 157.410512 -322.261001) (xy 157.352673 -322.288218) (xy 157.29188 -322.307971)
			(xy 157.22909 -322.319949) (xy 157.165294 -322.323963) (xy 157.101498 -322.319949) (xy 157.038708 -322.307971)
			(xy 156.977915 -322.288218) (xy 156.920076 -322.261001) (xy 156.866105 -322.22675) (xy 156.816852 -322.186005)
			(xy 156.773095 -322.139408) (xy 156.735522 -322.087693) (xy 156.704728 -322.031678) (xy 156.681196 -321.972245)
			(xy 156.665299 -321.910331) (xy 156.657288 -321.846913) (xy 155.583548 -321.846913) (xy 155.587192 -321.852036)
			(xy 155.584546 -321.882211) (xy 155.57299 -321.941675) (xy 155.554467 -321.99935) (xy 155.529237 -322.054422)
			(xy 155.497657 -322.106116) (xy 155.479242 -322.130166) (xy 155.474162 -322.13677) (xy 155.46578 -322.160138)
			(xy 155.464369 -322.164317) (xy 155.462834 -322.173001) (xy 155.462732 -322.17741) (xy 155.462732 -322.207128)
			(xy 155.468574 -322.223384) (xy 155.474162 -322.230242) (xy 155.495691 -322.257577) (xy 155.531868 -322.317015)
			(xy 155.559607 -322.380829) (xy 155.57839 -322.447828) (xy 155.587866 -322.516761) (xy 155.588462 -322.551552)
			(xy 155.58796 -322.583513) (xy 155.579949 -322.646931) (xy 155.564052 -322.708845) (xy 155.54052 -322.768278)
			(xy 155.509726 -322.824293) (xy 155.472153 -322.876008) (xy 155.428396 -322.922605) (xy 155.379143 -322.96335)
			(xy 155.325172 -322.997601) (xy 155.267333 -323.024818) (xy 155.20654 -323.044571) (xy 155.14375 -323.056549)
			(xy 155.079954 -323.060563) (xy 155.016158 -323.056549) (xy 154.953368 -323.044571) (xy 154.892575 -323.024818)
			(xy 154.834736 -322.997601) (xy 154.780765 -322.96335) (xy 154.731512 -322.922605) (xy 154.687755 -322.876008)
			(xy 154.650182 -322.824293) (xy 154.619388 -322.768278) (xy 154.595856 -322.708845) (xy 154.579959 -322.646931)
			(xy 154.571948 -322.583513) (xy 154.571446 -322.551552) (xy 154.572018 -322.516761) (xy 154.581507 -322.44783)
			(xy 154.600302 -322.380835) (xy 154.628052 -322.317026) (xy 154.664239 -322.257595) (xy 154.685746 -322.230242)
			(xy 154.691334 -322.223384) (xy 154.697176 -322.207128) (xy 154.697176 -322.15963) (xy 154.691334 -322.143374)
			(xy 154.685492 -322.136262) (xy 154.679396 -322.128642) (xy 154.672146 -322.119274) (xy 154.658424 -322.099963)
			(xy 154.651964 -322.090034) (xy 154.645305 -322.080874) (xy 154.626056 -322.068999) (xy 154.61488 -322.067174)
			(xy 154.580999 -322.06285) (xy 154.514734 -322.046288) (xy 154.451278 -322.021017) (xy 154.39177 -321.98749)
			(xy 154.364182 -321.967352) (xy 154.355038 -321.960494) (xy 154.332686 -321.955922) (xy 154.233626 -321.980306)
			(xy 154.215846 -321.994784) (xy 154.21102 -322.005198) (xy 154.19911 -322.029412) (xy 154.169487 -322.074514)
			(xy 154.133805 -322.114993) (xy 154.092778 -322.150043) (xy 154.047223 -322.178964) (xy 153.998048 -322.20118)
			(xy 153.946234 -322.216248) (xy 153.892814 -322.223868) (xy 153.865834 -322.2244) (xy 153.83858 -322.223939)
			(xy 153.784627 -322.216186) (xy 153.732326 -322.200833) (xy 153.682742 -322.178193) (xy 153.636886 -322.148727)
			(xy 153.59569 -322.113034) (xy 153.559994 -322.071841) (xy 153.530523 -322.025987) (xy 153.507879 -321.976406)
			(xy 153.492521 -321.924107) (xy 153.484763 -321.870154) (xy 153.484763 -321.815646) (xy 153.492521 -321.761693)
			(xy 153.507879 -321.709394) (xy 153.530523 -321.659813) (xy 153.559994 -321.613959) (xy 153.59569 -321.572766)
			(xy 153.636886 -321.537073) (xy 153.682742 -321.507607) (xy 153.732326 -321.484967) (xy 153.784627 -321.469614)
			(xy 153.83858 -321.461861) (xy 153.865834 -321.461384) (xy 153.895008 -321.461944) (xy 153.952676 -321.470825)
			(xy 154.008327 -321.488362) (xy 154.034744 -321.500754) (xy 154.045158 -321.506088) (xy 154.068018 -321.506342)
			(xy 154.160728 -321.463924) (xy 154.17546 -321.446144) (xy 154.178254 -321.434968) (xy 154.181048 -321.424554)
			(xy 154.185112 -321.410584) (xy 154.177238 -321.383152) (xy 154.088592 -321.30238) (xy 154.060652 -321.297046)
			(xy 154.04719 -321.30238) (xy 154.018141 -321.31296) (xy 153.958123 -321.327795) (xy 153.896747 -321.335227)
			(xy 153.865834 -321.335654) (xy 153.835085 -321.33521) (xy 153.774036 -321.327801) (xy 153.714325 -321.313087)
			(xy 153.656823 -321.291283) (xy 153.602369 -321.262706) (xy 153.551756 -321.227773) (xy 153.505724 -321.186994)
			(xy 153.464943 -321.140964) (xy 153.430007 -321.090353) (xy 153.401428 -321.035901) (xy 153.37962 -320.9784)
			(xy 153.364903 -320.91869) (xy 153.357491 -320.857641) (xy 153.357072 -320.826892) (xy 153.357072 -320.826384)
			(xy 153.357572 -320.795185) (xy 153.365259 -320.733261) (xy 153.380467 -320.672743) (xy 153.402967 -320.614541)
			(xy 153.432421 -320.559531) (xy 153.450036 -320.533776) (xy 153.454354 -320.527426) (xy 153.459434 -320.511678)
			(xy 153.459434 -320.51117) (xy 153.462482 -320.502026) (xy 153.460958 -320.482214) (xy 153.418032 -320.397632)
			(xy 153.413481 -320.389393) (xy 153.399539 -320.376766) (xy 153.381973 -320.37004) (xy 153.372566 -320.369692)
			(xy 151.838152 -320.369692) (xy 151.829018 -320.370081) (xy 151.811915 -320.376506) (xy 151.798153 -320.388521)
			(xy 151.793448 -320.396362) (xy 151.76627 -320.446654) (xy 151.760174 -320.458338) (xy 151.75737 -320.463907)
			(xy 151.754281 -320.475983) (xy 151.754078 -320.482214) (xy 151.754078 -320.517012) (xy 151.757888 -320.53022)
			(xy 151.761444 -320.536316) (xy 151.770147 -320.551082) (xy 151.78578 -320.581589) (xy 151.792686 -320.597276)
			(xy 151.799036 -320.61277) (xy 151.803669 -320.623163) (xy 151.820163 -320.638793) (xy 151.8418 -320.645731)
			(xy 151.853138 -320.644774) (xy 151.869885 -320.642651) (xy 151.903568 -320.640363) (xy 151.920448 -320.640202)
			(xy 151.951177 -320.640669) (xy 152.012186 -320.648082) (xy 152.071857 -320.662795) (xy 152.129319 -320.684593)
			(xy 152.183735 -320.713157) (xy 152.234312 -320.748073) (xy 152.280311 -320.78883) (xy 152.321063 -320.834834)
			(xy 152.355973 -320.885414) (xy 152.384531 -320.939834) (xy 152.406322 -320.997299) (xy 152.421028 -321.056971)
			(xy 152.428435 -321.117981) (xy 152.428956 -321.14871) (xy 152.428956 -321.149726) (xy 152.428891 -321.16334)
			(xy 152.427495 -321.190533) (xy 152.426162 -321.204082) (xy 152.425908 -321.205352) (xy 152.425654 -321.211194)
			(xy 152.425908 -321.217036) (xy 152.426162 -321.218306) (xy 152.427617 -321.232421) (xy 152.429143 -321.260759)
			(xy 152.42921 -321.274948) (xy 152.42921 -321.27571) (xy 152.428745 -321.306457) (xy 152.421332 -321.367503)
			(xy 152.406616 -321.42721) (xy 152.38481 -321.484708) (xy 152.356233 -321.539159) (xy 152.321302 -321.589768)
			(xy 152.280525 -321.635798) (xy 152.234498 -321.676578) (xy 152.183891 -321.711514) (xy 152.129443 -321.740094)
			(xy 152.071946 -321.761904) (xy 152.01224 -321.776626) (xy 151.951195 -321.784043) (xy 151.920448 -321.784472)
			(xy 151.907024 -321.78439) (xy 151.880213 -321.782992) (xy 151.866854 -321.781678) (xy 151.856948 -321.780662)
			(xy 151.838406 -321.785996) (xy 151.768556 -321.840098) (xy 151.75865 -321.856608) (xy 151.757126 -321.866514)
			(xy 151.751538 -321.896486) (xy 151.74976 -321.904868) (xy 151.751792 -321.921632) (xy 151.756364 -321.930776)
			(xy 151.771604 -321.958462) (xy 151.77634 -321.966228) (xy 151.790137 -321.978062) (xy 151.798528 -321.981576)
			(xy 151.828116 -321.992906) (xy 151.884461 -322.021881) (xy 151.936769 -322.057633) (xy 151.984229 -322.099607)
			(xy 152.005538 -322.123054) (xy 152.010872 -322.128388) (xy 152.01392 -322.130674) (xy 152.038085 -322.14863)
			(xy 152.082439 -322.189341) (xy 152.121677 -322.235002) (xy 152.155253 -322.284975) (xy 152.182697 -322.338562)
			(xy 152.203625 -322.395012) (xy 152.217745 -322.453538) (xy 152.224859 -322.513322) (xy 152.225248 -322.543424)
			(xy 152.224709 -322.577073) (xy 152.215844 -322.643785) (xy 152.19826 -322.708745) (xy 152.172262 -322.770819)
			(xy 152.138306 -322.828923) (xy 152.096984 -322.882041) (xy 152.049018 -322.929246) (xy 151.995246 -322.969714)
			(xy 151.966168 -322.986654) (xy 151.957786 -322.992496) (xy 151.934599 -323.012133) (xy 151.88437 -323.046328)
			(xy 151.830422 -323.074289) (xy 151.773524 -323.095615) (xy 151.714488 -323.110004) (xy 151.654158 -323.117248)
			(xy 151.623776 -323.117718) (xy 151.593046 -323.117253) (xy 151.532034 -323.109842) (xy 151.472359 -323.095131)
			(xy 151.414894 -323.073335) (xy 151.360474 -323.044771) (xy 151.309893 -323.009857) (xy 151.26389 -322.9691)
			(xy 151.223135 -322.923096) (xy 151.188221 -322.872514) (xy 151.159659 -322.818094) (xy 151.137865 -322.760627)
			(xy 151.123156 -322.700953) (xy 151.115747 -322.63994) (xy 151.115268 -322.60921) (xy 151.115437 -322.591881)
			(xy 151.117851 -322.557306) (xy 151.120094 -322.540122) (xy 151.120094 -322.526406) (xy 151.11797 -322.509659)
			(xy 151.115679 -322.475976) (xy 151.115522 -322.459096) (xy 151.115522 -322.458842) (xy 151.115863 -322.432809)
			(xy 151.121206 -322.381018) (xy 151.12619 -322.355464) (xy 151.127682 -322.346496) (xy 151.124937 -322.328537)
			(xy 151.120856 -322.320412) (xy 151.106124 -322.293996) (xy 151.101552 -322.285868) (xy 151.087836 -322.27393)
			(xy 151.0792 -322.270882) (xy 151.048716 -322.259231) (xy 150.990769 -322.229211) (xy 150.93714 -322.192024)
			(xy 150.888709 -322.14828) (xy 150.86711 -322.123816) (xy 150.861776 -322.118482) (xy 150.838498 -322.097728)
			(xy 150.796663 -322.051476) (xy 150.760794 -322.000459) (xy 150.731426 -321.945441) (xy 150.709001 -321.887247)
			(xy 150.693854 -321.82675) (xy 150.686213 -321.764854) (xy 150.685754 -321.733672) (xy 150.686261 -321.701328)
			(xy 150.694466 -321.637163) (xy 150.71074 -321.574556) (xy 150.734821 -321.514518) (xy 150.76632 -321.458017)
			(xy 150.804728 -321.405966) (xy 150.849426 -321.359205) (xy 150.899692 -321.318489) (xy 150.954714 -321.284474)
			(xy 150.98395 -321.27063) (xy 150.98903 -321.268344) (xy 150.993602 -321.264788) (xy 151.001319 -321.258394)
			(xy 151.011407 -321.241093) (xy 151.014102 -321.221248) (xy 151.008994 -321.201884) (xy 151.003254 -321.193668)
			(xy 150.999952 -321.18935) (xy 150.995888 -321.185794) (xy 150.995634 -321.18554) (xy 150.966197 -321.159485)
			(xy 150.914911 -321.099908) (xy 150.893526 -321.066922) (xy 150.89251 -321.065144) (xy 150.887176 -321.058032)
			(xy 150.885652 -321.056508) (xy 150.865435 -321.033132) (xy 150.830209 -320.982348) (xy 150.801384 -320.927676)
			(xy 150.779385 -320.869919) (xy 150.764534 -320.809925) (xy 150.757049 -320.748574) (xy 150.75662 -320.717672)
			(xy 150.75713 -320.684021) (xy 150.76595 -320.617301) (xy 150.783512 -320.552332) (xy 150.79599 -320.521076)
			(xy 150.798276 -320.515996) (xy 150.800054 -320.511932) (xy 150.804494 -320.500074) (xy 150.802346 -320.47488)
			(xy 150.79599 -320.463926) (xy 150.749508 -320.392806) (xy 150.744646 -320.385872) (xy 150.731311 -320.37545)
			(xy 150.715299 -320.369965) (xy 150.706836 -320.369692) (xy 148.648928 -320.369692) (xy 148.639091 -320.369155)
			(xy 148.620931 -320.361567) (xy 148.613622 -320.35496) (xy 147.506436 -319.247774) (xy 147.499091 -319.240966)
			(xy 147.480627 -319.233245) (xy 147.470622 -319.232788) (xy 147.124928 -319.232788) (xy 147.114967 -319.2323)
			(xy 147.096545 -319.22471) (xy 147.089114 -319.218056) (xy 146.879818 -319.00876) (xy 146.464274 -318.59347)
			(xy 146.462496 -318.591692) (xy 146.461734 -318.590676) (xy 146.457162 -318.586104) (xy 146.449288 -318.567562)
			(xy 146.449288 -318.559942) (xy 146.449288 -318.211708) (xy 146.449288 -318.208406) (xy 146.44829 -318.199214)
			(xy 146.440591 -318.18242) (xy 146.434302 -318.17564) (xy 146.291046 -318.032384) (xy 146.284338 -318.025144)
			(xy 146.276752 -318.006939) (xy 146.276314 -317.997078) (xy 146.276314 -316.08014) (xy 146.276314 -316.079886)
			(xy 146.276791 -316.06992) (xy 146.284367 -316.051483) (xy 146.291046 -316.044072) (xy 146.434302 -315.90107)
			(xy 146.440611 -315.89423) (xy 146.448303 -315.877302) (xy 146.449288 -315.86805) (xy 146.449288 -315.578998)
			(xy 146.449288 -315.568838) (xy 146.457162 -315.550296) (xy 146.461734 -315.545724) (xy 146.462496 -315.544708)
			(xy 146.464274 -315.54293) (xy 146.53514 -315.472064) (xy 146.572732 -315.434726) (xy 146.57829 -315.428143)
			(xy 146.585051 -315.412307) (xy 146.58594 -315.403738) (xy 146.58594 -311.945782) (xy 146.586368 -311.935714)
			(xy 146.594091 -311.917118) (xy 146.600926 -311.909714) (xy 147.000214 -311.510426) (xy 147.000722 -311.509918)
			(xy 147.007303 -311.502537) (xy 147.014748 -311.484237) (xy 147.0152 -311.474358) (xy 147.0152 -309.930546)
			(xy 146.990308 -309.901844) (xy 146.971258 -309.899304) (xy 146.944189 -309.895135) (xy 146.891541 -309.880048)
			(xy 146.841592 -309.857586) (xy 146.795369 -309.82821) (xy 146.753823 -309.792525) (xy 146.717809 -309.751265)
			(xy 146.688067 -309.705277) (xy 146.665208 -309.655508) (xy 146.649703 -309.602982) (xy 146.64187 -309.548777)
			(xy 146.641871 -309.49401) (xy 146.649705 -309.439806) (xy 146.665212 -309.38728) (xy 146.688073 -309.337511)
			(xy 146.717817 -309.291525) (xy 146.753833 -309.250266) (xy 146.79538 -309.214582) (xy 146.841603 -309.185208)
			(xy 146.891553 -309.162748) (xy 146.944202 -309.147663) (xy 146.971258 -309.1434) (xy 146.990308 -309.14086)
			(xy 147.0152 -309.112158) (xy 147.0152 -305.63947) (xy 147.014771 -305.629402) (xy 147.007049 -305.610806)
			(xy 147.000214 -305.603402) (xy 146.2913 -304.894488) (xy 146.284456 -304.887089) (xy 146.276726 -304.868491)
			(xy 146.276314 -304.85842) (xy 145.00606 -303.588166) (xy 144.999521 -303.582051) (xy 144.983324 -303.574452)
			(xy 144.965499 -303.572915) (xy 144.948241 -303.57763) (xy 144.940782 -303.582578) (xy 144.862804 -303.637696)
			(xy 144.855364 -303.643438) (xy 144.844917 -303.65904) (xy 144.840807 -303.677362) (xy 144.841722 -303.686718)
			(xy 144.844008 -303.70145) (xy 144.847056 -303.708054) (xy 144.87649 -303.772908) (xy 144.92895 -303.905334)
			(xy 144.973952 -304.040476) (xy 145.011355 -304.177916) (xy 145.041044 -304.317226) (xy 145.062926 -304.457973)
			(xy 145.076933 -304.599721) (xy 145.083023 -304.742029) (xy 145.081175 -304.884455) (xy 145.071396 -305.026557)
			(xy 145.053716 -305.167894) (xy 145.02819 -305.308026) (xy 144.994897 -305.446519) (xy 144.953941 -305.582942)
			(xy 144.905449 -305.716872) (xy 144.849571 -305.847892) (xy 144.786481 -305.975596) (xy 144.716375 -306.099587)
			(xy 144.639471 -306.21948) (xy 144.556007 -306.334903) (xy 144.466242 -306.445497) (xy 144.370457 -306.550919)
			(xy 144.268947 -306.650841) (xy 144.162028 -306.744953) (xy 144.050033 -306.832963) (xy 143.933309 -306.914597)
			(xy 143.812219 -306.989602) (xy 143.687138 -307.057745) (xy 143.558455 -307.118814) (xy 143.42657 -307.17262)
			(xy 143.291893 -307.218995) (xy 143.154841 -307.257795) (xy 143.015841 -307.288901) (xy 142.875324 -307.312215)
			(xy 142.733726 -307.327665) (xy 142.591487 -307.335203) (xy 142.44905 -307.334805) (xy 142.306855 -307.326473)
			(xy 142.165346 -307.310233) (xy 142.024961 -307.286135) (xy 141.886136 -307.254254) (xy 141.749304 -307.214689)
			(xy 141.614887 -307.167563) (xy 141.483305 -307.113022) (xy 141.354965 -307.051235) (xy 141.230267 -306.982395)
			(xy 141.109597 -306.906715) (xy 140.99333 -306.824431) (xy 140.881828 -306.735797) (xy 140.775437 -306.64109)
			(xy 140.674486 -306.540602) (xy 140.579291 -306.434647) (xy 140.490145 -306.323554) (xy 140.407327 -306.207667)
			(xy 140.331093 -306.087347) (xy 140.26168 -305.962966) (xy 140.199304 -305.834912) (xy 140.144159 -305.703582)
			(xy 140.096415 -305.569383) (xy 140.056221 -305.432734) (xy 140.023702 -305.294057) (xy 139.998958 -305.153785)
			(xy 139.982068 -305.012352) (xy 139.973082 -304.870197) (xy 139.97203 -304.727763) (xy 139.978913 -304.585491)
			(xy 139.993712 -304.443823) (xy 140.016379 -304.3032) (xy 140.046846 -304.164059) (xy 140.085016 -304.02683)
			(xy 140.130771 -303.891941) (xy 140.18397 -303.75981) (xy 140.244446 -303.630848) (xy 140.312013 -303.505455)
			(xy 140.386461 -303.384021) (xy 140.467557 -303.266923) (xy 140.555051 -303.154524) (xy 140.648671 -303.047174)
			(xy 140.748125 -302.945206) (xy 140.853105 -302.848936) (xy 140.963285 -302.758664) (xy 141.078323 -302.674671)
			(xy 141.197861 -302.597216) (xy 141.321528 -302.52654) (xy 141.448941 -302.462864) (xy 141.579703 -302.406384)
			(xy 141.646402 -302.381412) (xy 141.656816 -302.377602) (xy 142.77594 -301.258478) (xy 142.782789 -301.251081)
			(xy 142.790525 -301.232482) (xy 142.790926 -301.22241) (xy 142.79118 -295.995344) (xy 142.79118 -295.99509)
			(xy 142.79118 -294.997632) (xy 142.791644 -294.973054) (xy 142.799296 -294.924497) (xy 142.81445 -294.877735)
			(xy 142.836731 -294.833919) (xy 142.865591 -294.794127) (xy 142.88262 -294.776398) (xy 143.08201 -294.577008)
			(xy 143.304006 -294.355012) (xy 143.310685 -294.347598) (xy 143.318276 -294.329166) (xy 143.318275 -294.309231)
			(xy 143.310684 -294.290799) (xy 143.304006 -294.283384) (xy 143.082772 -294.06215) (xy 143.075374 -294.055303)
			(xy 143.056776 -294.047571) (xy 143.046704 -294.047164) (xy 142.514066 -294.047164) (xy 142.502222 -294.047789)
			(xy 142.481038 -294.058388) (xy 142.473426 -294.067484) (xy 142.47114 -294.070532) (xy 142.419578 -294.15613)
			(xy 142.418816 -294.182546) (xy 142.424912 -294.194484) (xy 142.435907 -294.216478) (xy 142.451505 -294.263107)
			(xy 142.459437 -294.311632) (xy 142.459964 -294.336216) (xy 142.459517 -294.360207) (xy 142.452008 -294.407598)
			(xy 142.437177 -294.453231) (xy 142.41539 -294.495981) (xy 142.387184 -294.534797) (xy 142.353252 -294.568723)
			(xy 142.31443 -294.596922) (xy 142.271675 -294.6187) (xy 142.22604 -294.633522) (xy 142.178647 -294.641021)
			(xy 142.154656 -294.641524) (xy 142.13093 -294.641071) (xy 142.08405 -294.633726) (xy 142.03887 -294.619218)
			(xy 141.996478 -294.597898) (xy 141.957892 -294.570277) (xy 141.924043 -294.537022) (xy 141.895744 -294.498932)
			(xy 141.873677 -294.456923) (xy 141.858372 -294.412007) (xy 141.850197 -294.365265) (xy 141.849348 -294.34155)
			(xy 141.849348 -294.337486) (xy 141.849677 -294.314405) (xy 141.856423 -294.268741) (xy 141.869941 -294.224605)
			(xy 141.879574 -294.203628) (xy 141.882114 -294.198548) (xy 141.884654 -294.187372) (xy 141.884654 -294.162226)
			(xy 141.884457 -294.155354) (xy 141.880839 -294.142097) (xy 141.877542 -294.136064) (xy 141.838934 -294.071802)
			(xy 141.834125 -294.064514) (xy 141.820635 -294.053445) (xy 141.804223 -294.047519) (xy 141.7955 -294.047164)
			(xy 141.574266 -294.047164) (xy 141.562422 -294.047789) (xy 141.541238 -294.058388) (xy 141.533626 -294.067484)
			(xy 141.53134 -294.070532) (xy 141.479778 -294.15613) (xy 141.479016 -294.182546) (xy 141.485112 -294.194484)
			(xy 141.496107 -294.216478) (xy 141.511705 -294.263107) (xy 141.519637 -294.311632) (xy 141.520164 -294.336216)
			(xy 141.519717 -294.360207) (xy 141.512208 -294.407598) (xy 141.497377 -294.453231) (xy 141.47559 -294.495981)
			(xy 141.447384 -294.534797) (xy 141.413452 -294.568723) (xy 141.37463 -294.596922) (xy 141.331875 -294.6187)
			(xy 141.28624 -294.633522) (xy 141.238847 -294.641021) (xy 141.214856 -294.641524) (xy 141.19113 -294.641071)
			(xy 141.14425 -294.633726) (xy 141.09907 -294.619218) (xy 141.056678 -294.597898) (xy 141.018092 -294.570277)
			(xy 140.984243 -294.537022) (xy 140.955944 -294.498932) (xy 140.933877 -294.456923) (xy 140.918572 -294.412007)
			(xy 140.910397 -294.365265) (xy 140.909548 -294.34155) (xy 140.909548 -294.337486) (xy 140.909877 -294.314405)
			(xy 140.916623 -294.268741) (xy 140.930141 -294.224605) (xy 140.939774 -294.203628) (xy 140.942314 -294.198548)
			(xy 140.944854 -294.187372) (xy 140.944854 -294.162226) (xy 140.944657 -294.155354) (xy 140.941039 -294.142097)
			(xy 140.937742 -294.136064) (xy 140.899134 -294.071802) (xy 140.894325 -294.064514) (xy 140.880835 -294.053445)
			(xy 140.864423 -294.047519) (xy 140.8557 -294.047164) (xy 140.634212 -294.047164) (xy 140.622363 -294.04778)
			(xy 140.601163 -294.058367) (xy 140.593572 -294.067484) (xy 140.591286 -294.070532) (xy 140.539724 -294.15613)
			(xy 140.538962 -294.182546) (xy 140.545058 -294.194484) (xy 140.556052 -294.216478) (xy 140.571647 -294.263108)
			(xy 140.579578 -294.311632) (xy 140.58011 -294.336216) (xy 140.579588 -294.361471) (xy 140.571275 -294.411293)
			(xy 140.554874 -294.459067) (xy 140.530833 -294.50349) (xy 140.499809 -294.54335) (xy 140.462647 -294.57756)
			(xy 140.420361 -294.605186) (xy 140.374105 -294.625476) (xy 140.32514 -294.637876) (xy 140.274802 -294.642047)
			(xy 140.224464 -294.637876) (xy 140.175499 -294.625476) (xy 140.129243 -294.605186) (xy 140.086957 -294.57756)
			(xy 140.049795 -294.54335) (xy 140.018771 -294.50349) (xy 139.99473 -294.459067) (xy 139.978329 -294.411293)
			(xy 139.970016 -294.361471) (xy 139.969494 -294.336216) (xy 139.969494 -294.334946) (xy 139.970089 -294.310029)
			(xy 139.97838 -294.260885) (xy 139.986004 -294.237156) (xy 139.988798 -294.229028) (xy 139.988798 -294.186864)
			(xy 139.988439 -294.178445) (xy 139.98298 -294.162515) (xy 139.97813 -294.155622) (xy 139.925298 -294.08755)
			(xy 139.899898 -294.07739) (xy 139.886436 -294.079422) (xy 139.866103 -294.082189) (xy 139.825168 -294.085114)
			(xy 139.804648 -294.085264) (xy 139.784191 -294.08512) (xy 139.743382 -294.082199) (xy 139.723114 -294.079422)
			(xy 139.709144 -294.07739) (xy 139.683998 -294.08755) (xy 139.649454 -294.132254) (xy 139.623038 -294.166036)
			(xy 139.616616 -294.175034) (xy 139.611473 -294.196509) (xy 139.613132 -294.207438) (xy 139.614402 -294.213026)
			(xy 139.616434 -294.217852) (xy 139.627444 -294.245997) (xy 139.639341 -294.305241) (xy 139.640056 -294.335454)
			(xy 139.640056 -294.336216) (xy 139.639584 -294.360208) (xy 139.632076 -294.4076) (xy 139.617248 -294.453235)
			(xy 139.595465 -294.495989) (xy 139.567262 -294.53481) (xy 139.533334 -294.568741) (xy 139.494517 -294.596948)
			(xy 139.451765 -294.618736) (xy 139.406132 -294.633569) (xy 139.35874 -294.641082) (xy 139.334748 -294.641524)
			(xy 139.311022 -294.64107) (xy 139.264143 -294.633724) (xy 139.218965 -294.619216) (xy 139.176573 -294.597895)
			(xy 139.137989 -294.570275) (xy 139.104141 -294.537019) (xy 139.075843 -294.498929) (xy 139.053776 -294.456921)
			(xy 139.038471 -294.412006) (xy 139.030297 -294.365264) (xy 139.02944 -294.34155) (xy 139.02944 -294.337486)
			(xy 139.029769 -294.314405) (xy 139.036515 -294.268741) (xy 139.050033 -294.224605) (xy 139.059666 -294.203628)
			(xy 139.062206 -294.198548) (xy 139.064746 -294.187372) (xy 139.064746 -294.162226) (xy 139.06455 -294.155354)
			(xy 139.060938 -294.142094) (xy 139.057634 -294.136064) (xy 139.019026 -294.071802) (xy 139.014217 -294.064515)
			(xy 139.000727 -294.053448) (xy 138.984314 -294.047525) (xy 138.975592 -294.047164) (xy 138.754104 -294.047164)
			(xy 138.742256 -294.047781) (xy 138.721059 -294.058371) (xy 138.713464 -294.067484) (xy 138.711178 -294.070532)
			(xy 138.659616 -294.15613) (xy 138.658854 -294.182546) (xy 138.66495 -294.194484) (xy 138.675944 -294.216478)
			(xy 138.69154 -294.263108) (xy 138.699471 -294.311632) (xy 138.700002 -294.336216) (xy 138.69948 -294.361471)
			(xy 138.691167 -294.411293) (xy 138.674766 -294.459067) (xy 138.650725 -294.50349) (xy 138.619701 -294.54335)
			(xy 138.582539 -294.57756) (xy 138.540253 -294.605186) (xy 138.493997 -294.625476) (xy 138.445032 -294.637876)
			(xy 138.394694 -294.642047) (xy 138.344356 -294.637876) (xy 138.295391 -294.625476) (xy 138.249135 -294.605186)
			(xy 138.206849 -294.57756) (xy 138.169687 -294.54335) (xy 138.138663 -294.50349) (xy 138.114622 -294.459067)
			(xy 138.098221 -294.411293) (xy 138.089908 -294.361471) (xy 138.089386 -294.336216) (xy 138.089513 -294.324676)
			(xy 138.09129 -294.301664) (xy 138.092942 -294.290242) (xy 138.09345 -294.286432) (xy 138.09345 -294.285416)
			(xy 138.097778 -294.262305) (xy 138.1126 -294.217684) (xy 138.134095 -294.175867) (xy 138.161754 -294.137844)
			(xy 138.19492 -294.104517) (xy 138.232808 -294.076674) (xy 138.25347 -294.065452) (xy 138.264646 -294.05961)
			(xy 138.278362 -294.040052) (xy 138.292332 -293.948866) (xy 138.293429 -293.936957) (xy 138.285881 -293.914297)
			(xy 138.277854 -293.905432) (xy 138.16711 -293.794688) (xy 138.159716 -293.787831) (xy 138.141117 -293.780079)
			(xy 138.131042 -293.779702) (xy 138.102594 -293.779702) (xy 138.089386 -293.783512) (xy 138.08329 -293.787068)
			(xy 138.059224 -293.800998) (xy 138.007276 -293.820817) (xy 137.952594 -293.830883) (xy 137.924794 -293.831518)
			(xy 137.901104 -293.831071) (xy 137.854294 -293.823753) (xy 137.809174 -293.809295) (xy 137.766829 -293.788042)
			(xy 137.728273 -293.760506) (xy 137.694433 -293.727345) (xy 137.666119 -293.689357) (xy 137.644011 -293.647452)
			(xy 137.628639 -293.602635) (xy 137.620373 -293.555983) (xy 137.619486 -293.532306) (xy 137.619486 -293.525956)
			(xy 137.619976 -293.501739) (xy 137.627672 -293.453918) (xy 137.642818 -293.407911) (xy 137.665032 -293.36487)
			(xy 137.69376 -293.325873) (xy 137.710672 -293.308532) (xy 137.710926 -293.308278) (xy 137.718038 -293.301166)
			(xy 137.727182 -293.280084) (xy 137.727182 -293.27983) (xy 137.728198 -293.277798) (xy 137.730992 -293.272464)
			(xy 137.733786 -293.261034) (xy 137.733786 -292.595046) (xy 137.733353 -292.58498) (xy 137.725623 -292.566392)
			(xy 137.7188 -292.558978) (xy 137.310622 -292.1508) (xy 137.303704 -292.14453) (xy 137.28664 -292.136991)
			(xy 137.277348 -292.136068) (xy 137.218674 -292.13302) (xy 137.208006 -292.132512) (xy 137.194798 -292.137338)
			(xy 137.189718 -292.13937) (xy 137.17143 -292.14826) (xy 137.167366 -292.151308) (xy 137.147466 -292.165509)
			(xy 137.104099 -292.188071) (xy 137.057695 -292.20345) (xy 137.009436 -292.211254) (xy 136.984994 -292.21176)
			(xy 136.98474 -292.21176) (xy 136.959459 -292.21127) (xy 136.909587 -292.202954) (xy 136.861763 -292.186542)
			(xy 136.817294 -292.162481) (xy 136.777391 -292.131429) (xy 136.743145 -292.094232) (xy 136.715488 -292.051905)
			(xy 136.695176 -292.005603) (xy 136.682763 -291.956589) (xy 136.678587 -291.9062) (xy 136.682763 -291.855811)
			(xy 136.695176 -291.806797) (xy 136.715488 -291.760495) (xy 136.743145 -291.718168) (xy 136.777391 -291.680971)
			(xy 136.817294 -291.649919) (xy 136.861763 -291.625858) (xy 136.909587 -291.609446) (xy 136.959459 -291.60113)
			(xy 136.98474 -291.600636) (xy 136.985248 -291.600636) (xy 137.007219 -291.601053) (xy 137.050696 -291.607428)
			(xy 137.071862 -291.613336) (xy 137.083546 -291.616638) (xy 137.096754 -291.614098) (xy 137.102298 -291.612844)
			(xy 137.112683 -291.608229) (xy 137.117328 -291.604954) (xy 137.180066 -291.55771) (xy 137.189168 -291.550106)
			(xy 137.199754 -291.528915) (xy 137.200386 -291.51707) (xy 137.200386 -291.278818) (xy 137.193528 -291.254942)
			(xy 137.190226 -291.249354) (xy 137.177292 -291.225922) (xy 137.15894 -291.175651) (xy 137.149622 -291.122951)
			(xy 137.149623 -291.069435) (xy 137.158943 -291.016736) (xy 137.177298 -290.966465) (xy 137.190226 -290.94303)
			(xy 137.193528 -290.937442) (xy 137.200386 -290.913566) (xy 137.200386 -289.658806) (xy 137.193528 -289.63493)
			(xy 137.190226 -289.629342) (xy 137.177289 -289.605911) (xy 137.158933 -289.55564) (xy 137.149613 -289.502939)
			(xy 137.149078 -289.47618) (xy 137.149078 -289.475926) (xy 137.149665 -289.449117) (xy 137.159064 -289.396327)
			(xy 137.177508 -289.34598) (xy 137.19048 -289.32251) (xy 137.193782 -289.316668) (xy 137.198608 -289.299396)
			(xy 137.200386 -289.285934) (xy 137.200386 -289.241738) (xy 137.20092 -289.2319) (xy 137.208503 -289.213735)
			(xy 137.215118 -289.206432) (xy 137.42035 -289.0012) (xy 137.425336 -288.9957) (xy 137.43218 -288.982534)
			(xy 137.433812 -288.975292) (xy 137.434828 -288.96564) (xy 137.434828 -288.955226) (xy 137.433304 -288.943288)
			(xy 137.428986 -288.925508) (xy 137.426192 -288.920174) (xy 137.411206 -288.888424) (xy 137.40892 -288.882836)
			(xy 137.39368 -288.862516) (xy 137.388092 -288.858198) (xy 137.37463 -288.84753) (xy 137.369046 -288.843474)
			(xy 137.356301 -288.838192) (xy 137.349484 -288.837116) (xy 137.28954 -288.829496) (xy 137.282936 -288.828734)
			(xy 137.279126 -288.828734) (xy 137.273117 -288.828904) (xy 137.261438 -288.831735) (xy 137.256012 -288.834322)
			(xy 137.245852 -288.839402) (xy 137.236708 -288.845498) (xy 137.224262 -288.855658) (xy 137.22096 -288.859722)
			(xy 137.203375 -288.880247) (xy 137.162285 -288.915353) (xy 137.115664 -288.942689) (xy 137.064963 -288.961402)
			(xy 137.011762 -288.97091) (xy 136.98474 -288.971482) (xy 136.959482 -288.970993) (xy 136.909655 -288.962684)
			(xy 136.861875 -288.946286) (xy 136.817446 -288.922248) (xy 136.77758 -288.891224) (xy 136.743364 -288.85406)
			(xy 136.715733 -288.811772) (xy 136.69544 -288.765512) (xy 136.683038 -288.716543) (xy 136.678866 -288.6662)
			(xy 136.683038 -288.615857) (xy 136.69544 -288.566888) (xy 136.715733 -288.520628) (xy 136.743364 -288.47834)
			(xy 136.77758 -288.441176) (xy 136.817446 -288.410152) (xy 136.861875 -288.386114) (xy 136.909655 -288.369716)
			(xy 136.959482 -288.361407) (xy 136.98474 -288.360866) (xy 137.008373 -288.361309) (xy 137.055076 -288.368582)
			(xy 137.100106 -288.382949) (xy 137.142391 -288.404069) (xy 137.180927 -288.431439) (xy 137.214796 -288.464409)
			(xy 137.229342 -288.48304) (xy 137.231374 -288.485834) (xy 137.235946 -288.490406) (xy 137.242511 -288.49653)
			(xy 137.258781 -288.504088) (xy 137.267696 -288.505138) (xy 137.273538 -288.505646) (xy 137.349992 -288.495232)
			(xy 137.357309 -288.494096) (xy 137.370859 -288.488148) (xy 137.376662 -288.483548) (xy 137.388346 -288.474404)
			(xy 137.39368 -288.47034) (xy 137.40892 -288.450274) (xy 137.411206 -288.444432) (xy 137.417929 -288.429259)
			(xy 137.432927 -288.399649) (xy 137.441178 -288.38525) (xy 137.574528 -288.155634) (xy 137.577669 -288.149756)
			(xy 137.581138 -288.136894) (xy 137.581386 -288.130234) (xy 137.581386 -287.522158) (xy 137.581267 -287.516654)
			(xy 137.578966 -287.505889) (xy 137.576814 -287.500822) (xy 137.572242 -287.49117) (xy 137.571734 -287.490662)
			(xy 137.567924 -287.482534) (xy 137.564622 -287.478216) (xy 137.559288 -287.47085) (xy 137.555732 -287.46577)
			(xy 137.55116 -287.461452) (xy 137.550652 -287.460944) (xy 137.527117 -287.439223) (xy 137.484652 -287.391277)
			(xy 137.447937 -287.338798) (xy 137.417452 -287.282471) (xy 137.40511 -287.252918) (xy 137.404348 -287.250886)
			(xy 137.402062 -287.246568) (xy 137.39588 -287.235595) (xy 137.37535 -287.221064) (xy 137.362946 -287.218882)
			(xy 137.285476 -287.20923) (xy 137.27938 -287.208722) (xy 137.266934 -287.208722) (xy 137.245852 -287.21939)
			(xy 137.236708 -287.225486) (xy 137.224262 -287.235646) (xy 137.22096 -287.23971) (xy 137.203372 -287.26023)
			(xy 137.162279 -287.295326) (xy 137.115657 -287.322654) (xy 137.064958 -287.341361) (xy 137.01176 -287.350866)
			(xy 136.98474 -287.35147) (xy 136.959483 -287.350981) (xy 136.909658 -287.342672) (xy 136.86188 -287.326275)
			(xy 136.817452 -287.302238) (xy 136.777588 -287.271215) (xy 136.743374 -287.234053) (xy 136.715744 -287.191766)
			(xy 136.695451 -287.145508) (xy 136.68305 -287.096541) (xy 136.678878 -287.0462) (xy 136.68305 -286.995859)
			(xy 136.695451 -286.946892) (xy 136.715744 -286.900634) (xy 136.743374 -286.858347) (xy 136.777588 -286.821185)
			(xy 136.817452 -286.790162) (xy 136.86188 -286.766125) (xy 136.909658 -286.749728) (xy 136.959483 -286.741419)
			(xy 136.98474 -286.740854) (xy 137.008373 -286.741297) (xy 137.055077 -286.74857) (xy 137.100107 -286.762937)
			(xy 137.142393 -286.784056) (xy 137.180929 -286.811426) (xy 137.214799 -286.844394) (xy 137.229342 -286.863028)
			(xy 137.231374 -286.865822) (xy 137.235946 -286.870394) (xy 137.24251 -286.876519) (xy 137.25878 -286.884079)
			(xy 137.267696 -286.885126) (xy 137.273538 -286.885634) (xy 137.349992 -286.87522) (xy 137.357308 -286.874084)
			(xy 137.370858 -286.868134) (xy 137.376662 -286.863536) (xy 137.388346 -286.854392) (xy 137.39368 -286.850328)
			(xy 137.40892 -286.830262) (xy 137.411206 -286.82442) (xy 137.41793 -286.809247) (xy 137.432928 -286.779638)
			(xy 137.441178 -286.765238) (xy 137.485628 -286.688784) (xy 137.485628 -286.688276) (xy 137.488422 -286.685482)
			(xy 137.490962 -286.669226) (xy 137.491975 -286.66145) (xy 137.489788 -286.645929) (xy 137.486644 -286.638746)
			(xy 137.452354 -286.568642) (xy 137.44448 -286.562038) (xy 137.442194 -286.560006) (xy 137.427716 -286.549592)
			(xy 137.42289 -286.546036) (xy 137.40384 -286.5374) (xy 137.397998 -286.536384) (xy 137.374997 -286.531599)
			(xy 137.330716 -286.51591) (xy 137.289359 -286.493626) (xy 137.251903 -286.465271) (xy 137.219231 -286.431514)
			(xy 137.192114 -286.393152) (xy 137.171191 -286.351091) (xy 137.156957 -286.306321) (xy 137.149746 -286.259899)
			(xy 137.149332 -286.23641) (xy 137.149468 -286.223647) (xy 137.151627 -286.198212) (xy 137.15365 -286.18561)
			(xy 137.153396 -286.18561) (xy 137.157953 -286.161491) (xy 137.173738 -286.115018) (xy 137.196754 -286.071668)
			(xy 137.226408 -286.032558) (xy 137.261937 -285.998696) (xy 137.302424 -285.970952) (xy 137.346828 -285.950042)
			(xy 137.394006 -285.936505) (xy 137.418318 -285.933134) (xy 137.432288 -285.931356) (xy 137.453878 -285.9151)
			(xy 137.497312 -285.80969) (xy 137.493502 -285.782766) (xy 137.484866 -285.771844) (xy 137.466037 -285.74717)
			(xy 137.433356 -285.6944) (xy 137.406714 -285.638339) (xy 137.386438 -285.579674) (xy 137.372776 -285.519126)
			(xy 137.365898 -285.457439) (xy 137.365486 -285.426404) (xy 137.366071 -285.389598) (xy 137.375727 -285.316621)
			(xy 137.394872 -285.245542) (xy 137.423177 -285.177589) (xy 137.441178 -285.14548) (xy 137.485882 -285.068518)
			(xy 137.491652 -285.057369) (xy 137.492581 -285.032315) (xy 137.48766 -285.020766) (xy 137.44575 -284.935422)
			(xy 137.42543 -284.92069) (xy 137.41273 -284.918912) (xy 137.388382 -284.915065) (xy 137.341277 -284.900549)
			(xy 137.297116 -284.878654) (xy 137.257046 -284.849949) (xy 137.222108 -284.815179) (xy 137.19321 -284.775248)
			(xy 137.171102 -284.731193) (xy 137.156359 -284.684159) (xy 137.15238 -284.659832) (xy 137.150856 -284.649418)
			(xy 137.149078 -284.616398) (xy 137.149557 -284.591747) (xy 137.15749 -284.543087) (xy 137.173133 -284.496332)
			(xy 137.196081 -284.452695) (xy 137.225739 -284.41331) (xy 137.261335 -284.379197) (xy 137.301947 -284.351244)
			(xy 137.346521 -284.330174) (xy 137.393899 -284.316535) (xy 137.418318 -284.313122) (xy 137.432288 -284.311344)
			(xy 137.453878 -284.295088) (xy 137.497058 -284.189678) (xy 137.493502 -284.162754) (xy 137.484866 -284.151832)
			(xy 137.461255 -284.120629) (xy 137.421992 -284.052947) (xy 137.406634 -284.016958) (xy 137.404348 -284.011116)
			(xy 137.395458 -283.998924) (xy 137.388924 -283.990932) (xy 137.371095 -283.980564) (xy 137.360914 -283.978858)
			(xy 137.28573 -283.96946) (xy 137.279126 -283.968952) (xy 137.266934 -283.968952) (xy 137.245852 -283.97962)
			(xy 137.236708 -283.985716) (xy 137.224262 -283.995876) (xy 137.22096 -283.99994) (xy 137.203374 -284.020464)
			(xy 137.162284 -284.055568) (xy 137.115663 -284.082902) (xy 137.064962 -284.101614) (xy 137.011762 -284.111122)
			(xy 136.98474 -284.1117) (xy 136.959481 -284.11121) (xy 136.90965 -284.102901) (xy 136.861868 -284.086503)
			(xy 136.817436 -284.062463) (xy 136.777568 -284.031437) (xy 136.74335 -283.994272) (xy 136.715717 -283.951981)
			(xy 136.695423 -283.905718) (xy 136.68302 -283.856746) (xy 136.678848 -283.8064) (xy 136.68302 -283.756054)
			(xy 136.695423 -283.707082) (xy 136.715717 -283.660819) (xy 136.74335 -283.618528) (xy 136.777568 -283.581363)
			(xy 136.817436 -283.550337) (xy 136.861868 -283.526297) (xy 136.90965 -283.509899) (xy 136.959481 -283.50159)
			(xy 136.98474 -283.501084) (xy 137.008373 -283.501527) (xy 137.055076 -283.5088) (xy 137.100105 -283.523168)
			(xy 137.142389 -283.544289) (xy 137.180923 -283.57166) (xy 137.214791 -283.604631) (xy 137.229342 -283.623258)
			(xy 137.231374 -283.626052) (xy 137.235946 -283.630624) (xy 137.242507 -283.636756) (xy 137.258777 -283.644327)
			(xy 137.267696 -283.645356) (xy 137.273538 -283.645864) (xy 137.349992 -283.63545) (xy 137.357309 -283.634315)
			(xy 137.370861 -283.628368) (xy 137.376662 -283.623766) (xy 137.388346 -283.614622) (xy 137.39368 -283.610558)
			(xy 137.40892 -283.590492) (xy 137.411206 -283.58465) (xy 137.417929 -283.569477) (xy 137.432925 -283.539867)
			(xy 137.441178 -283.525468) (xy 137.574528 -283.295852) (xy 137.577671 -283.289975) (xy 137.581145 -283.277112)
			(xy 137.581386 -283.270452) (xy 137.581386 -282.662376) (xy 137.581269 -282.656871) (xy 137.578971 -282.646105)
			(xy 137.576814 -282.64104) (xy 137.572242 -282.631388) (xy 137.571734 -282.63088) (xy 137.567924 -282.622752)
			(xy 137.564622 -282.618434) (xy 137.559288 -282.611068) (xy 137.555732 -282.605988) (xy 137.55116 -282.60167)
			(xy 137.550652 -282.601162) (xy 137.527117 -282.579441) (xy 137.48465 -282.531496) (xy 137.447934 -282.479018)
			(xy 137.417446 -282.422692) (xy 137.40511 -282.393136) (xy 137.404348 -282.391104) (xy 137.402062 -282.386786)
			(xy 137.39587 -282.375826) (xy 137.375339 -282.36132) (xy 137.362946 -282.3591) (xy 137.285476 -282.349448)
			(xy 137.27938 -282.34894) (xy 137.266934 -282.34894) (xy 137.245852 -282.359608) (xy 137.236708 -282.365704)
			(xy 137.224262 -282.375864) (xy 137.22096 -282.379928) (xy 137.203375 -282.400453) (xy 137.162285 -282.435558)
			(xy 137.115664 -282.462893) (xy 137.064963 -282.481606) (xy 137.011762 -282.491114) (xy 136.98474 -282.491688)
			(xy 136.959482 -282.491199) (xy 136.909653 -282.48289) (xy 136.861873 -282.466492) (xy 136.817443 -282.442453)
			(xy 136.777576 -282.411428) (xy 136.74336 -282.374264) (xy 136.715728 -282.331975) (xy 136.695434 -282.285714)
			(xy 136.683032 -282.236744) (xy 136.67886 -282.1864) (xy 136.683032 -282.136056) (xy 136.695434 -282.087086)
			(xy 136.715728 -282.040825) (xy 136.74336 -281.998536) (xy 136.777576 -281.961372) (xy 136.817443 -281.930347)
			(xy 136.861873 -281.906308) (xy 136.909653 -281.88991) (xy 136.959482 -281.881601) (xy 136.98474 -281.881072)
			(xy 137.008373 -281.881515) (xy 137.055076 -281.888788) (xy 137.100106 -281.903156) (xy 137.142391 -281.924276)
			(xy 137.180926 -281.951646) (xy 137.214794 -281.984616) (xy 137.229342 -282.003246) (xy 137.231374 -282.00604)
			(xy 137.235946 -282.010612) (xy 137.242511 -282.016735) (xy 137.258781 -282.024292) (xy 137.267696 -282.025344)
			(xy 137.273538 -282.025852) (xy 137.349992 -282.015438) (xy 137.357309 -282.014303) (xy 137.37086 -282.008355)
			(xy 137.376662 -282.003754) (xy 137.388346 -281.99461) (xy 137.39368 -281.990546) (xy 137.40892 -281.97048)
			(xy 137.411206 -281.964638) (xy 137.417929 -281.949465) (xy 137.432926 -281.919855) (xy 137.441178 -281.905456)
			(xy 137.485882 -281.828494) (xy 137.491647 -281.817346) (xy 137.492564 -281.792297) (xy 137.48766 -281.780742)
			(xy 137.44575 -281.695398) (xy 137.42543 -281.680666) (xy 137.41273 -281.678888) (xy 137.388383 -281.675041)
			(xy 137.341279 -281.660524) (xy 137.29712 -281.638628) (xy 137.257052 -281.609922) (xy 137.222117 -281.575152)
			(xy 137.193221 -281.535221) (xy 137.171116 -281.491166) (xy 137.156377 -281.444132) (xy 137.15238 -281.419808)
			(xy 137.150856 -281.409394) (xy 137.149078 -281.376374) (xy 137.149559 -281.351724) (xy 137.157495 -281.303067)
			(xy 137.173141 -281.256315) (xy 137.19609 -281.212682) (xy 137.225747 -281.1733) (xy 137.261344 -281.13919)
			(xy 137.301955 -281.111239) (xy 137.346527 -281.090172) (xy 137.393903 -281.076534) (xy 137.418318 -281.073098)
			(xy 137.432288 -281.07132) (xy 137.453878 -281.055064) (xy 137.497312 -280.949654) (xy 137.493502 -280.92273)
			(xy 137.484866 -280.911808) (xy 137.466038 -280.887134) (xy 137.433361 -280.834363) (xy 137.406722 -280.778301)
			(xy 137.38645 -280.719637) (xy 137.372793 -280.659089) (xy 137.365918 -280.597402) (xy 137.365486 -280.566368)
			(xy 137.366073 -280.529562) (xy 137.375733 -280.456588) (xy 137.394883 -280.385511) (xy 137.423191 -280.31756)
			(xy 137.441178 -280.285444) (xy 137.485882 -280.208482) (xy 137.491644 -280.197334) (xy 137.492556 -280.172287)
			(xy 137.48766 -280.16073) (xy 137.44575 -280.075386) (xy 137.42543 -280.060654) (xy 137.41273 -280.058876)
			(xy 137.388383 -280.055028) (xy 137.34128 -280.040512) (xy 137.297122 -280.018616) (xy 137.257055 -279.989909)
			(xy 137.222121 -279.955139) (xy 137.193227 -279.915207) (xy 137.171124 -279.871152) (xy 137.156386 -279.824118)
			(xy 137.15238 -279.799796) (xy 137.150856 -279.789382) (xy 137.149078 -279.756362) (xy 137.149552 -279.731708)
			(xy 137.157477 -279.68304) (xy 137.173114 -279.636276) (xy 137.196059 -279.592631) (xy 137.225715 -279.553237)
			(xy 137.261312 -279.519116) (xy 137.301927 -279.491155) (xy 137.346505 -279.47008) (xy 137.393889 -279.456437)
			(xy 137.418318 -279.453086) (xy 137.432288 -279.451308) (xy 137.453878 -279.435052) (xy 137.497058 -279.329642)
			(xy 137.493502 -279.302718) (xy 137.484866 -279.291796) (xy 137.461257 -279.260592) (xy 137.421998 -279.192908)
			(xy 137.406634 -279.156922) (xy 137.404348 -279.15108) (xy 137.395458 -279.138888) (xy 137.388921 -279.1309)
			(xy 137.371092 -279.12054) (xy 137.360914 -279.118822) (xy 137.28573 -279.109424) (xy 137.279126 -279.108916)
			(xy 137.266934 -279.108916) (xy 137.245852 -279.119584) (xy 137.236708 -279.12568) (xy 137.224262 -279.13584)
			(xy 137.22096 -279.139904) (xy 137.203372 -279.160425) (xy 137.162279 -279.195521) (xy 137.115658 -279.222849)
			(xy 137.064958 -279.241557) (xy 137.01176 -279.251063) (xy 136.98474 -279.251664) (xy 136.959484 -279.251175)
			(xy 136.909659 -279.242866) (xy 136.861882 -279.22647) (xy 136.817456 -279.202433) (xy 136.777592 -279.17141)
			(xy 136.743379 -279.134249) (xy 136.715749 -279.091963) (xy 136.695457 -279.045706) (xy 136.683056 -278.99674)
			(xy 136.678884 -278.9464) (xy 136.683056 -278.89606) (xy 136.695457 -278.847094) (xy 136.715749 -278.800837)
			(xy 136.743379 -278.758551) (xy 136.777592 -278.72139) (xy 136.817456 -278.690367) (xy 136.861882 -278.66633)
			(xy 136.909659 -278.649934) (xy 136.959484 -278.641625) (xy 136.98474 -278.641048) (xy 137.008373 -278.641491)
			(xy 137.055077 -278.648764) (xy 137.100107 -278.66313) (xy 137.142393 -278.684249) (xy 137.18093 -278.711619)
			(xy 137.2148 -278.744587) (xy 137.229342 -278.763222) (xy 137.231374 -278.766016) (xy 137.235946 -278.770588)
			(xy 137.24251 -278.776714) (xy 137.25878 -278.784274) (xy 137.267696 -278.78532) (xy 137.273538 -278.785828)
			(xy 137.349992 -278.775414) (xy 137.357308 -278.774278) (xy 137.370857 -278.768327) (xy 137.376662 -278.76373)
			(xy 137.388346 -278.754586) (xy 137.39368 -278.750522) (xy 137.40892 -278.730456) (xy 137.411206 -278.724614)
			(xy 137.41793 -278.709441) (xy 137.432928 -278.679832) (xy 137.441178 -278.665432) (xy 137.574528 -278.435816)
			(xy 137.577667 -278.429938) (xy 137.581132 -278.417075) (xy 137.581386 -278.410416) (xy 137.581386 -277.80234)
			(xy 137.581265 -277.796836) (xy 137.578961 -277.786073) (xy 137.576814 -277.781004) (xy 137.572242 -277.771352)
			(xy 137.571734 -277.770844) (xy 137.567924 -277.762716) (xy 137.564622 -277.758398) (xy 137.559288 -277.751032)
			(xy 137.555732 -277.745952) (xy 137.55116 -277.741634) (xy 137.550652 -277.741126) (xy 137.527118 -277.719404)
			(xy 137.484654 -277.671458) (xy 137.447941 -277.618978) (xy 137.417457 -277.562651) (xy 137.40511 -277.5331)
			(xy 137.404348 -277.531068) (xy 137.402062 -277.52675) (xy 137.395878 -277.51578) (xy 137.375348 -277.501254)
			(xy 137.362946 -277.499064) (xy 137.285476 -277.489412) (xy 137.27938 -277.488904) (xy 137.266934 -277.488904)
			(xy 137.245852 -277.499572) (xy 137.236708 -277.505668) (xy 137.224262 -277.515828) (xy 137.22096 -277.519892)
			(xy 137.203372 -277.540413) (xy 137.16228 -277.575511) (xy 137.115659 -277.60284) (xy 137.064959 -277.621549)
			(xy 137.011761 -277.631055) (xy 136.98474 -277.631652) (xy 136.959476 -277.631162) (xy 136.909638 -277.622852)
			(xy 136.861847 -277.606451) (xy 136.817408 -277.582406) (xy 136.777532 -277.551375) (xy 136.743309 -277.514203)
			(xy 136.715671 -277.471905) (xy 136.695373 -277.425635) (xy 136.682969 -277.376654) (xy 136.678796 -277.3263)
			(xy 136.682969 -277.275946) (xy 136.695373 -277.226965) (xy 136.715671 -277.180695) (xy 136.743309 -277.138397)
			(xy 136.777532 -277.101225) (xy 136.817408 -277.070194) (xy 136.861847 -277.046149) (xy 136.909638 -277.029748)
			(xy 136.959476 -277.021438) (xy 136.98474 -277.021036) (xy 137.008373 -277.021478) (xy 137.055077 -277.028751)
			(xy 137.100108 -277.043118) (xy 137.142395 -277.064236) (xy 137.180932 -277.091605) (xy 137.214803 -277.124573)
			(xy 137.229342 -277.14321) (xy 137.231374 -277.146004) (xy 137.235946 -277.150576) (xy 137.242509 -277.156703)
			(xy 137.258779 -277.164266) (xy 137.267696 -277.165308) (xy 137.273538 -277.165816) (xy 137.349992 -277.155402)
			(xy 137.357308 -277.154265) (xy 137.370856 -277.148314) (xy 137.376662 -277.143718) (xy 137.388346 -277.134574)
			(xy 137.39368 -277.13051) (xy 137.40892 -277.110444) (xy 137.411206 -277.104602) (xy 137.41793 -277.089429)
			(xy 137.432929 -277.059821) (xy 137.441178 -277.04542) (xy 137.485882 -276.968458) (xy 137.491662 -276.957309)
			(xy 137.492609 -276.932246) (xy 137.48766 -276.920706) (xy 137.44575 -276.835362) (xy 137.42543 -276.82063)
			(xy 137.41273 -276.818852) (xy 137.388381 -276.815005) (xy 137.341274 -276.80049) (xy 137.29711 -276.778596)
			(xy 137.257036 -276.749892) (xy 137.222094 -276.715123) (xy 137.193191 -276.675193) (xy 137.171078 -276.631139)
			(xy 137.156328 -276.584104) (xy 137.15238 -276.559772) (xy 137.150856 -276.549358) (xy 137.149078 -276.516338)
			(xy 137.149554 -276.491685) (xy 137.157482 -276.44302) (xy 137.173122 -276.396259) (xy 137.196067 -276.352617)
			(xy 137.225724 -276.313226) (xy 137.261321 -276.279109) (xy 137.301934 -276.251151) (xy 137.346511 -276.230078)
			(xy 137.393893 -276.216436) (xy 137.418318 -276.213062) (xy 137.432288 -276.211284) (xy 137.453878 -276.195028)
			(xy 137.497312 -276.089618) (xy 137.493502 -276.062694) (xy 137.484866 -276.051772) (xy 137.46604 -276.027097)
			(xy 137.433366 -275.974326) (xy 137.406731 -275.918264) (xy 137.386462 -275.859599) (xy 137.372809 -275.799052)
			(xy 137.365938 -275.737366) (xy 137.365486 -275.706332) (xy 137.366075 -275.669527) (xy 137.37574 -275.596554)
			(xy 137.394894 -275.52548) (xy 137.423205 -275.457532) (xy 137.441178 -275.425408) (xy 137.485882 -275.348446)
			(xy 137.49166 -275.337297) (xy 137.492601 -275.312237) (xy 137.48766 -275.300694) (xy 137.44575 -275.21535)
			(xy 137.42543 -275.200618) (xy 137.41273 -275.19884) (xy 137.388381 -275.194993) (xy 137.341275 -275.180478)
			(xy 137.297112 -275.158583) (xy 137.257039 -275.129879) (xy 137.222098 -275.09511) (xy 137.193197 -275.05518)
			(xy 137.171085 -275.011125) (xy 137.156337 -274.964091) (xy 137.15238 -274.93976) (xy 137.150856 -274.929346)
			(xy 137.149078 -274.896326) (xy 137.149555 -274.871673) (xy 137.157484 -274.82301) (xy 137.173125 -274.776251)
			(xy 137.196072 -274.732611) (xy 137.225728 -274.693221) (xy 137.261325 -274.659106) (xy 137.301938 -274.631149)
			(xy 137.346514 -274.610076) (xy 137.393895 -274.596436) (xy 137.418318 -274.59305) (xy 137.432288 -274.591272)
			(xy 137.453878 -274.575016) (xy 137.497058 -274.469606) (xy 137.493502 -274.442682) (xy 137.484866 -274.43176)
			(xy 137.461259 -274.400555) (xy 137.422004 -274.33287) (xy 137.406634 -274.296886) (xy 137.404348 -274.291044)
			(xy 137.395458 -274.278852) (xy 137.388918 -274.270869) (xy 137.371088 -274.260516) (xy 137.360914 -274.258786)
			(xy 137.28573 -274.249388) (xy 137.279126 -274.24888) (xy 137.266934 -274.24888) (xy 137.245852 -274.259548)
			(xy 137.236708 -274.265644) (xy 137.224262 -274.275804) (xy 137.22096 -274.279868) (xy 137.203373 -274.300391)
			(xy 137.162282 -274.335492) (xy 137.11566 -274.362823) (xy 137.06496 -274.381533) (xy 137.011761 -274.39104)
			(xy 136.98474 -274.391628) (xy 136.959478 -274.391138) (xy 136.909644 -274.382828) (xy 136.861856 -274.366429)
			(xy 136.817421 -274.342386) (xy 136.777549 -274.311358) (xy 136.743328 -274.274189) (xy 136.715693 -274.231894)
			(xy 136.695396 -274.185627) (xy 136.682992 -274.13665) (xy 136.67882 -274.0863) (xy 136.682992 -274.03595)
			(xy 136.695396 -273.986973) (xy 136.715693 -273.940706) (xy 136.743328 -273.898411) (xy 136.777549 -273.861242)
			(xy 136.817421 -273.830214) (xy 136.861856 -273.806171) (xy 136.909644 -273.789772) (xy 136.959478 -273.781462)
			(xy 136.98474 -273.781012) (xy 137.008374 -273.781454) (xy 137.055078 -273.788727) (xy 137.10011 -273.803093)
			(xy 137.142397 -273.82421) (xy 137.180936 -273.851577) (xy 137.21481 -273.884544) (xy 137.229342 -273.903186)
			(xy 137.231374 -273.90598) (xy 137.235946 -273.910552) (xy 137.242508 -273.916681) (xy 137.258778 -273.924247)
			(xy 137.267696 -273.925284) (xy 137.273538 -273.925792) (xy 137.349992 -273.915378) (xy 137.357309 -273.914244)
			(xy 137.370863 -273.908299) (xy 137.376662 -273.903694) (xy 137.388346 -273.89455) (xy 137.39368 -273.890486)
			(xy 137.40892 -273.87042) (xy 137.411206 -273.864578) (xy 137.417928 -273.849404) (xy 137.432924 -273.819794)
			(xy 137.441178 -273.805396) (xy 137.574528 -273.57578) (xy 137.577675 -273.569904) (xy 137.581156 -273.557041)
			(xy 137.581386 -273.55038) (xy 137.581386 -272.942304) (xy 137.581262 -272.936801) (xy 137.57895 -272.926041)
			(xy 137.576814 -272.920968) (xy 137.572242 -272.911316) (xy 137.571734 -272.910808) (xy 137.567924 -272.90268)
			(xy 137.564622 -272.898362) (xy 137.559288 -272.890996) (xy 137.555732 -272.885916) (xy 137.55116 -272.881598)
			(xy 137.550652 -272.88109) (xy 137.527116 -272.85937) (xy 137.484647 -272.811426) (xy 137.447928 -272.758948)
			(xy 137.417438 -272.702623) (xy 137.40511 -272.673064) (xy 137.404348 -272.671032) (xy 137.402062 -272.666714)
			(xy 137.395873 -272.65575) (xy 137.375343 -272.641235) (xy 137.362946 -272.639028) (xy 137.285476 -272.629376)
			(xy 137.27938 -272.628868) (xy 137.266934 -272.628868) (xy 137.245852 -272.639536) (xy 137.236708 -272.645632)
			(xy 137.224262 -272.655792) (xy 137.22096 -272.659856) (xy 137.203374 -272.680379) (xy 137.162283 -272.715482)
			(xy 137.115661 -272.742814) (xy 137.064961 -272.761525) (xy 137.011761 -272.771032) (xy 136.98474 -272.771616)
			(xy 136.959479 -272.771126) (xy 136.909647 -272.762817) (xy 136.861861 -272.746418) (xy 136.817427 -272.722376)
			(xy 136.777557 -272.691349) (xy 136.743338 -272.654181) (xy 136.715703 -272.611888) (xy 136.695408 -272.565623)
			(xy 136.683004 -272.516648) (xy 136.678832 -272.4663) (xy 136.683004 -272.415952) (xy 136.695408 -272.366977)
			(xy 136.715703 -272.320712) (xy 136.743338 -272.278419) (xy 136.777557 -272.241251) (xy 136.817427 -272.210224)
			(xy 136.861861 -272.186182) (xy 136.909647 -272.169783) (xy 136.959479 -272.161474) (xy 136.98474 -272.161)
			(xy 137.008374 -272.161442) (xy 137.055079 -272.168714) (xy 137.100111 -272.183079) (xy 137.142399 -272.204196)
			(xy 137.180939 -272.231563) (xy 137.214813 -272.264529) (xy 137.229342 -272.283174) (xy 137.231374 -272.285968)
			(xy 137.235946 -272.29054) (xy 137.242507 -272.29667) (xy 137.258777 -272.304239) (xy 137.267696 -272.305272)
			(xy 137.273538 -272.30578) (xy 137.349992 -272.295366) (xy 137.357309 -272.294231) (xy 137.370862 -272.288286)
			(xy 137.376662 -272.283682) (xy 137.388346 -272.274538) (xy 137.39368 -272.270474) (xy 137.40892 -272.250408)
			(xy 137.411206 -272.244566) (xy 137.417929 -272.229393) (xy 137.432924 -272.199782) (xy 137.441178 -272.185384)
			(xy 137.485882 -272.108422) (xy 137.491654 -272.097274) (xy 137.492584 -272.072218) (xy 137.48766 -272.06067)
			(xy 137.44575 -271.975326) (xy 137.42543 -271.960594) (xy 137.41273 -271.958816) (xy 137.388382 -271.954969)
			(xy 137.341277 -271.940453) (xy 137.297116 -271.918558) (xy 137.257045 -271.889853) (xy 137.222107 -271.855083)
			(xy 137.193208 -271.815153) (xy 137.171099 -271.771098) (xy 137.156355 -271.724064) (xy 137.15238 -271.699736)
			(xy 137.150856 -271.689322) (xy 137.149078 -271.656302) (xy 137.149557 -271.631651) (xy 137.157489 -271.58299)
			(xy 137.173132 -271.536234) (xy 137.19608 -271.492597) (xy 137.225737 -271.453211) (xy 137.261334 -271.419099)
			(xy 137.301946 -271.391144) (xy 137.34652 -271.370074) (xy 137.393898 -271.356435) (xy 137.418318 -271.353026)
			(xy 137.432288 -271.351248) (xy 137.453878 -271.334992) (xy 137.497312 -271.229582) (xy 137.493502 -271.202658)
			(xy 137.484866 -271.191736) (xy 137.466037 -271.167062) (xy 137.433357 -271.114292) (xy 137.406716 -271.058231)
			(xy 137.38644 -270.999566) (xy 137.37278 -270.939018) (xy 137.365902 -270.877331) (xy 137.365486 -270.846296)
			(xy 137.366071 -270.80949) (xy 137.375728 -270.736514) (xy 137.394875 -270.665435) (xy 137.42318 -270.597482)
			(xy 137.441178 -270.565372) (xy 137.485882 -270.48841) (xy 137.491651 -270.477262) (xy 137.492575 -270.452209)
			(xy 137.48766 -270.440658) (xy 137.44575 -270.355314) (xy 137.42543 -270.340582) (xy 137.41273 -270.338804)
			(xy 137.388695 -270.335005) (xy 137.342161 -270.320781) (xy 137.298475 -270.299353) (xy 137.258742 -270.271265)
			(xy 137.22397 -270.237228) (xy 137.195039 -270.198104) (xy 137.172683 -270.154885) (xy 137.157469 -270.108667)
			(xy 137.14978 -270.06062) (xy 137.149332 -270.03629) (xy 137.149802 -270.012313) (xy 137.157302 -269.964949)
			(xy 137.172115 -269.919341) (xy 137.193878 -269.87661) (xy 137.222054 -269.837807) (xy 137.255952 -269.803887)
			(xy 137.294736 -269.775685) (xy 137.337452 -269.753894) (xy 137.383051 -269.73905) (xy 137.430409 -269.731518)
			(xy 137.454386 -269.730982) (xy 137.45464 -269.730982) (xy 137.474452 -269.731744) (xy 137.484866 -269.732252)
			(xy 137.504678 -269.72514) (xy 137.565384 -269.668244) (xy 137.572584 -269.660854) (xy 137.58085 -269.641972)
			(xy 137.581386 -269.631668) (xy 137.581386 -268.693138) (xy 137.58192 -268.6833) (xy 137.589503 -268.665135)
			(xy 137.596118 -268.657832) (xy 138.125454 -268.128496) (xy 138.132164 -268.121256) (xy 138.139754 -268.103052)
			(xy 138.140186 -268.09319) (xy 138.140186 -267.9954) (xy 138.139566 -267.983554) (xy 138.128969 -267.962365)
			(xy 138.119866 -267.95476) (xy 138.06043 -267.91031) (xy 138.05369 -267.905638) (xy 138.038145 -267.900446)
			(xy 138.02995 -267.90015) (xy 138.007852 -267.90015) (xy 138.001502 -267.901674) (xy 137.982661 -267.906288)
			(xy 137.944189 -267.911257) (xy 137.924794 -267.91158) (xy 137.900802 -267.911133) (xy 137.853409 -267.903626)
			(xy 137.807774 -267.888796) (xy 137.765021 -267.86701) (xy 137.726202 -267.838804) (xy 137.692274 -267.804872)
			(xy 137.664072 -267.76605) (xy 137.642291 -267.723295) (xy 137.627466 -267.677658) (xy 137.619964 -267.630264)
			(xy 137.619486 -267.606272) (xy 137.619486 -267.606018) (xy 137.61999 -267.580673) (xy 137.628359 -267.530678)
			(xy 137.644855 -267.482746) (xy 137.669026 -267.438189) (xy 137.700211 -267.398226) (xy 137.718546 -267.38072)
			(xy 137.726166 -267.373862) (xy 137.733786 -267.35786) (xy 137.736046 -267.352685) (xy 137.738482 -267.341661)
			(xy 137.738612 -267.336016) (xy 137.738612 -267.320014) (xy 137.736326 -267.312648) (xy 137.733024 -267.30198)
			(xy 137.733024 -267.301726) (xy 137.729214 -267.288264) (xy 137.706862 -267.204952) (xy 137.705592 -267.199872)
			(xy 137.705338 -267.19911) (xy 137.704322 -267.195808) (xy 137.704322 -267.195554) (xy 137.69213 -267.15085)
			(xy 137.689026 -267.141101) (xy 137.676451 -267.124983) (xy 137.667746 -267.119608) (xy 137.6045 -267.084302)
			(xy 137.600182 -267.082778) (xy 137.5917 -267.079847) (xy 137.573774 -267.079343) (xy 137.56513 -267.081762)
			(xy 137.562082 -267.082524) (xy 137.555986 -267.084302) (xy 137.554462 -267.08481) (xy 137.530925 -267.092442)
			(xy 137.482168 -267.100858) (xy 137.457434 -267.101574) (xy 137.453116 -267.101574) (xy 137.429202 -267.100993)
			(xy 137.381991 -267.093303) (xy 137.336558 -267.078344) (xy 137.294013 -267.056482) (xy 137.255399 -267.028252)
			(xy 137.22166 -266.994345) (xy 137.193623 -266.955591) (xy 137.171972 -266.912938) (xy 137.15724 -266.867431)
			(xy 137.149785 -266.820182) (xy 137.149332 -266.796266) (xy 137.149818 -266.771387) (xy 137.157879 -266.722287)
			(xy 137.1738 -266.675145) (xy 137.197157 -266.63121) (xy 137.227333 -266.591646) (xy 137.263527 -266.557503)
			(xy 137.304781 -266.529683) (xy 137.350002 -266.508924) (xy 137.373868 -266.50188) (xy 137.381742 -266.499594)
			(xy 137.394696 -266.491212) (xy 137.417302 -266.46378) (xy 137.422635 -266.4568) (xy 137.428617 -266.440298)
			(xy 137.428986 -266.431522) (xy 137.428986 -266.256262) (xy 137.423652 -266.233656) (xy 137.42035 -266.227306)
			(xy 137.407277 -266.199011) (xy 137.386776 -266.140145) (xy 137.372944 -266.079366) (xy 137.365954 -266.017426)
			(xy 137.365486 -265.98626) (xy 137.365897 -265.956874) (xy 137.372138 -265.898433) (xy 137.384484 -265.84097)
			(xy 137.402798 -265.785123) (xy 137.414508 -265.758168) (xy 137.41908 -265.748262) (xy 137.424414 -265.736578)
			(xy 137.42654 -265.731569) (xy 137.428838 -265.720936) (xy 137.428986 -265.715496) (xy 137.428986 -265.540998)
			(xy 137.428582 -265.532227) (xy 137.422625 -265.515721) (xy 137.417302 -265.50874) (xy 137.394696 -265.481308)
			(xy 137.381742 -265.472926) (xy 137.373868 -265.47064) (xy 137.35001 -265.463588) (xy 137.304805 -265.442823)
			(xy 137.263565 -265.415002) (xy 137.227383 -265.380862) (xy 137.197216 -265.341305) (xy 137.173864 -265.29738)
			(xy 137.157944 -265.25025) (xy 137.149879 -265.201161) (xy 137.149881 -265.151415) (xy 137.15795 -265.102327)
			(xy 137.173873 -265.055197) (xy 137.197229 -265.011274) (xy 137.227399 -264.97172) (xy 137.263584 -264.937583)
			(xy 137.304826 -264.909765) (xy 137.350033 -264.889004) (xy 137.373868 -264.881868) (xy 137.381742 -264.879582)
			(xy 137.394696 -264.8712) (xy 137.417302 -264.843768) (xy 137.422633 -264.836787) (xy 137.428612 -264.820286)
			(xy 137.428986 -264.81151) (xy 137.428986 -264.6426) (xy 137.427716 -264.631424) (xy 137.423906 -264.615168)
			(xy 137.42162 -264.609834) (xy 137.404602 -264.570972) (xy 137.401808 -264.56386) (xy 137.396982 -264.557764)
			(xy 137.390532 -264.550233) (xy 137.373243 -264.540554) (xy 137.363454 -264.538968) (xy 137.286492 -264.529316)
			(xy 137.27938 -264.528808) (xy 137.266934 -264.528808) (xy 137.245852 -264.539476) (xy 137.236708 -264.545572)
			(xy 137.224262 -264.555732) (xy 137.22096 -264.559796) (xy 137.203372 -264.580317) (xy 137.16228 -264.615415)
			(xy 137.115658 -264.642743) (xy 137.064959 -264.661452) (xy 137.01176 -264.670957) (xy 136.98474 -264.671556)
			(xy 136.960847 -264.671096) (xy 136.913643 -264.663659) (xy 136.868174 -264.648959) (xy 136.82555 -264.627355)
			(xy 136.786811 -264.599376) (xy 136.752904 -264.565703) (xy 136.724656 -264.52716) (xy 136.702757 -264.484687)
			(xy 136.687742 -264.439321) (xy 136.679977 -264.39217) (xy 136.679432 -264.36828) (xy 136.679432 -264.365994)
			(xy 136.680224 -264.33516) (xy 136.692632 -264.274751) (xy 136.70407 -264.246106) (xy 136.706102 -264.24128)
			(xy 136.708134 -264.231628) (xy 136.70927 -264.225633) (xy 136.709018 -264.213438) (xy 136.707626 -264.207498)
			(xy 136.70534 -264.198608) (xy 136.656826 -264.123678) (xy 136.651963 -264.116745) (xy 136.638627 -264.106324)
			(xy 136.622617 -264.100837) (xy 136.614154 -264.100564) (xy 136.415272 -264.100564) (xy 136.402535 -264.101257)
			(xy 136.380131 -264.113384) (xy 136.3726 -264.123678) (xy 136.32815 -264.192258) (xy 136.323147 -264.200825)
			(xy 136.319489 -264.220304) (xy 136.321038 -264.230104) (xy 136.323324 -264.24128) (xy 136.325356 -264.245852)
			(xy 136.336386 -264.273425) (xy 136.348785 -264.331495) (xy 136.349994 -264.361168) (xy 136.349994 -264.36828)
			(xy 136.349376 -264.392169) (xy 136.341625 -264.439321) (xy 136.326623 -264.48469) (xy 136.304735 -264.527167)
			(xy 136.276497 -264.565716) (xy 136.242598 -264.599395) (xy 136.203866 -264.627381) (xy 136.161246 -264.64899)
			(xy 136.11578 -264.663696) (xy 136.068578 -264.671139) (xy 136.044686 -264.671556) (xy 136.020694 -264.671084)
			(xy 135.973301 -264.663577) (xy 135.927666 -264.648749) (xy 135.884912 -264.626965) (xy 135.846091 -264.598762)
			(xy 135.81216 -264.564835) (xy 135.783953 -264.526017) (xy 135.762164 -264.483265) (xy 135.747331 -264.437632)
			(xy 135.739818 -264.39024) (xy 135.739378 -264.366248) (xy 135.739875 -264.341328) (xy 135.747976 -264.29215)
			(xy 135.763954 -264.24494) (xy 135.787386 -264.20095) (xy 135.817649 -264.161349) (xy 135.85394 -264.127187)
			(xy 135.895296 -264.099371) (xy 135.94062 -264.078638) (xy 135.988709 -264.06554) (xy 136.013444 -264.062464)
			(xy 136.013952 -264.062464) (xy 136.017 -264.061956) (xy 136.026211 -264.060358) (xy 136.042655 -264.051497)
			(xy 136.054815 -264.037319) (xy 136.058402 -264.028682) (xy 136.084564 -263.956038) (xy 136.08595 -263.951919)
			(xy 136.087478 -263.943364) (xy 136.087612 -263.93902) (xy 136.087612 -263.924288) (xy 136.087465 -263.918419)
			(xy 136.084776 -263.906995) (xy 136.082278 -263.901682) (xy 136.077452 -263.89203) (xy 135.944864 -263.759442)
			(xy 135.937244 -263.751822) (xy 135.918194 -263.744202) (xy 135.87476 -263.745218) (xy 135.874252 -263.745218)
			(xy 135.84682 -263.745726) (xy 135.841636 -263.745951) (xy 135.83152 -263.748249) (xy 135.826754 -263.750298)
			(xy 135.809228 -263.758172) (xy 135.804936 -263.760257) (xy 135.797138 -263.765751) (xy 135.793734 -263.769094)
			(xy 135.776403 -263.78624) (xy 135.737297 -263.81535) (xy 135.69406 -263.837869) (xy 135.647791 -263.853224)
			(xy 135.599669 -263.861024) (xy 135.575294 -263.86155) (xy 135.570214 -263.86155) (xy 135.546685 -263.860762)
			(xy 135.500281 -263.85284) (xy 135.455642 -263.83789) (xy 135.413826 -263.816268) (xy 135.375823 -263.788485)
			(xy 135.342534 -263.755199) (xy 135.314747 -263.717199) (xy 135.293121 -263.675384) (xy 135.278167 -263.630747)
			(xy 135.270241 -263.584343) (xy 135.269478 -263.560814) (xy 135.269478 -263.555988) (xy 135.26998 -263.531589)
			(xy 135.277783 -263.483419) (xy 135.293141 -263.437101) (xy 135.315665 -263.393812) (xy 135.344781 -263.354652)
			(xy 135.361934 -263.337294) (xy 135.365294 -263.333904) (xy 135.370794 -263.326105) (xy 135.372856 -263.3218)
			(xy 135.379714 -263.30656) (xy 135.382034 -263.301779) (xy 135.384857 -263.291535) (xy 135.385302 -263.28624)
			(xy 135.38581 -263.256776) (xy 135.38581 -263.256268) (xy 135.386826 -263.212834) (xy 135.379206 -263.193784)
			(xy 135.371586 -263.186164) (xy 135.310372 -263.12495) (xy 135.302974 -263.118103) (xy 135.284376 -263.110371)
			(xy 135.274304 -263.109964) (xy 123.93676 -263.109964) (xy 123.926919 -263.110494) (xy 123.908747 -263.118069)
			(xy 123.901454 -263.124696) (xy 123.646692 -263.379458) (xy 123.64081 -263.385876) (xy 123.633405 -263.401619)
			(xy 123.631732 -263.418935) (xy 123.633484 -263.427464) (xy 123.635516 -263.435846) (xy 123.63704 -263.439402)
			(xy 123.64786 -263.467389) (xy 123.659498 -263.526244) (xy 123.660154 -263.556242) (xy 124.928896 -263.556242)
			(xy 124.932856 -263.507188) (xy 124.944633 -263.459404) (xy 124.963924 -263.414128) (xy 124.990227 -263.372532)
			(xy 125.022862 -263.335695) (xy 125.060983 -263.30457) (xy 125.103604 -263.279963) (xy 125.14962 -263.262511)
			(xy 125.197839 -263.252667) (xy 125.247014 -263.250686) (xy 125.295869 -263.256618) (xy 125.34314 -263.27031)
			(xy 125.387602 -263.291408) (xy 125.428105 -263.319364) (xy 125.463598 -263.353456) (xy 125.493163 -263.3928)
			(xy 125.516034 -263.436377) (xy 125.531618 -263.483058) (xy 125.539513 -263.531635) (xy 125.540008 -263.556242)
			(xy 126.809004 -263.556242) (xy 126.812964 -263.507188) (xy 126.824741 -263.459404) (xy 126.844032 -263.414128)
			(xy 126.870335 -263.372532) (xy 126.90297 -263.335695) (xy 126.941091 -263.30457) (xy 126.983712 -263.279963)
			(xy 127.029728 -263.262511) (xy 127.077947 -263.252667) (xy 127.127122 -263.250686) (xy 127.175977 -263.256618)
			(xy 127.223248 -263.27031) (xy 127.26771 -263.291408) (xy 127.308213 -263.319364) (xy 127.343706 -263.353456)
			(xy 127.373271 -263.3928) (xy 127.396142 -263.436377) (xy 127.411726 -263.483058) (xy 127.419621 -263.531635)
			(xy 127.420116 -263.556242) (xy 127.738627 -263.556242) (xy 127.742722 -263.505514) (xy 127.754901 -263.4561)
			(xy 127.774849 -263.40928) (xy 127.80205 -263.366266) (xy 127.835798 -263.328172) (xy 127.87522 -263.295985)
			(xy 127.919294 -263.270539) (xy 127.96688 -263.252492) (xy 128.016744 -263.242312) (xy 128.067596 -263.240263)
			(xy 128.118117 -263.246397) (xy 128.167001 -263.260557) (xy 128.21298 -263.282374) (xy 128.254864 -263.311284)
			(xy 128.291568 -263.346539) (xy 128.322141 -263.387225) (xy 128.345792 -263.432288) (xy 128.361908 -263.480562)
			(xy 128.370072 -263.530796) (xy 128.370584 -263.556242) (xy 128.688858 -263.556242) (xy 128.692818 -263.507188)
			(xy 128.704595 -263.459404) (xy 128.723886 -263.414128) (xy 128.750189 -263.372532) (xy 128.782824 -263.335695)
			(xy 128.820945 -263.30457) (xy 128.863566 -263.279963) (xy 128.909582 -263.262511) (xy 128.957801 -263.252667)
			(xy 129.006976 -263.250686) (xy 129.055831 -263.256618) (xy 129.103102 -263.27031) (xy 129.147564 -263.291408)
			(xy 129.188067 -263.319364) (xy 129.22356 -263.353456) (xy 129.253125 -263.3928) (xy 129.275996 -263.436377)
			(xy 129.29158 -263.483058) (xy 129.299475 -263.531635) (xy 129.29997 -263.556242) (xy 129.618481 -263.556242)
			(xy 129.622576 -263.505514) (xy 129.634755 -263.4561) (xy 129.654703 -263.40928) (xy 129.681904 -263.366266)
			(xy 129.715652 -263.328172) (xy 129.755074 -263.295985) (xy 129.799148 -263.270539) (xy 129.846734 -263.252492)
			(xy 129.896598 -263.242312) (xy 129.94745 -263.240263) (xy 129.997971 -263.246397) (xy 130.046855 -263.260557)
			(xy 130.092834 -263.282374) (xy 130.134718 -263.311284) (xy 130.171422 -263.346539) (xy 130.201995 -263.387225)
			(xy 130.225646 -263.432288) (xy 130.241762 -263.480562) (xy 130.249926 -263.530796) (xy 130.250438 -263.556242)
			(xy 131.498589 -263.556242) (xy 131.502684 -263.505514) (xy 131.514863 -263.4561) (xy 131.534811 -263.40928)
			(xy 131.562012 -263.366266) (xy 131.59576 -263.328172) (xy 131.635182 -263.295985) (xy 131.679256 -263.270539)
			(xy 131.726842 -263.252492) (xy 131.776706 -263.242312) (xy 131.827558 -263.240263) (xy 131.878079 -263.246397)
			(xy 131.926963 -263.260557) (xy 131.972942 -263.282374) (xy 132.014826 -263.311284) (xy 132.05153 -263.346539)
			(xy 132.082103 -263.387225) (xy 132.105754 -263.432288) (xy 132.12187 -263.480562) (xy 132.130034 -263.530796)
			(xy 132.130546 -263.556242) (xy 132.438643 -263.556242) (xy 132.442738 -263.505514) (xy 132.454917 -263.4561)
			(xy 132.474865 -263.40928) (xy 132.502066 -263.366266) (xy 132.535814 -263.328172) (xy 132.575236 -263.295985)
			(xy 132.61931 -263.270539) (xy 132.666896 -263.252492) (xy 132.71676 -263.242312) (xy 132.767612 -263.240263)
			(xy 132.818133 -263.246397) (xy 132.867017 -263.260557) (xy 132.912996 -263.282374) (xy 132.95488 -263.311284)
			(xy 132.991584 -263.346539) (xy 133.022157 -263.387225) (xy 133.045808 -263.432288) (xy 133.061924 -263.480562)
			(xy 133.070088 -263.530796) (xy 133.0706 -263.556242) (xy 133.388874 -263.556242) (xy 133.392834 -263.507188)
			(xy 133.404611 -263.459404) (xy 133.423902 -263.414128) (xy 133.450205 -263.372532) (xy 133.48284 -263.335695)
			(xy 133.520961 -263.30457) (xy 133.563582 -263.279963) (xy 133.609598 -263.262511) (xy 133.657817 -263.252667)
			(xy 133.706992 -263.250686) (xy 133.755847 -263.256618) (xy 133.803118 -263.27031) (xy 133.84758 -263.291408)
			(xy 133.888083 -263.319364) (xy 133.923576 -263.353456) (xy 133.953141 -263.3928) (xy 133.976012 -263.436377)
			(xy 133.991596 -263.483058) (xy 133.999491 -263.531635) (xy 133.999986 -263.556242) (xy 134.328928 -263.556242)
			(xy 134.332888 -263.507188) (xy 134.344665 -263.459404) (xy 134.363956 -263.414128) (xy 134.390259 -263.372532)
			(xy 134.422894 -263.335695) (xy 134.461015 -263.30457) (xy 134.503636 -263.279963) (xy 134.549652 -263.262511)
			(xy 134.597871 -263.252667) (xy 134.647046 -263.250686) (xy 134.695901 -263.256618) (xy 134.743172 -263.27031)
			(xy 134.787634 -263.291408) (xy 134.828137 -263.319364) (xy 134.86363 -263.353456) (xy 134.893195 -263.3928)
			(xy 134.916066 -263.436377) (xy 134.93165 -263.483058) (xy 134.939545 -263.531635) (xy 134.94004 -263.556242)
			(xy 134.939545 -263.580849) (xy 134.93165 -263.629426) (xy 134.916066 -263.676107) (xy 134.893195 -263.719684)
			(xy 134.86363 -263.759028) (xy 134.828137 -263.79312) (xy 134.787634 -263.821076) (xy 134.743172 -263.842174)
			(xy 134.695901 -263.855866) (xy 134.647046 -263.861798) (xy 134.597871 -263.859817) (xy 134.549652 -263.849973)
			(xy 134.503636 -263.832521) (xy 134.461015 -263.807914) (xy 134.422894 -263.776789) (xy 134.390259 -263.739952)
			(xy 134.363956 -263.698356) (xy 134.344665 -263.65308) (xy 134.332888 -263.605296) (xy 134.328928 -263.556242)
			(xy 133.999986 -263.556242) (xy 133.999491 -263.580849) (xy 133.991596 -263.629426) (xy 133.976012 -263.676107)
			(xy 133.953141 -263.719684) (xy 133.923576 -263.759028) (xy 133.888083 -263.79312) (xy 133.84758 -263.821076)
			(xy 133.803118 -263.842174) (xy 133.755847 -263.855866) (xy 133.706992 -263.861798) (xy 133.657817 -263.859817)
			(xy 133.609598 -263.849973) (xy 133.563582 -263.832521) (xy 133.520961 -263.807914) (xy 133.48284 -263.776789)
			(xy 133.450205 -263.739952) (xy 133.423902 -263.698356) (xy 133.404611 -263.65308) (xy 133.392834 -263.605296)
			(xy 133.388874 -263.556242) (xy 133.0706 -263.556242) (xy 133.070088 -263.581688) (xy 133.061924 -263.631922)
			(xy 133.045808 -263.680196) (xy 133.022157 -263.725259) (xy 132.991584 -263.765945) (xy 132.95488 -263.8012)
			(xy 132.912996 -263.83011) (xy 132.867017 -263.851927) (xy 132.818133 -263.866087) (xy 132.767612 -263.872221)
			(xy 132.71676 -263.870172) (xy 132.666896 -263.859992) (xy 132.61931 -263.841945) (xy 132.575236 -263.816499)
			(xy 132.535814 -263.784312) (xy 132.502066 -263.746218) (xy 132.474865 -263.703204) (xy 132.454917 -263.656384)
			(xy 132.442738 -263.60697) (xy 132.438643 -263.556242) (xy 132.130546 -263.556242) (xy 132.130034 -263.581688)
			(xy 132.12187 -263.631922) (xy 132.105754 -263.680196) (xy 132.082103 -263.725259) (xy 132.05153 -263.765945)
			(xy 132.014826 -263.8012) (xy 131.972942 -263.83011) (xy 131.926963 -263.851927) (xy 131.878079 -263.866087)
			(xy 131.827558 -263.872221) (xy 131.776706 -263.870172) (xy 131.726842 -263.859992) (xy 131.679256 -263.841945)
			(xy 131.635182 -263.816499) (xy 131.59576 -263.784312) (xy 131.562012 -263.746218) (xy 131.534811 -263.703204)
			(xy 131.514863 -263.656384) (xy 131.502684 -263.60697) (xy 131.498589 -263.556242) (xy 130.250438 -263.556242)
			(xy 130.249926 -263.581688) (xy 130.241762 -263.631922) (xy 130.225646 -263.680196) (xy 130.201995 -263.725259)
			(xy 130.171422 -263.765945) (xy 130.134718 -263.8012) (xy 130.092834 -263.83011) (xy 130.046855 -263.851927)
			(xy 129.997971 -263.866087) (xy 129.94745 -263.872221) (xy 129.896598 -263.870172) (xy 129.846734 -263.859992)
			(xy 129.799148 -263.841945) (xy 129.755074 -263.816499) (xy 129.715652 -263.784312) (xy 129.681904 -263.746218)
			(xy 129.654703 -263.703204) (xy 129.634755 -263.656384) (xy 129.622576 -263.60697) (xy 129.618481 -263.556242)
			(xy 129.29997 -263.556242) (xy 129.299475 -263.580849) (xy 129.29158 -263.629426) (xy 129.275996 -263.676107)
			(xy 129.253125 -263.719684) (xy 129.22356 -263.759028) (xy 129.188067 -263.79312) (xy 129.147564 -263.821076)
			(xy 129.103102 -263.842174) (xy 129.055831 -263.855866) (xy 129.006976 -263.861798) (xy 128.957801 -263.859817)
			(xy 128.909582 -263.849973) (xy 128.863566 -263.832521) (xy 128.820945 -263.807914) (xy 128.782824 -263.776789)
			(xy 128.750189 -263.739952) (xy 128.723886 -263.698356) (xy 128.704595 -263.65308) (xy 128.692818 -263.605296)
			(xy 128.688858 -263.556242) (xy 128.370584 -263.556242) (xy 128.370072 -263.581688) (xy 128.361908 -263.631922)
			(xy 128.345792 -263.680196) (xy 128.322141 -263.725259) (xy 128.291568 -263.765945) (xy 128.254864 -263.8012)
			(xy 128.21298 -263.83011) (xy 128.167001 -263.851927) (xy 128.118117 -263.866087) (xy 128.067596 -263.872221)
			(xy 128.016744 -263.870172) (xy 127.96688 -263.859992) (xy 127.919294 -263.841945) (xy 127.87522 -263.816499)
			(xy 127.835798 -263.784312) (xy 127.80205 -263.746218) (xy 127.774849 -263.703204) (xy 127.754901 -263.656384)
			(xy 127.742722 -263.60697) (xy 127.738627 -263.556242) (xy 127.420116 -263.556242) (xy 127.419621 -263.580849)
			(xy 127.411726 -263.629426) (xy 127.396142 -263.676107) (xy 127.373271 -263.719684) (xy 127.343706 -263.759028)
			(xy 127.308213 -263.79312) (xy 127.26771 -263.821076) (xy 127.223248 -263.842174) (xy 127.175977 -263.855866)
			(xy 127.127122 -263.861798) (xy 127.077947 -263.859817) (xy 127.029728 -263.849973) (xy 126.983712 -263.832521)
			(xy 126.941091 -263.807914) (xy 126.90297 -263.776789) (xy 126.870335 -263.739952) (xy 126.844032 -263.698356)
			(xy 126.824741 -263.65308) (xy 126.812964 -263.605296) (xy 126.809004 -263.556242) (xy 125.540008 -263.556242)
			(xy 125.539513 -263.580849) (xy 125.531618 -263.629426) (xy 125.516034 -263.676107) (xy 125.493163 -263.719684)
			(xy 125.463598 -263.759028) (xy 125.428105 -263.79312) (xy 125.387602 -263.821076) (xy 125.34314 -263.842174)
			(xy 125.295869 -263.855866) (xy 125.247014 -263.861798) (xy 125.197839 -263.859817) (xy 125.14962 -263.849973)
			(xy 125.103604 -263.832521) (xy 125.060983 -263.807914) (xy 125.022862 -263.776789) (xy 124.990227 -263.739952)
			(xy 124.963924 -263.698356) (xy 124.944633 -263.65308) (xy 124.932856 -263.605296) (xy 124.928896 -263.556242)
			(xy 123.660154 -263.556242) (xy 123.660154 -263.562338) (xy 123.659238 -263.586015) (xy 123.650992 -263.632672)
			(xy 123.635635 -263.677494) (xy 123.613536 -263.719404) (xy 123.585226 -263.757397) (xy 123.551385 -263.790558)
			(xy 123.512826 -263.818091) (xy 123.470476 -263.839336) (xy 123.425351 -263.85378) (xy 123.378536 -263.861078)
			(xy 123.354846 -263.86155) (xy 123.330849 -263.861107) (xy 123.283446 -263.853607) (xy 123.237799 -263.838783)
			(xy 123.195034 -263.817) (xy 123.156202 -263.788796) (xy 123.122261 -263.754865) (xy 123.094046 -263.716041)
			(xy 123.072251 -263.673282) (xy 123.057414 -263.62764) (xy 123.0499 -263.580239) (xy 123.049538 -263.556242)
			(xy 123.051062 -263.525762) (xy 123.052078 -263.514332) (xy 123.04776 -263.502394) (xy 123.044458 -263.492488)
			(xy 122.989848 -263.432544) (xy 122.988324 -263.430766) (xy 122.987308 -263.42975) (xy 122.979912 -263.422897)
			(xy 122.961314 -263.415152) (xy 122.95124 -263.414764) (xy 122.23496 -263.414764) (xy 122.225119 -263.415294)
			(xy 122.206947 -263.422869) (xy 122.199654 -263.429496) (xy 121.670318 -263.958832) (xy 121.663081 -263.965548)
			(xy 121.644876 -263.97315) (xy 121.635012 -263.973564) (xy 121.284492 -263.973564) (xy 121.274347 -263.974006)
			(xy 121.255634 -263.981844) (xy 121.241399 -263.996303) (xy 121.237248 -264.005568) (xy 121.205498 -264.085578)
			(xy 121.20499 -264.086594) (xy 121.20499 -264.086848) (xy 121.202047 -264.096067) (xy 121.202558 -264.115398)
			(xy 121.206006 -264.12444) (xy 121.215404 -264.146284) (xy 121.222262 -264.153142) (xy 121.238682 -264.170319)
			(xy 121.266534 -264.208816) (xy 121.288083 -264.251165) (xy 121.302809 -264.296341) (xy 121.310356 -264.343254)
			(xy 121.31089 -264.366248) (xy 122.578888 -264.366248) (xy 122.582848 -264.317194) (xy 122.594625 -264.26941)
			(xy 122.613916 -264.224134) (xy 122.640219 -264.182538) (xy 122.672854 -264.145701) (xy 122.710975 -264.114576)
			(xy 122.753596 -264.089969) (xy 122.799612 -264.072517) (xy 122.847831 -264.062673) (xy 122.897006 -264.060692)
			(xy 122.945861 -264.066624) (xy 122.993132 -264.080316) (xy 123.037594 -264.101414) (xy 123.078097 -264.12937)
			(xy 123.11359 -264.163462) (xy 123.143155 -264.202806) (xy 123.166026 -264.246383) (xy 123.18161 -264.293064)
			(xy 123.189505 -264.341641) (xy 123.19 -264.366248) (xy 124.458996 -264.366248) (xy 124.462956 -264.317194)
			(xy 124.474733 -264.26941) (xy 124.494024 -264.224134) (xy 124.520327 -264.182538) (xy 124.552962 -264.145701)
			(xy 124.591083 -264.114576) (xy 124.633704 -264.089969) (xy 124.67972 -264.072517) (xy 124.727939 -264.062673)
			(xy 124.777114 -264.060692) (xy 124.825969 -264.066624) (xy 124.87324 -264.080316) (xy 124.917702 -264.101414)
			(xy 124.958205 -264.12937) (xy 124.993698 -264.163462) (xy 125.023263 -264.202806) (xy 125.046134 -264.246383)
			(xy 125.061718 -264.293064) (xy 125.069613 -264.341641) (xy 125.070108 -264.366248) (xy 126.33885 -264.366248)
			(xy 126.34281 -264.317194) (xy 126.354587 -264.26941) (xy 126.373878 -264.224134) (xy 126.400181 -264.182538)
			(xy 126.432816 -264.145701) (xy 126.470937 -264.114576) (xy 126.513558 -264.089969) (xy 126.559574 -264.072517)
			(xy 126.607793 -264.062673) (xy 126.656968 -264.060692) (xy 126.705823 -264.066624) (xy 126.753094 -264.080316)
			(xy 126.797556 -264.101414) (xy 126.838059 -264.12937) (xy 126.873552 -264.163462) (xy 126.903117 -264.202806)
			(xy 126.925988 -264.246383) (xy 126.941572 -264.293064) (xy 126.949467 -264.341641) (xy 126.949962 -264.366248)
			(xy 128.208527 -264.366248) (xy 128.212622 -264.31552) (xy 128.224801 -264.266106) (xy 128.244749 -264.219286)
			(xy 128.27195 -264.176272) (xy 128.305698 -264.138178) (xy 128.34512 -264.105991) (xy 128.389194 -264.080545)
			(xy 128.43678 -264.062498) (xy 128.486644 -264.052318) (xy 128.537496 -264.050269) (xy 128.588017 -264.056403)
			(xy 128.636901 -264.070563) (xy 128.68288 -264.09238) (xy 128.724764 -264.12129) (xy 128.761468 -264.156545)
			(xy 128.792041 -264.197231) (xy 128.815692 -264.242294) (xy 128.831808 -264.290568) (xy 128.839972 -264.340802)
			(xy 128.840484 -264.366248) (xy 129.148581 -264.366248) (xy 129.152676 -264.31552) (xy 129.164855 -264.266106)
			(xy 129.184803 -264.219286) (xy 129.212004 -264.176272) (xy 129.245752 -264.138178) (xy 129.285174 -264.105991)
			(xy 129.329248 -264.080545) (xy 129.376834 -264.062498) (xy 129.426698 -264.052318) (xy 129.47755 -264.050269)
			(xy 129.528071 -264.056403) (xy 129.576955 -264.070563) (xy 129.622934 -264.09238) (xy 129.664818 -264.12129)
			(xy 129.701522 -264.156545) (xy 129.732095 -264.197231) (xy 129.755746 -264.242294) (xy 129.771862 -264.290568)
			(xy 129.780026 -264.340802) (xy 129.780538 -264.366248) (xy 130.099066 -264.366248) (xy 130.103026 -264.317194)
			(xy 130.114803 -264.26941) (xy 130.134094 -264.224134) (xy 130.160397 -264.182538) (xy 130.193032 -264.145701)
			(xy 130.231153 -264.114576) (xy 130.273774 -264.089969) (xy 130.31979 -264.072517) (xy 130.368009 -264.062673)
			(xy 130.417184 -264.060692) (xy 130.466039 -264.066624) (xy 130.51331 -264.080316) (xy 130.557772 -264.101414)
			(xy 130.598275 -264.12937) (xy 130.633768 -264.163462) (xy 130.663333 -264.202806) (xy 130.686204 -264.246383)
			(xy 130.701788 -264.293064) (xy 130.709683 -264.341641) (xy 130.710178 -264.366248) (xy 131.028435 -264.366248)
			(xy 131.03253 -264.31552) (xy 131.044709 -264.266106) (xy 131.064657 -264.219286) (xy 131.091858 -264.176272)
			(xy 131.125606 -264.138178) (xy 131.165028 -264.105991) (xy 131.209102 -264.080545) (xy 131.256688 -264.062498)
			(xy 131.306552 -264.052318) (xy 131.357404 -264.050269) (xy 131.407925 -264.056403) (xy 131.456809 -264.070563)
			(xy 131.502788 -264.09238) (xy 131.544672 -264.12129) (xy 131.581376 -264.156545) (xy 131.611949 -264.197231)
			(xy 131.6356 -264.242294) (xy 131.651716 -264.290568) (xy 131.65988 -264.340802) (xy 131.660392 -264.366248)
			(xy 131.97892 -264.366248) (xy 131.98288 -264.317194) (xy 131.994657 -264.26941) (xy 132.013948 -264.224134)
			(xy 132.040251 -264.182538) (xy 132.072886 -264.145701) (xy 132.111007 -264.114576) (xy 132.153628 -264.089969)
			(xy 132.199644 -264.072517) (xy 132.247863 -264.062673) (xy 132.297038 -264.060692) (xy 132.345893 -264.066624)
			(xy 132.393164 -264.080316) (xy 132.437626 -264.101414) (xy 132.478129 -264.12937) (xy 132.513622 -264.163462)
			(xy 132.543187 -264.202806) (xy 132.566058 -264.246383) (xy 132.581642 -264.293064) (xy 132.589537 -264.341641)
			(xy 132.590032 -264.366248) (xy 132.908543 -264.366248) (xy 132.912638 -264.31552) (xy 132.924817 -264.266106)
			(xy 132.944765 -264.219286) (xy 132.971966 -264.176272) (xy 133.005714 -264.138178) (xy 133.045136 -264.105991)
			(xy 133.08921 -264.080545) (xy 133.136796 -264.062498) (xy 133.18666 -264.052318) (xy 133.237512 -264.050269)
			(xy 133.288033 -264.056403) (xy 133.336917 -264.070563) (xy 133.382896 -264.09238) (xy 133.42478 -264.12129)
			(xy 133.461484 -264.156545) (xy 133.492057 -264.197231) (xy 133.515708 -264.242294) (xy 133.531824 -264.290568)
			(xy 133.539988 -264.340802) (xy 133.5405 -264.366248) (xy 133.859028 -264.366248) (xy 133.862988 -264.317194)
			(xy 133.874765 -264.26941) (xy 133.894056 -264.224134) (xy 133.920359 -264.182538) (xy 133.952994 -264.145701)
			(xy 133.991115 -264.114576) (xy 134.033736 -264.089969) (xy 134.079752 -264.072517) (xy 134.127971 -264.062673)
			(xy 134.177146 -264.060692) (xy 134.226001 -264.066624) (xy 134.273272 -264.080316) (xy 134.317734 -264.101414)
			(xy 134.358237 -264.12937) (xy 134.39373 -264.163462) (xy 134.423295 -264.202806) (xy 134.446166 -264.246383)
			(xy 134.46175 -264.293064) (xy 134.469645 -264.341641) (xy 134.47014 -264.366248) (xy 134.798828 -264.366248)
			(xy 134.802788 -264.317194) (xy 134.814565 -264.26941) (xy 134.833856 -264.224134) (xy 134.860159 -264.182538)
			(xy 134.892794 -264.145701) (xy 134.930915 -264.114576) (xy 134.973536 -264.089969) (xy 135.019552 -264.072517)
			(xy 135.067771 -264.062673) (xy 135.116946 -264.060692) (xy 135.165801 -264.066624) (xy 135.213072 -264.080316)
			(xy 135.257534 -264.101414) (xy 135.298037 -264.12937) (xy 135.33353 -264.163462) (xy 135.363095 -264.202806)
			(xy 135.385966 -264.246383) (xy 135.40155 -264.293064) (xy 135.409445 -264.341641) (xy 135.40994 -264.366248)
			(xy 135.409445 -264.390855) (xy 135.40155 -264.439432) (xy 135.385966 -264.486113) (xy 135.363095 -264.52969)
			(xy 135.33353 -264.569034) (xy 135.298037 -264.603126) (xy 135.257534 -264.631082) (xy 135.213072 -264.65218)
			(xy 135.165801 -264.665872) (xy 135.116946 -264.671804) (xy 135.067771 -264.669823) (xy 135.019552 -264.659979)
			(xy 134.973536 -264.642527) (xy 134.930915 -264.61792) (xy 134.892794 -264.586795) (xy 134.860159 -264.549958)
			(xy 134.833856 -264.508362) (xy 134.814565 -264.463086) (xy 134.802788 -264.415302) (xy 134.798828 -264.366248)
			(xy 134.47014 -264.366248) (xy 134.469645 -264.390855) (xy 134.46175 -264.439432) (xy 134.446166 -264.486113)
			(xy 134.423295 -264.52969) (xy 134.39373 -264.569034) (xy 134.358237 -264.603126) (xy 134.317734 -264.631082)
			(xy 134.273272 -264.65218) (xy 134.226001 -264.665872) (xy 134.177146 -264.671804) (xy 134.127971 -264.669823)
			(xy 134.079752 -264.659979) (xy 134.033736 -264.642527) (xy 133.991115 -264.61792) (xy 133.952994 -264.586795)
			(xy 133.920359 -264.549958) (xy 133.894056 -264.508362) (xy 133.874765 -264.463086) (xy 133.862988 -264.415302)
			(xy 133.859028 -264.366248) (xy 133.5405 -264.366248) (xy 133.539988 -264.391694) (xy 133.531824 -264.441928)
			(xy 133.515708 -264.490202) (xy 133.492057 -264.535265) (xy 133.461484 -264.575951) (xy 133.42478 -264.611206)
			(xy 133.382896 -264.640116) (xy 133.336917 -264.661933) (xy 133.288033 -264.676093) (xy 133.237512 -264.682227)
			(xy 133.18666 -264.680178) (xy 133.136796 -264.669998) (xy 133.08921 -264.651951) (xy 133.045136 -264.626505)
			(xy 133.005714 -264.594318) (xy 132.971966 -264.556224) (xy 132.944765 -264.51321) (xy 132.924817 -264.46639)
			(xy 132.912638 -264.416976) (xy 132.908543 -264.366248) (xy 132.590032 -264.366248) (xy 132.589537 -264.390855)
			(xy 132.581642 -264.439432) (xy 132.566058 -264.486113) (xy 132.543187 -264.52969) (xy 132.513622 -264.569034)
			(xy 132.478129 -264.603126) (xy 132.437626 -264.631082) (xy 132.393164 -264.65218) (xy 132.345893 -264.665872)
			(xy 132.297038 -264.671804) (xy 132.247863 -264.669823) (xy 132.199644 -264.659979) (xy 132.153628 -264.642527)
			(xy 132.111007 -264.61792) (xy 132.072886 -264.586795) (xy 132.040251 -264.549958) (xy 132.013948 -264.508362)
			(xy 131.994657 -264.463086) (xy 131.98288 -264.415302) (xy 131.97892 -264.366248) (xy 131.660392 -264.366248)
			(xy 131.65988 -264.391694) (xy 131.651716 -264.441928) (xy 131.6356 -264.490202) (xy 131.611949 -264.535265)
			(xy 131.581376 -264.575951) (xy 131.544672 -264.611206) (xy 131.502788 -264.640116) (xy 131.456809 -264.661933)
			(xy 131.407925 -264.676093) (xy 131.357404 -264.682227) (xy 131.306552 -264.680178) (xy 131.256688 -264.669998)
			(xy 131.209102 -264.651951) (xy 131.165028 -264.626505) (xy 131.125606 -264.594318) (xy 131.091858 -264.556224)
			(xy 131.064657 -264.51321) (xy 131.044709 -264.46639) (xy 131.03253 -264.416976) (xy 131.028435 -264.366248)
			(xy 130.710178 -264.366248) (xy 130.709683 -264.390855) (xy 130.701788 -264.439432) (xy 130.686204 -264.486113)
			(xy 130.663333 -264.52969) (xy 130.633768 -264.569034) (xy 130.598275 -264.603126) (xy 130.557772 -264.631082)
			(xy 130.51331 -264.65218) (xy 130.466039 -264.665872) (xy 130.417184 -264.671804) (xy 130.368009 -264.669823)
			(xy 130.31979 -264.659979) (xy 130.273774 -264.642527) (xy 130.231153 -264.61792) (xy 130.193032 -264.586795)
			(xy 130.160397 -264.549958) (xy 130.134094 -264.508362) (xy 130.114803 -264.463086) (xy 130.103026 -264.415302)
			(xy 130.099066 -264.366248) (xy 129.780538 -264.366248) (xy 129.780026 -264.391694) (xy 129.771862 -264.441928)
			(xy 129.755746 -264.490202) (xy 129.732095 -264.535265) (xy 129.701522 -264.575951) (xy 129.664818 -264.611206)
			(xy 129.622934 -264.640116) (xy 129.576955 -264.661933) (xy 129.528071 -264.676093) (xy 129.47755 -264.682227)
			(xy 129.426698 -264.680178) (xy 129.376834 -264.669998) (xy 129.329248 -264.651951) (xy 129.285174 -264.626505)
			(xy 129.245752 -264.594318) (xy 129.212004 -264.556224) (xy 129.184803 -264.51321) (xy 129.164855 -264.46639)
			(xy 129.152676 -264.416976) (xy 129.148581 -264.366248) (xy 128.840484 -264.366248) (xy 128.839972 -264.391694)
			(xy 128.831808 -264.441928) (xy 128.815692 -264.490202) (xy 128.792041 -264.535265) (xy 128.761468 -264.575951)
			(xy 128.724764 -264.611206) (xy 128.68288 -264.640116) (xy 128.636901 -264.661933) (xy 128.588017 -264.676093)
			(xy 128.537496 -264.682227) (xy 128.486644 -264.680178) (xy 128.43678 -264.669998) (xy 128.389194 -264.651951)
			(xy 128.34512 -264.626505) (xy 128.305698 -264.594318) (xy 128.27195 -264.556224) (xy 128.244749 -264.51321)
			(xy 128.224801 -264.46639) (xy 128.212622 -264.416976) (xy 128.208527 -264.366248) (xy 126.949962 -264.366248)
			(xy 126.949467 -264.390855) (xy 126.941572 -264.439432) (xy 126.925988 -264.486113) (xy 126.903117 -264.52969)
			(xy 126.873552 -264.569034) (xy 126.838059 -264.603126) (xy 126.797556 -264.631082) (xy 126.753094 -264.65218)
			(xy 126.705823 -264.665872) (xy 126.656968 -264.671804) (xy 126.607793 -264.669823) (xy 126.559574 -264.659979)
			(xy 126.513558 -264.642527) (xy 126.470937 -264.61792) (xy 126.432816 -264.586795) (xy 126.400181 -264.549958)
			(xy 126.373878 -264.508362) (xy 126.354587 -264.463086) (xy 126.34281 -264.415302) (xy 126.33885 -264.366248)
			(xy 125.070108 -264.366248) (xy 125.069613 -264.390855) (xy 125.061718 -264.439432) (xy 125.046134 -264.486113)
			(xy 125.023263 -264.52969) (xy 124.993698 -264.569034) (xy 124.958205 -264.603126) (xy 124.917702 -264.631082)
			(xy 124.87324 -264.65218) (xy 124.825969 -264.665872) (xy 124.777114 -264.671804) (xy 124.727939 -264.669823)
			(xy 124.67972 -264.659979) (xy 124.633704 -264.642527) (xy 124.591083 -264.61792) (xy 124.552962 -264.586795)
			(xy 124.520327 -264.549958) (xy 124.494024 -264.508362) (xy 124.474733 -264.463086) (xy 124.462956 -264.415302)
			(xy 124.458996 -264.366248) (xy 123.19 -264.366248) (xy 123.189505 -264.390855) (xy 123.18161 -264.439432)
			(xy 123.166026 -264.486113) (xy 123.143155 -264.52969) (xy 123.11359 -264.569034) (xy 123.078097 -264.603126)
			(xy 123.037594 -264.631082) (xy 122.993132 -264.65218) (xy 122.945861 -264.665872) (xy 122.897006 -264.671804)
			(xy 122.847831 -264.669823) (xy 122.799612 -264.659979) (xy 122.753596 -264.642527) (xy 122.710975 -264.61792)
			(xy 122.672854 -264.586795) (xy 122.640219 -264.549958) (xy 122.613916 -264.508362) (xy 122.594625 -264.463086)
			(xy 122.582848 -264.415302) (xy 122.578888 -264.366248) (xy 121.31089 -264.366248) (xy 121.310908 -264.36701)
			(xy 121.310908 -264.371328) (xy 121.310213 -264.395164) (xy 121.302334 -264.44219) (xy 121.28724 -264.487421)
			(xy 121.265298 -264.529755) (xy 121.237042 -264.568163) (xy 121.203158 -264.601712) (xy 121.164471 -264.629586)
			(xy 121.121922 -264.651107) (xy 121.076544 -264.665752) (xy 121.029441 -264.673164) (xy 121.0056 -264.673588)
			(xy 120.981607 -264.673142) (xy 120.934213 -264.665635) (xy 120.888577 -264.650806) (xy 120.845822 -264.62902)
			(xy 120.807002 -264.600815) (xy 120.773072 -264.566883) (xy 120.744869 -264.528061) (xy 120.723086 -264.485305)
			(xy 120.70826 -264.439667) (xy 120.700757 -264.392273) (xy 120.700292 -264.36828) (xy 120.700292 -264.36066)
			(xy 120.701339 -264.33688) (xy 120.709883 -264.290056) (xy 120.71731 -264.267442) (xy 120.723152 -264.250678)
			(xy 120.725946 -264.244328) (xy 120.734074 -264.228326) (xy 120.74505 -264.207935) (xy 120.772226 -264.17044)
			(xy 120.788176 -264.15365) (xy 120.795288 -264.146538) (xy 120.80494 -264.12317) (xy 120.808166 -264.114057)
			(xy 120.80828 -264.094741) (xy 120.805194 -264.085578) (xy 120.773952 -264.005822) (xy 120.769784 -263.996492)
			(xy 120.755497 -263.981906) (xy 120.736664 -263.974022) (xy 120.726454 -263.973564) (xy 119.40667 -263.973564)
			(xy 119.396528 -263.974009) (xy 119.377821 -263.981853) (xy 119.363593 -263.996312) (xy 119.359426 -264.005568)
			(xy 119.327676 -264.085578) (xy 119.327168 -264.086594) (xy 119.327168 -264.086848) (xy 119.324226 -264.096068)
			(xy 119.324737 -264.115398) (xy 119.328184 -264.12444) (xy 119.337582 -264.146284) (xy 119.34444 -264.153142)
			(xy 119.360861 -264.170318) (xy 119.388715 -264.208815) (xy 119.410265 -264.251163) (xy 119.424993 -264.29634)
			(xy 119.43254 -264.343254) (xy 119.433086 -264.36701) (xy 119.433086 -264.371328) (xy 119.432391 -264.395163)
			(xy 119.424511 -264.442189) (xy 119.409417 -264.487417) (xy 119.387475 -264.52975) (xy 119.359218 -264.568157)
			(xy 119.325335 -264.601703) (xy 119.286648 -264.629575) (xy 119.244098 -264.651093) (xy 119.198721 -264.665735)
			(xy 119.151619 -264.673144) (xy 119.127778 -264.673588) (xy 119.103788 -264.673116) (xy 119.056401 -264.665607)
			(xy 119.010771 -264.650777) (xy 118.968023 -264.628992) (xy 118.929209 -264.600788) (xy 118.895285 -264.566859)
			(xy 118.867086 -264.528041) (xy 118.845307 -264.48529) (xy 118.830483 -264.439658) (xy 118.822981 -264.39227)
			(xy 118.82247 -264.36828) (xy 118.82247 -264.36066) (xy 118.823517 -264.33688) (xy 118.83206 -264.290056)
			(xy 118.839488 -264.267442) (xy 118.84533 -264.250678) (xy 118.848124 -264.244328) (xy 118.856252 -264.228326)
			(xy 118.867228 -264.207934) (xy 118.894402 -264.170438) (xy 118.910354 -264.15365) (xy 118.917466 -264.146538)
			(xy 118.927118 -264.12317) (xy 118.930344 -264.114057) (xy 118.930458 -264.094741) (xy 118.927372 -264.085578)
			(xy 118.89613 -264.005822) (xy 118.891961 -263.996494) (xy 118.877673 -263.981915) (xy 118.85884 -263.974038)
			(xy 118.848632 -263.973564) (xy 117.526816 -263.973564) (xy 117.51668 -263.974019) (xy 117.49799 -263.981874)
			(xy 117.483779 -263.996333) (xy 117.479572 -264.005568) (xy 117.447822 -264.085578) (xy 117.447314 -264.086594)
			(xy 117.447314 -264.086848) (xy 117.44437 -264.096067) (xy 117.444881 -264.115398) (xy 117.44833 -264.12444)
			(xy 117.457728 -264.146284) (xy 117.464586 -264.153142) (xy 117.481004 -264.170319) (xy 117.508854 -264.208817)
			(xy 117.530402 -264.251166) (xy 117.545127 -264.296342) (xy 117.552673 -264.343254) (xy 117.553232 -264.36701)
			(xy 117.553232 -264.371328) (xy 117.552537 -264.395161) (xy 117.544657 -264.442184) (xy 117.529562 -264.487409)
			(xy 117.507619 -264.529738) (xy 117.479361 -264.56814) (xy 117.445477 -264.601682) (xy 117.406789 -264.629547)
			(xy 117.36424 -264.651059) (xy 117.318863 -264.665693) (xy 117.271763 -264.673094) (xy 117.247924 -264.673588)
			(xy 117.22393 -264.673144) (xy 117.176533 -264.66564) (xy 117.130893 -264.650813) (xy 117.088135 -264.629029)
			(xy 117.049312 -264.600823) (xy 117.01538 -264.566891) (xy 116.987173 -264.528068) (xy 116.965389 -264.48531)
			(xy 116.950561 -264.439671) (xy 116.943057 -264.392274) (xy 116.942616 -264.36828) (xy 116.942744 -264.35674)
			(xy 116.944524 -264.333728) (xy 116.946172 -264.322306) (xy 116.94668 -264.318496) (xy 116.94668 -264.31748)
			(xy 116.951302 -264.29301) (xy 116.967436 -264.2459) (xy 116.991002 -264.202034) (xy 117.021375 -264.162574)
			(xy 117.057749 -264.128567) (xy 117.099161 -264.100915) (xy 117.144512 -264.08035) (xy 117.168422 -264.073386)
			(xy 117.185186 -264.068814) (xy 117.206014 -264.041636) (xy 117.206014 -264.024364) (xy 117.20552 -264.01436)
			(xy 117.197855 -263.995878) (xy 117.183703 -263.981733) (xy 117.165218 -263.974075) (xy 117.155214 -263.973564)
			(xy 117.15496 -263.973564) (xy 117.145119 -263.973035) (xy 117.126944 -263.965463) (xy 117.119654 -263.958832)
			(xy 116.349018 -263.188196) (xy 116.3423 -263.18096) (xy 116.334698 -263.162755) (xy 116.334286 -263.15289)
			(xy 116.334286 -262.127746) (xy 116.333853 -262.11768) (xy 116.326123 -262.099092) (xy 116.3193 -262.091678)
			(xy 116.184172 -261.95655) (xy 116.176774 -261.949703) (xy 116.158176 -261.941971) (xy 116.148104 -261.941564)
			(xy 106.297476 -261.941564) (xy 106.287634 -261.942091) (xy 106.269458 -261.949662) (xy 106.26217 -261.956296)
			(xy 104.371902 -263.846564) (xy 111.234223 -263.846564) (xy 111.238253 -263.794066) (xy 111.25025 -263.742798)
			(xy 111.269933 -263.693963) (xy 111.296839 -263.648704) (xy 111.330339 -263.608083) (xy 111.369647 -263.573052)
			(xy 111.413842 -263.544432) (xy 111.461887 -263.522893) (xy 111.512658 -263.508941) (xy 111.564963 -263.502903)
			(xy 111.617577 -263.50492) (xy 111.669267 -263.514944) (xy 111.71882 -263.532742) (xy 111.765076 -263.557895)
			(xy 111.80695 -263.589814) (xy 111.843462 -263.627752) (xy 111.873754 -263.670818) (xy 111.897117 -263.718003)
			(xy 111.913003 -263.768202) (xy 111.92104 -263.820238) (xy 111.921544 -263.846564) (xy 111.92104 -263.87289)
			(xy 111.913003 -263.924926) (xy 111.897117 -263.975125) (xy 111.873754 -264.02231) (xy 111.843462 -264.065376)
			(xy 111.80695 -264.103314) (xy 111.765076 -264.135233) (xy 111.71882 -264.160386) (xy 111.669267 -264.178184)
			(xy 111.617577 -264.188208) (xy 111.564963 -264.190225) (xy 111.512658 -264.184187) (xy 111.461887 -264.170235)
			(xy 111.413842 -264.148696) (xy 111.369647 -264.120076) (xy 111.330339 -264.085045) (xy 111.296839 -264.044424)
			(xy 111.269933 -263.999165) (xy 111.25025 -263.95033) (xy 111.238253 -263.899062) (xy 111.234223 -263.846564)
			(xy 104.371902 -263.846564) (xy 104.289606 -263.92886) (xy 104.282367 -263.935571) (xy 104.264162 -263.943164)
			(xy 104.2543 -263.943592) (xy 101.191568 -263.943592) (xy 101.181727 -263.944121) (xy 101.163555 -263.951697)
			(xy 101.156262 -263.958324) (xy 100.748338 -264.366248) (xy 101.90532 -264.366248) (xy 101.90928 -264.317194)
			(xy 101.921057 -264.26941) (xy 101.940348 -264.224134) (xy 101.966651 -264.182538) (xy 101.999286 -264.145701)
			(xy 102.037407 -264.114576) (xy 102.080028 -264.089969) (xy 102.126044 -264.072517) (xy 102.174263 -264.062673)
			(xy 102.223438 -264.060692) (xy 102.272293 -264.066624) (xy 102.319564 -264.080316) (xy 102.364026 -264.101414)
			(xy 102.404529 -264.12937) (xy 102.440022 -264.163462) (xy 102.469587 -264.202806) (xy 102.492458 -264.246383)
			(xy 102.508042 -264.293064) (xy 102.515937 -264.341641) (xy 102.516432 -264.366248) (xy 102.516391 -264.36828)
			(xy 103.782126 -264.36828) (xy 103.786086 -264.319226) (xy 103.797863 -264.271442) (xy 103.817154 -264.226166)
			(xy 103.843457 -264.18457) (xy 103.876092 -264.147733) (xy 103.914213 -264.116608) (xy 103.956834 -264.092001)
			(xy 104.00285 -264.074549) (xy 104.051069 -264.064705) (xy 104.100244 -264.062724) (xy 104.149099 -264.068656)
			(xy 104.19637 -264.082348) (xy 104.240832 -264.103446) (xy 104.281335 -264.131402) (xy 104.316828 -264.165494)
			(xy 104.346393 -264.204838) (xy 104.369264 -264.248415) (xy 104.384848 -264.295096) (xy 104.392743 -264.343673)
			(xy 104.393238 -264.36828) (xy 105.662234 -264.36828) (xy 105.666194 -264.319226) (xy 105.677971 -264.271442)
			(xy 105.697262 -264.226166) (xy 105.723565 -264.18457) (xy 105.7562 -264.147733) (xy 105.794321 -264.116608)
			(xy 105.836942 -264.092001) (xy 105.882958 -264.074549) (xy 105.931177 -264.064705) (xy 105.980352 -264.062724)
			(xy 106.029207 -264.068656) (xy 106.076478 -264.082348) (xy 106.12094 -264.103446) (xy 106.161443 -264.131402)
			(xy 106.196936 -264.165494) (xy 106.226501 -264.204838) (xy 106.249372 -264.248415) (xy 106.264956 -264.295096)
			(xy 106.272851 -264.343673) (xy 106.273346 -264.36828) (xy 107.542088 -264.36828) (xy 107.546048 -264.319226)
			(xy 107.557825 -264.271442) (xy 107.577116 -264.226166) (xy 107.603419 -264.18457) (xy 107.636054 -264.147733)
			(xy 107.674175 -264.116608) (xy 107.716796 -264.092001) (xy 107.762812 -264.074549) (xy 107.811031 -264.064705)
			(xy 107.860206 -264.062724) (xy 107.909061 -264.068656) (xy 107.956332 -264.082348) (xy 108.000794 -264.103446)
			(xy 108.041297 -264.131402) (xy 108.07679 -264.165494) (xy 108.106355 -264.204838) (xy 108.129226 -264.248415)
			(xy 108.14481 -264.295096) (xy 108.152705 -264.343673) (xy 108.1532 -264.36828) (xy 115.062012 -264.36828)
			(xy 115.065972 -264.319226) (xy 115.077749 -264.271442) (xy 115.09704 -264.226166) (xy 115.123343 -264.18457)
			(xy 115.155978 -264.147733) (xy 115.194099 -264.116608) (xy 115.23672 -264.092001) (xy 115.282736 -264.074549)
			(xy 115.330955 -264.064705) (xy 115.38013 -264.062724) (xy 115.428985 -264.068656) (xy 115.476256 -264.082348)
			(xy 115.520718 -264.103446) (xy 115.561221 -264.131402) (xy 115.596714 -264.165494) (xy 115.626279 -264.204838)
			(xy 115.64915 -264.248415) (xy 115.664734 -264.295096) (xy 115.672629 -264.343673) (xy 115.673124 -264.36828)
			(xy 115.672629 -264.392887) (xy 115.664734 -264.441464) (xy 115.64915 -264.488145) (xy 115.626279 -264.531722)
			(xy 115.596714 -264.571066) (xy 115.561221 -264.605158) (xy 115.520718 -264.633114) (xy 115.476256 -264.654212)
			(xy 115.428985 -264.667904) (xy 115.38013 -264.673836) (xy 115.330955 -264.671855) (xy 115.282736 -264.662011)
			(xy 115.23672 -264.644559) (xy 115.194099 -264.619952) (xy 115.155978 -264.588827) (xy 115.123343 -264.55199)
			(xy 115.09704 -264.510394) (xy 115.077749 -264.465118) (xy 115.065972 -264.417334) (xy 115.062012 -264.36828)
			(xy 108.1532 -264.36828) (xy 108.152705 -264.392887) (xy 108.14481 -264.441464) (xy 108.129226 -264.488145)
			(xy 108.106355 -264.531722) (xy 108.07679 -264.571066) (xy 108.041297 -264.605158) (xy 108.000794 -264.633114)
			(xy 107.956332 -264.654212) (xy 107.909061 -264.667904) (xy 107.860206 -264.673836) (xy 107.811031 -264.671855)
			(xy 107.762812 -264.662011) (xy 107.716796 -264.644559) (xy 107.674175 -264.619952) (xy 107.636054 -264.588827)
			(xy 107.603419 -264.55199) (xy 107.577116 -264.510394) (xy 107.557825 -264.465118) (xy 107.546048 -264.417334)
			(xy 107.542088 -264.36828) (xy 106.273346 -264.36828) (xy 106.272851 -264.392887) (xy 106.264956 -264.441464)
			(xy 106.249372 -264.488145) (xy 106.226501 -264.531722) (xy 106.196936 -264.571066) (xy 106.161443 -264.605158)
			(xy 106.12094 -264.633114) (xy 106.076478 -264.654212) (xy 106.029207 -264.667904) (xy 105.980352 -264.673836)
			(xy 105.931177 -264.671855) (xy 105.882958 -264.662011) (xy 105.836942 -264.644559) (xy 105.794321 -264.619952)
			(xy 105.7562 -264.588827) (xy 105.723565 -264.55199) (xy 105.697262 -264.510394) (xy 105.677971 -264.465118)
			(xy 105.666194 -264.417334) (xy 105.662234 -264.36828) (xy 104.393238 -264.36828) (xy 104.392743 -264.392887)
			(xy 104.384848 -264.441464) (xy 104.369264 -264.488145) (xy 104.346393 -264.531722) (xy 104.316828 -264.571066)
			(xy 104.281335 -264.605158) (xy 104.240832 -264.633114) (xy 104.19637 -264.654212) (xy 104.149099 -264.667904)
			(xy 104.100244 -264.673836) (xy 104.051069 -264.671855) (xy 104.00285 -264.662011) (xy 103.956834 -264.644559)
			(xy 103.914213 -264.619952) (xy 103.876092 -264.588827) (xy 103.843457 -264.55199) (xy 103.817154 -264.510394)
			(xy 103.797863 -264.465118) (xy 103.786086 -264.417334) (xy 103.782126 -264.36828) (xy 102.516391 -264.36828)
			(xy 102.515937 -264.390855) (xy 102.508042 -264.439432) (xy 102.492458 -264.486113) (xy 102.469587 -264.52969)
			(xy 102.440022 -264.569034) (xy 102.404529 -264.603126) (xy 102.364026 -264.631082) (xy 102.319564 -264.65218)
			(xy 102.272293 -264.665872) (xy 102.223438 -264.671804) (xy 102.174263 -264.669823) (xy 102.126044 -264.659979)
			(xy 102.080028 -264.642527) (xy 102.037407 -264.61792) (xy 101.999286 -264.586795) (xy 101.966651 -264.549958)
			(xy 101.940348 -264.508362) (xy 101.921057 -264.463086) (xy 101.90928 -264.415302) (xy 101.90532 -264.366248)
			(xy 100.748338 -264.366248) (xy 100.595176 -264.51941) (xy 100.592128 -264.52449) (xy 100.588318 -264.53084)
			(xy 100.588064 -264.53084) (xy 100.572111 -264.554616) (xy 100.532867 -264.5963) (xy 100.510086 -264.613644)
			(xy 100.509578 -264.613898) (xy 100.507292 -264.615676) (xy 100.503171 -264.618954) (xy 100.496256 -264.626892)
			(xy 100.493576 -264.631424) (xy 100.484432 -264.64768) (xy 100.481384 -264.653268) (xy 100.478422 -264.658991)
			(xy 100.475201 -264.671464) (xy 100.475034 -264.677906) (xy 100.475034 -264.839196) (xy 100.475435 -264.848395)
			(xy 100.480773 -264.862564) (xy 111.234223 -264.862564) (xy 111.238253 -264.810066) (xy 111.25025 -264.758798)
			(xy 111.269933 -264.709963) (xy 111.296839 -264.664704) (xy 111.330339 -264.624083) (xy 111.369647 -264.589052)
			(xy 111.413842 -264.560432) (xy 111.461887 -264.538893) (xy 111.512658 -264.524941) (xy 111.564963 -264.518903)
			(xy 111.617577 -264.52092) (xy 111.669267 -264.530944) (xy 111.71882 -264.548742) (xy 111.765076 -264.573895)
			(xy 111.80695 -264.605814) (xy 111.843462 -264.643752) (xy 111.873754 -264.686818) (xy 111.897117 -264.734003)
			(xy 111.913003 -264.784202) (xy 111.92104 -264.836238) (xy 111.921544 -264.862564) (xy 111.92104 -264.88889)
			(xy 111.913003 -264.940926) (xy 111.897117 -264.991125) (xy 111.873754 -265.03831) (xy 111.843462 -265.081376)
			(xy 111.80695 -265.119314) (xy 111.765076 -265.151233) (xy 111.719063 -265.176254) (xy 121.168934 -265.176254)
			(xy 121.172894 -265.1272) (xy 121.184671 -265.079416) (xy 121.203962 -265.03414) (xy 121.230265 -264.992544)
			(xy 121.2629 -264.955707) (xy 121.301021 -264.924582) (xy 121.343642 -264.899975) (xy 121.389658 -264.882523)
			(xy 121.437877 -264.872679) (xy 121.487052 -264.870698) (xy 121.535907 -264.87663) (xy 121.583178 -264.890322)
			(xy 121.62764 -264.91142) (xy 121.668143 -264.939376) (xy 121.703636 -264.973468) (xy 121.733201 -265.012812)
			(xy 121.756072 -265.056389) (xy 121.771656 -265.10307) (xy 121.779551 -265.151647) (xy 121.780046 -265.176254)
			(xy 123.049042 -265.176254) (xy 123.053002 -265.1272) (xy 123.064779 -265.079416) (xy 123.08407 -265.03414)
			(xy 123.110373 -264.992544) (xy 123.143008 -264.955707) (xy 123.181129 -264.924582) (xy 123.22375 -264.899975)
			(xy 123.269766 -264.882523) (xy 123.317985 -264.872679) (xy 123.36716 -264.870698) (xy 123.416015 -264.87663)
			(xy 123.463286 -264.890322) (xy 123.507748 -264.91142) (xy 123.548251 -264.939376) (xy 123.583744 -264.973468)
			(xy 123.613309 -265.012812) (xy 123.63618 -265.056389) (xy 123.651764 -265.10307) (xy 123.659659 -265.151647)
			(xy 123.660154 -265.176254) (xy 124.928896 -265.176254) (xy 124.932856 -265.1272) (xy 124.944633 -265.079416)
			(xy 124.963924 -265.03414) (xy 124.990227 -264.992544) (xy 125.022862 -264.955707) (xy 125.060983 -264.924582)
			(xy 125.103604 -264.899975) (xy 125.14962 -264.882523) (xy 125.197839 -264.872679) (xy 125.247014 -264.870698)
			(xy 125.295869 -264.87663) (xy 125.34314 -264.890322) (xy 125.387602 -264.91142) (xy 125.428105 -264.939376)
			(xy 125.463598 -264.973468) (xy 125.493163 -265.012812) (xy 125.516034 -265.056389) (xy 125.531618 -265.10307)
			(xy 125.539513 -265.151647) (xy 125.540008 -265.176254) (xy 126.809004 -265.176254) (xy 126.812964 -265.1272)
			(xy 126.824741 -265.079416) (xy 126.844032 -265.03414) (xy 126.870335 -264.992544) (xy 126.90297 -264.955707)
			(xy 126.941091 -264.924582) (xy 126.983712 -264.899975) (xy 127.029728 -264.882523) (xy 127.077947 -264.872679)
			(xy 127.127122 -264.870698) (xy 127.175977 -264.87663) (xy 127.223248 -264.890322) (xy 127.26771 -264.91142)
			(xy 127.308213 -264.939376) (xy 127.343706 -264.973468) (xy 127.373271 -265.012812) (xy 127.396142 -265.056389)
			(xy 127.411726 -265.10307) (xy 127.419621 -265.151647) (xy 127.420116 -265.176254) (xy 127.738627 -265.176254)
			(xy 127.742722 -265.125526) (xy 127.754901 -265.076112) (xy 127.774849 -265.029292) (xy 127.80205 -264.986278)
			(xy 127.835798 -264.948184) (xy 127.87522 -264.915997) (xy 127.919294 -264.890551) (xy 127.96688 -264.872504)
			(xy 128.016744 -264.862324) (xy 128.067596 -264.860275) (xy 128.118117 -264.866409) (xy 128.167001 -264.880569)
			(xy 128.21298 -264.902386) (xy 128.254864 -264.931296) (xy 128.291568 -264.966551) (xy 128.322141 -265.007237)
			(xy 128.345792 -265.0523) (xy 128.361908 -265.100574) (xy 128.370072 -265.150808) (xy 128.370584 -265.176254)
			(xy 128.688858 -265.176254) (xy 128.692818 -265.1272) (xy 128.704595 -265.079416) (xy 128.723886 -265.03414)
			(xy 128.750189 -264.992544) (xy 128.782824 -264.955707) (xy 128.820945 -264.924582) (xy 128.863566 -264.899975)
			(xy 128.909582 -264.882523) (xy 128.957801 -264.872679) (xy 129.006976 -264.870698) (xy 129.055831 -264.87663)
			(xy 129.103102 -264.890322) (xy 129.147564 -264.91142) (xy 129.188067 -264.939376) (xy 129.22356 -264.973468)
			(xy 129.253125 -265.012812) (xy 129.275996 -265.056389) (xy 129.29158 -265.10307) (xy 129.299475 -265.151647)
			(xy 129.29997 -265.176254) (xy 129.628912 -265.176254) (xy 129.632872 -265.1272) (xy 129.644649 -265.079416)
			(xy 129.66394 -265.03414) (xy 129.690243 -264.992544) (xy 129.722878 -264.955707) (xy 129.760999 -264.924582)
			(xy 129.80362 -264.899975) (xy 129.849636 -264.882523) (xy 129.897855 -264.872679) (xy 129.94703 -264.870698)
			(xy 129.995885 -264.87663) (xy 130.043156 -264.890322) (xy 130.087618 -264.91142) (xy 130.128121 -264.939376)
			(xy 130.163614 -264.973468) (xy 130.193179 -265.012812) (xy 130.21605 -265.056389) (xy 130.231634 -265.10307)
			(xy 130.239529 -265.151647) (xy 130.240024 -265.176254) (xy 130.568966 -265.176254) (xy 130.572926 -265.1272)
			(xy 130.584703 -265.079416) (xy 130.603994 -265.03414) (xy 130.630297 -264.992544) (xy 130.662932 -264.955707)
			(xy 130.701053 -264.924582) (xy 130.743674 -264.899975) (xy 130.78969 -264.882523) (xy 130.837909 -264.872679)
			(xy 130.887084 -264.870698) (xy 130.935939 -264.87663) (xy 130.98321 -264.890322) (xy 131.027672 -264.91142)
			(xy 131.068175 -264.939376) (xy 131.103668 -264.973468) (xy 131.133233 -265.012812) (xy 131.156104 -265.056389)
			(xy 131.171688 -265.10307) (xy 131.179583 -265.151647) (xy 131.180078 -265.176254) (xy 131.498589 -265.176254)
			(xy 131.502684 -265.125526) (xy 131.514863 -265.076112) (xy 131.534811 -265.029292) (xy 131.562012 -264.986278)
			(xy 131.59576 -264.948184) (xy 131.635182 -264.915997) (xy 131.679256 -264.890551) (xy 131.726842 -264.872504)
			(xy 131.776706 -264.862324) (xy 131.827558 -264.860275) (xy 131.878079 -264.866409) (xy 131.926963 -264.880569)
			(xy 131.972942 -264.902386) (xy 132.014826 -264.931296) (xy 132.05153 -264.966551) (xy 132.082103 -265.007237)
			(xy 132.105754 -265.0523) (xy 132.12187 -265.100574) (xy 132.130034 -265.150808) (xy 132.130546 -265.176254)
			(xy 132.44882 -265.176254) (xy 132.45278 -265.1272) (xy 132.464557 -265.079416) (xy 132.483848 -265.03414)
			(xy 132.510151 -264.992544) (xy 132.542786 -264.955707) (xy 132.580907 -264.924582) (xy 132.623528 -264.899975)
			(xy 132.669544 -264.882523) (xy 132.717763 -264.872679) (xy 132.766938 -264.870698) (xy 132.815793 -264.87663)
			(xy 132.863064 -264.890322) (xy 132.907526 -264.91142) (xy 132.948029 -264.939376) (xy 132.983522 -264.973468)
			(xy 133.013087 -265.012812) (xy 133.035958 -265.056389) (xy 133.051542 -265.10307) (xy 133.059437 -265.151647)
			(xy 133.059932 -265.176254) (xy 133.388874 -265.176254) (xy 133.392834 -265.1272) (xy 133.404611 -265.079416)
			(xy 133.423902 -265.03414) (xy 133.450205 -264.992544) (xy 133.48284 -264.955707) (xy 133.520961 -264.924582)
			(xy 133.563582 -264.899975) (xy 133.609598 -264.882523) (xy 133.657817 -264.872679) (xy 133.706992 -264.870698)
			(xy 133.755847 -264.87663) (xy 133.803118 -264.890322) (xy 133.84758 -264.91142) (xy 133.888083 -264.939376)
			(xy 133.923576 -264.973468) (xy 133.953141 -265.012812) (xy 133.976012 -265.056389) (xy 133.991596 -265.10307)
			(xy 133.999491 -265.151647) (xy 133.999986 -265.176254) (xy 134.328928 -265.176254) (xy 134.332888 -265.1272)
			(xy 134.344665 -265.079416) (xy 134.363956 -265.03414) (xy 134.390259 -264.992544) (xy 134.422894 -264.955707)
			(xy 134.461015 -264.924582) (xy 134.503636 -264.899975) (xy 134.549652 -264.882523) (xy 134.597871 -264.872679)
			(xy 134.647046 -264.870698) (xy 134.695901 -264.87663) (xy 134.743172 -264.890322) (xy 134.787634 -264.91142)
			(xy 134.828137 -264.939376) (xy 134.86363 -264.973468) (xy 134.893195 -265.012812) (xy 134.916066 -265.056389)
			(xy 134.93165 -265.10307) (xy 134.939545 -265.151647) (xy 134.94004 -265.176254) (xy 135.268982 -265.176254)
			(xy 135.272942 -265.1272) (xy 135.284719 -265.079416) (xy 135.30401 -265.03414) (xy 135.330313 -264.992544)
			(xy 135.362948 -264.955707) (xy 135.401069 -264.924582) (xy 135.44369 -264.899975) (xy 135.489706 -264.882523)
			(xy 135.537925 -264.872679) (xy 135.5871 -264.870698) (xy 135.635955 -264.87663) (xy 135.683226 -264.890322)
			(xy 135.727688 -264.91142) (xy 135.768191 -264.939376) (xy 135.803684 -264.973468) (xy 135.833249 -265.012812)
			(xy 135.85612 -265.056389) (xy 135.871704 -265.10307) (xy 135.879599 -265.151647) (xy 135.880094 -265.176254)
			(xy 136.209036 -265.176254) (xy 136.212996 -265.1272) (xy 136.224773 -265.079416) (xy 136.244064 -265.03414)
			(xy 136.270367 -264.992544) (xy 136.303002 -264.955707) (xy 136.341123 -264.924582) (xy 136.383744 -264.899975)
			(xy 136.42976 -264.882523) (xy 136.477979 -264.872679) (xy 136.527154 -264.870698) (xy 136.576009 -264.87663)
			(xy 136.62328 -264.890322) (xy 136.667742 -264.91142) (xy 136.708245 -264.939376) (xy 136.743738 -264.973468)
			(xy 136.773303 -265.012812) (xy 136.796174 -265.056389) (xy 136.811758 -265.10307) (xy 136.819653 -265.151647)
			(xy 136.820148 -265.176254) (xy 136.819653 -265.200861) (xy 136.811758 -265.249438) (xy 136.796174 -265.296119)
			(xy 136.773303 -265.339696) (xy 136.743738 -265.37904) (xy 136.708245 -265.413132) (xy 136.667742 -265.441088)
			(xy 136.62328 -265.462186) (xy 136.576009 -265.475878) (xy 136.527154 -265.48181) (xy 136.477979 -265.479829)
			(xy 136.42976 -265.469985) (xy 136.383744 -265.452533) (xy 136.341123 -265.427926) (xy 136.303002 -265.396801)
			(xy 136.270367 -265.359964) (xy 136.244064 -265.318368) (xy 136.224773 -265.273092) (xy 136.212996 -265.225308)
			(xy 136.209036 -265.176254) (xy 135.880094 -265.176254) (xy 135.879599 -265.200861) (xy 135.871704 -265.249438)
			(xy 135.85612 -265.296119) (xy 135.833249 -265.339696) (xy 135.803684 -265.37904) (xy 135.768191 -265.413132)
			(xy 135.727688 -265.441088) (xy 135.683226 -265.462186) (xy 135.635955 -265.475878) (xy 135.5871 -265.48181)
			(xy 135.537925 -265.479829) (xy 135.489706 -265.469985) (xy 135.44369 -265.452533) (xy 135.401069 -265.427926)
			(xy 135.362948 -265.396801) (xy 135.330313 -265.359964) (xy 135.30401 -265.318368) (xy 135.284719 -265.273092)
			(xy 135.272942 -265.225308) (xy 135.268982 -265.176254) (xy 134.94004 -265.176254) (xy 134.939545 -265.200861)
			(xy 134.93165 -265.249438) (xy 134.916066 -265.296119) (xy 134.893195 -265.339696) (xy 134.86363 -265.37904)
			(xy 134.828137 -265.413132) (xy 134.787634 -265.441088) (xy 134.743172 -265.462186) (xy 134.695901 -265.475878)
			(xy 134.647046 -265.48181) (xy 134.597871 -265.479829) (xy 134.549652 -265.469985) (xy 134.503636 -265.452533)
			(xy 134.461015 -265.427926) (xy 134.422894 -265.396801) (xy 134.390259 -265.359964) (xy 134.363956 -265.318368)
			(xy 134.344665 -265.273092) (xy 134.332888 -265.225308) (xy 134.328928 -265.176254) (xy 133.999986 -265.176254)
			(xy 133.999491 -265.200861) (xy 133.991596 -265.249438) (xy 133.976012 -265.296119) (xy 133.953141 -265.339696)
			(xy 133.923576 -265.37904) (xy 133.888083 -265.413132) (xy 133.84758 -265.441088) (xy 133.803118 -265.462186)
			(xy 133.755847 -265.475878) (xy 133.706992 -265.48181) (xy 133.657817 -265.479829) (xy 133.609598 -265.469985)
			(xy 133.563582 -265.452533) (xy 133.520961 -265.427926) (xy 133.48284 -265.396801) (xy 133.450205 -265.359964)
			(xy 133.423902 -265.318368) (xy 133.404611 -265.273092) (xy 133.392834 -265.225308) (xy 133.388874 -265.176254)
			(xy 133.059932 -265.176254) (xy 133.059437 -265.200861) (xy 133.051542 -265.249438) (xy 133.035958 -265.296119)
			(xy 133.013087 -265.339696) (xy 132.983522 -265.37904) (xy 132.948029 -265.413132) (xy 132.907526 -265.441088)
			(xy 132.863064 -265.462186) (xy 132.815793 -265.475878) (xy 132.766938 -265.48181) (xy 132.717763 -265.479829)
			(xy 132.669544 -265.469985) (xy 132.623528 -265.452533) (xy 132.580907 -265.427926) (xy 132.542786 -265.396801)
			(xy 132.510151 -265.359964) (xy 132.483848 -265.318368) (xy 132.464557 -265.273092) (xy 132.45278 -265.225308)
			(xy 132.44882 -265.176254) (xy 132.130546 -265.176254) (xy 132.130034 -265.2017) (xy 132.12187 -265.251934)
			(xy 132.105754 -265.300208) (xy 132.082103 -265.345271) (xy 132.05153 -265.385957) (xy 132.014826 -265.421212)
			(xy 131.972942 -265.450122) (xy 131.926963 -265.471939) (xy 131.878079 -265.486099) (xy 131.827558 -265.492233)
			(xy 131.776706 -265.490184) (xy 131.726842 -265.480004) (xy 131.679256 -265.461957) (xy 131.635182 -265.436511)
			(xy 131.59576 -265.404324) (xy 131.562012 -265.36623) (xy 131.534811 -265.323216) (xy 131.514863 -265.276396)
			(xy 131.502684 -265.226982) (xy 131.498589 -265.176254) (xy 131.180078 -265.176254) (xy 131.179583 -265.200861)
			(xy 131.171688 -265.249438) (xy 131.156104 -265.296119) (xy 131.133233 -265.339696) (xy 131.103668 -265.37904)
			(xy 131.068175 -265.413132) (xy 131.027672 -265.441088) (xy 130.98321 -265.462186) (xy 130.935939 -265.475878)
			(xy 130.887084 -265.48181) (xy 130.837909 -265.479829) (xy 130.78969 -265.469985) (xy 130.743674 -265.452533)
			(xy 130.701053 -265.427926) (xy 130.662932 -265.396801) (xy 130.630297 -265.359964) (xy 130.603994 -265.318368)
			(xy 130.584703 -265.273092) (xy 130.572926 -265.225308) (xy 130.568966 -265.176254) (xy 130.240024 -265.176254)
			(xy 130.239529 -265.200861) (xy 130.231634 -265.249438) (xy 130.21605 -265.296119) (xy 130.193179 -265.339696)
			(xy 130.163614 -265.37904) (xy 130.128121 -265.413132) (xy 130.087618 -265.441088) (xy 130.043156 -265.462186)
			(xy 129.995885 -265.475878) (xy 129.94703 -265.48181) (xy 129.897855 -265.479829) (xy 129.849636 -265.469985)
			(xy 129.80362 -265.452533) (xy 129.760999 -265.427926) (xy 129.722878 -265.396801) (xy 129.690243 -265.359964)
			(xy 129.66394 -265.318368) (xy 129.644649 -265.273092) (xy 129.632872 -265.225308) (xy 129.628912 -265.176254)
			(xy 129.29997 -265.176254) (xy 129.299475 -265.200861) (xy 129.29158 -265.249438) (xy 129.275996 -265.296119)
			(xy 129.253125 -265.339696) (xy 129.22356 -265.37904) (xy 129.188067 -265.413132) (xy 129.147564 -265.441088)
			(xy 129.103102 -265.462186) (xy 129.055831 -265.475878) (xy 129.006976 -265.48181) (xy 128.957801 -265.479829)
			(xy 128.909582 -265.469985) (xy 128.863566 -265.452533) (xy 128.820945 -265.427926) (xy 128.782824 -265.396801)
			(xy 128.750189 -265.359964) (xy 128.723886 -265.318368) (xy 128.704595 -265.273092) (xy 128.692818 -265.225308)
			(xy 128.688858 -265.176254) (xy 128.370584 -265.176254) (xy 128.370072 -265.2017) (xy 128.361908 -265.251934)
			(xy 128.345792 -265.300208) (xy 128.322141 -265.345271) (xy 128.291568 -265.385957) (xy 128.254864 -265.421212)
			(xy 128.21298 -265.450122) (xy 128.167001 -265.471939) (xy 128.118117 -265.486099) (xy 128.067596 -265.492233)
			(xy 128.016744 -265.490184) (xy 127.96688 -265.480004) (xy 127.919294 -265.461957) (xy 127.87522 -265.436511)
			(xy 127.835798 -265.404324) (xy 127.80205 -265.36623) (xy 127.774849 -265.323216) (xy 127.754901 -265.276396)
			(xy 127.742722 -265.226982) (xy 127.738627 -265.176254) (xy 127.420116 -265.176254) (xy 127.419621 -265.200861)
			(xy 127.411726 -265.249438) (xy 127.396142 -265.296119) (xy 127.373271 -265.339696) (xy 127.343706 -265.37904)
			(xy 127.308213 -265.413132) (xy 127.26771 -265.441088) (xy 127.223248 -265.462186) (xy 127.175977 -265.475878)
			(xy 127.127122 -265.48181) (xy 127.077947 -265.479829) (xy 127.029728 -265.469985) (xy 126.983712 -265.452533)
			(xy 126.941091 -265.427926) (xy 126.90297 -265.396801) (xy 126.870335 -265.359964) (xy 126.844032 -265.318368)
			(xy 126.824741 -265.273092) (xy 126.812964 -265.225308) (xy 126.809004 -265.176254) (xy 125.540008 -265.176254)
			(xy 125.539513 -265.200861) (xy 125.531618 -265.249438) (xy 125.516034 -265.296119) (xy 125.493163 -265.339696)
			(xy 125.463598 -265.37904) (xy 125.428105 -265.413132) (xy 125.387602 -265.441088) (xy 125.34314 -265.462186)
			(xy 125.295869 -265.475878) (xy 125.247014 -265.48181) (xy 125.197839 -265.479829) (xy 125.14962 -265.469985)
			(xy 125.103604 -265.452533) (xy 125.060983 -265.427926) (xy 125.022862 -265.396801) (xy 124.990227 -265.359964)
			(xy 124.963924 -265.318368) (xy 124.944633 -265.273092) (xy 124.932856 -265.225308) (xy 124.928896 -265.176254)
			(xy 123.660154 -265.176254) (xy 123.659659 -265.200861) (xy 123.651764 -265.249438) (xy 123.63618 -265.296119)
			(xy 123.613309 -265.339696) (xy 123.583744 -265.37904) (xy 123.548251 -265.413132) (xy 123.507748 -265.441088)
			(xy 123.463286 -265.462186) (xy 123.416015 -265.475878) (xy 123.36716 -265.48181) (xy 123.317985 -265.479829)
			(xy 123.269766 -265.469985) (xy 123.22375 -265.452533) (xy 123.181129 -265.427926) (xy 123.143008 -265.396801)
			(xy 123.110373 -265.359964) (xy 123.08407 -265.318368) (xy 123.064779 -265.273092) (xy 123.053002 -265.225308)
			(xy 123.049042 -265.176254) (xy 121.780046 -265.176254) (xy 121.779551 -265.200861) (xy 121.771656 -265.249438)
			(xy 121.756072 -265.296119) (xy 121.733201 -265.339696) (xy 121.703636 -265.37904) (xy 121.668143 -265.413132)
			(xy 121.62764 -265.441088) (xy 121.583178 -265.462186) (xy 121.535907 -265.475878) (xy 121.487052 -265.48181)
			(xy 121.437877 -265.479829) (xy 121.389658 -265.469985) (xy 121.343642 -265.452533) (xy 121.301021 -265.427926)
			(xy 121.2629 -265.396801) (xy 121.230265 -265.359964) (xy 121.203962 -265.318368) (xy 121.184671 -265.273092)
			(xy 121.172894 -265.225308) (xy 121.168934 -265.176254) (xy 111.719063 -265.176254) (xy 111.71882 -265.176386)
			(xy 111.669267 -265.194184) (xy 111.617577 -265.204208) (xy 111.564963 -265.206225) (xy 111.512658 -265.200187)
			(xy 111.461887 -265.186235) (xy 111.413842 -265.164696) (xy 111.369647 -265.136076) (xy 111.330339 -265.101045)
			(xy 111.296839 -265.060424) (xy 111.269933 -265.015165) (xy 111.25025 -264.96633) (xy 111.238253 -264.915062)
			(xy 111.234223 -264.862564) (xy 100.480773 -264.862564) (xy 100.481922 -264.865613) (xy 100.494036 -264.879461)
			(xy 100.501958 -264.884154) (xy 100.54844 -264.908792) (xy 100.57892 -264.925048) (xy 100.587207 -264.929082)
			(xy 100.60546 -264.93153) (xy 100.623392 -264.927334) (xy 100.631244 -264.922508) (xy 100.631498 -264.922508)
			(xy 100.650428 -264.910337) (xy 100.691103 -264.891083) (xy 100.73416 -264.877995) (xy 100.778669 -264.871356)
			(xy 100.80117 -264.870946) (xy 100.809552 -264.870946) (xy 100.809806 -264.870946) (xy 100.817426 -264.8712)
			(xy 100.81768 -264.8712) (xy 100.843358 -264.873145) (xy 100.893571 -264.884551) (xy 100.941162 -264.904212)
			(xy 100.984784 -264.931571) (xy 101.023203 -264.965856) (xy 101.055332 -265.006095) (xy 101.080262 -265.05115)
			(xy 101.097287 -265.099746) (xy 101.105925 -265.150508) (xy 101.106478 -265.176254) (xy 101.435166 -265.176254)
			(xy 101.439126 -265.1272) (xy 101.450903 -265.079416) (xy 101.470194 -265.03414) (xy 101.496497 -264.992544)
			(xy 101.529132 -264.955707) (xy 101.567253 -264.924582) (xy 101.609874 -264.899975) (xy 101.65589 -264.882523)
			(xy 101.704109 -264.872679) (xy 101.753284 -264.870698) (xy 101.802139 -264.87663) (xy 101.84941 -264.890322)
			(xy 101.893872 -264.91142) (xy 101.934375 -264.939376) (xy 101.969868 -264.973468) (xy 101.999433 -265.012812)
			(xy 102.022304 -265.056389) (xy 102.037888 -265.10307) (xy 102.045783 -265.151647) (xy 102.046278 -265.176254)
			(xy 102.045783 -265.200861) (xy 102.037888 -265.249438) (xy 102.022304 -265.296119) (xy 101.999433 -265.339696)
			(xy 101.969868 -265.37904) (xy 101.934375 -265.413132) (xy 101.893872 -265.441088) (xy 101.84941 -265.462186)
			(xy 101.802139 -265.475878) (xy 101.753284 -265.48181) (xy 101.704109 -265.479829) (xy 101.65589 -265.469985)
			(xy 101.609874 -265.452533) (xy 101.567253 -265.427926) (xy 101.529132 -265.396801) (xy 101.496497 -265.359964)
			(xy 101.470194 -265.318368) (xy 101.450903 -265.273092) (xy 101.439126 -265.225308) (xy 101.435166 -265.176254)
			(xy 101.106478 -265.176254) (xy 101.106035 -265.200249) (xy 101.098534 -265.247648) (xy 101.083709 -265.29329)
			(xy 101.061926 -265.33605) (xy 101.03372 -265.374876) (xy 100.999788 -265.40881) (xy 100.960964 -265.437017)
			(xy 100.918205 -265.458803) (xy 100.872564 -265.47363) (xy 100.825165 -265.481134) (xy 100.80117 -265.481562)
			(xy 100.800916 -265.481562) (xy 100.778416 -265.481137) (xy 100.733908 -265.474496) (xy 100.690851 -265.461413)
			(xy 100.650172 -265.442171) (xy 100.631244 -265.43) (xy 100.619306 -265.422126) (xy 100.59162 -265.420602)
			(xy 100.54844 -265.443716) (xy 100.501958 -265.468354) (xy 100.49401 -265.473017) (xy 100.481863 -265.486853)
			(xy 100.475426 -265.504103) (xy 100.475034 -265.513312) (xy 100.475034 -265.681714) (xy 100.478082 -265.693652)
			(xy 100.480876 -265.69924) (xy 100.490782 -265.71829) (xy 100.49891 -265.72972) (xy 100.501958 -265.733022)
			(xy 100.506784 -265.736578) (xy 100.507292 -265.737086) (xy 100.526875 -265.7515) (xy 100.561633 -265.7855)
			(xy 100.590557 -265.824584) (xy 100.612914 -265.867762) (xy 100.628137 -265.91394) (xy 100.635842 -265.961949)
			(xy 100.636324 -265.98626) (xy 101.90532 -265.98626) (xy 101.90928 -265.937206) (xy 101.921057 -265.889422)
			(xy 101.940348 -265.844146) (xy 101.966651 -265.80255) (xy 101.999286 -265.765713) (xy 102.037407 -265.734588)
			(xy 102.080028 -265.709981) (xy 102.126044 -265.692529) (xy 102.174263 -265.682685) (xy 102.223438 -265.680704)
			(xy 102.272293 -265.686636) (xy 102.319564 -265.700328) (xy 102.364026 -265.721426) (xy 102.404529 -265.749382)
			(xy 102.440022 -265.783474) (xy 102.469587 -265.822818) (xy 102.492458 -265.866395) (xy 102.508042 -265.913076)
			(xy 102.515937 -265.961653) (xy 102.516432 -265.98626) (xy 103.785174 -265.98626) (xy 103.789134 -265.937206)
			(xy 103.800911 -265.889422) (xy 103.820202 -265.844146) (xy 103.846505 -265.80255) (xy 103.87914 -265.765713)
			(xy 103.917261 -265.734588) (xy 103.959882 -265.709981) (xy 104.005898 -265.692529) (xy 104.054117 -265.682685)
			(xy 104.103292 -265.680704) (xy 104.152147 -265.686636) (xy 104.199418 -265.700328) (xy 104.24388 -265.721426)
			(xy 104.284383 -265.749382) (xy 104.319876 -265.783474) (xy 104.349441 -265.822818) (xy 104.372312 -265.866395)
			(xy 104.387896 -265.913076) (xy 104.395791 -265.961653) (xy 104.396286 -265.98626) (xy 105.665282 -265.98626)
			(xy 105.669242 -265.937206) (xy 105.681019 -265.889422) (xy 105.70031 -265.844146) (xy 105.726613 -265.80255)
			(xy 105.759248 -265.765713) (xy 105.797369 -265.734588) (xy 105.83999 -265.709981) (xy 105.886006 -265.692529)
			(xy 105.934225 -265.682685) (xy 105.9834 -265.680704) (xy 106.032255 -265.686636) (xy 106.079526 -265.700328)
			(xy 106.123988 -265.721426) (xy 106.164491 -265.749382) (xy 106.199984 -265.783474) (xy 106.229549 -265.822818)
			(xy 106.25242 -265.866395) (xy 106.268004 -265.913076) (xy 106.275899 -265.961653) (xy 106.276394 -265.98626)
			(xy 107.545136 -265.98626) (xy 107.549096 -265.937206) (xy 107.560873 -265.889422) (xy 107.580164 -265.844146)
			(xy 107.606467 -265.80255) (xy 107.639102 -265.765713) (xy 107.677223 -265.734588) (xy 107.719844 -265.709981)
			(xy 107.76586 -265.692529) (xy 107.814079 -265.682685) (xy 107.863254 -265.680704) (xy 107.912109 -265.686636)
			(xy 107.95938 -265.700328) (xy 108.003842 -265.721426) (xy 108.044345 -265.749382) (xy 108.079838 -265.783474)
			(xy 108.109403 -265.822818) (xy 108.132274 -265.866395) (xy 108.147858 -265.913076) (xy 108.155753 -265.961653)
			(xy 108.156248 -265.98626) (xy 109.425244 -265.98626) (xy 109.429204 -265.937206) (xy 109.440981 -265.889422)
			(xy 109.460272 -265.844146) (xy 109.486575 -265.80255) (xy 109.51921 -265.765713) (xy 109.557331 -265.734588)
			(xy 109.599952 -265.709981) (xy 109.645968 -265.692529) (xy 109.694187 -265.682685) (xy 109.743362 -265.680704)
			(xy 109.792217 -265.686636) (xy 109.839488 -265.700328) (xy 109.88395 -265.721426) (xy 109.924453 -265.749382)
			(xy 109.959946 -265.783474) (xy 109.989511 -265.822818) (xy 110.012382 -265.866395) (xy 110.027966 -265.913076)
			(xy 110.035861 -265.961653) (xy 110.036356 -265.98626) (xy 113.178856 -265.98626) (xy 113.182816 -265.937206)
			(xy 113.194593 -265.889422) (xy 113.213884 -265.844146) (xy 113.240187 -265.80255) (xy 113.272822 -265.765713)
			(xy 113.310943 -265.734588) (xy 113.353564 -265.709981) (xy 113.39958 -265.692529) (xy 113.447799 -265.682685)
			(xy 113.496974 -265.680704) (xy 113.545829 -265.686636) (xy 113.5931 -265.700328) (xy 113.637562 -265.721426)
			(xy 113.678065 -265.749382) (xy 113.713558 -265.783474) (xy 113.743123 -265.822818) (xy 113.765994 -265.866395)
			(xy 113.781578 -265.913076) (xy 113.789473 -265.961653) (xy 113.789968 -265.98626) (xy 115.058964 -265.98626)
			(xy 115.062924 -265.937206) (xy 115.074701 -265.889422) (xy 115.093992 -265.844146) (xy 115.120295 -265.80255)
			(xy 115.15293 -265.765713) (xy 115.191051 -265.734588) (xy 115.233672 -265.709981) (xy 115.279688 -265.692529)
			(xy 115.327907 -265.682685) (xy 115.377082 -265.680704) (xy 115.425937 -265.686636) (xy 115.473208 -265.700328)
			(xy 115.51767 -265.721426) (xy 115.558173 -265.749382) (xy 115.593666 -265.783474) (xy 115.623231 -265.822818)
			(xy 115.646102 -265.866395) (xy 115.661686 -265.913076) (xy 115.669581 -265.961653) (xy 115.670076 -265.98626)
			(xy 116.938818 -265.98626) (xy 116.942778 -265.937206) (xy 116.954555 -265.889422) (xy 116.973846 -265.844146)
			(xy 117.000149 -265.80255) (xy 117.032784 -265.765713) (xy 117.070905 -265.734588) (xy 117.113526 -265.709981)
			(xy 117.159542 -265.692529) (xy 117.207761 -265.682685) (xy 117.256936 -265.680704) (xy 117.305791 -265.686636)
			(xy 117.353062 -265.700328) (xy 117.397524 -265.721426) (xy 117.438027 -265.749382) (xy 117.47352 -265.783474)
			(xy 117.503085 -265.822818) (xy 117.525956 -265.866395) (xy 117.54154 -265.913076) (xy 117.549435 -265.961653)
			(xy 117.54993 -265.98626) (xy 118.818926 -265.98626) (xy 118.822886 -265.937206) (xy 118.834663 -265.889422)
			(xy 118.853954 -265.844146) (xy 118.880257 -265.80255) (xy 118.912892 -265.765713) (xy 118.951013 -265.734588)
			(xy 118.993634 -265.709981) (xy 119.03965 -265.692529) (xy 119.087869 -265.682685) (xy 119.137044 -265.680704)
			(xy 119.185899 -265.686636) (xy 119.23317 -265.700328) (xy 119.277632 -265.721426) (xy 119.318135 -265.749382)
			(xy 119.353628 -265.783474) (xy 119.383193 -265.822818) (xy 119.406064 -265.866395) (xy 119.421648 -265.913076)
			(xy 119.429543 -265.961653) (xy 119.430038 -265.98626) (xy 120.699034 -265.98626) (xy 120.702994 -265.937206)
			(xy 120.714771 -265.889422) (xy 120.734062 -265.844146) (xy 120.760365 -265.80255) (xy 120.793 -265.765713)
			(xy 120.831121 -265.734588) (xy 120.873742 -265.709981) (xy 120.919758 -265.692529) (xy 120.967977 -265.682685)
			(xy 121.017152 -265.680704) (xy 121.066007 -265.686636) (xy 121.113278 -265.700328) (xy 121.15774 -265.721426)
			(xy 121.198243 -265.749382) (xy 121.233736 -265.783474) (xy 121.263301 -265.822818) (xy 121.286172 -265.866395)
			(xy 121.301756 -265.913076) (xy 121.309651 -265.961653) (xy 121.310146 -265.98626) (xy 122.578888 -265.98626)
			(xy 122.582848 -265.937206) (xy 122.594625 -265.889422) (xy 122.613916 -265.844146) (xy 122.640219 -265.80255)
			(xy 122.672854 -265.765713) (xy 122.710975 -265.734588) (xy 122.753596 -265.709981) (xy 122.799612 -265.692529)
			(xy 122.847831 -265.682685) (xy 122.897006 -265.680704) (xy 122.945861 -265.686636) (xy 122.993132 -265.700328)
			(xy 123.037594 -265.721426) (xy 123.078097 -265.749382) (xy 123.11359 -265.783474) (xy 123.143155 -265.822818)
			(xy 123.166026 -265.866395) (xy 123.18161 -265.913076) (xy 123.189505 -265.961653) (xy 123.19 -265.98626)
			(xy 124.458996 -265.98626) (xy 124.462956 -265.937206) (xy 124.474733 -265.889422) (xy 124.494024 -265.844146)
			(xy 124.520327 -265.80255) (xy 124.552962 -265.765713) (xy 124.591083 -265.734588) (xy 124.633704 -265.709981)
			(xy 124.67972 -265.692529) (xy 124.727939 -265.682685) (xy 124.777114 -265.680704) (xy 124.825969 -265.686636)
			(xy 124.87324 -265.700328) (xy 124.917702 -265.721426) (xy 124.958205 -265.749382) (xy 124.993698 -265.783474)
			(xy 125.023263 -265.822818) (xy 125.046134 -265.866395) (xy 125.061718 -265.913076) (xy 125.069613 -265.961653)
			(xy 125.070108 -265.98626) (xy 126.33885 -265.98626) (xy 126.34281 -265.937206) (xy 126.354587 -265.889422)
			(xy 126.373878 -265.844146) (xy 126.400181 -265.80255) (xy 126.432816 -265.765713) (xy 126.470937 -265.734588)
			(xy 126.513558 -265.709981) (xy 126.559574 -265.692529) (xy 126.607793 -265.682685) (xy 126.656968 -265.680704)
			(xy 126.705823 -265.686636) (xy 126.753094 -265.700328) (xy 126.797556 -265.721426) (xy 126.838059 -265.749382)
			(xy 126.873552 -265.783474) (xy 126.903117 -265.822818) (xy 126.925988 -265.866395) (xy 126.941572 -265.913076)
			(xy 126.949467 -265.961653) (xy 126.949962 -265.98626) (xy 128.208527 -265.98626) (xy 128.212622 -265.935532)
			(xy 128.224801 -265.886118) (xy 128.244749 -265.839298) (xy 128.27195 -265.796284) (xy 128.305698 -265.75819)
			(xy 128.34512 -265.726003) (xy 128.389194 -265.700557) (xy 128.43678 -265.68251) (xy 128.486644 -265.67233)
			(xy 128.537496 -265.670281) (xy 128.588017 -265.676415) (xy 128.636901 -265.690575) (xy 128.68288 -265.712392)
			(xy 128.724764 -265.741302) (xy 128.761468 -265.776557) (xy 128.792041 -265.817243) (xy 128.815692 -265.862306)
			(xy 128.831808 -265.91058) (xy 128.839972 -265.960814) (xy 128.840484 -265.98626) (xy 129.159012 -265.98626)
			(xy 129.162972 -265.937206) (xy 129.174749 -265.889422) (xy 129.19404 -265.844146) (xy 129.220343 -265.80255)
			(xy 129.252978 -265.765713) (xy 129.291099 -265.734588) (xy 129.33372 -265.709981) (xy 129.379736 -265.692529)
			(xy 129.427955 -265.682685) (xy 129.47713 -265.680704) (xy 129.525985 -265.686636) (xy 129.573256 -265.700328)
			(xy 129.617718 -265.721426) (xy 129.658221 -265.749382) (xy 129.693714 -265.783474) (xy 129.723279 -265.822818)
			(xy 129.74615 -265.866395) (xy 129.761734 -265.913076) (xy 129.769629 -265.961653) (xy 129.770124 -265.98626)
			(xy 131.028435 -265.98626) (xy 131.03253 -265.935532) (xy 131.044709 -265.886118) (xy 131.064657 -265.839298)
			(xy 131.091858 -265.796284) (xy 131.125606 -265.75819) (xy 131.165028 -265.726003) (xy 131.209102 -265.700557)
			(xy 131.256688 -265.68251) (xy 131.306552 -265.67233) (xy 131.357404 -265.670281) (xy 131.407925 -265.676415)
			(xy 131.456809 -265.690575) (xy 131.502788 -265.712392) (xy 131.544672 -265.741302) (xy 131.581376 -265.776557)
			(xy 131.611949 -265.817243) (xy 131.6356 -265.862306) (xy 131.651716 -265.91058) (xy 131.65988 -265.960814)
			(xy 131.660392 -265.98626) (xy 131.97892 -265.98626) (xy 131.98288 -265.937206) (xy 131.994657 -265.889422)
			(xy 132.013948 -265.844146) (xy 132.040251 -265.80255) (xy 132.072886 -265.765713) (xy 132.111007 -265.734588)
			(xy 132.153628 -265.709981) (xy 132.199644 -265.692529) (xy 132.247863 -265.682685) (xy 132.297038 -265.680704)
			(xy 132.345893 -265.686636) (xy 132.393164 -265.700328) (xy 132.437626 -265.721426) (xy 132.478129 -265.749382)
			(xy 132.513622 -265.783474) (xy 132.543187 -265.822818) (xy 132.566058 -265.866395) (xy 132.581642 -265.913076)
			(xy 132.589537 -265.961653) (xy 132.590032 -265.98626) (xy 132.918974 -265.98626) (xy 132.922934 -265.937206)
			(xy 132.934711 -265.889422) (xy 132.954002 -265.844146) (xy 132.980305 -265.80255) (xy 133.01294 -265.765713)
			(xy 133.051061 -265.734588) (xy 133.093682 -265.709981) (xy 133.139698 -265.692529) (xy 133.187917 -265.682685)
			(xy 133.237092 -265.680704) (xy 133.285947 -265.686636) (xy 133.333218 -265.700328) (xy 133.37768 -265.721426)
			(xy 133.418183 -265.749382) (xy 133.453676 -265.783474) (xy 133.483241 -265.822818) (xy 133.506112 -265.866395)
			(xy 133.521696 -265.913076) (xy 133.529591 -265.961653) (xy 133.530086 -265.98626) (xy 133.859028 -265.98626)
			(xy 133.862988 -265.937206) (xy 133.874765 -265.889422) (xy 133.894056 -265.844146) (xy 133.920359 -265.80255)
			(xy 133.952994 -265.765713) (xy 133.991115 -265.734588) (xy 134.033736 -265.709981) (xy 134.079752 -265.692529)
			(xy 134.127971 -265.682685) (xy 134.177146 -265.680704) (xy 134.226001 -265.686636) (xy 134.273272 -265.700328)
			(xy 134.317734 -265.721426) (xy 134.358237 -265.749382) (xy 134.39373 -265.783474) (xy 134.423295 -265.822818)
			(xy 134.446166 -265.866395) (xy 134.46175 -265.913076) (xy 134.469645 -265.961653) (xy 134.47014 -265.98626)
			(xy 134.798828 -265.98626) (xy 134.802788 -265.937206) (xy 134.814565 -265.889422) (xy 134.833856 -265.844146)
			(xy 134.860159 -265.80255) (xy 134.892794 -265.765713) (xy 134.930915 -265.734588) (xy 134.973536 -265.709981)
			(xy 135.019552 -265.692529) (xy 135.067771 -265.682685) (xy 135.116946 -265.680704) (xy 135.165801 -265.686636)
			(xy 135.213072 -265.700328) (xy 135.257534 -265.721426) (xy 135.298037 -265.749382) (xy 135.33353 -265.783474)
			(xy 135.363095 -265.822818) (xy 135.385966 -265.866395) (xy 135.40155 -265.913076) (xy 135.409445 -265.961653)
			(xy 135.40994 -265.98626) (xy 135.738882 -265.98626) (xy 135.742842 -265.937206) (xy 135.754619 -265.889422)
			(xy 135.77391 -265.844146) (xy 135.800213 -265.80255) (xy 135.832848 -265.765713) (xy 135.870969 -265.734588)
			(xy 135.91359 -265.709981) (xy 135.959606 -265.692529) (xy 136.007825 -265.682685) (xy 136.057 -265.680704)
			(xy 136.105855 -265.686636) (xy 136.153126 -265.700328) (xy 136.197588 -265.721426) (xy 136.238091 -265.749382)
			(xy 136.273584 -265.783474) (xy 136.303149 -265.822818) (xy 136.32602 -265.866395) (xy 136.341604 -265.913076)
			(xy 136.349499 -265.961653) (xy 136.349994 -265.98626) (xy 136.349499 -266.010867) (xy 136.341604 -266.059444)
			(xy 136.32602 -266.106125) (xy 136.303149 -266.149702) (xy 136.273584 -266.189046) (xy 136.238091 -266.223138)
			(xy 136.197588 -266.251094) (xy 136.153126 -266.272192) (xy 136.105855 -266.285884) (xy 136.057 -266.291816)
			(xy 136.007825 -266.289835) (xy 135.959606 -266.279991) (xy 135.91359 -266.262539) (xy 135.870969 -266.237932)
			(xy 135.832848 -266.206807) (xy 135.800213 -266.16997) (xy 135.77391 -266.128374) (xy 135.754619 -266.083098)
			(xy 135.742842 -266.035314) (xy 135.738882 -265.98626) (xy 135.40994 -265.98626) (xy 135.409445 -266.010867)
			(xy 135.40155 -266.059444) (xy 135.385966 -266.106125) (xy 135.363095 -266.149702) (xy 135.33353 -266.189046)
			(xy 135.298037 -266.223138) (xy 135.257534 -266.251094) (xy 135.213072 -266.272192) (xy 135.165801 -266.285884)
			(xy 135.116946 -266.291816) (xy 135.067771 -266.289835) (xy 135.019552 -266.279991) (xy 134.973536 -266.262539)
			(xy 134.930915 -266.237932) (xy 134.892794 -266.206807) (xy 134.860159 -266.16997) (xy 134.833856 -266.128374)
			(xy 134.814565 -266.083098) (xy 134.802788 -266.035314) (xy 134.798828 -265.98626) (xy 134.47014 -265.98626)
			(xy 134.469645 -266.010867) (xy 134.46175 -266.059444) (xy 134.446166 -266.106125) (xy 134.423295 -266.149702)
			(xy 134.39373 -266.189046) (xy 134.358237 -266.223138) (xy 134.317734 -266.251094) (xy 134.273272 -266.272192)
			(xy 134.226001 -266.285884) (xy 134.177146 -266.291816) (xy 134.127971 -266.289835) (xy 134.079752 -266.279991)
			(xy 134.033736 -266.262539) (xy 133.991115 -266.237932) (xy 133.952994 -266.206807) (xy 133.920359 -266.16997)
			(xy 133.894056 -266.128374) (xy 133.874765 -266.083098) (xy 133.862988 -266.035314) (xy 133.859028 -265.98626)
			(xy 133.530086 -265.98626) (xy 133.529591 -266.010867) (xy 133.521696 -266.059444) (xy 133.506112 -266.106125)
			(xy 133.483241 -266.149702) (xy 133.453676 -266.189046) (xy 133.418183 -266.223138) (xy 133.37768 -266.251094)
			(xy 133.333218 -266.272192) (xy 133.285947 -266.285884) (xy 133.237092 -266.291816) (xy 133.187917 -266.289835)
			(xy 133.139698 -266.279991) (xy 133.093682 -266.262539) (xy 133.051061 -266.237932) (xy 133.01294 -266.206807)
			(xy 132.980305 -266.16997) (xy 132.954002 -266.128374) (xy 132.934711 -266.083098) (xy 132.922934 -266.035314)
			(xy 132.918974 -265.98626) (xy 132.590032 -265.98626) (xy 132.589537 -266.010867) (xy 132.581642 -266.059444)
			(xy 132.566058 -266.106125) (xy 132.543187 -266.149702) (xy 132.513622 -266.189046) (xy 132.478129 -266.223138)
			(xy 132.437626 -266.251094) (xy 132.393164 -266.272192) (xy 132.345893 -266.285884) (xy 132.297038 -266.291816)
			(xy 132.247863 -266.289835) (xy 132.199644 -266.279991) (xy 132.153628 -266.262539) (xy 132.111007 -266.237932)
			(xy 132.072886 -266.206807) (xy 132.040251 -266.16997) (xy 132.013948 -266.128374) (xy 131.994657 -266.083098)
			(xy 131.98288 -266.035314) (xy 131.97892 -265.98626) (xy 131.660392 -265.98626) (xy 131.65988 -266.011706)
			(xy 131.651716 -266.06194) (xy 131.6356 -266.110214) (xy 131.611949 -266.155277) (xy 131.581376 -266.195963)
			(xy 131.544672 -266.231218) (xy 131.502788 -266.260128) (xy 131.456809 -266.281945) (xy 131.407925 -266.296105)
			(xy 131.357404 -266.302239) (xy 131.306552 -266.30019) (xy 131.256688 -266.29001) (xy 131.209102 -266.271963)
			(xy 131.165028 -266.246517) (xy 131.125606 -266.21433) (xy 131.091858 -266.176236) (xy 131.064657 -266.133222)
			(xy 131.044709 -266.086402) (xy 131.03253 -266.036988) (xy 131.028435 -265.98626) (xy 129.770124 -265.98626)
			(xy 129.769629 -266.010867) (xy 129.761734 -266.059444) (xy 129.74615 -266.106125) (xy 129.723279 -266.149702)
			(xy 129.693714 -266.189046) (xy 129.658221 -266.223138) (xy 129.617718 -266.251094) (xy 129.573256 -266.272192)
			(xy 129.525985 -266.285884) (xy 129.47713 -266.291816) (xy 129.427955 -266.289835) (xy 129.379736 -266.279991)
			(xy 129.33372 -266.262539) (xy 129.291099 -266.237932) (xy 129.252978 -266.206807) (xy 129.220343 -266.16997)
			(xy 129.19404 -266.128374) (xy 129.174749 -266.083098) (xy 129.162972 -266.035314) (xy 129.159012 -265.98626)
			(xy 128.840484 -265.98626) (xy 128.839972 -266.011706) (xy 128.831808 -266.06194) (xy 128.815692 -266.110214)
			(xy 128.792041 -266.155277) (xy 128.761468 -266.195963) (xy 128.724764 -266.231218) (xy 128.68288 -266.260128)
			(xy 128.636901 -266.281945) (xy 128.588017 -266.296105) (xy 128.537496 -266.302239) (xy 128.486644 -266.30019)
			(xy 128.43678 -266.29001) (xy 128.389194 -266.271963) (xy 128.34512 -266.246517) (xy 128.305698 -266.21433)
			(xy 128.27195 -266.176236) (xy 128.244749 -266.133222) (xy 128.224801 -266.086402) (xy 128.212622 -266.036988)
			(xy 128.208527 -265.98626) (xy 126.949962 -265.98626) (xy 126.949467 -266.010867) (xy 126.941572 -266.059444)
			(xy 126.925988 -266.106125) (xy 126.903117 -266.149702) (xy 126.873552 -266.189046) (xy 126.838059 -266.223138)
			(xy 126.797556 -266.251094) (xy 126.753094 -266.272192) (xy 126.705823 -266.285884) (xy 126.656968 -266.291816)
			(xy 126.607793 -266.289835) (xy 126.559574 -266.279991) (xy 126.513558 -266.262539) (xy 126.470937 -266.237932)
			(xy 126.432816 -266.206807) (xy 126.400181 -266.16997) (xy 126.373878 -266.128374) (xy 126.354587 -266.083098)
			(xy 126.34281 -266.035314) (xy 126.33885 -265.98626) (xy 125.070108 -265.98626) (xy 125.069613 -266.010867)
			(xy 125.061718 -266.059444) (xy 125.046134 -266.106125) (xy 125.023263 -266.149702) (xy 124.993698 -266.189046)
			(xy 124.958205 -266.223138) (xy 124.917702 -266.251094) (xy 124.87324 -266.272192) (xy 124.825969 -266.285884)
			(xy 124.777114 -266.291816) (xy 124.727939 -266.289835) (xy 124.67972 -266.279991) (xy 124.633704 -266.262539)
			(xy 124.591083 -266.237932) (xy 124.552962 -266.206807) (xy 124.520327 -266.16997) (xy 124.494024 -266.128374)
			(xy 124.474733 -266.083098) (xy 124.462956 -266.035314) (xy 124.458996 -265.98626) (xy 123.19 -265.98626)
			(xy 123.189505 -266.010867) (xy 123.18161 -266.059444) (xy 123.166026 -266.106125) (xy 123.143155 -266.149702)
			(xy 123.11359 -266.189046) (xy 123.078097 -266.223138) (xy 123.037594 -266.251094) (xy 122.993132 -266.272192)
			(xy 122.945861 -266.285884) (xy 122.897006 -266.291816) (xy 122.847831 -266.289835) (xy 122.799612 -266.279991)
			(xy 122.753596 -266.262539) (xy 122.710975 -266.237932) (xy 122.672854 -266.206807) (xy 122.640219 -266.16997)
			(xy 122.613916 -266.128374) (xy 122.594625 -266.083098) (xy 122.582848 -266.035314) (xy 122.578888 -265.98626)
			(xy 121.310146 -265.98626) (xy 121.309651 -266.010867) (xy 121.301756 -266.059444) (xy 121.286172 -266.106125)
			(xy 121.263301 -266.149702) (xy 121.233736 -266.189046) (xy 121.198243 -266.223138) (xy 121.15774 -266.251094)
			(xy 121.113278 -266.272192) (xy 121.066007 -266.285884) (xy 121.017152 -266.291816) (xy 120.967977 -266.289835)
			(xy 120.919758 -266.279991) (xy 120.873742 -266.262539) (xy 120.831121 -266.237932) (xy 120.793 -266.206807)
			(xy 120.760365 -266.16997) (xy 120.734062 -266.128374) (xy 120.714771 -266.083098) (xy 120.702994 -266.035314)
			(xy 120.699034 -265.98626) (xy 119.430038 -265.98626) (xy 119.429543 -266.010867) (xy 119.421648 -266.059444)
			(xy 119.406064 -266.106125) (xy 119.383193 -266.149702) (xy 119.353628 -266.189046) (xy 119.318135 -266.223138)
			(xy 119.277632 -266.251094) (xy 119.23317 -266.272192) (xy 119.185899 -266.285884) (xy 119.137044 -266.291816)
			(xy 119.087869 -266.289835) (xy 119.03965 -266.279991) (xy 118.993634 -266.262539) (xy 118.951013 -266.237932)
			(xy 118.912892 -266.206807) (xy 118.880257 -266.16997) (xy 118.853954 -266.128374) (xy 118.834663 -266.083098)
			(xy 118.822886 -266.035314) (xy 118.818926 -265.98626) (xy 117.54993 -265.98626) (xy 117.549435 -266.010867)
			(xy 117.54154 -266.059444) (xy 117.525956 -266.106125) (xy 117.503085 -266.149702) (xy 117.47352 -266.189046)
			(xy 117.438027 -266.223138) (xy 117.397524 -266.251094) (xy 117.353062 -266.272192) (xy 117.305791 -266.285884)
			(xy 117.256936 -266.291816) (xy 117.207761 -266.289835) (xy 117.159542 -266.279991) (xy 117.113526 -266.262539)
			(xy 117.070905 -266.237932) (xy 117.032784 -266.206807) (xy 117.000149 -266.16997) (xy 116.973846 -266.128374)
			(xy 116.954555 -266.083098) (xy 116.942778 -266.035314) (xy 116.938818 -265.98626) (xy 115.670076 -265.98626)
			(xy 115.669581 -266.010867) (xy 115.661686 -266.059444) (xy 115.646102 -266.106125) (xy 115.623231 -266.149702)
			(xy 115.593666 -266.189046) (xy 115.558173 -266.223138) (xy 115.51767 -266.251094) (xy 115.473208 -266.272192)
			(xy 115.425937 -266.285884) (xy 115.377082 -266.291816) (xy 115.327907 -266.289835) (xy 115.279688 -266.279991)
			(xy 115.233672 -266.262539) (xy 115.191051 -266.237932) (xy 115.15293 -266.206807) (xy 115.120295 -266.16997)
			(xy 115.093992 -266.128374) (xy 115.074701 -266.083098) (xy 115.062924 -266.035314) (xy 115.058964 -265.98626)
			(xy 113.789968 -265.98626) (xy 113.789473 -266.010867) (xy 113.781578 -266.059444) (xy 113.765994 -266.106125)
			(xy 113.743123 -266.149702) (xy 113.713558 -266.189046) (xy 113.678065 -266.223138) (xy 113.637562 -266.251094)
			(xy 113.5931 -266.272192) (xy 113.545829 -266.285884) (xy 113.496974 -266.291816) (xy 113.447799 -266.289835)
			(xy 113.39958 -266.279991) (xy 113.353564 -266.262539) (xy 113.310943 -266.237932) (xy 113.272822 -266.206807)
			(xy 113.240187 -266.16997) (xy 113.213884 -266.128374) (xy 113.194593 -266.083098) (xy 113.182816 -266.035314)
			(xy 113.178856 -265.98626) (xy 110.036356 -265.98626) (xy 110.035861 -266.010867) (xy 110.027966 -266.059444)
			(xy 110.012382 -266.106125) (xy 109.989511 -266.149702) (xy 109.959946 -266.189046) (xy 109.924453 -266.223138)
			(xy 109.88395 -266.251094) (xy 109.839488 -266.272192) (xy 109.792217 -266.285884) (xy 109.743362 -266.291816)
			(xy 109.694187 -266.289835) (xy 109.645968 -266.279991) (xy 109.599952 -266.262539) (xy 109.557331 -266.237932)
			(xy 109.51921 -266.206807) (xy 109.486575 -266.16997) (xy 109.460272 -266.128374) (xy 109.440981 -266.083098)
			(xy 109.429204 -266.035314) (xy 109.425244 -265.98626) (xy 108.156248 -265.98626) (xy 108.155753 -266.010867)
			(xy 108.147858 -266.059444) (xy 108.132274 -266.106125) (xy 108.109403 -266.149702) (xy 108.079838 -266.189046)
			(xy 108.044345 -266.223138) (xy 108.003842 -266.251094) (xy 107.95938 -266.272192) (xy 107.912109 -266.285884)
			(xy 107.863254 -266.291816) (xy 107.814079 -266.289835) (xy 107.76586 -266.279991) (xy 107.719844 -266.262539)
			(xy 107.677223 -266.237932) (xy 107.639102 -266.206807) (xy 107.606467 -266.16997) (xy 107.580164 -266.128374)
			(xy 107.560873 -266.083098) (xy 107.549096 -266.035314) (xy 107.545136 -265.98626) (xy 106.276394 -265.98626)
			(xy 106.275899 -266.010867) (xy 106.268004 -266.059444) (xy 106.25242 -266.106125) (xy 106.229549 -266.149702)
			(xy 106.199984 -266.189046) (xy 106.164491 -266.223138) (xy 106.123988 -266.251094) (xy 106.079526 -266.272192)
			(xy 106.032255 -266.285884) (xy 105.9834 -266.291816) (xy 105.934225 -266.289835) (xy 105.886006 -266.279991)
			(xy 105.83999 -266.262539) (xy 105.797369 -266.237932) (xy 105.759248 -266.206807) (xy 105.726613 -266.16997)
			(xy 105.70031 -266.128374) (xy 105.681019 -266.083098) (xy 105.669242 -266.035314) (xy 105.665282 -265.98626)
			(xy 104.396286 -265.98626) (xy 104.395791 -266.010867) (xy 104.387896 -266.059444) (xy 104.372312 -266.106125)
			(xy 104.349441 -266.149702) (xy 104.319876 -266.189046) (xy 104.284383 -266.223138) (xy 104.24388 -266.251094)
			(xy 104.199418 -266.272192) (xy 104.152147 -266.285884) (xy 104.103292 -266.291816) (xy 104.054117 -266.289835)
			(xy 104.005898 -266.279991) (xy 103.959882 -266.262539) (xy 103.917261 -266.237932) (xy 103.87914 -266.206807)
			(xy 103.846505 -266.16997) (xy 103.820202 -266.128374) (xy 103.800911 -266.083098) (xy 103.789134 -266.035314)
			(xy 103.785174 -265.98626) (xy 102.516432 -265.98626) (xy 102.515937 -266.010867) (xy 102.508042 -266.059444)
			(xy 102.492458 -266.106125) (xy 102.469587 -266.149702) (xy 102.440022 -266.189046) (xy 102.404529 -266.223138)
			(xy 102.364026 -266.251094) (xy 102.319564 -266.272192) (xy 102.272293 -266.285884) (xy 102.223438 -266.291816)
			(xy 102.174263 -266.289835) (xy 102.126044 -266.279991) (xy 102.080028 -266.262539) (xy 102.037407 -266.237932)
			(xy 101.999286 -266.206807) (xy 101.966651 -266.16997) (xy 101.940348 -266.128374) (xy 101.921057 -266.083098)
			(xy 101.90928 -266.035314) (xy 101.90532 -265.98626) (xy 100.636324 -265.98626) (xy 100.635853 -266.010604)
			(xy 100.62813 -266.058674) (xy 100.612874 -266.104909) (xy 100.590472 -266.148136) (xy 100.561492 -266.187259)
			(xy 100.526669 -266.221285) (xy 100.507038 -266.235688) (xy 100.502212 -266.239244) (xy 100.494338 -266.248134)
			(xy 100.48113 -266.273026) (xy 100.478322 -266.278594) (xy 100.475226 -266.29067) (xy 100.475034 -266.296902)
			(xy 100.475034 -266.459208) (xy 100.475437 -266.468406) (xy 100.481926 -266.48562) (xy 100.494042 -266.499465)
			(xy 100.501958 -266.504166) (xy 100.54844 -266.528804) (xy 100.57892 -266.54506) (xy 100.587207 -266.549093)
			(xy 100.60546 -266.551541) (xy 100.623392 -266.547346) (xy 100.631244 -266.54252) (xy 100.631498 -266.54252)
			(xy 100.650427 -266.530349) (xy 100.691103 -266.511094) (xy 100.73416 -266.498006) (xy 100.778669 -266.491366)
			(xy 100.80117 -266.490958) (xy 100.809552 -266.490958) (xy 100.809806 -266.490958) (xy 100.817426 -266.491212)
			(xy 100.81768 -266.491212) (xy 100.842953 -266.493094) (xy 100.892404 -266.504175) (xy 100.939348 -266.523265)
			(xy 100.982497 -266.549842) (xy 101.020668 -266.583176) (xy 101.052814 -266.622352) (xy 101.078053 -266.666297)
			(xy 101.095694 -266.713804) (xy 101.10089 -266.738608) (xy 101.103484 -266.752882) (xy 101.106281 -266.78176)
			(xy 101.106478 -266.796266) (xy 101.106029 -266.819755) (xy 101.098806 -266.866174) (xy 101.08457 -266.910944)
			(xy 101.074474 -266.932156) (xy 101.067108 -266.946888) (xy 101.072442 -266.979146) (xy 101.10851 -267.015214)
			(xy 101.109018 -267.015722) (xy 101.116396 -267.022313) (xy 101.134695 -267.029781) (xy 101.144578 -267.0302)
			(xy 101.35616 -267.0302) (xy 101.367487 -267.029589) (xy 101.387925 -267.019822) (xy 101.39553 -267.011404)
			(xy 101.396546 -267.010134) (xy 101.445568 -266.941808) (xy 101.452059 -266.931466) (xy 101.4555 -266.907329)
			(xy 101.452172 -266.89558) (xy 101.452172 -266.895326) (xy 101.444537 -266.871534) (xy 101.436239 -266.822263)
			(xy 101.435662 -266.797282) (xy 101.435662 -266.792202) (xy 101.436499 -266.767167) (xy 101.445331 -266.717864)
			(xy 101.462092 -266.670663) (xy 101.486331 -266.626831) (xy 101.5174 -266.587543) (xy 101.554464 -266.553852)
			(xy 101.59653 -266.526662) (xy 101.642469 -266.506703) (xy 101.69105 -266.494509) (xy 101.74097 -266.490408)
			(xy 101.79089 -266.494509) (xy 101.839471 -266.506703) (xy 101.88541 -266.526662) (xy 101.927476 -266.553852)
			(xy 101.96454 -266.587543) (xy 101.995609 -266.626831) (xy 102.019848 -266.670663) (xy 102.036609 -266.717864)
			(xy 102.045441 -266.767167) (xy 102.046278 -266.792202) (xy 102.046278 -266.79652) (xy 102.045738 -266.821691)
			(xy 102.037435 -266.871345) (xy 102.029768 -266.895326) (xy 102.029768 -266.89558) (xy 102.026413 -266.907324)
			(xy 102.029876 -266.931463) (xy 102.036372 -266.941808) (xy 102.084378 -267.008864) (xy 102.08641 -267.011404)
			(xy 102.094029 -267.019798) (xy 102.114462 -267.029552) (xy 102.12578 -267.0302) (xy 103.236268 -267.0302)
			(xy 103.247594 -267.029587) (xy 103.26803 -267.019818) (xy 103.275638 -267.011404) (xy 103.276654 -267.010134)
			(xy 103.325676 -266.941808) (xy 103.332166 -266.931466) (xy 103.335607 -266.907329) (xy 103.33228 -266.89558)
			(xy 103.33228 -266.895326) (xy 103.324645 -266.871534) (xy 103.316346 -266.822263) (xy 103.31577 -266.797282)
			(xy 103.31577 -266.792202) (xy 103.316607 -266.767167) (xy 103.325439 -266.717864) (xy 103.3422 -266.670663)
			(xy 103.366439 -266.626831) (xy 103.397508 -266.587543) (xy 103.434572 -266.553852) (xy 103.476638 -266.526662)
			(xy 103.522577 -266.506703) (xy 103.571158 -266.494509) (xy 103.621078 -266.490408) (xy 103.670998 -266.494509)
			(xy 103.719579 -266.506703) (xy 103.765518 -266.526662) (xy 103.807584 -266.553852) (xy 103.844648 -266.587543)
			(xy 103.875717 -266.626831) (xy 103.899956 -266.670663) (xy 103.916717 -266.717864) (xy 103.925549 -266.767167)
			(xy 103.926386 -266.792202) (xy 103.926386 -266.79652) (xy 103.925846 -266.821691) (xy 103.917543 -266.871345)
			(xy 103.909876 -266.895326) (xy 103.909876 -266.89558) (xy 103.906521 -266.907324) (xy 103.909984 -266.931463)
			(xy 103.91648 -266.941808) (xy 103.964486 -267.008864) (xy 103.966518 -267.011404) (xy 103.974138 -267.019797)
			(xy 103.994571 -267.029547) (xy 104.005888 -267.0302) (xy 104.176322 -267.0302) (xy 104.187653 -267.029596)
			(xy 104.208104 -267.019839) (xy 104.215692 -267.011404) (xy 104.216708 -267.010134) (xy 104.26573 -266.941808)
			(xy 104.272225 -266.931467) (xy 104.275669 -266.907328) (xy 104.272334 -266.89558) (xy 104.272334 -266.895326)
			(xy 104.2647 -266.871533) (xy 104.256402 -266.822263) (xy 104.255824 -266.797282) (xy 104.255824 -266.792202)
			(xy 104.256661 -266.767167) (xy 104.265493 -266.717864) (xy 104.282254 -266.670663) (xy 104.306493 -266.626831)
			(xy 104.337562 -266.587543) (xy 104.374626 -266.553852) (xy 104.416692 -266.526662) (xy 104.462631 -266.506703)
			(xy 104.511212 -266.494509) (xy 104.561132 -266.490408) (xy 104.611052 -266.494509) (xy 104.659633 -266.506703)
			(xy 104.705572 -266.526662) (xy 104.747638 -266.553852) (xy 104.784702 -266.587543) (xy 104.815771 -266.626831)
			(xy 104.84001 -266.670663) (xy 104.856771 -266.717864) (xy 104.865603 -266.767167) (xy 104.86644 -266.792202)
			(xy 104.86644 -266.79652) (xy 104.8659 -266.821691) (xy 104.857596 -266.871344) (xy 104.84993 -266.895326)
			(xy 104.84993 -266.89558) (xy 104.846577 -266.907324) (xy 104.850037 -266.931464) (xy 104.856534 -266.941808)
			(xy 104.90454 -267.008864) (xy 104.906572 -267.011404) (xy 104.914195 -267.019788) (xy 104.934628 -267.029517)
			(xy 104.945942 -267.0302) (xy 105.116122 -267.0302) (xy 105.127453 -267.029596) (xy 105.147904 -267.019839)
			(xy 105.155492 -267.011404) (xy 105.156508 -267.010134) (xy 105.20553 -266.941808) (xy 105.212025 -266.931467)
			(xy 105.215469 -266.907328) (xy 105.212134 -266.89558) (xy 105.212134 -266.895326) (xy 105.2045 -266.871533)
			(xy 105.196202 -266.822263) (xy 105.195624 -266.797282) (xy 105.195624 -266.792202) (xy 105.196461 -266.767167)
			(xy 105.205293 -266.717864) (xy 105.222054 -266.670663) (xy 105.246293 -266.626831) (xy 105.277362 -266.587543)
			(xy 105.314426 -266.553852) (xy 105.356492 -266.526662) (xy 105.402431 -266.506703) (xy 105.451012 -266.494509)
			(xy 105.500932 -266.490408) (xy 105.550852 -266.494509) (xy 105.599433 -266.506703) (xy 105.645372 -266.526662)
			(xy 105.687438 -266.553852) (xy 105.724502 -266.587543) (xy 105.755571 -266.626831) (xy 105.77981 -266.670663)
			(xy 105.796571 -266.717864) (xy 105.805403 -266.767167) (xy 105.80624 -266.792202) (xy 105.80624 -266.79652)
			(xy 105.8057 -266.821691) (xy 105.797396 -266.871344) (xy 105.78973 -266.895326) (xy 105.78973 -266.89558)
			(xy 105.786377 -266.907324) (xy 105.789837 -266.931464) (xy 105.796334 -266.941808) (xy 105.84434 -267.008864)
			(xy 105.846372 -267.011404) (xy 105.853995 -267.019788) (xy 105.874428 -267.029517) (xy 105.885742 -267.0302)
			(xy 106.99623 -267.0302) (xy 107.00756 -267.029595) (xy 107.028008 -267.019836) (xy 107.0356 -267.011404)
			(xy 107.036616 -267.010134) (xy 107.085638 -266.941808) (xy 107.092132 -266.931467) (xy 107.095575 -266.907328)
			(xy 107.092242 -266.89558) (xy 107.092242 -266.895326) (xy 107.084608 -266.871533) (xy 107.07631 -266.822263)
			(xy 107.075732 -266.797282) (xy 107.075732 -266.792202) (xy 107.076569 -266.767167) (xy 107.085401 -266.717864)
			(xy 107.102162 -266.670663) (xy 107.126401 -266.626831) (xy 107.15747 -266.587543) (xy 107.194534 -266.553852)
			(xy 107.2366 -266.526662) (xy 107.282539 -266.506703) (xy 107.33112 -266.494509) (xy 107.38104 -266.490408)
			(xy 107.43096 -266.494509) (xy 107.479541 -266.506703) (xy 107.52548 -266.526662) (xy 107.567546 -266.553852)
			(xy 107.60461 -266.587543) (xy 107.635679 -266.626831) (xy 107.659918 -266.670663) (xy 107.676679 -266.717864)
			(xy 107.685511 -266.767167) (xy 107.686348 -266.792202) (xy 107.686348 -266.79652) (xy 107.685808 -266.821691)
			(xy 107.677504 -266.871344) (xy 107.669838 -266.895326) (xy 107.669838 -266.89558) (xy 107.666484 -266.907324)
			(xy 107.669945 -266.931464) (xy 107.676442 -266.941808) (xy 107.724448 -267.008864) (xy 107.72648 -267.011404)
			(xy 107.734097 -267.019803) (xy 107.75453 -267.029569) (xy 107.76585 -267.0302) (xy 107.936284 -267.0302)
			(xy 107.947619 -267.029604) (xy 107.968082 -267.019856) (xy 107.975654 -267.011404) (xy 107.97667 -267.010134)
			(xy 108.025692 -266.941808) (xy 108.03219 -266.931468) (xy 108.035637 -266.907327) (xy 108.032296 -266.89558)
			(xy 108.032296 -266.895326) (xy 108.024661 -266.871534) (xy 108.016361 -266.822263) (xy 108.015786 -266.797282)
			(xy 108.015786 -266.792202) (xy 108.016623 -266.767167) (xy 108.025455 -266.717864) (xy 108.042216 -266.670663)
			(xy 108.066455 -266.626831) (xy 108.097524 -266.587543) (xy 108.134588 -266.553852) (xy 108.176654 -266.526662)
			(xy 108.222593 -266.506703) (xy 108.271174 -266.494509) (xy 108.321094 -266.490408) (xy 108.371014 -266.494509)
			(xy 108.419595 -266.506703) (xy 108.465534 -266.526662) (xy 108.5076 -266.553852) (xy 108.544664 -266.587543)
			(xy 108.575733 -266.626831) (xy 108.599972 -266.670663) (xy 108.616733 -266.717864) (xy 108.625565 -266.767167)
			(xy 108.626402 -266.792202) (xy 108.626402 -266.79652) (xy 108.625862 -266.821691) (xy 108.617557 -266.871344)
			(xy 108.609892 -266.895326) (xy 108.609892 -266.89558) (xy 108.606536 -266.907324) (xy 108.61 -266.931463)
			(xy 108.616496 -266.941808) (xy 108.664502 -267.008864) (xy 108.666534 -267.011404) (xy 108.674154 -267.019795)
			(xy 108.694588 -267.029538) (xy 108.705904 -267.0302) (xy 108.876338 -267.0302) (xy 108.887667 -267.029593)
			(xy 108.908113 -267.019832) (xy 108.915708 -267.011404) (xy 108.916724 -267.010134) (xy 108.965746 -266.941808)
			(xy 108.972239 -266.931466) (xy 108.975682 -266.907328) (xy 108.97235 -266.89558) (xy 108.97235 -266.895326)
			(xy 108.964716 -266.871533) (xy 108.956418 -266.822263) (xy 108.95584 -266.797282) (xy 108.95584 -266.792202)
			(xy 108.956677 -266.767167) (xy 108.965509 -266.717864) (xy 108.98227 -266.670663) (xy 109.006509 -266.626831)
			(xy 109.037578 -266.587543) (xy 109.074642 -266.553852) (xy 109.116708 -266.526662) (xy 109.162647 -266.506703)
			(xy 109.211228 -266.494509) (xy 109.261148 -266.490408) (xy 109.311068 -266.494509) (xy 109.359649 -266.506703)
			(xy 109.405588 -266.526662) (xy 109.447654 -266.553852) (xy 109.484718 -266.587543) (xy 109.515787 -266.626831)
			(xy 109.540026 -266.670663) (xy 109.556787 -266.717864) (xy 109.565619 -266.767167) (xy 109.566456 -266.792202)
			(xy 109.566456 -266.79652) (xy 109.565916 -266.821691) (xy 109.557612 -266.871344) (xy 109.549946 -266.895326)
			(xy 109.549946 -266.89558) (xy 109.546592 -266.907324) (xy 109.550053 -266.931464) (xy 109.55655 -266.941808)
			(xy 109.604556 -267.008864) (xy 109.606588 -267.011404) (xy 109.614206 -267.019802) (xy 109.634638 -267.029564)
			(xy 109.645958 -267.0302) (xy 111.693452 -267.0302) (xy 111.720376 -267.010134) (xy 111.725202 -266.993878)
			(xy 111.733019 -266.969161) (xy 111.755051 -266.922237) (xy 111.783887 -266.879158) (xy 111.818872 -266.840904)
			(xy 111.85921 -266.808344) (xy 111.903984 -266.782219) (xy 111.952178 -266.763122) (xy 112.002694 -266.751487)
			(xy 112.054386 -266.747579) (xy 112.106078 -266.751487) (xy 112.156594 -266.763122) (xy 112.204788 -266.782219)
			(xy 112.249562 -266.808344) (xy 112.2899 -266.840904) (xy 112.324885 -266.879158) (xy 112.353721 -266.922237)
			(xy 112.375753 -266.969161) (xy 112.38357 -266.993878) (xy 112.388396 -267.010134) (xy 112.41532 -267.0302)
			(xy 113.570004 -267.0302) (xy 113.581337 -267.0296) (xy 113.601793 -267.019847) (xy 113.609374 -267.011404)
			(xy 113.61039 -267.010134) (xy 113.659412 -266.941808) (xy 113.665908 -266.931467) (xy 113.669353 -266.907328)
			(xy 113.666016 -266.89558) (xy 113.666016 -266.895326) (xy 113.658383 -266.871533) (xy 113.650085 -266.822263)
			(xy 113.649506 -266.797282) (xy 113.649506 -266.792202) (xy 113.650343 -266.767167) (xy 113.659175 -266.717864)
			(xy 113.675936 -266.670663) (xy 113.700175 -266.626831) (xy 113.731244 -266.587543) (xy 113.768308 -266.553852)
			(xy 113.810374 -266.526662) (xy 113.856313 -266.506703) (xy 113.904894 -266.494509) (xy 113.954814 -266.490408)
			(xy 114.004734 -266.494509) (xy 114.053315 -266.506703) (xy 114.099254 -266.526662) (xy 114.14132 -266.553852)
			(xy 114.178384 -266.587543) (xy 114.209453 -266.626831) (xy 114.233692 -266.670663) (xy 114.250453 -266.717864)
			(xy 114.259285 -266.767167) (xy 114.260122 -266.792202) (xy 114.260122 -266.79652) (xy 114.259582 -266.821691)
			(xy 114.251277 -266.871344) (xy 114.243612 -266.895326) (xy 114.243612 -266.89558) (xy 114.240259 -266.907325)
			(xy 114.243718 -266.931465) (xy 114.250216 -266.941808) (xy 114.298222 -267.008864) (xy 114.300254 -267.011404)
			(xy 114.307876 -267.019791) (xy 114.328309 -267.029527) (xy 114.339624 -267.0302) (xy 114.509804 -267.0302)
			(xy 114.521137 -267.0296) (xy 114.541593 -267.019847) (xy 114.549174 -267.011404) (xy 114.55019 -267.010134)
			(xy 114.599212 -266.941808) (xy 114.605708 -266.931467) (xy 114.609153 -266.907328) (xy 114.605816 -266.89558)
			(xy 114.605816 -266.895326) (xy 114.598183 -266.871533) (xy 114.589885 -266.822263) (xy 114.589306 -266.797282)
			(xy 114.589306 -266.792202) (xy 114.590143 -266.767167) (xy 114.598975 -266.717864) (xy 114.615736 -266.670663)
			(xy 114.639975 -266.626831) (xy 114.671044 -266.587543) (xy 114.708108 -266.553852) (xy 114.750174 -266.526662)
			(xy 114.796113 -266.506703) (xy 114.844694 -266.494509) (xy 114.894614 -266.490408) (xy 114.944534 -266.494509)
			(xy 114.993115 -266.506703) (xy 115.039054 -266.526662) (xy 115.08112 -266.553852) (xy 115.118184 -266.587543)
			(xy 115.149253 -266.626831) (xy 115.173492 -266.670663) (xy 115.190253 -266.717864) (xy 115.199085 -266.767167)
			(xy 115.199922 -266.792202) (xy 115.199922 -266.79652) (xy 115.199382 -266.821691) (xy 115.191077 -266.871344)
			(xy 115.183412 -266.895326) (xy 115.183412 -266.89558) (xy 115.180059 -266.907325) (xy 115.183518 -266.931465)
			(xy 115.190016 -266.941808) (xy 115.238022 -267.008864) (xy 115.240054 -267.011404) (xy 115.247676 -267.019791)
			(xy 115.268109 -267.029527) (xy 115.279424 -267.0302) (xy 115.449858 -267.0302) (xy 115.461185 -267.029589)
			(xy 115.481624 -267.019823) (xy 115.489228 -267.011404) (xy 115.490244 -267.010134) (xy 115.539266 -266.941808)
			(xy 115.545757 -266.931466) (xy 115.549199 -266.907329) (xy 115.54587 -266.89558) (xy 115.54587 -266.895326)
			(xy 115.538235 -266.871534) (xy 115.529937 -266.822263) (xy 115.52936 -266.797282) (xy 115.52936 -266.792202)
			(xy 115.530197 -266.767167) (xy 115.539029 -266.717864) (xy 115.55579 -266.670663) (xy 115.580029 -266.626831)
			(xy 115.611098 -266.587543) (xy 115.648162 -266.553852) (xy 115.690228 -266.526662) (xy 115.736167 -266.506703)
			(xy 115.784748 -266.494509) (xy 115.834668 -266.490408) (xy 115.884588 -266.494509) (xy 115.933169 -266.506703)
			(xy 115.979108 -266.526662) (xy 116.021174 -266.553852) (xy 116.058238 -266.587543) (xy 116.089307 -266.626831)
			(xy 116.113546 -266.670663) (xy 116.130307 -266.717864) (xy 116.139139 -266.767167) (xy 116.139976 -266.792202)
			(xy 116.139976 -266.79652) (xy 116.139436 -266.821691) (xy 116.131133 -266.871345) (xy 116.123466 -266.895326)
			(xy 116.123466 -266.89558) (xy 116.120111 -266.907324) (xy 116.123574 -266.931463) (xy 116.13007 -266.941808)
			(xy 116.178076 -267.008864) (xy 116.180108 -267.011404) (xy 116.187727 -267.019799) (xy 116.20816 -267.029553)
			(xy 116.219478 -267.0302) (xy 117.329966 -267.0302) (xy 117.341292 -267.029587) (xy 117.361729 -267.019819)
			(xy 117.369336 -267.011404) (xy 117.370352 -267.010134) (xy 117.419374 -266.941808) (xy 117.425864 -266.931466)
			(xy 117.429305 -266.907329) (xy 117.425978 -266.89558) (xy 117.425978 -266.895326) (xy 117.418343 -266.871534)
			(xy 117.410044 -266.822263) (xy 117.409468 -266.797282) (xy 117.409468 -266.792202) (xy 117.410305 -266.767167)
			(xy 117.419137 -266.717864) (xy 117.435898 -266.670663) (xy 117.460137 -266.626831) (xy 117.491206 -266.587543)
			(xy 117.52827 -266.553852) (xy 117.570336 -266.526662) (xy 117.616275 -266.506703) (xy 117.664856 -266.494509)
			(xy 117.714776 -266.490408) (xy 117.764696 -266.494509) (xy 117.813277 -266.506703) (xy 117.859216 -266.526662)
			(xy 117.901282 -266.553852) (xy 117.938346 -266.587543) (xy 117.969415 -266.626831) (xy 117.993654 -266.670663)
			(xy 118.010415 -266.717864) (xy 118.019247 -266.767167) (xy 118.020084 -266.792202) (xy 118.020084 -266.79652)
			(xy 118.019544 -266.821691) (xy 118.011241 -266.871345) (xy 118.003574 -266.895326) (xy 118.003574 -266.89558)
			(xy 118.000219 -266.907324) (xy 118.003682 -266.931463) (xy 118.010178 -266.941808) (xy 118.058184 -267.008864)
			(xy 118.060216 -267.011404) (xy 118.067835 -267.019797) (xy 118.088268 -267.029548) (xy 118.099586 -267.0302)
			(xy 118.27002 -267.0302) (xy 118.281351 -267.029597) (xy 118.301803 -267.01984) (xy 118.30939 -267.011404)
			(xy 118.310406 -267.010134) (xy 118.359428 -266.941808) (xy 118.365923 -266.931467) (xy 118.369367 -266.907328)
			(xy 118.366032 -266.89558) (xy 118.366032 -266.895326) (xy 118.358398 -266.871533) (xy 118.350101 -266.822263)
			(xy 118.349522 -266.797282) (xy 118.349522 -266.792202) (xy 118.350359 -266.767167) (xy 118.359191 -266.717864)
			(xy 118.375952 -266.670663) (xy 118.400191 -266.626831) (xy 118.43126 -266.587543) (xy 118.468324 -266.553852)
			(xy 118.51039 -266.526662) (xy 118.556329 -266.506703) (xy 118.60491 -266.494509) (xy 118.65483 -266.490408)
			(xy 118.70475 -266.494509) (xy 118.753331 -266.506703) (xy 118.79927 -266.526662) (xy 118.841336 -266.553852)
			(xy 118.8784 -266.587543) (xy 118.909469 -266.626831) (xy 118.933708 -266.670663) (xy 118.950469 -266.717864)
			(xy 118.959301 -266.767167) (xy 118.960138 -266.792202) (xy 118.960138 -266.79652) (xy 118.959598 -266.821691)
			(xy 118.951294 -266.871344) (xy 118.943628 -266.895326) (xy 118.943628 -266.89558) (xy 118.940274 -266.907324)
			(xy 118.943734 -266.931464) (xy 118.950232 -266.941808) (xy 118.998238 -267.008864) (xy 119.00027 -267.011404)
			(xy 119.007893 -267.019788) (xy 119.028326 -267.029518) (xy 119.03964 -267.0302) (xy 119.20982 -267.0302)
			(xy 119.221151 -267.029597) (xy 119.241603 -267.01984) (xy 119.24919 -267.011404) (xy 119.250206 -267.010134)
			(xy 119.299228 -266.941808) (xy 119.305723 -266.931467) (xy 119.309167 -266.907328) (xy 119.305832 -266.89558)
			(xy 119.305832 -266.895326) (xy 119.298198 -266.871533) (xy 119.289901 -266.822263) (xy 119.289322 -266.797282)
			(xy 119.289322 -266.792202) (xy 119.290159 -266.767167) (xy 119.298991 -266.717864) (xy 119.315752 -266.670663)
			(xy 119.339991 -266.626831) (xy 119.37106 -266.587543) (xy 119.408124 -266.553852) (xy 119.45019 -266.526662)
			(xy 119.496129 -266.506703) (xy 119.54471 -266.494509) (xy 119.59463 -266.490408) (xy 119.64455 -266.494509)
			(xy 119.693131 -266.506703) (xy 119.73907 -266.526662) (xy 119.781136 -266.553852) (xy 119.8182 -266.587543)
			(xy 119.849269 -266.626831) (xy 119.873508 -266.670663) (xy 119.890269 -266.717864) (xy 119.899101 -266.767167)
			(xy 119.899938 -266.792202) (xy 119.899938 -266.79652) (xy 119.899398 -266.821691) (xy 119.891094 -266.871344)
			(xy 119.883428 -266.895326) (xy 119.883428 -266.89558) (xy 119.880074 -266.907324) (xy 119.883534 -266.931464)
			(xy 119.890032 -266.941808) (xy 119.938038 -267.008864) (xy 119.94007 -267.011404) (xy 119.947693 -267.019788)
			(xy 119.968126 -267.029518) (xy 119.97944 -267.0302) (xy 121.089928 -267.0302) (xy 121.101258 -267.029595)
			(xy 121.121707 -267.019836) (xy 121.129298 -267.011404) (xy 121.130314 -267.010134) (xy 121.179336 -266.941808)
			(xy 121.18583 -266.931467) (xy 121.189274 -266.907328) (xy 121.18594 -266.89558) (xy 121.18594 -266.895326)
			(xy 121.178306 -266.871533) (xy 121.170008 -266.822263) (xy 121.16943 -266.797282) (xy 121.16943 -266.792202)
			(xy 121.170267 -266.767167) (xy 121.179099 -266.717864) (xy 121.19586 -266.670663) (xy 121.220099 -266.626831)
			(xy 121.251168 -266.587543) (xy 121.288232 -266.553852) (xy 121.330298 -266.526662) (xy 121.376237 -266.506703)
			(xy 121.424818 -266.494509) (xy 121.474738 -266.490408) (xy 121.524658 -266.494509) (xy 121.573239 -266.506703)
			(xy 121.619178 -266.526662) (xy 121.661244 -266.553852) (xy 121.698308 -266.587543) (xy 121.729377 -266.626831)
			(xy 121.753616 -266.670663) (xy 121.770377 -266.717864) (xy 121.779209 -266.767167) (xy 121.780046 -266.792202)
			(xy 121.780046 -266.79652) (xy 121.779506 -266.821691) (xy 121.771202 -266.871344) (xy 121.763536 -266.895326)
			(xy 121.763536 -266.89558) (xy 121.760182 -266.907324) (xy 121.763643 -266.931464) (xy 121.77014 -266.941808)
			(xy 121.818146 -267.008864) (xy 121.820178 -267.011404) (xy 121.827795 -267.019804) (xy 121.848228 -267.02957)
			(xy 121.859548 -267.0302) (xy 122.029982 -267.0302) (xy 122.041317 -267.029605) (xy 122.061781 -267.019857)
			(xy 122.069352 -267.011404) (xy 122.070368 -267.010134) (xy 122.11939 -266.941808) (xy 122.125879 -266.931465)
			(xy 122.129318 -266.907329) (xy 122.125994 -266.89558) (xy 122.125994 -266.895326) (xy 122.118359 -266.871534)
			(xy 122.110059 -266.822263) (xy 122.109484 -266.797282) (xy 122.109484 -266.792202) (xy 122.110321 -266.767167)
			(xy 122.119153 -266.717864) (xy 122.135914 -266.670663) (xy 122.160153 -266.626831) (xy 122.191222 -266.587543)
			(xy 122.228286 -266.553852) (xy 122.270352 -266.526662) (xy 122.316291 -266.506703) (xy 122.364872 -266.494509)
			(xy 122.414792 -266.490408) (xy 122.464712 -266.494509) (xy 122.513293 -266.506703) (xy 122.559232 -266.526662)
			(xy 122.601298 -266.553852) (xy 122.638362 -266.587543) (xy 122.669431 -266.626831) (xy 122.69367 -266.670663)
			(xy 122.710431 -266.717864) (xy 122.719263 -266.767167) (xy 122.7201 -266.792202) (xy 122.7201 -266.79652)
			(xy 122.71956 -266.821691) (xy 122.711254 -266.871344) (xy 122.70359 -266.895326) (xy 122.70359 -266.89558)
			(xy 122.700234 -266.907324) (xy 122.703698 -266.931463) (xy 122.710194 -266.941808) (xy 122.7582 -267.008864)
			(xy 122.760232 -267.011404) (xy 122.767852 -267.019795) (xy 122.788286 -267.029539) (xy 122.799602 -267.0302)
			(xy 122.970036 -267.0302) (xy 122.981365 -267.029594) (xy 123.001812 -267.019833) (xy 123.009406 -267.011404)
			(xy 123.010422 -267.010134) (xy 123.059444 -266.941808) (xy 123.065937 -266.931466) (xy 123.06938 -266.907328)
			(xy 123.066048 -266.89558) (xy 123.066048 -266.895326) (xy 123.058414 -266.871533) (xy 123.050116 -266.822263)
			(xy 123.049538 -266.797282) (xy 123.049538 -266.792202) (xy 123.050375 -266.767167) (xy 123.059207 -266.717864)
			(xy 123.075968 -266.670663) (xy 123.100207 -266.626831) (xy 123.131276 -266.587543) (xy 123.16834 -266.553852)
			(xy 123.210406 -266.526662) (xy 123.256345 -266.506703) (xy 123.304926 -266.494509) (xy 123.354846 -266.490408)
			(xy 123.404766 -266.494509) (xy 123.453347 -266.506703) (xy 123.499286 -266.526662) (xy 123.541352 -266.553852)
			(xy 123.578416 -266.587543) (xy 123.609485 -266.626831) (xy 123.633724 -266.670663) (xy 123.650485 -266.717864)
			(xy 123.659317 -266.767167) (xy 123.660154 -266.792202) (xy 123.660154 -266.79652) (xy 123.659614 -266.821691)
			(xy 123.65131 -266.871344) (xy 123.643644 -266.895326) (xy 123.643644 -266.89558) (xy 123.64029 -266.907324)
			(xy 123.643751 -266.931464) (xy 123.650248 -266.941808) (xy 123.698254 -267.008864) (xy 123.700286 -267.011404)
			(xy 123.707903 -267.019802) (xy 123.728336 -267.029565) (xy 123.739656 -267.0302) (xy 124.84989 -267.0302)
			(xy 124.861224 -267.029603) (xy 124.881685 -267.019854) (xy 124.88926 -267.011404) (xy 124.890276 -267.010134)
			(xy 124.939298 -266.941808) (xy 124.945796 -266.931468) (xy 124.949242 -266.907327) (xy 124.945902 -266.89558)
			(xy 124.945902 -266.895326) (xy 124.938267 -266.871534) (xy 124.929967 -266.822263) (xy 124.929392 -266.797282)
			(xy 124.929392 -266.792202) (xy 124.930229 -266.767167) (xy 124.939061 -266.717864) (xy 124.955822 -266.670663)
			(xy 124.980061 -266.626831) (xy 125.01113 -266.587543) (xy 125.048194 -266.553852) (xy 125.09026 -266.526662)
			(xy 125.136199 -266.506703) (xy 125.18478 -266.494509) (xy 125.2347 -266.490408) (xy 125.28462 -266.494509)
			(xy 125.333201 -266.506703) (xy 125.37914 -266.526662) (xy 125.421206 -266.553852) (xy 125.45827 -266.587543)
			(xy 125.489339 -266.626831) (xy 125.513578 -266.670663) (xy 125.530339 -266.717864) (xy 125.539171 -266.767167)
			(xy 125.540008 -266.792202) (xy 125.540008 -266.79652) (xy 125.539468 -266.821691) (xy 125.531163 -266.871344)
			(xy 125.523498 -266.895326) (xy 125.523498 -266.89558) (xy 125.520146 -266.907325) (xy 125.523604 -266.931465)
			(xy 125.530102 -266.941808) (xy 125.578108 -267.008864) (xy 125.58014 -267.011404) (xy 125.587761 -267.019793)
			(xy 125.608194 -267.029535) (xy 125.61951 -267.0302) (xy 125.789944 -267.0302) (xy 125.801272 -267.029592)
			(xy 125.821716 -267.019829) (xy 125.829314 -267.011404) (xy 125.83033 -267.010134) (xy 125.879352 -266.941808)
			(xy 125.885844 -266.931466) (xy 125.889287 -266.907328) (xy 125.885956 -266.89558) (xy 125.885956 -266.895326)
			(xy 125.878322 -266.871533) (xy 125.870023 -266.822263) (xy 125.869446 -266.797282) (xy 125.869446 -266.792202)
			(xy 125.870213 -266.768418) (xy 125.878211 -266.721511) (xy 125.89339 -266.676412) (xy 125.915383 -266.634215)
			(xy 125.943656 -266.595942) (xy 125.977526 -266.562519) (xy 126.016172 -266.534756) (xy 126.058657 -266.513325)
			(xy 126.103952 -266.498745) (xy 126.150962 -266.491371) (xy 126.174754 -266.490958) (xy 126.19875 -266.491401)
			(xy 126.246154 -266.498902) (xy 126.2918 -266.513726) (xy 126.334564 -266.535508) (xy 126.373395 -266.563712)
			(xy 126.407336 -266.597644) (xy 126.43555 -266.636467) (xy 126.457344 -266.679226) (xy 126.47218 -266.724869)
			(xy 126.479693 -266.77227) (xy 126.480062 -266.796266) (xy 126.809004 -266.796266) (xy 126.812964 -266.747212)
			(xy 126.824741 -266.699428) (xy 126.844032 -266.654152) (xy 126.870335 -266.612556) (xy 126.90297 -266.575719)
			(xy 126.941091 -266.544594) (xy 126.983712 -266.519987) (xy 127.029728 -266.502535) (xy 127.077947 -266.492691)
			(xy 127.127122 -266.49071) (xy 127.175977 -266.496642) (xy 127.223248 -266.510334) (xy 127.26771 -266.531432)
			(xy 127.308213 -266.559388) (xy 127.343706 -266.59348) (xy 127.373271 -266.632824) (xy 127.396142 -266.676401)
			(xy 127.411726 -266.723082) (xy 127.419621 -266.771659) (xy 127.420116 -266.796266) (xy 127.738627 -266.796266)
			(xy 127.742722 -266.745538) (xy 127.754901 -266.696124) (xy 127.774849 -266.649304) (xy 127.80205 -266.60629)
			(xy 127.835798 -266.568196) (xy 127.87522 -266.536009) (xy 127.919294 -266.510563) (xy 127.96688 -266.492516)
			(xy 128.016744 -266.482336) (xy 128.067596 -266.480287) (xy 128.118117 -266.486421) (xy 128.167001 -266.500581)
			(xy 128.21298 -266.522398) (xy 128.254864 -266.551308) (xy 128.291568 -266.586563) (xy 128.322141 -266.627249)
			(xy 128.345792 -266.672312) (xy 128.361908 -266.720586) (xy 128.370072 -266.77082) (xy 128.370584 -266.796266)
			(xy 128.688858 -266.796266) (xy 128.692818 -266.747212) (xy 128.704595 -266.699428) (xy 128.723886 -266.654152)
			(xy 128.750189 -266.612556) (xy 128.782824 -266.575719) (xy 128.820945 -266.544594) (xy 128.863566 -266.519987)
			(xy 128.909582 -266.502535) (xy 128.957801 -266.492691) (xy 129.006976 -266.49071) (xy 129.055831 -266.496642)
			(xy 129.103102 -266.510334) (xy 129.147564 -266.531432) (xy 129.188067 -266.559388) (xy 129.22356 -266.59348)
			(xy 129.253125 -266.632824) (xy 129.275996 -266.676401) (xy 129.29158 -266.723082) (xy 129.299475 -266.771659)
			(xy 129.29997 -266.796266) (xy 129.618481 -266.796266) (xy 129.622576 -266.745538) (xy 129.634755 -266.696124)
			(xy 129.654703 -266.649304) (xy 129.681904 -266.60629) (xy 129.715652 -266.568196) (xy 129.755074 -266.536009)
			(xy 129.799148 -266.510563) (xy 129.846734 -266.492516) (xy 129.896598 -266.482336) (xy 129.94745 -266.480287)
			(xy 129.997971 -266.486421) (xy 130.046855 -266.500581) (xy 130.092834 -266.522398) (xy 130.134718 -266.551308)
			(xy 130.171422 -266.586563) (xy 130.201995 -266.627249) (xy 130.225646 -266.672312) (xy 130.241762 -266.720586)
			(xy 130.249926 -266.77082) (xy 130.250438 -266.796266) (xy 130.568966 -266.796266) (xy 130.572926 -266.747212)
			(xy 130.584703 -266.699428) (xy 130.603994 -266.654152) (xy 130.630297 -266.612556) (xy 130.662932 -266.575719)
			(xy 130.701053 -266.544594) (xy 130.743674 -266.519987) (xy 130.78969 -266.502535) (xy 130.837909 -266.492691)
			(xy 130.887084 -266.49071) (xy 130.935939 -266.496642) (xy 130.98321 -266.510334) (xy 131.027672 -266.531432)
			(xy 131.068175 -266.559388) (xy 131.103668 -266.59348) (xy 131.133233 -266.632824) (xy 131.156104 -266.676401)
			(xy 131.171688 -266.723082) (xy 131.179583 -266.771659) (xy 131.180078 -266.796266) (xy 131.498589 -266.796266)
			(xy 131.502684 -266.745538) (xy 131.514863 -266.696124) (xy 131.534811 -266.649304) (xy 131.562012 -266.60629)
			(xy 131.59576 -266.568196) (xy 131.635182 -266.536009) (xy 131.679256 -266.510563) (xy 131.726842 -266.492516)
			(xy 131.776706 -266.482336) (xy 131.827558 -266.480287) (xy 131.878079 -266.486421) (xy 131.926963 -266.500581)
			(xy 131.972942 -266.522398) (xy 132.014826 -266.551308) (xy 132.05153 -266.586563) (xy 132.082103 -266.627249)
			(xy 132.105754 -266.672312) (xy 132.12187 -266.720586) (xy 132.130034 -266.77082) (xy 132.130546 -266.796266)
			(xy 132.438643 -266.796266) (xy 132.442738 -266.745538) (xy 132.454917 -266.696124) (xy 132.474865 -266.649304)
			(xy 132.502066 -266.60629) (xy 132.535814 -266.568196) (xy 132.575236 -266.536009) (xy 132.61931 -266.510563)
			(xy 132.666896 -266.492516) (xy 132.71676 -266.482336) (xy 132.767612 -266.480287) (xy 132.818133 -266.486421)
			(xy 132.867017 -266.500581) (xy 132.912996 -266.522398) (xy 132.95488 -266.551308) (xy 132.991584 -266.586563)
			(xy 133.022157 -266.627249) (xy 133.045808 -266.672312) (xy 133.061924 -266.720586) (xy 133.070088 -266.77082)
			(xy 133.0706 -266.796266) (xy 133.388874 -266.796266) (xy 133.392834 -266.747212) (xy 133.404611 -266.699428)
			(xy 133.423902 -266.654152) (xy 133.450205 -266.612556) (xy 133.48284 -266.575719) (xy 133.520961 -266.544594)
			(xy 133.563582 -266.519987) (xy 133.609598 -266.502535) (xy 133.657817 -266.492691) (xy 133.706992 -266.49071)
			(xy 133.755847 -266.496642) (xy 133.803118 -266.510334) (xy 133.84758 -266.531432) (xy 133.888083 -266.559388)
			(xy 133.923576 -266.59348) (xy 133.953141 -266.632824) (xy 133.976012 -266.676401) (xy 133.991596 -266.723082)
			(xy 133.999491 -266.771659) (xy 133.999986 -266.796266) (xy 134.328928 -266.796266) (xy 134.332888 -266.747212)
			(xy 134.344665 -266.699428) (xy 134.363956 -266.654152) (xy 134.390259 -266.612556) (xy 134.422894 -266.575719)
			(xy 134.461015 -266.544594) (xy 134.503636 -266.519987) (xy 134.549652 -266.502535) (xy 134.597871 -266.492691)
			(xy 134.647046 -266.49071) (xy 134.695901 -266.496642) (xy 134.743172 -266.510334) (xy 134.787634 -266.531432)
			(xy 134.828137 -266.559388) (xy 134.86363 -266.59348) (xy 134.893195 -266.632824) (xy 134.916066 -266.676401)
			(xy 134.93165 -266.723082) (xy 134.939545 -266.771659) (xy 134.94004 -266.796266) (xy 135.268982 -266.796266)
			(xy 135.272942 -266.747212) (xy 135.284719 -266.699428) (xy 135.30401 -266.654152) (xy 135.330313 -266.612556)
			(xy 135.362948 -266.575719) (xy 135.401069 -266.544594) (xy 135.44369 -266.519987) (xy 135.489706 -266.502535)
			(xy 135.537925 -266.492691) (xy 135.5871 -266.49071) (xy 135.635955 -266.496642) (xy 135.683226 -266.510334)
			(xy 135.727688 -266.531432) (xy 135.768191 -266.559388) (xy 135.803684 -266.59348) (xy 135.833249 -266.632824)
			(xy 135.85612 -266.676401) (xy 135.871704 -266.723082) (xy 135.879599 -266.771659) (xy 135.880094 -266.796266)
			(xy 136.209036 -266.796266) (xy 136.212996 -266.747212) (xy 136.224773 -266.699428) (xy 136.244064 -266.654152)
			(xy 136.270367 -266.612556) (xy 136.303002 -266.575719) (xy 136.341123 -266.544594) (xy 136.383744 -266.519987)
			(xy 136.42976 -266.502535) (xy 136.477979 -266.492691) (xy 136.527154 -266.49071) (xy 136.576009 -266.496642)
			(xy 136.62328 -266.510334) (xy 136.667742 -266.531432) (xy 136.708245 -266.559388) (xy 136.743738 -266.59348)
			(xy 136.773303 -266.632824) (xy 136.796174 -266.676401) (xy 136.811758 -266.723082) (xy 136.819653 -266.771659)
			(xy 136.820148 -266.796266) (xy 136.819653 -266.820873) (xy 136.811758 -266.86945) (xy 136.796174 -266.916131)
			(xy 136.773303 -266.959708) (xy 136.743738 -266.999052) (xy 136.708245 -267.033144) (xy 136.667742 -267.0611)
			(xy 136.62328 -267.082198) (xy 136.576009 -267.09589) (xy 136.527154 -267.101822) (xy 136.477979 -267.099841)
			(xy 136.42976 -267.089997) (xy 136.383744 -267.072545) (xy 136.341123 -267.047938) (xy 136.303002 -267.016813)
			(xy 136.270367 -266.979976) (xy 136.244064 -266.93838) (xy 136.224773 -266.893104) (xy 136.212996 -266.84532)
			(xy 136.209036 -266.796266) (xy 135.880094 -266.796266) (xy 135.879599 -266.820873) (xy 135.871704 -266.86945)
			(xy 135.85612 -266.916131) (xy 135.833249 -266.959708) (xy 135.803684 -266.999052) (xy 135.768191 -267.033144)
			(xy 135.727688 -267.0611) (xy 135.683226 -267.082198) (xy 135.635955 -267.09589) (xy 135.5871 -267.101822)
			(xy 135.537925 -267.099841) (xy 135.489706 -267.089997) (xy 135.44369 -267.072545) (xy 135.401069 -267.047938)
			(xy 135.362948 -267.016813) (xy 135.330313 -266.979976) (xy 135.30401 -266.93838) (xy 135.284719 -266.893104)
			(xy 135.272942 -266.84532) (xy 135.268982 -266.796266) (xy 134.94004 -266.796266) (xy 134.939545 -266.820873)
			(xy 134.93165 -266.86945) (xy 134.916066 -266.916131) (xy 134.893195 -266.959708) (xy 134.86363 -266.999052)
			(xy 134.828137 -267.033144) (xy 134.787634 -267.0611) (xy 134.743172 -267.082198) (xy 134.695901 -267.09589)
			(xy 134.647046 -267.101822) (xy 134.597871 -267.099841) (xy 134.549652 -267.089997) (xy 134.503636 -267.072545)
			(xy 134.461015 -267.047938) (xy 134.422894 -267.016813) (xy 134.390259 -266.979976) (xy 134.363956 -266.93838)
			(xy 134.344665 -266.893104) (xy 134.332888 -266.84532) (xy 134.328928 -266.796266) (xy 133.999986 -266.796266)
			(xy 133.999491 -266.820873) (xy 133.991596 -266.86945) (xy 133.976012 -266.916131) (xy 133.953141 -266.959708)
			(xy 133.923576 -266.999052) (xy 133.888083 -267.033144) (xy 133.84758 -267.0611) (xy 133.803118 -267.082198)
			(xy 133.755847 -267.09589) (xy 133.706992 -267.101822) (xy 133.657817 -267.099841) (xy 133.609598 -267.089997)
			(xy 133.563582 -267.072545) (xy 133.520961 -267.047938) (xy 133.48284 -267.016813) (xy 133.450205 -266.979976)
			(xy 133.423902 -266.93838) (xy 133.404611 -266.893104) (xy 133.392834 -266.84532) (xy 133.388874 -266.796266)
			(xy 133.0706 -266.796266) (xy 133.070088 -266.821712) (xy 133.061924 -266.871946) (xy 133.045808 -266.92022)
			(xy 133.022157 -266.965283) (xy 132.991584 -267.005969) (xy 132.95488 -267.041224) (xy 132.912996 -267.070134)
			(xy 132.867017 -267.091951) (xy 132.818133 -267.106111) (xy 132.767612 -267.112245) (xy 132.71676 -267.110196)
			(xy 132.666896 -267.100016) (xy 132.61931 -267.081969) (xy 132.575236 -267.056523) (xy 132.535814 -267.024336)
			(xy 132.502066 -266.986242) (xy 132.474865 -266.943228) (xy 132.454917 -266.896408) (xy 132.442738 -266.846994)
			(xy 132.438643 -266.796266) (xy 132.130546 -266.796266) (xy 132.130034 -266.821712) (xy 132.12187 -266.871946)
			(xy 132.105754 -266.92022) (xy 132.082103 -266.965283) (xy 132.05153 -267.005969) (xy 132.014826 -267.041224)
			(xy 131.972942 -267.070134) (xy 131.926963 -267.091951) (xy 131.878079 -267.106111) (xy 131.827558 -267.112245)
			(xy 131.776706 -267.110196) (xy 131.726842 -267.100016) (xy 131.679256 -267.081969) (xy 131.635182 -267.056523)
			(xy 131.59576 -267.024336) (xy 131.562012 -266.986242) (xy 131.534811 -266.943228) (xy 131.514863 -266.896408)
			(xy 131.502684 -266.846994) (xy 131.498589 -266.796266) (xy 131.180078 -266.796266) (xy 131.179583 -266.820873)
			(xy 131.171688 -266.86945) (xy 131.156104 -266.916131) (xy 131.133233 -266.959708) (xy 131.103668 -266.999052)
			(xy 131.068175 -267.033144) (xy 131.027672 -267.0611) (xy 130.98321 -267.082198) (xy 130.935939 -267.09589)
			(xy 130.887084 -267.101822) (xy 130.837909 -267.099841) (xy 130.78969 -267.089997) (xy 130.743674 -267.072545)
			(xy 130.701053 -267.047938) (xy 130.662932 -267.016813) (xy 130.630297 -266.979976) (xy 130.603994 -266.93838)
			(xy 130.584703 -266.893104) (xy 130.572926 -266.84532) (xy 130.568966 -266.796266) (xy 130.250438 -266.796266)
			(xy 130.249926 -266.821712) (xy 130.241762 -266.871946) (xy 130.225646 -266.92022) (xy 130.201995 -266.965283)
			(xy 130.171422 -267.005969) (xy 130.134718 -267.041224) (xy 130.092834 -267.070134) (xy 130.046855 -267.091951)
			(xy 129.997971 -267.106111) (xy 129.94745 -267.112245) (xy 129.896598 -267.110196) (xy 129.846734 -267.100016)
			(xy 129.799148 -267.081969) (xy 129.755074 -267.056523) (xy 129.715652 -267.024336) (xy 129.681904 -266.986242)
			(xy 129.654703 -266.943228) (xy 129.634755 -266.896408) (xy 129.622576 -266.846994) (xy 129.618481 -266.796266)
			(xy 129.29997 -266.796266) (xy 129.299475 -266.820873) (xy 129.29158 -266.86945) (xy 129.275996 -266.916131)
			(xy 129.253125 -266.959708) (xy 129.22356 -266.999052) (xy 129.188067 -267.033144) (xy 129.147564 -267.0611)
			(xy 129.103102 -267.082198) (xy 129.055831 -267.09589) (xy 129.006976 -267.101822) (xy 128.957801 -267.099841)
			(xy 128.909582 -267.089997) (xy 128.863566 -267.072545) (xy 128.820945 -267.047938) (xy 128.782824 -267.016813)
			(xy 128.750189 -266.979976) (xy 128.723886 -266.93838) (xy 128.704595 -266.893104) (xy 128.692818 -266.84532)
			(xy 128.688858 -266.796266) (xy 128.370584 -266.796266) (xy 128.370072 -266.821712) (xy 128.361908 -266.871946)
			(xy 128.345792 -266.92022) (xy 128.322141 -266.965283) (xy 128.291568 -267.005969) (xy 128.254864 -267.041224)
			(xy 128.21298 -267.070134) (xy 128.167001 -267.091951) (xy 128.118117 -267.106111) (xy 128.067596 -267.112245)
			(xy 128.016744 -267.110196) (xy 127.96688 -267.100016) (xy 127.919294 -267.081969) (xy 127.87522 -267.056523)
			(xy 127.835798 -267.024336) (xy 127.80205 -266.986242) (xy 127.774849 -266.943228) (xy 127.754901 -266.896408)
			(xy 127.742722 -266.846994) (xy 127.738627 -266.796266) (xy 127.420116 -266.796266) (xy 127.419621 -266.820873)
			(xy 127.411726 -266.86945) (xy 127.396142 -266.916131) (xy 127.373271 -266.959708) (xy 127.343706 -266.999052)
			(xy 127.308213 -267.033144) (xy 127.26771 -267.0611) (xy 127.223248 -267.082198) (xy 127.175977 -267.09589)
			(xy 127.127122 -267.101822) (xy 127.077947 -267.099841) (xy 127.029728 -267.089997) (xy 126.983712 -267.072545)
			(xy 126.941091 -267.047938) (xy 126.90297 -267.016813) (xy 126.870335 -266.979976) (xy 126.844032 -266.93838)
			(xy 126.824741 -266.893104) (xy 126.812964 -266.84532) (xy 126.809004 -266.796266) (xy 126.480062 -266.796266)
			(xy 126.479922 -266.809029) (xy 126.477758 -266.834462) (xy 126.475744 -266.847066) (xy 126.475998 -266.847066)
			(xy 126.472087 -266.867845) (xy 126.459306 -266.908149) (xy 126.44111 -266.946314) (xy 126.42977 -266.96416)
			(xy 126.419864 -266.9794) (xy 126.42342 -267.01496) (xy 126.713742 -267.305282) (xy 126.724156 -267.311378)
			(xy 126.730506 -267.31341) (xy 126.754798 -267.321059) (xy 126.800616 -267.34329) (xy 126.842108 -267.372817)
			(xy 126.878123 -267.408822) (xy 126.907663 -267.450305) (xy 126.929908 -267.496116) (xy 126.937516 -267.52042)
			(xy 126.939548 -267.52677) (xy 126.945644 -267.537184) (xy 127.014732 -267.606272) (xy 128.218958 -267.606272)
			(xy 128.222918 -267.557218) (xy 128.234695 -267.509434) (xy 128.253986 -267.464158) (xy 128.280289 -267.422562)
			(xy 128.312924 -267.385725) (xy 128.351045 -267.3546) (xy 128.393666 -267.329993) (xy 128.439682 -267.312541)
			(xy 128.487901 -267.302697) (xy 128.537076 -267.300716) (xy 128.585931 -267.306648) (xy 128.633202 -267.32034)
			(xy 128.677664 -267.341438) (xy 128.718167 -267.369394) (xy 128.75366 -267.403486) (xy 128.783225 -267.44283)
			(xy 128.806096 -267.486407) (xy 128.82168 -267.533088) (xy 128.829575 -267.581665) (xy 128.83007 -267.606272)
			(xy 129.148581 -267.606272) (xy 129.152676 -267.555544) (xy 129.164855 -267.50613) (xy 129.184803 -267.45931)
			(xy 129.212004 -267.416296) (xy 129.245752 -267.378202) (xy 129.285174 -267.346015) (xy 129.329248 -267.320569)
			(xy 129.376834 -267.302522) (xy 129.426698 -267.292342) (xy 129.47755 -267.290293) (xy 129.528071 -267.296427)
			(xy 129.576955 -267.310587) (xy 129.622934 -267.332404) (xy 129.664818 -267.361314) (xy 129.701522 -267.396569)
			(xy 129.732095 -267.437255) (xy 129.755746 -267.482318) (xy 129.771862 -267.530592) (xy 129.780026 -267.580826)
			(xy 129.780538 -267.606272) (xy 130.099066 -267.606272) (xy 130.103026 -267.557218) (xy 130.114803 -267.509434)
			(xy 130.134094 -267.464158) (xy 130.160397 -267.422562) (xy 130.193032 -267.385725) (xy 130.231153 -267.3546)
			(xy 130.273774 -267.329993) (xy 130.31979 -267.312541) (xy 130.368009 -267.302697) (xy 130.417184 -267.300716)
			(xy 130.466039 -267.306648) (xy 130.51331 -267.32034) (xy 130.557772 -267.341438) (xy 130.598275 -267.369394)
			(xy 130.633768 -267.403486) (xy 130.663333 -267.44283) (xy 130.686204 -267.486407) (xy 130.701788 -267.533088)
			(xy 130.709683 -267.581665) (xy 130.710178 -267.606272) (xy 131.038866 -267.606272) (xy 131.042826 -267.557218)
			(xy 131.054603 -267.509434) (xy 131.073894 -267.464158) (xy 131.100197 -267.422562) (xy 131.132832 -267.385725)
			(xy 131.170953 -267.3546) (xy 131.213574 -267.329993) (xy 131.25959 -267.312541) (xy 131.307809 -267.302697)
			(xy 131.356984 -267.300716) (xy 131.405839 -267.306648) (xy 131.45311 -267.32034) (xy 131.497572 -267.341438)
			(xy 131.538075 -267.369394) (xy 131.573568 -267.403486) (xy 131.603133 -267.44283) (xy 131.626004 -267.486407)
			(xy 131.641588 -267.533088) (xy 131.649483 -267.581665) (xy 131.649978 -267.606272) (xy 131.97892 -267.606272)
			(xy 131.98288 -267.557218) (xy 131.994657 -267.509434) (xy 132.013948 -267.464158) (xy 132.040251 -267.422562)
			(xy 132.072886 -267.385725) (xy 132.111007 -267.3546) (xy 132.153628 -267.329993) (xy 132.199644 -267.312541)
			(xy 132.247863 -267.302697) (xy 132.297038 -267.300716) (xy 132.345893 -267.306648) (xy 132.393164 -267.32034)
			(xy 132.437626 -267.341438) (xy 132.478129 -267.369394) (xy 132.513622 -267.403486) (xy 132.543187 -267.44283)
			(xy 132.566058 -267.486407) (xy 132.581642 -267.533088) (xy 132.589537 -267.581665) (xy 132.590032 -267.606272)
			(xy 132.908543 -267.606272) (xy 132.912638 -267.555544) (xy 132.924817 -267.50613) (xy 132.944765 -267.45931)
			(xy 132.971966 -267.416296) (xy 133.005714 -267.378202) (xy 133.045136 -267.346015) (xy 133.08921 -267.320569)
			(xy 133.136796 -267.302522) (xy 133.18666 -267.292342) (xy 133.237512 -267.290293) (xy 133.288033 -267.296427)
			(xy 133.336917 -267.310587) (xy 133.382896 -267.332404) (xy 133.42478 -267.361314) (xy 133.461484 -267.396569)
			(xy 133.492057 -267.437255) (xy 133.515708 -267.482318) (xy 133.531824 -267.530592) (xy 133.539988 -267.580826)
			(xy 133.5405 -267.606272) (xy 133.859028 -267.606272) (xy 133.862988 -267.557218) (xy 133.874765 -267.509434)
			(xy 133.894056 -267.464158) (xy 133.920359 -267.422562) (xy 133.952994 -267.385725) (xy 133.991115 -267.3546)
			(xy 134.033736 -267.329993) (xy 134.079752 -267.312541) (xy 134.127971 -267.302697) (xy 134.177146 -267.300716)
			(xy 134.226001 -267.306648) (xy 134.273272 -267.32034) (xy 134.317734 -267.341438) (xy 134.358237 -267.369394)
			(xy 134.39373 -267.403486) (xy 134.423295 -267.44283) (xy 134.446166 -267.486407) (xy 134.46175 -267.533088)
			(xy 134.469645 -267.581665) (xy 134.47014 -267.606272) (xy 134.798828 -267.606272) (xy 134.802788 -267.557218)
			(xy 134.814565 -267.509434) (xy 134.833856 -267.464158) (xy 134.860159 -267.422562) (xy 134.892794 -267.385725)
			(xy 134.930915 -267.3546) (xy 134.973536 -267.329993) (xy 135.019552 -267.312541) (xy 135.067771 -267.302697)
			(xy 135.116946 -267.300716) (xy 135.165801 -267.306648) (xy 135.213072 -267.32034) (xy 135.257534 -267.341438)
			(xy 135.298037 -267.369394) (xy 135.33353 -267.403486) (xy 135.363095 -267.44283) (xy 135.385966 -267.486407)
			(xy 135.40155 -267.533088) (xy 135.409445 -267.581665) (xy 135.40994 -267.606272) (xy 135.738882 -267.606272)
			(xy 135.742842 -267.557218) (xy 135.754619 -267.509434) (xy 135.77391 -267.464158) (xy 135.800213 -267.422562)
			(xy 135.832848 -267.385725) (xy 135.870969 -267.3546) (xy 135.91359 -267.329993) (xy 135.959606 -267.312541)
			(xy 136.007825 -267.302697) (xy 136.057 -267.300716) (xy 136.105855 -267.306648) (xy 136.153126 -267.32034)
			(xy 136.197588 -267.341438) (xy 136.238091 -267.369394) (xy 136.273584 -267.403486) (xy 136.303149 -267.44283)
			(xy 136.32602 -267.486407) (xy 136.341604 -267.533088) (xy 136.349499 -267.581665) (xy 136.349994 -267.606272)
			(xy 136.678936 -267.606272) (xy 136.682896 -267.557218) (xy 136.694673 -267.509434) (xy 136.713964 -267.464158)
			(xy 136.740267 -267.422562) (xy 136.772902 -267.385725) (xy 136.811023 -267.3546) (xy 136.853644 -267.329993)
			(xy 136.89966 -267.312541) (xy 136.947879 -267.302697) (xy 136.997054 -267.300716) (xy 137.045909 -267.306648)
			(xy 137.09318 -267.32034) (xy 137.137642 -267.341438) (xy 137.178145 -267.369394) (xy 137.213638 -267.403486)
			(xy 137.243203 -267.44283) (xy 137.266074 -267.486407) (xy 137.281658 -267.533088) (xy 137.289553 -267.581665)
			(xy 137.290048 -267.606272) (xy 137.289553 -267.630879) (xy 137.281658 -267.679456) (xy 137.266074 -267.726137)
			(xy 137.243203 -267.769714) (xy 137.213638 -267.809058) (xy 137.178145 -267.84315) (xy 137.137642 -267.871106)
			(xy 137.09318 -267.892204) (xy 137.045909 -267.905896) (xy 136.997054 -267.911828) (xy 136.947879 -267.909847)
			(xy 136.89966 -267.900003) (xy 136.853644 -267.882551) (xy 136.811023 -267.857944) (xy 136.772902 -267.826819)
			(xy 136.740267 -267.789982) (xy 136.713964 -267.748386) (xy 136.694673 -267.70311) (xy 136.682896 -267.655326)
			(xy 136.678936 -267.606272) (xy 136.349994 -267.606272) (xy 136.349499 -267.630879) (xy 136.341604 -267.679456)
			(xy 136.32602 -267.726137) (xy 136.303149 -267.769714) (xy 136.273584 -267.809058) (xy 136.238091 -267.84315)
			(xy 136.197588 -267.871106) (xy 136.153126 -267.892204) (xy 136.105855 -267.905896) (xy 136.057 -267.911828)
			(xy 136.007825 -267.909847) (xy 135.959606 -267.900003) (xy 135.91359 -267.882551) (xy 135.870969 -267.857944)
			(xy 135.832848 -267.826819) (xy 135.800213 -267.789982) (xy 135.77391 -267.748386) (xy 135.754619 -267.70311)
			(xy 135.742842 -267.655326) (xy 135.738882 -267.606272) (xy 135.40994 -267.606272) (xy 135.409445 -267.630879)
			(xy 135.40155 -267.679456) (xy 135.385966 -267.726137) (xy 135.363095 -267.769714) (xy 135.33353 -267.809058)
			(xy 135.298037 -267.84315) (xy 135.257534 -267.871106) (xy 135.213072 -267.892204) (xy 135.165801 -267.905896)
			(xy 135.116946 -267.911828) (xy 135.067771 -267.909847) (xy 135.019552 -267.900003) (xy 134.973536 -267.882551)
			(xy 134.930915 -267.857944) (xy 134.892794 -267.826819) (xy 134.860159 -267.789982) (xy 134.833856 -267.748386)
			(xy 134.814565 -267.70311) (xy 134.802788 -267.655326) (xy 134.798828 -267.606272) (xy 134.47014 -267.606272)
			(xy 134.469645 -267.630879) (xy 134.46175 -267.679456) (xy 134.446166 -267.726137) (xy 134.423295 -267.769714)
			(xy 134.39373 -267.809058) (xy 134.358237 -267.84315) (xy 134.317734 -267.871106) (xy 134.273272 -267.892204)
			(xy 134.226001 -267.905896) (xy 134.177146 -267.911828) (xy 134.127971 -267.909847) (xy 134.079752 -267.900003)
			(xy 134.033736 -267.882551) (xy 133.991115 -267.857944) (xy 133.952994 -267.826819) (xy 133.920359 -267.789982)
			(xy 133.894056 -267.748386) (xy 133.874765 -267.70311) (xy 133.862988 -267.655326) (xy 133.859028 -267.606272)
			(xy 133.5405 -267.606272) (xy 133.539988 -267.631718) (xy 133.531824 -267.681952) (xy 133.515708 -267.730226)
			(xy 133.492057 -267.775289) (xy 133.461484 -267.815975) (xy 133.42478 -267.85123) (xy 133.382896 -267.88014)
			(xy 133.336917 -267.901957) (xy 133.288033 -267.916117) (xy 133.237512 -267.922251) (xy 133.18666 -267.920202)
			(xy 133.136796 -267.910022) (xy 133.08921 -267.891975) (xy 133.045136 -267.866529) (xy 133.005714 -267.834342)
			(xy 132.971966 -267.796248) (xy 132.944765 -267.753234) (xy 132.924817 -267.706414) (xy 132.912638 -267.657)
			(xy 132.908543 -267.606272) (xy 132.590032 -267.606272) (xy 132.589537 -267.630879) (xy 132.581642 -267.679456)
			(xy 132.566058 -267.726137) (xy 132.543187 -267.769714) (xy 132.513622 -267.809058) (xy 132.478129 -267.84315)
			(xy 132.437626 -267.871106) (xy 132.393164 -267.892204) (xy 132.345893 -267.905896) (xy 132.297038 -267.911828)
			(xy 132.247863 -267.909847) (xy 132.199644 -267.900003) (xy 132.153628 -267.882551) (xy 132.111007 -267.857944)
			(xy 132.072886 -267.826819) (xy 132.040251 -267.789982) (xy 132.013948 -267.748386) (xy 131.994657 -267.70311)
			(xy 131.98288 -267.655326) (xy 131.97892 -267.606272) (xy 131.649978 -267.606272) (xy 131.649483 -267.630879)
			(xy 131.641588 -267.679456) (xy 131.626004 -267.726137) (xy 131.603133 -267.769714) (xy 131.573568 -267.809058)
			(xy 131.538075 -267.84315) (xy 131.497572 -267.871106) (xy 131.45311 -267.892204) (xy 131.405839 -267.905896)
			(xy 131.356984 -267.911828) (xy 131.307809 -267.909847) (xy 131.25959 -267.900003) (xy 131.213574 -267.882551)
			(xy 131.170953 -267.857944) (xy 131.132832 -267.826819) (xy 131.100197 -267.789982) (xy 131.073894 -267.748386)
			(xy 131.054603 -267.70311) (xy 131.042826 -267.655326) (xy 131.038866 -267.606272) (xy 130.710178 -267.606272)
			(xy 130.709683 -267.630879) (xy 130.701788 -267.679456) (xy 130.686204 -267.726137) (xy 130.663333 -267.769714)
			(xy 130.633768 -267.809058) (xy 130.598275 -267.84315) (xy 130.557772 -267.871106) (xy 130.51331 -267.892204)
			(xy 130.466039 -267.905896) (xy 130.417184 -267.911828) (xy 130.368009 -267.909847) (xy 130.31979 -267.900003)
			(xy 130.273774 -267.882551) (xy 130.231153 -267.857944) (xy 130.193032 -267.826819) (xy 130.160397 -267.789982)
			(xy 130.134094 -267.748386) (xy 130.114803 -267.70311) (xy 130.103026 -267.655326) (xy 130.099066 -267.606272)
			(xy 129.780538 -267.606272) (xy 129.780026 -267.631718) (xy 129.771862 -267.681952) (xy 129.755746 -267.730226)
			(xy 129.732095 -267.775289) (xy 129.701522 -267.815975) (xy 129.664818 -267.85123) (xy 129.622934 -267.88014)
			(xy 129.576955 -267.901957) (xy 129.528071 -267.916117) (xy 129.47755 -267.922251) (xy 129.426698 -267.920202)
			(xy 129.376834 -267.910022) (xy 129.329248 -267.891975) (xy 129.285174 -267.866529) (xy 129.245752 -267.834342)
			(xy 129.212004 -267.796248) (xy 129.184803 -267.753234) (xy 129.164855 -267.706414) (xy 129.152676 -267.657)
			(xy 129.148581 -267.606272) (xy 128.83007 -267.606272) (xy 128.829575 -267.630879) (xy 128.82168 -267.679456)
			(xy 128.806096 -267.726137) (xy 128.783225 -267.769714) (xy 128.75366 -267.809058) (xy 128.718167 -267.84315)
			(xy 128.677664 -267.871106) (xy 128.633202 -267.892204) (xy 128.585931 -267.905896) (xy 128.537076 -267.911828)
			(xy 128.487901 -267.909847) (xy 128.439682 -267.900003) (xy 128.393666 -267.882551) (xy 128.351045 -267.857944)
			(xy 128.312924 -267.826819) (xy 128.280289 -267.789982) (xy 128.253986 -267.748386) (xy 128.234695 -267.70311)
			(xy 128.222918 -267.655326) (xy 128.218958 -267.606272) (xy 127.014732 -267.606272) (xy 127.442468 -268.034008)
			(xy 127.449317 -268.041405) (xy 127.457053 -268.060004) (xy 127.457454 -268.070076) (xy 127.457454 -268.416278)
			(xy 127.749058 -268.416278) (xy 127.753018 -268.367224) (xy 127.764795 -268.31944) (xy 127.784086 -268.274164)
			(xy 127.810389 -268.232568) (xy 127.843024 -268.195731) (xy 127.881145 -268.164606) (xy 127.923766 -268.139999)
			(xy 127.969782 -268.122547) (xy 128.018001 -268.112703) (xy 128.067176 -268.110722) (xy 128.116031 -268.116654)
			(xy 128.163302 -268.130346) (xy 128.207764 -268.151444) (xy 128.248267 -268.1794) (xy 128.28376 -268.213492)
			(xy 128.313325 -268.252836) (xy 128.336196 -268.296413) (xy 128.35178 -268.343094) (xy 128.359675 -268.391671)
			(xy 128.36017 -268.416278) (xy 128.688858 -268.416278) (xy 128.692818 -268.367224) (xy 128.704595 -268.31944)
			(xy 128.723886 -268.274164) (xy 128.750189 -268.232568) (xy 128.782824 -268.195731) (xy 128.820945 -268.164606)
			(xy 128.863566 -268.139999) (xy 128.909582 -268.122547) (xy 128.957801 -268.112703) (xy 129.006976 -268.110722)
			(xy 129.055831 -268.116654) (xy 129.103102 -268.130346) (xy 129.147564 -268.151444) (xy 129.188067 -268.1794)
			(xy 129.22356 -268.213492) (xy 129.253125 -268.252836) (xy 129.275996 -268.296413) (xy 129.29158 -268.343094)
			(xy 129.299475 -268.391671) (xy 129.29997 -268.416278) (xy 129.628912 -268.416278) (xy 129.632872 -268.367224)
			(xy 129.644649 -268.31944) (xy 129.66394 -268.274164) (xy 129.690243 -268.232568) (xy 129.722878 -268.195731)
			(xy 129.760999 -268.164606) (xy 129.80362 -268.139999) (xy 129.849636 -268.122547) (xy 129.897855 -268.112703)
			(xy 129.94703 -268.110722) (xy 129.995885 -268.116654) (xy 130.043156 -268.130346) (xy 130.087618 -268.151444)
			(xy 130.128121 -268.1794) (xy 130.163614 -268.213492) (xy 130.193179 -268.252836) (xy 130.21605 -268.296413)
			(xy 130.231634 -268.343094) (xy 130.239529 -268.391671) (xy 130.240024 -268.416278) (xy 131.50902 -268.416278)
			(xy 131.51298 -268.367224) (xy 131.524757 -268.31944) (xy 131.544048 -268.274164) (xy 131.570351 -268.232568)
			(xy 131.602986 -268.195731) (xy 131.641107 -268.164606) (xy 131.683728 -268.139999) (xy 131.729744 -268.122547)
			(xy 131.777963 -268.112703) (xy 131.827138 -268.110722) (xy 131.875993 -268.116654) (xy 131.923264 -268.130346)
			(xy 131.967726 -268.151444) (xy 132.008229 -268.1794) (xy 132.043722 -268.213492) (xy 132.073287 -268.252836)
			(xy 132.096158 -268.296413) (xy 132.111742 -268.343094) (xy 132.119637 -268.391671) (xy 132.120132 -268.416278)
			(xy 132.44882 -268.416278) (xy 132.45278 -268.367224) (xy 132.464557 -268.31944) (xy 132.483848 -268.274164)
			(xy 132.510151 -268.232568) (xy 132.542786 -268.195731) (xy 132.580907 -268.164606) (xy 132.623528 -268.139999)
			(xy 132.669544 -268.122547) (xy 132.717763 -268.112703) (xy 132.766938 -268.110722) (xy 132.815793 -268.116654)
			(xy 132.863064 -268.130346) (xy 132.907526 -268.151444) (xy 132.948029 -268.1794) (xy 132.983522 -268.213492)
			(xy 133.013087 -268.252836) (xy 133.035958 -268.296413) (xy 133.051542 -268.343094) (xy 133.059437 -268.391671)
			(xy 133.059932 -268.416278) (xy 133.388874 -268.416278) (xy 133.392834 -268.367224) (xy 133.404611 -268.31944)
			(xy 133.423902 -268.274164) (xy 133.450205 -268.232568) (xy 133.48284 -268.195731) (xy 133.520961 -268.164606)
			(xy 133.563582 -268.139999) (xy 133.609598 -268.122547) (xy 133.657817 -268.112703) (xy 133.706992 -268.110722)
			(xy 133.755847 -268.116654) (xy 133.803118 -268.130346) (xy 133.84758 -268.151444) (xy 133.888083 -268.1794)
			(xy 133.923576 -268.213492) (xy 133.953141 -268.252836) (xy 133.976012 -268.296413) (xy 133.991596 -268.343094)
			(xy 133.999491 -268.391671) (xy 133.999986 -268.416278) (xy 134.328928 -268.416278) (xy 134.332888 -268.367224)
			(xy 134.344665 -268.31944) (xy 134.363956 -268.274164) (xy 134.390259 -268.232568) (xy 134.422894 -268.195731)
			(xy 134.461015 -268.164606) (xy 134.503636 -268.139999) (xy 134.549652 -268.122547) (xy 134.597871 -268.112703)
			(xy 134.647046 -268.110722) (xy 134.695901 -268.116654) (xy 134.743172 -268.130346) (xy 134.787634 -268.151444)
			(xy 134.828137 -268.1794) (xy 134.86363 -268.213492) (xy 134.893195 -268.252836) (xy 134.916066 -268.296413)
			(xy 134.93165 -268.343094) (xy 134.939545 -268.391671) (xy 134.94004 -268.416278) (xy 135.268982 -268.416278)
			(xy 135.272942 -268.367224) (xy 135.284719 -268.31944) (xy 135.30401 -268.274164) (xy 135.330313 -268.232568)
			(xy 135.362948 -268.195731) (xy 135.401069 -268.164606) (xy 135.44369 -268.139999) (xy 135.489706 -268.122547)
			(xy 135.537925 -268.112703) (xy 135.5871 -268.110722) (xy 135.635955 -268.116654) (xy 135.683226 -268.130346)
			(xy 135.727688 -268.151444) (xy 135.768191 -268.1794) (xy 135.803684 -268.213492) (xy 135.833249 -268.252836)
			(xy 135.85612 -268.296413) (xy 135.871704 -268.343094) (xy 135.879599 -268.391671) (xy 135.880094 -268.416278)
			(xy 136.209036 -268.416278) (xy 136.212996 -268.367224) (xy 136.224773 -268.31944) (xy 136.244064 -268.274164)
			(xy 136.270367 -268.232568) (xy 136.303002 -268.195731) (xy 136.341123 -268.164606) (xy 136.383744 -268.139999)
			(xy 136.42976 -268.122547) (xy 136.477979 -268.112703) (xy 136.527154 -268.110722) (xy 136.576009 -268.116654)
			(xy 136.62328 -268.130346) (xy 136.667742 -268.151444) (xy 136.708245 -268.1794) (xy 136.743738 -268.213492)
			(xy 136.773303 -268.252836) (xy 136.796174 -268.296413) (xy 136.811758 -268.343094) (xy 136.819653 -268.391671)
			(xy 136.820148 -268.416278) (xy 136.819653 -268.440885) (xy 136.811758 -268.489462) (xy 136.796174 -268.536143)
			(xy 136.773303 -268.57972) (xy 136.743738 -268.619064) (xy 136.708245 -268.653156) (xy 136.667742 -268.681112)
			(xy 136.62328 -268.70221) (xy 136.576009 -268.715902) (xy 136.527154 -268.721834) (xy 136.477979 -268.719853)
			(xy 136.42976 -268.710009) (xy 136.383744 -268.692557) (xy 136.341123 -268.66795) (xy 136.303002 -268.636825)
			(xy 136.270367 -268.599988) (xy 136.244064 -268.558392) (xy 136.224773 -268.513116) (xy 136.212996 -268.465332)
			(xy 136.209036 -268.416278) (xy 135.880094 -268.416278) (xy 135.879599 -268.440885) (xy 135.871704 -268.489462)
			(xy 135.85612 -268.536143) (xy 135.833249 -268.57972) (xy 135.803684 -268.619064) (xy 135.768191 -268.653156)
			(xy 135.727688 -268.681112) (xy 135.683226 -268.70221) (xy 135.635955 -268.715902) (xy 135.5871 -268.721834)
			(xy 135.537925 -268.719853) (xy 135.489706 -268.710009) (xy 135.44369 -268.692557) (xy 135.401069 -268.66795)
			(xy 135.362948 -268.636825) (xy 135.330313 -268.599988) (xy 135.30401 -268.558392) (xy 135.284719 -268.513116)
			(xy 135.272942 -268.465332) (xy 135.268982 -268.416278) (xy 134.94004 -268.416278) (xy 134.939545 -268.440885)
			(xy 134.93165 -268.489462) (xy 134.916066 -268.536143) (xy 134.893195 -268.57972) (xy 134.86363 -268.619064)
			(xy 134.828137 -268.653156) (xy 134.787634 -268.681112) (xy 134.743172 -268.70221) (xy 134.695901 -268.715902)
			(xy 134.647046 -268.721834) (xy 134.597871 -268.719853) (xy 134.549652 -268.710009) (xy 134.503636 -268.692557)
			(xy 134.461015 -268.66795) (xy 134.422894 -268.636825) (xy 134.390259 -268.599988) (xy 134.363956 -268.558392)
			(xy 134.344665 -268.513116) (xy 134.332888 -268.465332) (xy 134.328928 -268.416278) (xy 133.999986 -268.416278)
			(xy 133.999491 -268.440885) (xy 133.991596 -268.489462) (xy 133.976012 -268.536143) (xy 133.953141 -268.57972)
			(xy 133.923576 -268.619064) (xy 133.888083 -268.653156) (xy 133.84758 -268.681112) (xy 133.803118 -268.70221)
			(xy 133.755847 -268.715902) (xy 133.706992 -268.721834) (xy 133.657817 -268.719853) (xy 133.609598 -268.710009)
			(xy 133.563582 -268.692557) (xy 133.520961 -268.66795) (xy 133.48284 -268.636825) (xy 133.450205 -268.599988)
			(xy 133.423902 -268.558392) (xy 133.404611 -268.513116) (xy 133.392834 -268.465332) (xy 133.388874 -268.416278)
			(xy 133.059932 -268.416278) (xy 133.059437 -268.440885) (xy 133.051542 -268.489462) (xy 133.035958 -268.536143)
			(xy 133.013087 -268.57972) (xy 132.983522 -268.619064) (xy 132.948029 -268.653156) (xy 132.907526 -268.681112)
			(xy 132.863064 -268.70221) (xy 132.815793 -268.715902) (xy 132.766938 -268.721834) (xy 132.717763 -268.719853)
			(xy 132.669544 -268.710009) (xy 132.623528 -268.692557) (xy 132.580907 -268.66795) (xy 132.542786 -268.636825)
			(xy 132.510151 -268.599988) (xy 132.483848 -268.558392) (xy 132.464557 -268.513116) (xy 132.45278 -268.465332)
			(xy 132.44882 -268.416278) (xy 132.120132 -268.416278) (xy 132.119637 -268.440885) (xy 132.111742 -268.489462)
			(xy 132.096158 -268.536143) (xy 132.073287 -268.57972) (xy 132.043722 -268.619064) (xy 132.008229 -268.653156)
			(xy 131.967726 -268.681112) (xy 131.923264 -268.70221) (xy 131.875993 -268.715902) (xy 131.827138 -268.721834)
			(xy 131.777963 -268.719853) (xy 131.729744 -268.710009) (xy 131.683728 -268.692557) (xy 131.641107 -268.66795)
			(xy 131.602986 -268.636825) (xy 131.570351 -268.599988) (xy 131.544048 -268.558392) (xy 131.524757 -268.513116)
			(xy 131.51298 -268.465332) (xy 131.50902 -268.416278) (xy 130.240024 -268.416278) (xy 130.239529 -268.440885)
			(xy 130.231634 -268.489462) (xy 130.21605 -268.536143) (xy 130.193179 -268.57972) (xy 130.163614 -268.619064)
			(xy 130.128121 -268.653156) (xy 130.087618 -268.681112) (xy 130.043156 -268.70221) (xy 129.995885 -268.715902)
			(xy 129.94703 -268.721834) (xy 129.897855 -268.719853) (xy 129.849636 -268.710009) (xy 129.80362 -268.692557)
			(xy 129.760999 -268.66795) (xy 129.722878 -268.636825) (xy 129.690243 -268.599988) (xy 129.66394 -268.558392)
			(xy 129.644649 -268.513116) (xy 129.632872 -268.465332) (xy 129.628912 -268.416278) (xy 129.29997 -268.416278)
			(xy 129.299475 -268.440885) (xy 129.29158 -268.489462) (xy 129.275996 -268.536143) (xy 129.253125 -268.57972)
			(xy 129.22356 -268.619064) (xy 129.188067 -268.653156) (xy 129.147564 -268.681112) (xy 129.103102 -268.70221)
			(xy 129.055831 -268.715902) (xy 129.006976 -268.721834) (xy 128.957801 -268.719853) (xy 128.909582 -268.710009)
			(xy 128.863566 -268.692557) (xy 128.820945 -268.66795) (xy 128.782824 -268.636825) (xy 128.750189 -268.599988)
			(xy 128.723886 -268.558392) (xy 128.704595 -268.513116) (xy 128.692818 -268.465332) (xy 128.688858 -268.416278)
			(xy 128.36017 -268.416278) (xy 128.359675 -268.440885) (xy 128.35178 -268.489462) (xy 128.336196 -268.536143)
			(xy 128.313325 -268.57972) (xy 128.28376 -268.619064) (xy 128.248267 -268.653156) (xy 128.207764 -268.681112)
			(xy 128.163302 -268.70221) (xy 128.116031 -268.715902) (xy 128.067176 -268.721834) (xy 128.018001 -268.719853)
			(xy 127.969782 -268.710009) (xy 127.923766 -268.692557) (xy 127.881145 -268.66795) (xy 127.843024 -268.636825)
			(xy 127.810389 -268.599988) (xy 127.784086 -268.558392) (xy 127.764795 -268.513116) (xy 127.753018 -268.465332)
			(xy 127.749058 -268.416278) (xy 127.457454 -268.416278) (xy 127.457454 -268.820138) (xy 127.457952 -268.830565)
			(xy 127.466203 -268.849717) (xy 127.473456 -268.857222) (xy 127.535178 -268.915134) (xy 127.554482 -268.922246)
			(xy 127.56515 -268.921484) (xy 127.584708 -268.920976) (xy 127.609964 -268.921498) (xy 127.659788 -268.929813)
			(xy 127.707563 -268.946216) (xy 127.751987 -268.970258) (xy 127.791848 -269.001284) (xy 127.826058 -269.038448)
			(xy 127.853686 -269.080735) (xy 127.873976 -269.126993) (xy 127.886376 -269.17596) (xy 127.890546 -269.226284)
			(xy 128.218958 -269.226284) (xy 128.222918 -269.17723) (xy 128.234695 -269.129446) (xy 128.253986 -269.08417)
			(xy 128.280289 -269.042574) (xy 128.312924 -269.005737) (xy 128.351045 -268.974612) (xy 128.393666 -268.950005)
			(xy 128.439682 -268.932553) (xy 128.487901 -268.922709) (xy 128.537076 -268.920728) (xy 128.585931 -268.92666)
			(xy 128.633202 -268.940352) (xy 128.677664 -268.96145) (xy 128.718167 -268.989406) (xy 128.75366 -269.023498)
			(xy 128.783225 -269.062842) (xy 128.806096 -269.106419) (xy 128.82168 -269.1531) (xy 128.829575 -269.201677)
			(xy 128.83007 -269.226284) (xy 129.148581 -269.226284) (xy 129.152676 -269.175556) (xy 129.164855 -269.126142)
			(xy 129.184803 -269.079322) (xy 129.212004 -269.036308) (xy 129.245752 -268.998214) (xy 129.285174 -268.966027)
			(xy 129.329248 -268.940581) (xy 129.376834 -268.922534) (xy 129.426698 -268.912354) (xy 129.47755 -268.910305)
			(xy 129.528071 -268.916439) (xy 129.576955 -268.930599) (xy 129.622934 -268.952416) (xy 129.664818 -268.981326)
			(xy 129.701522 -269.016581) (xy 129.732095 -269.057267) (xy 129.755746 -269.10233) (xy 129.771862 -269.150604)
			(xy 129.780026 -269.200838) (xy 129.780538 -269.226284) (xy 130.099066 -269.226284) (xy 130.103026 -269.17723)
			(xy 130.114803 -269.129446) (xy 130.134094 -269.08417) (xy 130.160397 -269.042574) (xy 130.193032 -269.005737)
			(xy 130.231153 -268.974612) (xy 130.273774 -268.950005) (xy 130.31979 -268.932553) (xy 130.368009 -268.922709)
			(xy 130.417184 -268.920728) (xy 130.466039 -268.92666) (xy 130.51331 -268.940352) (xy 130.557772 -268.96145)
			(xy 130.598275 -268.989406) (xy 130.633768 -269.023498) (xy 130.663333 -269.062842) (xy 130.686204 -269.106419)
			(xy 130.701788 -269.1531) (xy 130.709683 -269.201677) (xy 130.710178 -269.226284) (xy 131.038866 -269.226284)
			(xy 131.042826 -269.17723) (xy 131.054603 -269.129446) (xy 131.073894 -269.08417) (xy 131.100197 -269.042574)
			(xy 131.132832 -269.005737) (xy 131.170953 -268.974612) (xy 131.213574 -268.950005) (xy 131.25959 -268.932553)
			(xy 131.307809 -268.922709) (xy 131.356984 -268.920728) (xy 131.405839 -268.92666) (xy 131.45311 -268.940352)
			(xy 131.497572 -268.96145) (xy 131.538075 -268.989406) (xy 131.573568 -269.023498) (xy 131.603133 -269.062842)
			(xy 131.626004 -269.106419) (xy 131.641588 -269.1531) (xy 131.649483 -269.201677) (xy 131.649978 -269.226284)
			(xy 131.97892 -269.226284) (xy 131.98288 -269.17723) (xy 131.994657 -269.129446) (xy 132.013948 -269.08417)
			(xy 132.040251 -269.042574) (xy 132.072886 -269.005737) (xy 132.111007 -268.974612) (xy 132.153628 -268.950005)
			(xy 132.199644 -268.932553) (xy 132.247863 -268.922709) (xy 132.297038 -268.920728) (xy 132.345893 -268.92666)
			(xy 132.393164 -268.940352) (xy 132.437626 -268.96145) (xy 132.478129 -268.989406) (xy 132.513622 -269.023498)
			(xy 132.543187 -269.062842) (xy 132.566058 -269.106419) (xy 132.581642 -269.1531) (xy 132.589537 -269.201677)
			(xy 132.590032 -269.226284) (xy 132.908543 -269.226284) (xy 132.912638 -269.175556) (xy 132.924817 -269.126142)
			(xy 132.944765 -269.079322) (xy 132.971966 -269.036308) (xy 133.005714 -268.998214) (xy 133.045136 -268.966027)
			(xy 133.08921 -268.940581) (xy 133.136796 -268.922534) (xy 133.18666 -268.912354) (xy 133.237512 -268.910305)
			(xy 133.288033 -268.916439) (xy 133.336917 -268.930599) (xy 133.382896 -268.952416) (xy 133.42478 -268.981326)
			(xy 133.461484 -269.016581) (xy 133.492057 -269.057267) (xy 133.515708 -269.10233) (xy 133.531824 -269.150604)
			(xy 133.539988 -269.200838) (xy 133.5405 -269.226284) (xy 133.859028 -269.226284) (xy 133.862988 -269.17723)
			(xy 133.874765 -269.129446) (xy 133.894056 -269.08417) (xy 133.920359 -269.042574) (xy 133.952994 -269.005737)
			(xy 133.991115 -268.974612) (xy 134.033736 -268.950005) (xy 134.079752 -268.932553) (xy 134.127971 -268.922709)
			(xy 134.177146 -268.920728) (xy 134.226001 -268.92666) (xy 134.273272 -268.940352) (xy 134.317734 -268.96145)
			(xy 134.358237 -268.989406) (xy 134.39373 -269.023498) (xy 134.423295 -269.062842) (xy 134.446166 -269.106419)
			(xy 134.46175 -269.1531) (xy 134.469645 -269.201677) (xy 134.47014 -269.226284) (xy 134.798828 -269.226284)
			(xy 134.802788 -269.17723) (xy 134.814565 -269.129446) (xy 134.833856 -269.08417) (xy 134.860159 -269.042574)
			(xy 134.892794 -269.005737) (xy 134.930915 -268.974612) (xy 134.973536 -268.950005) (xy 135.019552 -268.932553)
			(xy 135.067771 -268.922709) (xy 135.116946 -268.920728) (xy 135.165801 -268.92666) (xy 135.213072 -268.940352)
			(xy 135.257534 -268.96145) (xy 135.298037 -268.989406) (xy 135.33353 -269.023498) (xy 135.363095 -269.062842)
			(xy 135.385966 -269.106419) (xy 135.40155 -269.1531) (xy 135.409445 -269.201677) (xy 135.40994 -269.226284)
			(xy 135.738882 -269.226284) (xy 135.742842 -269.17723) (xy 135.754619 -269.129446) (xy 135.77391 -269.08417)
			(xy 135.800213 -269.042574) (xy 135.832848 -269.005737) (xy 135.870969 -268.974612) (xy 135.91359 -268.950005)
			(xy 135.959606 -268.932553) (xy 136.007825 -268.922709) (xy 136.057 -268.920728) (xy 136.105855 -268.92666)
			(xy 136.153126 -268.940352) (xy 136.197588 -268.96145) (xy 136.238091 -268.989406) (xy 136.273584 -269.023498)
			(xy 136.303149 -269.062842) (xy 136.32602 -269.106419) (xy 136.341604 -269.1531) (xy 136.349499 -269.201677)
			(xy 136.349994 -269.226284) (xy 136.678936 -269.226284) (xy 136.682896 -269.17723) (xy 136.694673 -269.129446)
			(xy 136.713964 -269.08417) (xy 136.740267 -269.042574) (xy 136.772902 -269.005737) (xy 136.811023 -268.974612)
			(xy 136.853644 -268.950005) (xy 136.89966 -268.932553) (xy 136.947879 -268.922709) (xy 136.997054 -268.920728)
			(xy 137.045909 -268.92666) (xy 137.09318 -268.940352) (xy 137.137642 -268.96145) (xy 137.178145 -268.989406)
			(xy 137.213638 -269.023498) (xy 137.243203 -269.062842) (xy 137.266074 -269.106419) (xy 137.281658 -269.1531)
			(xy 137.289553 -269.201677) (xy 137.290048 -269.226284) (xy 137.289553 -269.250891) (xy 137.281658 -269.299468)
			(xy 137.266074 -269.346149) (xy 137.243203 -269.389726) (xy 137.213638 -269.42907) (xy 137.178145 -269.463162)
			(xy 137.137642 -269.491118) (xy 137.09318 -269.512216) (xy 137.045909 -269.525908) (xy 136.997054 -269.53184)
			(xy 136.947879 -269.529859) (xy 136.89966 -269.520015) (xy 136.853644 -269.502563) (xy 136.811023 -269.477956)
			(xy 136.772902 -269.446831) (xy 136.740267 -269.409994) (xy 136.713964 -269.368398) (xy 136.694673 -269.323122)
			(xy 136.682896 -269.275338) (xy 136.678936 -269.226284) (xy 136.349994 -269.226284) (xy 136.349499 -269.250891)
			(xy 136.341604 -269.299468) (xy 136.32602 -269.346149) (xy 136.303149 -269.389726) (xy 136.273584 -269.42907)
			(xy 136.238091 -269.463162) (xy 136.197588 -269.491118) (xy 136.153126 -269.512216) (xy 136.105855 -269.525908)
			(xy 136.057 -269.53184) (xy 136.007825 -269.529859) (xy 135.959606 -269.520015) (xy 135.91359 -269.502563)
			(xy 135.870969 -269.477956) (xy 135.832848 -269.446831) (xy 135.800213 -269.409994) (xy 135.77391 -269.368398)
			(xy 135.754619 -269.323122) (xy 135.742842 -269.275338) (xy 135.738882 -269.226284) (xy 135.40994 -269.226284)
			(xy 135.409445 -269.250891) (xy 135.40155 -269.299468) (xy 135.385966 -269.346149) (xy 135.363095 -269.389726)
			(xy 135.33353 -269.42907) (xy 135.298037 -269.463162) (xy 135.257534 -269.491118) (xy 135.213072 -269.512216)
			(xy 135.165801 -269.525908) (xy 135.116946 -269.53184) (xy 135.067771 -269.529859) (xy 135.019552 -269.520015)
			(xy 134.973536 -269.502563) (xy 134.930915 -269.477956) (xy 134.892794 -269.446831) (xy 134.860159 -269.409994)
			(xy 134.833856 -269.368398) (xy 134.814565 -269.323122) (xy 134.802788 -269.275338) (xy 134.798828 -269.226284)
			(xy 134.47014 -269.226284) (xy 134.469645 -269.250891) (xy 134.46175 -269.299468) (xy 134.446166 -269.346149)
			(xy 134.423295 -269.389726) (xy 134.39373 -269.42907) (xy 134.358237 -269.463162) (xy 134.317734 -269.491118)
			(xy 134.273272 -269.512216) (xy 134.226001 -269.525908) (xy 134.177146 -269.53184) (xy 134.127971 -269.529859)
			(xy 134.079752 -269.520015) (xy 134.033736 -269.502563) (xy 133.991115 -269.477956) (xy 133.952994 -269.446831)
			(xy 133.920359 -269.409994) (xy 133.894056 -269.368398) (xy 133.874765 -269.323122) (xy 133.862988 -269.275338)
			(xy 133.859028 -269.226284) (xy 133.5405 -269.226284) (xy 133.539988 -269.25173) (xy 133.531824 -269.301964)
			(xy 133.515708 -269.350238) (xy 133.492057 -269.395301) (xy 133.461484 -269.435987) (xy 133.42478 -269.471242)
			(xy 133.382896 -269.500152) (xy 133.336917 -269.521969) (xy 133.288033 -269.536129) (xy 133.237512 -269.542263)
			(xy 133.18666 -269.540214) (xy 133.136796 -269.530034) (xy 133.08921 -269.511987) (xy 133.045136 -269.486541)
			(xy 133.005714 -269.454354) (xy 132.971966 -269.41626) (xy 132.944765 -269.373246) (xy 132.924817 -269.326426)
			(xy 132.912638 -269.277012) (xy 132.908543 -269.226284) (xy 132.590032 -269.226284) (xy 132.589537 -269.250891)
			(xy 132.581642 -269.299468) (xy 132.566058 -269.346149) (xy 132.543187 -269.389726) (xy 132.513622 -269.42907)
			(xy 132.478129 -269.463162) (xy 132.437626 -269.491118) (xy 132.393164 -269.512216) (xy 132.345893 -269.525908)
			(xy 132.297038 -269.53184) (xy 132.247863 -269.529859) (xy 132.199644 -269.520015) (xy 132.153628 -269.502563)
			(xy 132.111007 -269.477956) (xy 132.072886 -269.446831) (xy 132.040251 -269.409994) (xy 132.013948 -269.368398)
			(xy 131.994657 -269.323122) (xy 131.98288 -269.275338) (xy 131.97892 -269.226284) (xy 131.649978 -269.226284)
			(xy 131.649483 -269.250891) (xy 131.641588 -269.299468) (xy 131.626004 -269.346149) (xy 131.603133 -269.389726)
			(xy 131.573568 -269.42907) (xy 131.538075 -269.463162) (xy 131.497572 -269.491118) (xy 131.45311 -269.512216)
			(xy 131.405839 -269.525908) (xy 131.356984 -269.53184) (xy 131.307809 -269.529859) (xy 131.25959 -269.520015)
			(xy 131.213574 -269.502563) (xy 131.170953 -269.477956) (xy 131.132832 -269.446831) (xy 131.100197 -269.409994)
			(xy 131.073894 -269.368398) (xy 131.054603 -269.323122) (xy 131.042826 -269.275338) (xy 131.038866 -269.226284)
			(xy 130.710178 -269.226284) (xy 130.709683 -269.250891) (xy 130.701788 -269.299468) (xy 130.686204 -269.346149)
			(xy 130.663333 -269.389726) (xy 130.633768 -269.42907) (xy 130.598275 -269.463162) (xy 130.557772 -269.491118)
			(xy 130.51331 -269.512216) (xy 130.466039 -269.525908) (xy 130.417184 -269.53184) (xy 130.368009 -269.529859)
			(xy 130.31979 -269.520015) (xy 130.273774 -269.502563) (xy 130.231153 -269.477956) (xy 130.193032 -269.446831)
			(xy 130.160397 -269.409994) (xy 130.134094 -269.368398) (xy 130.114803 -269.323122) (xy 130.103026 -269.275338)
			(xy 130.099066 -269.226284) (xy 129.780538 -269.226284) (xy 129.780026 -269.25173) (xy 129.771862 -269.301964)
			(xy 129.755746 -269.350238) (xy 129.732095 -269.395301) (xy 129.701522 -269.435987) (xy 129.664818 -269.471242)
			(xy 129.622934 -269.500152) (xy 129.576955 -269.521969) (xy 129.528071 -269.536129) (xy 129.47755 -269.542263)
			(xy 129.426698 -269.540214) (xy 129.376834 -269.530034) (xy 129.329248 -269.511987) (xy 129.285174 -269.486541)
			(xy 129.245752 -269.454354) (xy 129.212004 -269.41626) (xy 129.184803 -269.373246) (xy 129.164855 -269.326426)
			(xy 129.152676 -269.277012) (xy 129.148581 -269.226284) (xy 128.83007 -269.226284) (xy 128.829575 -269.250891)
			(xy 128.82168 -269.299468) (xy 128.806096 -269.346149) (xy 128.783225 -269.389726) (xy 128.75366 -269.42907)
			(xy 128.718167 -269.463162) (xy 128.677664 -269.491118) (xy 128.633202 -269.512216) (xy 128.585931 -269.525908)
			(xy 128.537076 -269.53184) (xy 128.487901 -269.529859) (xy 128.439682 -269.520015) (xy 128.393666 -269.502563)
			(xy 128.351045 -269.477956) (xy 128.312924 -269.446831) (xy 128.280289 -269.409994) (xy 128.253986 -269.368398)
			(xy 128.234695 -269.323122) (xy 128.222918 -269.275338) (xy 128.218958 -269.226284) (xy 127.890546 -269.226284)
			(xy 127.890547 -269.2263) (xy 127.886376 -269.27664) (xy 127.873976 -269.325607) (xy 127.853686 -269.371865)
			(xy 127.826058 -269.414152) (xy 127.791848 -269.451316) (xy 127.751987 -269.482342) (xy 127.707563 -269.506384)
			(xy 127.659788 -269.522787) (xy 127.609964 -269.531102) (xy 127.584708 -269.531592) (xy 127.56515 -269.531084)
			(xy 127.554482 -269.530322) (xy 127.535178 -269.537434) (xy 127.473456 -269.595346) (xy 127.466236 -269.602797)
			(xy 127.457991 -269.621813) (xy 127.457454 -269.632176) (xy 127.457454 -270.03629) (xy 127.738627 -270.03629)
			(xy 127.742722 -269.985562) (xy 127.754901 -269.936148) (xy 127.774849 -269.889328) (xy 127.80205 -269.846314)
			(xy 127.835798 -269.80822) (xy 127.87522 -269.776033) (xy 127.919294 -269.750587) (xy 127.96688 -269.73254)
			(xy 128.016744 -269.72236) (xy 128.067596 -269.720311) (xy 128.118117 -269.726445) (xy 128.167001 -269.740605)
			(xy 128.21298 -269.762422) (xy 128.254864 -269.791332) (xy 128.291568 -269.826587) (xy 128.322141 -269.867273)
			(xy 128.345792 -269.912336) (xy 128.361908 -269.96061) (xy 128.370072 -270.010844) (xy 128.370584 -270.03629)
			(xy 128.688858 -270.03629) (xy 128.692818 -269.987236) (xy 128.704595 -269.939452) (xy 128.723886 -269.894176)
			(xy 128.750189 -269.85258) (xy 128.782824 -269.815743) (xy 128.820945 -269.784618) (xy 128.863566 -269.760011)
			(xy 128.909582 -269.742559) (xy 128.957801 -269.732715) (xy 129.006976 -269.730734) (xy 129.055831 -269.736666)
			(xy 129.103102 -269.750358) (xy 129.147564 -269.771456) (xy 129.188067 -269.799412) (xy 129.22356 -269.833504)
			(xy 129.253125 -269.872848) (xy 129.275996 -269.916425) (xy 129.29158 -269.963106) (xy 129.299475 -270.011683)
			(xy 129.29997 -270.03629) (xy 129.618481 -270.03629) (xy 129.622576 -269.985562) (xy 129.634755 -269.936148)
			(xy 129.654703 -269.889328) (xy 129.681904 -269.846314) (xy 129.715652 -269.80822) (xy 129.755074 -269.776033)
			(xy 129.799148 -269.750587) (xy 129.846734 -269.73254) (xy 129.896598 -269.72236) (xy 129.94745 -269.720311)
			(xy 129.997971 -269.726445) (xy 130.046855 -269.740605) (xy 130.092834 -269.762422) (xy 130.134718 -269.791332)
			(xy 130.171422 -269.826587) (xy 130.201995 -269.867273) (xy 130.225646 -269.912336) (xy 130.241762 -269.96061)
			(xy 130.249926 -270.010844) (xy 130.250438 -270.03629) (xy 130.568966 -270.03629) (xy 130.572926 -269.987236)
			(xy 130.584703 -269.939452) (xy 130.603994 -269.894176) (xy 130.630297 -269.85258) (xy 130.662932 -269.815743)
			(xy 130.701053 -269.784618) (xy 130.743674 -269.760011) (xy 130.78969 -269.742559) (xy 130.837909 -269.732715)
			(xy 130.887084 -269.730734) (xy 130.935939 -269.736666) (xy 130.98321 -269.750358) (xy 131.027672 -269.771456)
			(xy 131.068175 -269.799412) (xy 131.103668 -269.833504) (xy 131.133233 -269.872848) (xy 131.156104 -269.916425)
			(xy 131.171688 -269.963106) (xy 131.179583 -270.011683) (xy 131.180078 -270.03629) (xy 131.498589 -270.03629)
			(xy 131.502684 -269.985562) (xy 131.514863 -269.936148) (xy 131.534811 -269.889328) (xy 131.562012 -269.846314)
			(xy 131.59576 -269.80822) (xy 131.635182 -269.776033) (xy 131.679256 -269.750587) (xy 131.726842 -269.73254)
			(xy 131.776706 -269.72236) (xy 131.827558 -269.720311) (xy 131.878079 -269.726445) (xy 131.926963 -269.740605)
			(xy 131.972942 -269.762422) (xy 132.014826 -269.791332) (xy 132.05153 -269.826587) (xy 132.082103 -269.867273)
			(xy 132.105754 -269.912336) (xy 132.12187 -269.96061) (xy 132.130034 -270.010844) (xy 132.130546 -270.03629)
			(xy 132.438643 -270.03629) (xy 132.442738 -269.985562) (xy 132.454917 -269.936148) (xy 132.474865 -269.889328)
			(xy 132.502066 -269.846314) (xy 132.535814 -269.80822) (xy 132.575236 -269.776033) (xy 132.61931 -269.750587)
			(xy 132.666896 -269.73254) (xy 132.71676 -269.72236) (xy 132.767612 -269.720311) (xy 132.818133 -269.726445)
			(xy 132.867017 -269.740605) (xy 132.912996 -269.762422) (xy 132.95488 -269.791332) (xy 132.991584 -269.826587)
			(xy 133.022157 -269.867273) (xy 133.045808 -269.912336) (xy 133.061924 -269.96061) (xy 133.070088 -270.010844)
			(xy 133.0706 -270.03629) (xy 133.388874 -270.03629) (xy 133.392834 -269.987236) (xy 133.404611 -269.939452)
			(xy 133.423902 -269.894176) (xy 133.450205 -269.85258) (xy 133.48284 -269.815743) (xy 133.520961 -269.784618)
			(xy 133.563582 -269.760011) (xy 133.609598 -269.742559) (xy 133.657817 -269.732715) (xy 133.706992 -269.730734)
			(xy 133.755847 -269.736666) (xy 133.803118 -269.750358) (xy 133.84758 -269.771456) (xy 133.888083 -269.799412)
			(xy 133.923576 -269.833504) (xy 133.953141 -269.872848) (xy 133.976012 -269.916425) (xy 133.991596 -269.963106)
			(xy 133.999491 -270.011683) (xy 133.999986 -270.03629) (xy 134.328928 -270.03629) (xy 134.332888 -269.987236)
			(xy 134.344665 -269.939452) (xy 134.363956 -269.894176) (xy 134.390259 -269.85258) (xy 134.422894 -269.815743)
			(xy 134.461015 -269.784618) (xy 134.503636 -269.760011) (xy 134.549652 -269.742559) (xy 134.597871 -269.732715)
			(xy 134.647046 -269.730734) (xy 134.695901 -269.736666) (xy 134.743172 -269.750358) (xy 134.787634 -269.771456)
			(xy 134.828137 -269.799412) (xy 134.86363 -269.833504) (xy 134.893195 -269.872848) (xy 134.916066 -269.916425)
			(xy 134.93165 -269.963106) (xy 134.939545 -270.011683) (xy 134.94004 -270.03629) (xy 135.268982 -270.03629)
			(xy 135.272942 -269.987236) (xy 135.284719 -269.939452) (xy 135.30401 -269.894176) (xy 135.330313 -269.85258)
			(xy 135.362948 -269.815743) (xy 135.401069 -269.784618) (xy 135.44369 -269.760011) (xy 135.489706 -269.742559)
			(xy 135.537925 -269.732715) (xy 135.5871 -269.730734) (xy 135.635955 -269.736666) (xy 135.683226 -269.750358)
			(xy 135.727688 -269.771456) (xy 135.768191 -269.799412) (xy 135.803684 -269.833504) (xy 135.833249 -269.872848)
			(xy 135.85612 -269.916425) (xy 135.871704 -269.963106) (xy 135.879599 -270.011683) (xy 135.880094 -270.03629)
			(xy 136.209036 -270.03629) (xy 136.212996 -269.987236) (xy 136.224773 -269.939452) (xy 136.244064 -269.894176)
			(xy 136.270367 -269.85258) (xy 136.303002 -269.815743) (xy 136.341123 -269.784618) (xy 136.383744 -269.760011)
			(xy 136.42976 -269.742559) (xy 136.477979 -269.732715) (xy 136.527154 -269.730734) (xy 136.576009 -269.736666)
			(xy 136.62328 -269.750358) (xy 136.667742 -269.771456) (xy 136.708245 -269.799412) (xy 136.743738 -269.833504)
			(xy 136.773303 -269.872848) (xy 136.796174 -269.916425) (xy 136.811758 -269.963106) (xy 136.819653 -270.011683)
			(xy 136.820148 -270.03629) (xy 136.819653 -270.060897) (xy 136.811758 -270.109474) (xy 136.796174 -270.156155)
			(xy 136.773303 -270.199732) (xy 136.743738 -270.239076) (xy 136.708245 -270.273168) (xy 136.667742 -270.301124)
			(xy 136.62328 -270.322222) (xy 136.576009 -270.335914) (xy 136.527154 -270.341846) (xy 136.477979 -270.339865)
			(xy 136.42976 -270.330021) (xy 136.383744 -270.312569) (xy 136.341123 -270.287962) (xy 136.303002 -270.256837)
			(xy 136.270367 -270.22) (xy 136.244064 -270.178404) (xy 136.224773 -270.133128) (xy 136.212996 -270.085344)
			(xy 136.209036 -270.03629) (xy 135.880094 -270.03629) (xy 135.879599 -270.060897) (xy 135.871704 -270.109474)
			(xy 135.85612 -270.156155) (xy 135.833249 -270.199732) (xy 135.803684 -270.239076) (xy 135.768191 -270.273168)
			(xy 135.727688 -270.301124) (xy 135.683226 -270.322222) (xy 135.635955 -270.335914) (xy 135.5871 -270.341846)
			(xy 135.537925 -270.339865) (xy 135.489706 -270.330021) (xy 135.44369 -270.312569) (xy 135.401069 -270.287962)
			(xy 135.362948 -270.256837) (xy 135.330313 -270.22) (xy 135.30401 -270.178404) (xy 135.284719 -270.133128)
			(xy 135.272942 -270.085344) (xy 135.268982 -270.03629) (xy 134.94004 -270.03629) (xy 134.939545 -270.060897)
			(xy 134.93165 -270.109474) (xy 134.916066 -270.156155) (xy 134.893195 -270.199732) (xy 134.86363 -270.239076)
			(xy 134.828137 -270.273168) (xy 134.787634 -270.301124) (xy 134.743172 -270.322222) (xy 134.695901 -270.335914)
			(xy 134.647046 -270.341846) (xy 134.597871 -270.339865) (xy 134.549652 -270.330021) (xy 134.503636 -270.312569)
			(xy 134.461015 -270.287962) (xy 134.422894 -270.256837) (xy 134.390259 -270.22) (xy 134.363956 -270.178404)
			(xy 134.344665 -270.133128) (xy 134.332888 -270.085344) (xy 134.328928 -270.03629) (xy 133.999986 -270.03629)
			(xy 133.999491 -270.060897) (xy 133.991596 -270.109474) (xy 133.976012 -270.156155) (xy 133.953141 -270.199732)
			(xy 133.923576 -270.239076) (xy 133.888083 -270.273168) (xy 133.84758 -270.301124) (xy 133.803118 -270.322222)
			(xy 133.755847 -270.335914) (xy 133.706992 -270.341846) (xy 133.657817 -270.339865) (xy 133.609598 -270.330021)
			(xy 133.563582 -270.312569) (xy 133.520961 -270.287962) (xy 133.48284 -270.256837) (xy 133.450205 -270.22)
			(xy 133.423902 -270.178404) (xy 133.404611 -270.133128) (xy 133.392834 -270.085344) (xy 133.388874 -270.03629)
			(xy 133.0706 -270.03629) (xy 133.070088 -270.061736) (xy 133.061924 -270.11197) (xy 133.045808 -270.160244)
			(xy 133.022157 -270.205307) (xy 132.991584 -270.245993) (xy 132.95488 -270.281248) (xy 132.912996 -270.310158)
			(xy 132.867017 -270.331975) (xy 132.818133 -270.346135) (xy 132.767612 -270.352269) (xy 132.71676 -270.35022)
			(xy 132.666896 -270.34004) (xy 132.61931 -270.321993) (xy 132.575236 -270.296547) (xy 132.535814 -270.26436)
			(xy 132.502066 -270.226266) (xy 132.474865 -270.183252) (xy 132.454917 -270.136432) (xy 132.442738 -270.087018)
			(xy 132.438643 -270.03629) (xy 132.130546 -270.03629) (xy 132.130034 -270.061736) (xy 132.12187 -270.11197)
			(xy 132.105754 -270.160244) (xy 132.082103 -270.205307) (xy 132.05153 -270.245993) (xy 132.014826 -270.281248)
			(xy 131.972942 -270.310158) (xy 131.926963 -270.331975) (xy 131.878079 -270.346135) (xy 131.827558 -270.352269)
			(xy 131.776706 -270.35022) (xy 131.726842 -270.34004) (xy 131.679256 -270.321993) (xy 131.635182 -270.296547)
			(xy 131.59576 -270.26436) (xy 131.562012 -270.226266) (xy 131.534811 -270.183252) (xy 131.514863 -270.136432)
			(xy 131.502684 -270.087018) (xy 131.498589 -270.03629) (xy 131.180078 -270.03629) (xy 131.179583 -270.060897)
			(xy 131.171688 -270.109474) (xy 131.156104 -270.156155) (xy 131.133233 -270.199732) (xy 131.103668 -270.239076)
			(xy 131.068175 -270.273168) (xy 131.027672 -270.301124) (xy 130.98321 -270.322222) (xy 130.935939 -270.335914)
			(xy 130.887084 -270.341846) (xy 130.837909 -270.339865) (xy 130.78969 -270.330021) (xy 130.743674 -270.312569)
			(xy 130.701053 -270.287962) (xy 130.662932 -270.256837) (xy 130.630297 -270.22) (xy 130.603994 -270.178404)
			(xy 130.584703 -270.133128) (xy 130.572926 -270.085344) (xy 130.568966 -270.03629) (xy 130.250438 -270.03629)
			(xy 130.249926 -270.061736) (xy 130.241762 -270.11197) (xy 130.225646 -270.160244) (xy 130.201995 -270.205307)
			(xy 130.171422 -270.245993) (xy 130.134718 -270.281248) (xy 130.092834 -270.310158) (xy 130.046855 -270.331975)
			(xy 129.997971 -270.346135) (xy 129.94745 -270.352269) (xy 129.896598 -270.35022) (xy 129.846734 -270.34004)
			(xy 129.799148 -270.321993) (xy 129.755074 -270.296547) (xy 129.715652 -270.26436) (xy 129.681904 -270.226266)
			(xy 129.654703 -270.183252) (xy 129.634755 -270.136432) (xy 129.622576 -270.087018) (xy 129.618481 -270.03629)
			(xy 129.29997 -270.03629) (xy 129.299475 -270.060897) (xy 129.29158 -270.109474) (xy 129.275996 -270.156155)
			(xy 129.253125 -270.199732) (xy 129.22356 -270.239076) (xy 129.188067 -270.273168) (xy 129.147564 -270.301124)
			(xy 129.103102 -270.322222) (xy 129.055831 -270.335914) (xy 129.006976 -270.341846) (xy 128.957801 -270.339865)
			(xy 128.909582 -270.330021) (xy 128.863566 -270.312569) (xy 128.820945 -270.287962) (xy 128.782824 -270.256837)
			(xy 128.750189 -270.22) (xy 128.723886 -270.178404) (xy 128.704595 -270.133128) (xy 128.692818 -270.085344)
			(xy 128.688858 -270.03629) (xy 128.370584 -270.03629) (xy 128.370072 -270.061736) (xy 128.361908 -270.11197)
			(xy 128.345792 -270.160244) (xy 128.322141 -270.205307) (xy 128.291568 -270.245993) (xy 128.254864 -270.281248)
			(xy 128.21298 -270.310158) (xy 128.167001 -270.331975) (xy 128.118117 -270.346135) (xy 128.067596 -270.352269)
			(xy 128.016744 -270.35022) (xy 127.96688 -270.34004) (xy 127.919294 -270.321993) (xy 127.87522 -270.296547)
			(xy 127.835798 -270.26436) (xy 127.80205 -270.226266) (xy 127.774849 -270.183252) (xy 127.754901 -270.136432)
			(xy 127.742722 -270.087018) (xy 127.738627 -270.03629) (xy 127.457454 -270.03629) (xy 127.457454 -270.603472)
			(xy 127.461264 -270.61668) (xy 127.46482 -270.622776) (xy 127.468217 -270.628709) (xy 127.471963 -270.641852)
			(xy 127.472186 -270.648684) (xy 127.472186 -270.846296) (xy 128.208527 -270.846296) (xy 128.212622 -270.795568)
			(xy 128.224801 -270.746154) (xy 128.244749 -270.699334) (xy 128.27195 -270.65632) (xy 128.305698 -270.618226)
			(xy 128.34512 -270.586039) (xy 128.389194 -270.560593) (xy 128.43678 -270.542546) (xy 128.486644 -270.532366)
			(xy 128.537496 -270.530317) (xy 128.588017 -270.536451) (xy 128.636901 -270.550611) (xy 128.68288 -270.572428)
			(xy 128.724764 -270.601338) (xy 128.761468 -270.636593) (xy 128.792041 -270.677279) (xy 128.815692 -270.722342)
			(xy 128.831808 -270.770616) (xy 128.839972 -270.82085) (xy 128.840484 -270.846296) (xy 129.148581 -270.846296)
			(xy 129.152676 -270.795568) (xy 129.164855 -270.746154) (xy 129.184803 -270.699334) (xy 129.212004 -270.65632)
			(xy 129.245752 -270.618226) (xy 129.285174 -270.586039) (xy 129.329248 -270.560593) (xy 129.376834 -270.542546)
			(xy 129.426698 -270.532366) (xy 129.47755 -270.530317) (xy 129.528071 -270.536451) (xy 129.576955 -270.550611)
			(xy 129.622934 -270.572428) (xy 129.664818 -270.601338) (xy 129.701522 -270.636593) (xy 129.732095 -270.677279)
			(xy 129.755746 -270.722342) (xy 129.771862 -270.770616) (xy 129.780026 -270.82085) (xy 129.780538 -270.846296)
			(xy 131.028435 -270.846296) (xy 131.03253 -270.795568) (xy 131.044709 -270.746154) (xy 131.064657 -270.699334)
			(xy 131.091858 -270.65632) (xy 131.125606 -270.618226) (xy 131.165028 -270.586039) (xy 131.209102 -270.560593)
			(xy 131.256688 -270.542546) (xy 131.306552 -270.532366) (xy 131.357404 -270.530317) (xy 131.407925 -270.536451)
			(xy 131.456809 -270.550611) (xy 131.502788 -270.572428) (xy 131.544672 -270.601338) (xy 131.581376 -270.636593)
			(xy 131.611949 -270.677279) (xy 131.6356 -270.722342) (xy 131.651716 -270.770616) (xy 131.65988 -270.82085)
			(xy 131.660392 -270.846296) (xy 131.97892 -270.846296) (xy 131.98288 -270.797242) (xy 131.994657 -270.749458)
			(xy 132.013948 -270.704182) (xy 132.040251 -270.662586) (xy 132.072886 -270.625749) (xy 132.111007 -270.594624)
			(xy 132.153628 -270.570017) (xy 132.199644 -270.552565) (xy 132.247863 -270.542721) (xy 132.297038 -270.54074)
			(xy 132.345893 -270.546672) (xy 132.393164 -270.560364) (xy 132.437626 -270.581462) (xy 132.478129 -270.609418)
			(xy 132.513622 -270.64351) (xy 132.543187 -270.682854) (xy 132.566058 -270.726431) (xy 132.581642 -270.773112)
			(xy 132.589537 -270.821689) (xy 132.590032 -270.846296) (xy 132.908543 -270.846296) (xy 132.912638 -270.795568)
			(xy 132.924817 -270.746154) (xy 132.944765 -270.699334) (xy 132.971966 -270.65632) (xy 133.005714 -270.618226)
			(xy 133.045136 -270.586039) (xy 133.08921 -270.560593) (xy 133.136796 -270.542546) (xy 133.18666 -270.532366)
			(xy 133.237512 -270.530317) (xy 133.288033 -270.536451) (xy 133.336917 -270.550611) (xy 133.382896 -270.572428)
			(xy 133.42478 -270.601338) (xy 133.461484 -270.636593) (xy 133.492057 -270.677279) (xy 133.515708 -270.722342)
			(xy 133.531824 -270.770616) (xy 133.539988 -270.82085) (xy 133.5405 -270.846296) (xy 133.859028 -270.846296)
			(xy 133.862988 -270.797242) (xy 133.874765 -270.749458) (xy 133.894056 -270.704182) (xy 133.920359 -270.662586)
			(xy 133.952994 -270.625749) (xy 133.991115 -270.594624) (xy 134.033736 -270.570017) (xy 134.079752 -270.552565)
			(xy 134.127971 -270.542721) (xy 134.177146 -270.54074) (xy 134.226001 -270.546672) (xy 134.273272 -270.560364)
			(xy 134.317734 -270.581462) (xy 134.358237 -270.609418) (xy 134.39373 -270.64351) (xy 134.423295 -270.682854)
			(xy 134.446166 -270.726431) (xy 134.46175 -270.773112) (xy 134.469645 -270.821689) (xy 134.47014 -270.846296)
			(xy 134.798828 -270.846296) (xy 134.802788 -270.797242) (xy 134.814565 -270.749458) (xy 134.833856 -270.704182)
			(xy 134.860159 -270.662586) (xy 134.892794 -270.625749) (xy 134.930915 -270.594624) (xy 134.973536 -270.570017)
			(xy 135.019552 -270.552565) (xy 135.067771 -270.542721) (xy 135.116946 -270.54074) (xy 135.165801 -270.546672)
			(xy 135.213072 -270.560364) (xy 135.257534 -270.581462) (xy 135.298037 -270.609418) (xy 135.33353 -270.64351)
			(xy 135.363095 -270.682854) (xy 135.385966 -270.726431) (xy 135.40155 -270.773112) (xy 135.409445 -270.821689)
			(xy 135.40994 -270.846296) (xy 135.738882 -270.846296) (xy 135.742842 -270.797242) (xy 135.754619 -270.749458)
			(xy 135.77391 -270.704182) (xy 135.800213 -270.662586) (xy 135.832848 -270.625749) (xy 135.870969 -270.594624)
			(xy 135.91359 -270.570017) (xy 135.959606 -270.552565) (xy 136.007825 -270.542721) (xy 136.057 -270.54074)
			(xy 136.105855 -270.546672) (xy 136.153126 -270.560364) (xy 136.197588 -270.581462) (xy 136.238091 -270.609418)
			(xy 136.273584 -270.64351) (xy 136.303149 -270.682854) (xy 136.32602 -270.726431) (xy 136.341604 -270.773112)
			(xy 136.349499 -270.821689) (xy 136.349994 -270.846296) (xy 136.349499 -270.870903) (xy 136.341604 -270.91948)
			(xy 136.32602 -270.966161) (xy 136.303149 -271.009738) (xy 136.273584 -271.049082) (xy 136.238091 -271.083174)
			(xy 136.197588 -271.11113) (xy 136.153126 -271.132228) (xy 136.105855 -271.14592) (xy 136.057 -271.151852)
			(xy 136.007825 -271.149871) (xy 135.959606 -271.140027) (xy 135.91359 -271.122575) (xy 135.870969 -271.097968)
			(xy 135.832848 -271.066843) (xy 135.800213 -271.030006) (xy 135.77391 -270.98841) (xy 135.754619 -270.943134)
			(xy 135.742842 -270.89535) (xy 135.738882 -270.846296) (xy 135.40994 -270.846296) (xy 135.409445 -270.870903)
			(xy 135.40155 -270.91948) (xy 135.385966 -270.966161) (xy 135.363095 -271.009738) (xy 135.33353 -271.049082)
			(xy 135.298037 -271.083174) (xy 135.257534 -271.11113) (xy 135.213072 -271.132228) (xy 135.165801 -271.14592)
			(xy 135.116946 -271.151852) (xy 135.067771 -271.149871) (xy 135.019552 -271.140027) (xy 134.973536 -271.122575)
			(xy 134.930915 -271.097968) (xy 134.892794 -271.066843) (xy 134.860159 -271.030006) (xy 134.833856 -270.98841)
			(xy 134.814565 -270.943134) (xy 134.802788 -270.89535) (xy 134.798828 -270.846296) (xy 134.47014 -270.846296)
			(xy 134.469645 -270.870903) (xy 134.46175 -270.91948) (xy 134.446166 -270.966161) (xy 134.423295 -271.009738)
			(xy 134.39373 -271.049082) (xy 134.358237 -271.083174) (xy 134.317734 -271.11113) (xy 134.273272 -271.132228)
			(xy 134.226001 -271.14592) (xy 134.177146 -271.151852) (xy 134.127971 -271.149871) (xy 134.079752 -271.140027)
			(xy 134.033736 -271.122575) (xy 133.991115 -271.097968) (xy 133.952994 -271.066843) (xy 133.920359 -271.030006)
			(xy 133.894056 -270.98841) (xy 133.874765 -270.943134) (xy 133.862988 -270.89535) (xy 133.859028 -270.846296)
			(xy 133.5405 -270.846296) (xy 133.539988 -270.871742) (xy 133.531824 -270.921976) (xy 133.515708 -270.97025)
			(xy 133.492057 -271.015313) (xy 133.461484 -271.055999) (xy 133.42478 -271.091254) (xy 133.382896 -271.120164)
			(xy 133.336917 -271.141981) (xy 133.288033 -271.156141) (xy 133.237512 -271.162275) (xy 133.18666 -271.160226)
			(xy 133.136796 -271.150046) (xy 133.08921 -271.131999) (xy 133.045136 -271.106553) (xy 133.005714 -271.074366)
			(xy 132.971966 -271.036272) (xy 132.944765 -270.993258) (xy 132.924817 -270.946438) (xy 132.912638 -270.897024)
			(xy 132.908543 -270.846296) (xy 132.590032 -270.846296) (xy 132.589537 -270.870903) (xy 132.581642 -270.91948)
			(xy 132.566058 -270.966161) (xy 132.543187 -271.009738) (xy 132.513622 -271.049082) (xy 132.478129 -271.083174)
			(xy 132.437626 -271.11113) (xy 132.393164 -271.132228) (xy 132.345893 -271.14592) (xy 132.297038 -271.151852)
			(xy 132.247863 -271.149871) (xy 132.199644 -271.140027) (xy 132.153628 -271.122575) (xy 132.111007 -271.097968)
			(xy 132.072886 -271.066843) (xy 132.040251 -271.030006) (xy 132.013948 -270.98841) (xy 131.994657 -270.943134)
			(xy 131.98288 -270.89535) (xy 131.97892 -270.846296) (xy 131.660392 -270.846296) (xy 131.65988 -270.871742)
			(xy 131.651716 -270.921976) (xy 131.6356 -270.97025) (xy 131.611949 -271.015313) (xy 131.581376 -271.055999)
			(xy 131.544672 -271.091254) (xy 131.502788 -271.120164) (xy 131.456809 -271.141981) (xy 131.407925 -271.156141)
			(xy 131.357404 -271.162275) (xy 131.306552 -271.160226) (xy 131.256688 -271.150046) (xy 131.209102 -271.131999)
			(xy 131.165028 -271.106553) (xy 131.125606 -271.074366) (xy 131.091858 -271.036272) (xy 131.064657 -270.993258)
			(xy 131.044709 -270.946438) (xy 131.03253 -270.897024) (xy 131.028435 -270.846296) (xy 129.780538 -270.846296)
			(xy 129.780026 -270.871742) (xy 129.771862 -270.921976) (xy 129.755746 -270.97025) (xy 129.732095 -271.015313)
			(xy 129.701522 -271.055999) (xy 129.664818 -271.091254) (xy 129.622934 -271.120164) (xy 129.576955 -271.141981)
			(xy 129.528071 -271.156141) (xy 129.47755 -271.162275) (xy 129.426698 -271.160226) (xy 129.376834 -271.150046)
			(xy 129.329248 -271.131999) (xy 129.285174 -271.106553) (xy 129.245752 -271.074366) (xy 129.212004 -271.036272)
			(xy 129.184803 -270.993258) (xy 129.164855 -270.946438) (xy 129.152676 -270.897024) (xy 129.148581 -270.846296)
			(xy 128.840484 -270.846296) (xy 128.839972 -270.871742) (xy 128.831808 -270.921976) (xy 128.815692 -270.97025)
			(xy 128.792041 -271.015313) (xy 128.761468 -271.055999) (xy 128.724764 -271.091254) (xy 128.68288 -271.120164)
			(xy 128.636901 -271.141981) (xy 128.588017 -271.156141) (xy 128.537496 -271.162275) (xy 128.486644 -271.160226)
			(xy 128.43678 -271.150046) (xy 128.389194 -271.131999) (xy 128.34512 -271.106553) (xy 128.305698 -271.074366)
			(xy 128.27195 -271.036272) (xy 128.244749 -270.993258) (xy 128.224801 -270.946438) (xy 128.212622 -270.897024)
			(xy 128.208527 -270.846296) (xy 127.472186 -270.846296) (xy 127.472186 -271.656302) (xy 127.738627 -271.656302)
			(xy 127.742722 -271.605574) (xy 127.754901 -271.55616) (xy 127.774849 -271.50934) (xy 127.80205 -271.466326)
			(xy 127.835798 -271.428232) (xy 127.87522 -271.396045) (xy 127.919294 -271.370599) (xy 127.96688 -271.352552)
			(xy 128.016744 -271.342372) (xy 128.067596 -271.340323) (xy 128.118117 -271.346457) (xy 128.167001 -271.360617)
			(xy 128.21298 -271.382434) (xy 128.254864 -271.411344) (xy 128.291568 -271.446599) (xy 128.322141 -271.487285)
			(xy 128.345792 -271.532348) (xy 128.361908 -271.580622) (xy 128.370072 -271.630856) (xy 128.370584 -271.656302)
			(xy 128.688858 -271.656302) (xy 128.692818 -271.607248) (xy 128.704595 -271.559464) (xy 128.723886 -271.514188)
			(xy 128.750189 -271.472592) (xy 128.782824 -271.435755) (xy 128.820945 -271.40463) (xy 128.863566 -271.380023)
			(xy 128.909582 -271.362571) (xy 128.957801 -271.352727) (xy 129.006976 -271.350746) (xy 129.055831 -271.356678)
			(xy 129.103102 -271.37037) (xy 129.147564 -271.391468) (xy 129.188067 -271.419424) (xy 129.22356 -271.453516)
			(xy 129.253125 -271.49286) (xy 129.275996 -271.536437) (xy 129.29158 -271.583118) (xy 129.299475 -271.631695)
			(xy 129.29997 -271.656302) (xy 129.618481 -271.656302) (xy 129.622576 -271.605574) (xy 129.634755 -271.55616)
			(xy 129.654703 -271.50934) (xy 129.681904 -271.466326) (xy 129.715652 -271.428232) (xy 129.755074 -271.396045)
			(xy 129.799148 -271.370599) (xy 129.846734 -271.352552) (xy 129.896598 -271.342372) (xy 129.94745 -271.340323)
			(xy 129.997971 -271.346457) (xy 130.046855 -271.360617) (xy 130.092834 -271.382434) (xy 130.134718 -271.411344)
			(xy 130.171422 -271.446599) (xy 130.201995 -271.487285) (xy 130.225646 -271.532348) (xy 130.241762 -271.580622)
			(xy 130.249926 -271.630856) (xy 130.250438 -271.656302) (xy 130.568966 -271.656302) (xy 130.572926 -271.607248)
			(xy 130.584703 -271.559464) (xy 130.603994 -271.514188) (xy 130.630297 -271.472592) (xy 130.662932 -271.435755)
			(xy 130.701053 -271.40463) (xy 130.743674 -271.380023) (xy 130.78969 -271.362571) (xy 130.837909 -271.352727)
			(xy 130.887084 -271.350746) (xy 130.935939 -271.356678) (xy 130.98321 -271.37037) (xy 131.027672 -271.391468)
			(xy 131.068175 -271.419424) (xy 131.103668 -271.453516) (xy 131.133233 -271.49286) (xy 131.156104 -271.536437)
			(xy 131.171688 -271.583118) (xy 131.179583 -271.631695) (xy 131.180078 -271.656302) (xy 131.498589 -271.656302)
			(xy 131.502684 -271.605574) (xy 131.514863 -271.55616) (xy 131.534811 -271.50934) (xy 131.562012 -271.466326)
			(xy 131.59576 -271.428232) (xy 131.635182 -271.396045) (xy 131.679256 -271.370599) (xy 131.726842 -271.352552)
			(xy 131.776706 -271.342372) (xy 131.827558 -271.340323) (xy 131.878079 -271.346457) (xy 131.926963 -271.360617)
			(xy 131.972942 -271.382434) (xy 132.014826 -271.411344) (xy 132.05153 -271.446599) (xy 132.082103 -271.487285)
			(xy 132.105754 -271.532348) (xy 132.12187 -271.580622) (xy 132.130034 -271.630856) (xy 132.130546 -271.656302)
			(xy 132.438643 -271.656302) (xy 132.442738 -271.605574) (xy 132.454917 -271.55616) (xy 132.474865 -271.50934)
			(xy 132.502066 -271.466326) (xy 132.535814 -271.428232) (xy 132.575236 -271.396045) (xy 132.61931 -271.370599)
			(xy 132.666896 -271.352552) (xy 132.71676 -271.342372) (xy 132.767612 -271.340323) (xy 132.818133 -271.346457)
			(xy 132.867017 -271.360617) (xy 132.912996 -271.382434) (xy 132.95488 -271.411344) (xy 132.991584 -271.446599)
			(xy 133.022157 -271.487285) (xy 133.045808 -271.532348) (xy 133.061924 -271.580622) (xy 133.070088 -271.630856)
			(xy 133.0706 -271.656302) (xy 133.388874 -271.656302) (xy 133.392834 -271.607248) (xy 133.404611 -271.559464)
			(xy 133.423902 -271.514188) (xy 133.450205 -271.472592) (xy 133.48284 -271.435755) (xy 133.520961 -271.40463)
			(xy 133.563582 -271.380023) (xy 133.609598 -271.362571) (xy 133.657817 -271.352727) (xy 133.706992 -271.350746)
			(xy 133.755847 -271.356678) (xy 133.803118 -271.37037) (xy 133.84758 -271.391468) (xy 133.888083 -271.419424)
			(xy 133.923576 -271.453516) (xy 133.953141 -271.49286) (xy 133.976012 -271.536437) (xy 133.991596 -271.583118)
			(xy 133.999491 -271.631695) (xy 133.999986 -271.656302) (xy 134.328928 -271.656302) (xy 134.332888 -271.607248)
			(xy 134.344665 -271.559464) (xy 134.363956 -271.514188) (xy 134.390259 -271.472592) (xy 134.422894 -271.435755)
			(xy 134.461015 -271.40463) (xy 134.503636 -271.380023) (xy 134.549652 -271.362571) (xy 134.597871 -271.352727)
			(xy 134.647046 -271.350746) (xy 134.695901 -271.356678) (xy 134.743172 -271.37037) (xy 134.787634 -271.391468)
			(xy 134.828137 -271.419424) (xy 134.86363 -271.453516) (xy 134.893195 -271.49286) (xy 134.916066 -271.536437)
			(xy 134.93165 -271.583118) (xy 134.939545 -271.631695) (xy 134.94004 -271.656302) (xy 135.268982 -271.656302)
			(xy 135.272942 -271.607248) (xy 135.284719 -271.559464) (xy 135.30401 -271.514188) (xy 135.330313 -271.472592)
			(xy 135.362948 -271.435755) (xy 135.401069 -271.40463) (xy 135.44369 -271.380023) (xy 135.489706 -271.362571)
			(xy 135.537925 -271.352727) (xy 135.5871 -271.350746) (xy 135.635955 -271.356678) (xy 135.683226 -271.37037)
			(xy 135.727688 -271.391468) (xy 135.768191 -271.419424) (xy 135.803684 -271.453516) (xy 135.833249 -271.49286)
			(xy 135.85612 -271.536437) (xy 135.871704 -271.583118) (xy 135.879599 -271.631695) (xy 135.880094 -271.656302)
			(xy 136.209036 -271.656302) (xy 136.212996 -271.607248) (xy 136.224773 -271.559464) (xy 136.244064 -271.514188)
			(xy 136.270367 -271.472592) (xy 136.303002 -271.435755) (xy 136.341123 -271.40463) (xy 136.383744 -271.380023)
			(xy 136.42976 -271.362571) (xy 136.477979 -271.352727) (xy 136.527154 -271.350746) (xy 136.576009 -271.356678)
			(xy 136.62328 -271.37037) (xy 136.667742 -271.391468) (xy 136.708245 -271.419424) (xy 136.743738 -271.453516)
			(xy 136.773303 -271.49286) (xy 136.796174 -271.536437) (xy 136.811758 -271.583118) (xy 136.819653 -271.631695)
			(xy 136.820148 -271.656302) (xy 136.819653 -271.680909) (xy 136.811758 -271.729486) (xy 136.796174 -271.776167)
			(xy 136.773303 -271.819744) (xy 136.743738 -271.859088) (xy 136.708245 -271.89318) (xy 136.667742 -271.921136)
			(xy 136.62328 -271.942234) (xy 136.576009 -271.955926) (xy 136.527154 -271.961858) (xy 136.477979 -271.959877)
			(xy 136.42976 -271.950033) (xy 136.383744 -271.932581) (xy 136.341123 -271.907974) (xy 136.303002 -271.876849)
			(xy 136.270367 -271.840012) (xy 136.244064 -271.798416) (xy 136.224773 -271.75314) (xy 136.212996 -271.705356)
			(xy 136.209036 -271.656302) (xy 135.880094 -271.656302) (xy 135.879599 -271.680909) (xy 135.871704 -271.729486)
			(xy 135.85612 -271.776167) (xy 135.833249 -271.819744) (xy 135.803684 -271.859088) (xy 135.768191 -271.89318)
			(xy 135.727688 -271.921136) (xy 135.683226 -271.942234) (xy 135.635955 -271.955926) (xy 135.5871 -271.961858)
			(xy 135.537925 -271.959877) (xy 135.489706 -271.950033) (xy 135.44369 -271.932581) (xy 135.401069 -271.907974)
			(xy 135.362948 -271.876849) (xy 135.330313 -271.840012) (xy 135.30401 -271.798416) (xy 135.284719 -271.75314)
			(xy 135.272942 -271.705356) (xy 135.268982 -271.656302) (xy 134.94004 -271.656302) (xy 134.939545 -271.680909)
			(xy 134.93165 -271.729486) (xy 134.916066 -271.776167) (xy 134.893195 -271.819744) (xy 134.86363 -271.859088)
			(xy 134.828137 -271.89318) (xy 134.787634 -271.921136) (xy 134.743172 -271.942234) (xy 134.695901 -271.955926)
			(xy 134.647046 -271.961858) (xy 134.597871 -271.959877) (xy 134.549652 -271.950033) (xy 134.503636 -271.932581)
			(xy 134.461015 -271.907974) (xy 134.422894 -271.876849) (xy 134.390259 -271.840012) (xy 134.363956 -271.798416)
			(xy 134.344665 -271.75314) (xy 134.332888 -271.705356) (xy 134.328928 -271.656302) (xy 133.999986 -271.656302)
			(xy 133.999491 -271.680909) (xy 133.991596 -271.729486) (xy 133.976012 -271.776167) (xy 133.953141 -271.819744)
			(xy 133.923576 -271.859088) (xy 133.888083 -271.89318) (xy 133.84758 -271.921136) (xy 133.803118 -271.942234)
			(xy 133.755847 -271.955926) (xy 133.706992 -271.961858) (xy 133.657817 -271.959877) (xy 133.609598 -271.950033)
			(xy 133.563582 -271.932581) (xy 133.520961 -271.907974) (xy 133.48284 -271.876849) (xy 133.450205 -271.840012)
			(xy 133.423902 -271.798416) (xy 133.404611 -271.75314) (xy 133.392834 -271.705356) (xy 133.388874 -271.656302)
			(xy 133.0706 -271.656302) (xy 133.070088 -271.681748) (xy 133.061924 -271.731982) (xy 133.045808 -271.780256)
			(xy 133.022157 -271.825319) (xy 132.991584 -271.866005) (xy 132.95488 -271.90126) (xy 132.912996 -271.93017)
			(xy 132.867017 -271.951987) (xy 132.818133 -271.966147) (xy 132.767612 -271.972281) (xy 132.71676 -271.970232)
			(xy 132.666896 -271.960052) (xy 132.61931 -271.942005) (xy 132.575236 -271.916559) (xy 132.535814 -271.884372)
			(xy 132.502066 -271.846278) (xy 132.474865 -271.803264) (xy 132.454917 -271.756444) (xy 132.442738 -271.70703)
			(xy 132.438643 -271.656302) (xy 132.130546 -271.656302) (xy 132.130034 -271.681748) (xy 132.12187 -271.731982)
			(xy 132.105754 -271.780256) (xy 132.082103 -271.825319) (xy 132.05153 -271.866005) (xy 132.014826 -271.90126)
			(xy 131.972942 -271.93017) (xy 131.926963 -271.951987) (xy 131.878079 -271.966147) (xy 131.827558 -271.972281)
			(xy 131.776706 -271.970232) (xy 131.726842 -271.960052) (xy 131.679256 -271.942005) (xy 131.635182 -271.916559)
			(xy 131.59576 -271.884372) (xy 131.562012 -271.846278) (xy 131.534811 -271.803264) (xy 131.514863 -271.756444)
			(xy 131.502684 -271.70703) (xy 131.498589 -271.656302) (xy 131.180078 -271.656302) (xy 131.179583 -271.680909)
			(xy 131.171688 -271.729486) (xy 131.156104 -271.776167) (xy 131.133233 -271.819744) (xy 131.103668 -271.859088)
			(xy 131.068175 -271.89318) (xy 131.027672 -271.921136) (xy 130.98321 -271.942234) (xy 130.935939 -271.955926)
			(xy 130.887084 -271.961858) (xy 130.837909 -271.959877) (xy 130.78969 -271.950033) (xy 130.743674 -271.932581)
			(xy 130.701053 -271.907974) (xy 130.662932 -271.876849) (xy 130.630297 -271.840012) (xy 130.603994 -271.798416)
			(xy 130.584703 -271.75314) (xy 130.572926 -271.705356) (xy 130.568966 -271.656302) (xy 130.250438 -271.656302)
			(xy 130.249926 -271.681748) (xy 130.241762 -271.731982) (xy 130.225646 -271.780256) (xy 130.201995 -271.825319)
			(xy 130.171422 -271.866005) (xy 130.134718 -271.90126) (xy 130.092834 -271.93017) (xy 130.046855 -271.951987)
			(xy 129.997971 -271.966147) (xy 129.94745 -271.972281) (xy 129.896598 -271.970232) (xy 129.846734 -271.960052)
			(xy 129.799148 -271.942005) (xy 129.755074 -271.916559) (xy 129.715652 -271.884372) (xy 129.681904 -271.846278)
			(xy 129.654703 -271.803264) (xy 129.634755 -271.756444) (xy 129.622576 -271.70703) (xy 129.618481 -271.656302)
			(xy 129.29997 -271.656302) (xy 129.299475 -271.680909) (xy 129.29158 -271.729486) (xy 129.275996 -271.776167)
			(xy 129.253125 -271.819744) (xy 129.22356 -271.859088) (xy 129.188067 -271.89318) (xy 129.147564 -271.921136)
			(xy 129.103102 -271.942234) (xy 129.055831 -271.955926) (xy 129.006976 -271.961858) (xy 128.957801 -271.959877)
			(xy 128.909582 -271.950033) (xy 128.863566 -271.932581) (xy 128.820945 -271.907974) (xy 128.782824 -271.876849)
			(xy 128.750189 -271.840012) (xy 128.723886 -271.798416) (xy 128.704595 -271.75314) (xy 128.692818 -271.705356)
			(xy 128.688858 -271.656302) (xy 128.370584 -271.656302) (xy 128.370072 -271.681748) (xy 128.361908 -271.731982)
			(xy 128.345792 -271.780256) (xy 128.322141 -271.825319) (xy 128.291568 -271.866005) (xy 128.254864 -271.90126)
			(xy 128.21298 -271.93017) (xy 128.167001 -271.951987) (xy 128.118117 -271.966147) (xy 128.067596 -271.972281)
			(xy 128.016744 -271.970232) (xy 127.96688 -271.960052) (xy 127.919294 -271.942005) (xy 127.87522 -271.916559)
			(xy 127.835798 -271.884372) (xy 127.80205 -271.846278) (xy 127.774849 -271.803264) (xy 127.754901 -271.756444)
			(xy 127.742722 -271.70703) (xy 127.738627 -271.656302) (xy 127.472186 -271.656302) (xy 127.472186 -272.06067)
			(xy 127.472639 -272.070824) (xy 127.480504 -272.089548) (xy 127.487426 -272.096992) (xy 127.538226 -272.146522)
			(xy 127.542621 -272.150589) (xy 127.55289 -272.156746) (xy 127.558546 -272.158714) (xy 127.567182 -272.161508)
			(xy 127.58293 -272.161) (xy 127.584962 -272.161) (xy 127.610202 -272.161542) (xy 127.659989 -272.169889)
			(xy 127.707725 -272.186313) (xy 127.752108 -272.210366) (xy 127.79193 -272.241392) (xy 127.826105 -272.278547)
			(xy 127.853703 -272.320817) (xy 127.873971 -272.367052) (xy 127.886357 -272.41599) (xy 127.890523 -272.4663)
			(xy 127.890522 -272.466308) (xy 128.208527 -272.466308) (xy 128.212622 -272.41558) (xy 128.224801 -272.366166)
			(xy 128.244749 -272.319346) (xy 128.27195 -272.276332) (xy 128.305698 -272.238238) (xy 128.34512 -272.206051)
			(xy 128.389194 -272.180605) (xy 128.43678 -272.162558) (xy 128.486644 -272.152378) (xy 128.537496 -272.150329)
			(xy 128.588017 -272.156463) (xy 128.636901 -272.170623) (xy 128.68288 -272.19244) (xy 128.724764 -272.22135)
			(xy 128.761468 -272.256605) (xy 128.792041 -272.297291) (xy 128.815692 -272.342354) (xy 128.831808 -272.390628)
			(xy 128.839972 -272.440862) (xy 128.840484 -272.466308) (xy 129.148581 -272.466308) (xy 129.152676 -272.41558)
			(xy 129.164855 -272.366166) (xy 129.184803 -272.319346) (xy 129.212004 -272.276332) (xy 129.245752 -272.238238)
			(xy 129.285174 -272.206051) (xy 129.329248 -272.180605) (xy 129.376834 -272.162558) (xy 129.426698 -272.152378)
			(xy 129.47755 -272.150329) (xy 129.528071 -272.156463) (xy 129.576955 -272.170623) (xy 129.622934 -272.19244)
			(xy 129.664818 -272.22135) (xy 129.701522 -272.256605) (xy 129.732095 -272.297291) (xy 129.755746 -272.342354)
			(xy 129.771862 -272.390628) (xy 129.780026 -272.440862) (xy 129.780538 -272.466308) (xy 130.099066 -272.466308)
			(xy 130.103026 -272.417254) (xy 130.114803 -272.36947) (xy 130.134094 -272.324194) (xy 130.160397 -272.282598)
			(xy 130.193032 -272.245761) (xy 130.231153 -272.214636) (xy 130.273774 -272.190029) (xy 130.31979 -272.172577)
			(xy 130.368009 -272.162733) (xy 130.417184 -272.160752) (xy 130.466039 -272.166684) (xy 130.51331 -272.180376)
			(xy 130.557772 -272.201474) (xy 130.598275 -272.22943) (xy 130.633768 -272.263522) (xy 130.663333 -272.302866)
			(xy 130.686204 -272.346443) (xy 130.701788 -272.393124) (xy 130.709683 -272.441701) (xy 130.710178 -272.466308)
			(xy 131.028435 -272.466308) (xy 131.03253 -272.41558) (xy 131.044709 -272.366166) (xy 131.064657 -272.319346)
			(xy 131.091858 -272.276332) (xy 131.125606 -272.238238) (xy 131.165028 -272.206051) (xy 131.209102 -272.180605)
			(xy 131.256688 -272.162558) (xy 131.306552 -272.152378) (xy 131.357404 -272.150329) (xy 131.407925 -272.156463)
			(xy 131.456809 -272.170623) (xy 131.502788 -272.19244) (xy 131.544672 -272.22135) (xy 131.581376 -272.256605)
			(xy 131.611949 -272.297291) (xy 131.6356 -272.342354) (xy 131.651716 -272.390628) (xy 131.65988 -272.440862)
			(xy 131.660392 -272.466308) (xy 131.97892 -272.466308) (xy 131.98288 -272.417254) (xy 131.994657 -272.36947)
			(xy 132.013948 -272.324194) (xy 132.040251 -272.282598) (xy 132.072886 -272.245761) (xy 132.111007 -272.214636)
			(xy 132.153628 -272.190029) (xy 132.199644 -272.172577) (xy 132.247863 -272.162733) (xy 132.297038 -272.160752)
			(xy 132.345893 -272.166684) (xy 132.393164 -272.180376) (xy 132.437626 -272.201474) (xy 132.478129 -272.22943)
			(xy 132.513622 -272.263522) (xy 132.543187 -272.302866) (xy 132.566058 -272.346443) (xy 132.581642 -272.393124)
			(xy 132.589537 -272.441701) (xy 132.590032 -272.466308) (xy 132.908543 -272.466308) (xy 132.912638 -272.41558)
			(xy 132.924817 -272.366166) (xy 132.944765 -272.319346) (xy 132.971966 -272.276332) (xy 133.005714 -272.238238)
			(xy 133.045136 -272.206051) (xy 133.08921 -272.180605) (xy 133.136796 -272.162558) (xy 133.18666 -272.152378)
			(xy 133.237512 -272.150329) (xy 133.288033 -272.156463) (xy 133.336917 -272.170623) (xy 133.382896 -272.19244)
			(xy 133.42478 -272.22135) (xy 133.461484 -272.256605) (xy 133.492057 -272.297291) (xy 133.515708 -272.342354)
			(xy 133.531824 -272.390628) (xy 133.539988 -272.440862) (xy 133.5405 -272.466308) (xy 133.859028 -272.466308)
			(xy 133.862988 -272.417254) (xy 133.874765 -272.36947) (xy 133.894056 -272.324194) (xy 133.920359 -272.282598)
			(xy 133.952994 -272.245761) (xy 133.991115 -272.214636) (xy 134.033736 -272.190029) (xy 134.079752 -272.172577)
			(xy 134.127971 -272.162733) (xy 134.177146 -272.160752) (xy 134.226001 -272.166684) (xy 134.273272 -272.180376)
			(xy 134.317734 -272.201474) (xy 134.358237 -272.22943) (xy 134.39373 -272.263522) (xy 134.423295 -272.302866)
			(xy 134.446166 -272.346443) (xy 134.46175 -272.393124) (xy 134.469645 -272.441701) (xy 134.47014 -272.466308)
			(xy 134.798828 -272.466308) (xy 134.802788 -272.417254) (xy 134.814565 -272.36947) (xy 134.833856 -272.324194)
			(xy 134.860159 -272.282598) (xy 134.892794 -272.245761) (xy 134.930915 -272.214636) (xy 134.973536 -272.190029)
			(xy 135.019552 -272.172577) (xy 135.067771 -272.162733) (xy 135.116946 -272.160752) (xy 135.165801 -272.166684)
			(xy 135.213072 -272.180376) (xy 135.257534 -272.201474) (xy 135.298037 -272.22943) (xy 135.33353 -272.263522)
			(xy 135.363095 -272.302866) (xy 135.385966 -272.346443) (xy 135.40155 -272.393124) (xy 135.409445 -272.441701)
			(xy 135.40994 -272.466308) (xy 135.738882 -272.466308) (xy 135.742842 -272.417254) (xy 135.754619 -272.36947)
			(xy 135.77391 -272.324194) (xy 135.800213 -272.282598) (xy 135.832848 -272.245761) (xy 135.870969 -272.214636)
			(xy 135.91359 -272.190029) (xy 135.959606 -272.172577) (xy 136.007825 -272.162733) (xy 136.057 -272.160752)
			(xy 136.105855 -272.166684) (xy 136.153126 -272.180376) (xy 136.197588 -272.201474) (xy 136.238091 -272.22943)
			(xy 136.273584 -272.263522) (xy 136.303149 -272.302866) (xy 136.32602 -272.346443) (xy 136.341604 -272.393124)
			(xy 136.349499 -272.441701) (xy 136.349994 -272.466308) (xy 136.349499 -272.490915) (xy 136.341604 -272.539492)
			(xy 136.32602 -272.586173) (xy 136.303149 -272.62975) (xy 136.273584 -272.669094) (xy 136.238091 -272.703186)
			(xy 136.197588 -272.731142) (xy 136.153126 -272.75224) (xy 136.105855 -272.765932) (xy 136.057 -272.771864)
			(xy 136.007825 -272.769883) (xy 135.959606 -272.760039) (xy 135.91359 -272.742587) (xy 135.870969 -272.71798)
			(xy 135.832848 -272.686855) (xy 135.800213 -272.650018) (xy 135.77391 -272.608422) (xy 135.754619 -272.563146)
			(xy 135.742842 -272.515362) (xy 135.738882 -272.466308) (xy 135.40994 -272.466308) (xy 135.409445 -272.490915)
			(xy 135.40155 -272.539492) (xy 135.385966 -272.586173) (xy 135.363095 -272.62975) (xy 135.33353 -272.669094)
			(xy 135.298037 -272.703186) (xy 135.257534 -272.731142) (xy 135.213072 -272.75224) (xy 135.165801 -272.765932)
			(xy 135.116946 -272.771864) (xy 135.067771 -272.769883) (xy 135.019552 -272.760039) (xy 134.973536 -272.742587)
			(xy 134.930915 -272.71798) (xy 134.892794 -272.686855) (xy 134.860159 -272.650018) (xy 134.833856 -272.608422)
			(xy 134.814565 -272.563146) (xy 134.802788 -272.515362) (xy 134.798828 -272.466308) (xy 134.47014 -272.466308)
			(xy 134.469645 -272.490915) (xy 134.46175 -272.539492) (xy 134.446166 -272.586173) (xy 134.423295 -272.62975)
			(xy 134.39373 -272.669094) (xy 134.358237 -272.703186) (xy 134.317734 -272.731142) (xy 134.273272 -272.75224)
			(xy 134.226001 -272.765932) (xy 134.177146 -272.771864) (xy 134.127971 -272.769883) (xy 134.079752 -272.760039)
			(xy 134.033736 -272.742587) (xy 133.991115 -272.71798) (xy 133.952994 -272.686855) (xy 133.920359 -272.650018)
			(xy 133.894056 -272.608422) (xy 133.874765 -272.563146) (xy 133.862988 -272.515362) (xy 133.859028 -272.466308)
			(xy 133.5405 -272.466308) (xy 133.539988 -272.491754) (xy 133.531824 -272.541988) (xy 133.515708 -272.590262)
			(xy 133.492057 -272.635325) (xy 133.461484 -272.676011) (xy 133.42478 -272.711266) (xy 133.382896 -272.740176)
			(xy 133.336917 -272.761993) (xy 133.288033 -272.776153) (xy 133.237512 -272.782287) (xy 133.18666 -272.780238)
			(xy 133.136796 -272.770058) (xy 133.08921 -272.752011) (xy 133.045136 -272.726565) (xy 133.005714 -272.694378)
			(xy 132.971966 -272.656284) (xy 132.944765 -272.61327) (xy 132.924817 -272.56645) (xy 132.912638 -272.517036)
			(xy 132.908543 -272.466308) (xy 132.590032 -272.466308) (xy 132.589537 -272.490915) (xy 132.581642 -272.539492)
			(xy 132.566058 -272.586173) (xy 132.543187 -272.62975) (xy 132.513622 -272.669094) (xy 132.478129 -272.703186)
			(xy 132.437626 -272.731142) (xy 132.393164 -272.75224) (xy 132.345893 -272.765932) (xy 132.297038 -272.771864)
			(xy 132.247863 -272.769883) (xy 132.199644 -272.760039) (xy 132.153628 -272.742587) (xy 132.111007 -272.71798)
			(xy 132.072886 -272.686855) (xy 132.040251 -272.650018) (xy 132.013948 -272.608422) (xy 131.994657 -272.563146)
			(xy 131.98288 -272.515362) (xy 131.97892 -272.466308) (xy 131.660392 -272.466308) (xy 131.65988 -272.491754)
			(xy 131.651716 -272.541988) (xy 131.6356 -272.590262) (xy 131.611949 -272.635325) (xy 131.581376 -272.676011)
			(xy 131.544672 -272.711266) (xy 131.502788 -272.740176) (xy 131.456809 -272.761993) (xy 131.407925 -272.776153)
			(xy 131.357404 -272.782287) (xy 131.306552 -272.780238) (xy 131.256688 -272.770058) (xy 131.209102 -272.752011)
			(xy 131.165028 -272.726565) (xy 131.125606 -272.694378) (xy 131.091858 -272.656284) (xy 131.064657 -272.61327)
			(xy 131.044709 -272.56645) (xy 131.03253 -272.517036) (xy 131.028435 -272.466308) (xy 130.710178 -272.466308)
			(xy 130.709683 -272.490915) (xy 130.701788 -272.539492) (xy 130.686204 -272.586173) (xy 130.663333 -272.62975)
			(xy 130.633768 -272.669094) (xy 130.598275 -272.703186) (xy 130.557772 -272.731142) (xy 130.51331 -272.75224)
			(xy 130.466039 -272.765932) (xy 130.417184 -272.771864) (xy 130.368009 -272.769883) (xy 130.31979 -272.760039)
			(xy 130.273774 -272.742587) (xy 130.231153 -272.71798) (xy 130.193032 -272.686855) (xy 130.160397 -272.650018)
			(xy 130.134094 -272.608422) (xy 130.114803 -272.563146) (xy 130.103026 -272.515362) (xy 130.099066 -272.466308)
			(xy 129.780538 -272.466308) (xy 129.780026 -272.491754) (xy 129.771862 -272.541988) (xy 129.755746 -272.590262)
			(xy 129.732095 -272.635325) (xy 129.701522 -272.676011) (xy 129.664818 -272.711266) (xy 129.622934 -272.740176)
			(xy 129.576955 -272.761993) (xy 129.528071 -272.776153) (xy 129.47755 -272.782287) (xy 129.426698 -272.780238)
			(xy 129.376834 -272.770058) (xy 129.329248 -272.752011) (xy 129.285174 -272.726565) (xy 129.245752 -272.694378)
			(xy 129.212004 -272.656284) (xy 129.184803 -272.61327) (xy 129.164855 -272.56645) (xy 129.152676 -272.517036)
			(xy 129.148581 -272.466308) (xy 128.840484 -272.466308) (xy 128.839972 -272.491754) (xy 128.831808 -272.541988)
			(xy 128.815692 -272.590262) (xy 128.792041 -272.635325) (xy 128.761468 -272.676011) (xy 128.724764 -272.711266)
			(xy 128.68288 -272.740176) (xy 128.636901 -272.761993) (xy 128.588017 -272.776153) (xy 128.537496 -272.782287)
			(xy 128.486644 -272.780238) (xy 128.43678 -272.770058) (xy 128.389194 -272.752011) (xy 128.34512 -272.726565)
			(xy 128.305698 -272.694378) (xy 128.27195 -272.656284) (xy 128.244749 -272.61327) (xy 128.224801 -272.56645)
			(xy 128.212622 -272.517036) (xy 128.208527 -272.466308) (xy 127.890522 -272.466308) (xy 127.886357 -272.51661)
			(xy 127.873971 -272.565548) (xy 127.853703 -272.611783) (xy 127.826105 -272.654053) (xy 127.79193 -272.691208)
			(xy 127.752108 -272.722234) (xy 127.707725 -272.746287) (xy 127.659989 -272.762711) (xy 127.610202 -272.771058)
			(xy 127.584962 -272.771616) (xy 127.57277 -272.771616) (xy 127.561594 -272.773902) (xy 127.554609 -272.775619)
			(xy 127.541963 -272.782459) (xy 127.536702 -272.787364) (xy 127.487426 -272.835624) (xy 127.480504 -272.842914)
			(xy 127.47264 -272.861395) (xy 127.472186 -272.871438) (xy 127.472186 -273.276314) (xy 127.738627 -273.276314)
			(xy 127.742722 -273.225586) (xy 127.754901 -273.176172) (xy 127.774849 -273.129352) (xy 127.80205 -273.086338)
			(xy 127.835798 -273.048244) (xy 127.87522 -273.016057) (xy 127.919294 -272.990611) (xy 127.96688 -272.972564)
			(xy 128.016744 -272.962384) (xy 128.067596 -272.960335) (xy 128.118117 -272.966469) (xy 128.167001 -272.980629)
			(xy 128.21298 -273.002446) (xy 128.254864 -273.031356) (xy 128.291568 -273.066611) (xy 128.322141 -273.107297)
			(xy 128.345792 -273.15236) (xy 128.361908 -273.200634) (xy 128.370072 -273.250868) (xy 128.370584 -273.276314)
			(xy 128.688858 -273.276314) (xy 128.692818 -273.22726) (xy 128.704595 -273.179476) (xy 128.723886 -273.1342)
			(xy 128.750189 -273.092604) (xy 128.782824 -273.055767) (xy 128.820945 -273.024642) (xy 128.863566 -273.000035)
			(xy 128.909582 -272.982583) (xy 128.957801 -272.972739) (xy 129.006976 -272.970758) (xy 129.055831 -272.97669)
			(xy 129.103102 -272.990382) (xy 129.147564 -273.01148) (xy 129.188067 -273.039436) (xy 129.22356 -273.073528)
			(xy 129.253125 -273.112872) (xy 129.275996 -273.156449) (xy 129.29158 -273.20313) (xy 129.299475 -273.251707)
			(xy 129.29997 -273.276314) (xy 129.618481 -273.276314) (xy 129.622576 -273.225586) (xy 129.634755 -273.176172)
			(xy 129.654703 -273.129352) (xy 129.681904 -273.086338) (xy 129.715652 -273.048244) (xy 129.755074 -273.016057)
			(xy 129.799148 -272.990611) (xy 129.846734 -272.972564) (xy 129.896598 -272.962384) (xy 129.94745 -272.960335)
			(xy 129.997971 -272.966469) (xy 130.046855 -272.980629) (xy 130.092834 -273.002446) (xy 130.134718 -273.031356)
			(xy 130.171422 -273.066611) (xy 130.201995 -273.107297) (xy 130.225646 -273.15236) (xy 130.241762 -273.200634)
			(xy 130.249926 -273.250868) (xy 130.250438 -273.276314) (xy 131.498589 -273.276314) (xy 131.502684 -273.225586)
			(xy 131.514863 -273.176172) (xy 131.534811 -273.129352) (xy 131.562012 -273.086338) (xy 131.59576 -273.048244)
			(xy 131.635182 -273.016057) (xy 131.679256 -272.990611) (xy 131.726842 -272.972564) (xy 131.776706 -272.962384)
			(xy 131.827558 -272.960335) (xy 131.878079 -272.966469) (xy 131.926963 -272.980629) (xy 131.972942 -273.002446)
			(xy 132.014826 -273.031356) (xy 132.05153 -273.066611) (xy 132.082103 -273.107297) (xy 132.105754 -273.15236)
			(xy 132.12187 -273.200634) (xy 132.130034 -273.250868) (xy 132.130546 -273.276314) (xy 132.438643 -273.276314)
			(xy 132.442738 -273.225586) (xy 132.454917 -273.176172) (xy 132.474865 -273.129352) (xy 132.502066 -273.086338)
			(xy 132.535814 -273.048244) (xy 132.575236 -273.016057) (xy 132.61931 -272.990611) (xy 132.666896 -272.972564)
			(xy 132.71676 -272.962384) (xy 132.767612 -272.960335) (xy 132.818133 -272.966469) (xy 132.867017 -272.980629)
			(xy 132.912996 -273.002446) (xy 132.95488 -273.031356) (xy 132.991584 -273.066611) (xy 133.022157 -273.107297)
			(xy 133.045808 -273.15236) (xy 133.061924 -273.200634) (xy 133.070088 -273.250868) (xy 133.0706 -273.276314)
			(xy 133.388874 -273.276314) (xy 133.392834 -273.22726) (xy 133.404611 -273.179476) (xy 133.423902 -273.1342)
			(xy 133.450205 -273.092604) (xy 133.48284 -273.055767) (xy 133.520961 -273.024642) (xy 133.563582 -273.000035)
			(xy 133.609598 -272.982583) (xy 133.657817 -272.972739) (xy 133.706992 -272.970758) (xy 133.755847 -272.97669)
			(xy 133.803118 -272.990382) (xy 133.84758 -273.01148) (xy 133.888083 -273.039436) (xy 133.923576 -273.073528)
			(xy 133.953141 -273.112872) (xy 133.976012 -273.156449) (xy 133.991596 -273.20313) (xy 133.999491 -273.251707)
			(xy 133.999986 -273.276314) (xy 134.328928 -273.276314) (xy 134.332888 -273.22726) (xy 134.344665 -273.179476)
			(xy 134.363956 -273.1342) (xy 134.390259 -273.092604) (xy 134.422894 -273.055767) (xy 134.461015 -273.024642)
			(xy 134.503636 -273.000035) (xy 134.549652 -272.982583) (xy 134.597871 -272.972739) (xy 134.647046 -272.970758)
			(xy 134.695901 -272.97669) (xy 134.743172 -272.990382) (xy 134.787634 -273.01148) (xy 134.828137 -273.039436)
			(xy 134.86363 -273.073528) (xy 134.893195 -273.112872) (xy 134.916066 -273.156449) (xy 134.93165 -273.20313)
			(xy 134.939545 -273.251707) (xy 134.94004 -273.276314) (xy 135.268982 -273.276314) (xy 135.272942 -273.22726)
			(xy 135.284719 -273.179476) (xy 135.30401 -273.1342) (xy 135.330313 -273.092604) (xy 135.362948 -273.055767)
			(xy 135.401069 -273.024642) (xy 135.44369 -273.000035) (xy 135.489706 -272.982583) (xy 135.537925 -272.972739)
			(xy 135.5871 -272.970758) (xy 135.635955 -272.97669) (xy 135.683226 -272.990382) (xy 135.727688 -273.01148)
			(xy 135.768191 -273.039436) (xy 135.803684 -273.073528) (xy 135.833249 -273.112872) (xy 135.85612 -273.156449)
			(xy 135.871704 -273.20313) (xy 135.879599 -273.251707) (xy 135.880094 -273.276314) (xy 136.209036 -273.276314)
			(xy 136.212996 -273.22726) (xy 136.224773 -273.179476) (xy 136.244064 -273.1342) (xy 136.270367 -273.092604)
			(xy 136.303002 -273.055767) (xy 136.341123 -273.024642) (xy 136.383744 -273.000035) (xy 136.42976 -272.982583)
			(xy 136.477979 -272.972739) (xy 136.527154 -272.970758) (xy 136.576009 -272.97669) (xy 136.62328 -272.990382)
			(xy 136.667742 -273.01148) (xy 136.708245 -273.039436) (xy 136.743738 -273.073528) (xy 136.773303 -273.112872)
			(xy 136.796174 -273.156449) (xy 136.811758 -273.20313) (xy 136.819653 -273.251707) (xy 136.820148 -273.276314)
			(xy 136.819653 -273.300921) (xy 136.811758 -273.349498) (xy 136.796174 -273.396179) (xy 136.773303 -273.439756)
			(xy 136.743738 -273.4791) (xy 136.708245 -273.513192) (xy 136.667742 -273.541148) (xy 136.62328 -273.562246)
			(xy 136.576009 -273.575938) (xy 136.527154 -273.58187) (xy 136.477979 -273.579889) (xy 136.42976 -273.570045)
			(xy 136.383744 -273.552593) (xy 136.341123 -273.527986) (xy 136.303002 -273.496861) (xy 136.270367 -273.460024)
			(xy 136.244064 -273.418428) (xy 136.224773 -273.373152) (xy 136.212996 -273.325368) (xy 136.209036 -273.276314)
			(xy 135.880094 -273.276314) (xy 135.879599 -273.300921) (xy 135.871704 -273.349498) (xy 135.85612 -273.396179)
			(xy 135.833249 -273.439756) (xy 135.803684 -273.4791) (xy 135.768191 -273.513192) (xy 135.727688 -273.541148)
			(xy 135.683226 -273.562246) (xy 135.635955 -273.575938) (xy 135.5871 -273.58187) (xy 135.537925 -273.579889)
			(xy 135.489706 -273.570045) (xy 135.44369 -273.552593) (xy 135.401069 -273.527986) (xy 135.362948 -273.496861)
			(xy 135.330313 -273.460024) (xy 135.30401 -273.418428) (xy 135.284719 -273.373152) (xy 135.272942 -273.325368)
			(xy 135.268982 -273.276314) (xy 134.94004 -273.276314) (xy 134.939545 -273.300921) (xy 134.93165 -273.349498)
			(xy 134.916066 -273.396179) (xy 134.893195 -273.439756) (xy 134.86363 -273.4791) (xy 134.828137 -273.513192)
			(xy 134.787634 -273.541148) (xy 134.743172 -273.562246) (xy 134.695901 -273.575938) (xy 134.647046 -273.58187)
			(xy 134.597871 -273.579889) (xy 134.549652 -273.570045) (xy 134.503636 -273.552593) (xy 134.461015 -273.527986)
			(xy 134.422894 -273.496861) (xy 134.390259 -273.460024) (xy 134.363956 -273.418428) (xy 134.344665 -273.373152)
			(xy 134.332888 -273.325368) (xy 134.328928 -273.276314) (xy 133.999986 -273.276314) (xy 133.999491 -273.300921)
			(xy 133.991596 -273.349498) (xy 133.976012 -273.396179) (xy 133.953141 -273.439756) (xy 133.923576 -273.4791)
			(xy 133.888083 -273.513192) (xy 133.84758 -273.541148) (xy 133.803118 -273.562246) (xy 133.755847 -273.575938)
			(xy 133.706992 -273.58187) (xy 133.657817 -273.579889) (xy 133.609598 -273.570045) (xy 133.563582 -273.552593)
			(xy 133.520961 -273.527986) (xy 133.48284 -273.496861) (xy 133.450205 -273.460024) (xy 133.423902 -273.418428)
			(xy 133.404611 -273.373152) (xy 133.392834 -273.325368) (xy 133.388874 -273.276314) (xy 133.0706 -273.276314)
			(xy 133.070088 -273.30176) (xy 133.061924 -273.351994) (xy 133.045808 -273.400268) (xy 133.022157 -273.445331)
			(xy 132.991584 -273.486017) (xy 132.95488 -273.521272) (xy 132.912996 -273.550182) (xy 132.867017 -273.571999)
			(xy 132.818133 -273.586159) (xy 132.767612 -273.592293) (xy 132.71676 -273.590244) (xy 132.666896 -273.580064)
			(xy 132.61931 -273.562017) (xy 132.575236 -273.536571) (xy 132.535814 -273.504384) (xy 132.502066 -273.46629)
			(xy 132.474865 -273.423276) (xy 132.454917 -273.376456) (xy 132.442738 -273.327042) (xy 132.438643 -273.276314)
			(xy 132.130546 -273.276314) (xy 132.130034 -273.30176) (xy 132.12187 -273.351994) (xy 132.105754 -273.400268)
			(xy 132.082103 -273.445331) (xy 132.05153 -273.486017) (xy 132.014826 -273.521272) (xy 131.972942 -273.550182)
			(xy 131.926963 -273.571999) (xy 131.878079 -273.586159) (xy 131.827558 -273.592293) (xy 131.776706 -273.590244)
			(xy 131.726842 -273.580064) (xy 131.679256 -273.562017) (xy 131.635182 -273.536571) (xy 131.59576 -273.504384)
			(xy 131.562012 -273.46629) (xy 131.534811 -273.423276) (xy 131.514863 -273.376456) (xy 131.502684 -273.327042)
			(xy 131.498589 -273.276314) (xy 130.250438 -273.276314) (xy 130.249926 -273.30176) (xy 130.241762 -273.351994)
			(xy 130.225646 -273.400268) (xy 130.201995 -273.445331) (xy 130.171422 -273.486017) (xy 130.134718 -273.521272)
			(xy 130.092834 -273.550182) (xy 130.046855 -273.571999) (xy 129.997971 -273.586159) (xy 129.94745 -273.592293)
			(xy 129.896598 -273.590244) (xy 129.846734 -273.580064) (xy 129.799148 -273.562017) (xy 129.755074 -273.536571)
			(xy 129.715652 -273.504384) (xy 129.681904 -273.46629) (xy 129.654703 -273.423276) (xy 129.634755 -273.376456)
			(xy 129.622576 -273.327042) (xy 129.618481 -273.276314) (xy 129.29997 -273.276314) (xy 129.299475 -273.300921)
			(xy 129.29158 -273.349498) (xy 129.275996 -273.396179) (xy 129.253125 -273.439756) (xy 129.22356 -273.4791)
			(xy 129.188067 -273.513192) (xy 129.147564 -273.541148) (xy 129.103102 -273.562246) (xy 129.055831 -273.575938)
			(xy 129.006976 -273.58187) (xy 128.957801 -273.579889) (xy 128.909582 -273.570045) (xy 128.863566 -273.552593)
			(xy 128.820945 -273.527986) (xy 128.782824 -273.496861) (xy 128.750189 -273.460024) (xy 128.723886 -273.418428)
			(xy 128.704595 -273.373152) (xy 128.692818 -273.325368) (xy 128.688858 -273.276314) (xy 128.370584 -273.276314)
			(xy 128.370072 -273.30176) (xy 128.361908 -273.351994) (xy 128.345792 -273.400268) (xy 128.322141 -273.445331)
			(xy 128.291568 -273.486017) (xy 128.254864 -273.521272) (xy 128.21298 -273.550182) (xy 128.167001 -273.571999)
			(xy 128.118117 -273.586159) (xy 128.067596 -273.592293) (xy 128.016744 -273.590244) (xy 127.96688 -273.580064)
			(xy 127.919294 -273.562017) (xy 127.87522 -273.536571) (xy 127.835798 -273.504384) (xy 127.80205 -273.46629)
			(xy 127.774849 -273.423276) (xy 127.754901 -273.376456) (xy 127.742722 -273.327042) (xy 127.738627 -273.276314)
			(xy 127.472186 -273.276314) (xy 127.472186 -273.31543) (xy 127.484632 -273.347688) (xy 127.490474 -273.354546)
			(xy 127.490474 -273.3548) (xy 127.521865 -273.391882) (xy 127.578823 -273.470602) (xy 127.628738 -273.553965)
			(xy 127.671232 -273.641344) (xy 127.689102 -273.686524) (xy 127.695488 -273.703436) (xy 127.7073 -273.737606)
			(xy 127.712724 -273.75485) (xy 127.712978 -273.755358) (xy 127.71628 -273.765264) (xy 127.727456 -273.77898)
			(xy 127.728218 -273.779742) (xy 127.739648 -273.793966) (xy 127.74803 -273.798792) (xy 127.769468 -273.81149)
			(xy 127.808606 -273.842322) (xy 127.842676 -273.878676) (xy 127.870907 -273.919731) (xy 127.892658 -273.964556)
			(xy 127.907437 -274.012138) (xy 127.914911 -274.061398) (xy 127.91491 -274.08632) (xy 128.208527 -274.08632)
			(xy 128.212622 -274.035592) (xy 128.224801 -273.986178) (xy 128.244749 -273.939358) (xy 128.27195 -273.896344)
			(xy 128.305698 -273.85825) (xy 128.34512 -273.826063) (xy 128.389194 -273.800617) (xy 128.43678 -273.78257)
			(xy 128.486644 -273.77239) (xy 128.537496 -273.770341) (xy 128.588017 -273.776475) (xy 128.636901 -273.790635)
			(xy 128.68288 -273.812452) (xy 128.724764 -273.841362) (xy 128.761468 -273.876617) (xy 128.792041 -273.917303)
			(xy 128.815692 -273.962366) (xy 128.831808 -274.01064) (xy 128.839972 -274.060874) (xy 128.840484 -274.08632)
			(xy 129.148581 -274.08632) (xy 129.152676 -274.035592) (xy 129.164855 -273.986178) (xy 129.184803 -273.939358)
			(xy 129.212004 -273.896344) (xy 129.245752 -273.85825) (xy 129.285174 -273.826063) (xy 129.329248 -273.800617)
			(xy 129.376834 -273.78257) (xy 129.426698 -273.77239) (xy 129.47755 -273.770341) (xy 129.528071 -273.776475)
			(xy 129.576955 -273.790635) (xy 129.622934 -273.812452) (xy 129.664818 -273.841362) (xy 129.701522 -273.876617)
			(xy 129.732095 -273.917303) (xy 129.755746 -273.962366) (xy 129.771862 -274.01064) (xy 129.780026 -274.060874)
			(xy 129.780538 -274.08632) (xy 130.099066 -274.08632) (xy 130.103026 -274.037266) (xy 130.114803 -273.989482)
			(xy 130.134094 -273.944206) (xy 130.160397 -273.90261) (xy 130.193032 -273.865773) (xy 130.231153 -273.834648)
			(xy 130.273774 -273.810041) (xy 130.31979 -273.792589) (xy 130.368009 -273.782745) (xy 130.417184 -273.780764)
			(xy 130.466039 -273.786696) (xy 130.51331 -273.800388) (xy 130.557772 -273.821486) (xy 130.598275 -273.849442)
			(xy 130.633768 -273.883534) (xy 130.663333 -273.922878) (xy 130.686204 -273.966455) (xy 130.701788 -274.013136)
			(xy 130.709683 -274.061713) (xy 130.710178 -274.08632) (xy 131.028435 -274.08632) (xy 131.03253 -274.035592)
			(xy 131.044709 -273.986178) (xy 131.064657 -273.939358) (xy 131.091858 -273.896344) (xy 131.125606 -273.85825)
			(xy 131.165028 -273.826063) (xy 131.209102 -273.800617) (xy 131.256688 -273.78257) (xy 131.306552 -273.77239)
			(xy 131.357404 -273.770341) (xy 131.407925 -273.776475) (xy 131.456809 -273.790635) (xy 131.502788 -273.812452)
			(xy 131.544672 -273.841362) (xy 131.581376 -273.876617) (xy 131.611949 -273.917303) (xy 131.6356 -273.962366)
			(xy 131.651716 -274.01064) (xy 131.65988 -274.060874) (xy 131.660392 -274.08632) (xy 131.97892 -274.08632)
			(xy 131.98288 -274.037266) (xy 131.994657 -273.989482) (xy 132.013948 -273.944206) (xy 132.040251 -273.90261)
			(xy 132.072886 -273.865773) (xy 132.111007 -273.834648) (xy 132.153628 -273.810041) (xy 132.199644 -273.792589)
			(xy 132.247863 -273.782745) (xy 132.297038 -273.780764) (xy 132.345893 -273.786696) (xy 132.393164 -273.800388)
			(xy 132.437626 -273.821486) (xy 132.478129 -273.849442) (xy 132.513622 -273.883534) (xy 132.543187 -273.922878)
			(xy 132.566058 -273.966455) (xy 132.581642 -274.013136) (xy 132.589537 -274.061713) (xy 132.590032 -274.08632)
			(xy 132.908543 -274.08632) (xy 132.912638 -274.035592) (xy 132.924817 -273.986178) (xy 132.944765 -273.939358)
			(xy 132.971966 -273.896344) (xy 133.005714 -273.85825) (xy 133.045136 -273.826063) (xy 133.08921 -273.800617)
			(xy 133.136796 -273.78257) (xy 133.18666 -273.77239) (xy 133.237512 -273.770341) (xy 133.288033 -273.776475)
			(xy 133.336917 -273.790635) (xy 133.382896 -273.812452) (xy 133.42478 -273.841362) (xy 133.461484 -273.876617)
			(xy 133.492057 -273.917303) (xy 133.515708 -273.962366) (xy 133.531824 -274.01064) (xy 133.539988 -274.060874)
			(xy 133.5405 -274.08632) (xy 133.859028 -274.08632) (xy 133.862988 -274.037266) (xy 133.874765 -273.989482)
			(xy 133.894056 -273.944206) (xy 133.920359 -273.90261) (xy 133.952994 -273.865773) (xy 133.991115 -273.834648)
			(xy 134.033736 -273.810041) (xy 134.079752 -273.792589) (xy 134.127971 -273.782745) (xy 134.177146 -273.780764)
			(xy 134.226001 -273.786696) (xy 134.273272 -273.800388) (xy 134.317734 -273.821486) (xy 134.358237 -273.849442)
			(xy 134.39373 -273.883534) (xy 134.423295 -273.922878) (xy 134.446166 -273.966455) (xy 134.46175 -274.013136)
			(xy 134.469645 -274.061713) (xy 134.47014 -274.08632) (xy 134.798828 -274.08632) (xy 134.802788 -274.037266)
			(xy 134.814565 -273.989482) (xy 134.833856 -273.944206) (xy 134.860159 -273.90261) (xy 134.892794 -273.865773)
			(xy 134.930915 -273.834648) (xy 134.973536 -273.810041) (xy 135.019552 -273.792589) (xy 135.067771 -273.782745)
			(xy 135.116946 -273.780764) (xy 135.165801 -273.786696) (xy 135.213072 -273.800388) (xy 135.257534 -273.821486)
			(xy 135.298037 -273.849442) (xy 135.33353 -273.883534) (xy 135.363095 -273.922878) (xy 135.385966 -273.966455)
			(xy 135.40155 -274.013136) (xy 135.409445 -274.061713) (xy 135.40994 -274.08632) (xy 135.738882 -274.08632)
			(xy 135.742842 -274.037266) (xy 135.754619 -273.989482) (xy 135.77391 -273.944206) (xy 135.800213 -273.90261)
			(xy 135.832848 -273.865773) (xy 135.870969 -273.834648) (xy 135.91359 -273.810041) (xy 135.959606 -273.792589)
			(xy 136.007825 -273.782745) (xy 136.057 -273.780764) (xy 136.105855 -273.786696) (xy 136.153126 -273.800388)
			(xy 136.197588 -273.821486) (xy 136.238091 -273.849442) (xy 136.273584 -273.883534) (xy 136.303149 -273.922878)
			(xy 136.32602 -273.966455) (xy 136.341604 -274.013136) (xy 136.349499 -274.061713) (xy 136.349994 -274.08632)
			(xy 136.349499 -274.110927) (xy 136.341604 -274.159504) (xy 136.32602 -274.206185) (xy 136.303149 -274.249762)
			(xy 136.273584 -274.289106) (xy 136.238091 -274.323198) (xy 136.197588 -274.351154) (xy 136.153126 -274.372252)
			(xy 136.105855 -274.385944) (xy 136.057 -274.391876) (xy 136.007825 -274.389895) (xy 135.959606 -274.380051)
			(xy 135.91359 -274.362599) (xy 135.870969 -274.337992) (xy 135.832848 -274.306867) (xy 135.800213 -274.27003)
			(xy 135.77391 -274.228434) (xy 135.754619 -274.183158) (xy 135.742842 -274.135374) (xy 135.738882 -274.08632)
			(xy 135.40994 -274.08632) (xy 135.409445 -274.110927) (xy 135.40155 -274.159504) (xy 135.385966 -274.206185)
			(xy 135.363095 -274.249762) (xy 135.33353 -274.289106) (xy 135.298037 -274.323198) (xy 135.257534 -274.351154)
			(xy 135.213072 -274.372252) (xy 135.165801 -274.385944) (xy 135.116946 -274.391876) (xy 135.067771 -274.389895)
			(xy 135.019552 -274.380051) (xy 134.973536 -274.362599) (xy 134.930915 -274.337992) (xy 134.892794 -274.306867)
			(xy 134.860159 -274.27003) (xy 134.833856 -274.228434) (xy 134.814565 -274.183158) (xy 134.802788 -274.135374)
			(xy 134.798828 -274.08632) (xy 134.47014 -274.08632) (xy 134.469645 -274.110927) (xy 134.46175 -274.159504)
			(xy 134.446166 -274.206185) (xy 134.423295 -274.249762) (xy 134.39373 -274.289106) (xy 134.358237 -274.323198)
			(xy 134.317734 -274.351154) (xy 134.273272 -274.372252) (xy 134.226001 -274.385944) (xy 134.177146 -274.391876)
			(xy 134.127971 -274.389895) (xy 134.079752 -274.380051) (xy 134.033736 -274.362599) (xy 133.991115 -274.337992)
			(xy 133.952994 -274.306867) (xy 133.920359 -274.27003) (xy 133.894056 -274.228434) (xy 133.874765 -274.183158)
			(xy 133.862988 -274.135374) (xy 133.859028 -274.08632) (xy 133.5405 -274.08632) (xy 133.539988 -274.111766)
			(xy 133.531824 -274.162) (xy 133.515708 -274.210274) (xy 133.492057 -274.255337) (xy 133.461484 -274.296023)
			(xy 133.42478 -274.331278) (xy 133.382896 -274.360188) (xy 133.336917 -274.382005) (xy 133.288033 -274.396165)
			(xy 133.237512 -274.402299) (xy 133.18666 -274.40025) (xy 133.136796 -274.39007) (xy 133.08921 -274.372023)
			(xy 133.045136 -274.346577) (xy 133.005714 -274.31439) (xy 132.971966 -274.276296) (xy 132.944765 -274.233282)
			(xy 132.924817 -274.186462) (xy 132.912638 -274.137048) (xy 132.908543 -274.08632) (xy 132.590032 -274.08632)
			(xy 132.589537 -274.110927) (xy 132.581642 -274.159504) (xy 132.566058 -274.206185) (xy 132.543187 -274.249762)
			(xy 132.513622 -274.289106) (xy 132.478129 -274.323198) (xy 132.437626 -274.351154) (xy 132.393164 -274.372252)
			(xy 132.345893 -274.385944) (xy 132.297038 -274.391876) (xy 132.247863 -274.389895) (xy 132.199644 -274.380051)
			(xy 132.153628 -274.362599) (xy 132.111007 -274.337992) (xy 132.072886 -274.306867) (xy 132.040251 -274.27003)
			(xy 132.013948 -274.228434) (xy 131.994657 -274.183158) (xy 131.98288 -274.135374) (xy 131.97892 -274.08632)
			(xy 131.660392 -274.08632) (xy 131.65988 -274.111766) (xy 131.651716 -274.162) (xy 131.6356 -274.210274)
			(xy 131.611949 -274.255337) (xy 131.581376 -274.296023) (xy 131.544672 -274.331278) (xy 131.502788 -274.360188)
			(xy 131.456809 -274.382005) (xy 131.407925 -274.396165) (xy 131.357404 -274.402299) (xy 131.306552 -274.40025)
			(xy 131.256688 -274.39007) (xy 131.209102 -274.372023) (xy 131.165028 -274.346577) (xy 131.125606 -274.31439)
			(xy 131.091858 -274.276296) (xy 131.064657 -274.233282) (xy 131.044709 -274.186462) (xy 131.03253 -274.137048)
			(xy 131.028435 -274.08632) (xy 130.710178 -274.08632) (xy 130.709683 -274.110927) (xy 130.701788 -274.159504)
			(xy 130.686204 -274.206185) (xy 130.663333 -274.249762) (xy 130.633768 -274.289106) (xy 130.598275 -274.323198)
			(xy 130.557772 -274.351154) (xy 130.51331 -274.372252) (xy 130.466039 -274.385944) (xy 130.417184 -274.391876)
			(xy 130.368009 -274.389895) (xy 130.31979 -274.380051) (xy 130.273774 -274.362599) (xy 130.231153 -274.337992)
			(xy 130.193032 -274.306867) (xy 130.160397 -274.27003) (xy 130.134094 -274.228434) (xy 130.114803 -274.183158)
			(xy 130.103026 -274.135374) (xy 130.099066 -274.08632) (xy 129.780538 -274.08632) (xy 129.780026 -274.111766)
			(xy 129.771862 -274.162) (xy 129.755746 -274.210274) (xy 129.732095 -274.255337) (xy 129.701522 -274.296023)
			(xy 129.664818 -274.331278) (xy 129.622934 -274.360188) (xy 129.576955 -274.382005) (xy 129.528071 -274.396165)
			(xy 129.47755 -274.402299) (xy 129.426698 -274.40025) (xy 129.376834 -274.39007) (xy 129.329248 -274.372023)
			(xy 129.285174 -274.346577) (xy 129.245752 -274.31439) (xy 129.212004 -274.276296) (xy 129.184803 -274.233282)
			(xy 129.164855 -274.186462) (xy 129.152676 -274.137048) (xy 129.148581 -274.08632) (xy 128.840484 -274.08632)
			(xy 128.839972 -274.111766) (xy 128.831808 -274.162) (xy 128.815692 -274.210274) (xy 128.792041 -274.255337)
			(xy 128.761468 -274.296023) (xy 128.724764 -274.331278) (xy 128.68288 -274.360188) (xy 128.636901 -274.382005)
			(xy 128.588017 -274.396165) (xy 128.537496 -274.402299) (xy 128.486644 -274.40025) (xy 128.43678 -274.39007)
			(xy 128.389194 -274.372023) (xy 128.34512 -274.346577) (xy 128.305698 -274.31439) (xy 128.27195 -274.276296)
			(xy 128.244749 -274.233282) (xy 128.224801 -274.186462) (xy 128.212622 -274.137048) (xy 128.208527 -274.08632)
			(xy 127.91491 -274.08632) (xy 127.91491 -274.111222) (xy 127.907433 -274.160482) (xy 127.89265 -274.208062)
			(xy 127.870897 -274.252886) (xy 127.842664 -274.293939) (xy 127.808592 -274.330292) (xy 127.769451 -274.361121)
			(xy 127.74803 -274.373848) (xy 127.739648 -274.378674) (xy 127.71628 -274.407376) (xy 127.712978 -274.417282)
			(xy 127.712724 -274.41779) (xy 127.699532 -274.45893) (xy 127.667643 -274.539232) (xy 127.629647 -274.616831)
			(xy 127.608076 -274.654264) (xy 127.581911 -274.697499) (xy 127.522895 -274.779543) (xy 127.49022 -274.818094)
			(xy 127.49022 -274.818348) (xy 127.484378 -274.825206) (xy 127.477012 -274.844002) (xy 127.476758 -274.845018)
			(xy 127.475234 -274.849336) (xy 127.473822 -274.853514) (xy 127.472285 -274.862199) (xy 127.472186 -274.866608)
			(xy 127.472186 -274.896326) (xy 127.738627 -274.896326) (xy 127.742722 -274.845598) (xy 127.754901 -274.796184)
			(xy 127.774849 -274.749364) (xy 127.80205 -274.70635) (xy 127.835798 -274.668256) (xy 127.87522 -274.636069)
			(xy 127.919294 -274.610623) (xy 127.96688 -274.592576) (xy 128.016744 -274.582396) (xy 128.067596 -274.580347)
			(xy 128.118117 -274.586481) (xy 128.167001 -274.600641) (xy 128.21298 -274.622458) (xy 128.254864 -274.651368)
			(xy 128.291568 -274.686623) (xy 128.322141 -274.727309) (xy 128.345792 -274.772372) (xy 128.361908 -274.820646)
			(xy 128.370072 -274.87088) (xy 128.370584 -274.896326) (xy 128.688858 -274.896326) (xy 128.692818 -274.847272)
			(xy 128.704595 -274.799488) (xy 128.723886 -274.754212) (xy 128.750189 -274.712616) (xy 128.782824 -274.675779)
			(xy 128.820945 -274.644654) (xy 128.863566 -274.620047) (xy 128.909582 -274.602595) (xy 128.957801 -274.592751)
			(xy 129.006976 -274.59077) (xy 129.055831 -274.596702) (xy 129.103102 -274.610394) (xy 129.147564 -274.631492)
			(xy 129.188067 -274.659448) (xy 129.22356 -274.69354) (xy 129.253125 -274.732884) (xy 129.275996 -274.776461)
			(xy 129.29158 -274.823142) (xy 129.299475 -274.871719) (xy 129.29997 -274.896326) (xy 129.618481 -274.896326)
			(xy 129.622576 -274.845598) (xy 129.634755 -274.796184) (xy 129.654703 -274.749364) (xy 129.681904 -274.70635)
			(xy 129.715652 -274.668256) (xy 129.755074 -274.636069) (xy 129.799148 -274.610623) (xy 129.846734 -274.592576)
			(xy 129.896598 -274.582396) (xy 129.94745 -274.580347) (xy 129.997971 -274.586481) (xy 130.046855 -274.600641)
			(xy 130.092834 -274.622458) (xy 130.134718 -274.651368) (xy 130.171422 -274.686623) (xy 130.201995 -274.727309)
			(xy 130.225646 -274.772372) (xy 130.241762 -274.820646) (xy 130.249926 -274.87088) (xy 130.250438 -274.896326)
			(xy 130.568966 -274.896326) (xy 130.572926 -274.847272) (xy 130.584703 -274.799488) (xy 130.603994 -274.754212)
			(xy 130.630297 -274.712616) (xy 130.662932 -274.675779) (xy 130.701053 -274.644654) (xy 130.743674 -274.620047)
			(xy 130.78969 -274.602595) (xy 130.837909 -274.592751) (xy 130.887084 -274.59077) (xy 130.935939 -274.596702)
			(xy 130.98321 -274.610394) (xy 131.027672 -274.631492) (xy 131.068175 -274.659448) (xy 131.103668 -274.69354)
			(xy 131.133233 -274.732884) (xy 131.156104 -274.776461) (xy 131.171688 -274.823142) (xy 131.179583 -274.871719)
			(xy 131.180078 -274.896326) (xy 131.498589 -274.896326) (xy 131.502684 -274.845598) (xy 131.514863 -274.796184)
			(xy 131.534811 -274.749364) (xy 131.562012 -274.70635) (xy 131.59576 -274.668256) (xy 131.635182 -274.636069)
			(xy 131.679256 -274.610623) (xy 131.726842 -274.592576) (xy 131.776706 -274.582396) (xy 131.827558 -274.580347)
			(xy 131.878079 -274.586481) (xy 131.926963 -274.600641) (xy 131.972942 -274.622458) (xy 132.014826 -274.651368)
			(xy 132.05153 -274.686623) (xy 132.082103 -274.727309) (xy 132.105754 -274.772372) (xy 132.12187 -274.820646)
			(xy 132.130034 -274.87088) (xy 132.130546 -274.896326) (xy 132.438643 -274.896326) (xy 132.442738 -274.845598)
			(xy 132.454917 -274.796184) (xy 132.474865 -274.749364) (xy 132.502066 -274.70635) (xy 132.535814 -274.668256)
			(xy 132.575236 -274.636069) (xy 132.61931 -274.610623) (xy 132.666896 -274.592576) (xy 132.71676 -274.582396)
			(xy 132.767612 -274.580347) (xy 132.818133 -274.586481) (xy 132.867017 -274.600641) (xy 132.912996 -274.622458)
			(xy 132.95488 -274.651368) (xy 132.991584 -274.686623) (xy 133.022157 -274.727309) (xy 133.045808 -274.772372)
			(xy 133.061924 -274.820646) (xy 133.070088 -274.87088) (xy 133.0706 -274.896326) (xy 133.388874 -274.896326)
			(xy 133.392834 -274.847272) (xy 133.404611 -274.799488) (xy 133.423902 -274.754212) (xy 133.450205 -274.712616)
			(xy 133.48284 -274.675779) (xy 133.520961 -274.644654) (xy 133.563582 -274.620047) (xy 133.609598 -274.602595)
			(xy 133.657817 -274.592751) (xy 133.706992 -274.59077) (xy 133.755847 -274.596702) (xy 133.803118 -274.610394)
			(xy 133.84758 -274.631492) (xy 133.888083 -274.659448) (xy 133.923576 -274.69354) (xy 133.953141 -274.732884)
			(xy 133.976012 -274.776461) (xy 133.991596 -274.823142) (xy 133.999491 -274.871719) (xy 133.999986 -274.896326)
			(xy 134.328928 -274.896326) (xy 134.332888 -274.847272) (xy 134.344665 -274.799488) (xy 134.363956 -274.754212)
			(xy 134.390259 -274.712616) (xy 134.422894 -274.675779) (xy 134.461015 -274.644654) (xy 134.503636 -274.620047)
			(xy 134.549652 -274.602595) (xy 134.597871 -274.592751) (xy 134.647046 -274.59077) (xy 134.695901 -274.596702)
			(xy 134.743172 -274.610394) (xy 134.787634 -274.631492) (xy 134.828137 -274.659448) (xy 134.86363 -274.69354)
			(xy 134.893195 -274.732884) (xy 134.916066 -274.776461) (xy 134.93165 -274.823142) (xy 134.939545 -274.871719)
			(xy 134.94004 -274.896326) (xy 135.268982 -274.896326) (xy 135.272942 -274.847272) (xy 135.284719 -274.799488)
			(xy 135.30401 -274.754212) (xy 135.330313 -274.712616) (xy 135.362948 -274.675779) (xy 135.401069 -274.644654)
			(xy 135.44369 -274.620047) (xy 135.489706 -274.602595) (xy 135.537925 -274.592751) (xy 135.5871 -274.59077)
			(xy 135.635955 -274.596702) (xy 135.683226 -274.610394) (xy 135.727688 -274.631492) (xy 135.768191 -274.659448)
			(xy 135.803684 -274.69354) (xy 135.833249 -274.732884) (xy 135.85612 -274.776461) (xy 135.871704 -274.823142)
			(xy 135.879599 -274.871719) (xy 135.880094 -274.896326) (xy 136.209036 -274.896326) (xy 136.212996 -274.847272)
			(xy 136.224773 -274.799488) (xy 136.244064 -274.754212) (xy 136.270367 -274.712616) (xy 136.303002 -274.675779)
			(xy 136.341123 -274.644654) (xy 136.383744 -274.620047) (xy 136.42976 -274.602595) (xy 136.477979 -274.592751)
			(xy 136.527154 -274.59077) (xy 136.576009 -274.596702) (xy 136.62328 -274.610394) (xy 136.667742 -274.631492)
			(xy 136.708245 -274.659448) (xy 136.743738 -274.69354) (xy 136.773303 -274.732884) (xy 136.796174 -274.776461)
			(xy 136.811758 -274.823142) (xy 136.819653 -274.871719) (xy 136.820148 -274.896326) (xy 136.819653 -274.920933)
			(xy 136.811758 -274.96951) (xy 136.796174 -275.016191) (xy 136.773303 -275.059768) (xy 136.743738 -275.099112)
			(xy 136.708245 -275.133204) (xy 136.667742 -275.16116) (xy 136.62328 -275.182258) (xy 136.576009 -275.19595)
			(xy 136.527154 -275.201882) (xy 136.477979 -275.199901) (xy 136.42976 -275.190057) (xy 136.383744 -275.172605)
			(xy 136.341123 -275.147998) (xy 136.303002 -275.116873) (xy 136.270367 -275.080036) (xy 136.244064 -275.03844)
			(xy 136.224773 -274.993164) (xy 136.212996 -274.94538) (xy 136.209036 -274.896326) (xy 135.880094 -274.896326)
			(xy 135.879599 -274.920933) (xy 135.871704 -274.96951) (xy 135.85612 -275.016191) (xy 135.833249 -275.059768)
			(xy 135.803684 -275.099112) (xy 135.768191 -275.133204) (xy 135.727688 -275.16116) (xy 135.683226 -275.182258)
			(xy 135.635955 -275.19595) (xy 135.5871 -275.201882) (xy 135.537925 -275.199901) (xy 135.489706 -275.190057)
			(xy 135.44369 -275.172605) (xy 135.401069 -275.147998) (xy 135.362948 -275.116873) (xy 135.330313 -275.080036)
			(xy 135.30401 -275.03844) (xy 135.284719 -274.993164) (xy 135.272942 -274.94538) (xy 135.268982 -274.896326)
			(xy 134.94004 -274.896326) (xy 134.939545 -274.920933) (xy 134.93165 -274.96951) (xy 134.916066 -275.016191)
			(xy 134.893195 -275.059768) (xy 134.86363 -275.099112) (xy 134.828137 -275.133204) (xy 134.787634 -275.16116)
			(xy 134.743172 -275.182258) (xy 134.695901 -275.19595) (xy 134.647046 -275.201882) (xy 134.597871 -275.199901)
			(xy 134.549652 -275.190057) (xy 134.503636 -275.172605) (xy 134.461015 -275.147998) (xy 134.422894 -275.116873)
			(xy 134.390259 -275.080036) (xy 134.363956 -275.03844) (xy 134.344665 -274.993164) (xy 134.332888 -274.94538)
			(xy 134.328928 -274.896326) (xy 133.999986 -274.896326) (xy 133.999491 -274.920933) (xy 133.991596 -274.96951)
			(xy 133.976012 -275.016191) (xy 133.953141 -275.059768) (xy 133.923576 -275.099112) (xy 133.888083 -275.133204)
			(xy 133.84758 -275.16116) (xy 133.803118 -275.182258) (xy 133.755847 -275.19595) (xy 133.706992 -275.201882)
			(xy 133.657817 -275.199901) (xy 133.609598 -275.190057) (xy 133.563582 -275.172605) (xy 133.520961 -275.147998)
			(xy 133.48284 -275.116873) (xy 133.450205 -275.080036) (xy 133.423902 -275.03844) (xy 133.404611 -274.993164)
			(xy 133.392834 -274.94538) (xy 133.388874 -274.896326) (xy 133.0706 -274.896326) (xy 133.070088 -274.921772)
			(xy 133.061924 -274.972006) (xy 133.045808 -275.02028) (xy 133.022157 -275.065343) (xy 132.991584 -275.106029)
			(xy 132.95488 -275.141284) (xy 132.912996 -275.170194) (xy 132.867017 -275.192011) (xy 132.818133 -275.206171)
			(xy 132.767612 -275.212305) (xy 132.71676 -275.210256) (xy 132.666896 -275.200076) (xy 132.61931 -275.182029)
			(xy 132.575236 -275.156583) (xy 132.535814 -275.124396) (xy 132.502066 -275.086302) (xy 132.474865 -275.043288)
			(xy 132.454917 -274.996468) (xy 132.442738 -274.947054) (xy 132.438643 -274.896326) (xy 132.130546 -274.896326)
			(xy 132.130034 -274.921772) (xy 132.12187 -274.972006) (xy 132.105754 -275.02028) (xy 132.082103 -275.065343)
			(xy 132.05153 -275.106029) (xy 132.014826 -275.141284) (xy 131.972942 -275.170194) (xy 131.926963 -275.192011)
			(xy 131.878079 -275.206171) (xy 131.827558 -275.212305) (xy 131.776706 -275.210256) (xy 131.726842 -275.200076)
			(xy 131.679256 -275.182029) (xy 131.635182 -275.156583) (xy 131.59576 -275.124396) (xy 131.562012 -275.086302)
			(xy 131.534811 -275.043288) (xy 131.514863 -274.996468) (xy 131.502684 -274.947054) (xy 131.498589 -274.896326)
			(xy 131.180078 -274.896326) (xy 131.179583 -274.920933) (xy 131.171688 -274.96951) (xy 131.156104 -275.016191)
			(xy 131.133233 -275.059768) (xy 131.103668 -275.099112) (xy 131.068175 -275.133204) (xy 131.027672 -275.16116)
			(xy 130.98321 -275.182258) (xy 130.935939 -275.19595) (xy 130.887084 -275.201882) (xy 130.837909 -275.199901)
			(xy 130.78969 -275.190057) (xy 130.743674 -275.172605) (xy 130.701053 -275.147998) (xy 130.662932 -275.116873)
			(xy 130.630297 -275.080036) (xy 130.603994 -275.03844) (xy 130.584703 -274.993164) (xy 130.572926 -274.94538)
			(xy 130.568966 -274.896326) (xy 130.250438 -274.896326) (xy 130.249926 -274.921772) (xy 130.241762 -274.972006)
			(xy 130.225646 -275.02028) (xy 130.201995 -275.065343) (xy 130.171422 -275.106029) (xy 130.134718 -275.141284)
			(xy 130.092834 -275.170194) (xy 130.046855 -275.192011) (xy 129.997971 -275.206171) (xy 129.94745 -275.212305)
			(xy 129.896598 -275.210256) (xy 129.846734 -275.200076) (xy 129.799148 -275.182029) (xy 129.755074 -275.156583)
			(xy 129.715652 -275.124396) (xy 129.681904 -275.086302) (xy 129.654703 -275.043288) (xy 129.634755 -274.996468)
			(xy 129.622576 -274.947054) (xy 129.618481 -274.896326) (xy 129.29997 -274.896326) (xy 129.299475 -274.920933)
			(xy 129.29158 -274.96951) (xy 129.275996 -275.016191) (xy 129.253125 -275.059768) (xy 129.22356 -275.099112)
			(xy 129.188067 -275.133204) (xy 129.147564 -275.16116) (xy 129.103102 -275.182258) (xy 129.055831 -275.19595)
			(xy 129.006976 -275.201882) (xy 128.957801 -275.199901) (xy 128.909582 -275.190057) (xy 128.863566 -275.172605)
			(xy 128.820945 -275.147998) (xy 128.782824 -275.116873) (xy 128.750189 -275.080036) (xy 128.723886 -275.03844)
			(xy 128.704595 -274.993164) (xy 128.692818 -274.94538) (xy 128.688858 -274.896326) (xy 128.370584 -274.896326)
			(xy 128.370072 -274.921772) (xy 128.361908 -274.972006) (xy 128.345792 -275.02028) (xy 128.322141 -275.065343)
			(xy 128.291568 -275.106029) (xy 128.254864 -275.141284) (xy 128.21298 -275.170194) (xy 128.167001 -275.192011)
			(xy 128.118117 -275.206171) (xy 128.067596 -275.212305) (xy 128.016744 -275.210256) (xy 127.96688 -275.200076)
			(xy 127.919294 -275.182029) (xy 127.87522 -275.156583) (xy 127.835798 -275.124396) (xy 127.80205 -275.086302)
			(xy 127.774849 -275.043288) (xy 127.754901 -274.996468) (xy 127.742722 -274.947054) (xy 127.738627 -274.896326)
			(xy 127.472186 -274.896326) (xy 127.472186 -274.935442) (xy 127.484632 -274.9677) (xy 127.490474 -274.974558)
			(xy 127.490474 -274.974812) (xy 127.522581 -275.012752) (xy 127.580686 -275.0934) (xy 127.631404 -275.178885)
			(xy 127.674335 -275.268535) (xy 127.709141 -275.361641) (xy 127.722884 -275.409406) (xy 127.725424 -275.41855)
			(xy 127.74676 -275.447252) (xy 127.754634 -275.452586) (xy 127.754888 -275.45284) (xy 127.758444 -275.45538)
			(xy 127.778333 -275.469704) (xy 127.813686 -275.50365) (xy 127.828802 -275.522944) (xy 127.843217 -275.542892)
			(xy 127.8661 -275.586463) (xy 127.881691 -275.633142) (xy 127.889588 -275.681718) (xy 127.889586 -275.706332)
			(xy 128.208527 -275.706332) (xy 128.212622 -275.655604) (xy 128.224801 -275.60619) (xy 128.244749 -275.55937)
			(xy 128.27195 -275.516356) (xy 128.305698 -275.478262) (xy 128.34512 -275.446075) (xy 128.389194 -275.420629)
			(xy 128.43678 -275.402582) (xy 128.486644 -275.392402) (xy 128.537496 -275.390353) (xy 128.588017 -275.396487)
			(xy 128.636901 -275.410647) (xy 128.68288 -275.432464) (xy 128.724764 -275.461374) (xy 128.761468 -275.496629)
			(xy 128.792041 -275.537315) (xy 128.815692 -275.582378) (xy 128.831808 -275.630652) (xy 128.839972 -275.680886)
			(xy 128.840484 -275.706332) (xy 129.148581 -275.706332) (xy 129.152676 -275.655604) (xy 129.164855 -275.60619)
			(xy 129.184803 -275.55937) (xy 129.212004 -275.516356) (xy 129.245752 -275.478262) (xy 129.285174 -275.446075)
			(xy 129.329248 -275.420629) (xy 129.376834 -275.402582) (xy 129.426698 -275.392402) (xy 129.47755 -275.390353)
			(xy 129.528071 -275.396487) (xy 129.576955 -275.410647) (xy 129.622934 -275.432464) (xy 129.664818 -275.461374)
			(xy 129.701522 -275.496629) (xy 129.732095 -275.537315) (xy 129.755746 -275.582378) (xy 129.771862 -275.630652)
			(xy 129.780026 -275.680886) (xy 129.780538 -275.706332) (xy 131.028435 -275.706332) (xy 131.03253 -275.655604)
			(xy 131.044709 -275.60619) (xy 131.064657 -275.55937) (xy 131.091858 -275.516356) (xy 131.125606 -275.478262)
			(xy 131.165028 -275.446075) (xy 131.209102 -275.420629) (xy 131.256688 -275.402582) (xy 131.306552 -275.392402)
			(xy 131.357404 -275.390353) (xy 131.407925 -275.396487) (xy 131.456809 -275.410647) (xy 131.502788 -275.432464)
			(xy 131.544672 -275.461374) (xy 131.581376 -275.496629) (xy 131.611949 -275.537315) (xy 131.6356 -275.582378)
			(xy 131.651716 -275.630652) (xy 131.65988 -275.680886) (xy 131.660392 -275.706332) (xy 131.97892 -275.706332)
			(xy 131.98288 -275.657278) (xy 131.994657 -275.609494) (xy 132.013948 -275.564218) (xy 132.040251 -275.522622)
			(xy 132.072886 -275.485785) (xy 132.111007 -275.45466) (xy 132.153628 -275.430053) (xy 132.199644 -275.412601)
			(xy 132.247863 -275.402757) (xy 132.297038 -275.400776) (xy 132.345893 -275.406708) (xy 132.393164 -275.4204)
			(xy 132.437626 -275.441498) (xy 132.478129 -275.469454) (xy 132.513622 -275.503546) (xy 132.543187 -275.54289)
			(xy 132.566058 -275.586467) (xy 132.581642 -275.633148) (xy 132.589537 -275.681725) (xy 132.590032 -275.706332)
			(xy 132.908543 -275.706332) (xy 132.912638 -275.655604) (xy 132.924817 -275.60619) (xy 132.944765 -275.55937)
			(xy 132.971966 -275.516356) (xy 133.005714 -275.478262) (xy 133.045136 -275.446075) (xy 133.08921 -275.420629)
			(xy 133.136796 -275.402582) (xy 133.18666 -275.392402) (xy 133.237512 -275.390353) (xy 133.288033 -275.396487)
			(xy 133.336917 -275.410647) (xy 133.382896 -275.432464) (xy 133.42478 -275.461374) (xy 133.461484 -275.496629)
			(xy 133.492057 -275.537315) (xy 133.515708 -275.582378) (xy 133.531824 -275.630652) (xy 133.539988 -275.680886)
			(xy 133.5405 -275.706332) (xy 133.859028 -275.706332) (xy 133.862988 -275.657278) (xy 133.874765 -275.609494)
			(xy 133.894056 -275.564218) (xy 133.920359 -275.522622) (xy 133.952994 -275.485785) (xy 133.991115 -275.45466)
			(xy 134.033736 -275.430053) (xy 134.079752 -275.412601) (xy 134.127971 -275.402757) (xy 134.177146 -275.400776)
			(xy 134.226001 -275.406708) (xy 134.273272 -275.4204) (xy 134.317734 -275.441498) (xy 134.358237 -275.469454)
			(xy 134.39373 -275.503546) (xy 134.423295 -275.54289) (xy 134.446166 -275.586467) (xy 134.46175 -275.633148)
			(xy 134.469645 -275.681725) (xy 134.47014 -275.706332) (xy 134.798828 -275.706332) (xy 134.802788 -275.657278)
			(xy 134.814565 -275.609494) (xy 134.833856 -275.564218) (xy 134.860159 -275.522622) (xy 134.892794 -275.485785)
			(xy 134.930915 -275.45466) (xy 134.973536 -275.430053) (xy 135.019552 -275.412601) (xy 135.067771 -275.402757)
			(xy 135.116946 -275.400776) (xy 135.165801 -275.406708) (xy 135.213072 -275.4204) (xy 135.257534 -275.441498)
			(xy 135.298037 -275.469454) (xy 135.33353 -275.503546) (xy 135.363095 -275.54289) (xy 135.385966 -275.586467)
			(xy 135.40155 -275.633148) (xy 135.409445 -275.681725) (xy 135.40994 -275.706332) (xy 135.738882 -275.706332)
			(xy 135.742842 -275.657278) (xy 135.754619 -275.609494) (xy 135.77391 -275.564218) (xy 135.800213 -275.522622)
			(xy 135.832848 -275.485785) (xy 135.870969 -275.45466) (xy 135.91359 -275.430053) (xy 135.959606 -275.412601)
			(xy 136.007825 -275.402757) (xy 136.057 -275.400776) (xy 136.105855 -275.406708) (xy 136.153126 -275.4204)
			(xy 136.197588 -275.441498) (xy 136.238091 -275.469454) (xy 136.273584 -275.503546) (xy 136.303149 -275.54289)
			(xy 136.32602 -275.586467) (xy 136.341604 -275.633148) (xy 136.349499 -275.681725) (xy 136.349994 -275.706332)
			(xy 136.349499 -275.730939) (xy 136.341604 -275.779516) (xy 136.32602 -275.826197) (xy 136.303149 -275.869774)
			(xy 136.273584 -275.909118) (xy 136.238091 -275.94321) (xy 136.197588 -275.971166) (xy 136.153126 -275.992264)
			(xy 136.105855 -276.005956) (xy 136.057 -276.011888) (xy 136.007825 -276.009907) (xy 135.959606 -276.000063)
			(xy 135.91359 -275.982611) (xy 135.870969 -275.958004) (xy 135.832848 -275.926879) (xy 135.800213 -275.890042)
			(xy 135.77391 -275.848446) (xy 135.754619 -275.80317) (xy 135.742842 -275.755386) (xy 135.738882 -275.706332)
			(xy 135.40994 -275.706332) (xy 135.409445 -275.730939) (xy 135.40155 -275.779516) (xy 135.385966 -275.826197)
			(xy 135.363095 -275.869774) (xy 135.33353 -275.909118) (xy 135.298037 -275.94321) (xy 135.257534 -275.971166)
			(xy 135.213072 -275.992264) (xy 135.165801 -276.005956) (xy 135.116946 -276.011888) (xy 135.067771 -276.009907)
			(xy 135.019552 -276.000063) (xy 134.973536 -275.982611) (xy 134.930915 -275.958004) (xy 134.892794 -275.926879)
			(xy 134.860159 -275.890042) (xy 134.833856 -275.848446) (xy 134.814565 -275.80317) (xy 134.802788 -275.755386)
			(xy 134.798828 -275.706332) (xy 134.47014 -275.706332) (xy 134.469645 -275.730939) (xy 134.46175 -275.779516)
			(xy 134.446166 -275.826197) (xy 134.423295 -275.869774) (xy 134.39373 -275.909118) (xy 134.358237 -275.94321)
			(xy 134.317734 -275.971166) (xy 134.273272 -275.992264) (xy 134.226001 -276.005956) (xy 134.177146 -276.011888)
			(xy 134.127971 -276.009907) (xy 134.079752 -276.000063) (xy 134.033736 -275.982611) (xy 133.991115 -275.958004)
			(xy 133.952994 -275.926879) (xy 133.920359 -275.890042) (xy 133.894056 -275.848446) (xy 133.874765 -275.80317)
			(xy 133.862988 -275.755386) (xy 133.859028 -275.706332) (xy 133.5405 -275.706332) (xy 133.539988 -275.731778)
			(xy 133.531824 -275.782012) (xy 133.515708 -275.830286) (xy 133.492057 -275.875349) (xy 133.461484 -275.916035)
			(xy 133.42478 -275.95129) (xy 133.382896 -275.9802) (xy 133.336917 -276.002017) (xy 133.288033 -276.016177)
			(xy 133.237512 -276.022311) (xy 133.18666 -276.020262) (xy 133.136796 -276.010082) (xy 133.08921 -275.992035)
			(xy 133.045136 -275.966589) (xy 133.005714 -275.934402) (xy 132.971966 -275.896308) (xy 132.944765 -275.853294)
			(xy 132.924817 -275.806474) (xy 132.912638 -275.75706) (xy 132.908543 -275.706332) (xy 132.590032 -275.706332)
			(xy 132.589537 -275.730939) (xy 132.581642 -275.779516) (xy 132.566058 -275.826197) (xy 132.543187 -275.869774)
			(xy 132.513622 -275.909118) (xy 132.478129 -275.94321) (xy 132.437626 -275.971166) (xy 132.393164 -275.992264)
			(xy 132.345893 -276.005956) (xy 132.297038 -276.011888) (xy 132.247863 -276.009907) (xy 132.199644 -276.000063)
			(xy 132.153628 -275.982611) (xy 132.111007 -275.958004) (xy 132.072886 -275.926879) (xy 132.040251 -275.890042)
			(xy 132.013948 -275.848446) (xy 131.994657 -275.80317) (xy 131.98288 -275.755386) (xy 131.97892 -275.706332)
			(xy 131.660392 -275.706332) (xy 131.65988 -275.731778) (xy 131.651716 -275.782012) (xy 131.6356 -275.830286)
			(xy 131.611949 -275.875349) (xy 131.581376 -275.916035) (xy 131.544672 -275.95129) (xy 131.502788 -275.9802)
			(xy 131.456809 -276.002017) (xy 131.407925 -276.016177) (xy 131.357404 -276.022311) (xy 131.306552 -276.020262)
			(xy 131.256688 -276.010082) (xy 131.209102 -275.992035) (xy 131.165028 -275.966589) (xy 131.125606 -275.934402)
			(xy 131.091858 -275.896308) (xy 131.064657 -275.853294) (xy 131.044709 -275.806474) (xy 131.03253 -275.75706)
			(xy 131.028435 -275.706332) (xy 129.780538 -275.706332) (xy 129.780026 -275.731778) (xy 129.771862 -275.782012)
			(xy 129.755746 -275.830286) (xy 129.732095 -275.875349) (xy 129.701522 -275.916035) (xy 129.664818 -275.95129)
			(xy 129.622934 -275.9802) (xy 129.576955 -276.002017) (xy 129.528071 -276.016177) (xy 129.47755 -276.022311)
			(xy 129.426698 -276.020262) (xy 129.376834 -276.010082) (xy 129.329248 -275.992035) (xy 129.285174 -275.966589)
			(xy 129.245752 -275.934402) (xy 129.212004 -275.896308) (xy 129.184803 -275.853294) (xy 129.164855 -275.806474)
			(xy 129.152676 -275.75706) (xy 129.148581 -275.706332) (xy 128.840484 -275.706332) (xy 128.839972 -275.731778)
			(xy 128.831808 -275.782012) (xy 128.815692 -275.830286) (xy 128.792041 -275.875349) (xy 128.761468 -275.916035)
			(xy 128.724764 -275.95129) (xy 128.68288 -275.9802) (xy 128.636901 -276.002017) (xy 128.588017 -276.016177)
			(xy 128.537496 -276.022311) (xy 128.486644 -276.020262) (xy 128.43678 -276.010082) (xy 128.389194 -275.992035)
			(xy 128.34512 -275.966589) (xy 128.305698 -275.934402) (xy 128.27195 -275.896308) (xy 128.244749 -275.853294)
			(xy 128.224801 -275.806474) (xy 128.212622 -275.75706) (xy 128.208527 -275.706332) (xy 127.889586 -275.706332)
			(xy 127.889584 -275.730933) (xy 127.881679 -275.779508) (xy 127.86608 -275.826184) (xy 127.843189 -275.869751)
			(xy 127.828802 -275.88972) (xy 127.812907 -275.91003) (xy 127.775495 -275.945523) (xy 127.75438 -275.960332)
			(xy 127.747014 -275.965158) (xy 127.725424 -275.994114) (xy 127.722884 -276.003258) (xy 127.709147 -276.051062)
			(xy 127.674304 -276.14423) (xy 127.631323 -276.233935) (xy 127.580543 -276.319468) (xy 127.522365 -276.400151)
			(xy 127.49022 -276.438106) (xy 127.49022 -276.43836) (xy 127.484378 -276.445218) (xy 127.477012 -276.464014)
			(xy 127.476758 -276.46503) (xy 127.475234 -276.469348) (xy 127.473823 -276.473527) (xy 127.472288 -276.482211)
			(xy 127.472186 -276.48662) (xy 127.472186 -276.516338) (xy 127.738627 -276.516338) (xy 127.742722 -276.46561)
			(xy 127.754901 -276.416196) (xy 127.774849 -276.369376) (xy 127.80205 -276.326362) (xy 127.835798 -276.288268)
			(xy 127.87522 -276.256081) (xy 127.919294 -276.230635) (xy 127.96688 -276.212588) (xy 128.016744 -276.202408)
			(xy 128.067596 -276.200359) (xy 128.118117 -276.206493) (xy 128.167001 -276.220653) (xy 128.21298 -276.24247)
			(xy 128.254864 -276.27138) (xy 128.291568 -276.306635) (xy 128.322141 -276.347321) (xy 128.345792 -276.392384)
			(xy 128.361908 -276.440658) (xy 128.370072 -276.490892) (xy 128.370584 -276.516338) (xy 128.688858 -276.516338)
			(xy 128.692818 -276.467284) (xy 128.704595 -276.4195) (xy 128.723886 -276.374224) (xy 128.750189 -276.332628)
			(xy 128.782824 -276.295791) (xy 128.820945 -276.264666) (xy 128.863566 -276.240059) (xy 128.909582 -276.222607)
			(xy 128.957801 -276.212763) (xy 129.006976 -276.210782) (xy 129.055831 -276.216714) (xy 129.103102 -276.230406)
			(xy 129.147564 -276.251504) (xy 129.188067 -276.27946) (xy 129.22356 -276.313552) (xy 129.253125 -276.352896)
			(xy 129.275996 -276.396473) (xy 129.29158 -276.443154) (xy 129.299475 -276.491731) (xy 129.29997 -276.516338)
			(xy 129.618481 -276.516338) (xy 129.622576 -276.46561) (xy 129.634755 -276.416196) (xy 129.654703 -276.369376)
			(xy 129.681904 -276.326362) (xy 129.715652 -276.288268) (xy 129.755074 -276.256081) (xy 129.799148 -276.230635)
			(xy 129.846734 -276.212588) (xy 129.896598 -276.202408) (xy 129.94745 -276.200359) (xy 129.997971 -276.206493)
			(xy 130.046855 -276.220653) (xy 130.092834 -276.24247) (xy 130.134718 -276.27138) (xy 130.171422 -276.306635)
			(xy 130.201995 -276.347321) (xy 130.225646 -276.392384) (xy 130.241762 -276.440658) (xy 130.249926 -276.490892)
			(xy 130.250438 -276.516338) (xy 130.568966 -276.516338) (xy 130.572926 -276.467284) (xy 130.584703 -276.4195)
			(xy 130.603994 -276.374224) (xy 130.630297 -276.332628) (xy 130.662932 -276.295791) (xy 130.701053 -276.264666)
			(xy 130.743674 -276.240059) (xy 130.78969 -276.222607) (xy 130.837909 -276.212763) (xy 130.887084 -276.210782)
			(xy 130.935939 -276.216714) (xy 130.98321 -276.230406) (xy 131.027672 -276.251504) (xy 131.068175 -276.27946)
			(xy 131.103668 -276.313552) (xy 131.133233 -276.352896) (xy 131.156104 -276.396473) (xy 131.171688 -276.443154)
			(xy 131.179583 -276.491731) (xy 131.180078 -276.516338) (xy 131.498589 -276.516338) (xy 131.502684 -276.46561)
			(xy 131.514863 -276.416196) (xy 131.534811 -276.369376) (xy 131.562012 -276.326362) (xy 131.59576 -276.288268)
			(xy 131.635182 -276.256081) (xy 131.679256 -276.230635) (xy 131.726842 -276.212588) (xy 131.776706 -276.202408)
			(xy 131.827558 -276.200359) (xy 131.878079 -276.206493) (xy 131.926963 -276.220653) (xy 131.972942 -276.24247)
			(xy 132.014826 -276.27138) (xy 132.05153 -276.306635) (xy 132.082103 -276.347321) (xy 132.105754 -276.392384)
			(xy 132.12187 -276.440658) (xy 132.130034 -276.490892) (xy 132.130546 -276.516338) (xy 132.438643 -276.516338)
			(xy 132.442738 -276.46561) (xy 132.454917 -276.416196) (xy 132.474865 -276.369376) (xy 132.502066 -276.326362)
			(xy 132.535814 -276.288268) (xy 132.575236 -276.256081) (xy 132.61931 -276.230635) (xy 132.666896 -276.212588)
			(xy 132.71676 -276.202408) (xy 132.767612 -276.200359) (xy 132.818133 -276.206493) (xy 132.867017 -276.220653)
			(xy 132.912996 -276.24247) (xy 132.95488 -276.27138) (xy 132.991584 -276.306635) (xy 133.022157 -276.347321)
			(xy 133.045808 -276.392384) (xy 133.061924 -276.440658) (xy 133.070088 -276.490892) (xy 133.0706 -276.516338)
			(xy 133.388874 -276.516338) (xy 133.392834 -276.467284) (xy 133.404611 -276.4195) (xy 133.423902 -276.374224)
			(xy 133.450205 -276.332628) (xy 133.48284 -276.295791) (xy 133.520961 -276.264666) (xy 133.563582 -276.240059)
			(xy 133.609598 -276.222607) (xy 133.657817 -276.212763) (xy 133.706992 -276.210782) (xy 133.755847 -276.216714)
			(xy 133.803118 -276.230406) (xy 133.84758 -276.251504) (xy 133.888083 -276.27946) (xy 133.923576 -276.313552)
			(xy 133.953141 -276.352896) (xy 133.976012 -276.396473) (xy 133.991596 -276.443154) (xy 133.999491 -276.491731)
			(xy 133.999986 -276.516338) (xy 134.328928 -276.516338) (xy 134.332888 -276.467284) (xy 134.344665 -276.4195)
			(xy 134.363956 -276.374224) (xy 134.390259 -276.332628) (xy 134.422894 -276.295791) (xy 134.461015 -276.264666)
			(xy 134.503636 -276.240059) (xy 134.549652 -276.222607) (xy 134.597871 -276.212763) (xy 134.647046 -276.210782)
			(xy 134.695901 -276.216714) (xy 134.743172 -276.230406) (xy 134.787634 -276.251504) (xy 134.828137 -276.27946)
			(xy 134.86363 -276.313552) (xy 134.893195 -276.352896) (xy 134.916066 -276.396473) (xy 134.93165 -276.443154)
			(xy 134.939545 -276.491731) (xy 134.94004 -276.516338) (xy 135.268982 -276.516338) (xy 135.272942 -276.467284)
			(xy 135.284719 -276.4195) (xy 135.30401 -276.374224) (xy 135.330313 -276.332628) (xy 135.362948 -276.295791)
			(xy 135.401069 -276.264666) (xy 135.44369 -276.240059) (xy 135.489706 -276.222607) (xy 135.537925 -276.212763)
			(xy 135.5871 -276.210782) (xy 135.635955 -276.216714) (xy 135.683226 -276.230406) (xy 135.727688 -276.251504)
			(xy 135.768191 -276.27946) (xy 135.803684 -276.313552) (xy 135.833249 -276.352896) (xy 135.85612 -276.396473)
			(xy 135.871704 -276.443154) (xy 135.879599 -276.491731) (xy 135.880094 -276.516338) (xy 136.209036 -276.516338)
			(xy 136.212996 -276.467284) (xy 136.224773 -276.4195) (xy 136.244064 -276.374224) (xy 136.270367 -276.332628)
			(xy 136.303002 -276.295791) (xy 136.341123 -276.264666) (xy 136.383744 -276.240059) (xy 136.42976 -276.222607)
			(xy 136.477979 -276.212763) (xy 136.527154 -276.210782) (xy 136.576009 -276.216714) (xy 136.62328 -276.230406)
			(xy 136.667742 -276.251504) (xy 136.708245 -276.27946) (xy 136.743738 -276.313552) (xy 136.773303 -276.352896)
			(xy 136.796174 -276.396473) (xy 136.811758 -276.443154) (xy 136.819653 -276.491731) (xy 136.820148 -276.516338)
			(xy 136.819653 -276.540945) (xy 136.811758 -276.589522) (xy 136.796174 -276.636203) (xy 136.773303 -276.67978)
			(xy 136.743738 -276.719124) (xy 136.708245 -276.753216) (xy 136.667742 -276.781172) (xy 136.62328 -276.80227)
			(xy 136.576009 -276.815962) (xy 136.527154 -276.821894) (xy 136.477979 -276.819913) (xy 136.42976 -276.810069)
			(xy 136.383744 -276.792617) (xy 136.341123 -276.76801) (xy 136.303002 -276.736885) (xy 136.270367 -276.700048)
			(xy 136.244064 -276.658452) (xy 136.224773 -276.613176) (xy 136.212996 -276.565392) (xy 136.209036 -276.516338)
			(xy 135.880094 -276.516338) (xy 135.879599 -276.540945) (xy 135.871704 -276.589522) (xy 135.85612 -276.636203)
			(xy 135.833249 -276.67978) (xy 135.803684 -276.719124) (xy 135.768191 -276.753216) (xy 135.727688 -276.781172)
			(xy 135.683226 -276.80227) (xy 135.635955 -276.815962) (xy 135.5871 -276.821894) (xy 135.537925 -276.819913)
			(xy 135.489706 -276.810069) (xy 135.44369 -276.792617) (xy 135.401069 -276.76801) (xy 135.362948 -276.736885)
			(xy 135.330313 -276.700048) (xy 135.30401 -276.658452) (xy 135.284719 -276.613176) (xy 135.272942 -276.565392)
			(xy 135.268982 -276.516338) (xy 134.94004 -276.516338) (xy 134.939545 -276.540945) (xy 134.93165 -276.589522)
			(xy 134.916066 -276.636203) (xy 134.893195 -276.67978) (xy 134.86363 -276.719124) (xy 134.828137 -276.753216)
			(xy 134.787634 -276.781172) (xy 134.743172 -276.80227) (xy 134.695901 -276.815962) (xy 134.647046 -276.821894)
			(xy 134.597871 -276.819913) (xy 134.549652 -276.810069) (xy 134.503636 -276.792617) (xy 134.461015 -276.76801)
			(xy 134.422894 -276.736885) (xy 134.390259 -276.700048) (xy 134.363956 -276.658452) (xy 134.344665 -276.613176)
			(xy 134.332888 -276.565392) (xy 134.328928 -276.516338) (xy 133.999986 -276.516338) (xy 133.999491 -276.540945)
			(xy 133.991596 -276.589522) (xy 133.976012 -276.636203) (xy 133.953141 -276.67978) (xy 133.923576 -276.719124)
			(xy 133.888083 -276.753216) (xy 133.84758 -276.781172) (xy 133.803118 -276.80227) (xy 133.755847 -276.815962)
			(xy 133.706992 -276.821894) (xy 133.657817 -276.819913) (xy 133.609598 -276.810069) (xy 133.563582 -276.792617)
			(xy 133.520961 -276.76801) (xy 133.48284 -276.736885) (xy 133.450205 -276.700048) (xy 133.423902 -276.658452)
			(xy 133.404611 -276.613176) (xy 133.392834 -276.565392) (xy 133.388874 -276.516338) (xy 133.0706 -276.516338)
			(xy 133.070088 -276.541784) (xy 133.061924 -276.592018) (xy 133.045808 -276.640292) (xy 133.022157 -276.685355)
			(xy 132.991584 -276.726041) (xy 132.95488 -276.761296) (xy 132.912996 -276.790206) (xy 132.867017 -276.812023)
			(xy 132.818133 -276.826183) (xy 132.767612 -276.832317) (xy 132.71676 -276.830268) (xy 132.666896 -276.820088)
			(xy 132.61931 -276.802041) (xy 132.575236 -276.776595) (xy 132.535814 -276.744408) (xy 132.502066 -276.706314)
			(xy 132.474865 -276.6633) (xy 132.454917 -276.61648) (xy 132.442738 -276.567066) (xy 132.438643 -276.516338)
			(xy 132.130546 -276.516338) (xy 132.130034 -276.541784) (xy 132.12187 -276.592018) (xy 132.105754 -276.640292)
			(xy 132.082103 -276.685355) (xy 132.05153 -276.726041) (xy 132.014826 -276.761296) (xy 131.972942 -276.790206)
			(xy 131.926963 -276.812023) (xy 131.878079 -276.826183) (xy 131.827558 -276.832317) (xy 131.776706 -276.830268)
			(xy 131.726842 -276.820088) (xy 131.679256 -276.802041) (xy 131.635182 -276.776595) (xy 131.59576 -276.744408)
			(xy 131.562012 -276.706314) (xy 131.534811 -276.6633) (xy 131.514863 -276.61648) (xy 131.502684 -276.567066)
			(xy 131.498589 -276.516338) (xy 131.180078 -276.516338) (xy 131.179583 -276.540945) (xy 131.171688 -276.589522)
			(xy 131.156104 -276.636203) (xy 131.133233 -276.67978) (xy 131.103668 -276.719124) (xy 131.068175 -276.753216)
			(xy 131.027672 -276.781172) (xy 130.98321 -276.80227) (xy 130.935939 -276.815962) (xy 130.887084 -276.821894)
			(xy 130.837909 -276.819913) (xy 130.78969 -276.810069) (xy 130.743674 -276.792617) (xy 130.701053 -276.76801)
			(xy 130.662932 -276.736885) (xy 130.630297 -276.700048) (xy 130.603994 -276.658452) (xy 130.584703 -276.613176)
			(xy 130.572926 -276.565392) (xy 130.568966 -276.516338) (xy 130.250438 -276.516338) (xy 130.249926 -276.541784)
			(xy 130.241762 -276.592018) (xy 130.225646 -276.640292) (xy 130.201995 -276.685355) (xy 130.171422 -276.726041)
			(xy 130.134718 -276.761296) (xy 130.092834 -276.790206) (xy 130.046855 -276.812023) (xy 129.997971 -276.826183)
			(xy 129.94745 -276.832317) (xy 129.896598 -276.830268) (xy 129.846734 -276.820088) (xy 129.799148 -276.802041)
			(xy 129.755074 -276.776595) (xy 129.715652 -276.744408) (xy 129.681904 -276.706314) (xy 129.654703 -276.6633)
			(xy 129.634755 -276.61648) (xy 129.622576 -276.567066) (xy 129.618481 -276.516338) (xy 129.29997 -276.516338)
			(xy 129.299475 -276.540945) (xy 129.29158 -276.589522) (xy 129.275996 -276.636203) (xy 129.253125 -276.67978)
			(xy 129.22356 -276.719124) (xy 129.188067 -276.753216) (xy 129.147564 -276.781172) (xy 129.103102 -276.80227)
			(xy 129.055831 -276.815962) (xy 129.006976 -276.821894) (xy 128.957801 -276.819913) (xy 128.909582 -276.810069)
			(xy 128.863566 -276.792617) (xy 128.820945 -276.76801) (xy 128.782824 -276.736885) (xy 128.750189 -276.700048)
			(xy 128.723886 -276.658452) (xy 128.704595 -276.613176) (xy 128.692818 -276.565392) (xy 128.688858 -276.516338)
			(xy 128.370584 -276.516338) (xy 128.370072 -276.541784) (xy 128.361908 -276.592018) (xy 128.345792 -276.640292)
			(xy 128.322141 -276.685355) (xy 128.291568 -276.726041) (xy 128.254864 -276.761296) (xy 128.21298 -276.790206)
			(xy 128.167001 -276.812023) (xy 128.118117 -276.826183) (xy 128.067596 -276.832317) (xy 128.016744 -276.830268)
			(xy 127.96688 -276.820088) (xy 127.919294 -276.802041) (xy 127.87522 -276.776595) (xy 127.835798 -276.744408)
			(xy 127.80205 -276.706314) (xy 127.774849 -276.6633) (xy 127.754901 -276.61648) (xy 127.742722 -276.567066)
			(xy 127.738627 -276.516338) (xy 127.472186 -276.516338) (xy 127.472186 -276.555454) (xy 127.484632 -276.587712)
			(xy 127.490474 -276.59457) (xy 127.490474 -276.594824) (xy 127.521877 -276.631933) (xy 127.578851 -276.71071)
			(xy 127.628767 -276.794138) (xy 127.67125 -276.881586) (xy 127.689102 -276.926802) (xy 127.695107 -276.942591)
			(xy 127.706284 -276.974474) (xy 127.711454 -276.990556) (xy 127.715264 -276.9997) (xy 127.719836 -277.008082)
			(xy 127.722122 -277.012654) (xy 127.739648 -277.03399) (xy 127.74803 -277.038816) (xy 127.769466 -277.051514)
			(xy 127.808601 -277.082345) (xy 127.842668 -277.118699) (xy 127.870895 -277.159752) (xy 127.892643 -277.204575)
			(xy 127.90742 -277.252154) (xy 127.914891 -277.301411) (xy 127.914889 -277.326344) (xy 128.208527 -277.326344)
			(xy 128.212622 -277.275616) (xy 128.224801 -277.226202) (xy 128.244749 -277.179382) (xy 128.27195 -277.136368)
			(xy 128.305698 -277.098274) (xy 128.34512 -277.066087) (xy 128.389194 -277.040641) (xy 128.43678 -277.022594)
			(xy 128.486644 -277.012414) (xy 128.537496 -277.010365) (xy 128.588017 -277.016499) (xy 128.636901 -277.030659)
			(xy 128.68288 -277.052476) (xy 128.724764 -277.081386) (xy 128.761468 -277.116641) (xy 128.792041 -277.157327)
			(xy 128.815692 -277.20239) (xy 128.831808 -277.250664) (xy 128.839972 -277.300898) (xy 128.840484 -277.326344)
			(xy 129.148581 -277.326344) (xy 129.152676 -277.275616) (xy 129.164855 -277.226202) (xy 129.184803 -277.179382)
			(xy 129.212004 -277.136368) (xy 129.245752 -277.098274) (xy 129.285174 -277.066087) (xy 129.329248 -277.040641)
			(xy 129.376834 -277.022594) (xy 129.426698 -277.012414) (xy 129.47755 -277.010365) (xy 129.528071 -277.016499)
			(xy 129.576955 -277.030659) (xy 129.622934 -277.052476) (xy 129.664818 -277.081386) (xy 129.701522 -277.116641)
			(xy 129.732095 -277.157327) (xy 129.755746 -277.20239) (xy 129.771862 -277.250664) (xy 129.780026 -277.300898)
			(xy 129.780538 -277.326344) (xy 130.099066 -277.326344) (xy 130.103026 -277.27729) (xy 130.114803 -277.229506)
			(xy 130.134094 -277.18423) (xy 130.160397 -277.142634) (xy 130.193032 -277.105797) (xy 130.231153 -277.074672)
			(xy 130.273774 -277.050065) (xy 130.31979 -277.032613) (xy 130.368009 -277.022769) (xy 130.417184 -277.020788)
			(xy 130.466039 -277.02672) (xy 130.51331 -277.040412) (xy 130.557772 -277.06151) (xy 130.598275 -277.089466)
			(xy 130.633768 -277.123558) (xy 130.663333 -277.162902) (xy 130.686204 -277.206479) (xy 130.701788 -277.25316)
			(xy 130.709683 -277.301737) (xy 130.710178 -277.326344) (xy 131.028435 -277.326344) (xy 131.03253 -277.275616)
			(xy 131.044709 -277.226202) (xy 131.064657 -277.179382) (xy 131.091858 -277.136368) (xy 131.125606 -277.098274)
			(xy 131.165028 -277.066087) (xy 131.209102 -277.040641) (xy 131.256688 -277.022594) (xy 131.306552 -277.012414)
			(xy 131.357404 -277.010365) (xy 131.407925 -277.016499) (xy 131.456809 -277.030659) (xy 131.502788 -277.052476)
			(xy 131.544672 -277.081386) (xy 131.581376 -277.116641) (xy 131.611949 -277.157327) (xy 131.6356 -277.20239)
			(xy 131.651716 -277.250664) (xy 131.65988 -277.300898) (xy 131.660392 -277.326344) (xy 131.97892 -277.326344)
			(xy 131.98288 -277.27729) (xy 131.994657 -277.229506) (xy 132.013948 -277.18423) (xy 132.040251 -277.142634)
			(xy 132.072886 -277.105797) (xy 132.111007 -277.074672) (xy 132.153628 -277.050065) (xy 132.199644 -277.032613)
			(xy 132.247863 -277.022769) (xy 132.297038 -277.020788) (xy 132.345893 -277.02672) (xy 132.393164 -277.040412)
			(xy 132.437626 -277.06151) (xy 132.478129 -277.089466) (xy 132.513622 -277.123558) (xy 132.543187 -277.162902)
			(xy 132.566058 -277.206479) (xy 132.581642 -277.25316) (xy 132.589537 -277.301737) (xy 132.590032 -277.326344)
			(xy 132.908543 -277.326344) (xy 132.912638 -277.275616) (xy 132.924817 -277.226202) (xy 132.944765 -277.179382)
			(xy 132.971966 -277.136368) (xy 133.005714 -277.098274) (xy 133.045136 -277.066087) (xy 133.08921 -277.040641)
			(xy 133.136796 -277.022594) (xy 133.18666 -277.012414) (xy 133.237512 -277.010365) (xy 133.288033 -277.016499)
			(xy 133.336917 -277.030659) (xy 133.382896 -277.052476) (xy 133.42478 -277.081386) (xy 133.461484 -277.116641)
			(xy 133.492057 -277.157327) (xy 133.515708 -277.20239) (xy 133.531824 -277.250664) (xy 133.539988 -277.300898)
			(xy 133.5405 -277.326344) (xy 133.859028 -277.326344) (xy 133.862988 -277.27729) (xy 133.874765 -277.229506)
			(xy 133.894056 -277.18423) (xy 133.920359 -277.142634) (xy 133.952994 -277.105797) (xy 133.991115 -277.074672)
			(xy 134.033736 -277.050065) (xy 134.079752 -277.032613) (xy 134.127971 -277.022769) (xy 134.177146 -277.020788)
			(xy 134.226001 -277.02672) (xy 134.273272 -277.040412) (xy 134.317734 -277.06151) (xy 134.358237 -277.089466)
			(xy 134.39373 -277.123558) (xy 134.423295 -277.162902) (xy 134.446166 -277.206479) (xy 134.46175 -277.25316)
			(xy 134.469645 -277.301737) (xy 134.47014 -277.326344) (xy 134.798828 -277.326344) (xy 134.802788 -277.27729)
			(xy 134.814565 -277.229506) (xy 134.833856 -277.18423) (xy 134.860159 -277.142634) (xy 134.892794 -277.105797)
			(xy 134.930915 -277.074672) (xy 134.973536 -277.050065) (xy 135.019552 -277.032613) (xy 135.067771 -277.022769)
			(xy 135.116946 -277.020788) (xy 135.165801 -277.02672) (xy 135.213072 -277.040412) (xy 135.257534 -277.06151)
			(xy 135.298037 -277.089466) (xy 135.33353 -277.123558) (xy 135.363095 -277.162902) (xy 135.385966 -277.206479)
			(xy 135.40155 -277.25316) (xy 135.409445 -277.301737) (xy 135.40994 -277.326344) (xy 135.738882 -277.326344)
			(xy 135.742842 -277.27729) (xy 135.754619 -277.229506) (xy 135.77391 -277.18423) (xy 135.800213 -277.142634)
			(xy 135.832848 -277.105797) (xy 135.870969 -277.074672) (xy 135.91359 -277.050065) (xy 135.959606 -277.032613)
			(xy 136.007825 -277.022769) (xy 136.057 -277.020788) (xy 136.105855 -277.02672) (xy 136.153126 -277.040412)
			(xy 136.197588 -277.06151) (xy 136.238091 -277.089466) (xy 136.273584 -277.123558) (xy 136.303149 -277.162902)
			(xy 136.32602 -277.206479) (xy 136.341604 -277.25316) (xy 136.349499 -277.301737) (xy 136.349994 -277.326344)
			(xy 136.349499 -277.350951) (xy 136.341604 -277.399528) (xy 136.32602 -277.446209) (xy 136.303149 -277.489786)
			(xy 136.273584 -277.52913) (xy 136.238091 -277.563222) (xy 136.197588 -277.591178) (xy 136.153126 -277.612276)
			(xy 136.105855 -277.625968) (xy 136.057 -277.6319) (xy 136.007825 -277.629919) (xy 135.959606 -277.620075)
			(xy 135.91359 -277.602623) (xy 135.870969 -277.578016) (xy 135.832848 -277.546891) (xy 135.800213 -277.510054)
			(xy 135.77391 -277.468458) (xy 135.754619 -277.423182) (xy 135.742842 -277.375398) (xy 135.738882 -277.326344)
			(xy 135.40994 -277.326344) (xy 135.409445 -277.350951) (xy 135.40155 -277.399528) (xy 135.385966 -277.446209)
			(xy 135.363095 -277.489786) (xy 135.33353 -277.52913) (xy 135.298037 -277.563222) (xy 135.257534 -277.591178)
			(xy 135.213072 -277.612276) (xy 135.165801 -277.625968) (xy 135.116946 -277.6319) (xy 135.067771 -277.629919)
			(xy 135.019552 -277.620075) (xy 134.973536 -277.602623) (xy 134.930915 -277.578016) (xy 134.892794 -277.546891)
			(xy 134.860159 -277.510054) (xy 134.833856 -277.468458) (xy 134.814565 -277.423182) (xy 134.802788 -277.375398)
			(xy 134.798828 -277.326344) (xy 134.47014 -277.326344) (xy 134.469645 -277.350951) (xy 134.46175 -277.399528)
			(xy 134.446166 -277.446209) (xy 134.423295 -277.489786) (xy 134.39373 -277.52913) (xy 134.358237 -277.563222)
			(xy 134.317734 -277.591178) (xy 134.273272 -277.612276) (xy 134.226001 -277.625968) (xy 134.177146 -277.6319)
			(xy 134.127971 -277.629919) (xy 134.079752 -277.620075) (xy 134.033736 -277.602623) (xy 133.991115 -277.578016)
			(xy 133.952994 -277.546891) (xy 133.920359 -277.510054) (xy 133.894056 -277.468458) (xy 133.874765 -277.423182)
			(xy 133.862988 -277.375398) (xy 133.859028 -277.326344) (xy 133.5405 -277.326344) (xy 133.539988 -277.35179)
			(xy 133.531824 -277.402024) (xy 133.515708 -277.450298) (xy 133.492057 -277.495361) (xy 133.461484 -277.536047)
			(xy 133.42478 -277.571302) (xy 133.382896 -277.600212) (xy 133.336917 -277.622029) (xy 133.288033 -277.636189)
			(xy 133.237512 -277.642323) (xy 133.18666 -277.640274) (xy 133.136796 -277.630094) (xy 133.08921 -277.612047)
			(xy 133.045136 -277.586601) (xy 133.005714 -277.554414) (xy 132.971966 -277.51632) (xy 132.944765 -277.473306)
			(xy 132.924817 -277.426486) (xy 132.912638 -277.377072) (xy 132.908543 -277.326344) (xy 132.590032 -277.326344)
			(xy 132.589537 -277.350951) (xy 132.581642 -277.399528) (xy 132.566058 -277.446209) (xy 132.543187 -277.489786)
			(xy 132.513622 -277.52913) (xy 132.478129 -277.563222) (xy 132.437626 -277.591178) (xy 132.393164 -277.612276)
			(xy 132.345893 -277.625968) (xy 132.297038 -277.6319) (xy 132.247863 -277.629919) (xy 132.199644 -277.620075)
			(xy 132.153628 -277.602623) (xy 132.111007 -277.578016) (xy 132.072886 -277.546891) (xy 132.040251 -277.510054)
			(xy 132.013948 -277.468458) (xy 131.994657 -277.423182) (xy 131.98288 -277.375398) (xy 131.97892 -277.326344)
			(xy 131.660392 -277.326344) (xy 131.65988 -277.35179) (xy 131.651716 -277.402024) (xy 131.6356 -277.450298)
			(xy 131.611949 -277.495361) (xy 131.581376 -277.536047) (xy 131.544672 -277.571302) (xy 131.502788 -277.600212)
			(xy 131.456809 -277.622029) (xy 131.407925 -277.636189) (xy 131.357404 -277.642323) (xy 131.306552 -277.640274)
			(xy 131.256688 -277.630094) (xy 131.209102 -277.612047) (xy 131.165028 -277.586601) (xy 131.125606 -277.554414)
			(xy 131.091858 -277.51632) (xy 131.064657 -277.473306) (xy 131.044709 -277.426486) (xy 131.03253 -277.377072)
			(xy 131.028435 -277.326344) (xy 130.710178 -277.326344) (xy 130.709683 -277.350951) (xy 130.701788 -277.399528)
			(xy 130.686204 -277.446209) (xy 130.663333 -277.489786) (xy 130.633768 -277.52913) (xy 130.598275 -277.563222)
			(xy 130.557772 -277.591178) (xy 130.51331 -277.612276) (xy 130.466039 -277.625968) (xy 130.417184 -277.6319)
			(xy 130.368009 -277.629919) (xy 130.31979 -277.620075) (xy 130.273774 -277.602623) (xy 130.231153 -277.578016)
			(xy 130.193032 -277.546891) (xy 130.160397 -277.510054) (xy 130.134094 -277.468458) (xy 130.114803 -277.423182)
			(xy 130.103026 -277.375398) (xy 130.099066 -277.326344) (xy 129.780538 -277.326344) (xy 129.780026 -277.35179)
			(xy 129.771862 -277.402024) (xy 129.755746 -277.450298) (xy 129.732095 -277.495361) (xy 129.701522 -277.536047)
			(xy 129.664818 -277.571302) (xy 129.622934 -277.600212) (xy 129.576955 -277.622029) (xy 129.528071 -277.636189)
			(xy 129.47755 -277.642323) (xy 129.426698 -277.640274) (xy 129.376834 -277.630094) (xy 129.329248 -277.612047)
			(xy 129.285174 -277.586601) (xy 129.245752 -277.554414) (xy 129.212004 -277.51632) (xy 129.184803 -277.473306)
			(xy 129.164855 -277.426486) (xy 129.152676 -277.377072) (xy 129.148581 -277.326344) (xy 128.840484 -277.326344)
			(xy 128.839972 -277.35179) (xy 128.831808 -277.402024) (xy 128.815692 -277.450298) (xy 128.792041 -277.495361)
			(xy 128.761468 -277.536047) (xy 128.724764 -277.571302) (xy 128.68288 -277.600212) (xy 128.636901 -277.622029)
			(xy 128.588017 -277.636189) (xy 128.537496 -277.642323) (xy 128.486644 -277.640274) (xy 128.43678 -277.630094)
			(xy 128.389194 -277.612047) (xy 128.34512 -277.586601) (xy 128.305698 -277.554414) (xy 128.27195 -277.51632)
			(xy 128.244749 -277.473306) (xy 128.224801 -277.426486) (xy 128.212622 -277.377072) (xy 128.208527 -277.326344)
			(xy 127.914889 -277.326344) (xy 127.914888 -277.351232) (xy 127.90741 -277.400489) (xy 127.892627 -277.448066)
			(xy 127.870873 -277.492886) (xy 127.84264 -277.533935) (xy 127.808569 -277.570284) (xy 127.76943 -277.60111)
			(xy 127.74803 -277.613872) (xy 127.739648 -277.618698) (xy 127.71628 -277.6474) (xy 127.712978 -277.657306)
			(xy 127.712724 -277.657814) (xy 127.699535 -277.698955) (xy 127.66765 -277.77926) (xy 127.629659 -277.856862)
			(xy 127.608076 -277.894288) (xy 127.58191 -277.937522) (xy 127.522893 -278.019565) (xy 127.49022 -278.058118)
			(xy 127.49022 -278.058372) (xy 127.484378 -278.06523) (xy 127.477012 -278.084026) (xy 127.476758 -278.085042)
			(xy 127.475234 -278.08936) (xy 127.473824 -278.093539) (xy 127.472292 -278.102223) (xy 127.472186 -278.106632)
			(xy 127.472186 -278.13635) (xy 127.738627 -278.13635) (xy 127.742722 -278.085622) (xy 127.754901 -278.036208)
			(xy 127.774849 -277.989388) (xy 127.80205 -277.946374) (xy 127.835798 -277.90828) (xy 127.87522 -277.876093)
			(xy 127.919294 -277.850647) (xy 127.96688 -277.8326) (xy 128.016744 -277.82242) (xy 128.067596 -277.820371)
			(xy 128.118117 -277.826505) (xy 128.167001 -277.840665) (xy 128.21298 -277.862482) (xy 128.254864 -277.891392)
			(xy 128.291568 -277.926647) (xy 128.322141 -277.967333) (xy 128.345792 -278.012396) (xy 128.361908 -278.06067)
			(xy 128.370072 -278.110904) (xy 128.370584 -278.13635) (xy 128.688858 -278.13635) (xy 128.692818 -278.087296)
			(xy 128.704595 -278.039512) (xy 128.723886 -277.994236) (xy 128.750189 -277.95264) (xy 128.782824 -277.915803)
			(xy 128.820945 -277.884678) (xy 128.863566 -277.860071) (xy 128.909582 -277.842619) (xy 128.957801 -277.832775)
			(xy 129.006976 -277.830794) (xy 129.055831 -277.836726) (xy 129.103102 -277.850418) (xy 129.147564 -277.871516)
			(xy 129.188067 -277.899472) (xy 129.22356 -277.933564) (xy 129.253125 -277.972908) (xy 129.275996 -278.016485)
			(xy 129.29158 -278.063166) (xy 129.299475 -278.111743) (xy 129.29997 -278.13635) (xy 129.618481 -278.13635)
			(xy 129.622576 -278.085622) (xy 129.634755 -278.036208) (xy 129.654703 -277.989388) (xy 129.681904 -277.946374)
			(xy 129.715652 -277.90828) (xy 129.755074 -277.876093) (xy 129.799148 -277.850647) (xy 129.846734 -277.8326)
			(xy 129.896598 -277.82242) (xy 129.94745 -277.820371) (xy 129.997971 -277.826505) (xy 130.046855 -277.840665)
			(xy 130.092834 -277.862482) (xy 130.134718 -277.891392) (xy 130.171422 -277.926647) (xy 130.201995 -277.967333)
			(xy 130.225646 -278.012396) (xy 130.241762 -278.06067) (xy 130.249926 -278.110904) (xy 130.250438 -278.13635)
			(xy 131.498589 -278.13635) (xy 131.502684 -278.085622) (xy 131.514863 -278.036208) (xy 131.534811 -277.989388)
			(xy 131.562012 -277.946374) (xy 131.59576 -277.90828) (xy 131.635182 -277.876093) (xy 131.679256 -277.850647)
			(xy 131.726842 -277.8326) (xy 131.776706 -277.82242) (xy 131.827558 -277.820371) (xy 131.878079 -277.826505)
			(xy 131.926963 -277.840665) (xy 131.972942 -277.862482) (xy 132.014826 -277.891392) (xy 132.05153 -277.926647)
			(xy 132.082103 -277.967333) (xy 132.105754 -278.012396) (xy 132.12187 -278.06067) (xy 132.130034 -278.110904)
			(xy 132.130546 -278.13635) (xy 132.438643 -278.13635) (xy 132.442738 -278.085622) (xy 132.454917 -278.036208)
			(xy 132.474865 -277.989388) (xy 132.502066 -277.946374) (xy 132.535814 -277.90828) (xy 132.575236 -277.876093)
			(xy 132.61931 -277.850647) (xy 132.666896 -277.8326) (xy 132.71676 -277.82242) (xy 132.767612 -277.820371)
			(xy 132.818133 -277.826505) (xy 132.867017 -277.840665) (xy 132.912996 -277.862482) (xy 132.95488 -277.891392)
			(xy 132.991584 -277.926647) (xy 133.022157 -277.967333) (xy 133.045808 -278.012396) (xy 133.061924 -278.06067)
			(xy 133.070088 -278.110904) (xy 133.0706 -278.13635) (xy 133.388874 -278.13635) (xy 133.392834 -278.087296)
			(xy 133.404611 -278.039512) (xy 133.423902 -277.994236) (xy 133.450205 -277.95264) (xy 133.48284 -277.915803)
			(xy 133.520961 -277.884678) (xy 133.563582 -277.860071) (xy 133.609598 -277.842619) (xy 133.657817 -277.832775)
			(xy 133.706992 -277.830794) (xy 133.755847 -277.836726) (xy 133.803118 -277.850418) (xy 133.84758 -277.871516)
			(xy 133.888083 -277.899472) (xy 133.923576 -277.933564) (xy 133.953141 -277.972908) (xy 133.976012 -278.016485)
			(xy 133.991596 -278.063166) (xy 133.999491 -278.111743) (xy 133.999986 -278.13635) (xy 134.328928 -278.13635)
			(xy 134.332888 -278.087296) (xy 134.344665 -278.039512) (xy 134.363956 -277.994236) (xy 134.390259 -277.95264)
			(xy 134.422894 -277.915803) (xy 134.461015 -277.884678) (xy 134.503636 -277.860071) (xy 134.549652 -277.842619)
			(xy 134.597871 -277.832775) (xy 134.647046 -277.830794) (xy 134.695901 -277.836726) (xy 134.743172 -277.850418)
			(xy 134.787634 -277.871516) (xy 134.828137 -277.899472) (xy 134.86363 -277.933564) (xy 134.893195 -277.972908)
			(xy 134.916066 -278.016485) (xy 134.93165 -278.063166) (xy 134.939545 -278.111743) (xy 134.94004 -278.13635)
			(xy 135.268982 -278.13635) (xy 135.272942 -278.087296) (xy 135.284719 -278.039512) (xy 135.30401 -277.994236)
			(xy 135.330313 -277.95264) (xy 135.362948 -277.915803) (xy 135.401069 -277.884678) (xy 135.44369 -277.860071)
			(xy 135.489706 -277.842619) (xy 135.537925 -277.832775) (xy 135.5871 -277.830794) (xy 135.635955 -277.836726)
			(xy 135.683226 -277.850418) (xy 135.727688 -277.871516) (xy 135.768191 -277.899472) (xy 135.803684 -277.933564)
			(xy 135.833249 -277.972908) (xy 135.85612 -278.016485) (xy 135.871704 -278.063166) (xy 135.879599 -278.111743)
			(xy 135.880094 -278.13635) (xy 136.209036 -278.13635) (xy 136.212996 -278.087296) (xy 136.224773 -278.039512)
			(xy 136.244064 -277.994236) (xy 136.270367 -277.95264) (xy 136.303002 -277.915803) (xy 136.341123 -277.884678)
			(xy 136.383744 -277.860071) (xy 136.42976 -277.842619) (xy 136.477979 -277.832775) (xy 136.527154 -277.830794)
			(xy 136.576009 -277.836726) (xy 136.62328 -277.850418) (xy 136.667742 -277.871516) (xy 136.708245 -277.899472)
			(xy 136.743738 -277.933564) (xy 136.773303 -277.972908) (xy 136.796174 -278.016485) (xy 136.811758 -278.063166)
			(xy 136.819653 -278.111743) (xy 136.820148 -278.13635) (xy 136.819653 -278.160957) (xy 136.811758 -278.209534)
			(xy 136.796174 -278.256215) (xy 136.773303 -278.299792) (xy 136.743738 -278.339136) (xy 136.708245 -278.373228)
			(xy 136.667742 -278.401184) (xy 136.62328 -278.422282) (xy 136.576009 -278.435974) (xy 136.527154 -278.441906)
			(xy 136.477979 -278.439925) (xy 136.42976 -278.430081) (xy 136.383744 -278.412629) (xy 136.341123 -278.388022)
			(xy 136.303002 -278.356897) (xy 136.270367 -278.32006) (xy 136.244064 -278.278464) (xy 136.224773 -278.233188)
			(xy 136.212996 -278.185404) (xy 136.209036 -278.13635) (xy 135.880094 -278.13635) (xy 135.879599 -278.160957)
			(xy 135.871704 -278.209534) (xy 135.85612 -278.256215) (xy 135.833249 -278.299792) (xy 135.803684 -278.339136)
			(xy 135.768191 -278.373228) (xy 135.727688 -278.401184) (xy 135.683226 -278.422282) (xy 135.635955 -278.435974)
			(xy 135.5871 -278.441906) (xy 135.537925 -278.439925) (xy 135.489706 -278.430081) (xy 135.44369 -278.412629)
			(xy 135.401069 -278.388022) (xy 135.362948 -278.356897) (xy 135.330313 -278.32006) (xy 135.30401 -278.278464)
			(xy 135.284719 -278.233188) (xy 135.272942 -278.185404) (xy 135.268982 -278.13635) (xy 134.94004 -278.13635)
			(xy 134.939545 -278.160957) (xy 134.93165 -278.209534) (xy 134.916066 -278.256215) (xy 134.893195 -278.299792)
			(xy 134.86363 -278.339136) (xy 134.828137 -278.373228) (xy 134.787634 -278.401184) (xy 134.743172 -278.422282)
			(xy 134.695901 -278.435974) (xy 134.647046 -278.441906) (xy 134.597871 -278.439925) (xy 134.549652 -278.430081)
			(xy 134.503636 -278.412629) (xy 134.461015 -278.388022) (xy 134.422894 -278.356897) (xy 134.390259 -278.32006)
			(xy 134.363956 -278.278464) (xy 134.344665 -278.233188) (xy 134.332888 -278.185404) (xy 134.328928 -278.13635)
			(xy 133.999986 -278.13635) (xy 133.999491 -278.160957) (xy 133.991596 -278.209534) (xy 133.976012 -278.256215)
			(xy 133.953141 -278.299792) (xy 133.923576 -278.339136) (xy 133.888083 -278.373228) (xy 133.84758 -278.401184)
			(xy 133.803118 -278.422282) (xy 133.755847 -278.435974) (xy 133.706992 -278.441906) (xy 133.657817 -278.439925)
			(xy 133.609598 -278.430081) (xy 133.563582 -278.412629) (xy 133.520961 -278.388022) (xy 133.48284 -278.356897)
			(xy 133.450205 -278.32006) (xy 133.423902 -278.278464) (xy 133.404611 -278.233188) (xy 133.392834 -278.185404)
			(xy 133.388874 -278.13635) (xy 133.0706 -278.13635) (xy 133.070088 -278.161796) (xy 133.061924 -278.21203)
			(xy 133.045808 -278.260304) (xy 133.022157 -278.305367) (xy 132.991584 -278.346053) (xy 132.95488 -278.381308)
			(xy 132.912996 -278.410218) (xy 132.867017 -278.432035) (xy 132.818133 -278.446195) (xy 132.767612 -278.452329)
			(xy 132.71676 -278.45028) (xy 132.666896 -278.4401) (xy 132.61931 -278.422053) (xy 132.575236 -278.396607)
			(xy 132.535814 -278.36442) (xy 132.502066 -278.326326) (xy 132.474865 -278.283312) (xy 132.454917 -278.236492)
			(xy 132.442738 -278.187078) (xy 132.438643 -278.13635) (xy 132.130546 -278.13635) (xy 132.130034 -278.161796)
			(xy 132.12187 -278.21203) (xy 132.105754 -278.260304) (xy 132.082103 -278.305367) (xy 132.05153 -278.346053)
			(xy 132.014826 -278.381308) (xy 131.972942 -278.410218) (xy 131.926963 -278.432035) (xy 131.878079 -278.446195)
			(xy 131.827558 -278.452329) (xy 131.776706 -278.45028) (xy 131.726842 -278.4401) (xy 131.679256 -278.422053)
			(xy 131.635182 -278.396607) (xy 131.59576 -278.36442) (xy 131.562012 -278.326326) (xy 131.534811 -278.283312)
			(xy 131.514863 -278.236492) (xy 131.502684 -278.187078) (xy 131.498589 -278.13635) (xy 130.250438 -278.13635)
			(xy 130.249926 -278.161796) (xy 130.241762 -278.21203) (xy 130.225646 -278.260304) (xy 130.201995 -278.305367)
			(xy 130.171422 -278.346053) (xy 130.134718 -278.381308) (xy 130.092834 -278.410218) (xy 130.046855 -278.432035)
			(xy 129.997971 -278.446195) (xy 129.94745 -278.452329) (xy 129.896598 -278.45028) (xy 129.846734 -278.4401)
			(xy 129.799148 -278.422053) (xy 129.755074 -278.396607) (xy 129.715652 -278.36442) (xy 129.681904 -278.326326)
			(xy 129.654703 -278.283312) (xy 129.634755 -278.236492) (xy 129.622576 -278.187078) (xy 129.618481 -278.13635)
			(xy 129.29997 -278.13635) (xy 129.299475 -278.160957) (xy 129.29158 -278.209534) (xy 129.275996 -278.256215)
			(xy 129.253125 -278.299792) (xy 129.22356 -278.339136) (xy 129.188067 -278.373228) (xy 129.147564 -278.401184)
			(xy 129.103102 -278.422282) (xy 129.055831 -278.435974) (xy 129.006976 -278.441906) (xy 128.957801 -278.439925)
			(xy 128.909582 -278.430081) (xy 128.863566 -278.412629) (xy 128.820945 -278.388022) (xy 128.782824 -278.356897)
			(xy 128.750189 -278.32006) (xy 128.723886 -278.278464) (xy 128.704595 -278.233188) (xy 128.692818 -278.185404)
			(xy 128.688858 -278.13635) (xy 128.370584 -278.13635) (xy 128.370072 -278.161796) (xy 128.361908 -278.21203)
			(xy 128.345792 -278.260304) (xy 128.322141 -278.305367) (xy 128.291568 -278.346053) (xy 128.254864 -278.381308)
			(xy 128.21298 -278.410218) (xy 128.167001 -278.432035) (xy 128.118117 -278.446195) (xy 128.067596 -278.452329)
			(xy 128.016744 -278.45028) (xy 127.96688 -278.4401) (xy 127.919294 -278.422053) (xy 127.87522 -278.396607)
			(xy 127.835798 -278.36442) (xy 127.80205 -278.326326) (xy 127.774849 -278.283312) (xy 127.754901 -278.236492)
			(xy 127.742722 -278.187078) (xy 127.738627 -278.13635) (xy 127.472186 -278.13635) (xy 127.472186 -278.16556)
			(xy 127.47879 -278.182832) (xy 127.48514 -278.189944) (xy 127.515323 -278.22413) (xy 127.570696 -278.296599)
			(xy 127.620048 -278.373295) (xy 127.663059 -278.453719) (xy 127.699448 -278.537348) (xy 127.728978 -278.623637)
			(xy 127.740664 -278.667718) (xy 127.743269 -278.676364) (xy 127.753554 -278.691192) (xy 127.76073 -278.696674)
			(xy 127.779038 -278.710109) (xy 127.811851 -278.741501) (xy 127.839658 -278.777401) (xy 127.86185 -278.81702)
			(xy 127.877936 -278.859486) (xy 127.883158 -278.881586) (xy 127.888492 -278.914352) (xy 127.888492 -278.914606)
			(xy 127.889752 -278.923389) (xy 127.897406 -278.93938) (xy 127.903478 -278.945848) (xy 127.903989 -278.946356)
			(xy 128.208527 -278.946356) (xy 128.212622 -278.895628) (xy 128.224801 -278.846214) (xy 128.244749 -278.799394)
			(xy 128.27195 -278.75638) (xy 128.305698 -278.718286) (xy 128.34512 -278.686099) (xy 128.389194 -278.660653)
			(xy 128.43678 -278.642606) (xy 128.486644 -278.632426) (xy 128.537496 -278.630377) (xy 128.588017 -278.636511)
			(xy 128.636901 -278.650671) (xy 128.68288 -278.672488) (xy 128.724764 -278.701398) (xy 128.761468 -278.736653)
			(xy 128.792041 -278.777339) (xy 128.815692 -278.822402) (xy 128.831808 -278.870676) (xy 128.839972 -278.92091)
			(xy 128.840484 -278.946356) (xy 129.148581 -278.946356) (xy 129.152676 -278.895628) (xy 129.164855 -278.846214)
			(xy 129.184803 -278.799394) (xy 129.212004 -278.75638) (xy 129.245752 -278.718286) (xy 129.285174 -278.686099)
			(xy 129.329248 -278.660653) (xy 129.376834 -278.642606) (xy 129.426698 -278.632426) (xy 129.47755 -278.630377)
			(xy 129.528071 -278.636511) (xy 129.576955 -278.650671) (xy 129.622934 -278.672488) (xy 129.664818 -278.701398)
			(xy 129.701522 -278.736653) (xy 129.732095 -278.777339) (xy 129.755746 -278.822402) (xy 129.771862 -278.870676)
			(xy 129.780026 -278.92091) (xy 129.780538 -278.946356) (xy 130.099066 -278.946356) (xy 130.103026 -278.897302)
			(xy 130.114803 -278.849518) (xy 130.134094 -278.804242) (xy 130.160397 -278.762646) (xy 130.193032 -278.725809)
			(xy 130.231153 -278.694684) (xy 130.273774 -278.670077) (xy 130.31979 -278.652625) (xy 130.368009 -278.642781)
			(xy 130.417184 -278.6408) (xy 130.466039 -278.646732) (xy 130.51331 -278.660424) (xy 130.557772 -278.681522)
			(xy 130.598275 -278.709478) (xy 130.633768 -278.74357) (xy 130.663333 -278.782914) (xy 130.686204 -278.826491)
			(xy 130.701788 -278.873172) (xy 130.709683 -278.921749) (xy 130.710178 -278.946356) (xy 131.028435 -278.946356)
			(xy 131.03253 -278.895628) (xy 131.044709 -278.846214) (xy 131.064657 -278.799394) (xy 131.091858 -278.75638)
			(xy 131.125606 -278.718286) (xy 131.165028 -278.686099) (xy 131.209102 -278.660653) (xy 131.256688 -278.642606)
			(xy 131.306552 -278.632426) (xy 131.357404 -278.630377) (xy 131.407925 -278.636511) (xy 131.456809 -278.650671)
			(xy 131.502788 -278.672488) (xy 131.544672 -278.701398) (xy 131.581376 -278.736653) (xy 131.611949 -278.777339)
			(xy 131.6356 -278.822402) (xy 131.651716 -278.870676) (xy 131.65988 -278.92091) (xy 131.660392 -278.946356)
			(xy 131.97892 -278.946356) (xy 131.98288 -278.897302) (xy 131.994657 -278.849518) (xy 132.013948 -278.804242)
			(xy 132.040251 -278.762646) (xy 132.072886 -278.725809) (xy 132.111007 -278.694684) (xy 132.153628 -278.670077)
			(xy 132.199644 -278.652625) (xy 132.247863 -278.642781) (xy 132.297038 -278.6408) (xy 132.345893 -278.646732)
			(xy 132.393164 -278.660424) (xy 132.437626 -278.681522) (xy 132.478129 -278.709478) (xy 132.513622 -278.74357)
			(xy 132.543187 -278.782914) (xy 132.566058 -278.826491) (xy 132.581642 -278.873172) (xy 132.589537 -278.921749)
			(xy 132.590032 -278.946356) (xy 132.908543 -278.946356) (xy 132.912638 -278.895628) (xy 132.924817 -278.846214)
			(xy 132.944765 -278.799394) (xy 132.971966 -278.75638) (xy 133.005714 -278.718286) (xy 133.045136 -278.686099)
			(xy 133.08921 -278.660653) (xy 133.136796 -278.642606) (xy 133.18666 -278.632426) (xy 133.237512 -278.630377)
			(xy 133.288033 -278.636511) (xy 133.336917 -278.650671) (xy 133.382896 -278.672488) (xy 133.42478 -278.701398)
			(xy 133.461484 -278.736653) (xy 133.492057 -278.777339) (xy 133.515708 -278.822402) (xy 133.531824 -278.870676)
			(xy 133.539988 -278.92091) (xy 133.5405 -278.946356) (xy 133.859028 -278.946356) (xy 133.862988 -278.897302)
			(xy 133.874765 -278.849518) (xy 133.894056 -278.804242) (xy 133.920359 -278.762646) (xy 133.952994 -278.725809)
			(xy 133.991115 -278.694684) (xy 134.033736 -278.670077) (xy 134.079752 -278.652625) (xy 134.127971 -278.642781)
			(xy 134.177146 -278.6408) (xy 134.226001 -278.646732) (xy 134.273272 -278.660424) (xy 134.317734 -278.681522)
			(xy 134.358237 -278.709478) (xy 134.39373 -278.74357) (xy 134.423295 -278.782914) (xy 134.446166 -278.826491)
			(xy 134.46175 -278.873172) (xy 134.469645 -278.921749) (xy 134.47014 -278.946356) (xy 134.798828 -278.946356)
			(xy 134.802788 -278.897302) (xy 134.814565 -278.849518) (xy 134.833856 -278.804242) (xy 134.860159 -278.762646)
			(xy 134.892794 -278.725809) (xy 134.930915 -278.694684) (xy 134.973536 -278.670077) (xy 135.019552 -278.652625)
			(xy 135.067771 -278.642781) (xy 135.116946 -278.6408) (xy 135.165801 -278.646732) (xy 135.213072 -278.660424)
			(xy 135.257534 -278.681522) (xy 135.298037 -278.709478) (xy 135.33353 -278.74357) (xy 135.363095 -278.782914)
			(xy 135.385966 -278.826491) (xy 135.40155 -278.873172) (xy 135.409445 -278.921749) (xy 135.40994 -278.946356)
			(xy 135.738882 -278.946356) (xy 135.742842 -278.897302) (xy 135.754619 -278.849518) (xy 135.77391 -278.804242)
			(xy 135.800213 -278.762646) (xy 135.832848 -278.725809) (xy 135.870969 -278.694684) (xy 135.91359 -278.670077)
			(xy 135.959606 -278.652625) (xy 136.007825 -278.642781) (xy 136.057 -278.6408) (xy 136.105855 -278.646732)
			(xy 136.153126 -278.660424) (xy 136.197588 -278.681522) (xy 136.238091 -278.709478) (xy 136.273584 -278.74357)
			(xy 136.303149 -278.782914) (xy 136.32602 -278.826491) (xy 136.341604 -278.873172) (xy 136.349499 -278.921749)
			(xy 136.349994 -278.946356) (xy 136.349499 -278.970963) (xy 136.341604 -279.01954) (xy 136.32602 -279.066221)
			(xy 136.303149 -279.109798) (xy 136.273584 -279.149142) (xy 136.238091 -279.183234) (xy 136.197588 -279.21119)
			(xy 136.153126 -279.232288) (xy 136.105855 -279.24598) (xy 136.057 -279.251912) (xy 136.007825 -279.249931)
			(xy 135.959606 -279.240087) (xy 135.91359 -279.222635) (xy 135.870969 -279.198028) (xy 135.832848 -279.166903)
			(xy 135.800213 -279.130066) (xy 135.77391 -279.08847) (xy 135.754619 -279.043194) (xy 135.742842 -278.99541)
			(xy 135.738882 -278.946356) (xy 135.40994 -278.946356) (xy 135.409445 -278.970963) (xy 135.40155 -279.01954)
			(xy 135.385966 -279.066221) (xy 135.363095 -279.109798) (xy 135.33353 -279.149142) (xy 135.298037 -279.183234)
			(xy 135.257534 -279.21119) (xy 135.213072 -279.232288) (xy 135.165801 -279.24598) (xy 135.116946 -279.251912)
			(xy 135.067771 -279.249931) (xy 135.019552 -279.240087) (xy 134.973536 -279.222635) (xy 134.930915 -279.198028)
			(xy 134.892794 -279.166903) (xy 134.860159 -279.130066) (xy 134.833856 -279.08847) (xy 134.814565 -279.043194)
			(xy 134.802788 -278.99541) (xy 134.798828 -278.946356) (xy 134.47014 -278.946356) (xy 134.469645 -278.970963)
			(xy 134.46175 -279.01954) (xy 134.446166 -279.066221) (xy 134.423295 -279.109798) (xy 134.39373 -279.149142)
			(xy 134.358237 -279.183234) (xy 134.317734 -279.21119) (xy 134.273272 -279.232288) (xy 134.226001 -279.24598)
			(xy 134.177146 -279.251912) (xy 134.127971 -279.249931) (xy 134.079752 -279.240087) (xy 134.033736 -279.222635)
			(xy 133.991115 -279.198028) (xy 133.952994 -279.166903) (xy 133.920359 -279.130066) (xy 133.894056 -279.08847)
			(xy 133.874765 -279.043194) (xy 133.862988 -278.99541) (xy 133.859028 -278.946356) (xy 133.5405 -278.946356)
			(xy 133.539988 -278.971802) (xy 133.531824 -279.022036) (xy 133.515708 -279.07031) (xy 133.492057 -279.115373)
			(xy 133.461484 -279.156059) (xy 133.42478 -279.191314) (xy 133.382896 -279.220224) (xy 133.336917 -279.242041)
			(xy 133.288033 -279.256201) (xy 133.237512 -279.262335) (xy 133.18666 -279.260286) (xy 133.136796 -279.250106)
			(xy 133.08921 -279.232059) (xy 133.045136 -279.206613) (xy 133.005714 -279.174426) (xy 132.971966 -279.136332)
			(xy 132.944765 -279.093318) (xy 132.924817 -279.046498) (xy 132.912638 -278.997084) (xy 132.908543 -278.946356)
			(xy 132.590032 -278.946356) (xy 132.589537 -278.970963) (xy 132.581642 -279.01954) (xy 132.566058 -279.066221)
			(xy 132.543187 -279.109798) (xy 132.513622 -279.149142) (xy 132.478129 -279.183234) (xy 132.437626 -279.21119)
			(xy 132.393164 -279.232288) (xy 132.345893 -279.24598) (xy 132.297038 -279.251912) (xy 132.247863 -279.249931)
			(xy 132.199644 -279.240087) (xy 132.153628 -279.222635) (xy 132.111007 -279.198028) (xy 132.072886 -279.166903)
			(xy 132.040251 -279.130066) (xy 132.013948 -279.08847) (xy 131.994657 -279.043194) (xy 131.98288 -278.99541)
			(xy 131.97892 -278.946356) (xy 131.660392 -278.946356) (xy 131.65988 -278.971802) (xy 131.651716 -279.022036)
			(xy 131.6356 -279.07031) (xy 131.611949 -279.115373) (xy 131.581376 -279.156059) (xy 131.544672 -279.191314)
			(xy 131.502788 -279.220224) (xy 131.456809 -279.242041) (xy 131.407925 -279.256201) (xy 131.357404 -279.262335)
			(xy 131.306552 -279.260286) (xy 131.256688 -279.250106) (xy 131.209102 -279.232059) (xy 131.165028 -279.206613)
			(xy 131.125606 -279.174426) (xy 131.091858 -279.136332) (xy 131.064657 -279.093318) (xy 131.044709 -279.046498)
			(xy 131.03253 -278.997084) (xy 131.028435 -278.946356) (xy 130.710178 -278.946356) (xy 130.709683 -278.970963)
			(xy 130.701788 -279.01954) (xy 130.686204 -279.066221) (xy 130.663333 -279.109798) (xy 130.633768 -279.149142)
			(xy 130.598275 -279.183234) (xy 130.557772 -279.21119) (xy 130.51331 -279.232288) (xy 130.466039 -279.24598)
			(xy 130.417184 -279.251912) (xy 130.368009 -279.249931) (xy 130.31979 -279.240087) (xy 130.273774 -279.222635)
			(xy 130.231153 -279.198028) (xy 130.193032 -279.166903) (xy 130.160397 -279.130066) (xy 130.134094 -279.08847)
			(xy 130.114803 -279.043194) (xy 130.103026 -278.99541) (xy 130.099066 -278.946356) (xy 129.780538 -278.946356)
			(xy 129.780026 -278.971802) (xy 129.771862 -279.022036) (xy 129.755746 -279.07031) (xy 129.732095 -279.115373)
			(xy 129.701522 -279.156059) (xy 129.664818 -279.191314) (xy 129.622934 -279.220224) (xy 129.576955 -279.242041)
			(xy 129.528071 -279.256201) (xy 129.47755 -279.262335) (xy 129.426698 -279.260286) (xy 129.376834 -279.250106)
			(xy 129.329248 -279.232059) (xy 129.285174 -279.206613) (xy 129.245752 -279.174426) (xy 129.212004 -279.136332)
			(xy 129.184803 -279.093318) (xy 129.164855 -279.046498) (xy 129.152676 -278.997084) (xy 129.148581 -278.946356)
			(xy 128.840484 -278.946356) (xy 128.839972 -278.971802) (xy 128.831808 -279.022036) (xy 128.815692 -279.07031)
			(xy 128.792041 -279.115373) (xy 128.761468 -279.156059) (xy 128.724764 -279.191314) (xy 128.68288 -279.220224)
			(xy 128.636901 -279.242041) (xy 128.588017 -279.256201) (xy 128.537496 -279.262335) (xy 128.486644 -279.260286)
			(xy 128.43678 -279.250106) (xy 128.389194 -279.232059) (xy 128.34512 -279.206613) (xy 128.305698 -279.174426)
			(xy 128.27195 -279.136332) (xy 128.244749 -279.093318) (xy 128.224801 -279.046498) (xy 128.212622 -278.997084)
			(xy 128.208527 -278.946356) (xy 127.903989 -278.946356) (xy 127.939913 -278.982102) (xy 128.006786 -279.060169)
			(xy 128.066296 -279.143983) (xy 128.117954 -279.232853) (xy 128.161333 -279.326044) (xy 128.196074 -279.422788)
			(xy 128.209548 -279.47239) (xy 128.21412 -279.48382) (xy 128.235729 -279.497023) (xy 128.274815 -279.529216)
			(xy 128.308261 -279.567235) (xy 128.335209 -279.610105) (xy 128.354968 -279.656728) (xy 128.367031 -279.705907)
			(xy 128.371087 -279.756362) (xy 128.688858 -279.756362) (xy 128.692818 -279.707308) (xy 128.704595 -279.659524)
			(xy 128.723886 -279.614248) (xy 128.750189 -279.572652) (xy 128.782824 -279.535815) (xy 128.820945 -279.50469)
			(xy 128.863566 -279.480083) (xy 128.909582 -279.462631) (xy 128.957801 -279.452787) (xy 129.006976 -279.450806)
			(xy 129.055831 -279.456738) (xy 129.103102 -279.47043) (xy 129.147564 -279.491528) (xy 129.188067 -279.519484)
			(xy 129.22356 -279.553576) (xy 129.253125 -279.59292) (xy 129.275996 -279.636497) (xy 129.29158 -279.683178)
			(xy 129.299475 -279.731755) (xy 129.29997 -279.756362) (xy 129.618481 -279.756362) (xy 129.622576 -279.705634)
			(xy 129.634755 -279.65622) (xy 129.654703 -279.6094) (xy 129.681904 -279.566386) (xy 129.715652 -279.528292)
			(xy 129.755074 -279.496105) (xy 129.799148 -279.470659) (xy 129.846734 -279.452612) (xy 129.896598 -279.442432)
			(xy 129.94745 -279.440383) (xy 129.997971 -279.446517) (xy 130.046855 -279.460677) (xy 130.092834 -279.482494)
			(xy 130.134718 -279.511404) (xy 130.171422 -279.546659) (xy 130.201995 -279.587345) (xy 130.225646 -279.632408)
			(xy 130.241762 -279.680682) (xy 130.249926 -279.730916) (xy 130.250438 -279.756362) (xy 130.568966 -279.756362)
			(xy 130.572926 -279.707308) (xy 130.584703 -279.659524) (xy 130.603994 -279.614248) (xy 130.630297 -279.572652)
			(xy 130.662932 -279.535815) (xy 130.701053 -279.50469) (xy 130.743674 -279.480083) (xy 130.78969 -279.462631)
			(xy 130.837909 -279.452787) (xy 130.887084 -279.450806) (xy 130.935939 -279.456738) (xy 130.98321 -279.47043)
			(xy 131.027672 -279.491528) (xy 131.068175 -279.519484) (xy 131.103668 -279.553576) (xy 131.133233 -279.59292)
			(xy 131.156104 -279.636497) (xy 131.171688 -279.683178) (xy 131.179583 -279.731755) (xy 131.180078 -279.756362)
			(xy 131.498589 -279.756362) (xy 131.502684 -279.705634) (xy 131.514863 -279.65622) (xy 131.534811 -279.6094)
			(xy 131.562012 -279.566386) (xy 131.59576 -279.528292) (xy 131.635182 -279.496105) (xy 131.679256 -279.470659)
			(xy 131.726842 -279.452612) (xy 131.776706 -279.442432) (xy 131.827558 -279.440383) (xy 131.878079 -279.446517)
			(xy 131.926963 -279.460677) (xy 131.972942 -279.482494) (xy 132.014826 -279.511404) (xy 132.05153 -279.546659)
			(xy 132.082103 -279.587345) (xy 132.105754 -279.632408) (xy 132.12187 -279.680682) (xy 132.130034 -279.730916)
			(xy 132.130546 -279.756362) (xy 132.438643 -279.756362) (xy 132.442738 -279.705634) (xy 132.454917 -279.65622)
			(xy 132.474865 -279.6094) (xy 132.502066 -279.566386) (xy 132.535814 -279.528292) (xy 132.575236 -279.496105)
			(xy 132.61931 -279.470659) (xy 132.666896 -279.452612) (xy 132.71676 -279.442432) (xy 132.767612 -279.440383)
			(xy 132.818133 -279.446517) (xy 132.867017 -279.460677) (xy 132.912996 -279.482494) (xy 132.95488 -279.511404)
			(xy 132.991584 -279.546659) (xy 133.022157 -279.587345) (xy 133.045808 -279.632408) (xy 133.061924 -279.680682)
			(xy 133.070088 -279.730916) (xy 133.0706 -279.756362) (xy 133.388874 -279.756362) (xy 133.392834 -279.707308)
			(xy 133.404611 -279.659524) (xy 133.423902 -279.614248) (xy 133.450205 -279.572652) (xy 133.48284 -279.535815)
			(xy 133.520961 -279.50469) (xy 133.563582 -279.480083) (xy 133.609598 -279.462631) (xy 133.657817 -279.452787)
			(xy 133.706992 -279.450806) (xy 133.755847 -279.456738) (xy 133.803118 -279.47043) (xy 133.84758 -279.491528)
			(xy 133.888083 -279.519484) (xy 133.923576 -279.553576) (xy 133.953141 -279.59292) (xy 133.976012 -279.636497)
			(xy 133.991596 -279.683178) (xy 133.999491 -279.731755) (xy 133.999986 -279.756362) (xy 134.328928 -279.756362)
			(xy 134.332888 -279.707308) (xy 134.344665 -279.659524) (xy 134.363956 -279.614248) (xy 134.390259 -279.572652)
			(xy 134.422894 -279.535815) (xy 134.461015 -279.50469) (xy 134.503636 -279.480083) (xy 134.549652 -279.462631)
			(xy 134.597871 -279.452787) (xy 134.647046 -279.450806) (xy 134.695901 -279.456738) (xy 134.743172 -279.47043)
			(xy 134.787634 -279.491528) (xy 134.828137 -279.519484) (xy 134.86363 -279.553576) (xy 134.893195 -279.59292)
			(xy 134.916066 -279.636497) (xy 134.93165 -279.683178) (xy 134.939545 -279.731755) (xy 134.94004 -279.756362)
			(xy 135.268982 -279.756362) (xy 135.272942 -279.707308) (xy 135.284719 -279.659524) (xy 135.30401 -279.614248)
			(xy 135.330313 -279.572652) (xy 135.362948 -279.535815) (xy 135.401069 -279.50469) (xy 135.44369 -279.480083)
			(xy 135.489706 -279.462631) (xy 135.537925 -279.452787) (xy 135.5871 -279.450806) (xy 135.635955 -279.456738)
			(xy 135.683226 -279.47043) (xy 135.727688 -279.491528) (xy 135.768191 -279.519484) (xy 135.803684 -279.553576)
			(xy 135.833249 -279.59292) (xy 135.85612 -279.636497) (xy 135.871704 -279.683178) (xy 135.879599 -279.731755)
			(xy 135.880094 -279.756362) (xy 136.209036 -279.756362) (xy 136.212996 -279.707308) (xy 136.224773 -279.659524)
			(xy 136.244064 -279.614248) (xy 136.270367 -279.572652) (xy 136.303002 -279.535815) (xy 136.341123 -279.50469)
			(xy 136.383744 -279.480083) (xy 136.42976 -279.462631) (xy 136.477979 -279.452787) (xy 136.527154 -279.450806)
			(xy 136.576009 -279.456738) (xy 136.62328 -279.47043) (xy 136.667742 -279.491528) (xy 136.708245 -279.519484)
			(xy 136.743738 -279.553576) (xy 136.773303 -279.59292) (xy 136.796174 -279.636497) (xy 136.811758 -279.683178)
			(xy 136.819653 -279.731755) (xy 136.820148 -279.756362) (xy 136.819653 -279.780969) (xy 136.811758 -279.829546)
			(xy 136.796174 -279.876227) (xy 136.773303 -279.919804) (xy 136.743738 -279.959148) (xy 136.708245 -279.99324)
			(xy 136.667742 -280.021196) (xy 136.62328 -280.042294) (xy 136.576009 -280.055986) (xy 136.527154 -280.061918)
			(xy 136.477979 -280.059937) (xy 136.42976 -280.050093) (xy 136.383744 -280.032641) (xy 136.341123 -280.008034)
			(xy 136.303002 -279.976909) (xy 136.270367 -279.940072) (xy 136.244064 -279.898476) (xy 136.224773 -279.8532)
			(xy 136.212996 -279.805416) (xy 136.209036 -279.756362) (xy 135.880094 -279.756362) (xy 135.879599 -279.780969)
			(xy 135.871704 -279.829546) (xy 135.85612 -279.876227) (xy 135.833249 -279.919804) (xy 135.803684 -279.959148)
			(xy 135.768191 -279.99324) (xy 135.727688 -280.021196) (xy 135.683226 -280.042294) (xy 135.635955 -280.055986)
			(xy 135.5871 -280.061918) (xy 135.537925 -280.059937) (xy 135.489706 -280.050093) (xy 135.44369 -280.032641)
			(xy 135.401069 -280.008034) (xy 135.362948 -279.976909) (xy 135.330313 -279.940072) (xy 135.30401 -279.898476)
			(xy 135.284719 -279.8532) (xy 135.272942 -279.805416) (xy 135.268982 -279.756362) (xy 134.94004 -279.756362)
			(xy 134.939545 -279.780969) (xy 134.93165 -279.829546) (xy 134.916066 -279.876227) (xy 134.893195 -279.919804)
			(xy 134.86363 -279.959148) (xy 134.828137 -279.99324) (xy 134.787634 -280.021196) (xy 134.743172 -280.042294)
			(xy 134.695901 -280.055986) (xy 134.647046 -280.061918) (xy 134.597871 -280.059937) (xy 134.549652 -280.050093)
			(xy 134.503636 -280.032641) (xy 134.461015 -280.008034) (xy 134.422894 -279.976909) (xy 134.390259 -279.940072)
			(xy 134.363956 -279.898476) (xy 134.344665 -279.8532) (xy 134.332888 -279.805416) (xy 134.328928 -279.756362)
			(xy 133.999986 -279.756362) (xy 133.999491 -279.780969) (xy 133.991596 -279.829546) (xy 133.976012 -279.876227)
			(xy 133.953141 -279.919804) (xy 133.923576 -279.959148) (xy 133.888083 -279.99324) (xy 133.84758 -280.021196)
			(xy 133.803118 -280.042294) (xy 133.755847 -280.055986) (xy 133.706992 -280.061918) (xy 133.657817 -280.059937)
			(xy 133.609598 -280.050093) (xy 133.563582 -280.032641) (xy 133.520961 -280.008034) (xy 133.48284 -279.976909)
			(xy 133.450205 -279.940072) (xy 133.423902 -279.898476) (xy 133.404611 -279.8532) (xy 133.392834 -279.805416)
			(xy 133.388874 -279.756362) (xy 133.0706 -279.756362) (xy 133.070088 -279.781808) (xy 133.061924 -279.832042)
			(xy 133.045808 -279.880316) (xy 133.022157 -279.925379) (xy 132.991584 -279.966065) (xy 132.95488 -280.00132)
			(xy 132.912996 -280.03023) (xy 132.867017 -280.052047) (xy 132.818133 -280.066207) (xy 132.767612 -280.072341)
			(xy 132.71676 -280.070292) (xy 132.666896 -280.060112) (xy 132.61931 -280.042065) (xy 132.575236 -280.016619)
			(xy 132.535814 -279.984432) (xy 132.502066 -279.946338) (xy 132.474865 -279.903324) (xy 132.454917 -279.856504)
			(xy 132.442738 -279.80709) (xy 132.438643 -279.756362) (xy 132.130546 -279.756362) (xy 132.130034 -279.781808)
			(xy 132.12187 -279.832042) (xy 132.105754 -279.880316) (xy 132.082103 -279.925379) (xy 132.05153 -279.966065)
			(xy 132.014826 -280.00132) (xy 131.972942 -280.03023) (xy 131.926963 -280.052047) (xy 131.878079 -280.066207)
			(xy 131.827558 -280.072341) (xy 131.776706 -280.070292) (xy 131.726842 -280.060112) (xy 131.679256 -280.042065)
			(xy 131.635182 -280.016619) (xy 131.59576 -279.984432) (xy 131.562012 -279.946338) (xy 131.534811 -279.903324)
			(xy 131.514863 -279.856504) (xy 131.502684 -279.80709) (xy 131.498589 -279.756362) (xy 131.180078 -279.756362)
			(xy 131.179583 -279.780969) (xy 131.171688 -279.829546) (xy 131.156104 -279.876227) (xy 131.133233 -279.919804)
			(xy 131.103668 -279.959148) (xy 131.068175 -279.99324) (xy 131.027672 -280.021196) (xy 130.98321 -280.042294)
			(xy 130.935939 -280.055986) (xy 130.887084 -280.061918) (xy 130.837909 -280.059937) (xy 130.78969 -280.050093)
			(xy 130.743674 -280.032641) (xy 130.701053 -280.008034) (xy 130.662932 -279.976909) (xy 130.630297 -279.940072)
			(xy 130.603994 -279.898476) (xy 130.584703 -279.8532) (xy 130.572926 -279.805416) (xy 130.568966 -279.756362)
			(xy 130.250438 -279.756362) (xy 130.249926 -279.781808) (xy 130.241762 -279.832042) (xy 130.225646 -279.880316)
			(xy 130.201995 -279.925379) (xy 130.171422 -279.966065) (xy 130.134718 -280.00132) (xy 130.092834 -280.03023)
			(xy 130.046855 -280.052047) (xy 129.997971 -280.066207) (xy 129.94745 -280.072341) (xy 129.896598 -280.070292)
			(xy 129.846734 -280.060112) (xy 129.799148 -280.042065) (xy 129.755074 -280.016619) (xy 129.715652 -279.984432)
			(xy 129.681904 -279.946338) (xy 129.654703 -279.903324) (xy 129.634755 -279.856504) (xy 129.622576 -279.80709)
			(xy 129.618481 -279.756362) (xy 129.29997 -279.756362) (xy 129.299475 -279.780969) (xy 129.29158 -279.829546)
			(xy 129.275996 -279.876227) (xy 129.253125 -279.919804) (xy 129.22356 -279.959148) (xy 129.188067 -279.99324)
			(xy 129.147564 -280.021196) (xy 129.103102 -280.042294) (xy 129.055831 -280.055986) (xy 129.006976 -280.061918)
			(xy 128.957801 -280.059937) (xy 128.909582 -280.050093) (xy 128.863566 -280.032641) (xy 128.820945 -280.008034)
			(xy 128.782824 -279.976909) (xy 128.750189 -279.940072) (xy 128.723886 -279.898476) (xy 128.704595 -279.8532)
			(xy 128.692818 -279.805416) (xy 128.688858 -279.756362) (xy 128.371087 -279.756362) (xy 128.371089 -279.756381)
			(xy 128.367037 -279.806855) (xy 128.35498 -279.856036) (xy 128.335227 -279.902661) (xy 128.308284 -279.945534)
			(xy 128.274843 -279.983558) (xy 128.23576 -280.015755) (xy 128.21412 -280.028904) (xy 128.209548 -280.040334)
			(xy 128.196078 -280.089938) (xy 128.16134 -280.186683) (xy 128.117963 -280.279876) (xy 128.066306 -280.368747)
			(xy 128.006795 -280.452562) (xy 127.939922 -280.530629) (xy 127.903989 -280.566368) (xy 128.208527 -280.566368)
			(xy 128.212622 -280.51564) (xy 128.224801 -280.466226) (xy 128.244749 -280.419406) (xy 128.27195 -280.376392)
			(xy 128.305698 -280.338298) (xy 128.34512 -280.306111) (xy 128.389194 -280.280665) (xy 128.43678 -280.262618)
			(xy 128.486644 -280.252438) (xy 128.537496 -280.250389) (xy 128.588017 -280.256523) (xy 128.636901 -280.270683)
			(xy 128.68288 -280.2925) (xy 128.724764 -280.32141) (xy 128.761468 -280.356665) (xy 128.792041 -280.397351)
			(xy 128.815692 -280.442414) (xy 128.831808 -280.490688) (xy 128.839972 -280.540922) (xy 128.840484 -280.566368)
			(xy 129.148581 -280.566368) (xy 129.152676 -280.51564) (xy 129.164855 -280.466226) (xy 129.184803 -280.419406)
			(xy 129.212004 -280.376392) (xy 129.245752 -280.338298) (xy 129.285174 -280.306111) (xy 129.329248 -280.280665)
			(xy 129.376834 -280.262618) (xy 129.426698 -280.252438) (xy 129.47755 -280.250389) (xy 129.528071 -280.256523)
			(xy 129.576955 -280.270683) (xy 129.622934 -280.2925) (xy 129.664818 -280.32141) (xy 129.701522 -280.356665)
			(xy 129.732095 -280.397351) (xy 129.755746 -280.442414) (xy 129.771862 -280.490688) (xy 129.780026 -280.540922)
			(xy 129.780538 -280.566368) (xy 131.028435 -280.566368) (xy 131.03253 -280.51564) (xy 131.044709 -280.466226)
			(xy 131.064657 -280.419406) (xy 131.091858 -280.376392) (xy 131.125606 -280.338298) (xy 131.165028 -280.306111)
			(xy 131.209102 -280.280665) (xy 131.256688 -280.262618) (xy 131.306552 -280.252438) (xy 131.357404 -280.250389)
			(xy 131.407925 -280.256523) (xy 131.456809 -280.270683) (xy 131.502788 -280.2925) (xy 131.544672 -280.32141)
			(xy 131.581376 -280.356665) (xy 131.611949 -280.397351) (xy 131.6356 -280.442414) (xy 131.651716 -280.490688)
			(xy 131.65988 -280.540922) (xy 131.660392 -280.566368) (xy 131.97892 -280.566368) (xy 131.98288 -280.517314)
			(xy 131.994657 -280.46953) (xy 132.013948 -280.424254) (xy 132.040251 -280.382658) (xy 132.072886 -280.345821)
			(xy 132.111007 -280.314696) (xy 132.153628 -280.290089) (xy 132.199644 -280.272637) (xy 132.247863 -280.262793)
			(xy 132.297038 -280.260812) (xy 132.345893 -280.266744) (xy 132.393164 -280.280436) (xy 132.437626 -280.301534)
			(xy 132.478129 -280.32949) (xy 132.513622 -280.363582) (xy 132.543187 -280.402926) (xy 132.566058 -280.446503)
			(xy 132.581642 -280.493184) (xy 132.589537 -280.541761) (xy 132.590032 -280.566368) (xy 132.908543 -280.566368)
			(xy 132.912638 -280.51564) (xy 132.924817 -280.466226) (xy 132.944765 -280.419406) (xy 132.971966 -280.376392)
			(xy 133.005714 -280.338298) (xy 133.045136 -280.306111) (xy 133.08921 -280.280665) (xy 133.136796 -280.262618)
			(xy 133.18666 -280.252438) (xy 133.237512 -280.250389) (xy 133.288033 -280.256523) (xy 133.336917 -280.270683)
			(xy 133.382896 -280.2925) (xy 133.42478 -280.32141) (xy 133.461484 -280.356665) (xy 133.492057 -280.397351)
			(xy 133.515708 -280.442414) (xy 133.531824 -280.490688) (xy 133.539988 -280.540922) (xy 133.5405 -280.566368)
			(xy 133.859028 -280.566368) (xy 133.862988 -280.517314) (xy 133.874765 -280.46953) (xy 133.894056 -280.424254)
			(xy 133.920359 -280.382658) (xy 133.952994 -280.345821) (xy 133.991115 -280.314696) (xy 134.033736 -280.290089)
			(xy 134.079752 -280.272637) (xy 134.127971 -280.262793) (xy 134.177146 -280.260812) (xy 134.226001 -280.266744)
			(xy 134.273272 -280.280436) (xy 134.317734 -280.301534) (xy 134.358237 -280.32949) (xy 134.39373 -280.363582)
			(xy 134.423295 -280.402926) (xy 134.446166 -280.446503) (xy 134.46175 -280.493184) (xy 134.469645 -280.541761)
			(xy 134.47014 -280.566368) (xy 134.798828 -280.566368) (xy 134.802788 -280.517314) (xy 134.814565 -280.46953)
			(xy 134.833856 -280.424254) (xy 134.860159 -280.382658) (xy 134.892794 -280.345821) (xy 134.930915 -280.314696)
			(xy 134.973536 -280.290089) (xy 135.019552 -280.272637) (xy 135.067771 -280.262793) (xy 135.116946 -280.260812)
			(xy 135.165801 -280.266744) (xy 135.213072 -280.280436) (xy 135.257534 -280.301534) (xy 135.298037 -280.32949)
			(xy 135.33353 -280.363582) (xy 135.363095 -280.402926) (xy 135.385966 -280.446503) (xy 135.40155 -280.493184)
			(xy 135.409445 -280.541761) (xy 135.40994 -280.566368) (xy 135.738882 -280.566368) (xy 135.742842 -280.517314)
			(xy 135.754619 -280.46953) (xy 135.77391 -280.424254) (xy 135.800213 -280.382658) (xy 135.832848 -280.345821)
			(xy 135.870969 -280.314696) (xy 135.91359 -280.290089) (xy 135.959606 -280.272637) (xy 136.007825 -280.262793)
			(xy 136.057 -280.260812) (xy 136.105855 -280.266744) (xy 136.153126 -280.280436) (xy 136.197588 -280.301534)
			(xy 136.238091 -280.32949) (xy 136.273584 -280.363582) (xy 136.303149 -280.402926) (xy 136.32602 -280.446503)
			(xy 136.341604 -280.493184) (xy 136.349499 -280.541761) (xy 136.349994 -280.566368) (xy 136.349499 -280.590975)
			(xy 136.341604 -280.639552) (xy 136.32602 -280.686233) (xy 136.303149 -280.72981) (xy 136.273584 -280.769154)
			(xy 136.238091 -280.803246) (xy 136.197588 -280.831202) (xy 136.153126 -280.8523) (xy 136.105855 -280.865992)
			(xy 136.057 -280.871924) (xy 136.007825 -280.869943) (xy 135.959606 -280.860099) (xy 135.91359 -280.842647)
			(xy 135.870969 -280.81804) (xy 135.832848 -280.786915) (xy 135.800213 -280.750078) (xy 135.77391 -280.708482)
			(xy 135.754619 -280.663206) (xy 135.742842 -280.615422) (xy 135.738882 -280.566368) (xy 135.40994 -280.566368)
			(xy 135.409445 -280.590975) (xy 135.40155 -280.639552) (xy 135.385966 -280.686233) (xy 135.363095 -280.72981)
			(xy 135.33353 -280.769154) (xy 135.298037 -280.803246) (xy 135.257534 -280.831202) (xy 135.213072 -280.8523)
			(xy 135.165801 -280.865992) (xy 135.116946 -280.871924) (xy 135.067771 -280.869943) (xy 135.019552 -280.860099)
			(xy 134.973536 -280.842647) (xy 134.930915 -280.81804) (xy 134.892794 -280.786915) (xy 134.860159 -280.750078)
			(xy 134.833856 -280.708482) (xy 134.814565 -280.663206) (xy 134.802788 -280.615422) (xy 134.798828 -280.566368)
			(xy 134.47014 -280.566368) (xy 134.469645 -280.590975) (xy 134.46175 -280.639552) (xy 134.446166 -280.686233)
			(xy 134.423295 -280.72981) (xy 134.39373 -280.769154) (xy 134.358237 -280.803246) (xy 134.317734 -280.831202)
			(xy 134.273272 -280.8523) (xy 134.226001 -280.865992) (xy 134.177146 -280.871924) (xy 134.127971 -280.869943)
			(xy 134.079752 -280.860099) (xy 134.033736 -280.842647) (xy 133.991115 -280.81804) (xy 133.952994 -280.786915)
			(xy 133.920359 -280.750078) (xy 133.894056 -280.708482) (xy 133.874765 -280.663206) (xy 133.862988 -280.615422)
			(xy 133.859028 -280.566368) (xy 133.5405 -280.566368) (xy 133.539988 -280.591814) (xy 133.531824 -280.642048)
			(xy 133.515708 -280.690322) (xy 133.492057 -280.735385) (xy 133.461484 -280.776071) (xy 133.42478 -280.811326)
			(xy 133.382896 -280.840236) (xy 133.336917 -280.862053) (xy 133.288033 -280.876213) (xy 133.237512 -280.882347)
			(xy 133.18666 -280.880298) (xy 133.136796 -280.870118) (xy 133.08921 -280.852071) (xy 133.045136 -280.826625)
			(xy 133.005714 -280.794438) (xy 132.971966 -280.756344) (xy 132.944765 -280.71333) (xy 132.924817 -280.66651)
			(xy 132.912638 -280.617096) (xy 132.908543 -280.566368) (xy 132.590032 -280.566368) (xy 132.589537 -280.590975)
			(xy 132.581642 -280.639552) (xy 132.566058 -280.686233) (xy 132.543187 -280.72981) (xy 132.513622 -280.769154)
			(xy 132.478129 -280.803246) (xy 132.437626 -280.831202) (xy 132.393164 -280.8523) (xy 132.345893 -280.865992)
			(xy 132.297038 -280.871924) (xy 132.247863 -280.869943) (xy 132.199644 -280.860099) (xy 132.153628 -280.842647)
			(xy 132.111007 -280.81804) (xy 132.072886 -280.786915) (xy 132.040251 -280.750078) (xy 132.013948 -280.708482)
			(xy 131.994657 -280.663206) (xy 131.98288 -280.615422) (xy 131.97892 -280.566368) (xy 131.660392 -280.566368)
			(xy 131.65988 -280.591814) (xy 131.651716 -280.642048) (xy 131.6356 -280.690322) (xy 131.611949 -280.735385)
			(xy 131.581376 -280.776071) (xy 131.544672 -280.811326) (xy 131.502788 -280.840236) (xy 131.456809 -280.862053)
			(xy 131.407925 -280.876213) (xy 131.357404 -280.882347) (xy 131.306552 -280.880298) (xy 131.256688 -280.870118)
			(xy 131.209102 -280.852071) (xy 131.165028 -280.826625) (xy 131.125606 -280.794438) (xy 131.091858 -280.756344)
			(xy 131.064657 -280.71333) (xy 131.044709 -280.66651) (xy 131.03253 -280.617096) (xy 131.028435 -280.566368)
			(xy 129.780538 -280.566368) (xy 129.780026 -280.591814) (xy 129.771862 -280.642048) (xy 129.755746 -280.690322)
			(xy 129.732095 -280.735385) (xy 129.701522 -280.776071) (xy 129.664818 -280.811326) (xy 129.622934 -280.840236)
			(xy 129.576955 -280.862053) (xy 129.528071 -280.876213) (xy 129.47755 -280.882347) (xy 129.426698 -280.880298)
			(xy 129.376834 -280.870118) (xy 129.329248 -280.852071) (xy 129.285174 -280.826625) (xy 129.245752 -280.794438)
			(xy 129.212004 -280.756344) (xy 129.184803 -280.71333) (xy 129.164855 -280.66651) (xy 129.152676 -280.617096)
			(xy 129.148581 -280.566368) (xy 128.840484 -280.566368) (xy 128.839972 -280.591814) (xy 128.831808 -280.642048)
			(xy 128.815692 -280.690322) (xy 128.792041 -280.735385) (xy 128.761468 -280.776071) (xy 128.724764 -280.811326)
			(xy 128.68288 -280.840236) (xy 128.636901 -280.862053) (xy 128.588017 -280.876213) (xy 128.537496 -280.882347)
			(xy 128.486644 -280.880298) (xy 128.43678 -280.870118) (xy 128.389194 -280.852071) (xy 128.34512 -280.826625)
			(xy 128.305698 -280.794438) (xy 128.27195 -280.756344) (xy 128.244749 -280.71333) (xy 128.224801 -280.66651)
			(xy 128.212622 -280.617096) (xy 128.208527 -280.566368) (xy 127.903989 -280.566368) (xy 127.903478 -280.566876)
			(xy 127.897373 -280.573322) (xy 127.889709 -280.589323) (xy 127.888492 -280.598118) (xy 127.888492 -280.598372)
			(xy 127.883158 -280.631138) (xy 127.877958 -280.653247) (xy 127.861896 -280.695729) (xy 127.839711 -280.735359)
			(xy 127.811893 -280.771259) (xy 127.779058 -280.802637) (xy 127.76073 -280.81605) (xy 127.753545 -280.821523)
			(xy 127.743255 -280.836354) (xy 127.740664 -280.845006) (xy 127.728979 -280.889086) (xy 127.699434 -280.975369)
			(xy 127.663036 -281.058993) (xy 127.620024 -281.139414) (xy 127.570676 -281.216111) (xy 127.515312 -281.288585)
			(xy 127.48514 -281.32278) (xy 127.47879 -281.329892) (xy 127.472186 -281.347164) (xy 127.472186 -281.376374)
			(xy 127.738627 -281.376374) (xy 127.742722 -281.325646) (xy 127.754901 -281.276232) (xy 127.774849 -281.229412)
			(xy 127.80205 -281.186398) (xy 127.835798 -281.148304) (xy 127.87522 -281.116117) (xy 127.919294 -281.090671)
			(xy 127.96688 -281.072624) (xy 128.016744 -281.062444) (xy 128.067596 -281.060395) (xy 128.118117 -281.066529)
			(xy 128.167001 -281.080689) (xy 128.21298 -281.102506) (xy 128.254864 -281.131416) (xy 128.291568 -281.166671)
			(xy 128.322141 -281.207357) (xy 128.345792 -281.25242) (xy 128.361908 -281.300694) (xy 128.370072 -281.350928)
			(xy 128.370584 -281.376374) (xy 128.688858 -281.376374) (xy 128.692818 -281.32732) (xy 128.704595 -281.279536)
			(xy 128.723886 -281.23426) (xy 128.750189 -281.192664) (xy 128.782824 -281.155827) (xy 128.820945 -281.124702)
			(xy 128.863566 -281.100095) (xy 128.909582 -281.082643) (xy 128.957801 -281.072799) (xy 129.006976 -281.070818)
			(xy 129.055831 -281.07675) (xy 129.103102 -281.090442) (xy 129.147564 -281.11154) (xy 129.188067 -281.139496)
			(xy 129.22356 -281.173588) (xy 129.253125 -281.212932) (xy 129.275996 -281.256509) (xy 129.29158 -281.30319)
			(xy 129.299475 -281.351767) (xy 129.29997 -281.376374) (xy 129.618481 -281.376374) (xy 129.622576 -281.325646)
			(xy 129.634755 -281.276232) (xy 129.654703 -281.229412) (xy 129.681904 -281.186398) (xy 129.715652 -281.148304)
			(xy 129.755074 -281.116117) (xy 129.799148 -281.090671) (xy 129.846734 -281.072624) (xy 129.896598 -281.062444)
			(xy 129.94745 -281.060395) (xy 129.997971 -281.066529) (xy 130.046855 -281.080689) (xy 130.092834 -281.102506)
			(xy 130.134718 -281.131416) (xy 130.171422 -281.166671) (xy 130.201995 -281.207357) (xy 130.225646 -281.25242)
			(xy 130.241762 -281.300694) (xy 130.249926 -281.350928) (xy 130.250438 -281.376374) (xy 130.568966 -281.376374)
			(xy 130.572926 -281.32732) (xy 130.584703 -281.279536) (xy 130.603994 -281.23426) (xy 130.630297 -281.192664)
			(xy 130.662932 -281.155827) (xy 130.701053 -281.124702) (xy 130.743674 -281.100095) (xy 130.78969 -281.082643)
			(xy 130.837909 -281.072799) (xy 130.887084 -281.070818) (xy 130.935939 -281.07675) (xy 130.98321 -281.090442)
			(xy 131.027672 -281.11154) (xy 131.068175 -281.139496) (xy 131.103668 -281.173588) (xy 131.133233 -281.212932)
			(xy 131.156104 -281.256509) (xy 131.171688 -281.30319) (xy 131.179583 -281.351767) (xy 131.180078 -281.376374)
			(xy 131.498589 -281.376374) (xy 131.502684 -281.325646) (xy 131.514863 -281.276232) (xy 131.534811 -281.229412)
			(xy 131.562012 -281.186398) (xy 131.59576 -281.148304) (xy 131.635182 -281.116117) (xy 131.679256 -281.090671)
			(xy 131.726842 -281.072624) (xy 131.776706 -281.062444) (xy 131.827558 -281.060395) (xy 131.878079 -281.066529)
			(xy 131.926963 -281.080689) (xy 131.972942 -281.102506) (xy 132.014826 -281.131416) (xy 132.05153 -281.166671)
			(xy 132.082103 -281.207357) (xy 132.105754 -281.25242) (xy 132.12187 -281.300694) (xy 132.130034 -281.350928)
			(xy 132.130546 -281.376374) (xy 132.438643 -281.376374) (xy 132.442738 -281.325646) (xy 132.454917 -281.276232)
			(xy 132.474865 -281.229412) (xy 132.502066 -281.186398) (xy 132.535814 -281.148304) (xy 132.575236 -281.116117)
			(xy 132.61931 -281.090671) (xy 132.666896 -281.072624) (xy 132.71676 -281.062444) (xy 132.767612 -281.060395)
			(xy 132.818133 -281.066529) (xy 132.867017 -281.080689) (xy 132.912996 -281.102506) (xy 132.95488 -281.131416)
			(xy 132.991584 -281.166671) (xy 133.022157 -281.207357) (xy 133.045808 -281.25242) (xy 133.061924 -281.300694)
			(xy 133.070088 -281.350928) (xy 133.0706 -281.376374) (xy 133.388874 -281.376374) (xy 133.392834 -281.32732)
			(xy 133.404611 -281.279536) (xy 133.423902 -281.23426) (xy 133.450205 -281.192664) (xy 133.48284 -281.155827)
			(xy 133.520961 -281.124702) (xy 133.563582 -281.100095) (xy 133.609598 -281.082643) (xy 133.657817 -281.072799)
			(xy 133.706992 -281.070818) (xy 133.755847 -281.07675) (xy 133.803118 -281.090442) (xy 133.84758 -281.11154)
			(xy 133.888083 -281.139496) (xy 133.923576 -281.173588) (xy 133.953141 -281.212932) (xy 133.976012 -281.256509)
			(xy 133.991596 -281.30319) (xy 133.999491 -281.351767) (xy 133.999986 -281.376374) (xy 134.328928 -281.376374)
			(xy 134.332888 -281.32732) (xy 134.344665 -281.279536) (xy 134.363956 -281.23426) (xy 134.390259 -281.192664)
			(xy 134.422894 -281.155827) (xy 134.461015 -281.124702) (xy 134.503636 -281.100095) (xy 134.549652 -281.082643)
			(xy 134.597871 -281.072799) (xy 134.647046 -281.070818) (xy 134.695901 -281.07675) (xy 134.743172 -281.090442)
			(xy 134.787634 -281.11154) (xy 134.828137 -281.139496) (xy 134.86363 -281.173588) (xy 134.893195 -281.212932)
			(xy 134.916066 -281.256509) (xy 134.93165 -281.30319) (xy 134.939545 -281.351767) (xy 134.94004 -281.376374)
			(xy 135.268982 -281.376374) (xy 135.272942 -281.32732) (xy 135.284719 -281.279536) (xy 135.30401 -281.23426)
			(xy 135.330313 -281.192664) (xy 135.362948 -281.155827) (xy 135.401069 -281.124702) (xy 135.44369 -281.100095)
			(xy 135.489706 -281.082643) (xy 135.537925 -281.072799) (xy 135.5871 -281.070818) (xy 135.635955 -281.07675)
			(xy 135.683226 -281.090442) (xy 135.727688 -281.11154) (xy 135.768191 -281.139496) (xy 135.803684 -281.173588)
			(xy 135.833249 -281.212932) (xy 135.85612 -281.256509) (xy 135.871704 -281.30319) (xy 135.879599 -281.351767)
			(xy 135.880094 -281.376374) (xy 136.209036 -281.376374) (xy 136.212996 -281.32732) (xy 136.224773 -281.279536)
			(xy 136.244064 -281.23426) (xy 136.270367 -281.192664) (xy 136.303002 -281.155827) (xy 136.341123 -281.124702)
			(xy 136.383744 -281.100095) (xy 136.42976 -281.082643) (xy 136.477979 -281.072799) (xy 136.527154 -281.070818)
			(xy 136.576009 -281.07675) (xy 136.62328 -281.090442) (xy 136.667742 -281.11154) (xy 136.708245 -281.139496)
			(xy 136.743738 -281.173588) (xy 136.773303 -281.212932) (xy 136.796174 -281.256509) (xy 136.811758 -281.30319)
			(xy 136.819653 -281.351767) (xy 136.820148 -281.376374) (xy 136.819653 -281.400981) (xy 136.811758 -281.449558)
			(xy 136.796174 -281.496239) (xy 136.773303 -281.539816) (xy 136.743738 -281.57916) (xy 136.708245 -281.613252)
			(xy 136.667742 -281.641208) (xy 136.62328 -281.662306) (xy 136.576009 -281.675998) (xy 136.527154 -281.68193)
			(xy 136.477979 -281.679949) (xy 136.42976 -281.670105) (xy 136.383744 -281.652653) (xy 136.341123 -281.628046)
			(xy 136.303002 -281.596921) (xy 136.270367 -281.560084) (xy 136.244064 -281.518488) (xy 136.224773 -281.473212)
			(xy 136.212996 -281.425428) (xy 136.209036 -281.376374) (xy 135.880094 -281.376374) (xy 135.879599 -281.400981)
			(xy 135.871704 -281.449558) (xy 135.85612 -281.496239) (xy 135.833249 -281.539816) (xy 135.803684 -281.57916)
			(xy 135.768191 -281.613252) (xy 135.727688 -281.641208) (xy 135.683226 -281.662306) (xy 135.635955 -281.675998)
			(xy 135.5871 -281.68193) (xy 135.537925 -281.679949) (xy 135.489706 -281.670105) (xy 135.44369 -281.652653)
			(xy 135.401069 -281.628046) (xy 135.362948 -281.596921) (xy 135.330313 -281.560084) (xy 135.30401 -281.518488)
			(xy 135.284719 -281.473212) (xy 135.272942 -281.425428) (xy 135.268982 -281.376374) (xy 134.94004 -281.376374)
			(xy 134.939545 -281.400981) (xy 134.93165 -281.449558) (xy 134.916066 -281.496239) (xy 134.893195 -281.539816)
			(xy 134.86363 -281.57916) (xy 134.828137 -281.613252) (xy 134.787634 -281.641208) (xy 134.743172 -281.662306)
			(xy 134.695901 -281.675998) (xy 134.647046 -281.68193) (xy 134.597871 -281.679949) (xy 134.549652 -281.670105)
			(xy 134.503636 -281.652653) (xy 134.461015 -281.628046) (xy 134.422894 -281.596921) (xy 134.390259 -281.560084)
			(xy 134.363956 -281.518488) (xy 134.344665 -281.473212) (xy 134.332888 -281.425428) (xy 134.328928 -281.376374)
			(xy 133.999986 -281.376374) (xy 133.999491 -281.400981) (xy 133.991596 -281.449558) (xy 133.976012 -281.496239)
			(xy 133.953141 -281.539816) (xy 133.923576 -281.57916) (xy 133.888083 -281.613252) (xy 133.84758 -281.641208)
			(xy 133.803118 -281.662306) (xy 133.755847 -281.675998) (xy 133.706992 -281.68193) (xy 133.657817 -281.679949)
			(xy 133.609598 -281.670105) (xy 133.563582 -281.652653) (xy 133.520961 -281.628046) (xy 133.48284 -281.596921)
			(xy 133.450205 -281.560084) (xy 133.423902 -281.518488) (xy 133.404611 -281.473212) (xy 133.392834 -281.425428)
			(xy 133.388874 -281.376374) (xy 133.0706 -281.376374) (xy 133.070088 -281.40182) (xy 133.061924 -281.452054)
			(xy 133.045808 -281.500328) (xy 133.022157 -281.545391) (xy 132.991584 -281.586077) (xy 132.95488 -281.621332)
			(xy 132.912996 -281.650242) (xy 132.867017 -281.672059) (xy 132.818133 -281.686219) (xy 132.767612 -281.692353)
			(xy 132.71676 -281.690304) (xy 132.666896 -281.680124) (xy 132.61931 -281.662077) (xy 132.575236 -281.636631)
			(xy 132.535814 -281.604444) (xy 132.502066 -281.56635) (xy 132.474865 -281.523336) (xy 132.454917 -281.476516)
			(xy 132.442738 -281.427102) (xy 132.438643 -281.376374) (xy 132.130546 -281.376374) (xy 132.130034 -281.40182)
			(xy 132.12187 -281.452054) (xy 132.105754 -281.500328) (xy 132.082103 -281.545391) (xy 132.05153 -281.586077)
			(xy 132.014826 -281.621332) (xy 131.972942 -281.650242) (xy 131.926963 -281.672059) (xy 131.878079 -281.686219)
			(xy 131.827558 -281.692353) (xy 131.776706 -281.690304) (xy 131.726842 -281.680124) (xy 131.679256 -281.662077)
			(xy 131.635182 -281.636631) (xy 131.59576 -281.604444) (xy 131.562012 -281.56635) (xy 131.534811 -281.523336)
			(xy 131.514863 -281.476516) (xy 131.502684 -281.427102) (xy 131.498589 -281.376374) (xy 131.180078 -281.376374)
			(xy 131.179583 -281.400981) (xy 131.171688 -281.449558) (xy 131.156104 -281.496239) (xy 131.133233 -281.539816)
			(xy 131.103668 -281.57916) (xy 131.068175 -281.613252) (xy 131.027672 -281.641208) (xy 130.98321 -281.662306)
			(xy 130.935939 -281.675998) (xy 130.887084 -281.68193) (xy 130.837909 -281.679949) (xy 130.78969 -281.670105)
			(xy 130.743674 -281.652653) (xy 130.701053 -281.628046) (xy 130.662932 -281.596921) (xy 130.630297 -281.560084)
			(xy 130.603994 -281.518488) (xy 130.584703 -281.473212) (xy 130.572926 -281.425428) (xy 130.568966 -281.376374)
			(xy 130.250438 -281.376374) (xy 130.249926 -281.40182) (xy 130.241762 -281.452054) (xy 130.225646 -281.500328)
			(xy 130.201995 -281.545391) (xy 130.171422 -281.586077) (xy 130.134718 -281.621332) (xy 130.092834 -281.650242)
			(xy 130.046855 -281.672059) (xy 129.997971 -281.686219) (xy 129.94745 -281.692353) (xy 129.896598 -281.690304)
			(xy 129.846734 -281.680124) (xy 129.799148 -281.662077) (xy 129.755074 -281.636631) (xy 129.715652 -281.604444)
			(xy 129.681904 -281.56635) (xy 129.654703 -281.523336) (xy 129.634755 -281.476516) (xy 129.622576 -281.427102)
			(xy 129.618481 -281.376374) (xy 129.29997 -281.376374) (xy 129.299475 -281.400981) (xy 129.29158 -281.449558)
			(xy 129.275996 -281.496239) (xy 129.253125 -281.539816) (xy 129.22356 -281.57916) (xy 129.188067 -281.613252)
			(xy 129.147564 -281.641208) (xy 129.103102 -281.662306) (xy 129.055831 -281.675998) (xy 129.006976 -281.68193)
			(xy 128.957801 -281.679949) (xy 128.909582 -281.670105) (xy 128.863566 -281.652653) (xy 128.820945 -281.628046)
			(xy 128.782824 -281.596921) (xy 128.750189 -281.560084) (xy 128.723886 -281.518488) (xy 128.704595 -281.473212)
			(xy 128.692818 -281.425428) (xy 128.688858 -281.376374) (xy 128.370584 -281.376374) (xy 128.370072 -281.40182)
			(xy 128.361908 -281.452054) (xy 128.345792 -281.500328) (xy 128.322141 -281.545391) (xy 128.291568 -281.586077)
			(xy 128.254864 -281.621332) (xy 128.21298 -281.650242) (xy 128.167001 -281.672059) (xy 128.118117 -281.686219)
			(xy 128.067596 -281.692353) (xy 128.016744 -281.690304) (xy 127.96688 -281.680124) (xy 127.919294 -281.662077)
			(xy 127.87522 -281.636631) (xy 127.835798 -281.604444) (xy 127.80205 -281.56635) (xy 127.774849 -281.523336)
			(xy 127.754901 -281.476516) (xy 127.742722 -281.427102) (xy 127.738627 -281.376374) (xy 127.472186 -281.376374)
			(xy 127.472186 -281.405584) (xy 127.47879 -281.422856) (xy 127.48514 -281.429968) (xy 127.518914 -281.468314)
			(xy 127.580175 -281.550107) (xy 127.633809 -281.637093) (xy 127.679379 -281.728561) (xy 127.716512 -281.823767)
			(xy 127.731266 -281.87269) (xy 127.734328 -281.881831) (xy 127.746083 -281.897092) (xy 127.754126 -281.902408)
			(xy 127.776443 -281.916312) (xy 127.816764 -281.950055) (xy 127.851238 -281.989753) (xy 127.878996 -282.034405)
			(xy 127.899339 -282.082888) (xy 127.911755 -282.133978) (xy 127.915928 -282.18638) (xy 128.208527 -282.18638)
			(xy 128.212622 -282.135652) (xy 128.224801 -282.086238) (xy 128.244749 -282.039418) (xy 128.27195 -281.996404)
			(xy 128.305698 -281.95831) (xy 128.34512 -281.926123) (xy 128.389194 -281.900677) (xy 128.43678 -281.88263)
			(xy 128.486644 -281.87245) (xy 128.537496 -281.870401) (xy 128.588017 -281.876535) (xy 128.636901 -281.890695)
			(xy 128.68288 -281.912512) (xy 128.724764 -281.941422) (xy 128.761468 -281.976677) (xy 128.792041 -282.017363)
			(xy 128.815692 -282.062426) (xy 128.831808 -282.1107) (xy 128.839972 -282.160934) (xy 128.840484 -282.18638)
			(xy 129.148581 -282.18638) (xy 129.152676 -282.135652) (xy 129.164855 -282.086238) (xy 129.184803 -282.039418)
			(xy 129.212004 -281.996404) (xy 129.245752 -281.95831) (xy 129.285174 -281.926123) (xy 129.329248 -281.900677)
			(xy 129.376834 -281.88263) (xy 129.426698 -281.87245) (xy 129.47755 -281.870401) (xy 129.528071 -281.876535)
			(xy 129.576955 -281.890695) (xy 129.622934 -281.912512) (xy 129.664818 -281.941422) (xy 129.701522 -281.976677)
			(xy 129.732095 -282.017363) (xy 129.755746 -282.062426) (xy 129.771862 -282.1107) (xy 129.780026 -282.160934)
			(xy 129.780538 -282.18638) (xy 130.099066 -282.18638) (xy 130.103026 -282.137326) (xy 130.114803 -282.089542)
			(xy 130.134094 -282.044266) (xy 130.160397 -282.00267) (xy 130.193032 -281.965833) (xy 130.231153 -281.934708)
			(xy 130.273774 -281.910101) (xy 130.31979 -281.892649) (xy 130.368009 -281.882805) (xy 130.417184 -281.880824)
			(xy 130.466039 -281.886756) (xy 130.51331 -281.900448) (xy 130.557772 -281.921546) (xy 130.598275 -281.949502)
			(xy 130.633768 -281.983594) (xy 130.663333 -282.022938) (xy 130.686204 -282.066515) (xy 130.701788 -282.113196)
			(xy 130.709683 -282.161773) (xy 130.710178 -282.18638) (xy 131.028435 -282.18638) (xy 131.03253 -282.135652)
			(xy 131.044709 -282.086238) (xy 131.064657 -282.039418) (xy 131.091858 -281.996404) (xy 131.125606 -281.95831)
			(xy 131.165028 -281.926123) (xy 131.209102 -281.900677) (xy 131.256688 -281.88263) (xy 131.306552 -281.87245)
			(xy 131.357404 -281.870401) (xy 131.407925 -281.876535) (xy 131.456809 -281.890695) (xy 131.502788 -281.912512)
			(xy 131.544672 -281.941422) (xy 131.581376 -281.976677) (xy 131.611949 -282.017363) (xy 131.6356 -282.062426)
			(xy 131.651716 -282.1107) (xy 131.65988 -282.160934) (xy 131.660392 -282.18638) (xy 131.97892 -282.18638)
			(xy 131.98288 -282.137326) (xy 131.994657 -282.089542) (xy 132.013948 -282.044266) (xy 132.040251 -282.00267)
			(xy 132.072886 -281.965833) (xy 132.111007 -281.934708) (xy 132.153628 -281.910101) (xy 132.199644 -281.892649)
			(xy 132.247863 -281.882805) (xy 132.297038 -281.880824) (xy 132.345893 -281.886756) (xy 132.393164 -281.900448)
			(xy 132.437626 -281.921546) (xy 132.478129 -281.949502) (xy 132.513622 -281.983594) (xy 132.543187 -282.022938)
			(xy 132.566058 -282.066515) (xy 132.581642 -282.113196) (xy 132.589537 -282.161773) (xy 132.590032 -282.18638)
			(xy 132.908543 -282.18638) (xy 132.912638 -282.135652) (xy 132.924817 -282.086238) (xy 132.944765 -282.039418)
			(xy 132.971966 -281.996404) (xy 133.005714 -281.95831) (xy 133.045136 -281.926123) (xy 133.08921 -281.900677)
			(xy 133.136796 -281.88263) (xy 133.18666 -281.87245) (xy 133.237512 -281.870401) (xy 133.288033 -281.876535)
			(xy 133.336917 -281.890695) (xy 133.382896 -281.912512) (xy 133.42478 -281.941422) (xy 133.461484 -281.976677)
			(xy 133.492057 -282.017363) (xy 133.515708 -282.062426) (xy 133.531824 -282.1107) (xy 133.539988 -282.160934)
			(xy 133.5405 -282.18638) (xy 133.859028 -282.18638) (xy 133.862988 -282.137326) (xy 133.874765 -282.089542)
			(xy 133.894056 -282.044266) (xy 133.920359 -282.00267) (xy 133.952994 -281.965833) (xy 133.991115 -281.934708)
			(xy 134.033736 -281.910101) (xy 134.079752 -281.892649) (xy 134.127971 -281.882805) (xy 134.177146 -281.880824)
			(xy 134.226001 -281.886756) (xy 134.273272 -281.900448) (xy 134.317734 -281.921546) (xy 134.358237 -281.949502)
			(xy 134.39373 -281.983594) (xy 134.423295 -282.022938) (xy 134.446166 -282.066515) (xy 134.46175 -282.113196)
			(xy 134.469645 -282.161773) (xy 134.47014 -282.18638) (xy 134.798828 -282.18638) (xy 134.802788 -282.137326)
			(xy 134.814565 -282.089542) (xy 134.833856 -282.044266) (xy 134.860159 -282.00267) (xy 134.892794 -281.965833)
			(xy 134.930915 -281.934708) (xy 134.973536 -281.910101) (xy 135.019552 -281.892649) (xy 135.067771 -281.882805)
			(xy 135.116946 -281.880824) (xy 135.165801 -281.886756) (xy 135.213072 -281.900448) (xy 135.257534 -281.921546)
			(xy 135.298037 -281.949502) (xy 135.33353 -281.983594) (xy 135.363095 -282.022938) (xy 135.385966 -282.066515)
			(xy 135.40155 -282.113196) (xy 135.409445 -282.161773) (xy 135.40994 -282.18638) (xy 135.738882 -282.18638)
			(xy 135.742842 -282.137326) (xy 135.754619 -282.089542) (xy 135.77391 -282.044266) (xy 135.800213 -282.00267)
			(xy 135.832848 -281.965833) (xy 135.870969 -281.934708) (xy 135.91359 -281.910101) (xy 135.959606 -281.892649)
			(xy 136.007825 -281.882805) (xy 136.057 -281.880824) (xy 136.105855 -281.886756) (xy 136.153126 -281.900448)
			(xy 136.197588 -281.921546) (xy 136.238091 -281.949502) (xy 136.273584 -281.983594) (xy 136.303149 -282.022938)
			(xy 136.32602 -282.066515) (xy 136.341604 -282.113196) (xy 136.349499 -282.161773) (xy 136.349994 -282.18638)
			(xy 136.349499 -282.210987) (xy 136.341604 -282.259564) (xy 136.32602 -282.306245) (xy 136.303149 -282.349822)
			(xy 136.273584 -282.389166) (xy 136.238091 -282.423258) (xy 136.197588 -282.451214) (xy 136.153126 -282.472312)
			(xy 136.105855 -282.486004) (xy 136.057 -282.491936) (xy 136.007825 -282.489955) (xy 135.959606 -282.480111)
			(xy 135.91359 -282.462659) (xy 135.870969 -282.438052) (xy 135.832848 -282.406927) (xy 135.800213 -282.37009)
			(xy 135.77391 -282.328494) (xy 135.754619 -282.283218) (xy 135.742842 -282.235434) (xy 135.738882 -282.18638)
			(xy 135.40994 -282.18638) (xy 135.409445 -282.210987) (xy 135.40155 -282.259564) (xy 135.385966 -282.306245)
			(xy 135.363095 -282.349822) (xy 135.33353 -282.389166) (xy 135.298037 -282.423258) (xy 135.257534 -282.451214)
			(xy 135.213072 -282.472312) (xy 135.165801 -282.486004) (xy 135.116946 -282.491936) (xy 135.067771 -282.489955)
			(xy 135.019552 -282.480111) (xy 134.973536 -282.462659) (xy 134.930915 -282.438052) (xy 134.892794 -282.406927)
			(xy 134.860159 -282.37009) (xy 134.833856 -282.328494) (xy 134.814565 -282.283218) (xy 134.802788 -282.235434)
			(xy 134.798828 -282.18638) (xy 134.47014 -282.18638) (xy 134.469645 -282.210987) (xy 134.46175 -282.259564)
			(xy 134.446166 -282.306245) (xy 134.423295 -282.349822) (xy 134.39373 -282.389166) (xy 134.358237 -282.423258)
			(xy 134.317734 -282.451214) (xy 134.273272 -282.472312) (xy 134.226001 -282.486004) (xy 134.177146 -282.491936)
			(xy 134.127971 -282.489955) (xy 134.079752 -282.480111) (xy 134.033736 -282.462659) (xy 133.991115 -282.438052)
			(xy 133.952994 -282.406927) (xy 133.920359 -282.37009) (xy 133.894056 -282.328494) (xy 133.874765 -282.283218)
			(xy 133.862988 -282.235434) (xy 133.859028 -282.18638) (xy 133.5405 -282.18638) (xy 133.539988 -282.211826)
			(xy 133.531824 -282.26206) (xy 133.515708 -282.310334) (xy 133.492057 -282.355397) (xy 133.461484 -282.396083)
			(xy 133.42478 -282.431338) (xy 133.382896 -282.460248) (xy 133.336917 -282.482065) (xy 133.288033 -282.496225)
			(xy 133.237512 -282.502359) (xy 133.18666 -282.50031) (xy 133.136796 -282.49013) (xy 133.08921 -282.472083)
			(xy 133.045136 -282.446637) (xy 133.005714 -282.41445) (xy 132.971966 -282.376356) (xy 132.944765 -282.333342)
			(xy 132.924817 -282.286522) (xy 132.912638 -282.237108) (xy 132.908543 -282.18638) (xy 132.590032 -282.18638)
			(xy 132.589537 -282.210987) (xy 132.581642 -282.259564) (xy 132.566058 -282.306245) (xy 132.543187 -282.349822)
			(xy 132.513622 -282.389166) (xy 132.478129 -282.423258) (xy 132.437626 -282.451214) (xy 132.393164 -282.472312)
			(xy 132.345893 -282.486004) (xy 132.297038 -282.491936) (xy 132.247863 -282.489955) (xy 132.199644 -282.480111)
			(xy 132.153628 -282.462659) (xy 132.111007 -282.438052) (xy 132.072886 -282.406927) (xy 132.040251 -282.37009)
			(xy 132.013948 -282.328494) (xy 131.994657 -282.283218) (xy 131.98288 -282.235434) (xy 131.97892 -282.18638)
			(xy 131.660392 -282.18638) (xy 131.65988 -282.211826) (xy 131.651716 -282.26206) (xy 131.6356 -282.310334)
			(xy 131.611949 -282.355397) (xy 131.581376 -282.396083) (xy 131.544672 -282.431338) (xy 131.502788 -282.460248)
			(xy 131.456809 -282.482065) (xy 131.407925 -282.496225) (xy 131.357404 -282.502359) (xy 131.306552 -282.50031)
			(xy 131.256688 -282.49013) (xy 131.209102 -282.472083) (xy 131.165028 -282.446637) (xy 131.125606 -282.41445)
			(xy 131.091858 -282.376356) (xy 131.064657 -282.333342) (xy 131.044709 -282.286522) (xy 131.03253 -282.237108)
			(xy 131.028435 -282.18638) (xy 130.710178 -282.18638) (xy 130.709683 -282.210987) (xy 130.701788 -282.259564)
			(xy 130.686204 -282.306245) (xy 130.663333 -282.349822) (xy 130.633768 -282.389166) (xy 130.598275 -282.423258)
			(xy 130.557772 -282.451214) (xy 130.51331 -282.472312) (xy 130.466039 -282.486004) (xy 130.417184 -282.491936)
			(xy 130.368009 -282.489955) (xy 130.31979 -282.480111) (xy 130.273774 -282.462659) (xy 130.231153 -282.438052)
			(xy 130.193032 -282.406927) (xy 130.160397 -282.37009) (xy 130.134094 -282.328494) (xy 130.114803 -282.283218)
			(xy 130.103026 -282.235434) (xy 130.099066 -282.18638) (xy 129.780538 -282.18638) (xy 129.780026 -282.211826)
			(xy 129.771862 -282.26206) (xy 129.755746 -282.310334) (xy 129.732095 -282.355397) (xy 129.701522 -282.396083)
			(xy 129.664818 -282.431338) (xy 129.622934 -282.460248) (xy 129.576955 -282.482065) (xy 129.528071 -282.496225)
			(xy 129.47755 -282.502359) (xy 129.426698 -282.50031) (xy 129.376834 -282.49013) (xy 129.329248 -282.472083)
			(xy 129.285174 -282.446637) (xy 129.245752 -282.41445) (xy 129.212004 -282.376356) (xy 129.184803 -282.333342)
			(xy 129.164855 -282.286522) (xy 129.152676 -282.237108) (xy 129.148581 -282.18638) (xy 128.840484 -282.18638)
			(xy 128.839972 -282.211826) (xy 128.831808 -282.26206) (xy 128.815692 -282.310334) (xy 128.792041 -282.355397)
			(xy 128.761468 -282.396083) (xy 128.724764 -282.431338) (xy 128.68288 -282.460248) (xy 128.636901 -282.482065)
			(xy 128.588017 -282.496225) (xy 128.537496 -282.502359) (xy 128.486644 -282.50031) (xy 128.43678 -282.49013)
			(xy 128.389194 -282.472083) (xy 128.34512 -282.446637) (xy 128.305698 -282.41445) (xy 128.27195 -282.376356)
			(xy 128.244749 -282.333342) (xy 128.224801 -282.286522) (xy 128.212622 -282.237108) (xy 128.208527 -282.18638)
			(xy 127.915928 -282.18638) (xy 127.915929 -282.18639) (xy 127.911758 -282.238801) (xy 127.899346 -282.289893)
			(xy 127.879006 -282.338376) (xy 127.85125 -282.383031) (xy 127.816779 -282.422731) (xy 127.776459 -282.456476)
			(xy 127.754126 -282.470352) (xy 127.74604 -282.475621) (xy 127.734278 -282.490902) (xy 127.731266 -282.50007)
			(xy 127.716534 -282.549) (xy 127.679413 -282.644214) (xy 127.633845 -282.735687) (xy 127.580203 -282.82267)
			(xy 127.518925 -282.904454) (xy 127.48514 -282.942792) (xy 127.47879 -282.949904) (xy 127.472186 -282.967176)
			(xy 127.472186 -282.996386) (xy 127.738627 -282.996386) (xy 127.742722 -282.945658) (xy 127.754901 -282.896244)
			(xy 127.774849 -282.849424) (xy 127.80205 -282.80641) (xy 127.835798 -282.768316) (xy 127.87522 -282.736129)
			(xy 127.919294 -282.710683) (xy 127.96688 -282.692636) (xy 128.016744 -282.682456) (xy 128.067596 -282.680407)
			(xy 128.118117 -282.686541) (xy 128.167001 -282.700701) (xy 128.21298 -282.722518) (xy 128.254864 -282.751428)
			(xy 128.291568 -282.786683) (xy 128.322141 -282.827369) (xy 128.345792 -282.872432) (xy 128.361908 -282.920706)
			(xy 128.370072 -282.97094) (xy 128.370584 -282.996386) (xy 128.688858 -282.996386) (xy 128.692818 -282.947332)
			(xy 128.704595 -282.899548) (xy 128.723886 -282.854272) (xy 128.750189 -282.812676) (xy 128.782824 -282.775839)
			(xy 128.820945 -282.744714) (xy 128.863566 -282.720107) (xy 128.909582 -282.702655) (xy 128.957801 -282.692811)
			(xy 129.006976 -282.69083) (xy 129.055831 -282.696762) (xy 129.103102 -282.710454) (xy 129.147564 -282.731552)
			(xy 129.188067 -282.759508) (xy 129.22356 -282.7936) (xy 129.253125 -282.832944) (xy 129.275996 -282.876521)
			(xy 129.29158 -282.923202) (xy 129.299475 -282.971779) (xy 129.29997 -282.996386) (xy 129.618481 -282.996386)
			(xy 129.622576 -282.945658) (xy 129.634755 -282.896244) (xy 129.654703 -282.849424) (xy 129.681904 -282.80641)
			(xy 129.715652 -282.768316) (xy 129.755074 -282.736129) (xy 129.799148 -282.710683) (xy 129.846734 -282.692636)
			(xy 129.896598 -282.682456) (xy 129.94745 -282.680407) (xy 129.997971 -282.686541) (xy 130.046855 -282.700701)
			(xy 130.092834 -282.722518) (xy 130.134718 -282.751428) (xy 130.171422 -282.786683) (xy 130.201995 -282.827369)
			(xy 130.225646 -282.872432) (xy 130.241762 -282.920706) (xy 130.249926 -282.97094) (xy 130.250438 -282.996386)
			(xy 131.498589 -282.996386) (xy 131.502684 -282.945658) (xy 131.514863 -282.896244) (xy 131.534811 -282.849424)
			(xy 131.562012 -282.80641) (xy 131.59576 -282.768316) (xy 131.635182 -282.736129) (xy 131.679256 -282.710683)
			(xy 131.726842 -282.692636) (xy 131.776706 -282.682456) (xy 131.827558 -282.680407) (xy 131.878079 -282.686541)
			(xy 131.926963 -282.700701) (xy 131.972942 -282.722518) (xy 132.014826 -282.751428) (xy 132.05153 -282.786683)
			(xy 132.082103 -282.827369) (xy 132.105754 -282.872432) (xy 132.12187 -282.920706) (xy 132.130034 -282.97094)
			(xy 132.130546 -282.996386) (xy 132.438643 -282.996386) (xy 132.442738 -282.945658) (xy 132.454917 -282.896244)
			(xy 132.474865 -282.849424) (xy 132.502066 -282.80641) (xy 132.535814 -282.768316) (xy 132.575236 -282.736129)
			(xy 132.61931 -282.710683) (xy 132.666896 -282.692636) (xy 132.71676 -282.682456) (xy 132.767612 -282.680407)
			(xy 132.818133 -282.686541) (xy 132.867017 -282.700701) (xy 132.912996 -282.722518) (xy 132.95488 -282.751428)
			(xy 132.991584 -282.786683) (xy 133.022157 -282.827369) (xy 133.045808 -282.872432) (xy 133.061924 -282.920706)
			(xy 133.070088 -282.97094) (xy 133.0706 -282.996386) (xy 133.388874 -282.996386) (xy 133.392834 -282.947332)
			(xy 133.404611 -282.899548) (xy 133.423902 -282.854272) (xy 133.450205 -282.812676) (xy 133.48284 -282.775839)
			(xy 133.520961 -282.744714) (xy 133.563582 -282.720107) (xy 133.609598 -282.702655) (xy 133.657817 -282.692811)
			(xy 133.706992 -282.69083) (xy 133.755847 -282.696762) (xy 133.803118 -282.710454) (xy 133.84758 -282.731552)
			(xy 133.888083 -282.759508) (xy 133.923576 -282.7936) (xy 133.953141 -282.832944) (xy 133.976012 -282.876521)
			(xy 133.991596 -282.923202) (xy 133.999491 -282.971779) (xy 133.999986 -282.996386) (xy 134.328928 -282.996386)
			(xy 134.332888 -282.947332) (xy 134.344665 -282.899548) (xy 134.363956 -282.854272) (xy 134.390259 -282.812676)
			(xy 134.422894 -282.775839) (xy 134.461015 -282.744714) (xy 134.503636 -282.720107) (xy 134.549652 -282.702655)
			(xy 134.597871 -282.692811) (xy 134.647046 -282.69083) (xy 134.695901 -282.696762) (xy 134.743172 -282.710454)
			(xy 134.787634 -282.731552) (xy 134.828137 -282.759508) (xy 134.86363 -282.7936) (xy 134.893195 -282.832944)
			(xy 134.916066 -282.876521) (xy 134.93165 -282.923202) (xy 134.939545 -282.971779) (xy 134.94004 -282.996386)
			(xy 135.268982 -282.996386) (xy 135.272942 -282.947332) (xy 135.284719 -282.899548) (xy 135.30401 -282.854272)
			(xy 135.330313 -282.812676) (xy 135.362948 -282.775839) (xy 135.401069 -282.744714) (xy 135.44369 -282.720107)
			(xy 135.489706 -282.702655) (xy 135.537925 -282.692811) (xy 135.5871 -282.69083) (xy 135.635955 -282.696762)
			(xy 135.683226 -282.710454) (xy 135.727688 -282.731552) (xy 135.768191 -282.759508) (xy 135.803684 -282.7936)
			(xy 135.833249 -282.832944) (xy 135.85612 -282.876521) (xy 135.871704 -282.923202) (xy 135.879599 -282.971779)
			(xy 135.880094 -282.996386) (xy 136.209036 -282.996386) (xy 136.212996 -282.947332) (xy 136.224773 -282.899548)
			(xy 136.244064 -282.854272) (xy 136.270367 -282.812676) (xy 136.303002 -282.775839) (xy 136.341123 -282.744714)
			(xy 136.383744 -282.720107) (xy 136.42976 -282.702655) (xy 136.477979 -282.692811) (xy 136.527154 -282.69083)
			(xy 136.576009 -282.696762) (xy 136.62328 -282.710454) (xy 136.667742 -282.731552) (xy 136.708245 -282.759508)
			(xy 136.743738 -282.7936) (xy 136.773303 -282.832944) (xy 136.796174 -282.876521) (xy 136.811758 -282.923202)
			(xy 136.819653 -282.971779) (xy 136.820148 -282.996386) (xy 136.819653 -283.020993) (xy 136.811758 -283.06957)
			(xy 136.796174 -283.116251) (xy 136.773303 -283.159828) (xy 136.743738 -283.199172) (xy 136.708245 -283.233264)
			(xy 136.667742 -283.26122) (xy 136.62328 -283.282318) (xy 136.576009 -283.29601) (xy 136.527154 -283.301942)
			(xy 136.477979 -283.299961) (xy 136.42976 -283.290117) (xy 136.383744 -283.272665) (xy 136.341123 -283.248058)
			(xy 136.303002 -283.216933) (xy 136.270367 -283.180096) (xy 136.244064 -283.1385) (xy 136.224773 -283.093224)
			(xy 136.212996 -283.04544) (xy 136.209036 -282.996386) (xy 135.880094 -282.996386) (xy 135.879599 -283.020993)
			(xy 135.871704 -283.06957) (xy 135.85612 -283.116251) (xy 135.833249 -283.159828) (xy 135.803684 -283.199172)
			(xy 135.768191 -283.233264) (xy 135.727688 -283.26122) (xy 135.683226 -283.282318) (xy 135.635955 -283.29601)
			(xy 135.5871 -283.301942) (xy 135.537925 -283.299961) (xy 135.489706 -283.290117) (xy 135.44369 -283.272665)
			(xy 135.401069 -283.248058) (xy 135.362948 -283.216933) (xy 135.330313 -283.180096) (xy 135.30401 -283.1385)
			(xy 135.284719 -283.093224) (xy 135.272942 -283.04544) (xy 135.268982 -282.996386) (xy 134.94004 -282.996386)
			(xy 134.939545 -283.020993) (xy 134.93165 -283.06957) (xy 134.916066 -283.116251) (xy 134.893195 -283.159828)
			(xy 134.86363 -283.199172) (xy 134.828137 -283.233264) (xy 134.787634 -283.26122) (xy 134.743172 -283.282318)
			(xy 134.695901 -283.29601) (xy 134.647046 -283.301942) (xy 134.597871 -283.299961) (xy 134.549652 -283.290117)
			(xy 134.503636 -283.272665) (xy 134.461015 -283.248058) (xy 134.422894 -283.216933) (xy 134.390259 -283.180096)
			(xy 134.363956 -283.1385) (xy 134.344665 -283.093224) (xy 134.332888 -283.04544) (xy 134.328928 -282.996386)
			(xy 133.999986 -282.996386) (xy 133.999491 -283.020993) (xy 133.991596 -283.06957) (xy 133.976012 -283.116251)
			(xy 133.953141 -283.159828) (xy 133.923576 -283.199172) (xy 133.888083 -283.233264) (xy 133.84758 -283.26122)
			(xy 133.803118 -283.282318) (xy 133.755847 -283.29601) (xy 133.706992 -283.301942) (xy 133.657817 -283.299961)
			(xy 133.609598 -283.290117) (xy 133.563582 -283.272665) (xy 133.520961 -283.248058) (xy 133.48284 -283.216933)
			(xy 133.450205 -283.180096) (xy 133.423902 -283.1385) (xy 133.404611 -283.093224) (xy 133.392834 -283.04544)
			(xy 133.388874 -282.996386) (xy 133.0706 -282.996386) (xy 133.070088 -283.021832) (xy 133.061924 -283.072066)
			(xy 133.045808 -283.12034) (xy 133.022157 -283.165403) (xy 132.991584 -283.206089) (xy 132.95488 -283.241344)
			(xy 132.912996 -283.270254) (xy 132.867017 -283.292071) (xy 132.818133 -283.306231) (xy 132.767612 -283.312365)
			(xy 132.71676 -283.310316) (xy 132.666896 -283.300136) (xy 132.61931 -283.282089) (xy 132.575236 -283.256643)
			(xy 132.535814 -283.224456) (xy 132.502066 -283.186362) (xy 132.474865 -283.143348) (xy 132.454917 -283.096528)
			(xy 132.442738 -283.047114) (xy 132.438643 -282.996386) (xy 132.130546 -282.996386) (xy 132.130034 -283.021832)
			(xy 132.12187 -283.072066) (xy 132.105754 -283.12034) (xy 132.082103 -283.165403) (xy 132.05153 -283.206089)
			(xy 132.014826 -283.241344) (xy 131.972942 -283.270254) (xy 131.926963 -283.292071) (xy 131.878079 -283.306231)
			(xy 131.827558 -283.312365) (xy 131.776706 -283.310316) (xy 131.726842 -283.300136) (xy 131.679256 -283.282089)
			(xy 131.635182 -283.256643) (xy 131.59576 -283.224456) (xy 131.562012 -283.186362) (xy 131.534811 -283.143348)
			(xy 131.514863 -283.096528) (xy 131.502684 -283.047114) (xy 131.498589 -282.996386) (xy 130.250438 -282.996386)
			(xy 130.249926 -283.021832) (xy 130.241762 -283.072066) (xy 130.225646 -283.12034) (xy 130.201995 -283.165403)
			(xy 130.171422 -283.206089) (xy 130.134718 -283.241344) (xy 130.092834 -283.270254) (xy 130.046855 -283.292071)
			(xy 129.997971 -283.306231) (xy 129.94745 -283.312365) (xy 129.896598 -283.310316) (xy 129.846734 -283.300136)
			(xy 129.799148 -283.282089) (xy 129.755074 -283.256643) (xy 129.715652 -283.224456) (xy 129.681904 -283.186362)
			(xy 129.654703 -283.143348) (xy 129.634755 -283.096528) (xy 129.622576 -283.047114) (xy 129.618481 -282.996386)
			(xy 129.29997 -282.996386) (xy 129.299475 -283.020993) (xy 129.29158 -283.06957) (xy 129.275996 -283.116251)
			(xy 129.253125 -283.159828) (xy 129.22356 -283.199172) (xy 129.188067 -283.233264) (xy 129.147564 -283.26122)
			(xy 129.103102 -283.282318) (xy 129.055831 -283.29601) (xy 129.006976 -283.301942) (xy 128.957801 -283.299961)
			(xy 128.909582 -283.290117) (xy 128.863566 -283.272665) (xy 128.820945 -283.248058) (xy 128.782824 -283.216933)
			(xy 128.750189 -283.180096) (xy 128.723886 -283.1385) (xy 128.704595 -283.093224) (xy 128.692818 -283.04544)
			(xy 128.688858 -282.996386) (xy 128.370584 -282.996386) (xy 128.370072 -283.021832) (xy 128.361908 -283.072066)
			(xy 128.345792 -283.12034) (xy 128.322141 -283.165403) (xy 128.291568 -283.206089) (xy 128.254864 -283.241344)
			(xy 128.21298 -283.270254) (xy 128.167001 -283.292071) (xy 128.118117 -283.306231) (xy 128.067596 -283.312365)
			(xy 128.016744 -283.310316) (xy 127.96688 -283.300136) (xy 127.919294 -283.282089) (xy 127.87522 -283.256643)
			(xy 127.835798 -283.224456) (xy 127.80205 -283.186362) (xy 127.774849 -283.143348) (xy 127.754901 -283.096528)
			(xy 127.742722 -283.047114) (xy 127.738627 -282.996386) (xy 127.472186 -282.996386) (xy 127.472186 -283.025596)
			(xy 127.47879 -283.042868) (xy 127.48514 -283.04998) (xy 127.515327 -283.084187) (xy 127.570705 -283.156699)
			(xy 127.62006 -283.233438) (xy 127.66307 -283.313905) (xy 127.699455 -283.397576) (xy 127.728979 -283.483907)
			(xy 127.740664 -283.528008) (xy 127.743267 -283.536655) (xy 127.753551 -283.551485) (xy 127.76073 -283.556964)
			(xy 127.780344 -283.571387) (xy 127.815162 -283.605415) (xy 127.84414 -283.644535) (xy 127.866547 -283.687757)
			(xy 127.881813 -283.733985) (xy 127.889553 -283.78205) (xy 127.890016 -283.806392) (xy 128.208527 -283.806392)
			(xy 128.212622 -283.755664) (xy 128.224801 -283.70625) (xy 128.244749 -283.65943) (xy 128.27195 -283.616416)
			(xy 128.305698 -283.578322) (xy 128.34512 -283.546135) (xy 128.389194 -283.520689) (xy 128.43678 -283.502642)
			(xy 128.486644 -283.492462) (xy 128.537496 -283.490413) (xy 128.588017 -283.496547) (xy 128.636901 -283.510707)
			(xy 128.68288 -283.532524) (xy 128.724764 -283.561434) (xy 128.761468 -283.596689) (xy 128.792041 -283.637375)
			(xy 128.815692 -283.682438) (xy 128.831808 -283.730712) (xy 128.839972 -283.780946) (xy 128.840484 -283.806392)
			(xy 129.148581 -283.806392) (xy 129.152676 -283.755664) (xy 129.164855 -283.70625) (xy 129.184803 -283.65943)
			(xy 129.212004 -283.616416) (xy 129.245752 -283.578322) (xy 129.285174 -283.546135) (xy 129.329248 -283.520689)
			(xy 129.376834 -283.502642) (xy 129.426698 -283.492462) (xy 129.47755 -283.490413) (xy 129.528071 -283.496547)
			(xy 129.576955 -283.510707) (xy 129.622934 -283.532524) (xy 129.664818 -283.561434) (xy 129.701522 -283.596689)
			(xy 129.732095 -283.637375) (xy 129.755746 -283.682438) (xy 129.771862 -283.730712) (xy 129.780026 -283.780946)
			(xy 129.780538 -283.806392) (xy 130.099066 -283.806392) (xy 130.103026 -283.757338) (xy 130.114803 -283.709554)
			(xy 130.134094 -283.664278) (xy 130.160397 -283.622682) (xy 130.193032 -283.585845) (xy 130.231153 -283.55472)
			(xy 130.273774 -283.530113) (xy 130.31979 -283.512661) (xy 130.368009 -283.502817) (xy 130.417184 -283.500836)
			(xy 130.466039 -283.506768) (xy 130.51331 -283.52046) (xy 130.557772 -283.541558) (xy 130.598275 -283.569514)
			(xy 130.633768 -283.603606) (xy 130.663333 -283.64295) (xy 130.686204 -283.686527) (xy 130.701788 -283.733208)
			(xy 130.709683 -283.781785) (xy 130.710178 -283.806392) (xy 131.028435 -283.806392) (xy 131.03253 -283.755664)
			(xy 131.044709 -283.70625) (xy 131.064657 -283.65943) (xy 131.091858 -283.616416) (xy 131.125606 -283.578322)
			(xy 131.165028 -283.546135) (xy 131.209102 -283.520689) (xy 131.256688 -283.502642) (xy 131.306552 -283.492462)
			(xy 131.357404 -283.490413) (xy 131.407925 -283.496547) (xy 131.456809 -283.510707) (xy 131.502788 -283.532524)
			(xy 131.544672 -283.561434) (xy 131.581376 -283.596689) (xy 131.611949 -283.637375) (xy 131.6356 -283.682438)
			(xy 131.651716 -283.730712) (xy 131.65988 -283.780946) (xy 131.660392 -283.806392) (xy 131.97892 -283.806392)
			(xy 131.98288 -283.757338) (xy 131.994657 -283.709554) (xy 132.013948 -283.664278) (xy 132.040251 -283.622682)
			(xy 132.072886 -283.585845) (xy 132.111007 -283.55472) (xy 132.153628 -283.530113) (xy 132.199644 -283.512661)
			(xy 132.247863 -283.502817) (xy 132.297038 -283.500836) (xy 132.345893 -283.506768) (xy 132.393164 -283.52046)
			(xy 132.437626 -283.541558) (xy 132.478129 -283.569514) (xy 132.513622 -283.603606) (xy 132.543187 -283.64295)
			(xy 132.566058 -283.686527) (xy 132.581642 -283.733208) (xy 132.589537 -283.781785) (xy 132.590032 -283.806392)
			(xy 132.908543 -283.806392) (xy 132.912638 -283.755664) (xy 132.924817 -283.70625) (xy 132.944765 -283.65943)
			(xy 132.971966 -283.616416) (xy 133.005714 -283.578322) (xy 133.045136 -283.546135) (xy 133.08921 -283.520689)
			(xy 133.136796 -283.502642) (xy 133.18666 -283.492462) (xy 133.237512 -283.490413) (xy 133.288033 -283.496547)
			(xy 133.336917 -283.510707) (xy 133.382896 -283.532524) (xy 133.42478 -283.561434) (xy 133.461484 -283.596689)
			(xy 133.492057 -283.637375) (xy 133.515708 -283.682438) (xy 133.531824 -283.730712) (xy 133.539988 -283.780946)
			(xy 133.5405 -283.806392) (xy 133.859028 -283.806392) (xy 133.862988 -283.757338) (xy 133.874765 -283.709554)
			(xy 133.894056 -283.664278) (xy 133.920359 -283.622682) (xy 133.952994 -283.585845) (xy 133.991115 -283.55472)
			(xy 134.033736 -283.530113) (xy 134.079752 -283.512661) (xy 134.127971 -283.502817) (xy 134.177146 -283.500836)
			(xy 134.226001 -283.506768) (xy 134.273272 -283.52046) (xy 134.317734 -283.541558) (xy 134.358237 -283.569514)
			(xy 134.39373 -283.603606) (xy 134.423295 -283.64295) (xy 134.446166 -283.686527) (xy 134.46175 -283.733208)
			(xy 134.469645 -283.781785) (xy 134.47014 -283.806392) (xy 134.798828 -283.806392) (xy 134.802788 -283.757338)
			(xy 134.814565 -283.709554) (xy 134.833856 -283.664278) (xy 134.860159 -283.622682) (xy 134.892794 -283.585845)
			(xy 134.930915 -283.55472) (xy 134.973536 -283.530113) (xy 135.019552 -283.512661) (xy 135.067771 -283.502817)
			(xy 135.116946 -283.500836) (xy 135.165801 -283.506768) (xy 135.213072 -283.52046) (xy 135.257534 -283.541558)
			(xy 135.298037 -283.569514) (xy 135.33353 -283.603606) (xy 135.363095 -283.64295) (xy 135.385966 -283.686527)
			(xy 135.40155 -283.733208) (xy 135.409445 -283.781785) (xy 135.40994 -283.806392) (xy 135.738882 -283.806392)
			(xy 135.742842 -283.757338) (xy 135.754619 -283.709554) (xy 135.77391 -283.664278) (xy 135.800213 -283.622682)
			(xy 135.832848 -283.585845) (xy 135.870969 -283.55472) (xy 135.91359 -283.530113) (xy 135.959606 -283.512661)
			(xy 136.007825 -283.502817) (xy 136.057 -283.500836) (xy 136.105855 -283.506768) (xy 136.153126 -283.52046)
			(xy 136.197588 -283.541558) (xy 136.238091 -283.569514) (xy 136.273584 -283.603606) (xy 136.303149 -283.64295)
			(xy 136.32602 -283.686527) (xy 136.341604 -283.733208) (xy 136.349499 -283.781785) (xy 136.349994 -283.806392)
			(xy 136.349499 -283.830999) (xy 136.341604 -283.879576) (xy 136.32602 -283.926257) (xy 136.303149 -283.969834)
			(xy 136.273584 -284.009178) (xy 136.238091 -284.04327) (xy 136.197588 -284.071226) (xy 136.153126 -284.092324)
			(xy 136.105855 -284.106016) (xy 136.057 -284.111948) (xy 136.007825 -284.109967) (xy 135.959606 -284.100123)
			(xy 135.91359 -284.082671) (xy 135.870969 -284.058064) (xy 135.832848 -284.026939) (xy 135.800213 -283.990102)
			(xy 135.77391 -283.948506) (xy 135.754619 -283.90323) (xy 135.742842 -283.855446) (xy 135.738882 -283.806392)
			(xy 135.40994 -283.806392) (xy 135.409445 -283.830999) (xy 135.40155 -283.879576) (xy 135.385966 -283.926257)
			(xy 135.363095 -283.969834) (xy 135.33353 -284.009178) (xy 135.298037 -284.04327) (xy 135.257534 -284.071226)
			(xy 135.213072 -284.092324) (xy 135.165801 -284.106016) (xy 135.116946 -284.111948) (xy 135.067771 -284.109967)
			(xy 135.019552 -284.100123) (xy 134.973536 -284.082671) (xy 134.930915 -284.058064) (xy 134.892794 -284.026939)
			(xy 134.860159 -283.990102) (xy 134.833856 -283.948506) (xy 134.814565 -283.90323) (xy 134.802788 -283.855446)
			(xy 134.798828 -283.806392) (xy 134.47014 -283.806392) (xy 134.469645 -283.830999) (xy 134.46175 -283.879576)
			(xy 134.446166 -283.926257) (xy 134.423295 -283.969834) (xy 134.39373 -284.009178) (xy 134.358237 -284.04327)
			(xy 134.317734 -284.071226) (xy 134.273272 -284.092324) (xy 134.226001 -284.106016) (xy 134.177146 -284.111948)
			(xy 134.127971 -284.109967) (xy 134.079752 -284.100123) (xy 134.033736 -284.082671) (xy 133.991115 -284.058064)
			(xy 133.952994 -284.026939) (xy 133.920359 -283.990102) (xy 133.894056 -283.948506) (xy 133.874765 -283.90323)
			(xy 133.862988 -283.855446) (xy 133.859028 -283.806392) (xy 133.5405 -283.806392) (xy 133.539988 -283.831838)
			(xy 133.531824 -283.882072) (xy 133.515708 -283.930346) (xy 133.492057 -283.975409) (xy 133.461484 -284.016095)
			(xy 133.42478 -284.05135) (xy 133.382896 -284.08026) (xy 133.336917 -284.102077) (xy 133.288033 -284.116237)
			(xy 133.237512 -284.122371) (xy 133.18666 -284.120322) (xy 133.136796 -284.110142) (xy 133.08921 -284.092095)
			(xy 133.045136 -284.066649) (xy 133.005714 -284.034462) (xy 132.971966 -283.996368) (xy 132.944765 -283.953354)
			(xy 132.924817 -283.906534) (xy 132.912638 -283.85712) (xy 132.908543 -283.806392) (xy 132.590032 -283.806392)
			(xy 132.589537 -283.830999) (xy 132.581642 -283.879576) (xy 132.566058 -283.926257) (xy 132.543187 -283.969834)
			(xy 132.513622 -284.009178) (xy 132.478129 -284.04327) (xy 132.437626 -284.071226) (xy 132.393164 -284.092324)
			(xy 132.345893 -284.106016) (xy 132.297038 -284.111948) (xy 132.247863 -284.109967) (xy 132.199644 -284.100123)
			(xy 132.153628 -284.082671) (xy 132.111007 -284.058064) (xy 132.072886 -284.026939) (xy 132.040251 -283.990102)
			(xy 132.013948 -283.948506) (xy 131.994657 -283.90323) (xy 131.98288 -283.855446) (xy 131.97892 -283.806392)
			(xy 131.660392 -283.806392) (xy 131.65988 -283.831838) (xy 131.651716 -283.882072) (xy 131.6356 -283.930346)
			(xy 131.611949 -283.975409) (xy 131.581376 -284.016095) (xy 131.544672 -284.05135) (xy 131.502788 -284.08026)
			(xy 131.456809 -284.102077) (xy 131.407925 -284.116237) (xy 131.357404 -284.122371) (xy 131.306552 -284.120322)
			(xy 131.256688 -284.110142) (xy 131.209102 -284.092095) (xy 131.165028 -284.066649) (xy 131.125606 -284.034462)
			(xy 131.091858 -283.996368) (xy 131.064657 -283.953354) (xy 131.044709 -283.906534) (xy 131.03253 -283.85712)
			(xy 131.028435 -283.806392) (xy 130.710178 -283.806392) (xy 130.709683 -283.830999) (xy 130.701788 -283.879576)
			(xy 130.686204 -283.926257) (xy 130.663333 -283.969834) (xy 130.633768 -284.009178) (xy 130.598275 -284.04327)
			(xy 130.557772 -284.071226) (xy 130.51331 -284.092324) (xy 130.466039 -284.106016) (xy 130.417184 -284.111948)
			(xy 130.368009 -284.109967) (xy 130.31979 -284.100123) (xy 130.273774 -284.082671) (xy 130.231153 -284.058064)
			(xy 130.193032 -284.026939) (xy 130.160397 -283.990102) (xy 130.134094 -283.948506) (xy 130.114803 -283.90323)
			(xy 130.103026 -283.855446) (xy 130.099066 -283.806392) (xy 129.780538 -283.806392) (xy 129.780026 -283.831838)
			(xy 129.771862 -283.882072) (xy 129.755746 -283.930346) (xy 129.732095 -283.975409) (xy 129.701522 -284.016095)
			(xy 129.664818 -284.05135) (xy 129.622934 -284.08026) (xy 129.576955 -284.102077) (xy 129.528071 -284.116237)
			(xy 129.47755 -284.122371) (xy 129.426698 -284.120322) (xy 129.376834 -284.110142) (xy 129.329248 -284.092095)
			(xy 129.285174 -284.066649) (xy 129.245752 -284.034462) (xy 129.212004 -283.996368) (xy 129.184803 -283.953354)
			(xy 129.164855 -283.906534) (xy 129.152676 -283.85712) (xy 129.148581 -283.806392) (xy 128.840484 -283.806392)
			(xy 128.839972 -283.831838) (xy 128.831808 -283.882072) (xy 128.815692 -283.930346) (xy 128.792041 -283.975409)
			(xy 128.761468 -284.016095) (xy 128.724764 -284.05135) (xy 128.68288 -284.08026) (xy 128.636901 -284.102077)
			(xy 128.588017 -284.116237) (xy 128.537496 -284.122371) (xy 128.486644 -284.120322) (xy 128.43678 -284.110142)
			(xy 128.389194 -284.092095) (xy 128.34512 -284.066649) (xy 128.305698 -284.034462) (xy 128.27195 -283.996368)
			(xy 128.244749 -283.953354) (xy 128.224801 -283.906534) (xy 128.212622 -283.85712) (xy 128.208527 -283.806392)
			(xy 127.890016 -283.806392) (xy 127.889576 -283.829732) (xy 127.88248 -283.875871) (xy 127.868453 -283.920394)
			(xy 127.85852 -283.94152) (xy 127.856742 -283.945076) (xy 127.845112 -283.966856) (xy 127.815898 -284.006658)
			(xy 127.780642 -284.041221) (xy 127.76073 -284.05582) (xy 127.753552 -284.061298) (xy 127.743282 -284.076134)
			(xy 127.740664 -284.084776) (xy 127.728997 -284.128882) (xy 127.699478 -284.215217) (xy 127.663094 -284.298891)
			(xy 127.620084 -284.37936) (xy 127.570726 -284.456099) (xy 127.515342 -284.528609) (xy 127.48514 -284.562804)
			(xy 127.47879 -284.569916) (xy 127.472186 -284.587188) (xy 127.472186 -284.616398) (xy 127.738627 -284.616398)
			(xy 127.742722 -284.56567) (xy 127.754901 -284.516256) (xy 127.774849 -284.469436) (xy 127.80205 -284.426422)
			(xy 127.835798 -284.388328) (xy 127.87522 -284.356141) (xy 127.919294 -284.330695) (xy 127.96688 -284.312648)
			(xy 128.016744 -284.302468) (xy 128.067596 -284.300419) (xy 128.118117 -284.306553) (xy 128.167001 -284.320713)
			(xy 128.21298 -284.34253) (xy 128.254864 -284.37144) (xy 128.291568 -284.406695) (xy 128.322141 -284.447381)
			(xy 128.345792 -284.492444) (xy 128.361908 -284.540718) (xy 128.370072 -284.590952) (xy 128.370584 -284.616398)
			(xy 128.688858 -284.616398) (xy 128.692818 -284.567344) (xy 128.704595 -284.51956) (xy 128.723886 -284.474284)
			(xy 128.750189 -284.432688) (xy 128.782824 -284.395851) (xy 128.820945 -284.364726) (xy 128.863566 -284.340119)
			(xy 128.909582 -284.322667) (xy 128.957801 -284.312823) (xy 129.006976 -284.310842) (xy 129.055831 -284.316774)
			(xy 129.103102 -284.330466) (xy 129.147564 -284.351564) (xy 129.188067 -284.37952) (xy 129.22356 -284.413612)
			(xy 129.253125 -284.452956) (xy 129.275996 -284.496533) (xy 129.29158 -284.543214) (xy 129.299475 -284.591791)
			(xy 129.29997 -284.616398) (xy 129.618481 -284.616398) (xy 129.622576 -284.56567) (xy 129.634755 -284.516256)
			(xy 129.654703 -284.469436) (xy 129.681904 -284.426422) (xy 129.715652 -284.388328) (xy 129.755074 -284.356141)
			(xy 129.799148 -284.330695) (xy 129.846734 -284.312648) (xy 129.896598 -284.302468) (xy 129.94745 -284.300419)
			(xy 129.997971 -284.306553) (xy 130.046855 -284.320713) (xy 130.092834 -284.34253) (xy 130.134718 -284.37144)
			(xy 130.171422 -284.406695) (xy 130.201995 -284.447381) (xy 130.225646 -284.492444) (xy 130.241762 -284.540718)
			(xy 130.249926 -284.590952) (xy 130.250438 -284.616398) (xy 130.568966 -284.616398) (xy 130.572926 -284.567344)
			(xy 130.584703 -284.51956) (xy 130.603994 -284.474284) (xy 130.630297 -284.432688) (xy 130.662932 -284.395851)
			(xy 130.701053 -284.364726) (xy 130.743674 -284.340119) (xy 130.78969 -284.322667) (xy 130.837909 -284.312823)
			(xy 130.887084 -284.310842) (xy 130.935939 -284.316774) (xy 130.98321 -284.330466) (xy 131.027672 -284.351564)
			(xy 131.068175 -284.37952) (xy 131.103668 -284.413612) (xy 131.133233 -284.452956) (xy 131.156104 -284.496533)
			(xy 131.171688 -284.543214) (xy 131.179583 -284.591791) (xy 131.180078 -284.616398) (xy 131.498589 -284.616398)
			(xy 131.502684 -284.56567) (xy 131.514863 -284.516256) (xy 131.534811 -284.469436) (xy 131.562012 -284.426422)
			(xy 131.59576 -284.388328) (xy 131.635182 -284.356141) (xy 131.679256 -284.330695) (xy 131.726842 -284.312648)
			(xy 131.776706 -284.302468) (xy 131.827558 -284.300419) (xy 131.878079 -284.306553) (xy 131.926963 -284.320713)
			(xy 131.972942 -284.34253) (xy 132.014826 -284.37144) (xy 132.05153 -284.406695) (xy 132.082103 -284.447381)
			(xy 132.105754 -284.492444) (xy 132.12187 -284.540718) (xy 132.130034 -284.590952) (xy 132.130546 -284.616398)
			(xy 132.438643 -284.616398) (xy 132.442738 -284.56567) (xy 132.454917 -284.516256) (xy 132.474865 -284.469436)
			(xy 132.502066 -284.426422) (xy 132.535814 -284.388328) (xy 132.575236 -284.356141) (xy 132.61931 -284.330695)
			(xy 132.666896 -284.312648) (xy 132.71676 -284.302468) (xy 132.767612 -284.300419) (xy 132.818133 -284.306553)
			(xy 132.867017 -284.320713) (xy 132.912996 -284.34253) (xy 132.95488 -284.37144) (xy 132.991584 -284.406695)
			(xy 133.022157 -284.447381) (xy 133.045808 -284.492444) (xy 133.061924 -284.540718) (xy 133.070088 -284.590952)
			(xy 133.0706 -284.616398) (xy 133.388874 -284.616398) (xy 133.392834 -284.567344) (xy 133.404611 -284.51956)
			(xy 133.423902 -284.474284) (xy 133.450205 -284.432688) (xy 133.48284 -284.395851) (xy 133.520961 -284.364726)
			(xy 133.563582 -284.340119) (xy 133.609598 -284.322667) (xy 133.657817 -284.312823) (xy 133.706992 -284.310842)
			(xy 133.755847 -284.316774) (xy 133.803118 -284.330466) (xy 133.84758 -284.351564) (xy 133.888083 -284.37952)
			(xy 133.923576 -284.413612) (xy 133.953141 -284.452956) (xy 133.976012 -284.496533) (xy 133.991596 -284.543214)
			(xy 133.999491 -284.591791) (xy 133.999986 -284.616398) (xy 134.328928 -284.616398) (xy 134.332888 -284.567344)
			(xy 134.344665 -284.51956) (xy 134.363956 -284.474284) (xy 134.390259 -284.432688) (xy 134.422894 -284.395851)
			(xy 134.461015 -284.364726) (xy 134.503636 -284.340119) (xy 134.549652 -284.322667) (xy 134.597871 -284.312823)
			(xy 134.647046 -284.310842) (xy 134.695901 -284.316774) (xy 134.743172 -284.330466) (xy 134.787634 -284.351564)
			(xy 134.828137 -284.37952) (xy 134.86363 -284.413612) (xy 134.893195 -284.452956) (xy 134.916066 -284.496533)
			(xy 134.93165 -284.543214) (xy 134.939545 -284.591791) (xy 134.94004 -284.616398) (xy 135.268982 -284.616398)
			(xy 135.272942 -284.567344) (xy 135.284719 -284.51956) (xy 135.30401 -284.474284) (xy 135.330313 -284.432688)
			(xy 135.362948 -284.395851) (xy 135.401069 -284.364726) (xy 135.44369 -284.340119) (xy 135.489706 -284.322667)
			(xy 135.537925 -284.312823) (xy 135.5871 -284.310842) (xy 135.635955 -284.316774) (xy 135.683226 -284.330466)
			(xy 135.727688 -284.351564) (xy 135.768191 -284.37952) (xy 135.803684 -284.413612) (xy 135.833249 -284.452956)
			(xy 135.85612 -284.496533) (xy 135.871704 -284.543214) (xy 135.879599 -284.591791) (xy 135.880094 -284.616398)
			(xy 136.209036 -284.616398) (xy 136.212996 -284.567344) (xy 136.224773 -284.51956) (xy 136.244064 -284.474284)
			(xy 136.270367 -284.432688) (xy 136.303002 -284.395851) (xy 136.341123 -284.364726) (xy 136.383744 -284.340119)
			(xy 136.42976 -284.322667) (xy 136.477979 -284.312823) (xy 136.527154 -284.310842) (xy 136.576009 -284.316774)
			(xy 136.62328 -284.330466) (xy 136.667742 -284.351564) (xy 136.708245 -284.37952) (xy 136.743738 -284.413612)
			(xy 136.773303 -284.452956) (xy 136.796174 -284.496533) (xy 136.811758 -284.543214) (xy 136.819653 -284.591791)
			(xy 136.820148 -284.616398) (xy 136.819653 -284.641005) (xy 136.811758 -284.689582) (xy 136.796174 -284.736263)
			(xy 136.773303 -284.77984) (xy 136.743738 -284.819184) (xy 136.708245 -284.853276) (xy 136.667742 -284.881232)
			(xy 136.62328 -284.90233) (xy 136.576009 -284.916022) (xy 136.527154 -284.921954) (xy 136.477979 -284.919973)
			(xy 136.42976 -284.910129) (xy 136.383744 -284.892677) (xy 136.341123 -284.86807) (xy 136.303002 -284.836945)
			(xy 136.270367 -284.800108) (xy 136.244064 -284.758512) (xy 136.224773 -284.713236) (xy 136.212996 -284.665452)
			(xy 136.209036 -284.616398) (xy 135.880094 -284.616398) (xy 135.879599 -284.641005) (xy 135.871704 -284.689582)
			(xy 135.85612 -284.736263) (xy 135.833249 -284.77984) (xy 135.803684 -284.819184) (xy 135.768191 -284.853276)
			(xy 135.727688 -284.881232) (xy 135.683226 -284.90233) (xy 135.635955 -284.916022) (xy 135.5871 -284.921954)
			(xy 135.537925 -284.919973) (xy 135.489706 -284.910129) (xy 135.44369 -284.892677) (xy 135.401069 -284.86807)
			(xy 135.362948 -284.836945) (xy 135.330313 -284.800108) (xy 135.30401 -284.758512) (xy 135.284719 -284.713236)
			(xy 135.272942 -284.665452) (xy 135.268982 -284.616398) (xy 134.94004 -284.616398) (xy 134.939545 -284.641005)
			(xy 134.93165 -284.689582) (xy 134.916066 -284.736263) (xy 134.893195 -284.77984) (xy 134.86363 -284.819184)
			(xy 134.828137 -284.853276) (xy 134.787634 -284.881232) (xy 134.743172 -284.90233) (xy 134.695901 -284.916022)
			(xy 134.647046 -284.921954) (xy 134.597871 -284.919973) (xy 134.549652 -284.910129) (xy 134.503636 -284.892677)
			(xy 134.461015 -284.86807) (xy 134.422894 -284.836945) (xy 134.390259 -284.800108) (xy 134.363956 -284.758512)
			(xy 134.344665 -284.713236) (xy 134.332888 -284.665452) (xy 134.328928 -284.616398) (xy 133.999986 -284.616398)
			(xy 133.999491 -284.641005) (xy 133.991596 -284.689582) (xy 133.976012 -284.736263) (xy 133.953141 -284.77984)
			(xy 133.923576 -284.819184) (xy 133.888083 -284.853276) (xy 133.84758 -284.881232) (xy 133.803118 -284.90233)
			(xy 133.755847 -284.916022) (xy 133.706992 -284.921954) (xy 133.657817 -284.919973) (xy 133.609598 -284.910129)
			(xy 133.563582 -284.892677) (xy 133.520961 -284.86807) (xy 133.48284 -284.836945) (xy 133.450205 -284.800108)
			(xy 133.423902 -284.758512) (xy 133.404611 -284.713236) (xy 133.392834 -284.665452) (xy 133.388874 -284.616398)
			(xy 133.0706 -284.616398) (xy 133.070088 -284.641844) (xy 133.061924 -284.692078) (xy 133.045808 -284.740352)
			(xy 133.022157 -284.785415) (xy 132.991584 -284.826101) (xy 132.95488 -284.861356) (xy 132.912996 -284.890266)
			(xy 132.867017 -284.912083) (xy 132.818133 -284.926243) (xy 132.767612 -284.932377) (xy 132.71676 -284.930328)
			(xy 132.666896 -284.920148) (xy 132.61931 -284.902101) (xy 132.575236 -284.876655) (xy 132.535814 -284.844468)
			(xy 132.502066 -284.806374) (xy 132.474865 -284.76336) (xy 132.454917 -284.71654) (xy 132.442738 -284.667126)
			(xy 132.438643 -284.616398) (xy 132.130546 -284.616398) (xy 132.130034 -284.641844) (xy 132.12187 -284.692078)
			(xy 132.105754 -284.740352) (xy 132.082103 -284.785415) (xy 132.05153 -284.826101) (xy 132.014826 -284.861356)
			(xy 131.972942 -284.890266) (xy 131.926963 -284.912083) (xy 131.878079 -284.926243) (xy 131.827558 -284.932377)
			(xy 131.776706 -284.930328) (xy 131.726842 -284.920148) (xy 131.679256 -284.902101) (xy 131.635182 -284.876655)
			(xy 131.59576 -284.844468) (xy 131.562012 -284.806374) (xy 131.534811 -284.76336) (xy 131.514863 -284.71654)
			(xy 131.502684 -284.667126) (xy 131.498589 -284.616398) (xy 131.180078 -284.616398) (xy 131.179583 -284.641005)
			(xy 131.171688 -284.689582) (xy 131.156104 -284.736263) (xy 131.133233 -284.77984) (xy 131.103668 -284.819184)
			(xy 131.068175 -284.853276) (xy 131.027672 -284.881232) (xy 130.98321 -284.90233) (xy 130.935939 -284.916022)
			(xy 130.887084 -284.921954) (xy 130.837909 -284.919973) (xy 130.78969 -284.910129) (xy 130.743674 -284.892677)
			(xy 130.701053 -284.86807) (xy 130.662932 -284.836945) (xy 130.630297 -284.800108) (xy 130.603994 -284.758512)
			(xy 130.584703 -284.713236) (xy 130.572926 -284.665452) (xy 130.568966 -284.616398) (xy 130.250438 -284.616398)
			(xy 130.249926 -284.641844) (xy 130.241762 -284.692078) (xy 130.225646 -284.740352) (xy 130.201995 -284.785415)
			(xy 130.171422 -284.826101) (xy 130.134718 -284.861356) (xy 130.092834 -284.890266) (xy 130.046855 -284.912083)
			(xy 129.997971 -284.926243) (xy 129.94745 -284.932377) (xy 129.896598 -284.930328) (xy 129.846734 -284.920148)
			(xy 129.799148 -284.902101) (xy 129.755074 -284.876655) (xy 129.715652 -284.844468) (xy 129.681904 -284.806374)
			(xy 129.654703 -284.76336) (xy 129.634755 -284.71654) (xy 129.622576 -284.667126) (xy 129.618481 -284.616398)
			(xy 129.29997 -284.616398) (xy 129.299475 -284.641005) (xy 129.29158 -284.689582) (xy 129.275996 -284.736263)
			(xy 129.253125 -284.77984) (xy 129.22356 -284.819184) (xy 129.188067 -284.853276) (xy 129.147564 -284.881232)
			(xy 129.103102 -284.90233) (xy 129.055831 -284.916022) (xy 129.006976 -284.921954) (xy 128.957801 -284.919973)
			(xy 128.909582 -284.910129) (xy 128.863566 -284.892677) (xy 128.820945 -284.86807) (xy 128.782824 -284.836945)
			(xy 128.750189 -284.800108) (xy 128.723886 -284.758512) (xy 128.704595 -284.713236) (xy 128.692818 -284.665452)
			(xy 128.688858 -284.616398) (xy 128.370584 -284.616398) (xy 128.370072 -284.641844) (xy 128.361908 -284.692078)
			(xy 128.345792 -284.740352) (xy 128.322141 -284.785415) (xy 128.291568 -284.826101) (xy 128.254864 -284.861356)
			(xy 128.21298 -284.890266) (xy 128.167001 -284.912083) (xy 128.118117 -284.926243) (xy 128.067596 -284.932377)
			(xy 128.016744 -284.930328) (xy 127.96688 -284.920148) (xy 127.919294 -284.902101) (xy 127.87522 -284.876655)
			(xy 127.835798 -284.844468) (xy 127.80205 -284.806374) (xy 127.774849 -284.76336) (xy 127.754901 -284.71654)
			(xy 127.742722 -284.667126) (xy 127.738627 -284.616398) (xy 127.472186 -284.616398) (xy 127.472186 -284.645608)
			(xy 127.47879 -284.66288) (xy 127.48514 -284.669992) (xy 127.518916 -284.708337) (xy 127.580183 -284.790128)
			(xy 127.633822 -284.877111) (xy 127.679398 -284.968578) (xy 127.716537 -285.063783) (xy 127.731266 -285.112714)
			(xy 127.734331 -285.121852) (xy 127.74609 -285.137107) (xy 127.754126 -285.142432) (xy 127.776441 -285.156336)
			(xy 127.816758 -285.190078) (xy 127.851229 -285.229775) (xy 127.878984 -285.274426) (xy 127.899324 -285.322906)
			(xy 127.911736 -285.373994) (xy 127.915909 -285.426402) (xy 127.915909 -285.426404) (xy 128.208527 -285.426404)
			(xy 128.212622 -285.375676) (xy 128.224801 -285.326262) (xy 128.244749 -285.279442) (xy 128.27195 -285.236428)
			(xy 128.305698 -285.198334) (xy 128.34512 -285.166147) (xy 128.389194 -285.140701) (xy 128.43678 -285.122654)
			(xy 128.486644 -285.112474) (xy 128.537496 -285.110425) (xy 128.588017 -285.116559) (xy 128.636901 -285.130719)
			(xy 128.68288 -285.152536) (xy 128.724764 -285.181446) (xy 128.761468 -285.216701) (xy 128.792041 -285.257387)
			(xy 128.815692 -285.30245) (xy 128.831808 -285.350724) (xy 128.839972 -285.400958) (xy 128.840484 -285.426404)
			(xy 129.148581 -285.426404) (xy 129.152676 -285.375676) (xy 129.164855 -285.326262) (xy 129.184803 -285.279442)
			(xy 129.212004 -285.236428) (xy 129.245752 -285.198334) (xy 129.285174 -285.166147) (xy 129.329248 -285.140701)
			(xy 129.376834 -285.122654) (xy 129.426698 -285.112474) (xy 129.47755 -285.110425) (xy 129.528071 -285.116559)
			(xy 129.576955 -285.130719) (xy 129.622934 -285.152536) (xy 129.664818 -285.181446) (xy 129.701522 -285.216701)
			(xy 129.732095 -285.257387) (xy 129.755746 -285.30245) (xy 129.771862 -285.350724) (xy 129.780026 -285.400958)
			(xy 129.780538 -285.426404) (xy 131.028435 -285.426404) (xy 131.03253 -285.375676) (xy 131.044709 -285.326262)
			(xy 131.064657 -285.279442) (xy 131.091858 -285.236428) (xy 131.125606 -285.198334) (xy 131.165028 -285.166147)
			(xy 131.209102 -285.140701) (xy 131.256688 -285.122654) (xy 131.306552 -285.112474) (xy 131.357404 -285.110425)
			(xy 131.407925 -285.116559) (xy 131.456809 -285.130719) (xy 131.502788 -285.152536) (xy 131.544672 -285.181446)
			(xy 131.581376 -285.216701) (xy 131.611949 -285.257387) (xy 131.6356 -285.30245) (xy 131.651716 -285.350724)
			(xy 131.65988 -285.400958) (xy 131.660392 -285.426404) (xy 131.97892 -285.426404) (xy 131.98288 -285.37735)
			(xy 131.994657 -285.329566) (xy 132.013948 -285.28429) (xy 132.040251 -285.242694) (xy 132.072886 -285.205857)
			(xy 132.111007 -285.174732) (xy 132.153628 -285.150125) (xy 132.199644 -285.132673) (xy 132.247863 -285.122829)
			(xy 132.297038 -285.120848) (xy 132.345893 -285.12678) (xy 132.393164 -285.140472) (xy 132.437626 -285.16157)
			(xy 132.478129 -285.189526) (xy 132.513622 -285.223618) (xy 132.543187 -285.262962) (xy 132.566058 -285.306539)
			(xy 132.581642 -285.35322) (xy 132.589537 -285.401797) (xy 132.590032 -285.426404) (xy 132.908543 -285.426404)
			(xy 132.912638 -285.375676) (xy 132.924817 -285.326262) (xy 132.944765 -285.279442) (xy 132.971966 -285.236428)
			(xy 133.005714 -285.198334) (xy 133.045136 -285.166147) (xy 133.08921 -285.140701) (xy 133.136796 -285.122654)
			(xy 133.18666 -285.112474) (xy 133.237512 -285.110425) (xy 133.288033 -285.116559) (xy 133.336917 -285.130719)
			(xy 133.382896 -285.152536) (xy 133.42478 -285.181446) (xy 133.461484 -285.216701) (xy 133.492057 -285.257387)
			(xy 133.515708 -285.30245) (xy 133.531824 -285.350724) (xy 133.539988 -285.400958) (xy 133.5405 -285.426404)
			(xy 133.859028 -285.426404) (xy 133.862988 -285.37735) (xy 133.874765 -285.329566) (xy 133.894056 -285.28429)
			(xy 133.920359 -285.242694) (xy 133.952994 -285.205857) (xy 133.991115 -285.174732) (xy 134.033736 -285.150125)
			(xy 134.079752 -285.132673) (xy 134.127971 -285.122829) (xy 134.177146 -285.120848) (xy 134.226001 -285.12678)
			(xy 134.273272 -285.140472) (xy 134.317734 -285.16157) (xy 134.358237 -285.189526) (xy 134.39373 -285.223618)
			(xy 134.423295 -285.262962) (xy 134.446166 -285.306539) (xy 134.46175 -285.35322) (xy 134.469645 -285.401797)
			(xy 134.47014 -285.426404) (xy 134.798828 -285.426404) (xy 134.802788 -285.37735) (xy 134.814565 -285.329566)
			(xy 134.833856 -285.28429) (xy 134.860159 -285.242694) (xy 134.892794 -285.205857) (xy 134.930915 -285.174732)
			(xy 134.973536 -285.150125) (xy 135.019552 -285.132673) (xy 135.067771 -285.122829) (xy 135.116946 -285.120848)
			(xy 135.165801 -285.12678) (xy 135.213072 -285.140472) (xy 135.257534 -285.16157) (xy 135.298037 -285.189526)
			(xy 135.33353 -285.223618) (xy 135.363095 -285.262962) (xy 135.385966 -285.306539) (xy 135.40155 -285.35322)
			(xy 135.409445 -285.401797) (xy 135.40994 -285.426404) (xy 135.738882 -285.426404) (xy 135.742842 -285.37735)
			(xy 135.754619 -285.329566) (xy 135.77391 -285.28429) (xy 135.800213 -285.242694) (xy 135.832848 -285.205857)
			(xy 135.870969 -285.174732) (xy 135.91359 -285.150125) (xy 135.959606 -285.132673) (xy 136.007825 -285.122829)
			(xy 136.057 -285.120848) (xy 136.105855 -285.12678) (xy 136.153126 -285.140472) (xy 136.197588 -285.16157)
			(xy 136.238091 -285.189526) (xy 136.273584 -285.223618) (xy 136.303149 -285.262962) (xy 136.32602 -285.306539)
			(xy 136.341604 -285.35322) (xy 136.349499 -285.401797) (xy 136.349994 -285.426404) (xy 136.349499 -285.451011)
			(xy 136.341604 -285.499588) (xy 136.32602 -285.546269) (xy 136.303149 -285.589846) (xy 136.273584 -285.62919)
			(xy 136.238091 -285.663282) (xy 136.197588 -285.691238) (xy 136.153126 -285.712336) (xy 136.105855 -285.726028)
			(xy 136.057 -285.73196) (xy 136.007825 -285.729979) (xy 135.959606 -285.720135) (xy 135.91359 -285.702683)
			(xy 135.870969 -285.678076) (xy 135.832848 -285.646951) (xy 135.800213 -285.610114) (xy 135.77391 -285.568518)
			(xy 135.754619 -285.523242) (xy 135.742842 -285.475458) (xy 135.738882 -285.426404) (xy 135.40994 -285.426404)
			(xy 135.409445 -285.451011) (xy 135.40155 -285.499588) (xy 135.385966 -285.546269) (xy 135.363095 -285.589846)
			(xy 135.33353 -285.62919) (xy 135.298037 -285.663282) (xy 135.257534 -285.691238) (xy 135.213072 -285.712336)
			(xy 135.165801 -285.726028) (xy 135.116946 -285.73196) (xy 135.067771 -285.729979) (xy 135.019552 -285.720135)
			(xy 134.973536 -285.702683) (xy 134.930915 -285.678076) (xy 134.892794 -285.646951) (xy 134.860159 -285.610114)
			(xy 134.833856 -285.568518) (xy 134.814565 -285.523242) (xy 134.802788 -285.475458) (xy 134.798828 -285.426404)
			(xy 134.47014 -285.426404) (xy 134.469645 -285.451011) (xy 134.46175 -285.499588) (xy 134.446166 -285.546269)
			(xy 134.423295 -285.589846) (xy 134.39373 -285.62919) (xy 134.358237 -285.663282) (xy 134.317734 -285.691238)
			(xy 134.273272 -285.712336) (xy 134.226001 -285.726028) (xy 134.177146 -285.73196) (xy 134.127971 -285.729979)
			(xy 134.079752 -285.720135) (xy 134.033736 -285.702683) (xy 133.991115 -285.678076) (xy 133.952994 -285.646951)
			(xy 133.920359 -285.610114) (xy 133.894056 -285.568518) (xy 133.874765 -285.523242) (xy 133.862988 -285.475458)
			(xy 133.859028 -285.426404) (xy 133.5405 -285.426404) (xy 133.539988 -285.45185) (xy 133.531824 -285.502084)
			(xy 133.515708 -285.550358) (xy 133.492057 -285.595421) (xy 133.461484 -285.636107) (xy 133.42478 -285.671362)
			(xy 133.382896 -285.700272) (xy 133.336917 -285.722089) (xy 133.288033 -285.736249) (xy 133.237512 -285.742383)
			(xy 133.18666 -285.740334) (xy 133.136796 -285.730154) (xy 133.08921 -285.712107) (xy 133.045136 -285.686661)
			(xy 133.005714 -285.654474) (xy 132.971966 -285.61638) (xy 132.944765 -285.573366) (xy 132.924817 -285.526546)
			(xy 132.912638 -285.477132) (xy 132.908543 -285.426404) (xy 132.590032 -285.426404) (xy 132.589537 -285.451011)
			(xy 132.581642 -285.499588) (xy 132.566058 -285.546269) (xy 132.543187 -285.589846) (xy 132.513622 -285.62919)
			(xy 132.478129 -285.663282) (xy 132.437626 -285.691238) (xy 132.393164 -285.712336) (xy 132.345893 -285.726028)
			(xy 132.297038 -285.73196) (xy 132.247863 -285.729979) (xy 132.199644 -285.720135) (xy 132.153628 -285.702683)
			(xy 132.111007 -285.678076) (xy 132.072886 -285.646951) (xy 132.040251 -285.610114) (xy 132.013948 -285.568518)
			(xy 131.994657 -285.523242) (xy 131.98288 -285.475458) (xy 131.97892 -285.426404) (xy 131.660392 -285.426404)
			(xy 131.65988 -285.45185) (xy 131.651716 -285.502084) (xy 131.6356 -285.550358) (xy 131.611949 -285.595421)
			(xy 131.581376 -285.636107) (xy 131.544672 -285.671362) (xy 131.502788 -285.700272) (xy 131.456809 -285.722089)
			(xy 131.407925 -285.736249) (xy 131.357404 -285.742383) (xy 131.306552 -285.740334) (xy 131.256688 -285.730154)
			(xy 131.209102 -285.712107) (xy 131.165028 -285.686661) (xy 131.125606 -285.654474) (xy 131.091858 -285.61638)
			(xy 131.064657 -285.573366) (xy 131.044709 -285.526546) (xy 131.03253 -285.477132) (xy 131.028435 -285.426404)
			(xy 129.780538 -285.426404) (xy 129.780026 -285.45185) (xy 129.771862 -285.502084) (xy 129.755746 -285.550358)
			(xy 129.732095 -285.595421) (xy 129.701522 -285.636107) (xy 129.664818 -285.671362) (xy 129.622934 -285.700272)
			(xy 129.576955 -285.722089) (xy 129.528071 -285.736249) (xy 129.47755 -285.742383) (xy 129.426698 -285.740334)
			(xy 129.376834 -285.730154) (xy 129.329248 -285.712107) (xy 129.285174 -285.686661) (xy 129.245752 -285.654474)
			(xy 129.212004 -285.61638) (xy 129.184803 -285.573366) (xy 129.164855 -285.526546) (xy 129.152676 -285.477132)
			(xy 129.148581 -285.426404) (xy 128.840484 -285.426404) (xy 128.839972 -285.45185) (xy 128.831808 -285.502084)
			(xy 128.815692 -285.550358) (xy 128.792041 -285.595421) (xy 128.761468 -285.636107) (xy 128.724764 -285.671362)
			(xy 128.68288 -285.700272) (xy 128.636901 -285.722089) (xy 128.588017 -285.736249) (xy 128.537496 -285.742383)
			(xy 128.486644 -285.740334) (xy 128.43678 -285.730154) (xy 128.389194 -285.712107) (xy 128.34512 -285.686661)
			(xy 128.305698 -285.654474) (xy 128.27195 -285.61638) (xy 128.244749 -285.573366) (xy 128.224801 -285.526546)
			(xy 128.212622 -285.477132) (xy 128.208527 -285.426404) (xy 127.915909 -285.426404) (xy 127.911736 -285.47881)
			(xy 127.899322 -285.529898) (xy 127.878982 -285.578378) (xy 127.851226 -285.623029) (xy 127.816755 -285.662725)
			(xy 127.776437 -285.696466) (xy 127.754126 -285.710376) (xy 127.746043 -285.715647) (xy 127.734287 -285.730929)
			(xy 127.731266 -285.740094) (xy 127.716533 -285.789024) (xy 127.67941 -285.884237) (xy 127.633841 -285.975708)
			(xy 127.580198 -286.06269) (xy 127.518919 -286.144473) (xy 127.48514 -286.182816) (xy 127.47879 -286.189928)
			(xy 127.472186 -286.2072) (xy 127.472186 -286.23641) (xy 127.738627 -286.23641) (xy 127.742722 -286.185682)
			(xy 127.754901 -286.136268) (xy 127.774849 -286.089448) (xy 127.80205 -286.046434) (xy 127.835798 -286.00834)
			(xy 127.87522 -285.976153) (xy 127.919294 -285.950707) (xy 127.96688 -285.93266) (xy 128.016744 -285.92248)
			(xy 128.067596 -285.920431) (xy 128.118117 -285.926565) (xy 128.167001 -285.940725) (xy 128.21298 -285.962542)
			(xy 128.254864 -285.991452) (xy 128.291568 -286.026707) (xy 128.322141 -286.067393) (xy 128.345792 -286.112456)
			(xy 128.361908 -286.16073) (xy 128.370072 -286.210964) (xy 128.370584 -286.23641) (xy 128.688858 -286.23641)
			(xy 128.692818 -286.187356) (xy 128.704595 -286.139572) (xy 128.723886 -286.094296) (xy 128.750189 -286.0527)
			(xy 128.782824 -286.015863) (xy 128.820945 -285.984738) (xy 128.863566 -285.960131) (xy 128.909582 -285.942679)
			(xy 128.957801 -285.932835) (xy 129.006976 -285.930854) (xy 129.055831 -285.936786) (xy 129.103102 -285.950478)
			(xy 129.147564 -285.971576) (xy 129.188067 -285.999532) (xy 129.22356 -286.033624) (xy 129.253125 -286.072968)
			(xy 129.275996 -286.116545) (xy 129.29158 -286.163226) (xy 129.299475 -286.211803) (xy 129.29997 -286.23641)
			(xy 129.618481 -286.23641) (xy 129.622576 -286.185682) (xy 129.634755 -286.136268) (xy 129.654703 -286.089448)
			(xy 129.681904 -286.046434) (xy 129.715652 -286.00834) (xy 129.755074 -285.976153) (xy 129.799148 -285.950707)
			(xy 129.846734 -285.93266) (xy 129.896598 -285.92248) (xy 129.94745 -285.920431) (xy 129.997971 -285.926565)
			(xy 130.046855 -285.940725) (xy 130.092834 -285.962542) (xy 130.134718 -285.991452) (xy 130.171422 -286.026707)
			(xy 130.201995 -286.067393) (xy 130.225646 -286.112456) (xy 130.241762 -286.16073) (xy 130.249926 -286.210964)
			(xy 130.250438 -286.23641) (xy 130.568966 -286.23641) (xy 130.572926 -286.187356) (xy 130.584703 -286.139572)
			(xy 130.603994 -286.094296) (xy 130.630297 -286.0527) (xy 130.662932 -286.015863) (xy 130.701053 -285.984738)
			(xy 130.743674 -285.960131) (xy 130.78969 -285.942679) (xy 130.837909 -285.932835) (xy 130.887084 -285.930854)
			(xy 130.935939 -285.936786) (xy 130.98321 -285.950478) (xy 131.027672 -285.971576) (xy 131.068175 -285.999532)
			(xy 131.103668 -286.033624) (xy 131.133233 -286.072968) (xy 131.156104 -286.116545) (xy 131.171688 -286.163226)
			(xy 131.179583 -286.211803) (xy 131.180078 -286.23641) (xy 131.498589 -286.23641) (xy 131.502684 -286.185682)
			(xy 131.514863 -286.136268) (xy 131.534811 -286.089448) (xy 131.562012 -286.046434) (xy 131.59576 -286.00834)
			(xy 131.635182 -285.976153) (xy 131.679256 -285.950707) (xy 131.726842 -285.93266) (xy 131.776706 -285.92248)
			(xy 131.827558 -285.920431) (xy 131.878079 -285.926565) (xy 131.926963 -285.940725) (xy 131.972942 -285.962542)
			(xy 132.014826 -285.991452) (xy 132.05153 -286.026707) (xy 132.082103 -286.067393) (xy 132.105754 -286.112456)
			(xy 132.12187 -286.16073) (xy 132.130034 -286.210964) (xy 132.130546 -286.23641) (xy 132.438643 -286.23641)
			(xy 132.442738 -286.185682) (xy 132.454917 -286.136268) (xy 132.474865 -286.089448) (xy 132.502066 -286.046434)
			(xy 132.535814 -286.00834) (xy 132.575236 -285.976153) (xy 132.61931 -285.950707) (xy 132.666896 -285.93266)
			(xy 132.71676 -285.92248) (xy 132.767612 -285.920431) (xy 132.818133 -285.926565) (xy 132.867017 -285.940725)
			(xy 132.912996 -285.962542) (xy 132.95488 -285.991452) (xy 132.991584 -286.026707) (xy 133.022157 -286.067393)
			(xy 133.045808 -286.112456) (xy 133.061924 -286.16073) (xy 133.070088 -286.210964) (xy 133.0706 -286.23641)
			(xy 133.388874 -286.23641) (xy 133.392834 -286.187356) (xy 133.404611 -286.139572) (xy 133.423902 -286.094296)
			(xy 133.450205 -286.0527) (xy 133.48284 -286.015863) (xy 133.520961 -285.984738) (xy 133.563582 -285.960131)
			(xy 133.609598 -285.942679) (xy 133.657817 -285.932835) (xy 133.706992 -285.930854) (xy 133.755847 -285.936786)
			(xy 133.803118 -285.950478) (xy 133.84758 -285.971576) (xy 133.888083 -285.999532) (xy 133.923576 -286.033624)
			(xy 133.953141 -286.072968) (xy 133.976012 -286.116545) (xy 133.991596 -286.163226) (xy 133.999491 -286.211803)
			(xy 133.999986 -286.23641) (xy 134.328928 -286.23641) (xy 134.332888 -286.187356) (xy 134.344665 -286.139572)
			(xy 134.363956 -286.094296) (xy 134.390259 -286.0527) (xy 134.422894 -286.015863) (xy 134.461015 -285.984738)
			(xy 134.503636 -285.960131) (xy 134.549652 -285.942679) (xy 134.597871 -285.932835) (xy 134.647046 -285.930854)
			(xy 134.695901 -285.936786) (xy 134.743172 -285.950478) (xy 134.787634 -285.971576) (xy 134.828137 -285.999532)
			(xy 134.86363 -286.033624) (xy 134.893195 -286.072968) (xy 134.916066 -286.116545) (xy 134.93165 -286.163226)
			(xy 134.939545 -286.211803) (xy 134.94004 -286.23641) (xy 135.268982 -286.23641) (xy 135.272942 -286.187356)
			(xy 135.284719 -286.139572) (xy 135.30401 -286.094296) (xy 135.330313 -286.0527) (xy 135.362948 -286.015863)
			(xy 135.401069 -285.984738) (xy 135.44369 -285.960131) (xy 135.489706 -285.942679) (xy 135.537925 -285.932835)
			(xy 135.5871 -285.930854) (xy 135.635955 -285.936786) (xy 135.683226 -285.950478) (xy 135.727688 -285.971576)
			(xy 135.768191 -285.999532) (xy 135.803684 -286.033624) (xy 135.833249 -286.072968) (xy 135.85612 -286.116545)
			(xy 135.871704 -286.163226) (xy 135.879599 -286.211803) (xy 135.880094 -286.23641) (xy 136.209036 -286.23641)
			(xy 136.212996 -286.187356) (xy 136.224773 -286.139572) (xy 136.244064 -286.094296) (xy 136.270367 -286.0527)
			(xy 136.303002 -286.015863) (xy 136.341123 -285.984738) (xy 136.383744 -285.960131) (xy 136.42976 -285.942679)
			(xy 136.477979 -285.932835) (xy 136.527154 -285.930854) (xy 136.576009 -285.936786) (xy 136.62328 -285.950478)
			(xy 136.667742 -285.971576) (xy 136.708245 -285.999532) (xy 136.743738 -286.033624) (xy 136.773303 -286.072968)
			(xy 136.796174 -286.116545) (xy 136.811758 -286.163226) (xy 136.819653 -286.211803) (xy 136.820148 -286.23641)
			(xy 136.819653 -286.261017) (xy 136.811758 -286.309594) (xy 136.796174 -286.356275) (xy 136.773303 -286.399852)
			(xy 136.743738 -286.439196) (xy 136.708245 -286.473288) (xy 136.667742 -286.501244) (xy 136.62328 -286.522342)
			(xy 136.576009 -286.536034) (xy 136.527154 -286.541966) (xy 136.477979 -286.539985) (xy 136.42976 -286.530141)
			(xy 136.383744 -286.512689) (xy 136.341123 -286.488082) (xy 136.303002 -286.456957) (xy 136.270367 -286.42012)
			(xy 136.244064 -286.378524) (xy 136.224773 -286.333248) (xy 136.212996 -286.285464) (xy 136.209036 -286.23641)
			(xy 135.880094 -286.23641) (xy 135.879599 -286.261017) (xy 135.871704 -286.309594) (xy 135.85612 -286.356275)
			(xy 135.833249 -286.399852) (xy 135.803684 -286.439196) (xy 135.768191 -286.473288) (xy 135.727688 -286.501244)
			(xy 135.683226 -286.522342) (xy 135.635955 -286.536034) (xy 135.5871 -286.541966) (xy 135.537925 -286.539985)
			(xy 135.489706 -286.530141) (xy 135.44369 -286.512689) (xy 135.401069 -286.488082) (xy 135.362948 -286.456957)
			(xy 135.330313 -286.42012) (xy 135.30401 -286.378524) (xy 135.284719 -286.333248) (xy 135.272942 -286.285464)
			(xy 135.268982 -286.23641) (xy 134.94004 -286.23641) (xy 134.939545 -286.261017) (xy 134.93165 -286.309594)
			(xy 134.916066 -286.356275) (xy 134.893195 -286.399852) (xy 134.86363 -286.439196) (xy 134.828137 -286.473288)
			(xy 134.787634 -286.501244) (xy 134.743172 -286.522342) (xy 134.695901 -286.536034) (xy 134.647046 -286.541966)
			(xy 134.597871 -286.539985) (xy 134.549652 -286.530141) (xy 134.503636 -286.512689) (xy 134.461015 -286.488082)
			(xy 134.422894 -286.456957) (xy 134.390259 -286.42012) (xy 134.363956 -286.378524) (xy 134.344665 -286.333248)
			(xy 134.332888 -286.285464) (xy 134.328928 -286.23641) (xy 133.999986 -286.23641) (xy 133.999491 -286.261017)
			(xy 133.991596 -286.309594) (xy 133.976012 -286.356275) (xy 133.953141 -286.399852) (xy 133.923576 -286.439196)
			(xy 133.888083 -286.473288) (xy 133.84758 -286.501244) (xy 133.803118 -286.522342) (xy 133.755847 -286.536034)
			(xy 133.706992 -286.541966) (xy 133.657817 -286.539985) (xy 133.609598 -286.530141) (xy 133.563582 -286.512689)
			(xy 133.520961 -286.488082) (xy 133.48284 -286.456957) (xy 133.450205 -286.42012) (xy 133.423902 -286.378524)
			(xy 133.404611 -286.333248) (xy 133.392834 -286.285464) (xy 133.388874 -286.23641) (xy 133.0706 -286.23641)
			(xy 133.070088 -286.261856) (xy 133.061924 -286.31209) (xy 133.045808 -286.360364) (xy 133.022157 -286.405427)
			(xy 132.991584 -286.446113) (xy 132.95488 -286.481368) (xy 132.912996 -286.510278) (xy 132.867017 -286.532095)
			(xy 132.818133 -286.546255) (xy 132.767612 -286.552389) (xy 132.71676 -286.55034) (xy 132.666896 -286.54016)
			(xy 132.61931 -286.522113) (xy 132.575236 -286.496667) (xy 132.535814 -286.46448) (xy 132.502066 -286.426386)
			(xy 132.474865 -286.383372) (xy 132.454917 -286.336552) (xy 132.442738 -286.287138) (xy 132.438643 -286.23641)
			(xy 132.130546 -286.23641) (xy 132.130034 -286.261856) (xy 132.12187 -286.31209) (xy 132.105754 -286.360364)
			(xy 132.082103 -286.405427) (xy 132.05153 -286.446113) (xy 132.014826 -286.481368) (xy 131.972942 -286.510278)
			(xy 131.926963 -286.532095) (xy 131.878079 -286.546255) (xy 131.827558 -286.552389) (xy 131.776706 -286.55034)
			(xy 131.726842 -286.54016) (xy 131.679256 -286.522113) (xy 131.635182 -286.496667) (xy 131.59576 -286.46448)
			(xy 131.562012 -286.426386) (xy 131.534811 -286.383372) (xy 131.514863 -286.336552) (xy 131.502684 -286.287138)
			(xy 131.498589 -286.23641) (xy 131.180078 -286.23641) (xy 131.179583 -286.261017) (xy 131.171688 -286.309594)
			(xy 131.156104 -286.356275) (xy 131.133233 -286.399852) (xy 131.103668 -286.439196) (xy 131.068175 -286.473288)
			(xy 131.027672 -286.501244) (xy 130.98321 -286.522342) (xy 130.935939 -286.536034) (xy 130.887084 -286.541966)
			(xy 130.837909 -286.539985) (xy 130.78969 -286.530141) (xy 130.743674 -286.512689) (xy 130.701053 -286.488082)
			(xy 130.662932 -286.456957) (xy 130.630297 -286.42012) (xy 130.603994 -286.378524) (xy 130.584703 -286.333248)
			(xy 130.572926 -286.285464) (xy 130.568966 -286.23641) (xy 130.250438 -286.23641) (xy 130.249926 -286.261856)
			(xy 130.241762 -286.31209) (xy 130.225646 -286.360364) (xy 130.201995 -286.405427) (xy 130.171422 -286.446113)
			(xy 130.134718 -286.481368) (xy 130.092834 -286.510278) (xy 130.046855 -286.532095) (xy 129.997971 -286.546255)
			(xy 129.94745 -286.552389) (xy 129.896598 -286.55034) (xy 129.846734 -286.54016) (xy 129.799148 -286.522113)
			(xy 129.755074 -286.496667) (xy 129.715652 -286.46448) (xy 129.681904 -286.426386) (xy 129.654703 -286.383372)
			(xy 129.634755 -286.336552) (xy 129.622576 -286.287138) (xy 129.618481 -286.23641) (xy 129.29997 -286.23641)
			(xy 129.299475 -286.261017) (xy 129.29158 -286.309594) (xy 129.275996 -286.356275) (xy 129.253125 -286.399852)
			(xy 129.22356 -286.439196) (xy 129.188067 -286.473288) (xy 129.147564 -286.501244) (xy 129.103102 -286.522342)
			(xy 129.055831 -286.536034) (xy 129.006976 -286.541966) (xy 128.957801 -286.539985) (xy 128.909582 -286.530141)
			(xy 128.863566 -286.512689) (xy 128.820945 -286.488082) (xy 128.782824 -286.456957) (xy 128.750189 -286.42012)
			(xy 128.723886 -286.378524) (xy 128.704595 -286.333248) (xy 128.692818 -286.285464) (xy 128.688858 -286.23641)
			(xy 128.370584 -286.23641) (xy 128.370072 -286.261856) (xy 128.361908 -286.31209) (xy 128.345792 -286.360364)
			(xy 128.322141 -286.405427) (xy 128.291568 -286.446113) (xy 128.254864 -286.481368) (xy 128.21298 -286.510278)
			(xy 128.167001 -286.532095) (xy 128.118117 -286.546255) (xy 128.067596 -286.552389) (xy 128.016744 -286.55034)
			(xy 127.96688 -286.54016) (xy 127.919294 -286.522113) (xy 127.87522 -286.496667) (xy 127.835798 -286.46448)
			(xy 127.80205 -286.426386) (xy 127.774849 -286.383372) (xy 127.754901 -286.336552) (xy 127.742722 -286.287138)
			(xy 127.738627 -286.23641) (xy 127.472186 -286.23641) (xy 127.472186 -286.265366) (xy 127.47879 -286.282638)
			(xy 127.48514 -286.28975) (xy 127.515328 -286.323957) (xy 127.570708 -286.396468) (xy 127.620065 -286.473206)
			(xy 127.663077 -286.553673) (xy 127.699464 -286.637343) (xy 127.72899 -286.723674) (xy 127.740664 -286.767778)
			(xy 127.743263 -286.776428) (xy 127.753542 -286.791266) (xy 127.76073 -286.796734) (xy 127.78034 -286.811159)
			(xy 127.81515 -286.845189) (xy 127.844119 -286.88431) (xy 127.866516 -286.927532) (xy 127.881772 -286.97376)
			(xy 127.8895 -287.021822) (xy 127.890016 -287.046162) (xy 128.208527 -287.046162) (xy 128.212622 -286.995434)
			(xy 128.224801 -286.94602) (xy 128.244749 -286.8992) (xy 128.27195 -286.856186) (xy 128.305698 -286.818092)
			(xy 128.34512 -286.785905) (xy 128.389194 -286.760459) (xy 128.43678 -286.742412) (xy 128.486644 -286.732232)
			(xy 128.537496 -286.730183) (xy 128.588017 -286.736317) (xy 128.636901 -286.750477) (xy 128.68288 -286.772294)
			(xy 128.724764 -286.801204) (xy 128.761468 -286.836459) (xy 128.792041 -286.877145) (xy 128.815692 -286.922208)
			(xy 128.831808 -286.970482) (xy 128.839972 -287.020716) (xy 128.840484 -287.046162) (xy 129.148581 -287.046162)
			(xy 129.152676 -286.995434) (xy 129.164855 -286.94602) (xy 129.184803 -286.8992) (xy 129.212004 -286.856186)
			(xy 129.245752 -286.818092) (xy 129.285174 -286.785905) (xy 129.329248 -286.760459) (xy 129.376834 -286.742412)
			(xy 129.426698 -286.732232) (xy 129.47755 -286.730183) (xy 129.528071 -286.736317) (xy 129.576955 -286.750477)
			(xy 129.622934 -286.772294) (xy 129.664818 -286.801204) (xy 129.701522 -286.836459) (xy 129.732095 -286.877145)
			(xy 129.755746 -286.922208) (xy 129.771862 -286.970482) (xy 129.780026 -287.020716) (xy 129.780538 -287.046162)
			(xy 129.780533 -287.046416) (xy 130.099066 -287.046416) (xy 130.103026 -286.997362) (xy 130.114803 -286.949578)
			(xy 130.134094 -286.904302) (xy 130.160397 -286.862706) (xy 130.193032 -286.825869) (xy 130.231153 -286.794744)
			(xy 130.273774 -286.770137) (xy 130.31979 -286.752685) (xy 130.368009 -286.742841) (xy 130.417184 -286.74086)
			(xy 130.466039 -286.746792) (xy 130.51331 -286.760484) (xy 130.557772 -286.781582) (xy 130.598275 -286.809538)
			(xy 130.633768 -286.84363) (xy 130.663333 -286.882974) (xy 130.686204 -286.926551) (xy 130.701788 -286.973232)
			(xy 130.709683 -287.021809) (xy 130.710173 -287.046162) (xy 131.028435 -287.046162) (xy 131.03253 -286.995434)
			(xy 131.044709 -286.94602) (xy 131.064657 -286.8992) (xy 131.091858 -286.856186) (xy 131.125606 -286.818092)
			(xy 131.165028 -286.785905) (xy 131.209102 -286.760459) (xy 131.256688 -286.742412) (xy 131.306552 -286.732232)
			(xy 131.357404 -286.730183) (xy 131.407925 -286.736317) (xy 131.456809 -286.750477) (xy 131.502788 -286.772294)
			(xy 131.544672 -286.801204) (xy 131.581376 -286.836459) (xy 131.611949 -286.877145) (xy 131.6356 -286.922208)
			(xy 131.651716 -286.970482) (xy 131.65988 -287.020716) (xy 131.660392 -287.046162) (xy 131.97892 -287.046162)
			(xy 131.98288 -286.997108) (xy 131.994657 -286.949324) (xy 132.013948 -286.904048) (xy 132.040251 -286.862452)
			(xy 132.072886 -286.825615) (xy 132.111007 -286.79449) (xy 132.153628 -286.769883) (xy 132.199644 -286.752431)
			(xy 132.247863 -286.742587) (xy 132.297038 -286.740606) (xy 132.345893 -286.746538) (xy 132.393164 -286.76023)
			(xy 132.437626 -286.781328) (xy 132.478129 -286.809284) (xy 132.513622 -286.843376) (xy 132.543187 -286.88272)
			(xy 132.566058 -286.926297) (xy 132.581642 -286.972978) (xy 132.589537 -287.021555) (xy 132.590032 -287.046162)
			(xy 132.908543 -287.046162) (xy 132.912638 -286.995434) (xy 132.924817 -286.94602) (xy 132.944765 -286.8992)
			(xy 132.971966 -286.856186) (xy 133.005714 -286.818092) (xy 133.045136 -286.785905) (xy 133.08921 -286.760459)
			(xy 133.136796 -286.742412) (xy 133.18666 -286.732232) (xy 133.237512 -286.730183) (xy 133.288033 -286.736317)
			(xy 133.336917 -286.750477) (xy 133.382896 -286.772294) (xy 133.42478 -286.801204) (xy 133.461484 -286.836459)
			(xy 133.492057 -286.877145) (xy 133.515708 -286.922208) (xy 133.531824 -286.970482) (xy 133.539988 -287.020716)
			(xy 133.5405 -287.046162) (xy 133.540495 -287.046416) (xy 133.859028 -287.046416) (xy 133.862988 -286.997362)
			(xy 133.874765 -286.949578) (xy 133.894056 -286.904302) (xy 133.920359 -286.862706) (xy 133.952994 -286.825869)
			(xy 133.991115 -286.794744) (xy 134.033736 -286.770137) (xy 134.079752 -286.752685) (xy 134.127971 -286.742841)
			(xy 134.177146 -286.74086) (xy 134.226001 -286.746792) (xy 134.273272 -286.760484) (xy 134.317734 -286.781582)
			(xy 134.358237 -286.809538) (xy 134.39373 -286.84363) (xy 134.423295 -286.882974) (xy 134.446166 -286.926551)
			(xy 134.46175 -286.973232) (xy 134.469645 -287.021809) (xy 134.470135 -287.046162) (xy 134.798828 -287.046162)
			(xy 134.802788 -286.997108) (xy 134.814565 -286.949324) (xy 134.833856 -286.904048) (xy 134.860159 -286.862452)
			(xy 134.892794 -286.825615) (xy 134.930915 -286.79449) (xy 134.973536 -286.769883) (xy 135.019552 -286.752431)
			(xy 135.067771 -286.742587) (xy 135.116946 -286.740606) (xy 135.165801 -286.746538) (xy 135.213072 -286.76023)
			(xy 135.257534 -286.781328) (xy 135.298037 -286.809284) (xy 135.33353 -286.843376) (xy 135.363095 -286.88272)
			(xy 135.385966 -286.926297) (xy 135.40155 -286.972978) (xy 135.409445 -287.021555) (xy 135.40994 -287.046162)
			(xy 135.738882 -287.046162) (xy 135.742842 -286.997108) (xy 135.754619 -286.949324) (xy 135.77391 -286.904048)
			(xy 135.800213 -286.862452) (xy 135.832848 -286.825615) (xy 135.870969 -286.79449) (xy 135.91359 -286.769883)
			(xy 135.959606 -286.752431) (xy 136.007825 -286.742587) (xy 136.057 -286.740606) (xy 136.105855 -286.746538)
			(xy 136.153126 -286.76023) (xy 136.197588 -286.781328) (xy 136.238091 -286.809284) (xy 136.273584 -286.843376)
			(xy 136.303149 -286.88272) (xy 136.32602 -286.926297) (xy 136.341604 -286.972978) (xy 136.349499 -287.021555)
			(xy 136.349994 -287.046162) (xy 136.349499 -287.070769) (xy 136.341604 -287.119346) (xy 136.32602 -287.166027)
			(xy 136.303149 -287.209604) (xy 136.273584 -287.248948) (xy 136.238091 -287.28304) (xy 136.197588 -287.310996)
			(xy 136.153126 -287.332094) (xy 136.105855 -287.345786) (xy 136.057 -287.351718) (xy 136.007825 -287.349737)
			(xy 135.959606 -287.339893) (xy 135.91359 -287.322441) (xy 135.870969 -287.297834) (xy 135.832848 -287.266709)
			(xy 135.800213 -287.229872) (xy 135.77391 -287.188276) (xy 135.754619 -287.143) (xy 135.742842 -287.095216)
			(xy 135.738882 -287.046162) (xy 135.40994 -287.046162) (xy 135.409445 -287.070769) (xy 135.40155 -287.119346)
			(xy 135.385966 -287.166027) (xy 135.363095 -287.209604) (xy 135.33353 -287.248948) (xy 135.298037 -287.28304)
			(xy 135.257534 -287.310996) (xy 135.213072 -287.332094) (xy 135.165801 -287.345786) (xy 135.116946 -287.351718)
			(xy 135.067771 -287.349737) (xy 135.019552 -287.339893) (xy 134.973536 -287.322441) (xy 134.930915 -287.297834)
			(xy 134.892794 -287.266709) (xy 134.860159 -287.229872) (xy 134.833856 -287.188276) (xy 134.814565 -287.143)
			(xy 134.802788 -287.095216) (xy 134.798828 -287.046162) (xy 134.470135 -287.046162) (xy 134.47014 -287.046416)
			(xy 134.469645 -287.071023) (xy 134.46175 -287.1196) (xy 134.446166 -287.166281) (xy 134.423295 -287.209858)
			(xy 134.39373 -287.249202) (xy 134.358237 -287.283294) (xy 134.317734 -287.31125) (xy 134.273272 -287.332348)
			(xy 134.226001 -287.34604) (xy 134.177146 -287.351972) (xy 134.127971 -287.349991) (xy 134.079752 -287.340147)
			(xy 134.033736 -287.322695) (xy 133.991115 -287.298088) (xy 133.952994 -287.266963) (xy 133.920359 -287.230126)
			(xy 133.894056 -287.18853) (xy 133.874765 -287.143254) (xy 133.862988 -287.09547) (xy 133.859028 -287.046416)
			(xy 133.540495 -287.046416) (xy 133.539988 -287.071608) (xy 133.531824 -287.121842) (xy 133.515708 -287.170116)
			(xy 133.492057 -287.215179) (xy 133.461484 -287.255865) (xy 133.42478 -287.29112) (xy 133.382896 -287.32003)
			(xy 133.336917 -287.341847) (xy 133.288033 -287.356007) (xy 133.237512 -287.362141) (xy 133.18666 -287.360092)
			(xy 133.136796 -287.349912) (xy 133.08921 -287.331865) (xy 133.045136 -287.306419) (xy 133.005714 -287.274232)
			(xy 132.971966 -287.236138) (xy 132.944765 -287.193124) (xy 132.924817 -287.146304) (xy 132.912638 -287.09689)
			(xy 132.908543 -287.046162) (xy 132.590032 -287.046162) (xy 132.589537 -287.070769) (xy 132.581642 -287.119346)
			(xy 132.566058 -287.166027) (xy 132.543187 -287.209604) (xy 132.513622 -287.248948) (xy 132.478129 -287.28304)
			(xy 132.437626 -287.310996) (xy 132.393164 -287.332094) (xy 132.345893 -287.345786) (xy 132.297038 -287.351718)
			(xy 132.247863 -287.349737) (xy 132.199644 -287.339893) (xy 132.153628 -287.322441) (xy 132.111007 -287.297834)
			(xy 132.072886 -287.266709) (xy 132.040251 -287.229872) (xy 132.013948 -287.188276) (xy 131.994657 -287.143)
			(xy 131.98288 -287.095216) (xy 131.97892 -287.046162) (xy 131.660392 -287.046162) (xy 131.65988 -287.071608)
			(xy 131.651716 -287.121842) (xy 131.6356 -287.170116) (xy 131.611949 -287.215179) (xy 131.581376 -287.255865)
			(xy 131.544672 -287.29112) (xy 131.502788 -287.32003) (xy 131.456809 -287.341847) (xy 131.407925 -287.356007)
			(xy 131.357404 -287.362141) (xy 131.306552 -287.360092) (xy 131.256688 -287.349912) (xy 131.209102 -287.331865)
			(xy 131.165028 -287.306419) (xy 131.125606 -287.274232) (xy 131.091858 -287.236138) (xy 131.064657 -287.193124)
			(xy 131.044709 -287.146304) (xy 131.03253 -287.09689) (xy 131.028435 -287.046162) (xy 130.710173 -287.046162)
			(xy 130.710178 -287.046416) (xy 130.709683 -287.071023) (xy 130.701788 -287.1196) (xy 130.686204 -287.166281)
			(xy 130.663333 -287.209858) (xy 130.633768 -287.249202) (xy 130.598275 -287.283294) (xy 130.557772 -287.31125)
			(xy 130.51331 -287.332348) (xy 130.466039 -287.34604) (xy 130.417184 -287.351972) (xy 130.368009 -287.349991)
			(xy 130.31979 -287.340147) (xy 130.273774 -287.322695) (xy 130.231153 -287.298088) (xy 130.193032 -287.266963)
			(xy 130.160397 -287.230126) (xy 130.134094 -287.18853) (xy 130.114803 -287.143254) (xy 130.103026 -287.09547)
			(xy 130.099066 -287.046416) (xy 129.780533 -287.046416) (xy 129.780026 -287.071608) (xy 129.771862 -287.121842)
			(xy 129.755746 -287.170116) (xy 129.732095 -287.215179) (xy 129.701522 -287.255865) (xy 129.664818 -287.29112)
			(xy 129.622934 -287.32003) (xy 129.576955 -287.341847) (xy 129.528071 -287.356007) (xy 129.47755 -287.362141)
			(xy 129.426698 -287.360092) (xy 129.376834 -287.349912) (xy 129.329248 -287.331865) (xy 129.285174 -287.306419)
			(xy 129.245752 -287.274232) (xy 129.212004 -287.236138) (xy 129.184803 -287.193124) (xy 129.164855 -287.146304)
			(xy 129.152676 -287.09689) (xy 129.148581 -287.046162) (xy 128.840484 -287.046162) (xy 128.839972 -287.071608)
			(xy 128.831808 -287.121842) (xy 128.815692 -287.170116) (xy 128.792041 -287.215179) (xy 128.761468 -287.255865)
			(xy 128.724764 -287.29112) (xy 128.68288 -287.32003) (xy 128.636901 -287.341847) (xy 128.588017 -287.356007)
			(xy 128.537496 -287.362141) (xy 128.486644 -287.360092) (xy 128.43678 -287.349912) (xy 128.389194 -287.331865)
			(xy 128.34512 -287.306419) (xy 128.305698 -287.274232) (xy 128.27195 -287.236138) (xy 128.244749 -287.193124)
			(xy 128.224801 -287.146304) (xy 128.212622 -287.09689) (xy 128.208527 -287.046162) (xy 127.890016 -287.046162)
			(xy 127.88957 -287.069501) (xy 127.882465 -287.115636) (xy 127.868429 -287.160154) (xy 127.85852 -287.18129)
			(xy 127.856742 -287.184846) (xy 127.845114 -287.206628) (xy 127.815903 -287.246432) (xy 127.780648 -287.280998)
			(xy 127.76073 -287.29559) (xy 127.753549 -287.301065) (xy 127.74327 -287.3159) (xy 127.740664 -287.324546)
			(xy 127.728998 -287.368653) (xy 127.699481 -287.454989) (xy 127.663099 -287.538664) (xy 127.62009 -287.619134)
			(xy 127.570734 -287.695875) (xy 127.515351 -287.768386) (xy 127.48514 -287.802574) (xy 127.47879 -287.809686)
			(xy 127.472186 -287.826958) (xy 127.472186 -287.856422) (xy 127.738627 -287.856422) (xy 127.742722 -287.805694)
			(xy 127.754901 -287.75628) (xy 127.774849 -287.70946) (xy 127.80205 -287.666446) (xy 127.835798 -287.628352)
			(xy 127.87522 -287.596165) (xy 127.919294 -287.570719) (xy 127.96688 -287.552672) (xy 128.016744 -287.542492)
			(xy 128.067596 -287.540443) (xy 128.118117 -287.546577) (xy 128.167001 -287.560737) (xy 128.21298 -287.582554)
			(xy 128.254864 -287.611464) (xy 128.291568 -287.646719) (xy 128.322141 -287.687405) (xy 128.345792 -287.732468)
			(xy 128.361908 -287.780742) (xy 128.370072 -287.830976) (xy 128.370584 -287.856422) (xy 128.688858 -287.856422)
			(xy 128.692818 -287.807368) (xy 128.704595 -287.759584) (xy 128.723886 -287.714308) (xy 128.750189 -287.672712)
			(xy 128.782824 -287.635875) (xy 128.820945 -287.60475) (xy 128.863566 -287.580143) (xy 128.909582 -287.562691)
			(xy 128.957801 -287.552847) (xy 129.006976 -287.550866) (xy 129.055831 -287.556798) (xy 129.103102 -287.57049)
			(xy 129.147564 -287.591588) (xy 129.188067 -287.619544) (xy 129.22356 -287.653636) (xy 129.253125 -287.69298)
			(xy 129.275996 -287.736557) (xy 129.29158 -287.783238) (xy 129.299475 -287.831815) (xy 129.29997 -287.856422)
			(xy 129.618481 -287.856422) (xy 129.622576 -287.805694) (xy 129.634755 -287.75628) (xy 129.654703 -287.70946)
			(xy 129.681904 -287.666446) (xy 129.715652 -287.628352) (xy 129.755074 -287.596165) (xy 129.799148 -287.570719)
			(xy 129.846734 -287.552672) (xy 129.896598 -287.542492) (xy 129.94745 -287.540443) (xy 129.997971 -287.546577)
			(xy 130.046855 -287.560737) (xy 130.092834 -287.582554) (xy 130.134718 -287.611464) (xy 130.171422 -287.646719)
			(xy 130.201995 -287.687405) (xy 130.225646 -287.732468) (xy 130.241762 -287.780742) (xy 130.249926 -287.830976)
			(xy 130.250438 -287.856422) (xy 131.498589 -287.856422) (xy 131.502684 -287.805694) (xy 131.514863 -287.75628)
			(xy 131.534811 -287.70946) (xy 131.562012 -287.666446) (xy 131.59576 -287.628352) (xy 131.635182 -287.596165)
			(xy 131.679256 -287.570719) (xy 131.726842 -287.552672) (xy 131.776706 -287.542492) (xy 131.827558 -287.540443)
			(xy 131.878079 -287.546577) (xy 131.926963 -287.560737) (xy 131.972942 -287.582554) (xy 132.014826 -287.611464)
			(xy 132.05153 -287.646719) (xy 132.082103 -287.687405) (xy 132.105754 -287.732468) (xy 132.12187 -287.780742)
			(xy 132.130034 -287.830976) (xy 132.130546 -287.856422) (xy 132.438643 -287.856422) (xy 132.442738 -287.805694)
			(xy 132.454917 -287.75628) (xy 132.474865 -287.70946) (xy 132.502066 -287.666446) (xy 132.535814 -287.628352)
			(xy 132.575236 -287.596165) (xy 132.61931 -287.570719) (xy 132.666896 -287.552672) (xy 132.71676 -287.542492)
			(xy 132.767612 -287.540443) (xy 132.818133 -287.546577) (xy 132.867017 -287.560737) (xy 132.912996 -287.582554)
			(xy 132.95488 -287.611464) (xy 132.991584 -287.646719) (xy 133.022157 -287.687405) (xy 133.045808 -287.732468)
			(xy 133.061924 -287.780742) (xy 133.070088 -287.830976) (xy 133.0706 -287.856422) (xy 133.388874 -287.856422)
			(xy 133.392834 -287.807368) (xy 133.404611 -287.759584) (xy 133.423902 -287.714308) (xy 133.450205 -287.672712)
			(xy 133.48284 -287.635875) (xy 133.520961 -287.60475) (xy 133.563582 -287.580143) (xy 133.609598 -287.562691)
			(xy 133.657817 -287.552847) (xy 133.706992 -287.550866) (xy 133.755847 -287.556798) (xy 133.803118 -287.57049)
			(xy 133.84758 -287.591588) (xy 133.888083 -287.619544) (xy 133.923576 -287.653636) (xy 133.953141 -287.69298)
			(xy 133.976012 -287.736557) (xy 133.991596 -287.783238) (xy 133.999491 -287.831815) (xy 133.999986 -287.856422)
			(xy 134.328928 -287.856422) (xy 134.332888 -287.807368) (xy 134.344665 -287.759584) (xy 134.363956 -287.714308)
			(xy 134.390259 -287.672712) (xy 134.422894 -287.635875) (xy 134.461015 -287.60475) (xy 134.503636 -287.580143)
			(xy 134.549652 -287.562691) (xy 134.597871 -287.552847) (xy 134.647046 -287.550866) (xy 134.695901 -287.556798)
			(xy 134.743172 -287.57049) (xy 134.787634 -287.591588) (xy 134.828137 -287.619544) (xy 134.86363 -287.653636)
			(xy 134.893195 -287.69298) (xy 134.916066 -287.736557) (xy 134.93165 -287.783238) (xy 134.939545 -287.831815)
			(xy 134.94004 -287.856422) (xy 135.268982 -287.856422) (xy 135.272942 -287.807368) (xy 135.284719 -287.759584)
			(xy 135.30401 -287.714308) (xy 135.330313 -287.672712) (xy 135.362948 -287.635875) (xy 135.401069 -287.60475)
			(xy 135.44369 -287.580143) (xy 135.489706 -287.562691) (xy 135.537925 -287.552847) (xy 135.5871 -287.550866)
			(xy 135.635955 -287.556798) (xy 135.683226 -287.57049) (xy 135.727688 -287.591588) (xy 135.768191 -287.619544)
			(xy 135.803684 -287.653636) (xy 135.833249 -287.69298) (xy 135.85612 -287.736557) (xy 135.871704 -287.783238)
			(xy 135.879599 -287.831815) (xy 135.880094 -287.856422) (xy 136.209036 -287.856422) (xy 136.212996 -287.807368)
			(xy 136.224773 -287.759584) (xy 136.244064 -287.714308) (xy 136.270367 -287.672712) (xy 136.303002 -287.635875)
			(xy 136.341123 -287.60475) (xy 136.383744 -287.580143) (xy 136.42976 -287.562691) (xy 136.477979 -287.552847)
			(xy 136.527154 -287.550866) (xy 136.576009 -287.556798) (xy 136.62328 -287.57049) (xy 136.667742 -287.591588)
			(xy 136.708245 -287.619544) (xy 136.743738 -287.653636) (xy 136.773303 -287.69298) (xy 136.796174 -287.736557)
			(xy 136.811758 -287.783238) (xy 136.819653 -287.831815) (xy 136.820148 -287.856422) (xy 136.819653 -287.881029)
			(xy 136.811758 -287.929606) (xy 136.796174 -287.976287) (xy 136.773303 -288.019864) (xy 136.743738 -288.059208)
			(xy 136.708245 -288.0933) (xy 136.667742 -288.121256) (xy 136.62328 -288.142354) (xy 136.576009 -288.156046)
			(xy 136.527154 -288.161978) (xy 136.477979 -288.159997) (xy 136.42976 -288.150153) (xy 136.383744 -288.132701)
			(xy 136.341123 -288.108094) (xy 136.303002 -288.076969) (xy 136.270367 -288.040132) (xy 136.244064 -287.998536)
			(xy 136.224773 -287.95326) (xy 136.212996 -287.905476) (xy 136.209036 -287.856422) (xy 135.880094 -287.856422)
			(xy 135.879599 -287.881029) (xy 135.871704 -287.929606) (xy 135.85612 -287.976287) (xy 135.833249 -288.019864)
			(xy 135.803684 -288.059208) (xy 135.768191 -288.0933) (xy 135.727688 -288.121256) (xy 135.683226 -288.142354)
			(xy 135.635955 -288.156046) (xy 135.5871 -288.161978) (xy 135.537925 -288.159997) (xy 135.489706 -288.150153)
			(xy 135.44369 -288.132701) (xy 135.401069 -288.108094) (xy 135.362948 -288.076969) (xy 135.330313 -288.040132)
			(xy 135.30401 -287.998536) (xy 135.284719 -287.95326) (xy 135.272942 -287.905476) (xy 135.268982 -287.856422)
			(xy 134.94004 -287.856422) (xy 134.939545 -287.881029) (xy 134.93165 -287.929606) (xy 134.916066 -287.976287)
			(xy 134.893195 -288.019864) (xy 134.86363 -288.059208) (xy 134.828137 -288.0933) (xy 134.787634 -288.121256)
			(xy 134.743172 -288.142354) (xy 134.695901 -288.156046) (xy 134.647046 -288.161978) (xy 134.597871 -288.159997)
			(xy 134.549652 -288.150153) (xy 134.503636 -288.132701) (xy 134.461015 -288.108094) (xy 134.422894 -288.076969)
			(xy 134.390259 -288.040132) (xy 134.363956 -287.998536) (xy 134.344665 -287.95326) (xy 134.332888 -287.905476)
			(xy 134.328928 -287.856422) (xy 133.999986 -287.856422) (xy 133.999491 -287.881029) (xy 133.991596 -287.929606)
			(xy 133.976012 -287.976287) (xy 133.953141 -288.019864) (xy 133.923576 -288.059208) (xy 133.888083 -288.0933)
			(xy 133.84758 -288.121256) (xy 133.803118 -288.142354) (xy 133.755847 -288.156046) (xy 133.706992 -288.161978)
			(xy 133.657817 -288.159997) (xy 133.609598 -288.150153) (xy 133.563582 -288.132701) (xy 133.520961 -288.108094)
			(xy 133.48284 -288.076969) (xy 133.450205 -288.040132) (xy 133.423902 -287.998536) (xy 133.404611 -287.95326)
			(xy 133.392834 -287.905476) (xy 133.388874 -287.856422) (xy 133.0706 -287.856422) (xy 133.070088 -287.881868)
			(xy 133.061924 -287.932102) (xy 133.045808 -287.980376) (xy 133.022157 -288.025439) (xy 132.991584 -288.066125)
			(xy 132.95488 -288.10138) (xy 132.912996 -288.13029) (xy 132.867017 -288.152107) (xy 132.818133 -288.166267)
			(xy 132.767612 -288.172401) (xy 132.71676 -288.170352) (xy 132.666896 -288.160172) (xy 132.61931 -288.142125)
			(xy 132.575236 -288.116679) (xy 132.535814 -288.084492) (xy 132.502066 -288.046398) (xy 132.474865 -288.003384)
			(xy 132.454917 -287.956564) (xy 132.442738 -287.90715) (xy 132.438643 -287.856422) (xy 132.130546 -287.856422)
			(xy 132.130034 -287.881868) (xy 132.12187 -287.932102) (xy 132.105754 -287.980376) (xy 132.082103 -288.025439)
			(xy 132.05153 -288.066125) (xy 132.014826 -288.10138) (xy 131.972942 -288.13029) (xy 131.926963 -288.152107)
			(xy 131.878079 -288.166267) (xy 131.827558 -288.172401) (xy 131.776706 -288.170352) (xy 131.726842 -288.160172)
			(xy 131.679256 -288.142125) (xy 131.635182 -288.116679) (xy 131.59576 -288.084492) (xy 131.562012 -288.046398)
			(xy 131.534811 -288.003384) (xy 131.514863 -287.956564) (xy 131.502684 -287.90715) (xy 131.498589 -287.856422)
			(xy 130.250438 -287.856422) (xy 130.249926 -287.881868) (xy 130.241762 -287.932102) (xy 130.225646 -287.980376)
			(xy 130.201995 -288.025439) (xy 130.171422 -288.066125) (xy 130.134718 -288.10138) (xy 130.092834 -288.13029)
			(xy 130.046855 -288.152107) (xy 129.997971 -288.166267) (xy 129.94745 -288.172401) (xy 129.896598 -288.170352)
			(xy 129.846734 -288.160172) (xy 129.799148 -288.142125) (xy 129.755074 -288.116679) (xy 129.715652 -288.084492)
			(xy 129.681904 -288.046398) (xy 129.654703 -288.003384) (xy 129.634755 -287.956564) (xy 129.622576 -287.90715)
			(xy 129.618481 -287.856422) (xy 129.29997 -287.856422) (xy 129.299475 -287.881029) (xy 129.29158 -287.929606)
			(xy 129.275996 -287.976287) (xy 129.253125 -288.019864) (xy 129.22356 -288.059208) (xy 129.188067 -288.0933)
			(xy 129.147564 -288.121256) (xy 129.103102 -288.142354) (xy 129.055831 -288.156046) (xy 129.006976 -288.161978)
			(xy 128.957801 -288.159997) (xy 128.909582 -288.150153) (xy 128.863566 -288.132701) (xy 128.820945 -288.108094)
			(xy 128.782824 -288.076969) (xy 128.750189 -288.040132) (xy 128.723886 -287.998536) (xy 128.704595 -287.95326)
			(xy 128.692818 -287.905476) (xy 128.688858 -287.856422) (xy 128.370584 -287.856422) (xy 128.370072 -287.881868)
			(xy 128.361908 -287.932102) (xy 128.345792 -287.980376) (xy 128.322141 -288.025439) (xy 128.291568 -288.066125)
			(xy 128.254864 -288.10138) (xy 128.21298 -288.13029) (xy 128.167001 -288.152107) (xy 128.118117 -288.166267)
			(xy 128.067596 -288.172401) (xy 128.016744 -288.170352) (xy 127.96688 -288.160172) (xy 127.919294 -288.142125)
			(xy 127.87522 -288.116679) (xy 127.835798 -288.084492) (xy 127.80205 -288.046398) (xy 127.774849 -288.003384)
			(xy 127.754901 -287.956564) (xy 127.742722 -287.90715) (xy 127.738627 -287.856422) (xy 127.472186 -287.856422)
			(xy 127.472186 -287.885378) (xy 127.47879 -287.90265) (xy 127.48514 -287.909762) (xy 127.520777 -287.950243)
			(xy 127.585023 -288.036879) (xy 127.61341 -288.082736) (xy 127.638406 -288.125192) (xy 127.681784 -288.21366)
			(xy 127.717307 -288.305565) (xy 127.73152 -288.352738) (xy 127.73454 -288.361796) (xy 127.746169 -288.376921)
			(xy 127.754126 -288.382202) (xy 127.762737 -288.387411) (xy 127.779386 -288.398721) (xy 127.7874 -288.404808)
			(xy 127.810971 -288.4239) (xy 127.851366 -288.469141) (xy 127.867664 -288.494724) (xy 127.880595 -288.517011)
			(xy 127.900145 -288.564683) (xy 127.912069 -288.614809) (xy 127.916078 -288.666174) (xy 128.208527 -288.666174)
			(xy 128.212622 -288.615446) (xy 128.224801 -288.566032) (xy 128.244749 -288.519212) (xy 128.27195 -288.476198)
			(xy 128.305698 -288.438104) (xy 128.34512 -288.405917) (xy 128.389194 -288.380471) (xy 128.43678 -288.362424)
			(xy 128.486644 -288.352244) (xy 128.537496 -288.350195) (xy 128.588017 -288.356329) (xy 128.636901 -288.370489)
			(xy 128.68288 -288.392306) (xy 128.724764 -288.421216) (xy 128.761468 -288.456471) (xy 128.792041 -288.497157)
			(xy 128.815692 -288.54222) (xy 128.831808 -288.590494) (xy 128.839972 -288.640728) (xy 128.840484 -288.666174)
			(xy 129.148581 -288.666174) (xy 129.152676 -288.615446) (xy 129.164855 -288.566032) (xy 129.184803 -288.519212)
			(xy 129.212004 -288.476198) (xy 129.245752 -288.438104) (xy 129.285174 -288.405917) (xy 129.329248 -288.380471)
			(xy 129.376834 -288.362424) (xy 129.426698 -288.352244) (xy 129.47755 -288.350195) (xy 129.528071 -288.356329)
			(xy 129.576955 -288.370489) (xy 129.622934 -288.392306) (xy 129.664818 -288.421216) (xy 129.701522 -288.456471)
			(xy 129.732095 -288.497157) (xy 129.755746 -288.54222) (xy 129.771862 -288.590494) (xy 129.780026 -288.640728)
			(xy 129.780538 -288.666174) (xy 130.099066 -288.666174) (xy 130.103026 -288.61712) (xy 130.114803 -288.569336)
			(xy 130.134094 -288.52406) (xy 130.160397 -288.482464) (xy 130.193032 -288.445627) (xy 130.231153 -288.414502)
			(xy 130.273774 -288.389895) (xy 130.31979 -288.372443) (xy 130.368009 -288.362599) (xy 130.417184 -288.360618)
			(xy 130.466039 -288.36655) (xy 130.51331 -288.380242) (xy 130.557772 -288.40134) (xy 130.598275 -288.429296)
			(xy 130.633768 -288.463388) (xy 130.663333 -288.502732) (xy 130.686204 -288.546309) (xy 130.701788 -288.59299)
			(xy 130.709683 -288.641567) (xy 130.710178 -288.666174) (xy 131.028435 -288.666174) (xy 131.03253 -288.615446)
			(xy 131.044709 -288.566032) (xy 131.064657 -288.519212) (xy 131.091858 -288.476198) (xy 131.125606 -288.438104)
			(xy 131.165028 -288.405917) (xy 131.209102 -288.380471) (xy 131.256688 -288.362424) (xy 131.306552 -288.352244)
			(xy 131.357404 -288.350195) (xy 131.407925 -288.356329) (xy 131.456809 -288.370489) (xy 131.502788 -288.392306)
			(xy 131.544672 -288.421216) (xy 131.581376 -288.456471) (xy 131.611949 -288.497157) (xy 131.6356 -288.54222)
			(xy 131.651716 -288.590494) (xy 131.65988 -288.640728) (xy 131.660392 -288.666174) (xy 131.97892 -288.666174)
			(xy 131.98288 -288.61712) (xy 131.994657 -288.569336) (xy 132.013948 -288.52406) (xy 132.040251 -288.482464)
			(xy 132.072886 -288.445627) (xy 132.111007 -288.414502) (xy 132.153628 -288.389895) (xy 132.199644 -288.372443)
			(xy 132.247863 -288.362599) (xy 132.297038 -288.360618) (xy 132.345893 -288.36655) (xy 132.393164 -288.380242)
			(xy 132.437626 -288.40134) (xy 132.478129 -288.429296) (xy 132.513622 -288.463388) (xy 132.543187 -288.502732)
			(xy 132.566058 -288.546309) (xy 132.581642 -288.59299) (xy 132.589537 -288.641567) (xy 132.590032 -288.666174)
			(xy 132.908543 -288.666174) (xy 132.912638 -288.615446) (xy 132.924817 -288.566032) (xy 132.944765 -288.519212)
			(xy 132.971966 -288.476198) (xy 133.005714 -288.438104) (xy 133.045136 -288.405917) (xy 133.08921 -288.380471)
			(xy 133.136796 -288.362424) (xy 133.18666 -288.352244) (xy 133.237512 -288.350195) (xy 133.288033 -288.356329)
			(xy 133.336917 -288.370489) (xy 133.382896 -288.392306) (xy 133.42478 -288.421216) (xy 133.461484 -288.456471)
			(xy 133.492057 -288.497157) (xy 133.515708 -288.54222) (xy 133.531824 -288.590494) (xy 133.539988 -288.640728)
			(xy 133.5405 -288.666174) (xy 133.859028 -288.666174) (xy 133.862988 -288.61712) (xy 133.874765 -288.569336)
			(xy 133.894056 -288.52406) (xy 133.920359 -288.482464) (xy 133.952994 -288.445627) (xy 133.991115 -288.414502)
			(xy 134.033736 -288.389895) (xy 134.079752 -288.372443) (xy 134.127971 -288.362599) (xy 134.177146 -288.360618)
			(xy 134.226001 -288.36655) (xy 134.273272 -288.380242) (xy 134.317734 -288.40134) (xy 134.358237 -288.429296)
			(xy 134.39373 -288.463388) (xy 134.423295 -288.502732) (xy 134.446166 -288.546309) (xy 134.46175 -288.59299)
			(xy 134.469645 -288.641567) (xy 134.47014 -288.666174) (xy 134.798828 -288.666174) (xy 134.802788 -288.61712)
			(xy 134.814565 -288.569336) (xy 134.833856 -288.52406) (xy 134.860159 -288.482464) (xy 134.892794 -288.445627)
			(xy 134.930915 -288.414502) (xy 134.973536 -288.389895) (xy 135.019552 -288.372443) (xy 135.067771 -288.362599)
			(xy 135.116946 -288.360618) (xy 135.165801 -288.36655) (xy 135.213072 -288.380242) (xy 135.257534 -288.40134)
			(xy 135.298037 -288.429296) (xy 135.33353 -288.463388) (xy 135.363095 -288.502732) (xy 135.385966 -288.546309)
			(xy 135.40155 -288.59299) (xy 135.409445 -288.641567) (xy 135.40994 -288.666174) (xy 135.738882 -288.666174)
			(xy 135.742842 -288.61712) (xy 135.754619 -288.569336) (xy 135.77391 -288.52406) (xy 135.800213 -288.482464)
			(xy 135.832848 -288.445627) (xy 135.870969 -288.414502) (xy 135.91359 -288.389895) (xy 135.959606 -288.372443)
			(xy 136.007825 -288.362599) (xy 136.057 -288.360618) (xy 136.105855 -288.36655) (xy 136.153126 -288.380242)
			(xy 136.197588 -288.40134) (xy 136.238091 -288.429296) (xy 136.273584 -288.463388) (xy 136.303149 -288.502732)
			(xy 136.32602 -288.546309) (xy 136.341604 -288.59299) (xy 136.349499 -288.641567) (xy 136.349994 -288.666174)
			(xy 136.349499 -288.690781) (xy 136.341604 -288.739358) (xy 136.32602 -288.786039) (xy 136.303149 -288.829616)
			(xy 136.273584 -288.86896) (xy 136.238091 -288.903052) (xy 136.197588 -288.931008) (xy 136.153126 -288.952106)
			(xy 136.105855 -288.965798) (xy 136.057 -288.97173) (xy 136.007825 -288.969749) (xy 135.959606 -288.959905)
			(xy 135.91359 -288.942453) (xy 135.870969 -288.917846) (xy 135.832848 -288.886721) (xy 135.800213 -288.849884)
			(xy 135.77391 -288.808288) (xy 135.754619 -288.763012) (xy 135.742842 -288.715228) (xy 135.738882 -288.666174)
			(xy 135.40994 -288.666174) (xy 135.409445 -288.690781) (xy 135.40155 -288.739358) (xy 135.385966 -288.786039)
			(xy 135.363095 -288.829616) (xy 135.33353 -288.86896) (xy 135.298037 -288.903052) (xy 135.257534 -288.931008)
			(xy 135.213072 -288.952106) (xy 135.165801 -288.965798) (xy 135.116946 -288.97173) (xy 135.067771 -288.969749)
			(xy 135.019552 -288.959905) (xy 134.973536 -288.942453) (xy 134.930915 -288.917846) (xy 134.892794 -288.886721)
			(xy 134.860159 -288.849884) (xy 134.833856 -288.808288) (xy 134.814565 -288.763012) (xy 134.802788 -288.715228)
			(xy 134.798828 -288.666174) (xy 134.47014 -288.666174) (xy 134.469645 -288.690781) (xy 134.46175 -288.739358)
			(xy 134.446166 -288.786039) (xy 134.423295 -288.829616) (xy 134.39373 -288.86896) (xy 134.358237 -288.903052)
			(xy 134.317734 -288.931008) (xy 134.273272 -288.952106) (xy 134.226001 -288.965798) (xy 134.177146 -288.97173)
			(xy 134.127971 -288.969749) (xy 134.079752 -288.959905) (xy 134.033736 -288.942453) (xy 133.991115 -288.917846)
			(xy 133.952994 -288.886721) (xy 133.920359 -288.849884) (xy 133.894056 -288.808288) (xy 133.874765 -288.763012)
			(xy 133.862988 -288.715228) (xy 133.859028 -288.666174) (xy 133.5405 -288.666174) (xy 133.539988 -288.69162)
			(xy 133.531824 -288.741854) (xy 133.515708 -288.790128) (xy 133.492057 -288.835191) (xy 133.461484 -288.875877)
			(xy 133.42478 -288.911132) (xy 133.382896 -288.940042) (xy 133.336917 -288.961859) (xy 133.288033 -288.976019)
			(xy 133.237512 -288.982153) (xy 133.18666 -288.980104) (xy 133.136796 -288.969924) (xy 133.08921 -288.951877)
			(xy 133.045136 -288.926431) (xy 133.005714 -288.894244) (xy 132.971966 -288.85615) (xy 132.944765 -288.813136)
			(xy 132.924817 -288.766316) (xy 132.912638 -288.716902) (xy 132.908543 -288.666174) (xy 132.590032 -288.666174)
			(xy 132.589537 -288.690781) (xy 132.581642 -288.739358) (xy 132.566058 -288.786039) (xy 132.543187 -288.829616)
			(xy 132.513622 -288.86896) (xy 132.478129 -288.903052) (xy 132.437626 -288.931008) (xy 132.393164 -288.952106)
			(xy 132.345893 -288.965798) (xy 132.297038 -288.97173) (xy 132.247863 -288.969749) (xy 132.199644 -288.959905)
			(xy 132.153628 -288.942453) (xy 132.111007 -288.917846) (xy 132.072886 -288.886721) (xy 132.040251 -288.849884)
			(xy 132.013948 -288.808288) (xy 131.994657 -288.763012) (xy 131.98288 -288.715228) (xy 131.97892 -288.666174)
			(xy 131.660392 -288.666174) (xy 131.65988 -288.69162) (xy 131.651716 -288.741854) (xy 131.6356 -288.790128)
			(xy 131.611949 -288.835191) (xy 131.581376 -288.875877) (xy 131.544672 -288.911132) (xy 131.502788 -288.940042)
			(xy 131.456809 -288.961859) (xy 131.407925 -288.976019) (xy 131.357404 -288.982153) (xy 131.306552 -288.980104)
			(xy 131.256688 -288.969924) (xy 131.209102 -288.951877) (xy 131.165028 -288.926431) (xy 131.125606 -288.894244)
			(xy 131.091858 -288.85615) (xy 131.064657 -288.813136) (xy 131.044709 -288.766316) (xy 131.03253 -288.716902)
			(xy 131.028435 -288.666174) (xy 130.710178 -288.666174) (xy 130.709683 -288.690781) (xy 130.701788 -288.739358)
			(xy 130.686204 -288.786039) (xy 130.663333 -288.829616) (xy 130.633768 -288.86896) (xy 130.598275 -288.903052)
			(xy 130.557772 -288.931008) (xy 130.51331 -288.952106) (xy 130.466039 -288.965798) (xy 130.417184 -288.97173)
			(xy 130.368009 -288.969749) (xy 130.31979 -288.959905) (xy 130.273774 -288.942453) (xy 130.231153 -288.917846)
			(xy 130.193032 -288.886721) (xy 130.160397 -288.849884) (xy 130.134094 -288.808288) (xy 130.114803 -288.763012)
			(xy 130.103026 -288.715228) (xy 130.099066 -288.666174) (xy 129.780538 -288.666174) (xy 129.780026 -288.69162)
			(xy 129.771862 -288.741854) (xy 129.755746 -288.790128) (xy 129.732095 -288.835191) (xy 129.701522 -288.875877)
			(xy 129.664818 -288.911132) (xy 129.622934 -288.940042) (xy 129.576955 -288.961859) (xy 129.528071 -288.976019)
			(xy 129.47755 -288.982153) (xy 129.426698 -288.980104) (xy 129.376834 -288.969924) (xy 129.329248 -288.951877)
			(xy 129.285174 -288.926431) (xy 129.245752 -288.894244) (xy 129.212004 -288.85615) (xy 129.184803 -288.813136)
			(xy 129.164855 -288.766316) (xy 129.152676 -288.716902) (xy 129.148581 -288.666174) (xy 128.840484 -288.666174)
			(xy 128.839972 -288.69162) (xy 128.831808 -288.741854) (xy 128.815692 -288.790128) (xy 128.792041 -288.835191)
			(xy 128.761468 -288.875877) (xy 128.724764 -288.911132) (xy 128.68288 -288.940042) (xy 128.636901 -288.961859)
			(xy 128.588017 -288.976019) (xy 128.537496 -288.982153) (xy 128.486644 -288.980104) (xy 128.43678 -288.969924)
			(xy 128.389194 -288.951877) (xy 128.34512 -288.926431) (xy 128.305698 -288.894244) (xy 128.27195 -288.85615)
			(xy 128.244749 -288.813136) (xy 128.224801 -288.766316) (xy 128.212622 -288.716902) (xy 128.208527 -288.666174)
			(xy 127.916078 -288.666174) (xy 127.916078 -288.666178) (xy 127.912076 -288.717547) (xy 127.900159 -288.767675)
			(xy 127.880615 -288.815349) (xy 127.867664 -288.837624) (xy 127.863346 -288.844228) (xy 127.849158 -288.865577)
			(xy 127.815268 -288.904033) (xy 127.775866 -288.936819) (xy 127.754126 -288.9504) (xy 127.746097 -288.955642)
			(xy 127.734364 -288.970788) (xy 127.731266 -288.979864) (xy 127.716534 -289.028795) (xy 127.679414 -289.124009)
			(xy 127.633847 -289.215481) (xy 127.580205 -289.302465) (xy 127.518927 -289.38425) (xy 127.48514 -289.422586)
			(xy 127.47879 -289.429698) (xy 127.472186 -289.44697) (xy 127.472186 -289.47618) (xy 127.738627 -289.47618)
			(xy 127.742722 -289.425452) (xy 127.754901 -289.376038) (xy 127.774849 -289.329218) (xy 127.80205 -289.286204)
			(xy 127.835798 -289.24811) (xy 127.87522 -289.215923) (xy 127.919294 -289.190477) (xy 127.96688 -289.17243)
			(xy 128.016744 -289.16225) (xy 128.067596 -289.160201) (xy 128.118117 -289.166335) (xy 128.167001 -289.180495)
			(xy 128.21298 -289.202312) (xy 128.254864 -289.231222) (xy 128.291568 -289.266477) (xy 128.322141 -289.307163)
			(xy 128.345792 -289.352226) (xy 128.361908 -289.4005) (xy 128.370072 -289.450734) (xy 128.370584 -289.47618)
			(xy 128.688858 -289.47618) (xy 128.692818 -289.427126) (xy 128.704595 -289.379342) (xy 128.723886 -289.334066)
			(xy 128.750189 -289.29247) (xy 128.782824 -289.255633) (xy 128.820945 -289.224508) (xy 128.863566 -289.199901)
			(xy 128.909582 -289.182449) (xy 128.957801 -289.172605) (xy 129.006976 -289.170624) (xy 129.055831 -289.176556)
			(xy 129.103102 -289.190248) (xy 129.147564 -289.211346) (xy 129.188067 -289.239302) (xy 129.22356 -289.273394)
			(xy 129.253125 -289.312738) (xy 129.275996 -289.356315) (xy 129.29158 -289.402996) (xy 129.299475 -289.451573)
			(xy 129.29997 -289.47618) (xy 129.618481 -289.47618) (xy 129.622576 -289.425452) (xy 129.634755 -289.376038)
			(xy 129.654703 -289.329218) (xy 129.681904 -289.286204) (xy 129.715652 -289.24811) (xy 129.755074 -289.215923)
			(xy 129.799148 -289.190477) (xy 129.846734 -289.17243) (xy 129.896598 -289.16225) (xy 129.94745 -289.160201)
			(xy 129.997971 -289.166335) (xy 130.046855 -289.180495) (xy 130.092834 -289.202312) (xy 130.134718 -289.231222)
			(xy 130.171422 -289.266477) (xy 130.201995 -289.307163) (xy 130.225646 -289.352226) (xy 130.241762 -289.4005)
			(xy 130.249926 -289.450734) (xy 130.250438 -289.47618) (xy 130.568966 -289.47618) (xy 130.572926 -289.427126)
			(xy 130.584703 -289.379342) (xy 130.603994 -289.334066) (xy 130.630297 -289.29247) (xy 130.662932 -289.255633)
			(xy 130.701053 -289.224508) (xy 130.743674 -289.199901) (xy 130.78969 -289.182449) (xy 130.837909 -289.172605)
			(xy 130.887084 -289.170624) (xy 130.935939 -289.176556) (xy 130.98321 -289.190248) (xy 131.027672 -289.211346)
			(xy 131.068175 -289.239302) (xy 131.103668 -289.273394) (xy 131.133233 -289.312738) (xy 131.156104 -289.356315)
			(xy 131.171688 -289.402996) (xy 131.179583 -289.451573) (xy 131.180078 -289.47618) (xy 131.498589 -289.47618)
			(xy 131.502684 -289.425452) (xy 131.514863 -289.376038) (xy 131.534811 -289.329218) (xy 131.562012 -289.286204)
			(xy 131.59576 -289.24811) (xy 131.635182 -289.215923) (xy 131.679256 -289.190477) (xy 131.726842 -289.17243)
			(xy 131.776706 -289.16225) (xy 131.827558 -289.160201) (xy 131.878079 -289.166335) (xy 131.926963 -289.180495)
			(xy 131.972942 -289.202312) (xy 132.014826 -289.231222) (xy 132.05153 -289.266477) (xy 132.082103 -289.307163)
			(xy 132.105754 -289.352226) (xy 132.12187 -289.4005) (xy 132.130034 -289.450734) (xy 132.130546 -289.47618)
			(xy 132.438643 -289.47618) (xy 132.442738 -289.425452) (xy 132.454917 -289.376038) (xy 132.474865 -289.329218)
			(xy 132.502066 -289.286204) (xy 132.535814 -289.24811) (xy 132.575236 -289.215923) (xy 132.61931 -289.190477)
			(xy 132.666896 -289.17243) (xy 132.71676 -289.16225) (xy 132.767612 -289.160201) (xy 132.818133 -289.166335)
			(xy 132.867017 -289.180495) (xy 132.912996 -289.202312) (xy 132.95488 -289.231222) (xy 132.991584 -289.266477)
			(xy 133.022157 -289.307163) (xy 133.045808 -289.352226) (xy 133.061924 -289.4005) (xy 133.070088 -289.450734)
			(xy 133.0706 -289.47618) (xy 133.388874 -289.47618) (xy 133.392834 -289.427126) (xy 133.404611 -289.379342)
			(xy 133.423902 -289.334066) (xy 133.450205 -289.29247) (xy 133.48284 -289.255633) (xy 133.520961 -289.224508)
			(xy 133.563582 -289.199901) (xy 133.609598 -289.182449) (xy 133.657817 -289.172605) (xy 133.706992 -289.170624)
			(xy 133.755847 -289.176556) (xy 133.803118 -289.190248) (xy 133.84758 -289.211346) (xy 133.888083 -289.239302)
			(xy 133.923576 -289.273394) (xy 133.953141 -289.312738) (xy 133.976012 -289.356315) (xy 133.991596 -289.402996)
			(xy 133.999491 -289.451573) (xy 133.999986 -289.47618) (xy 134.328928 -289.47618) (xy 134.332888 -289.427126)
			(xy 134.344665 -289.379342) (xy 134.363956 -289.334066) (xy 134.390259 -289.29247) (xy 134.422894 -289.255633)
			(xy 134.461015 -289.224508) (xy 134.503636 -289.199901) (xy 134.549652 -289.182449) (xy 134.597871 -289.172605)
			(xy 134.647046 -289.170624) (xy 134.695901 -289.176556) (xy 134.743172 -289.190248) (xy 134.787634 -289.211346)
			(xy 134.828137 -289.239302) (xy 134.86363 -289.273394) (xy 134.893195 -289.312738) (xy 134.916066 -289.356315)
			(xy 134.93165 -289.402996) (xy 134.939545 -289.451573) (xy 134.94004 -289.47618) (xy 135.268982 -289.47618)
			(xy 135.272942 -289.427126) (xy 135.284719 -289.379342) (xy 135.30401 -289.334066) (xy 135.330313 -289.29247)
			(xy 135.362948 -289.255633) (xy 135.401069 -289.224508) (xy 135.44369 -289.199901) (xy 135.489706 -289.182449)
			(xy 135.537925 -289.172605) (xy 135.5871 -289.170624) (xy 135.635955 -289.176556) (xy 135.683226 -289.190248)
			(xy 135.727688 -289.211346) (xy 135.768191 -289.239302) (xy 135.803684 -289.273394) (xy 135.833249 -289.312738)
			(xy 135.85612 -289.356315) (xy 135.871704 -289.402996) (xy 135.879599 -289.451573) (xy 135.880094 -289.47618)
			(xy 136.209036 -289.47618) (xy 136.212996 -289.427126) (xy 136.224773 -289.379342) (xy 136.244064 -289.334066)
			(xy 136.270367 -289.29247) (xy 136.303002 -289.255633) (xy 136.341123 -289.224508) (xy 136.383744 -289.199901)
			(xy 136.42976 -289.182449) (xy 136.477979 -289.172605) (xy 136.527154 -289.170624) (xy 136.576009 -289.176556)
			(xy 136.62328 -289.190248) (xy 136.667742 -289.211346) (xy 136.708245 -289.239302) (xy 136.743738 -289.273394)
			(xy 136.773303 -289.312738) (xy 136.796174 -289.356315) (xy 136.811758 -289.402996) (xy 136.819653 -289.451573)
			(xy 136.820148 -289.47618) (xy 136.819653 -289.500787) (xy 136.811758 -289.549364) (xy 136.796174 -289.596045)
			(xy 136.773303 -289.639622) (xy 136.743738 -289.678966) (xy 136.708245 -289.713058) (xy 136.667742 -289.741014)
			(xy 136.62328 -289.762112) (xy 136.576009 -289.775804) (xy 136.527154 -289.781736) (xy 136.477979 -289.779755)
			(xy 136.42976 -289.769911) (xy 136.383744 -289.752459) (xy 136.341123 -289.727852) (xy 136.303002 -289.696727)
			(xy 136.270367 -289.65989) (xy 136.244064 -289.618294) (xy 136.224773 -289.573018) (xy 136.212996 -289.525234)
			(xy 136.209036 -289.47618) (xy 135.880094 -289.47618) (xy 135.879599 -289.500787) (xy 135.871704 -289.549364)
			(xy 135.85612 -289.596045) (xy 135.833249 -289.639622) (xy 135.803684 -289.678966) (xy 135.768191 -289.713058)
			(xy 135.727688 -289.741014) (xy 135.683226 -289.762112) (xy 135.635955 -289.775804) (xy 135.5871 -289.781736)
			(xy 135.537925 -289.779755) (xy 135.489706 -289.769911) (xy 135.44369 -289.752459) (xy 135.401069 -289.727852)
			(xy 135.362948 -289.696727) (xy 135.330313 -289.65989) (xy 135.30401 -289.618294) (xy 135.284719 -289.573018)
			(xy 135.272942 -289.525234) (xy 135.268982 -289.47618) (xy 134.94004 -289.47618) (xy 134.939545 -289.500787)
			(xy 134.93165 -289.549364) (xy 134.916066 -289.596045) (xy 134.893195 -289.639622) (xy 134.86363 -289.678966)
			(xy 134.828137 -289.713058) (xy 134.787634 -289.741014) (xy 134.743172 -289.762112) (xy 134.695901 -289.775804)
			(xy 134.647046 -289.781736) (xy 134.597871 -289.779755) (xy 134.549652 -289.769911) (xy 134.503636 -289.752459)
			(xy 134.461015 -289.727852) (xy 134.422894 -289.696727) (xy 134.390259 -289.65989) (xy 134.363956 -289.618294)
			(xy 134.344665 -289.573018) (xy 134.332888 -289.525234) (xy 134.328928 -289.47618) (xy 133.999986 -289.47618)
			(xy 133.999491 -289.500787) (xy 133.991596 -289.549364) (xy 133.976012 -289.596045) (xy 133.953141 -289.639622)
			(xy 133.923576 -289.678966) (xy 133.888083 -289.713058) (xy 133.84758 -289.741014) (xy 133.803118 -289.762112)
			(xy 133.755847 -289.775804) (xy 133.706992 -289.781736) (xy 133.657817 -289.779755) (xy 133.609598 -289.769911)
			(xy 133.563582 -289.752459) (xy 133.520961 -289.727852) (xy 133.48284 -289.696727) (xy 133.450205 -289.65989)
			(xy 133.423902 -289.618294) (xy 133.404611 -289.573018) (xy 133.392834 -289.525234) (xy 133.388874 -289.47618)
			(xy 133.0706 -289.47618) (xy 133.070088 -289.501626) (xy 133.061924 -289.55186) (xy 133.045808 -289.600134)
			(xy 133.022157 -289.645197) (xy 132.991584 -289.685883) (xy 132.95488 -289.721138) (xy 132.912996 -289.750048)
			(xy 132.867017 -289.771865) (xy 132.818133 -289.786025) (xy 132.767612 -289.792159) (xy 132.71676 -289.79011)
			(xy 132.666896 -289.77993) (xy 132.61931 -289.761883) (xy 132.575236 -289.736437) (xy 132.535814 -289.70425)
			(xy 132.502066 -289.666156) (xy 132.474865 -289.623142) (xy 132.454917 -289.576322) (xy 132.442738 -289.526908)
			(xy 132.438643 -289.47618) (xy 132.130546 -289.47618) (xy 132.130034 -289.501626) (xy 132.12187 -289.55186)
			(xy 132.105754 -289.600134) (xy 132.082103 -289.645197) (xy 132.05153 -289.685883) (xy 132.014826 -289.721138)
			(xy 131.972942 -289.750048) (xy 131.926963 -289.771865) (xy 131.878079 -289.786025) (xy 131.827558 -289.792159)
			(xy 131.776706 -289.79011) (xy 131.726842 -289.77993) (xy 131.679256 -289.761883) (xy 131.635182 -289.736437)
			(xy 131.59576 -289.70425) (xy 131.562012 -289.666156) (xy 131.534811 -289.623142) (xy 131.514863 -289.576322)
			(xy 131.502684 -289.526908) (xy 131.498589 -289.47618) (xy 131.180078 -289.47618) (xy 131.179583 -289.500787)
			(xy 131.171688 -289.549364) (xy 131.156104 -289.596045) (xy 131.133233 -289.639622) (xy 131.103668 -289.678966)
			(xy 131.068175 -289.713058) (xy 131.027672 -289.741014) (xy 130.98321 -289.762112) (xy 130.935939 -289.775804)
			(xy 130.887084 -289.781736) (xy 130.837909 -289.779755) (xy 130.78969 -289.769911) (xy 130.743674 -289.752459)
			(xy 130.701053 -289.727852) (xy 130.662932 -289.696727) (xy 130.630297 -289.65989) (xy 130.603994 -289.618294)
			(xy 130.584703 -289.573018) (xy 130.572926 -289.525234) (xy 130.568966 -289.47618) (xy 130.250438 -289.47618)
			(xy 130.249926 -289.501626) (xy 130.241762 -289.55186) (xy 130.225646 -289.600134) (xy 130.201995 -289.645197)
			(xy 130.171422 -289.685883) (xy 130.134718 -289.721138) (xy 130.092834 -289.750048) (xy 130.046855 -289.771865)
			(xy 129.997971 -289.786025) (xy 129.94745 -289.792159) (xy 129.896598 -289.79011) (xy 129.846734 -289.77993)
			(xy 129.799148 -289.761883) (xy 129.755074 -289.736437) (xy 129.715652 -289.70425) (xy 129.681904 -289.666156)
			(xy 129.654703 -289.623142) (xy 129.634755 -289.576322) (xy 129.622576 -289.526908) (xy 129.618481 -289.47618)
			(xy 129.29997 -289.47618) (xy 129.299475 -289.500787) (xy 129.29158 -289.549364) (xy 129.275996 -289.596045)
			(xy 129.253125 -289.639622) (xy 129.22356 -289.678966) (xy 129.188067 -289.713058) (xy 129.147564 -289.741014)
			(xy 129.103102 -289.762112) (xy 129.055831 -289.775804) (xy 129.006976 -289.781736) (xy 128.957801 -289.779755)
			(xy 128.909582 -289.769911) (xy 128.863566 -289.752459) (xy 128.820945 -289.727852) (xy 128.782824 -289.696727)
			(xy 128.750189 -289.65989) (xy 128.723886 -289.618294) (xy 128.704595 -289.573018) (xy 128.692818 -289.525234)
			(xy 128.688858 -289.47618) (xy 128.370584 -289.47618) (xy 128.370072 -289.501626) (xy 128.361908 -289.55186)
			(xy 128.345792 -289.600134) (xy 128.322141 -289.645197) (xy 128.291568 -289.685883) (xy 128.254864 -289.721138)
			(xy 128.21298 -289.750048) (xy 128.167001 -289.771865) (xy 128.118117 -289.786025) (xy 128.067596 -289.792159)
			(xy 128.016744 -289.79011) (xy 127.96688 -289.77993) (xy 127.919294 -289.761883) (xy 127.87522 -289.736437)
			(xy 127.835798 -289.70425) (xy 127.80205 -289.666156) (xy 127.774849 -289.623142) (xy 127.754901 -289.576322)
			(xy 127.742722 -289.526908) (xy 127.738627 -289.47618) (xy 127.472186 -289.47618) (xy 127.472186 -289.50539)
			(xy 127.47879 -289.522662) (xy 127.48514 -289.529774) (xy 127.515327 -289.563981) (xy 127.570706 -289.636493)
			(xy 127.620061 -289.713232) (xy 127.663071 -289.793698) (xy 127.699457 -289.87737) (xy 127.728981 -289.963701)
			(xy 127.740664 -290.007802) (xy 127.743266 -290.01645) (xy 127.753549 -290.031282) (xy 127.76073 -290.036758)
			(xy 127.780345 -290.051181) (xy 127.815163 -290.085209) (xy 127.844142 -290.124329) (xy 127.866549 -290.16755)
			(xy 127.881816 -290.213779) (xy 127.889557 -290.261844) (xy 127.890016 -290.286186) (xy 128.208527 -290.286186)
			(xy 128.212622 -290.235458) (xy 128.224801 -290.186044) (xy 128.244749 -290.139224) (xy 128.27195 -290.09621)
			(xy 128.305698 -290.058116) (xy 128.34512 -290.025929) (xy 128.389194 -290.000483) (xy 128.43678 -289.982436)
			(xy 128.486644 -289.972256) (xy 128.537496 -289.970207) (xy 128.588017 -289.976341) (xy 128.636901 -289.990501)
			(xy 128.68288 -290.012318) (xy 128.724764 -290.041228) (xy 128.761468 -290.076483) (xy 128.792041 -290.117169)
			(xy 128.815692 -290.162232) (xy 128.831808 -290.210506) (xy 128.839972 -290.26074) (xy 128.840484 -290.286186)
			(xy 129.148581 -290.286186) (xy 129.152676 -290.235458) (xy 129.164855 -290.186044) (xy 129.184803 -290.139224)
			(xy 129.212004 -290.09621) (xy 129.245752 -290.058116) (xy 129.285174 -290.025929) (xy 129.329248 -290.000483)
			(xy 129.376834 -289.982436) (xy 129.426698 -289.972256) (xy 129.47755 -289.970207) (xy 129.528071 -289.976341)
			(xy 129.576955 -289.990501) (xy 129.622934 -290.012318) (xy 129.664818 -290.041228) (xy 129.701522 -290.076483)
			(xy 129.732095 -290.117169) (xy 129.755746 -290.162232) (xy 129.771862 -290.210506) (xy 129.780026 -290.26074)
			(xy 129.780538 -290.286186) (xy 131.028435 -290.286186) (xy 131.03253 -290.235458) (xy 131.044709 -290.186044)
			(xy 131.064657 -290.139224) (xy 131.091858 -290.09621) (xy 131.125606 -290.058116) (xy 131.165028 -290.025929)
			(xy 131.209102 -290.000483) (xy 131.256688 -289.982436) (xy 131.306552 -289.972256) (xy 131.357404 -289.970207)
			(xy 131.407925 -289.976341) (xy 131.456809 -289.990501) (xy 131.502788 -290.012318) (xy 131.544672 -290.041228)
			(xy 131.581376 -290.076483) (xy 131.611949 -290.117169) (xy 131.6356 -290.162232) (xy 131.651716 -290.210506)
			(xy 131.65988 -290.26074) (xy 131.660392 -290.286186) (xy 131.97892 -290.286186) (xy 131.98288 -290.237132)
			(xy 131.994657 -290.189348) (xy 132.013948 -290.144072) (xy 132.040251 -290.102476) (xy 132.072886 -290.065639)
			(xy 132.111007 -290.034514) (xy 132.153628 -290.009907) (xy 132.199644 -289.992455) (xy 132.247863 -289.982611)
			(xy 132.297038 -289.98063) (xy 132.345893 -289.986562) (xy 132.393164 -290.000254) (xy 132.437626 -290.021352)
			(xy 132.478129 -290.049308) (xy 132.513622 -290.0834) (xy 132.543187 -290.122744) (xy 132.566058 -290.166321)
			(xy 132.581642 -290.213002) (xy 132.589537 -290.261579) (xy 132.590032 -290.286186) (xy 132.908543 -290.286186)
			(xy 132.912638 -290.235458) (xy 132.924817 -290.186044) (xy 132.944765 -290.139224) (xy 132.971966 -290.09621)
			(xy 133.005714 -290.058116) (xy 133.045136 -290.025929) (xy 133.08921 -290.000483) (xy 133.136796 -289.982436)
			(xy 133.18666 -289.972256) (xy 133.237512 -289.970207) (xy 133.288033 -289.976341) (xy 133.336917 -289.990501)
			(xy 133.382896 -290.012318) (xy 133.42478 -290.041228) (xy 133.461484 -290.076483) (xy 133.492057 -290.117169)
			(xy 133.515708 -290.162232) (xy 133.531824 -290.210506) (xy 133.539988 -290.26074) (xy 133.5405 -290.286186)
			(xy 133.859028 -290.286186) (xy 133.862988 -290.237132) (xy 133.874765 -290.189348) (xy 133.894056 -290.144072)
			(xy 133.920359 -290.102476) (xy 133.952994 -290.065639) (xy 133.991115 -290.034514) (xy 134.033736 -290.009907)
			(xy 134.079752 -289.992455) (xy 134.127971 -289.982611) (xy 134.177146 -289.98063) (xy 134.226001 -289.986562)
			(xy 134.273272 -290.000254) (xy 134.317734 -290.021352) (xy 134.358237 -290.049308) (xy 134.39373 -290.0834)
			(xy 134.423295 -290.122744) (xy 134.446166 -290.166321) (xy 134.46175 -290.213002) (xy 134.469645 -290.261579)
			(xy 134.47014 -290.286186) (xy 134.798828 -290.286186) (xy 134.802788 -290.237132) (xy 134.814565 -290.189348)
			(xy 134.833856 -290.144072) (xy 134.860159 -290.102476) (xy 134.892794 -290.065639) (xy 134.930915 -290.034514)
			(xy 134.973536 -290.009907) (xy 135.019552 -289.992455) (xy 135.067771 -289.982611) (xy 135.116946 -289.98063)
			(xy 135.165801 -289.986562) (xy 135.213072 -290.000254) (xy 135.257534 -290.021352) (xy 135.298037 -290.049308)
			(xy 135.33353 -290.0834) (xy 135.363095 -290.122744) (xy 135.385966 -290.166321) (xy 135.40155 -290.213002)
			(xy 135.409445 -290.261579) (xy 135.40994 -290.286186) (xy 135.738882 -290.286186) (xy 135.742842 -290.237132)
			(xy 135.754619 -290.189348) (xy 135.77391 -290.144072) (xy 135.800213 -290.102476) (xy 135.832848 -290.065639)
			(xy 135.870969 -290.034514) (xy 135.91359 -290.009907) (xy 135.959606 -289.992455) (xy 136.007825 -289.982611)
			(xy 136.057 -289.98063) (xy 136.105855 -289.986562) (xy 136.153126 -290.000254) (xy 136.197588 -290.021352)
			(xy 136.238091 -290.049308) (xy 136.273584 -290.0834) (xy 136.303149 -290.122744) (xy 136.32602 -290.166321)
			(xy 136.341604 -290.213002) (xy 136.349499 -290.261579) (xy 136.349994 -290.286186) (xy 136.349499 -290.310793)
			(xy 136.341604 -290.35937) (xy 136.32602 -290.406051) (xy 136.303149 -290.449628) (xy 136.273584 -290.488972)
			(xy 136.238091 -290.523064) (xy 136.197588 -290.55102) (xy 136.153126 -290.572118) (xy 136.105855 -290.58581)
			(xy 136.057 -290.591742) (xy 136.007825 -290.589761) (xy 135.959606 -290.579917) (xy 135.91359 -290.562465)
			(xy 135.870969 -290.537858) (xy 135.832848 -290.506733) (xy 135.800213 -290.469896) (xy 135.77391 -290.4283)
			(xy 135.754619 -290.383024) (xy 135.742842 -290.33524) (xy 135.738882 -290.286186) (xy 135.40994 -290.286186)
			(xy 135.409445 -290.310793) (xy 135.40155 -290.35937) (xy 135.385966 -290.406051) (xy 135.363095 -290.449628)
			(xy 135.33353 -290.488972) (xy 135.298037 -290.523064) (xy 135.257534 -290.55102) (xy 135.213072 -290.572118)
			(xy 135.165801 -290.58581) (xy 135.116946 -290.591742) (xy 135.067771 -290.589761) (xy 135.019552 -290.579917)
			(xy 134.973536 -290.562465) (xy 134.930915 -290.537858) (xy 134.892794 -290.506733) (xy 134.860159 -290.469896)
			(xy 134.833856 -290.4283) (xy 134.814565 -290.383024) (xy 134.802788 -290.33524) (xy 134.798828 -290.286186)
			(xy 134.47014 -290.286186) (xy 134.469645 -290.310793) (xy 134.46175 -290.35937) (xy 134.446166 -290.406051)
			(xy 134.423295 -290.449628) (xy 134.39373 -290.488972) (xy 134.358237 -290.523064) (xy 134.317734 -290.55102)
			(xy 134.273272 -290.572118) (xy 134.226001 -290.58581) (xy 134.177146 -290.591742) (xy 134.127971 -290.589761)
			(xy 134.079752 -290.579917) (xy 134.033736 -290.562465) (xy 133.991115 -290.537858) (xy 133.952994 -290.506733)
			(xy 133.920359 -290.469896) (xy 133.894056 -290.4283) (xy 133.874765 -290.383024) (xy 133.862988 -290.33524)
			(xy 133.859028 -290.286186) (xy 133.5405 -290.286186) (xy 133.539988 -290.311632) (xy 133.531824 -290.361866)
			(xy 133.515708 -290.41014) (xy 133.492057 -290.455203) (xy 133.461484 -290.495889) (xy 133.42478 -290.531144)
			(xy 133.382896 -290.560054) (xy 133.336917 -290.581871) (xy 133.288033 -290.596031) (xy 133.237512 -290.602165)
			(xy 133.18666 -290.600116) (xy 133.136796 -290.589936) (xy 133.08921 -290.571889) (xy 133.045136 -290.546443)
			(xy 133.005714 -290.514256) (xy 132.971966 -290.476162) (xy 132.944765 -290.433148) (xy 132.924817 -290.386328)
			(xy 132.912638 -290.336914) (xy 132.908543 -290.286186) (xy 132.590032 -290.286186) (xy 132.589537 -290.310793)
			(xy 132.581642 -290.35937) (xy 132.566058 -290.406051) (xy 132.543187 -290.449628) (xy 132.513622 -290.488972)
			(xy 132.478129 -290.523064) (xy 132.437626 -290.55102) (xy 132.393164 -290.572118) (xy 132.345893 -290.58581)
			(xy 132.297038 -290.591742) (xy 132.247863 -290.589761) (xy 132.199644 -290.579917) (xy 132.153628 -290.562465)
			(xy 132.111007 -290.537858) (xy 132.072886 -290.506733) (xy 132.040251 -290.469896) (xy 132.013948 -290.4283)
			(xy 131.994657 -290.383024) (xy 131.98288 -290.33524) (xy 131.97892 -290.286186) (xy 131.660392 -290.286186)
			(xy 131.65988 -290.311632) (xy 131.651716 -290.361866) (xy 131.6356 -290.41014) (xy 131.611949 -290.455203)
			(xy 131.581376 -290.495889) (xy 131.544672 -290.531144) (xy 131.502788 -290.560054) (xy 131.456809 -290.581871)
			(xy 131.407925 -290.596031) (xy 131.357404 -290.602165) (xy 131.306552 -290.600116) (xy 131.256688 -290.589936)
			(xy 131.209102 -290.571889) (xy 131.165028 -290.546443) (xy 131.125606 -290.514256) (xy 131.091858 -290.476162)
			(xy 131.064657 -290.433148) (xy 131.044709 -290.386328) (xy 131.03253 -290.336914) (xy 131.028435 -290.286186)
			(xy 129.780538 -290.286186) (xy 129.780026 -290.311632) (xy 129.771862 -290.361866) (xy 129.755746 -290.41014)
			(xy 129.732095 -290.455203) (xy 129.701522 -290.495889) (xy 129.664818 -290.531144) (xy 129.622934 -290.560054)
			(xy 129.576955 -290.581871) (xy 129.528071 -290.596031) (xy 129.47755 -290.602165) (xy 129.426698 -290.600116)
			(xy 129.376834 -290.589936) (xy 129.329248 -290.571889) (xy 129.285174 -290.546443) (xy 129.245752 -290.514256)
			(xy 129.212004 -290.476162) (xy 129.184803 -290.433148) (xy 129.164855 -290.386328) (xy 129.152676 -290.336914)
			(xy 129.148581 -290.286186) (xy 128.840484 -290.286186) (xy 128.839972 -290.311632) (xy 128.831808 -290.361866)
			(xy 128.815692 -290.41014) (xy 128.792041 -290.455203) (xy 128.761468 -290.495889) (xy 128.724764 -290.531144)
			(xy 128.68288 -290.560054) (xy 128.636901 -290.581871) (xy 128.588017 -290.596031) (xy 128.537496 -290.602165)
			(xy 128.486644 -290.600116) (xy 128.43678 -290.589936) (xy 128.389194 -290.571889) (xy 128.34512 -290.546443)
			(xy 128.305698 -290.514256) (xy 128.27195 -290.476162) (xy 128.244749 -290.433148) (xy 128.224801 -290.386328)
			(xy 128.212622 -290.336914) (xy 128.208527 -290.286186) (xy 127.890016 -290.286186) (xy 127.889576 -290.309527)
			(xy 127.882481 -290.355665) (xy 127.868455 -290.400189) (xy 127.85852 -290.421314) (xy 127.856742 -290.42487)
			(xy 127.845113 -290.446651) (xy 127.815899 -290.486453) (xy 127.780643 -290.521016) (xy 127.76073 -290.535614)
			(xy 127.753551 -290.541091) (xy 127.74328 -290.555927) (xy 127.740664 -290.56457) (xy 127.728997 -290.608676)
			(xy 127.699478 -290.695011) (xy 127.663095 -290.778686) (xy 127.620085 -290.859155) (xy 127.570727 -290.935894)
			(xy 127.515344 -291.008404) (xy 127.48514 -291.042598) (xy 127.47879 -291.04971) (xy 127.472186 -291.066982)
			(xy 127.472186 -291.096192) (xy 127.738627 -291.096192) (xy 127.742722 -291.045464) (xy 127.754901 -290.99605)
			(xy 127.774849 -290.94923) (xy 127.80205 -290.906216) (xy 127.835798 -290.868122) (xy 127.87522 -290.835935)
			(xy 127.919294 -290.810489) (xy 127.96688 -290.792442) (xy 128.016744 -290.782262) (xy 128.067596 -290.780213)
			(xy 128.118117 -290.786347) (xy 128.167001 -290.800507) (xy 128.21298 -290.822324) (xy 128.254864 -290.851234)
			(xy 128.291568 -290.886489) (xy 128.322141 -290.927175) (xy 128.345792 -290.972238) (xy 128.361908 -291.020512)
			(xy 128.370072 -291.070746) (xy 128.370584 -291.096192) (xy 128.688858 -291.096192) (xy 128.692818 -291.047138)
			(xy 128.704595 -290.999354) (xy 128.723886 -290.954078) (xy 128.750189 -290.912482) (xy 128.782824 -290.875645)
			(xy 128.820945 -290.84452) (xy 128.863566 -290.819913) (xy 128.909582 -290.802461) (xy 128.957801 -290.792617)
			(xy 129.006976 -290.790636) (xy 129.055831 -290.796568) (xy 129.103102 -290.81026) (xy 129.147564 -290.831358)
			(xy 129.188067 -290.859314) (xy 129.22356 -290.893406) (xy 129.253125 -290.93275) (xy 129.275996 -290.976327)
			(xy 129.29158 -291.023008) (xy 129.299475 -291.071585) (xy 129.29997 -291.096192) (xy 129.618481 -291.096192)
			(xy 129.622576 -291.045464) (xy 129.634755 -290.99605) (xy 129.654703 -290.94923) (xy 129.681904 -290.906216)
			(xy 129.715652 -290.868122) (xy 129.755074 -290.835935) (xy 129.799148 -290.810489) (xy 129.846734 -290.792442)
			(xy 129.896598 -290.782262) (xy 129.94745 -290.780213) (xy 129.997971 -290.786347) (xy 130.046855 -290.800507)
			(xy 130.092834 -290.822324) (xy 130.134718 -290.851234) (xy 130.171422 -290.886489) (xy 130.201995 -290.927175)
			(xy 130.225646 -290.972238) (xy 130.241762 -291.020512) (xy 130.249926 -291.070746) (xy 130.250438 -291.096192)
			(xy 130.568966 -291.096192) (xy 130.572926 -291.047138) (xy 130.584703 -290.999354) (xy 130.603994 -290.954078)
			(xy 130.630297 -290.912482) (xy 130.662932 -290.875645) (xy 130.701053 -290.84452) (xy 130.743674 -290.819913)
			(xy 130.78969 -290.802461) (xy 130.837909 -290.792617) (xy 130.887084 -290.790636) (xy 130.935939 -290.796568)
			(xy 130.98321 -290.81026) (xy 131.027672 -290.831358) (xy 131.068175 -290.859314) (xy 131.103668 -290.893406)
			(xy 131.133233 -290.93275) (xy 131.156104 -290.976327) (xy 131.171688 -291.023008) (xy 131.179583 -291.071585)
			(xy 131.180078 -291.096192) (xy 131.498589 -291.096192) (xy 131.502684 -291.045464) (xy 131.514863 -290.99605)
			(xy 131.534811 -290.94923) (xy 131.562012 -290.906216) (xy 131.59576 -290.868122) (xy 131.635182 -290.835935)
			(xy 131.679256 -290.810489) (xy 131.726842 -290.792442) (xy 131.776706 -290.782262) (xy 131.827558 -290.780213)
			(xy 131.878079 -290.786347) (xy 131.926963 -290.800507) (xy 131.972942 -290.822324) (xy 132.014826 -290.851234)
			(xy 132.05153 -290.886489) (xy 132.082103 -290.927175) (xy 132.105754 -290.972238) (xy 132.12187 -291.020512)
			(xy 132.130034 -291.070746) (xy 132.130546 -291.096192) (xy 132.438643 -291.096192) (xy 132.442738 -291.045464)
			(xy 132.454917 -290.99605) (xy 132.474865 -290.94923) (xy 132.502066 -290.906216) (xy 132.535814 -290.868122)
			(xy 132.575236 -290.835935) (xy 132.61931 -290.810489) (xy 132.666896 -290.792442) (xy 132.71676 -290.782262)
			(xy 132.767612 -290.780213) (xy 132.818133 -290.786347) (xy 132.867017 -290.800507) (xy 132.912996 -290.822324)
			(xy 132.95488 -290.851234) (xy 132.991584 -290.886489) (xy 133.022157 -290.927175) (xy 133.045808 -290.972238)
			(xy 133.061924 -291.020512) (xy 133.070088 -291.070746) (xy 133.0706 -291.096192) (xy 133.388874 -291.096192)
			(xy 133.392834 -291.047138) (xy 133.404611 -290.999354) (xy 133.423902 -290.954078) (xy 133.450205 -290.912482)
			(xy 133.48284 -290.875645) (xy 133.520961 -290.84452) (xy 133.563582 -290.819913) (xy 133.609598 -290.802461)
			(xy 133.657817 -290.792617) (xy 133.706992 -290.790636) (xy 133.755847 -290.796568) (xy 133.803118 -290.81026)
			(xy 133.84758 -290.831358) (xy 133.888083 -290.859314) (xy 133.923576 -290.893406) (xy 133.953141 -290.93275)
			(xy 133.976012 -290.976327) (xy 133.991596 -291.023008) (xy 133.999491 -291.071585) (xy 133.999986 -291.096192)
			(xy 134.328928 -291.096192) (xy 134.332888 -291.047138) (xy 134.344665 -290.999354) (xy 134.363956 -290.954078)
			(xy 134.390259 -290.912482) (xy 134.422894 -290.875645) (xy 134.461015 -290.84452) (xy 134.503636 -290.819913)
			(xy 134.549652 -290.802461) (xy 134.597871 -290.792617) (xy 134.647046 -290.790636) (xy 134.695901 -290.796568)
			(xy 134.743172 -290.81026) (xy 134.787634 -290.831358) (xy 134.828137 -290.859314) (xy 134.86363 -290.893406)
			(xy 134.893195 -290.93275) (xy 134.916066 -290.976327) (xy 134.93165 -291.023008) (xy 134.939545 -291.071585)
			(xy 134.94004 -291.096192) (xy 135.268982 -291.096192) (xy 135.272942 -291.047138) (xy 135.284719 -290.999354)
			(xy 135.30401 -290.954078) (xy 135.330313 -290.912482) (xy 135.362948 -290.875645) (xy 135.401069 -290.84452)
			(xy 135.44369 -290.819913) (xy 135.489706 -290.802461) (xy 135.537925 -290.792617) (xy 135.5871 -290.790636)
			(xy 135.635955 -290.796568) (xy 135.683226 -290.81026) (xy 135.727688 -290.831358) (xy 135.768191 -290.859314)
			(xy 135.803684 -290.893406) (xy 135.833249 -290.93275) (xy 135.85612 -290.976327) (xy 135.871704 -291.023008)
			(xy 135.879599 -291.071585) (xy 135.880094 -291.096192) (xy 136.209036 -291.096192) (xy 136.212996 -291.047138)
			(xy 136.224773 -290.999354) (xy 136.244064 -290.954078) (xy 136.270367 -290.912482) (xy 136.303002 -290.875645)
			(xy 136.341123 -290.84452) (xy 136.383744 -290.819913) (xy 136.42976 -290.802461) (xy 136.477979 -290.792617)
			(xy 136.527154 -290.790636) (xy 136.576009 -290.796568) (xy 136.62328 -290.81026) (xy 136.667742 -290.831358)
			(xy 136.708245 -290.859314) (xy 136.743738 -290.893406) (xy 136.773303 -290.93275) (xy 136.796174 -290.976327)
			(xy 136.811758 -291.023008) (xy 136.819653 -291.071585) (xy 136.820148 -291.096192) (xy 136.819653 -291.120799)
			(xy 136.811758 -291.169376) (xy 136.796174 -291.216057) (xy 136.773303 -291.259634) (xy 136.743738 -291.298978)
			(xy 136.708245 -291.33307) (xy 136.667742 -291.361026) (xy 136.62328 -291.382124) (xy 136.576009 -291.395816)
			(xy 136.527154 -291.401748) (xy 136.477979 -291.399767) (xy 136.42976 -291.389923) (xy 136.383744 -291.372471)
			(xy 136.341123 -291.347864) (xy 136.303002 -291.316739) (xy 136.270367 -291.279902) (xy 136.244064 -291.238306)
			(xy 136.224773 -291.19303) (xy 136.212996 -291.145246) (xy 136.209036 -291.096192) (xy 135.880094 -291.096192)
			(xy 135.879599 -291.120799) (xy 135.871704 -291.169376) (xy 135.85612 -291.216057) (xy 135.833249 -291.259634)
			(xy 135.803684 -291.298978) (xy 135.768191 -291.33307) (xy 135.727688 -291.361026) (xy 135.683226 -291.382124)
			(xy 135.635955 -291.395816) (xy 135.5871 -291.401748) (xy 135.537925 -291.399767) (xy 135.489706 -291.389923)
			(xy 135.44369 -291.372471) (xy 135.401069 -291.347864) (xy 135.362948 -291.316739) (xy 135.330313 -291.279902)
			(xy 135.30401 -291.238306) (xy 135.284719 -291.19303) (xy 135.272942 -291.145246) (xy 135.268982 -291.096192)
			(xy 134.94004 -291.096192) (xy 134.939545 -291.120799) (xy 134.93165 -291.169376) (xy 134.916066 -291.216057)
			(xy 134.893195 -291.259634) (xy 134.86363 -291.298978) (xy 134.828137 -291.33307) (xy 134.787634 -291.361026)
			(xy 134.743172 -291.382124) (xy 134.695901 -291.395816) (xy 134.647046 -291.401748) (xy 134.597871 -291.399767)
			(xy 134.549652 -291.389923) (xy 134.503636 -291.372471) (xy 134.461015 -291.347864) (xy 134.422894 -291.316739)
			(xy 134.390259 -291.279902) (xy 134.363956 -291.238306) (xy 134.344665 -291.19303) (xy 134.332888 -291.145246)
			(xy 134.328928 -291.096192) (xy 133.999986 -291.096192) (xy 133.999491 -291.120799) (xy 133.991596 -291.169376)
			(xy 133.976012 -291.216057) (xy 133.953141 -291.259634) (xy 133.923576 -291.298978) (xy 133.888083 -291.33307)
			(xy 133.84758 -291.361026) (xy 133.803118 -291.382124) (xy 133.755847 -291.395816) (xy 133.706992 -291.401748)
			(xy 133.657817 -291.399767) (xy 133.609598 -291.389923) (xy 133.563582 -291.372471) (xy 133.520961 -291.347864)
			(xy 133.48284 -291.316739) (xy 133.450205 -291.279902) (xy 133.423902 -291.238306) (xy 133.404611 -291.19303)
			(xy 133.392834 -291.145246) (xy 133.388874 -291.096192) (xy 133.0706 -291.096192) (xy 133.070088 -291.121638)
			(xy 133.061924 -291.171872) (xy 133.045808 -291.220146) (xy 133.022157 -291.265209) (xy 132.991584 -291.305895)
			(xy 132.95488 -291.34115) (xy 132.912996 -291.37006) (xy 132.867017 -291.391877) (xy 132.818133 -291.406037)
			(xy 132.767612 -291.412171) (xy 132.71676 -291.410122) (xy 132.666896 -291.399942) (xy 132.61931 -291.381895)
			(xy 132.575236 -291.356449) (xy 132.535814 -291.324262) (xy 132.502066 -291.286168) (xy 132.474865 -291.243154)
			(xy 132.454917 -291.196334) (xy 132.442738 -291.14692) (xy 132.438643 -291.096192) (xy 132.130546 -291.096192)
			(xy 132.130034 -291.121638) (xy 132.12187 -291.171872) (xy 132.105754 -291.220146) (xy 132.082103 -291.265209)
			(xy 132.05153 -291.305895) (xy 132.014826 -291.34115) (xy 131.972942 -291.37006) (xy 131.926963 -291.391877)
			(xy 131.878079 -291.406037) (xy 131.827558 -291.412171) (xy 131.776706 -291.410122) (xy 131.726842 -291.399942)
			(xy 131.679256 -291.381895) (xy 131.635182 -291.356449) (xy 131.59576 -291.324262) (xy 131.562012 -291.286168)
			(xy 131.534811 -291.243154) (xy 131.514863 -291.196334) (xy 131.502684 -291.14692) (xy 131.498589 -291.096192)
			(xy 131.180078 -291.096192) (xy 131.179583 -291.120799) (xy 131.171688 -291.169376) (xy 131.156104 -291.216057)
			(xy 131.133233 -291.259634) (xy 131.103668 -291.298978) (xy 131.068175 -291.33307) (xy 131.027672 -291.361026)
			(xy 130.98321 -291.382124) (xy 130.935939 -291.395816) (xy 130.887084 -291.401748) (xy 130.837909 -291.399767)
			(xy 130.78969 -291.389923) (xy 130.743674 -291.372471) (xy 130.701053 -291.347864) (xy 130.662932 -291.316739)
			(xy 130.630297 -291.279902) (xy 130.603994 -291.238306) (xy 130.584703 -291.19303) (xy 130.572926 -291.145246)
			(xy 130.568966 -291.096192) (xy 130.250438 -291.096192) (xy 130.249926 -291.121638) (xy 130.241762 -291.171872)
			(xy 130.225646 -291.220146) (xy 130.201995 -291.265209) (xy 130.171422 -291.305895) (xy 130.134718 -291.34115)
			(xy 130.092834 -291.37006) (xy 130.046855 -291.391877) (xy 129.997971 -291.406037) (xy 129.94745 -291.412171)
			(xy 129.896598 -291.410122) (xy 129.846734 -291.399942) (xy 129.799148 -291.381895) (xy 129.755074 -291.356449)
			(xy 129.715652 -291.324262) (xy 129.681904 -291.286168) (xy 129.654703 -291.243154) (xy 129.634755 -291.196334)
			(xy 129.622576 -291.14692) (xy 129.618481 -291.096192) (xy 129.29997 -291.096192) (xy 129.299475 -291.120799)
			(xy 129.29158 -291.169376) (xy 129.275996 -291.216057) (xy 129.253125 -291.259634) (xy 129.22356 -291.298978)
			(xy 129.188067 -291.33307) (xy 129.147564 -291.361026) (xy 129.103102 -291.382124) (xy 129.055831 -291.395816)
			(xy 129.006976 -291.401748) (xy 128.957801 -291.399767) (xy 128.909582 -291.389923) (xy 128.863566 -291.372471)
			(xy 128.820945 -291.347864) (xy 128.782824 -291.316739) (xy 128.750189 -291.279902) (xy 128.723886 -291.238306)
			(xy 128.704595 -291.19303) (xy 128.692818 -291.145246) (xy 128.688858 -291.096192) (xy 128.370584 -291.096192)
			(xy 128.370072 -291.121638) (xy 128.361908 -291.171872) (xy 128.345792 -291.220146) (xy 128.322141 -291.265209)
			(xy 128.291568 -291.305895) (xy 128.254864 -291.34115) (xy 128.21298 -291.37006) (xy 128.167001 -291.391877)
			(xy 128.118117 -291.406037) (xy 128.067596 -291.412171) (xy 128.016744 -291.410122) (xy 127.96688 -291.399942)
			(xy 127.919294 -291.381895) (xy 127.87522 -291.356449) (xy 127.835798 -291.324262) (xy 127.80205 -291.286168)
			(xy 127.774849 -291.243154) (xy 127.754901 -291.196334) (xy 127.742722 -291.14692) (xy 127.738627 -291.096192)
			(xy 127.472186 -291.096192) (xy 127.472186 -291.125402) (xy 127.47879 -291.142674) (xy 127.48514 -291.149786)
			(xy 127.515327 -291.183993) (xy 127.570705 -291.256505) (xy 127.620059 -291.333244) (xy 127.663069 -291.413711)
			(xy 127.699453 -291.497383) (xy 127.728977 -291.583714) (xy 127.740664 -291.627814) (xy 127.743268 -291.636461)
			(xy 127.753552 -291.651289) (xy 127.76073 -291.65677) (xy 127.780344 -291.671193) (xy 127.815161 -291.705221)
			(xy 127.844139 -291.744342) (xy 127.866544 -291.787563) (xy 127.881809 -291.833792) (xy 127.889548 -291.881856)
			(xy 127.890016 -291.906198) (xy 128.208527 -291.906198) (xy 128.212622 -291.85547) (xy 128.224801 -291.806056)
			(xy 128.244749 -291.759236) (xy 128.27195 -291.716222) (xy 128.305698 -291.678128) (xy 128.34512 -291.645941)
			(xy 128.389194 -291.620495) (xy 128.43678 -291.602448) (xy 128.486644 -291.592268) (xy 128.537496 -291.590219)
			(xy 128.588017 -291.596353) (xy 128.636901 -291.610513) (xy 128.68288 -291.63233) (xy 128.724764 -291.66124)
			(xy 128.761468 -291.696495) (xy 128.792041 -291.737181) (xy 128.815692 -291.782244) (xy 128.831808 -291.830518)
			(xy 128.839972 -291.880752) (xy 128.840484 -291.906198) (xy 129.148581 -291.906198) (xy 129.152676 -291.85547)
			(xy 129.164855 -291.806056) (xy 129.184803 -291.759236) (xy 129.212004 -291.716222) (xy 129.245752 -291.678128)
			(xy 129.285174 -291.645941) (xy 129.329248 -291.620495) (xy 129.376834 -291.602448) (xy 129.426698 -291.592268)
			(xy 129.47755 -291.590219) (xy 129.528071 -291.596353) (xy 129.576955 -291.610513) (xy 129.622934 -291.63233)
			(xy 129.664818 -291.66124) (xy 129.701522 -291.696495) (xy 129.732095 -291.737181) (xy 129.755746 -291.782244)
			(xy 129.771862 -291.830518) (xy 129.780026 -291.880752) (xy 129.780538 -291.906198) (xy 130.099066 -291.906198)
			(xy 130.103026 -291.857144) (xy 130.114803 -291.80936) (xy 130.134094 -291.764084) (xy 130.160397 -291.722488)
			(xy 130.193032 -291.685651) (xy 130.231153 -291.654526) (xy 130.273774 -291.629919) (xy 130.31979 -291.612467)
			(xy 130.368009 -291.602623) (xy 130.417184 -291.600642) (xy 130.466039 -291.606574) (xy 130.51331 -291.620266)
			(xy 130.557772 -291.641364) (xy 130.598275 -291.66932) (xy 130.633768 -291.703412) (xy 130.663333 -291.742756)
			(xy 130.686204 -291.786333) (xy 130.701788 -291.833014) (xy 130.709683 -291.881591) (xy 130.710178 -291.906198)
			(xy 131.028435 -291.906198) (xy 131.03253 -291.85547) (xy 131.044709 -291.806056) (xy 131.064657 -291.759236)
			(xy 131.091858 -291.716222) (xy 131.125606 -291.678128) (xy 131.165028 -291.645941) (xy 131.209102 -291.620495)
			(xy 131.256688 -291.602448) (xy 131.306552 -291.592268) (xy 131.357404 -291.590219) (xy 131.407925 -291.596353)
			(xy 131.456809 -291.610513) (xy 131.502788 -291.63233) (xy 131.544672 -291.66124) (xy 131.581376 -291.696495)
			(xy 131.611949 -291.737181) (xy 131.6356 -291.782244) (xy 131.651716 -291.830518) (xy 131.65988 -291.880752)
			(xy 131.660392 -291.906198) (xy 131.97892 -291.906198) (xy 131.98288 -291.857144) (xy 131.994657 -291.80936)
			(xy 132.013948 -291.764084) (xy 132.040251 -291.722488) (xy 132.072886 -291.685651) (xy 132.111007 -291.654526)
			(xy 132.153628 -291.629919) (xy 132.199644 -291.612467) (xy 132.247863 -291.602623) (xy 132.297038 -291.600642)
			(xy 132.345893 -291.606574) (xy 132.393164 -291.620266) (xy 132.437626 -291.641364) (xy 132.478129 -291.66932)
			(xy 132.513622 -291.703412) (xy 132.543187 -291.742756) (xy 132.566058 -291.786333) (xy 132.581642 -291.833014)
			(xy 132.589537 -291.881591) (xy 132.590032 -291.906198) (xy 132.908543 -291.906198) (xy 132.912638 -291.85547)
			(xy 132.924817 -291.806056) (xy 132.944765 -291.759236) (xy 132.971966 -291.716222) (xy 133.005714 -291.678128)
			(xy 133.045136 -291.645941) (xy 133.08921 -291.620495) (xy 133.136796 -291.602448) (xy 133.18666 -291.592268)
			(xy 133.237512 -291.590219) (xy 133.288033 -291.596353) (xy 133.336917 -291.610513) (xy 133.382896 -291.63233)
			(xy 133.42478 -291.66124) (xy 133.461484 -291.696495) (xy 133.492057 -291.737181) (xy 133.515708 -291.782244)
			(xy 133.531824 -291.830518) (xy 133.539988 -291.880752) (xy 133.5405 -291.906198) (xy 133.859028 -291.906198)
			(xy 133.862988 -291.857144) (xy 133.874765 -291.80936) (xy 133.894056 -291.764084) (xy 133.920359 -291.722488)
			(xy 133.952994 -291.685651) (xy 133.991115 -291.654526) (xy 134.033736 -291.629919) (xy 134.079752 -291.612467)
			(xy 134.127971 -291.602623) (xy 134.177146 -291.600642) (xy 134.226001 -291.606574) (xy 134.273272 -291.620266)
			(xy 134.317734 -291.641364) (xy 134.358237 -291.66932) (xy 134.39373 -291.703412) (xy 134.423295 -291.742756)
			(xy 134.446166 -291.786333) (xy 134.46175 -291.833014) (xy 134.469645 -291.881591) (xy 134.47014 -291.906198)
			(xy 134.798828 -291.906198) (xy 134.802788 -291.857144) (xy 134.814565 -291.80936) (xy 134.833856 -291.764084)
			(xy 134.860159 -291.722488) (xy 134.892794 -291.685651) (xy 134.930915 -291.654526) (xy 134.973536 -291.629919)
			(xy 135.019552 -291.612467) (xy 135.067771 -291.602623) (xy 135.116946 -291.600642) (xy 135.165801 -291.606574)
			(xy 135.213072 -291.620266) (xy 135.257534 -291.641364) (xy 135.298037 -291.66932) (xy 135.33353 -291.703412)
			(xy 135.363095 -291.742756) (xy 135.385966 -291.786333) (xy 135.40155 -291.833014) (xy 135.409445 -291.881591)
			(xy 135.40994 -291.906198) (xy 135.738882 -291.906198) (xy 135.742842 -291.857144) (xy 135.754619 -291.80936)
			(xy 135.77391 -291.764084) (xy 135.800213 -291.722488) (xy 135.832848 -291.685651) (xy 135.870969 -291.654526)
			(xy 135.91359 -291.629919) (xy 135.959606 -291.612467) (xy 136.007825 -291.602623) (xy 136.057 -291.600642)
			(xy 136.105855 -291.606574) (xy 136.153126 -291.620266) (xy 136.197588 -291.641364) (xy 136.238091 -291.66932)
			(xy 136.273584 -291.703412) (xy 136.303149 -291.742756) (xy 136.32602 -291.786333) (xy 136.341604 -291.833014)
			(xy 136.349499 -291.881591) (xy 136.349994 -291.906198) (xy 136.349499 -291.930805) (xy 136.341604 -291.979382)
			(xy 136.32602 -292.026063) (xy 136.303149 -292.06964) (xy 136.273584 -292.108984) (xy 136.238091 -292.143076)
			(xy 136.197588 -292.171032) (xy 136.153126 -292.19213) (xy 136.105855 -292.205822) (xy 136.057 -292.211754)
			(xy 136.007825 -292.209773) (xy 135.959606 -292.199929) (xy 135.91359 -292.182477) (xy 135.870969 -292.15787)
			(xy 135.832848 -292.126745) (xy 135.800213 -292.089908) (xy 135.77391 -292.048312) (xy 135.754619 -292.003036)
			(xy 135.742842 -291.955252) (xy 135.738882 -291.906198) (xy 135.40994 -291.906198) (xy 135.409445 -291.930805)
			(xy 135.40155 -291.979382) (xy 135.385966 -292.026063) (xy 135.363095 -292.06964) (xy 135.33353 -292.108984)
			(xy 135.298037 -292.143076) (xy 135.257534 -292.171032) (xy 135.213072 -292.19213) (xy 135.165801 -292.205822)
			(xy 135.116946 -292.211754) (xy 135.067771 -292.209773) (xy 135.019552 -292.199929) (xy 134.973536 -292.182477)
			(xy 134.930915 -292.15787) (xy 134.892794 -292.126745) (xy 134.860159 -292.089908) (xy 134.833856 -292.048312)
			(xy 134.814565 -292.003036) (xy 134.802788 -291.955252) (xy 134.798828 -291.906198) (xy 134.47014 -291.906198)
			(xy 134.469645 -291.930805) (xy 134.46175 -291.979382) (xy 134.446166 -292.026063) (xy 134.423295 -292.06964)
			(xy 134.39373 -292.108984) (xy 134.358237 -292.143076) (xy 134.317734 -292.171032) (xy 134.273272 -292.19213)
			(xy 134.226001 -292.205822) (xy 134.177146 -292.211754) (xy 134.127971 -292.209773) (xy 134.079752 -292.199929)
			(xy 134.033736 -292.182477) (xy 133.991115 -292.15787) (xy 133.952994 -292.126745) (xy 133.920359 -292.089908)
			(xy 133.894056 -292.048312) (xy 133.874765 -292.003036) (xy 133.862988 -291.955252) (xy 133.859028 -291.906198)
			(xy 133.5405 -291.906198) (xy 133.539988 -291.931644) (xy 133.531824 -291.981878) (xy 133.515708 -292.030152)
			(xy 133.492057 -292.075215) (xy 133.461484 -292.115901) (xy 133.42478 -292.151156) (xy 133.382896 -292.180066)
			(xy 133.336917 -292.201883) (xy 133.288033 -292.216043) (xy 133.237512 -292.222177) (xy 133.18666 -292.220128)
			(xy 133.136796 -292.209948) (xy 133.08921 -292.191901) (xy 133.045136 -292.166455) (xy 133.005714 -292.134268)
			(xy 132.971966 -292.096174) (xy 132.944765 -292.05316) (xy 132.924817 -292.00634) (xy 132.912638 -291.956926)
			(xy 132.908543 -291.906198) (xy 132.590032 -291.906198) (xy 132.589537 -291.930805) (xy 132.581642 -291.979382)
			(xy 132.566058 -292.026063) (xy 132.543187 -292.06964) (xy 132.513622 -292.108984) (xy 132.478129 -292.143076)
			(xy 132.437626 -292.171032) (xy 132.393164 -292.19213) (xy 132.345893 -292.205822) (xy 132.297038 -292.211754)
			(xy 132.247863 -292.209773) (xy 132.199644 -292.199929) (xy 132.153628 -292.182477) (xy 132.111007 -292.15787)
			(xy 132.072886 -292.126745) (xy 132.040251 -292.089908) (xy 132.013948 -292.048312) (xy 131.994657 -292.003036)
			(xy 131.98288 -291.955252) (xy 131.97892 -291.906198) (xy 131.660392 -291.906198) (xy 131.65988 -291.931644)
			(xy 131.651716 -291.981878) (xy 131.6356 -292.030152) (xy 131.611949 -292.075215) (xy 131.581376 -292.115901)
			(xy 131.544672 -292.151156) (xy 131.502788 -292.180066) (xy 131.456809 -292.201883) (xy 131.407925 -292.216043)
			(xy 131.357404 -292.222177) (xy 131.306552 -292.220128) (xy 131.256688 -292.209948) (xy 131.209102 -292.191901)
			(xy 131.165028 -292.166455) (xy 131.125606 -292.134268) (xy 131.091858 -292.096174) (xy 131.064657 -292.05316)
			(xy 131.044709 -292.00634) (xy 131.03253 -291.956926) (xy 131.028435 -291.906198) (xy 130.710178 -291.906198)
			(xy 130.709683 -291.930805) (xy 130.701788 -291.979382) (xy 130.686204 -292.026063) (xy 130.663333 -292.06964)
			(xy 130.633768 -292.108984) (xy 130.598275 -292.143076) (xy 130.557772 -292.171032) (xy 130.51331 -292.19213)
			(xy 130.466039 -292.205822) (xy 130.417184 -292.211754) (xy 130.368009 -292.209773) (xy 130.31979 -292.199929)
			(xy 130.273774 -292.182477) (xy 130.231153 -292.15787) (xy 130.193032 -292.126745) (xy 130.160397 -292.089908)
			(xy 130.134094 -292.048312) (xy 130.114803 -292.003036) (xy 130.103026 -291.955252) (xy 130.099066 -291.906198)
			(xy 129.780538 -291.906198) (xy 129.780026 -291.931644) (xy 129.771862 -291.981878) (xy 129.755746 -292.030152)
			(xy 129.732095 -292.075215) (xy 129.701522 -292.115901) (xy 129.664818 -292.151156) (xy 129.622934 -292.180066)
			(xy 129.576955 -292.201883) (xy 129.528071 -292.216043) (xy 129.47755 -292.222177) (xy 129.426698 -292.220128)
			(xy 129.376834 -292.209948) (xy 129.329248 -292.191901) (xy 129.285174 -292.166455) (xy 129.245752 -292.134268)
			(xy 129.212004 -292.096174) (xy 129.184803 -292.05316) (xy 129.164855 -292.00634) (xy 129.152676 -291.956926)
			(xy 129.148581 -291.906198) (xy 128.840484 -291.906198) (xy 128.839972 -291.931644) (xy 128.831808 -291.981878)
			(xy 128.815692 -292.030152) (xy 128.792041 -292.075215) (xy 128.761468 -292.115901) (xy 128.724764 -292.151156)
			(xy 128.68288 -292.180066) (xy 128.636901 -292.201883) (xy 128.588017 -292.216043) (xy 128.537496 -292.222177)
			(xy 128.486644 -292.220128) (xy 128.43678 -292.209948) (xy 128.389194 -292.191901) (xy 128.34512 -292.166455)
			(xy 128.305698 -292.134268) (xy 128.27195 -292.096174) (xy 128.244749 -292.05316) (xy 128.224801 -292.00634)
			(xy 128.212622 -291.956926) (xy 128.208527 -291.906198) (xy 127.890016 -291.906198) (xy 127.889575 -291.929538)
			(xy 127.882479 -291.975676) (xy 127.868451 -292.020199) (xy 127.85852 -292.041326) (xy 127.856742 -292.044882)
			(xy 127.845112 -292.066662) (xy 127.815898 -292.106463) (xy 127.780641 -292.141025) (xy 127.76073 -292.155626)
			(xy 127.753553 -292.161104) (xy 127.743284 -292.175941) (xy 127.740664 -292.184582) (xy 127.728996 -292.228688)
			(xy 127.699477 -292.315023) (xy 127.663094 -292.398697) (xy 127.620083 -292.479165) (xy 127.570724 -292.555904)
			(xy 127.51534 -292.628413) (xy 127.48514 -292.66261) (xy 127.47879 -292.669722) (xy 127.472186 -292.686994)
			(xy 127.472186 -292.716204) (xy 127.738627 -292.716204) (xy 127.742722 -292.665476) (xy 127.754901 -292.616062)
			(xy 127.774849 -292.569242) (xy 127.80205 -292.526228) (xy 127.835798 -292.488134) (xy 127.87522 -292.455947)
			(xy 127.919294 -292.430501) (xy 127.96688 -292.412454) (xy 128.016744 -292.402274) (xy 128.067596 -292.400225)
			(xy 128.118117 -292.406359) (xy 128.167001 -292.420519) (xy 128.21298 -292.442336) (xy 128.254864 -292.471246)
			(xy 128.291568 -292.506501) (xy 128.322141 -292.547187) (xy 128.345792 -292.59225) (xy 128.361908 -292.640524)
			(xy 128.370072 -292.690758) (xy 128.370584 -292.716204) (xy 128.688858 -292.716204) (xy 128.692818 -292.66715)
			(xy 128.704595 -292.619366) (xy 128.723886 -292.57409) (xy 128.750189 -292.532494) (xy 128.782824 -292.495657)
			(xy 128.820945 -292.464532) (xy 128.863566 -292.439925) (xy 128.909582 -292.422473) (xy 128.957801 -292.412629)
			(xy 129.006976 -292.410648) (xy 129.055831 -292.41658) (xy 129.103102 -292.430272) (xy 129.147564 -292.45137)
			(xy 129.188067 -292.479326) (xy 129.22356 -292.513418) (xy 129.253125 -292.552762) (xy 129.275996 -292.596339)
			(xy 129.29158 -292.64302) (xy 129.299475 -292.691597) (xy 129.29997 -292.716204) (xy 129.618481 -292.716204)
			(xy 129.622576 -292.665476) (xy 129.634755 -292.616062) (xy 129.654703 -292.569242) (xy 129.681904 -292.526228)
			(xy 129.715652 -292.488134) (xy 129.755074 -292.455947) (xy 129.799148 -292.430501) (xy 129.846734 -292.412454)
			(xy 129.896598 -292.402274) (xy 129.94745 -292.400225) (xy 129.997971 -292.406359) (xy 130.046855 -292.420519)
			(xy 130.092834 -292.442336) (xy 130.134718 -292.471246) (xy 130.171422 -292.506501) (xy 130.201995 -292.547187)
			(xy 130.225646 -292.59225) (xy 130.241762 -292.640524) (xy 130.249926 -292.690758) (xy 130.250438 -292.716204)
			(xy 131.498589 -292.716204) (xy 131.502684 -292.665476) (xy 131.514863 -292.616062) (xy 131.534811 -292.569242)
			(xy 131.562012 -292.526228) (xy 131.59576 -292.488134) (xy 131.635182 -292.455947) (xy 131.679256 -292.430501)
			(xy 131.726842 -292.412454) (xy 131.776706 -292.402274) (xy 131.827558 -292.400225) (xy 131.878079 -292.406359)
			(xy 131.926963 -292.420519) (xy 131.972942 -292.442336) (xy 132.014826 -292.471246) (xy 132.05153 -292.506501)
			(xy 132.082103 -292.547187) (xy 132.105754 -292.59225) (xy 132.12187 -292.640524) (xy 132.130034 -292.690758)
			(xy 132.130546 -292.716204) (xy 132.438643 -292.716204) (xy 132.442738 -292.665476) (xy 132.454917 -292.616062)
			(xy 132.474865 -292.569242) (xy 132.502066 -292.526228) (xy 132.535814 -292.488134) (xy 132.575236 -292.455947)
			(xy 132.61931 -292.430501) (xy 132.666896 -292.412454) (xy 132.71676 -292.402274) (xy 132.767612 -292.400225)
			(xy 132.818133 -292.406359) (xy 132.867017 -292.420519) (xy 132.912996 -292.442336) (xy 132.95488 -292.471246)
			(xy 132.991584 -292.506501) (xy 133.022157 -292.547187) (xy 133.045808 -292.59225) (xy 133.061924 -292.640524)
			(xy 133.070088 -292.690758) (xy 133.0706 -292.716204) (xy 133.388874 -292.716204) (xy 133.392834 -292.66715)
			(xy 133.404611 -292.619366) (xy 133.423902 -292.57409) (xy 133.450205 -292.532494) (xy 133.48284 -292.495657)
			(xy 133.520961 -292.464532) (xy 133.563582 -292.439925) (xy 133.609598 -292.422473) (xy 133.657817 -292.412629)
			(xy 133.706992 -292.410648) (xy 133.755847 -292.41658) (xy 133.803118 -292.430272) (xy 133.84758 -292.45137)
			(xy 133.888083 -292.479326) (xy 133.923576 -292.513418) (xy 133.953141 -292.552762) (xy 133.976012 -292.596339)
			(xy 133.991596 -292.64302) (xy 133.999491 -292.691597) (xy 133.999986 -292.716204) (xy 134.328928 -292.716204)
			(xy 134.332888 -292.66715) (xy 134.344665 -292.619366) (xy 134.363956 -292.57409) (xy 134.390259 -292.532494)
			(xy 134.422894 -292.495657) (xy 134.461015 -292.464532) (xy 134.503636 -292.439925) (xy 134.549652 -292.422473)
			(xy 134.597871 -292.412629) (xy 134.647046 -292.410648) (xy 134.695901 -292.41658) (xy 134.743172 -292.430272)
			(xy 134.787634 -292.45137) (xy 134.828137 -292.479326) (xy 134.86363 -292.513418) (xy 134.893195 -292.552762)
			(xy 134.916066 -292.596339) (xy 134.93165 -292.64302) (xy 134.939545 -292.691597) (xy 134.94004 -292.716204)
			(xy 135.268982 -292.716204) (xy 135.272942 -292.66715) (xy 135.284719 -292.619366) (xy 135.30401 -292.57409)
			(xy 135.330313 -292.532494) (xy 135.362948 -292.495657) (xy 135.401069 -292.464532) (xy 135.44369 -292.439925)
			(xy 135.489706 -292.422473) (xy 135.537925 -292.412629) (xy 135.5871 -292.410648) (xy 135.635955 -292.41658)
			(xy 135.683226 -292.430272) (xy 135.727688 -292.45137) (xy 135.768191 -292.479326) (xy 135.803684 -292.513418)
			(xy 135.833249 -292.552762) (xy 135.85612 -292.596339) (xy 135.871704 -292.64302) (xy 135.879599 -292.691597)
			(xy 135.880094 -292.716204) (xy 136.209036 -292.716204) (xy 136.212996 -292.66715) (xy 136.224773 -292.619366)
			(xy 136.244064 -292.57409) (xy 136.270367 -292.532494) (xy 136.303002 -292.495657) (xy 136.341123 -292.464532)
			(xy 136.383744 -292.439925) (xy 136.42976 -292.422473) (xy 136.477979 -292.412629) (xy 136.527154 -292.410648)
			(xy 136.576009 -292.41658) (xy 136.62328 -292.430272) (xy 136.667742 -292.45137) (xy 136.708245 -292.479326)
			(xy 136.743738 -292.513418) (xy 136.773303 -292.552762) (xy 136.796174 -292.596339) (xy 136.811758 -292.64302)
			(xy 136.819653 -292.691597) (xy 136.820148 -292.716204) (xy 136.819653 -292.740811) (xy 136.811758 -292.789388)
			(xy 136.796174 -292.836069) (xy 136.773303 -292.879646) (xy 136.743738 -292.91899) (xy 136.708245 -292.953082)
			(xy 136.667742 -292.981038) (xy 136.62328 -293.002136) (xy 136.576009 -293.015828) (xy 136.527154 -293.02176)
			(xy 136.477979 -293.019779) (xy 136.42976 -293.009935) (xy 136.383744 -292.992483) (xy 136.341123 -292.967876)
			(xy 136.303002 -292.936751) (xy 136.270367 -292.899914) (xy 136.244064 -292.858318) (xy 136.224773 -292.813042)
			(xy 136.212996 -292.765258) (xy 136.209036 -292.716204) (xy 135.880094 -292.716204) (xy 135.879599 -292.740811)
			(xy 135.871704 -292.789388) (xy 135.85612 -292.836069) (xy 135.833249 -292.879646) (xy 135.803684 -292.91899)
			(xy 135.768191 -292.953082) (xy 135.727688 -292.981038) (xy 135.683226 -293.002136) (xy 135.635955 -293.015828)
			(xy 135.5871 -293.02176) (xy 135.537925 -293.019779) (xy 135.489706 -293.009935) (xy 135.44369 -292.992483)
			(xy 135.401069 -292.967876) (xy 135.362948 -292.936751) (xy 135.330313 -292.899914) (xy 135.30401 -292.858318)
			(xy 135.284719 -292.813042) (xy 135.272942 -292.765258) (xy 135.268982 -292.716204) (xy 134.94004 -292.716204)
			(xy 134.939545 -292.740811) (xy 134.93165 -292.789388) (xy 134.916066 -292.836069) (xy 134.893195 -292.879646)
			(xy 134.86363 -292.91899) (xy 134.828137 -292.953082) (xy 134.787634 -292.981038) (xy 134.743172 -293.002136)
			(xy 134.695901 -293.015828) (xy 134.647046 -293.02176) (xy 134.597871 -293.019779) (xy 134.549652 -293.009935)
			(xy 134.503636 -292.992483) (xy 134.461015 -292.967876) (xy 134.422894 -292.936751) (xy 134.390259 -292.899914)
			(xy 134.363956 -292.858318) (xy 134.344665 -292.813042) (xy 134.332888 -292.765258) (xy 134.328928 -292.716204)
			(xy 133.999986 -292.716204) (xy 133.999491 -292.740811) (xy 133.991596 -292.789388) (xy 133.976012 -292.836069)
			(xy 133.953141 -292.879646) (xy 133.923576 -292.91899) (xy 133.888083 -292.953082) (xy 133.84758 -292.981038)
			(xy 133.803118 -293.002136) (xy 133.755847 -293.015828) (xy 133.706992 -293.02176) (xy 133.657817 -293.019779)
			(xy 133.609598 -293.009935) (xy 133.563582 -292.992483) (xy 133.520961 -292.967876) (xy 133.48284 -292.936751)
			(xy 133.450205 -292.899914) (xy 133.423902 -292.858318) (xy 133.404611 -292.813042) (xy 133.392834 -292.765258)
			(xy 133.388874 -292.716204) (xy 133.0706 -292.716204) (xy 133.070088 -292.74165) (xy 133.061924 -292.791884)
			(xy 133.045808 -292.840158) (xy 133.022157 -292.885221) (xy 132.991584 -292.925907) (xy 132.95488 -292.961162)
			(xy 132.912996 -292.990072) (xy 132.867017 -293.011889) (xy 132.818133 -293.026049) (xy 132.767612 -293.032183)
			(xy 132.71676 -293.030134) (xy 132.666896 -293.019954) (xy 132.61931 -293.001907) (xy 132.575236 -292.976461)
			(xy 132.535814 -292.944274) (xy 132.502066 -292.90618) (xy 132.474865 -292.863166) (xy 132.454917 -292.816346)
			(xy 132.442738 -292.766932) (xy 132.438643 -292.716204) (xy 132.130546 -292.716204) (xy 132.130034 -292.74165)
			(xy 132.12187 -292.791884) (xy 132.105754 -292.840158) (xy 132.082103 -292.885221) (xy 132.05153 -292.925907)
			(xy 132.014826 -292.961162) (xy 131.972942 -292.990072) (xy 131.926963 -293.011889) (xy 131.878079 -293.026049)
			(xy 131.827558 -293.032183) (xy 131.776706 -293.030134) (xy 131.726842 -293.019954) (xy 131.679256 -293.001907)
			(xy 131.635182 -292.976461) (xy 131.59576 -292.944274) (xy 131.562012 -292.90618) (xy 131.534811 -292.863166)
			(xy 131.514863 -292.816346) (xy 131.502684 -292.766932) (xy 131.498589 -292.716204) (xy 130.250438 -292.716204)
			(xy 130.249926 -292.74165) (xy 130.241762 -292.791884) (xy 130.225646 -292.840158) (xy 130.201995 -292.885221)
			(xy 130.171422 -292.925907) (xy 130.134718 -292.961162) (xy 130.092834 -292.990072) (xy 130.046855 -293.011889)
			(xy 129.997971 -293.026049) (xy 129.94745 -293.032183) (xy 129.896598 -293.030134) (xy 129.846734 -293.019954)
			(xy 129.799148 -293.001907) (xy 129.755074 -292.976461) (xy 129.715652 -292.944274) (xy 129.681904 -292.90618)
			(xy 129.654703 -292.863166) (xy 129.634755 -292.816346) (xy 129.622576 -292.766932) (xy 129.618481 -292.716204)
			(xy 129.29997 -292.716204) (xy 129.299475 -292.740811) (xy 129.29158 -292.789388) (xy 129.275996 -292.836069)
			(xy 129.253125 -292.879646) (xy 129.22356 -292.91899) (xy 129.188067 -292.953082) (xy 129.147564 -292.981038)
			(xy 129.103102 -293.002136) (xy 129.055831 -293.015828) (xy 129.006976 -293.02176) (xy 128.957801 -293.019779)
			(xy 128.909582 -293.009935) (xy 128.863566 -292.992483) (xy 128.820945 -292.967876) (xy 128.782824 -292.936751)
			(xy 128.750189 -292.899914) (xy 128.723886 -292.858318) (xy 128.704595 -292.813042) (xy 128.692818 -292.765258)
			(xy 128.688858 -292.716204) (xy 128.370584 -292.716204) (xy 128.370072 -292.74165) (xy 128.361908 -292.791884)
			(xy 128.345792 -292.840158) (xy 128.322141 -292.885221) (xy 128.291568 -292.925907) (xy 128.254864 -292.961162)
			(xy 128.21298 -292.990072) (xy 128.167001 -293.011889) (xy 128.118117 -293.026049) (xy 128.067596 -293.032183)
			(xy 128.016744 -293.030134) (xy 127.96688 -293.019954) (xy 127.919294 -293.001907) (xy 127.87522 -292.976461)
			(xy 127.835798 -292.944274) (xy 127.80205 -292.90618) (xy 127.774849 -292.863166) (xy 127.754901 -292.816346)
			(xy 127.742722 -292.766932) (xy 127.738627 -292.716204) (xy 127.472186 -292.716204) (xy 127.472186 -292.745414)
			(xy 127.47879 -292.762686) (xy 127.48514 -292.769798) (xy 127.515327 -292.804005) (xy 127.570704 -292.876518)
			(xy 127.620057 -292.953257) (xy 127.663066 -293.033724) (xy 127.69945 -293.117396) (xy 127.728972 -293.203727)
			(xy 127.740664 -293.247826) (xy 127.743256 -293.256481) (xy 127.753526 -293.271331) (xy 127.76073 -293.276782)
			(xy 127.780343 -293.291206) (xy 127.815159 -293.325234) (xy 127.844135 -293.364354) (xy 127.866539 -293.407576)
			(xy 127.881802 -293.453804) (xy 127.889539 -293.501869) (xy 127.890016 -293.52621) (xy 128.208527 -293.52621)
			(xy 128.212622 -293.475482) (xy 128.224801 -293.426068) (xy 128.244749 -293.379248) (xy 128.27195 -293.336234)
			(xy 128.305698 -293.29814) (xy 128.34512 -293.265953) (xy 128.389194 -293.240507) (xy 128.43678 -293.22246)
			(xy 128.486644 -293.21228) (xy 128.537496 -293.210231) (xy 128.588017 -293.216365) (xy 128.636901 -293.230525)
			(xy 128.68288 -293.252342) (xy 128.724764 -293.281252) (xy 128.761468 -293.316507) (xy 128.792041 -293.357193)
			(xy 128.815692 -293.402256) (xy 128.831808 -293.45053) (xy 128.839972 -293.500764) (xy 128.840484 -293.52621)
			(xy 129.159012 -293.52621) (xy 129.162972 -293.477156) (xy 129.174749 -293.429372) (xy 129.19404 -293.384096)
			(xy 129.220343 -293.3425) (xy 129.252978 -293.305663) (xy 129.291099 -293.274538) (xy 129.33372 -293.249931)
			(xy 129.379736 -293.232479) (xy 129.427955 -293.222635) (xy 129.47713 -293.220654) (xy 129.525985 -293.226586)
			(xy 129.573256 -293.240278) (xy 129.617718 -293.261376) (xy 129.658221 -293.289332) (xy 129.693714 -293.323424)
			(xy 129.723279 -293.362768) (xy 129.74615 -293.406345) (xy 129.761734 -293.453026) (xy 129.769629 -293.501603)
			(xy 129.770124 -293.52621) (xy 130.099066 -293.52621) (xy 130.103026 -293.477156) (xy 130.114803 -293.429372)
			(xy 130.134094 -293.384096) (xy 130.160397 -293.3425) (xy 130.193032 -293.305663) (xy 130.231153 -293.274538)
			(xy 130.273774 -293.249931) (xy 130.31979 -293.232479) (xy 130.368009 -293.222635) (xy 130.417184 -293.220654)
			(xy 130.466039 -293.226586) (xy 130.51331 -293.240278) (xy 130.557772 -293.261376) (xy 130.598275 -293.289332)
			(xy 130.633768 -293.323424) (xy 130.663333 -293.362768) (xy 130.686204 -293.406345) (xy 130.701788 -293.453026)
			(xy 130.709683 -293.501603) (xy 130.710178 -293.52621) (xy 131.038866 -293.52621) (xy 131.042826 -293.477156)
			(xy 131.054603 -293.429372) (xy 131.073894 -293.384096) (xy 131.100197 -293.3425) (xy 131.132832 -293.305663)
			(xy 131.170953 -293.274538) (xy 131.213574 -293.249931) (xy 131.25959 -293.232479) (xy 131.307809 -293.222635)
			(xy 131.356984 -293.220654) (xy 131.405839 -293.226586) (xy 131.45311 -293.240278) (xy 131.497572 -293.261376)
			(xy 131.538075 -293.289332) (xy 131.573568 -293.323424) (xy 131.603133 -293.362768) (xy 131.626004 -293.406345)
			(xy 131.641588 -293.453026) (xy 131.649483 -293.501603) (xy 131.649978 -293.52621) (xy 131.97892 -293.52621)
			(xy 131.98288 -293.477156) (xy 131.994657 -293.429372) (xy 132.013948 -293.384096) (xy 132.040251 -293.3425)
			(xy 132.072886 -293.305663) (xy 132.111007 -293.274538) (xy 132.153628 -293.249931) (xy 132.199644 -293.232479)
			(xy 132.247863 -293.222635) (xy 132.297038 -293.220654) (xy 132.345893 -293.226586) (xy 132.393164 -293.240278)
			(xy 132.437626 -293.261376) (xy 132.478129 -293.289332) (xy 132.513622 -293.323424) (xy 132.543187 -293.362768)
			(xy 132.566058 -293.406345) (xy 132.581642 -293.453026) (xy 132.589537 -293.501603) (xy 132.590032 -293.52621)
			(xy 132.908543 -293.52621) (xy 132.912638 -293.475482) (xy 132.924817 -293.426068) (xy 132.944765 -293.379248)
			(xy 132.971966 -293.336234) (xy 133.005714 -293.29814) (xy 133.045136 -293.265953) (xy 133.08921 -293.240507)
			(xy 133.136796 -293.22246) (xy 133.18666 -293.21228) (xy 133.237512 -293.210231) (xy 133.288033 -293.216365)
			(xy 133.336917 -293.230525) (xy 133.382896 -293.252342) (xy 133.42478 -293.281252) (xy 133.461484 -293.316507)
			(xy 133.492057 -293.357193) (xy 133.515708 -293.402256) (xy 133.531824 -293.45053) (xy 133.539988 -293.500764)
			(xy 133.5405 -293.52621) (xy 133.859028 -293.52621) (xy 133.862988 -293.477156) (xy 133.874765 -293.429372)
			(xy 133.894056 -293.384096) (xy 133.920359 -293.3425) (xy 133.952994 -293.305663) (xy 133.991115 -293.274538)
			(xy 134.033736 -293.249931) (xy 134.079752 -293.232479) (xy 134.127971 -293.222635) (xy 134.177146 -293.220654)
			(xy 134.226001 -293.226586) (xy 134.273272 -293.240278) (xy 134.317734 -293.261376) (xy 134.358237 -293.289332)
			(xy 134.39373 -293.323424) (xy 134.423295 -293.362768) (xy 134.446166 -293.406345) (xy 134.46175 -293.453026)
			(xy 134.469645 -293.501603) (xy 134.47014 -293.52621) (xy 134.798828 -293.52621) (xy 134.802788 -293.477156)
			(xy 134.814565 -293.429372) (xy 134.833856 -293.384096) (xy 134.860159 -293.3425) (xy 134.892794 -293.305663)
			(xy 134.930915 -293.274538) (xy 134.973536 -293.249931) (xy 135.019552 -293.232479) (xy 135.067771 -293.222635)
			(xy 135.116946 -293.220654) (xy 135.165801 -293.226586) (xy 135.213072 -293.240278) (xy 135.257534 -293.261376)
			(xy 135.298037 -293.289332) (xy 135.33353 -293.323424) (xy 135.363095 -293.362768) (xy 135.385966 -293.406345)
			(xy 135.40155 -293.453026) (xy 135.409445 -293.501603) (xy 135.40994 -293.52621) (xy 135.738882 -293.52621)
			(xy 135.742842 -293.477156) (xy 135.754619 -293.429372) (xy 135.77391 -293.384096) (xy 135.800213 -293.3425)
			(xy 135.832848 -293.305663) (xy 135.870969 -293.274538) (xy 135.91359 -293.249931) (xy 135.959606 -293.232479)
			(xy 136.007825 -293.222635) (xy 136.057 -293.220654) (xy 136.105855 -293.226586) (xy 136.153126 -293.240278)
			(xy 136.197588 -293.261376) (xy 136.238091 -293.289332) (xy 136.273584 -293.323424) (xy 136.303149 -293.362768)
			(xy 136.32602 -293.406345) (xy 136.341604 -293.453026) (xy 136.349499 -293.501603) (xy 136.349994 -293.52621)
			(xy 136.678936 -293.52621) (xy 136.682896 -293.477156) (xy 136.694673 -293.429372) (xy 136.713964 -293.384096)
			(xy 136.740267 -293.3425) (xy 136.772902 -293.305663) (xy 136.811023 -293.274538) (xy 136.853644 -293.249931)
			(xy 136.89966 -293.232479) (xy 136.947879 -293.222635) (xy 136.997054 -293.220654) (xy 137.045909 -293.226586)
			(xy 137.09318 -293.240278) (xy 137.137642 -293.261376) (xy 137.178145 -293.289332) (xy 137.213638 -293.323424)
			(xy 137.243203 -293.362768) (xy 137.266074 -293.406345) (xy 137.281658 -293.453026) (xy 137.289553 -293.501603)
			(xy 137.290048 -293.52621) (xy 137.289553 -293.550817) (xy 137.281658 -293.599394) (xy 137.266074 -293.646075)
			(xy 137.243203 -293.689652) (xy 137.213638 -293.728996) (xy 137.178145 -293.763088) (xy 137.137642 -293.791044)
			(xy 137.09318 -293.812142) (xy 137.045909 -293.825834) (xy 136.997054 -293.831766) (xy 136.947879 -293.829785)
			(xy 136.89966 -293.819941) (xy 136.853644 -293.802489) (xy 136.811023 -293.777882) (xy 136.772902 -293.746757)
			(xy 136.740267 -293.70992) (xy 136.713964 -293.668324) (xy 136.694673 -293.623048) (xy 136.682896 -293.575264)
			(xy 136.678936 -293.52621) (xy 136.349994 -293.52621) (xy 136.349499 -293.550817) (xy 136.341604 -293.599394)
			(xy 136.32602 -293.646075) (xy 136.303149 -293.689652) (xy 136.273584 -293.728996) (xy 136.238091 -293.763088)
			(xy 136.197588 -293.791044) (xy 136.153126 -293.812142) (xy 136.105855 -293.825834) (xy 136.057 -293.831766)
			(xy 136.007825 -293.829785) (xy 135.959606 -293.819941) (xy 135.91359 -293.802489) (xy 135.870969 -293.777882)
			(xy 135.832848 -293.746757) (xy 135.800213 -293.70992) (xy 135.77391 -293.668324) (xy 135.754619 -293.623048)
			(xy 135.742842 -293.575264) (xy 135.738882 -293.52621) (xy 135.40994 -293.52621) (xy 135.409445 -293.550817)
			(xy 135.40155 -293.599394) (xy 135.385966 -293.646075) (xy 135.363095 -293.689652) (xy 135.33353 -293.728996)
			(xy 135.298037 -293.763088) (xy 135.257534 -293.791044) (xy 135.213072 -293.812142) (xy 135.165801 -293.825834)
			(xy 135.116946 -293.831766) (xy 135.067771 -293.829785) (xy 135.019552 -293.819941) (xy 134.973536 -293.802489)
			(xy 134.930915 -293.777882) (xy 134.892794 -293.746757) (xy 134.860159 -293.70992) (xy 134.833856 -293.668324)
			(xy 134.814565 -293.623048) (xy 134.802788 -293.575264) (xy 134.798828 -293.52621) (xy 134.47014 -293.52621)
			(xy 134.469645 -293.550817) (xy 134.46175 -293.599394) (xy 134.446166 -293.646075) (xy 134.423295 -293.689652)
			(xy 134.39373 -293.728996) (xy 134.358237 -293.763088) (xy 134.317734 -293.791044) (xy 134.273272 -293.812142)
			(xy 134.226001 -293.825834) (xy 134.177146 -293.831766) (xy 134.127971 -293.829785) (xy 134.079752 -293.819941)
			(xy 134.033736 -293.802489) (xy 133.991115 -293.777882) (xy 133.952994 -293.746757) (xy 133.920359 -293.70992)
			(xy 133.894056 -293.668324) (xy 133.874765 -293.623048) (xy 133.862988 -293.575264) (xy 133.859028 -293.52621)
			(xy 133.5405 -293.52621) (xy 133.539988 -293.551656) (xy 133.531824 -293.60189) (xy 133.515708 -293.650164)
			(xy 133.492057 -293.695227) (xy 133.461484 -293.735913) (xy 133.42478 -293.771168) (xy 133.382896 -293.800078)
			(xy 133.336917 -293.821895) (xy 133.288033 -293.836055) (xy 133.237512 -293.842189) (xy 133.18666 -293.84014)
			(xy 133.136796 -293.82996) (xy 133.08921 -293.811913) (xy 133.045136 -293.786467) (xy 133.005714 -293.75428)
			(xy 132.971966 -293.716186) (xy 132.944765 -293.673172) (xy 132.924817 -293.626352) (xy 132.912638 -293.576938)
			(xy 132.908543 -293.52621) (xy 132.590032 -293.52621) (xy 132.589537 -293.550817) (xy 132.581642 -293.599394)
			(xy 132.566058 -293.646075) (xy 132.543187 -293.689652) (xy 132.513622 -293.728996) (xy 132.478129 -293.763088)
			(xy 132.437626 -293.791044) (xy 132.393164 -293.812142) (xy 132.345893 -293.825834) (xy 132.297038 -293.831766)
			(xy 132.247863 -293.829785) (xy 132.199644 -293.819941) (xy 132.153628 -293.802489) (xy 132.111007 -293.777882)
			(xy 132.072886 -293.746757) (xy 132.040251 -293.70992) (xy 132.013948 -293.668324) (xy 131.994657 -293.623048)
			(xy 131.98288 -293.575264) (xy 131.97892 -293.52621) (xy 131.649978 -293.52621) (xy 131.649483 -293.550817)
			(xy 131.641588 -293.599394) (xy 131.626004 -293.646075) (xy 131.603133 -293.689652) (xy 131.573568 -293.728996)
			(xy 131.538075 -293.763088) (xy 131.497572 -293.791044) (xy 131.45311 -293.812142) (xy 131.405839 -293.825834)
			(xy 131.356984 -293.831766) (xy 131.307809 -293.829785) (xy 131.25959 -293.819941) (xy 131.213574 -293.802489)
			(xy 131.170953 -293.777882) (xy 131.132832 -293.746757) (xy 131.100197 -293.70992) (xy 131.073894 -293.668324)
			(xy 131.054603 -293.623048) (xy 131.042826 -293.575264) (xy 131.038866 -293.52621) (xy 130.710178 -293.52621)
			(xy 130.709683 -293.550817) (xy 130.701788 -293.599394) (xy 130.686204 -293.646075) (xy 130.663333 -293.689652)
			(xy 130.633768 -293.728996) (xy 130.598275 -293.763088) (xy 130.557772 -293.791044) (xy 130.51331 -293.812142)
			(xy 130.466039 -293.825834) (xy 130.417184 -293.831766) (xy 130.368009 -293.829785) (xy 130.31979 -293.819941)
			(xy 130.273774 -293.802489) (xy 130.231153 -293.777882) (xy 130.193032 -293.746757) (xy 130.160397 -293.70992)
			(xy 130.134094 -293.668324) (xy 130.114803 -293.623048) (xy 130.103026 -293.575264) (xy 130.099066 -293.52621)
			(xy 129.770124 -293.52621) (xy 129.769629 -293.550817) (xy 129.761734 -293.599394) (xy 129.74615 -293.646075)
			(xy 129.723279 -293.689652) (xy 129.693714 -293.728996) (xy 129.658221 -293.763088) (xy 129.617718 -293.791044)
			(xy 129.573256 -293.812142) (xy 129.525985 -293.825834) (xy 129.47713 -293.831766) (xy 129.427955 -293.829785)
			(xy 129.379736 -293.819941) (xy 129.33372 -293.802489) (xy 129.291099 -293.777882) (xy 129.252978 -293.746757)
			(xy 129.220343 -293.70992) (xy 129.19404 -293.668324) (xy 129.174749 -293.623048) (xy 129.162972 -293.575264)
			(xy 129.159012 -293.52621) (xy 128.840484 -293.52621) (xy 128.839972 -293.551656) (xy 128.831808 -293.60189)
			(xy 128.815692 -293.650164) (xy 128.792041 -293.695227) (xy 128.761468 -293.735913) (xy 128.724764 -293.771168)
			(xy 128.68288 -293.800078) (xy 128.636901 -293.821895) (xy 128.588017 -293.836055) (xy 128.537496 -293.842189)
			(xy 128.486644 -293.84014) (xy 128.43678 -293.82996) (xy 128.389194 -293.811913) (xy 128.34512 -293.786467)
			(xy 128.305698 -293.75428) (xy 128.27195 -293.716186) (xy 128.244749 -293.673172) (xy 128.224801 -293.626352)
			(xy 128.212622 -293.576938) (xy 128.208527 -293.52621) (xy 127.890016 -293.52621) (xy 127.889574 -293.54955)
			(xy 127.882476 -293.595688) (xy 127.868447 -293.64021) (xy 127.85852 -293.661338) (xy 127.856742 -293.664894)
			(xy 127.845111 -293.686673) (xy 127.815896 -293.726473) (xy 127.780638 -293.761034) (xy 127.76073 -293.775638)
			(xy 127.753554 -293.781117) (xy 127.743289 -293.795954) (xy 127.740664 -293.804594) (xy 127.728996 -293.8487)
			(xy 127.699476 -293.935034) (xy 127.663092 -294.018707) (xy 127.62008 -294.099175) (xy 127.570721 -294.175913)
			(xy 127.515336 -294.248422) (xy 127.48514 -294.282622) (xy 127.47879 -294.289734) (xy 127.472186 -294.307006)
			(xy 127.472186 -294.336216) (xy 127.749058 -294.336216) (xy 127.753018 -294.287162) (xy 127.764795 -294.239378)
			(xy 127.784086 -294.194102) (xy 127.810389 -294.152506) (xy 127.843024 -294.115669) (xy 127.881145 -294.084544)
			(xy 127.923766 -294.059937) (xy 127.969782 -294.042485) (xy 128.018001 -294.032641) (xy 128.067176 -294.03066)
			(xy 128.116031 -294.036592) (xy 128.163302 -294.050284) (xy 128.207764 -294.071382) (xy 128.248267 -294.099338)
			(xy 128.28376 -294.13343) (xy 128.313325 -294.172774) (xy 128.336196 -294.216351) (xy 128.35178 -294.263032)
			(xy 128.359675 -294.311609) (xy 128.36017 -294.336216) (xy 128.688858 -294.336216) (xy 128.692818 -294.287162)
			(xy 128.704595 -294.239378) (xy 128.723886 -294.194102) (xy 128.750189 -294.152506) (xy 128.782824 -294.115669)
			(xy 128.820945 -294.084544) (xy 128.863566 -294.059937) (xy 128.909582 -294.042485) (xy 128.957801 -294.032641)
			(xy 129.006976 -294.03066) (xy 129.055831 -294.036592) (xy 129.103102 -294.050284) (xy 129.147564 -294.071382)
			(xy 129.188067 -294.099338) (xy 129.22356 -294.13343) (xy 129.253125 -294.172774) (xy 129.275996 -294.216351)
			(xy 129.29158 -294.263032) (xy 129.299475 -294.311609) (xy 129.29997 -294.336216) (xy 129.628912 -294.336216)
			(xy 129.632872 -294.287162) (xy 129.644649 -294.239378) (xy 129.66394 -294.194102) (xy 129.690243 -294.152506)
			(xy 129.722878 -294.115669) (xy 129.760999 -294.084544) (xy 129.80362 -294.059937) (xy 129.849636 -294.042485)
			(xy 129.897855 -294.032641) (xy 129.94703 -294.03066) (xy 129.995885 -294.036592) (xy 130.043156 -294.050284)
			(xy 130.087618 -294.071382) (xy 130.128121 -294.099338) (xy 130.163614 -294.13343) (xy 130.193179 -294.172774)
			(xy 130.21605 -294.216351) (xy 130.231634 -294.263032) (xy 130.239529 -294.311609) (xy 130.240024 -294.336216)
			(xy 130.568966 -294.336216) (xy 130.572926 -294.287162) (xy 130.584703 -294.239378) (xy 130.603994 -294.194102)
			(xy 130.630297 -294.152506) (xy 130.662932 -294.115669) (xy 130.701053 -294.084544) (xy 130.743674 -294.059937)
			(xy 130.78969 -294.042485) (xy 130.837909 -294.032641) (xy 130.887084 -294.03066) (xy 130.935939 -294.036592)
			(xy 130.98321 -294.050284) (xy 131.027672 -294.071382) (xy 131.068175 -294.099338) (xy 131.103668 -294.13343)
			(xy 131.133233 -294.172774) (xy 131.156104 -294.216351) (xy 131.171688 -294.263032) (xy 131.179583 -294.311609)
			(xy 131.180078 -294.336216) (xy 131.50902 -294.336216) (xy 131.51298 -294.287162) (xy 131.524757 -294.239378)
			(xy 131.544048 -294.194102) (xy 131.570351 -294.152506) (xy 131.602986 -294.115669) (xy 131.641107 -294.084544)
			(xy 131.683728 -294.059937) (xy 131.729744 -294.042485) (xy 131.777963 -294.032641) (xy 131.827138 -294.03066)
			(xy 131.875993 -294.036592) (xy 131.923264 -294.050284) (xy 131.967726 -294.071382) (xy 132.008229 -294.099338)
			(xy 132.043722 -294.13343) (xy 132.073287 -294.172774) (xy 132.096158 -294.216351) (xy 132.111742 -294.263032)
			(xy 132.119637 -294.311609) (xy 132.120132 -294.336216) (xy 132.449074 -294.336216) (xy 132.453034 -294.287162)
			(xy 132.464811 -294.239378) (xy 132.484102 -294.194102) (xy 132.510405 -294.152506) (xy 132.54304 -294.115669)
			(xy 132.581161 -294.084544) (xy 132.623782 -294.059937) (xy 132.669798 -294.042485) (xy 132.718017 -294.032641)
			(xy 132.767192 -294.03066) (xy 132.816047 -294.036592) (xy 132.863318 -294.050284) (xy 132.90778 -294.071382)
			(xy 132.948283 -294.099338) (xy 132.983776 -294.13343) (xy 133.013341 -294.172774) (xy 133.036212 -294.216351)
			(xy 133.051796 -294.263032) (xy 133.059691 -294.311609) (xy 133.060186 -294.336216) (xy 133.388874 -294.336216)
			(xy 133.392834 -294.287162) (xy 133.404611 -294.239378) (xy 133.423902 -294.194102) (xy 133.450205 -294.152506)
			(xy 133.48284 -294.115669) (xy 133.520961 -294.084544) (xy 133.563582 -294.059937) (xy 133.609598 -294.042485)
			(xy 133.657817 -294.032641) (xy 133.706992 -294.03066) (xy 133.755847 -294.036592) (xy 133.803118 -294.050284)
			(xy 133.84758 -294.071382) (xy 133.888083 -294.099338) (xy 133.923576 -294.13343) (xy 133.953141 -294.172774)
			(xy 133.976012 -294.216351) (xy 133.991596 -294.263032) (xy 133.999491 -294.311609) (xy 133.999986 -294.336216)
			(xy 134.328928 -294.336216) (xy 134.332888 -294.287162) (xy 134.344665 -294.239378) (xy 134.363956 -294.194102)
			(xy 134.390259 -294.152506) (xy 134.422894 -294.115669) (xy 134.461015 -294.084544) (xy 134.503636 -294.059937)
			(xy 134.549652 -294.042485) (xy 134.597871 -294.032641) (xy 134.647046 -294.03066) (xy 134.695901 -294.036592)
			(xy 134.743172 -294.050284) (xy 134.787634 -294.071382) (xy 134.828137 -294.099338) (xy 134.86363 -294.13343)
			(xy 134.893195 -294.172774) (xy 134.916066 -294.216351) (xy 134.93165 -294.263032) (xy 134.939545 -294.311609)
			(xy 134.94004 -294.336216) (xy 135.268982 -294.336216) (xy 135.272942 -294.287162) (xy 135.284719 -294.239378)
			(xy 135.30401 -294.194102) (xy 135.330313 -294.152506) (xy 135.362948 -294.115669) (xy 135.401069 -294.084544)
			(xy 135.44369 -294.059937) (xy 135.489706 -294.042485) (xy 135.537925 -294.032641) (xy 135.5871 -294.03066)
			(xy 135.635955 -294.036592) (xy 135.683226 -294.050284) (xy 135.727688 -294.071382) (xy 135.768191 -294.099338)
			(xy 135.803684 -294.13343) (xy 135.833249 -294.172774) (xy 135.85612 -294.216351) (xy 135.871704 -294.263032)
			(xy 135.879599 -294.311609) (xy 135.880094 -294.336216) (xy 136.209036 -294.336216) (xy 136.212996 -294.287162)
			(xy 136.224773 -294.239378) (xy 136.244064 -294.194102) (xy 136.270367 -294.152506) (xy 136.303002 -294.115669)
			(xy 136.341123 -294.084544) (xy 136.383744 -294.059937) (xy 136.42976 -294.042485) (xy 136.477979 -294.032641)
			(xy 136.527154 -294.03066) (xy 136.576009 -294.036592) (xy 136.62328 -294.050284) (xy 136.667742 -294.071382)
			(xy 136.708245 -294.099338) (xy 136.743738 -294.13343) (xy 136.773303 -294.172774) (xy 136.796174 -294.216351)
			(xy 136.811758 -294.263032) (xy 136.819653 -294.311609) (xy 136.820148 -294.336216) (xy 137.148836 -294.336216)
			(xy 137.152796 -294.287162) (xy 137.164573 -294.239378) (xy 137.183864 -294.194102) (xy 137.210167 -294.152506)
			(xy 137.242802 -294.115669) (xy 137.280923 -294.084544) (xy 137.323544 -294.059937) (xy 137.36956 -294.042485)
			(xy 137.417779 -294.032641) (xy 137.466954 -294.03066) (xy 137.515809 -294.036592) (xy 137.56308 -294.050284)
			(xy 137.607542 -294.071382) (xy 137.648045 -294.099338) (xy 137.683538 -294.13343) (xy 137.713103 -294.172774)
			(xy 137.735974 -294.216351) (xy 137.751558 -294.263032) (xy 137.759453 -294.311609) (xy 137.759948 -294.336216)
			(xy 137.759453 -294.360823) (xy 137.751558 -294.4094) (xy 137.735974 -294.456081) (xy 137.713103 -294.499658)
			(xy 137.683538 -294.539002) (xy 137.648045 -294.573094) (xy 137.607542 -294.60105) (xy 137.56308 -294.622148)
			(xy 137.515809 -294.63584) (xy 137.466954 -294.641772) (xy 137.417779 -294.639791) (xy 137.36956 -294.629947)
			(xy 137.323544 -294.612495) (xy 137.280923 -294.587888) (xy 137.242802 -294.556763) (xy 137.210167 -294.519926)
			(xy 137.183864 -294.47833) (xy 137.164573 -294.433054) (xy 137.152796 -294.38527) (xy 137.148836 -294.336216)
			(xy 136.820148 -294.336216) (xy 136.819653 -294.360823) (xy 136.811758 -294.4094) (xy 136.796174 -294.456081)
			(xy 136.773303 -294.499658) (xy 136.743738 -294.539002) (xy 136.708245 -294.573094) (xy 136.667742 -294.60105)
			(xy 136.62328 -294.622148) (xy 136.576009 -294.63584) (xy 136.527154 -294.641772) (xy 136.477979 -294.639791)
			(xy 136.42976 -294.629947) (xy 136.383744 -294.612495) (xy 136.341123 -294.587888) (xy 136.303002 -294.556763)
			(xy 136.270367 -294.519926) (xy 136.244064 -294.47833) (xy 136.224773 -294.433054) (xy 136.212996 -294.38527)
			(xy 136.209036 -294.336216) (xy 135.880094 -294.336216) (xy 135.879599 -294.360823) (xy 135.871704 -294.4094)
			(xy 135.85612 -294.456081) (xy 135.833249 -294.499658) (xy 135.803684 -294.539002) (xy 135.768191 -294.573094)
			(xy 135.727688 -294.60105) (xy 135.683226 -294.622148) (xy 135.635955 -294.63584) (xy 135.5871 -294.641772)
			(xy 135.537925 -294.639791) (xy 135.489706 -294.629947) (xy 135.44369 -294.612495) (xy 135.401069 -294.587888)
			(xy 135.362948 -294.556763) (xy 135.330313 -294.519926) (xy 135.30401 -294.47833) (xy 135.284719 -294.433054)
			(xy 135.272942 -294.38527) (xy 135.268982 -294.336216) (xy 134.94004 -294.336216) (xy 134.939545 -294.360823)
			(xy 134.93165 -294.4094) (xy 134.916066 -294.456081) (xy 134.893195 -294.499658) (xy 134.86363 -294.539002)
			(xy 134.828137 -294.573094) (xy 134.787634 -294.60105) (xy 134.743172 -294.622148) (xy 134.695901 -294.63584)
			(xy 134.647046 -294.641772) (xy 134.597871 -294.639791) (xy 134.549652 -294.629947) (xy 134.503636 -294.612495)
			(xy 134.461015 -294.587888) (xy 134.422894 -294.556763) (xy 134.390259 -294.519926) (xy 134.363956 -294.47833)
			(xy 134.344665 -294.433054) (xy 134.332888 -294.38527) (xy 134.328928 -294.336216) (xy 133.999986 -294.336216)
			(xy 133.999491 -294.360823) (xy 133.991596 -294.4094) (xy 133.976012 -294.456081) (xy 133.953141 -294.499658)
			(xy 133.923576 -294.539002) (xy 133.888083 -294.573094) (xy 133.84758 -294.60105) (xy 133.803118 -294.622148)
			(xy 133.755847 -294.63584) (xy 133.706992 -294.641772) (xy 133.657817 -294.639791) (xy 133.609598 -294.629947)
			(xy 133.563582 -294.612495) (xy 133.520961 -294.587888) (xy 133.48284 -294.556763) (xy 133.450205 -294.519926)
			(xy 133.423902 -294.47833) (xy 133.404611 -294.433054) (xy 133.392834 -294.38527) (xy 133.388874 -294.336216)
			(xy 133.060186 -294.336216) (xy 133.059691 -294.360823) (xy 133.051796 -294.4094) (xy 133.036212 -294.456081)
			(xy 133.013341 -294.499658) (xy 132.983776 -294.539002) (xy 132.948283 -294.573094) (xy 132.90778 -294.60105)
			(xy 132.863318 -294.622148) (xy 132.816047 -294.63584) (xy 132.767192 -294.641772) (xy 132.718017 -294.639791)
			(xy 132.669798 -294.629947) (xy 132.623782 -294.612495) (xy 132.581161 -294.587888) (xy 132.54304 -294.556763)
			(xy 132.510405 -294.519926) (xy 132.484102 -294.47833) (xy 132.464811 -294.433054) (xy 132.453034 -294.38527)
			(xy 132.449074 -294.336216) (xy 132.120132 -294.336216) (xy 132.119637 -294.360823) (xy 132.111742 -294.4094)
			(xy 132.096158 -294.456081) (xy 132.073287 -294.499658) (xy 132.043722 -294.539002) (xy 132.008229 -294.573094)
			(xy 131.967726 -294.60105) (xy 131.923264 -294.622148) (xy 131.875993 -294.63584) (xy 131.827138 -294.641772)
			(xy 131.777963 -294.639791) (xy 131.729744 -294.629947) (xy 131.683728 -294.612495) (xy 131.641107 -294.587888)
			(xy 131.602986 -294.556763) (xy 131.570351 -294.519926) (xy 131.544048 -294.47833) (xy 131.524757 -294.433054)
			(xy 131.51298 -294.38527) (xy 131.50902 -294.336216) (xy 131.180078 -294.336216) (xy 131.179583 -294.360823)
			(xy 131.171688 -294.4094) (xy 131.156104 -294.456081) (xy 131.133233 -294.499658) (xy 131.103668 -294.539002)
			(xy 131.068175 -294.573094) (xy 131.027672 -294.60105) (xy 130.98321 -294.622148) (xy 130.935939 -294.63584)
			(xy 130.887084 -294.641772) (xy 130.837909 -294.639791) (xy 130.78969 -294.629947) (xy 130.743674 -294.612495)
			(xy 130.701053 -294.587888) (xy 130.662932 -294.556763) (xy 130.630297 -294.519926) (xy 130.603994 -294.47833)
			(xy 130.584703 -294.433054) (xy 130.572926 -294.38527) (xy 130.568966 -294.336216) (xy 130.240024 -294.336216)
			(xy 130.239529 -294.360823) (xy 130.231634 -294.4094) (xy 130.21605 -294.456081) (xy 130.193179 -294.499658)
			(xy 130.163614 -294.539002) (xy 130.128121 -294.573094) (xy 130.087618 -294.60105) (xy 130.043156 -294.622148)
			(xy 129.995885 -294.63584) (xy 129.94703 -294.641772) (xy 129.897855 -294.639791) (xy 129.849636 -294.629947)
			(xy 129.80362 -294.612495) (xy 129.760999 -294.587888) (xy 129.722878 -294.556763) (xy 129.690243 -294.519926)
			(xy 129.66394 -294.47833) (xy 129.644649 -294.433054) (xy 129.632872 -294.38527) (xy 129.628912 -294.336216)
			(xy 129.29997 -294.336216) (xy 129.299475 -294.360823) (xy 129.29158 -294.4094) (xy 129.275996 -294.456081)
			(xy 129.253125 -294.499658) (xy 129.22356 -294.539002) (xy 129.188067 -294.573094) (xy 129.147564 -294.60105)
			(xy 129.103102 -294.622148) (xy 129.055831 -294.63584) (xy 129.006976 -294.641772) (xy 128.957801 -294.639791)
			(xy 128.909582 -294.629947) (xy 128.863566 -294.612495) (xy 128.820945 -294.587888) (xy 128.782824 -294.556763)
			(xy 128.750189 -294.519926) (xy 128.723886 -294.47833) (xy 128.704595 -294.433054) (xy 128.692818 -294.38527)
			(xy 128.688858 -294.336216) (xy 128.36017 -294.336216) (xy 128.359675 -294.360823) (xy 128.35178 -294.4094)
			(xy 128.336196 -294.456081) (xy 128.313325 -294.499658) (xy 128.28376 -294.539002) (xy 128.248267 -294.573094)
			(xy 128.207764 -294.60105) (xy 128.163302 -294.622148) (xy 128.116031 -294.63584) (xy 128.067176 -294.641772)
			(xy 128.018001 -294.639791) (xy 127.969782 -294.629947) (xy 127.923766 -294.612495) (xy 127.881145 -294.587888)
			(xy 127.843024 -294.556763) (xy 127.810389 -294.519926) (xy 127.784086 -294.47833) (xy 127.764795 -294.433054)
			(xy 127.753018 -294.38527) (xy 127.749058 -294.336216) (xy 127.472186 -294.336216) (xy 127.472186 -294.365426)
			(xy 127.47879 -294.382698) (xy 127.48514 -294.38981) (xy 127.515326 -294.424018) (xy 127.570703 -294.49653)
			(xy 127.620056 -294.57327) (xy 127.663063 -294.653737) (xy 127.699446 -294.737409) (xy 127.728968 -294.82374)
			(xy 127.740664 -294.867838) (xy 127.743257 -294.876492) (xy 127.753529 -294.891339) (xy 127.76073 -294.896794)
			(xy 127.781045 -294.911773) (xy 127.816931 -294.947263) (xy 127.8465 -294.988166) (xy 127.868948 -295.033369)
			(xy 127.883666 -295.081646) (xy 127.887476 -295.106598) (xy 127.888746 -295.114726) (xy 127.903478 -295.145714)
			(xy 127.904007 -295.146222) (xy 128.218958 -295.146222) (xy 128.222918 -295.097168) (xy 128.234695 -295.049384)
			(xy 128.253986 -295.004108) (xy 128.280289 -294.962512) (xy 128.312924 -294.925675) (xy 128.351045 -294.89455)
			(xy 128.393666 -294.869943) (xy 128.439682 -294.852491) (xy 128.487901 -294.842647) (xy 128.537076 -294.840666)
			(xy 128.585931 -294.846598) (xy 128.633202 -294.86029) (xy 128.677664 -294.881388) (xy 128.718167 -294.909344)
			(xy 128.75366 -294.943436) (xy 128.783225 -294.98278) (xy 128.806096 -295.026357) (xy 128.82168 -295.073038)
			(xy 128.829575 -295.121615) (xy 128.83007 -295.146222) (xy 129.159012 -295.146222) (xy 129.162972 -295.097168)
			(xy 129.174749 -295.049384) (xy 129.19404 -295.004108) (xy 129.220343 -294.962512) (xy 129.252978 -294.925675)
			(xy 129.291099 -294.89455) (xy 129.33372 -294.869943) (xy 129.379736 -294.852491) (xy 129.427955 -294.842647)
			(xy 129.47713 -294.840666) (xy 129.525985 -294.846598) (xy 129.573256 -294.86029) (xy 129.617718 -294.881388)
			(xy 129.658221 -294.909344) (xy 129.693714 -294.943436) (xy 129.723279 -294.98278) (xy 129.74615 -295.026357)
			(xy 129.761734 -295.073038) (xy 129.769629 -295.121615) (xy 129.770124 -295.146222) (xy 130.099066 -295.146222)
			(xy 130.103026 -295.097168) (xy 130.114803 -295.049384) (xy 130.134094 -295.004108) (xy 130.160397 -294.962512)
			(xy 130.193032 -294.925675) (xy 130.231153 -294.89455) (xy 130.273774 -294.869943) (xy 130.31979 -294.852491)
			(xy 130.368009 -294.842647) (xy 130.417184 -294.840666) (xy 130.466039 -294.846598) (xy 130.51331 -294.86029)
			(xy 130.557772 -294.881388) (xy 130.598275 -294.909344) (xy 130.633768 -294.943436) (xy 130.663333 -294.98278)
			(xy 130.686204 -295.026357) (xy 130.701788 -295.073038) (xy 130.709683 -295.121615) (xy 130.710178 -295.146222)
			(xy 131.038866 -295.146222) (xy 131.042826 -295.097168) (xy 131.054603 -295.049384) (xy 131.073894 -295.004108)
			(xy 131.100197 -294.962512) (xy 131.132832 -294.925675) (xy 131.170953 -294.89455) (xy 131.213574 -294.869943)
			(xy 131.25959 -294.852491) (xy 131.307809 -294.842647) (xy 131.356984 -294.840666) (xy 131.405839 -294.846598)
			(xy 131.45311 -294.86029) (xy 131.497572 -294.881388) (xy 131.538075 -294.909344) (xy 131.573568 -294.943436)
			(xy 131.603133 -294.98278) (xy 131.626004 -295.026357) (xy 131.641588 -295.073038) (xy 131.649483 -295.121615)
			(xy 131.649978 -295.146222) (xy 131.97892 -295.146222) (xy 131.98288 -295.097168) (xy 131.994657 -295.049384)
			(xy 132.013948 -295.004108) (xy 132.040251 -294.962512) (xy 132.072886 -294.925675) (xy 132.111007 -294.89455)
			(xy 132.153628 -294.869943) (xy 132.199644 -294.852491) (xy 132.247863 -294.842647) (xy 132.297038 -294.840666)
			(xy 132.345893 -294.846598) (xy 132.393164 -294.86029) (xy 132.437626 -294.881388) (xy 132.478129 -294.909344)
			(xy 132.513622 -294.943436) (xy 132.543187 -294.98278) (xy 132.566058 -295.026357) (xy 132.581642 -295.073038)
			(xy 132.589537 -295.121615) (xy 132.590032 -295.146222) (xy 132.918974 -295.146222) (xy 132.922934 -295.097168)
			(xy 132.934711 -295.049384) (xy 132.954002 -295.004108) (xy 132.980305 -294.962512) (xy 133.01294 -294.925675)
			(xy 133.051061 -294.89455) (xy 133.093682 -294.869943) (xy 133.139698 -294.852491) (xy 133.187917 -294.842647)
			(xy 133.237092 -294.840666) (xy 133.285947 -294.846598) (xy 133.333218 -294.86029) (xy 133.37768 -294.881388)
			(xy 133.418183 -294.909344) (xy 133.453676 -294.943436) (xy 133.483241 -294.98278) (xy 133.506112 -295.026357)
			(xy 133.521696 -295.073038) (xy 133.529591 -295.121615) (xy 133.530086 -295.146222) (xy 133.859028 -295.146222)
			(xy 133.862988 -295.097168) (xy 133.874765 -295.049384) (xy 133.894056 -295.004108) (xy 133.920359 -294.962512)
			(xy 133.952994 -294.925675) (xy 133.991115 -294.89455) (xy 134.033736 -294.869943) (xy 134.079752 -294.852491)
			(xy 134.127971 -294.842647) (xy 134.177146 -294.840666) (xy 134.226001 -294.846598) (xy 134.273272 -294.86029)
			(xy 134.317734 -294.881388) (xy 134.358237 -294.909344) (xy 134.39373 -294.943436) (xy 134.423295 -294.98278)
			(xy 134.446166 -295.026357) (xy 134.46175 -295.073038) (xy 134.469645 -295.121615) (xy 134.47014 -295.146222)
			(xy 134.798828 -295.146222) (xy 134.802788 -295.097168) (xy 134.814565 -295.049384) (xy 134.833856 -295.004108)
			(xy 134.860159 -294.962512) (xy 134.892794 -294.925675) (xy 134.930915 -294.89455) (xy 134.973536 -294.869943)
			(xy 135.019552 -294.852491) (xy 135.067771 -294.842647) (xy 135.116946 -294.840666) (xy 135.165801 -294.846598)
			(xy 135.213072 -294.86029) (xy 135.257534 -294.881388) (xy 135.298037 -294.909344) (xy 135.33353 -294.943436)
			(xy 135.363095 -294.98278) (xy 135.385966 -295.026357) (xy 135.40155 -295.073038) (xy 135.409445 -295.121615)
			(xy 135.40994 -295.146222) (xy 135.738882 -295.146222) (xy 135.742842 -295.097168) (xy 135.754619 -295.049384)
			(xy 135.77391 -295.004108) (xy 135.800213 -294.962512) (xy 135.832848 -294.925675) (xy 135.870969 -294.89455)
			(xy 135.91359 -294.869943) (xy 135.959606 -294.852491) (xy 136.007825 -294.842647) (xy 136.057 -294.840666)
			(xy 136.105855 -294.846598) (xy 136.153126 -294.86029) (xy 136.197588 -294.881388) (xy 136.238091 -294.909344)
			(xy 136.273584 -294.943436) (xy 136.303149 -294.98278) (xy 136.32602 -295.026357) (xy 136.341604 -295.073038)
			(xy 136.349499 -295.121615) (xy 136.349994 -295.146222) (xy 136.678936 -295.146222) (xy 136.682896 -295.097168)
			(xy 136.694673 -295.049384) (xy 136.713964 -295.004108) (xy 136.740267 -294.962512) (xy 136.772902 -294.925675)
			(xy 136.811023 -294.89455) (xy 136.853644 -294.869943) (xy 136.89966 -294.852491) (xy 136.947879 -294.842647)
			(xy 136.997054 -294.840666) (xy 137.045909 -294.846598) (xy 137.09318 -294.86029) (xy 137.137642 -294.881388)
			(xy 137.178145 -294.909344) (xy 137.213638 -294.943436) (xy 137.243203 -294.98278) (xy 137.266074 -295.026357)
			(xy 137.281658 -295.073038) (xy 137.289553 -295.121615) (xy 137.290048 -295.146222) (xy 137.61899 -295.146222)
			(xy 137.62295 -295.097168) (xy 137.634727 -295.049384) (xy 137.654018 -295.004108) (xy 137.680321 -294.962512)
			(xy 137.712956 -294.925675) (xy 137.751077 -294.89455) (xy 137.793698 -294.869943) (xy 137.839714 -294.852491)
			(xy 137.887933 -294.842647) (xy 137.937108 -294.840666) (xy 137.985963 -294.846598) (xy 138.033234 -294.86029)
			(xy 138.077696 -294.881388) (xy 138.118199 -294.909344) (xy 138.153692 -294.943436) (xy 138.183257 -294.98278)
			(xy 138.206128 -295.026357) (xy 138.221712 -295.073038) (xy 138.229607 -295.121615) (xy 138.230102 -295.146222)
			(xy 138.559044 -295.146222) (xy 138.563004 -295.097168) (xy 138.574781 -295.049384) (xy 138.594072 -295.004108)
			(xy 138.620375 -294.962512) (xy 138.65301 -294.925675) (xy 138.691131 -294.89455) (xy 138.733752 -294.869943)
			(xy 138.779768 -294.852491) (xy 138.827987 -294.842647) (xy 138.877162 -294.840666) (xy 138.926017 -294.846598)
			(xy 138.973288 -294.86029) (xy 139.01775 -294.881388) (xy 139.058253 -294.909344) (xy 139.093746 -294.943436)
			(xy 139.123311 -294.98278) (xy 139.146182 -295.026357) (xy 139.161766 -295.073038) (xy 139.169661 -295.121615)
			(xy 139.170156 -295.146222) (xy 140.438898 -295.146222) (xy 140.442858 -295.097168) (xy 140.454635 -295.049384)
			(xy 140.473926 -295.004108) (xy 140.500229 -294.962512) (xy 140.532864 -294.925675) (xy 140.570985 -294.89455)
			(xy 140.613606 -294.869943) (xy 140.659622 -294.852491) (xy 140.707841 -294.842647) (xy 140.757016 -294.840666)
			(xy 140.805871 -294.846598) (xy 140.853142 -294.86029) (xy 140.897604 -294.881388) (xy 140.938107 -294.909344)
			(xy 140.9736 -294.943436) (xy 141.003165 -294.98278) (xy 141.026036 -295.026357) (xy 141.04162 -295.073038)
			(xy 141.049515 -295.121615) (xy 141.05001 -295.146222) (xy 141.378952 -295.146222) (xy 141.382912 -295.097168)
			(xy 141.394689 -295.049384) (xy 141.41398 -295.004108) (xy 141.440283 -294.962512) (xy 141.472918 -294.925675)
			(xy 141.511039 -294.89455) (xy 141.55366 -294.869943) (xy 141.599676 -294.852491) (xy 141.647895 -294.842647)
			(xy 141.69707 -294.840666) (xy 141.745925 -294.846598) (xy 141.793196 -294.86029) (xy 141.837658 -294.881388)
			(xy 141.878161 -294.909344) (xy 141.913654 -294.943436) (xy 141.943219 -294.98278) (xy 141.96609 -295.026357)
			(xy 141.981674 -295.073038) (xy 141.989569 -295.121615) (xy 141.990064 -295.146222) (xy 141.989569 -295.170829)
			(xy 141.981674 -295.219406) (xy 141.96609 -295.266087) (xy 141.943219 -295.309664) (xy 141.913654 -295.349008)
			(xy 141.878161 -295.3831) (xy 141.837658 -295.411056) (xy 141.793196 -295.432154) (xy 141.745925 -295.445846)
			(xy 141.69707 -295.451778) (xy 141.647895 -295.449797) (xy 141.599676 -295.439953) (xy 141.55366 -295.422501)
			(xy 141.511039 -295.397894) (xy 141.472918 -295.366769) (xy 141.440283 -295.329932) (xy 141.41398 -295.288336)
			(xy 141.394689 -295.24306) (xy 141.382912 -295.195276) (xy 141.378952 -295.146222) (xy 141.05001 -295.146222)
			(xy 141.049515 -295.170829) (xy 141.04162 -295.219406) (xy 141.026036 -295.266087) (xy 141.003165 -295.309664)
			(xy 140.9736 -295.349008) (xy 140.938107 -295.3831) (xy 140.897604 -295.411056) (xy 140.853142 -295.432154)
			(xy 140.805871 -295.445846) (xy 140.757016 -295.451778) (xy 140.707841 -295.449797) (xy 140.659622 -295.439953)
			(xy 140.613606 -295.422501) (xy 140.570985 -295.397894) (xy 140.532864 -295.366769) (xy 140.500229 -295.329932)
			(xy 140.473926 -295.288336) (xy 140.454635 -295.24306) (xy 140.442858 -295.195276) (xy 140.438898 -295.146222)
			(xy 139.170156 -295.146222) (xy 139.169661 -295.170829) (xy 139.161766 -295.219406) (xy 139.146182 -295.266087)
			(xy 139.123311 -295.309664) (xy 139.093746 -295.349008) (xy 139.058253 -295.3831) (xy 139.01775 -295.411056)
			(xy 138.973288 -295.432154) (xy 138.926017 -295.445846) (xy 138.877162 -295.451778) (xy 138.827987 -295.449797)
			(xy 138.779768 -295.439953) (xy 138.733752 -295.422501) (xy 138.691131 -295.397894) (xy 138.65301 -295.366769)
			(xy 138.620375 -295.329932) (xy 138.594072 -295.288336) (xy 138.574781 -295.24306) (xy 138.563004 -295.195276)
			(xy 138.559044 -295.146222) (xy 138.230102 -295.146222) (xy 138.229607 -295.170829) (xy 138.221712 -295.219406)
			(xy 138.206128 -295.266087) (xy 138.183257 -295.309664) (xy 138.153692 -295.349008) (xy 138.118199 -295.3831)
			(xy 138.077696 -295.411056) (xy 138.033234 -295.432154) (xy 137.985963 -295.445846) (xy 137.937108 -295.451778)
			(xy 137.887933 -295.449797) (xy 137.839714 -295.439953) (xy 137.793698 -295.422501) (xy 137.751077 -295.397894)
			(xy 137.712956 -295.366769) (xy 137.680321 -295.329932) (xy 137.654018 -295.288336) (xy 137.634727 -295.24306)
			(xy 137.62295 -295.195276) (xy 137.61899 -295.146222) (xy 137.290048 -295.146222) (xy 137.289553 -295.170829)
			(xy 137.281658 -295.219406) (xy 137.266074 -295.266087) (xy 137.243203 -295.309664) (xy 137.213638 -295.349008)
			(xy 137.178145 -295.3831) (xy 137.137642 -295.411056) (xy 137.09318 -295.432154) (xy 137.045909 -295.445846)
			(xy 136.997054 -295.451778) (xy 136.947879 -295.449797) (xy 136.89966 -295.439953) (xy 136.853644 -295.422501)
			(xy 136.811023 -295.397894) (xy 136.772902 -295.366769) (xy 136.740267 -295.329932) (xy 136.713964 -295.288336)
			(xy 136.694673 -295.24306) (xy 136.682896 -295.195276) (xy 136.678936 -295.146222) (xy 136.349994 -295.146222)
			(xy 136.349499 -295.170829) (xy 136.341604 -295.219406) (xy 136.32602 -295.266087) (xy 136.303149 -295.309664)
			(xy 136.273584 -295.349008) (xy 136.238091 -295.3831) (xy 136.197588 -295.411056) (xy 136.153126 -295.432154)
			(xy 136.105855 -295.445846) (xy 136.057 -295.451778) (xy 136.007825 -295.449797) (xy 135.959606 -295.439953)
			(xy 135.91359 -295.422501) (xy 135.870969 -295.397894) (xy 135.832848 -295.366769) (xy 135.800213 -295.329932)
			(xy 135.77391 -295.288336) (xy 135.754619 -295.24306) (xy 135.742842 -295.195276) (xy 135.738882 -295.146222)
			(xy 135.40994 -295.146222) (xy 135.409445 -295.170829) (xy 135.40155 -295.219406) (xy 135.385966 -295.266087)
			(xy 135.363095 -295.309664) (xy 135.33353 -295.349008) (xy 135.298037 -295.3831) (xy 135.257534 -295.411056)
			(xy 135.213072 -295.432154) (xy 135.165801 -295.445846) (xy 135.116946 -295.451778) (xy 135.067771 -295.449797)
			(xy 135.019552 -295.439953) (xy 134.973536 -295.422501) (xy 134.930915 -295.397894) (xy 134.892794 -295.366769)
			(xy 134.860159 -295.329932) (xy 134.833856 -295.288336) (xy 134.814565 -295.24306) (xy 134.802788 -295.195276)
			(xy 134.798828 -295.146222) (xy 134.47014 -295.146222) (xy 134.469645 -295.170829) (xy 134.46175 -295.219406)
			(xy 134.446166 -295.266087) (xy 134.423295 -295.309664) (xy 134.39373 -295.349008) (xy 134.358237 -295.3831)
			(xy 134.317734 -295.411056) (xy 134.273272 -295.432154) (xy 134.226001 -295.445846) (xy 134.177146 -295.451778)
			(xy 134.127971 -295.449797) (xy 134.079752 -295.439953) (xy 134.033736 -295.422501) (xy 133.991115 -295.397894)
			(xy 133.952994 -295.366769) (xy 133.920359 -295.329932) (xy 133.894056 -295.288336) (xy 133.874765 -295.24306)
			(xy 133.862988 -295.195276) (xy 133.859028 -295.146222) (xy 133.530086 -295.146222) (xy 133.529591 -295.170829)
			(xy 133.521696 -295.219406) (xy 133.506112 -295.266087) (xy 133.483241 -295.309664) (xy 133.453676 -295.349008)
			(xy 133.418183 -295.3831) (xy 133.37768 -295.411056) (xy 133.333218 -295.432154) (xy 133.285947 -295.445846)
			(xy 133.237092 -295.451778) (xy 133.187917 -295.449797) (xy 133.139698 -295.439953) (xy 133.093682 -295.422501)
			(xy 133.051061 -295.397894) (xy 133.01294 -295.366769) (xy 132.980305 -295.329932) (xy 132.954002 -295.288336)
			(xy 132.934711 -295.24306) (xy 132.922934 -295.195276) (xy 132.918974 -295.146222) (xy 132.590032 -295.146222)
			(xy 132.589537 -295.170829) (xy 132.581642 -295.219406) (xy 132.566058 -295.266087) (xy 132.543187 -295.309664)
			(xy 132.513622 -295.349008) (xy 132.478129 -295.3831) (xy 132.437626 -295.411056) (xy 132.393164 -295.432154)
			(xy 132.345893 -295.445846) (xy 132.297038 -295.451778) (xy 132.247863 -295.449797) (xy 132.199644 -295.439953)
			(xy 132.153628 -295.422501) (xy 132.111007 -295.397894) (xy 132.072886 -295.366769) (xy 132.040251 -295.329932)
			(xy 132.013948 -295.288336) (xy 131.994657 -295.24306) (xy 131.98288 -295.195276) (xy 131.97892 -295.146222)
			(xy 131.649978 -295.146222) (xy 131.649483 -295.170829) (xy 131.641588 -295.219406) (xy 131.626004 -295.266087)
			(xy 131.603133 -295.309664) (xy 131.573568 -295.349008) (xy 131.538075 -295.3831) (xy 131.497572 -295.411056)
			(xy 131.45311 -295.432154) (xy 131.405839 -295.445846) (xy 131.356984 -295.451778) (xy 131.307809 -295.449797)
			(xy 131.25959 -295.439953) (xy 131.213574 -295.422501) (xy 131.170953 -295.397894) (xy 131.132832 -295.366769)
			(xy 131.100197 -295.329932) (xy 131.073894 -295.288336) (xy 131.054603 -295.24306) (xy 131.042826 -295.195276)
			(xy 131.038866 -295.146222) (xy 130.710178 -295.146222) (xy 130.709683 -295.170829) (xy 130.701788 -295.219406)
			(xy 130.686204 -295.266087) (xy 130.663333 -295.309664) (xy 130.633768 -295.349008) (xy 130.598275 -295.3831)
			(xy 130.557772 -295.411056) (xy 130.51331 -295.432154) (xy 130.466039 -295.445846) (xy 130.417184 -295.451778)
			(xy 130.368009 -295.449797) (xy 130.31979 -295.439953) (xy 130.273774 -295.422501) (xy 130.231153 -295.397894)
			(xy 130.193032 -295.366769) (xy 130.160397 -295.329932) (xy 130.134094 -295.288336) (xy 130.114803 -295.24306)
			(xy 130.103026 -295.195276) (xy 130.099066 -295.146222) (xy 129.770124 -295.146222) (xy 129.769629 -295.170829)
			(xy 129.761734 -295.219406) (xy 129.74615 -295.266087) (xy 129.723279 -295.309664) (xy 129.693714 -295.349008)
			(xy 129.658221 -295.3831) (xy 129.617718 -295.411056) (xy 129.573256 -295.432154) (xy 129.525985 -295.445846)
			(xy 129.47713 -295.451778) (xy 129.427955 -295.449797) (xy 129.379736 -295.439953) (xy 129.33372 -295.422501)
			(xy 129.291099 -295.397894) (xy 129.252978 -295.366769) (xy 129.220343 -295.329932) (xy 129.19404 -295.288336)
			(xy 129.174749 -295.24306) (xy 129.162972 -295.195276) (xy 129.159012 -295.146222) (xy 128.83007 -295.146222)
			(xy 128.829575 -295.170829) (xy 128.82168 -295.219406) (xy 128.806096 -295.266087) (xy 128.783225 -295.309664)
			(xy 128.75366 -295.349008) (xy 128.718167 -295.3831) (xy 128.677664 -295.411056) (xy 128.633202 -295.432154)
			(xy 128.585931 -295.445846) (xy 128.537076 -295.451778) (xy 128.487901 -295.449797) (xy 128.439682 -295.439953)
			(xy 128.393666 -295.422501) (xy 128.351045 -295.397894) (xy 128.312924 -295.366769) (xy 128.280289 -295.329932)
			(xy 128.253986 -295.288336) (xy 128.234695 -295.24306) (xy 128.222918 -295.195276) (xy 128.218958 -295.146222)
			(xy 127.904007 -295.146222) (xy 127.909828 -295.15181) (xy 127.94731 -295.189679) (xy 128.015753 -295.271349)
			(xy 128.04648 -295.314878) (xy 128.048258 -295.317672) (xy 128.075876 -295.358962) (xy 128.124587 -295.445543)
			(xy 128.16551 -295.536066) (xy 128.198329 -295.629832) (xy 128.211072 -295.677844) (xy 128.213618 -295.686469)
			(xy 128.22377 -295.701298) (xy 128.230884 -295.7068) (xy 128.250499 -295.721223) (xy 128.285317 -295.75525)
			(xy 128.314295 -295.794369) (xy 128.3367 -295.837591) (xy 128.351963 -295.883821) (xy 128.359699 -295.931886)
			(xy 128.36017 -295.956228) (xy 128.688858 -295.956228) (xy 128.692818 -295.907174) (xy 128.704595 -295.85939)
			(xy 128.723886 -295.814114) (xy 128.750189 -295.772518) (xy 128.782824 -295.735681) (xy 128.820945 -295.704556)
			(xy 128.863566 -295.679949) (xy 128.909582 -295.662497) (xy 128.957801 -295.652653) (xy 129.006976 -295.650672)
			(xy 129.055831 -295.656604) (xy 129.103102 -295.670296) (xy 129.147564 -295.691394) (xy 129.188067 -295.71935)
			(xy 129.22356 -295.753442) (xy 129.253125 -295.792786) (xy 129.275996 -295.836363) (xy 129.29158 -295.883044)
			(xy 129.299475 -295.931621) (xy 129.29997 -295.956228) (xy 129.628912 -295.956228) (xy 129.632872 -295.907174)
			(xy 129.644649 -295.85939) (xy 129.66394 -295.814114) (xy 129.690243 -295.772518) (xy 129.722878 -295.735681)
			(xy 129.760999 -295.704556) (xy 129.80362 -295.679949) (xy 129.849636 -295.662497) (xy 129.897855 -295.652653)
			(xy 129.94703 -295.650672) (xy 129.995885 -295.656604) (xy 130.043156 -295.670296) (xy 130.087618 -295.691394)
			(xy 130.128121 -295.71935) (xy 130.163614 -295.753442) (xy 130.193179 -295.792786) (xy 130.21605 -295.836363)
			(xy 130.231634 -295.883044) (xy 130.239529 -295.931621) (xy 130.240024 -295.956228) (xy 130.239529 -295.980835)
			(xy 130.237718 -295.991975) (xy 130.572409 -295.991975) (xy 130.575097 -295.942413) (xy 130.585767 -295.893939)
			(xy 130.604139 -295.847829) (xy 130.629728 -295.805299) (xy 130.66186 -295.767469) (xy 130.699689 -295.735335)
			(xy 130.742219 -295.709744) (xy 130.788327 -295.691371) (xy 130.836801 -295.680699) (xy 130.886363 -295.678009)
			(xy 130.935707 -295.683372) (xy 130.983534 -295.696647) (xy 131.028583 -295.717485) (xy 131.069667 -295.745336)
			(xy 131.105705 -295.779467) (xy 131.135747 -295.818977) (xy 131.159001 -295.862828) (xy 131.174855 -295.909863)
			(xy 131.182891 -295.958843) (xy 131.18338 -295.98366) (xy 131.183198 -295.997843) (xy 131.18053 -296.026083)
			(xy 131.178046 -296.040048) (xy 131.17576 -296.05224) (xy 131.182872 -296.075608) (xy 131.258056 -296.153332)
			(xy 131.28117 -296.160952) (xy 131.293616 -296.15892) (xy 131.307122 -296.156993) (xy 131.33433 -296.154955)
			(xy 131.347972 -296.154856) (xy 131.361682 -296.155013) (xy 131.389018 -296.157171) (xy 131.402582 -296.159174)
			(xy 131.415028 -296.160952) (xy 131.438142 -296.153332) (xy 131.513326 -296.075608) (xy 131.520438 -296.05224)
			(xy 131.518152 -296.040048) (xy 131.515673 -296.026083) (xy 131.513003 -295.997843) (xy 131.512818 -295.98366)
			(xy 131.51334 -295.958405) (xy 131.521653 -295.908583) (xy 131.538054 -295.860809) (xy 131.562095 -295.816386)
			(xy 131.593119 -295.776526) (xy 131.630281 -295.742316) (xy 131.672567 -295.71469) (xy 131.718823 -295.6944)
			(xy 131.767788 -295.682) (xy 131.818126 -295.677829) (xy 131.868464 -295.682) (xy 131.917429 -295.6944)
			(xy 131.963685 -295.71469) (xy 132.005971 -295.742316) (xy 132.043133 -295.776526) (xy 132.074157 -295.816386)
			(xy 132.098198 -295.860809) (xy 132.114599 -295.908583) (xy 132.122912 -295.958405) (xy 132.123434 -295.98366)
			(xy 132.123249 -295.997779) (xy 132.120576 -296.025892) (xy 132.1181 -296.039794) (xy 132.115814 -296.05224)
			(xy 132.122926 -296.075608) (xy 132.19811 -296.153078) (xy 132.221224 -296.160952) (xy 132.233416 -296.15892)
			(xy 132.246922 -296.156993) (xy 132.27413 -296.154955) (xy 132.287772 -296.154856) (xy 132.301546 -296.154995)
			(xy 132.329009 -296.157158) (xy 132.342636 -296.159174) (xy 132.355082 -296.160952) (xy 132.378196 -296.153332)
			(xy 132.45338 -296.075608) (xy 132.460492 -296.05224) (xy 132.458206 -296.040048) (xy 132.455726 -296.026083)
			(xy 132.453057 -295.997843) (xy 132.452872 -295.98366) (xy 132.453421 -295.958843) (xy 132.461457 -295.909863)
			(xy 132.477312 -295.862829) (xy 132.500566 -295.818979) (xy 132.530609 -295.779469) (xy 132.566647 -295.74534)
			(xy 132.607732 -295.71749) (xy 132.652782 -295.696654) (xy 132.700609 -295.683381) (xy 132.749953 -295.67802)
			(xy 132.799514 -295.680713) (xy 132.847987 -295.691388) (xy 132.894095 -295.709764) (xy 132.936622 -295.735358)
			(xy 132.974448 -295.767494) (xy 133.006577 -295.805327) (xy 133.032162 -295.847859) (xy 133.05053 -295.89397)
			(xy 133.061195 -295.942445) (xy 133.063877 -295.991981) (xy 133.392301 -295.991981) (xy 133.394988 -295.942417)
			(xy 133.405658 -295.893941) (xy 133.42403 -295.84783) (xy 133.449619 -295.805298) (xy 133.481752 -295.767466)
			(xy 133.519582 -295.735331) (xy 133.562112 -295.709739) (xy 133.608222 -295.691364) (xy 133.656697 -295.680691)
			(xy 133.706261 -295.678001) (xy 133.755607 -295.683364) (xy 133.803435 -295.696639) (xy 133.848485 -295.717477)
			(xy 133.889571 -295.745329) (xy 133.92561 -295.77946) (xy 133.955653 -295.818972) (xy 133.978908 -295.862824)
			(xy 133.994763 -295.90986) (xy 134.002799 -295.958842) (xy 134.003288 -295.98366) (xy 134.003106 -295.997843)
			(xy 134.000438 -296.026083) (xy 133.997954 -296.040048) (xy 133.995668 -296.05224) (xy 134.00278 -296.075608)
			(xy 134.077964 -296.153332) (xy 134.101078 -296.160952) (xy 134.113524 -296.15892) (xy 134.12703 -296.156992)
			(xy 134.154238 -296.154955) (xy 134.16788 -296.154856) (xy 134.18159 -296.155012) (xy 134.208926 -296.157171)
			(xy 134.22249 -296.159174) (xy 134.234936 -296.160952) (xy 134.25805 -296.153332) (xy 134.333234 -296.075608)
			(xy 134.340346 -296.05224) (xy 134.33806 -296.040048) (xy 134.335581 -296.026083) (xy 134.332911 -295.997843)
			(xy 134.332726 -295.98366) (xy 134.333248 -295.958405) (xy 134.341561 -295.908583) (xy 134.357962 -295.860809)
			(xy 134.382003 -295.816386) (xy 134.413027 -295.776526) (xy 134.450189 -295.742316) (xy 134.492475 -295.71469)
			(xy 134.538731 -295.6944) (xy 134.587696 -295.682) (xy 134.638034 -295.677829) (xy 134.688372 -295.682)
			(xy 134.737337 -295.6944) (xy 134.783593 -295.71469) (xy 134.825879 -295.742316) (xy 134.863041 -295.776526)
			(xy 134.894065 -295.816386) (xy 134.918106 -295.860809) (xy 134.934507 -295.908583) (xy 134.94282 -295.958405)
			(xy 134.943342 -295.98366) (xy 134.943159 -295.997843) (xy 134.940491 -296.026083) (xy 134.938008 -296.040048)
			(xy 134.935722 -296.05224) (xy 134.942834 -296.075608) (xy 135.018018 -296.153332) (xy 135.041132 -296.160952)
			(xy 135.053578 -296.15892) (xy 135.067083 -296.156986) (xy 135.094292 -296.154953) (xy 135.107934 -296.154856)
			(xy 135.121644 -296.155006) (xy 135.14898 -296.157169) (xy 135.162544 -296.159174) (xy 135.17499 -296.160952)
			(xy 135.198104 -296.153332) (xy 135.273288 -296.075608) (xy 135.2804 -296.05224) (xy 135.278114 -296.040048)
			(xy 135.275634 -296.026083) (xy 135.272965 -295.997843) (xy 135.27278 -295.98366) (xy 135.273321 -295.958843)
			(xy 135.281357 -295.909864) (xy 135.297211 -295.862829) (xy 135.320466 -295.81898) (xy 135.350508 -295.77947)
			(xy 135.386546 -295.745341) (xy 135.427631 -295.717491) (xy 135.47268 -295.696655) (xy 135.520506 -295.683382)
			(xy 135.56985 -295.67802) (xy 135.619411 -295.680712) (xy 135.667884 -295.691387) (xy 135.713992 -295.709763)
			(xy 135.756519 -295.735356) (xy 135.794345 -295.767492) (xy 135.826475 -295.805324) (xy 135.85206 -295.847855)
			(xy 135.870428 -295.893966) (xy 135.881095 -295.94244) (xy 135.881841 -295.956228) (xy 140.909052 -295.956228)
			(xy 140.913012 -295.907174) (xy 140.924789 -295.85939) (xy 140.94408 -295.814114) (xy 140.970383 -295.772518)
			(xy 141.003018 -295.735681) (xy 141.041139 -295.704556) (xy 141.08376 -295.679949) (xy 141.129776 -295.662497)
			(xy 141.177995 -295.652653) (xy 141.22717 -295.650672) (xy 141.276025 -295.656604) (xy 141.323296 -295.670296)
			(xy 141.367758 -295.691394) (xy 141.408261 -295.71935) (xy 141.443754 -295.753442) (xy 141.473319 -295.792786)
			(xy 141.49619 -295.836363) (xy 141.511774 -295.883044) (xy 141.519669 -295.931621) (xy 141.520164 -295.956228)
			(xy 141.519669 -295.980835) (xy 141.511774 -296.029412) (xy 141.49619 -296.076093) (xy 141.473319 -296.11967)
			(xy 141.443754 -296.159014) (xy 141.408261 -296.193106) (xy 141.367758 -296.221062) (xy 141.323296 -296.24216)
			(xy 141.276025 -296.255852) (xy 141.22717 -296.261784) (xy 141.177995 -296.259803) (xy 141.129776 -296.249959)
			(xy 141.08376 -296.232507) (xy 141.041139 -296.2079) (xy 141.003018 -296.176775) (xy 140.970383 -296.139938)
			(xy 140.94408 -296.098342) (xy 140.924789 -296.053066) (xy 140.913012 -296.005282) (xy 140.909052 -295.956228)
			(xy 135.881841 -295.956228) (xy 135.883778 -295.992002) (xy 135.878409 -296.041345) (xy 135.865127 -296.089169)
			(xy 135.844283 -296.134215) (xy 135.816427 -296.175295) (xy 135.782291 -296.211327) (xy 135.742776 -296.241362)
			(xy 135.698923 -296.264609) (xy 135.651886 -296.280455) (xy 135.602905 -296.288483) (xy 135.578088 -296.288968)
			(xy 135.556498 -296.288206) (xy 135.543798 -296.28719) (xy 135.521446 -296.296842) (xy 135.45312 -296.380408)
			(xy 135.44804 -296.404284) (xy 135.451342 -296.416476) (xy 135.457299 -296.439642) (xy 135.463672 -296.487048)
			(xy 135.464042 -296.510964) (xy 135.463544 -296.537613) (xy 135.455601 -296.590317) (xy 135.447413 -296.616861)
			(xy 139.641824 -296.616861) (xy 139.641824 -296.563563) (xy 139.649767 -296.510859) (xy 139.665477 -296.459929)
			(xy 139.688603 -296.411908) (xy 139.718627 -296.367871) (xy 139.754879 -296.3288) (xy 139.79655 -296.295569)
			(xy 139.842708 -296.26892) (xy 139.892322 -296.249448) (xy 139.944284 -296.237588) (xy 139.997434 -296.233605)
			(xy 140.050584 -296.237588) (xy 140.102546 -296.249448) (xy 140.15216 -296.26892) (xy 140.198318 -296.295569)
			(xy 140.239989 -296.3288) (xy 140.276241 -296.367871) (xy 140.306265 -296.411908) (xy 140.329391 -296.459929)
			(xy 140.345101 -296.510859) (xy 140.353044 -296.563563) (xy 140.353542 -296.590212) (xy 140.353044 -296.616861)
			(xy 140.345101 -296.669565) (xy 140.329391 -296.720495) (xy 140.306265 -296.768516) (xy 140.276241 -296.812553)
			(xy 140.239989 -296.851624) (xy 140.198318 -296.884855) (xy 140.15216 -296.911504) (xy 140.102546 -296.930976)
			(xy 140.050584 -296.942836) (xy 139.997434 -296.94682) (xy 139.944284 -296.942836) (xy 139.892322 -296.930976)
			(xy 139.842708 -296.911504) (xy 139.79655 -296.884855) (xy 139.754879 -296.851624) (xy 139.718627 -296.812553)
			(xy 139.688603 -296.768516) (xy 139.665477 -296.720495) (xy 139.649767 -296.669565) (xy 139.641824 -296.616861)
			(xy 135.447413 -296.616861) (xy 135.439891 -296.641247) (xy 135.416765 -296.689268) (xy 135.386741 -296.733305)
			(xy 135.350489 -296.772376) (xy 135.308818 -296.805607) (xy 135.26266 -296.832256) (xy 135.213046 -296.851728)
			(xy 135.161084 -296.863588) (xy 135.107934 -296.867572) (xy 135.054784 -296.863588) (xy 135.002822 -296.851728)
			(xy 134.953208 -296.832256) (xy 134.90705 -296.805607) (xy 134.865379 -296.772376) (xy 134.829127 -296.733305)
			(xy 134.799103 -296.689268) (xy 134.775977 -296.641247) (xy 134.760267 -296.590317) (xy 134.752324 -296.537613)
			(xy 134.751826 -296.510964) (xy 134.752192 -296.487047) (xy 134.758568 -296.439642) (xy 134.764526 -296.416476)
			(xy 134.767828 -296.404284) (xy 134.762748 -296.380662) (xy 134.694422 -296.297096) (xy 134.67207 -296.287444)
			(xy 134.65937 -296.288206) (xy 134.638034 -296.288968) (xy 134.616444 -296.288206) (xy 134.603744 -296.28719)
			(xy 134.581392 -296.296842) (xy 134.513066 -296.380408) (xy 134.507986 -296.404284) (xy 134.511288 -296.416476)
			(xy 134.517244 -296.439642) (xy 134.523617 -296.487048) (xy 134.523988 -296.510964) (xy 134.52349 -296.537613)
			(xy 134.515547 -296.590317) (xy 134.499837 -296.641247) (xy 134.476711 -296.689268) (xy 134.446687 -296.733305)
			(xy 134.410435 -296.772376) (xy 134.368764 -296.805607) (xy 134.322606 -296.832256) (xy 134.272992 -296.851728)
			(xy 134.22103 -296.863588) (xy 134.16788 -296.867572) (xy 134.11473 -296.863588) (xy 134.062768 -296.851728)
			(xy 134.013154 -296.832256) (xy 133.966996 -296.805607) (xy 133.925325 -296.772376) (xy 133.889073 -296.733305)
			(xy 133.859049 -296.689268) (xy 133.835923 -296.641247) (xy 133.820213 -296.590317) (xy 133.81227 -296.537613)
			(xy 133.811772 -296.510964) (xy 133.812136 -296.487047) (xy 133.818514 -296.439642) (xy 133.824472 -296.416476)
			(xy 133.827774 -296.404284) (xy 133.822694 -296.380662) (xy 133.754368 -296.297096) (xy 133.732016 -296.287444)
			(xy 133.719316 -296.288206) (xy 133.69798 -296.288968) (xy 133.673162 -296.288501) (xy 133.62418 -296.280467)
			(xy 133.577143 -296.264616) (xy 133.533289 -296.241364) (xy 133.493775 -296.211324) (xy 133.459641 -296.175287)
			(xy 133.431787 -296.134203) (xy 133.410946 -296.089154) (xy 133.397668 -296.041326) (xy 133.392301 -295.991981)
			(xy 133.063877 -295.991981) (xy 133.063878 -295.992007) (xy 133.058507 -296.04135) (xy 133.045225 -296.089175)
			(xy 133.02438 -296.13422) (xy 132.996523 -296.1753) (xy 132.962386 -296.211332) (xy 132.92287 -296.241366)
			(xy 132.879016 -296.264612) (xy 132.831979 -296.280457) (xy 132.782997 -296.288484) (xy 132.75818 -296.288968)
			(xy 132.736336 -296.288206) (xy 132.72389 -296.28719) (xy 132.701284 -296.296842) (xy 132.632958 -296.380408)
			(xy 132.627878 -296.404284) (xy 132.63118 -296.416476) (xy 132.637136 -296.439642) (xy 132.643509 -296.487048)
			(xy 132.64388 -296.510964) (xy 132.643382 -296.537613) (xy 132.635439 -296.590317) (xy 132.619729 -296.641247)
			(xy 132.596603 -296.689268) (xy 132.566579 -296.733305) (xy 132.530327 -296.772376) (xy 132.488656 -296.805607)
			(xy 132.442498 -296.832256) (xy 132.392884 -296.851728) (xy 132.340922 -296.863588) (xy 132.287772 -296.867572)
			(xy 132.234622 -296.863588) (xy 132.18266 -296.851728) (xy 132.133046 -296.832256) (xy 132.086888 -296.805607)
			(xy 132.045217 -296.772376) (xy 132.008965 -296.733305) (xy 131.978941 -296.689268) (xy 131.955815 -296.641247)
			(xy 131.940105 -296.590317) (xy 131.932162 -296.537613) (xy 131.931664 -296.510964) (xy 131.932029 -296.487047)
			(xy 131.938406 -296.439642) (xy 131.944364 -296.416476) (xy 131.947666 -296.404538) (xy 131.942586 -296.380662)
			(xy 131.87426 -296.297096) (xy 131.851908 -296.287444) (xy 131.839462 -296.288206) (xy 131.818126 -296.288968)
			(xy 131.796536 -296.288206) (xy 131.783836 -296.28719) (xy 131.761484 -296.296842) (xy 131.693158 -296.380408)
			(xy 131.688078 -296.404284) (xy 131.69138 -296.416476) (xy 131.697336 -296.439642) (xy 131.703709 -296.487048)
			(xy 131.70408 -296.510964) (xy 131.703582 -296.537613) (xy 131.695639 -296.590317) (xy 131.679929 -296.641247)
			(xy 131.656803 -296.689268) (xy 131.626779 -296.733305) (xy 131.590527 -296.772376) (xy 131.548856 -296.805607)
			(xy 131.502698 -296.832256) (xy 131.453084 -296.851728) (xy 131.401122 -296.863588) (xy 131.347972 -296.867572)
			(xy 131.294822 -296.863588) (xy 131.24286 -296.851728) (xy 131.193246 -296.832256) (xy 131.147088 -296.805607)
			(xy 131.105417 -296.772376) (xy 131.069165 -296.733305) (xy 131.039141 -296.689268) (xy 131.016015 -296.641247)
			(xy 131.000305 -296.590317) (xy 130.992362 -296.537613) (xy 130.991864 -296.510964) (xy 130.992229 -296.487047)
			(xy 130.998606 -296.439642) (xy 131.004564 -296.416476) (xy 131.007866 -296.404284) (xy 131.002786 -296.380662)
			(xy 130.93446 -296.297096) (xy 130.912108 -296.287444) (xy 130.899408 -296.288206) (xy 130.878072 -296.288968)
			(xy 130.853255 -296.288492) (xy 130.804274 -296.280458) (xy 130.757239 -296.264606) (xy 130.713388 -296.241353)
			(xy 130.673875 -296.211313) (xy 130.639744 -296.175277) (xy 130.611891 -296.134193) (xy 130.591052 -296.089145)
			(xy 130.577774 -296.041319) (xy 130.572409 -295.991975) (xy 130.237718 -295.991975) (xy 130.231634 -296.029412)
			(xy 130.21605 -296.076093) (xy 130.193179 -296.11967) (xy 130.163614 -296.159014) (xy 130.128121 -296.193106)
			(xy 130.087618 -296.221062) (xy 130.043156 -296.24216) (xy 129.995885 -296.255852) (xy 129.94703 -296.261784)
			(xy 129.897855 -296.259803) (xy 129.849636 -296.249959) (xy 129.80362 -296.232507) (xy 129.760999 -296.2079)
			(xy 129.722878 -296.176775) (xy 129.690243 -296.139938) (xy 129.66394 -296.098342) (xy 129.644649 -296.053066)
			(xy 129.632872 -296.005282) (xy 129.628912 -295.956228) (xy 129.29997 -295.956228) (xy 129.299475 -295.980835)
			(xy 129.29158 -296.029412) (xy 129.275996 -296.076093) (xy 129.253125 -296.11967) (xy 129.22356 -296.159014)
			(xy 129.188067 -296.193106) (xy 129.147564 -296.221062) (xy 129.103102 -296.24216) (xy 129.055831 -296.255852)
			(xy 129.006976 -296.261784) (xy 128.957801 -296.259803) (xy 128.909582 -296.249959) (xy 128.863566 -296.232507)
			(xy 128.820945 -296.2079) (xy 128.782824 -296.176775) (xy 128.750189 -296.139938) (xy 128.723886 -296.098342)
			(xy 128.704595 -296.053066) (xy 128.692818 -296.005282) (xy 128.688858 -295.956228) (xy 128.36017 -295.956228)
			(xy 128.359812 -295.977557) (xy 128.353865 -296.019798) (xy 128.342092 -296.060799) (xy 128.333754 -296.080434)
			(xy 128.32715 -296.094912) (xy 128.332992 -296.125646) (xy 128.36398 -296.156888) (xy 128.386098 -296.179638)
			(xy 128.425657 -296.22925) (xy 128.459413 -296.282979) (xy 128.486942 -296.340149) (xy 128.507898 -296.400042)
			(xy 128.522017 -296.461904) (xy 128.529122 -296.524958) (xy 128.529588 -296.556684) (xy 128.529588 -296.581322)
			(xy 128.534414 -296.591736) (xy 128.545827 -296.616828) (xy 128.564402 -296.668732) (xy 128.571498 -296.695368)
			(xy 128.57861 -296.72661) (xy 128.58115 -296.73931) (xy 129.466848 -297.818556) (xy 129.47015 -297.822112)
			(xy 134.728458 -303.08042) (xy 134.735306 -303.087818) (xy 134.74304 -303.106416) (xy 134.743444 -303.116488)
			(xy 134.743444 -304.230024) (xy 134.743753 -304.238782) (xy 134.749593 -304.25529) (xy 134.754874 -304.262282)
			(xy 135.66521 -305.3715) (xy 135.674139 -305.382499) (xy 135.691038 -305.405242) (xy 135.698992 -305.416966)
			(xy 139.731577 -311.452277) (xy 141.398437 -311.452277) (xy 141.401049 -311.389254) (xy 141.411437 -311.327038)
			(xy 141.42944 -311.266584) (xy 141.454783 -311.208822) (xy 141.487075 -311.154638) (xy 141.525822 -311.104864)
			(xy 141.570429 -311.060265) (xy 141.620209 -311.021527) (xy 141.674398 -310.989243) (xy 141.732165 -310.96391)
			(xy 141.792621 -310.945917) (xy 141.854839 -310.93554) (xy 141.917863 -310.932939) (xy 141.980724 -310.938153)
			(xy 142.042458 -310.951103) (xy 142.102116 -310.97159) (xy 142.158781 -310.999298) (xy 142.211584 -311.033803)
			(xy 142.259714 -311.074574) (xy 142.302431 -311.120985) (xy 142.339079 -311.172323) (xy 142.369096 -311.227801)
			(xy 142.39202 -311.286565) (xy 142.407499 -311.347714) (xy 142.415295 -311.410307) (xy 142.415768 -311.441846)
			(xy 142.415768 -311.443878) (xy 142.415768 -311.4548) (xy 142.424404 -311.474358) (xy 142.496794 -311.53989)
			(xy 142.517114 -311.546494) (xy 142.528036 -311.545224) (xy 142.541459 -311.543907) (xy 142.568397 -311.542508)
			(xy 142.581884 -311.54243) (xy 142.612617 -311.542853) (xy 142.673636 -311.55026) (xy 142.733316 -311.564969)
			(xy 142.790789 -311.586765) (xy 142.845214 -311.61533) (xy 142.8958 -311.650248) (xy 142.941807 -311.691008)
			(xy 142.982566 -311.737017) (xy 143.017481 -311.787605) (xy 143.046044 -311.842032) (xy 143.067837 -311.899505)
			(xy 143.082544 -311.959186) (xy 143.089949 -312.020205) (xy 143.090392 -312.050938) (xy 143.090227 -312.067305)
			(xy 143.088067 -312.09997) (xy 143.086074 -312.116216) (xy 143.08455 -312.128662) (xy 143.093186 -312.15203)
			(xy 143.174212 -312.224928) (xy 143.198088 -312.231024) (xy 143.210534 -312.227976) (xy 143.239447 -312.221567)
			(xy 143.29827 -312.214691) (xy 143.327882 -312.21426) (xy 143.359425 -312.214749) (xy 143.422026 -312.22255)
			(xy 143.483182 -312.238035) (xy 143.541953 -312.260965) (xy 143.597435 -312.290989) (xy 143.648778 -312.327646)
			(xy 143.695193 -312.370371) (xy 143.735966 -312.41851) (xy 143.741226 -312.426561) (xy 145.338794 -312.426561)
			(xy 145.338794 -312.362639) (xy 145.346805 -312.299221) (xy 145.362702 -312.237307) (xy 145.386234 -312.177874)
			(xy 145.417028 -312.121859) (xy 145.454601 -312.070144) (xy 145.498358 -312.023547) (xy 145.547611 -311.982802)
			(xy 145.601582 -311.948551) (xy 145.659421 -311.921334) (xy 145.720214 -311.901581) (xy 145.783004 -311.889603)
			(xy 145.8468 -311.88559) (xy 145.910596 -311.889603) (xy 145.973386 -311.901581) (xy 146.034179 -311.921334)
			(xy 146.092018 -311.948551) (xy 146.145989 -311.982802) (xy 146.195242 -312.023547) (xy 146.238999 -312.070144)
			(xy 146.276572 -312.121859) (xy 146.307366 -312.177874) (xy 146.330898 -312.237307) (xy 146.346795 -312.299221)
			(xy 146.354806 -312.362639) (xy 146.355308 -312.3946) (xy 146.354806 -312.426561) (xy 146.346795 -312.489979)
			(xy 146.330898 -312.551893) (xy 146.307366 -312.611326) (xy 146.276572 -312.667341) (xy 146.238999 -312.719056)
			(xy 146.195242 -312.765653) (xy 146.145989 -312.806398) (xy 146.092018 -312.840649) (xy 146.034179 -312.867866)
			(xy 145.973386 -312.887619) (xy 145.910596 -312.899597) (xy 145.8468 -312.903611) (xy 145.783004 -312.899597)
			(xy 145.720214 -312.887619) (xy 145.659421 -312.867866) (xy 145.601582 -312.840649) (xy 145.547611 -312.806398)
			(xy 145.498358 -312.765653) (xy 145.454601 -312.719056) (xy 145.417028 -312.667341) (xy 145.386234 -312.611326)
			(xy 145.362702 -312.551893) (xy 145.346805 -312.489979) (xy 145.338794 -312.426561) (xy 143.741226 -312.426561)
			(xy 143.770471 -312.471323) (xy 143.798179 -312.527998) (xy 143.818663 -312.587665) (xy 143.83161 -312.649408)
			(xy 143.83682 -312.712278) (xy 143.834213 -312.77531) (xy 143.823829 -312.837535) (xy 143.805828 -312.897998)
			(xy 143.780487 -312.95577) (xy 143.748194 -313.009964) (xy 143.709445 -313.059747) (xy 143.664836 -313.104355)
			(xy 143.615052 -313.143102) (xy 143.560858 -313.175393) (xy 143.503085 -313.200733) (xy 143.442622 -313.218732)
			(xy 143.380396 -313.229114) (xy 143.317364 -313.231719) (xy 143.254494 -313.226508) (xy 143.192752 -313.21356)
			(xy 143.133085 -313.193074) (xy 143.076411 -313.165364) (xy 143.023599 -313.130858) (xy 142.975461 -313.090083)
			(xy 142.932737 -313.043668) (xy 142.896082 -312.992324) (xy 142.866059 -312.93684) (xy 142.84313 -312.878069)
			(xy 142.827647 -312.816912) (xy 142.819848 -312.754311) (xy 142.819374 -312.722768) (xy 142.819539 -312.706401)
			(xy 142.821699 -312.673736) (xy 142.823692 -312.65749) (xy 142.825216 -312.645044) (xy 142.81658 -312.621676)
			(xy 142.735554 -312.548778) (xy 142.711678 -312.542682) (xy 142.699232 -312.54573) (xy 142.67032 -312.552145)
			(xy 142.611496 -312.559017) (xy 142.581884 -312.559446) (xy 142.551154 -312.558959) (xy 142.490143 -312.551549)
			(xy 142.430469 -312.53684) (xy 142.373003 -312.515046) (xy 142.318583 -312.486484) (xy 142.268003 -312.451572)
			(xy 142.221999 -312.410817) (xy 142.181242 -312.364815) (xy 142.146327 -312.314236) (xy 142.117763 -312.259817)
			(xy 142.095966 -312.202352) (xy 142.081255 -312.142679) (xy 142.073842 -312.081668) (xy 142.073376 -312.050938)
			(xy 142.073376 -312.048906) (xy 142.073376 -312.037984) (xy 142.06474 -312.018426) (xy 141.99235 -311.952894)
			(xy 141.97203 -311.94629) (xy 141.961108 -311.94756) (xy 141.947685 -311.948881) (xy 141.920747 -311.950278)
			(xy 141.90726 -311.950354) (xy 141.875721 -311.94979) (xy 141.813129 -311.941983) (xy 141.751983 -311.926493)
			(xy 141.693223 -311.90356) (xy 141.63775 -311.873534) (xy 141.586418 -311.836877) (xy 141.540014 -311.794152)
			(xy 141.499251 -311.746015) (xy 141.464755 -311.693207) (xy 141.437057 -311.636536) (xy 141.41658 -311.576875)
			(xy 141.403641 -311.515139) (xy 141.398437 -311.452277) (xy 139.731577 -311.452277) (xy 141.889818 -314.682378)
			(xy 142.917418 -314.682378) (xy 142.917838 -314.651847) (xy 142.925153 -314.591226) (xy 142.939675 -314.531916)
			(xy 142.961194 -314.474773) (xy 142.989402 -314.420617) (xy 143.023892 -314.37023) (xy 143.064168 -314.324335)
			(xy 143.109651 -314.283593) (xy 143.159684 -314.248592) (xy 143.186404 -314.233814) (xy 143.196056 -314.228734)
			(xy 143.209264 -314.211716) (xy 143.232886 -314.117736) (xy 143.22933 -314.096908) (xy 143.223234 -314.087764)
			(xy 143.207009 -314.062652) (xy 143.179919 -314.009351) (xy 143.159267 -313.953241) (xy 143.145337 -313.895096)
			(xy 143.138323 -313.835719) (xy 143.13789 -313.805824) (xy 143.138392 -313.773863) (xy 143.146403 -313.710445)
			(xy 143.1623 -313.648531) (xy 143.185832 -313.589098) (xy 143.216626 -313.533083) (xy 143.254199 -313.481368)
			(xy 143.297956 -313.434771) (xy 143.347209 -313.394026) (xy 143.40118 -313.359775) (xy 143.459019 -313.332558)
			(xy 143.519812 -313.312805) (xy 143.582602 -313.300827) (xy 143.646398 -313.296814) (xy 143.710194 -313.300827)
			(xy 143.772984 -313.312805) (xy 143.833777 -313.332558) (xy 143.891616 -313.359775) (xy 143.945587 -313.394026)
			(xy 143.99484 -313.434771) (xy 144.038597 -313.481368) (xy 144.07617 -313.533083) (xy 144.106964 -313.589098)
			(xy 144.130496 -313.648531) (xy 144.146393 -313.710445) (xy 144.154404 -313.773863) (xy 144.154906 -313.805824)
			(xy 144.154475 -313.836354) (xy 144.14716 -313.896975) (xy 144.132639 -313.956284) (xy 144.11112 -314.013427)
			(xy 144.082914 -314.067582) (xy 144.048425 -314.117969) (xy 144.008151 -314.163864) (xy 143.962671 -314.204607)
			(xy 143.912639 -314.239609) (xy 143.88592 -314.254388) (xy 143.876268 -314.259468) (xy 143.86306 -314.276486)
			(xy 143.839438 -314.370466) (xy 143.842994 -314.391294) (xy 143.84909 -314.400438) (xy 143.865319 -314.425548)
			(xy 143.892408 -314.47885) (xy 143.913059 -314.53496) (xy 143.926987 -314.593106) (xy 143.934002 -314.652483)
			(xy 143.934434 -314.682378) (xy 143.933932 -314.714339) (xy 143.925921 -314.777757) (xy 143.910024 -314.839671)
			(xy 143.886492 -314.899104) (xy 143.855698 -314.955119) (xy 143.818125 -315.006834) (xy 143.774368 -315.053431)
			(xy 143.725115 -315.094176) (xy 143.671144 -315.128427) (xy 143.613305 -315.155644) (xy 143.552512 -315.175397)
			(xy 143.489722 -315.187375) (xy 143.425926 -315.191389) (xy 143.36213 -315.187375) (xy 143.29934 -315.175397)
			(xy 143.238547 -315.155644) (xy 143.180708 -315.128427) (xy 143.126737 -315.094176) (xy 143.077484 -315.053431)
			(xy 143.033727 -315.006834) (xy 142.996154 -314.955119) (xy 142.96536 -314.899104) (xy 142.941828 -314.839671)
			(xy 142.925931 -314.777757) (xy 142.91792 -314.714339) (xy 142.917418 -314.682378) (xy 141.889818 -314.682378)
			(xy 142.305278 -315.30417) (xy 142.311048 -315.312013) (xy 142.327117 -315.322978) (xy 142.33652 -315.325506)
			(xy 142.41018 -315.341762) (xy 142.429738 -315.33846) (xy 142.438374 -315.332872) (xy 142.461278 -315.319026)
			(xy 142.510136 -315.297179) (xy 142.561566 -315.282369) (xy 142.61456 -315.274885) (xy 142.64132 -315.274452)
			(xy 142.668571 -315.274939) (xy 142.722519 -315.282698) (xy 142.774814 -315.298054) (xy 142.824391 -315.320696)
			(xy 142.870242 -315.350162) (xy 142.911433 -315.385853) (xy 142.947126 -315.427042) (xy 142.976594 -315.472891)
			(xy 142.999239 -315.522468) (xy 143.014598 -315.574761) (xy 143.022359 -315.628709) (xy 143.022828 -315.65596)
			(xy 143.022828 -315.657992) (xy 143.022828 -315.658246) (xy 143.022828 -315.660278) (xy 143.022319 -315.688873)
			(xy 143.013781 -315.745423) (xy 142.996895 -315.800063) (xy 142.972038 -315.851569) (xy 142.939768 -315.898786)
			(xy 142.900809 -315.940654) (xy 142.856034 -315.976234) (xy 142.806448 -316.004729) (xy 142.780004 -316.015624)
			(xy 142.770352 -316.019434) (xy 142.755874 -316.033404) (xy 142.723362 -316.109604) (xy 142.719758 -316.119111)
			(xy 142.719623 -316.139424) (xy 142.723108 -316.148974) (xy 143.233985 -317.382144) (xy 143.66824 -317.382144)
			(xy 143.672311 -317.326522) (xy 143.684437 -317.272085) (xy 143.70436 -317.219994) (xy 143.731656 -317.171359)
			(xy 143.765742 -317.127216) (xy 143.805891 -317.088507) (xy 143.851249 -317.056056) (xy 143.900849 -317.030555)
			(xy 143.953633 -317.012548) (xy 144.008476 -317.002418) (xy 144.06421 -317.000381) (xy 144.119647 -317.006481)
			(xy 144.173604 -317.020587) (xy 144.224933 -317.042399) (xy 144.272539 -317.071453) (xy 144.315407 -317.107128)
			(xy 144.352624 -317.148665) (xy 144.383397 -317.195178) (xy 144.407069 -317.245675) (xy 144.423137 -317.299082)
			(xy 144.431257 -317.354258) (xy 144.431766 -317.382144) (xy 144.431257 -317.41003) (xy 144.423137 -317.465206)
			(xy 144.407069 -317.518613) (xy 144.383397 -317.56911) (xy 144.352624 -317.615623) (xy 144.315407 -317.65716)
			(xy 144.272539 -317.692835) (xy 144.224933 -317.721889) (xy 144.173604 -317.743701) (xy 144.119647 -317.757807)
			(xy 144.06421 -317.763907) (xy 144.008476 -317.76187) (xy 143.953633 -317.75174) (xy 143.900849 -317.733733)
			(xy 143.851249 -317.708232) (xy 143.805891 -317.675781) (xy 143.765742 -317.637072) (xy 143.731656 -317.592929)
			(xy 143.70436 -317.544294) (xy 143.684437 -317.492203) (xy 143.672311 -317.437766) (xy 143.66824 -317.382144)
			(xy 143.233985 -317.382144) (xy 143.707612 -318.525398) (xy 144.478756 -320.386202) (xy 144.484056 -320.39715)
			(xy 144.50263 -320.412796) (xy 144.514316 -320.416174) (xy 144.59458 -320.434716) (xy 144.600561 -320.435908)
			(xy 144.612754 -320.435776) (xy 144.61871 -320.434462) (xy 144.618964 -320.434462) (xy 144.624699 -320.432786)
			(xy 144.635223 -320.427137) (xy 144.639792 -320.423286) (xy 144.661712 -320.404401) (xy 144.70909 -320.371189)
			(xy 144.759937 -320.343578) (xy 144.786604 -320.332354) (xy 144.798288 -320.327782) (xy 144.81429 -320.308732)
			(xy 144.838166 -320.202814) (xy 144.831816 -320.178938) (xy 144.82318 -320.16954) (xy 144.804148 -320.148238)
			(xy 144.771977 -320.10104) (xy 144.747195 -320.049576) (xy 144.730358 -319.994993) (xy 144.721841 -319.938512)
			(xy 144.721326 -319.909952) (xy 144.721812 -319.882701) (xy 144.729568 -319.828753) (xy 144.744923 -319.776458)
			(xy 144.767565 -319.726881) (xy 144.797031 -319.681031) (xy 144.832722 -319.63984) (xy 144.873913 -319.604149)
			(xy 144.919763 -319.574683) (xy 144.96934 -319.552041) (xy 145.021635 -319.536686) (xy 145.075583 -319.52893)
			(xy 145.130085 -319.52893) (xy 145.184033 -319.536686) (xy 145.236328 -319.552041) (xy 145.285905 -319.574683)
			(xy 145.331755 -319.604149) (xy 145.372946 -319.63984) (xy 145.408637 -319.681031) (xy 145.438103 -319.726881)
			(xy 145.460745 -319.776458) (xy 145.4761 -319.828753) (xy 145.483856 -319.882701) (xy 145.484342 -319.909952)
			(xy 145.483846 -319.937961) (xy 145.475651 -319.993378) (xy 145.459446 -320.047002) (xy 145.435577 -320.097682)
			(xy 145.404558 -320.144329) (xy 145.367055 -320.185942) (xy 145.323873 -320.221627) (xy 145.300192 -320.236596)
			(xy 145.28927 -320.2432) (xy 145.27657 -320.264282) (xy 145.269966 -320.372994) (xy 145.280126 -320.3956)
			(xy 145.290032 -320.403474) (xy 145.31569 -320.424178) (xy 145.361965 -320.47114) (xy 145.401776 -320.523692)
			(xy 145.434456 -320.580953) (xy 145.459453 -320.64196) (xy 145.47635 -320.705689) (xy 145.484861 -320.771067)
			(xy 145.485358 -320.804032) (xy 145.484879 -320.836033) (xy 145.476854 -320.89953) (xy 145.460922 -320.961517)
			(xy 145.437335 -321.021014) (xy 145.406467 -321.07708) (xy 145.400766 -321.084913) (xy 147.896828 -321.084913)
			(xy 147.896828 -321.020991) (xy 147.904839 -320.957573) (xy 147.920736 -320.895659) (xy 147.944268 -320.836226)
			(xy 147.975062 -320.780211) (xy 148.012635 -320.728496) (xy 148.056392 -320.681899) (xy 148.105645 -320.641154)
			(xy 148.159616 -320.606903) (xy 148.217455 -320.579686) (xy 148.278248 -320.559933) (xy 148.341038 -320.547955)
			(xy 148.404834 -320.543942) (xy 148.46863 -320.547955) (xy 148.53142 -320.559933) (xy 148.592213 -320.579686)
			(xy 148.650052 -320.606903) (xy 148.704023 -320.641154) (xy 148.753276 -320.681899) (xy 148.797033 -320.728496)
			(xy 148.834606 -320.780211) (xy 148.8654 -320.836226) (xy 148.888932 -320.895659) (xy 148.904829 -320.957573)
			(xy 148.91284 -321.020991) (xy 148.913342 -321.052952) (xy 148.91284 -321.084913) (xy 148.904829 -321.148331)
			(xy 148.888932 -321.210245) (xy 148.8654 -321.269678) (xy 148.834606 -321.325693) (xy 148.797033 -321.377408)
			(xy 148.753276 -321.424005) (xy 148.704023 -321.46475) (xy 148.650052 -321.499001) (xy 148.592213 -321.526218)
			(xy 148.53142 -321.545971) (xy 148.46863 -321.557949) (xy 148.404834 -321.561963) (xy 148.341038 -321.557949)
			(xy 148.278248 -321.545971) (xy 148.217455 -321.526218) (xy 148.159616 -321.499001) (xy 148.105645 -321.46475)
			(xy 148.056392 -321.424005) (xy 148.012635 -321.377408) (xy 147.975062 -321.325693) (xy 147.944268 -321.269678)
			(xy 147.920736 -321.210245) (xy 147.904839 -321.148331) (xy 147.896828 -321.084913) (xy 145.400766 -321.084913)
			(xy 145.368806 -321.128828) (xy 145.324947 -321.17544) (xy 145.275585 -321.216177) (xy 145.221499 -321.250397)
			(xy 145.163546 -321.277556) (xy 145.102642 -321.297227) (xy 145.03975 -321.309098) (xy 145.007838 -321.311524)
			(xy 144.995392 -321.312286) (xy 144.97431 -321.324732) (xy 144.924018 -321.405504) (xy 144.918145 -321.416198)
			(xy 144.916162 -321.440475) (xy 144.920208 -321.451986) (xy 144.985994 -321.610736) (xy 145.02003 -321.692778)
			(xy 145.030607 -321.719197) (xy 145.047149 -321.773651) (xy 145.05305 -321.80149) (xy 145.388838 -323.490336)
			(xy 145.389648 -323.493979) (xy 145.392198 -323.500994) (xy 145.393918 -323.504306) (xy 145.39976 -323.515228)
			(xy 145.404586 -323.528436) (xy 145.668833 -324.720669) (xy 153.57322 -324.720669) (xy 153.57322 -324.656747)
			(xy 153.581231 -324.593329) (xy 153.597128 -324.531415) (xy 153.62066 -324.471982) (xy 153.651454 -324.415967)
			(xy 153.689027 -324.364252) (xy 153.732784 -324.317655) (xy 153.782037 -324.27691) (xy 153.836008 -324.242659)
			(xy 153.893847 -324.215442) (xy 153.95464 -324.195689) (xy 154.01743 -324.183711) (xy 154.081226 -324.179698)
			(xy 154.145022 -324.183711) (xy 154.207812 -324.195689) (xy 154.268605 -324.215442) (xy 154.326444 -324.242659)
			(xy 154.380415 -324.27691) (xy 154.429668 -324.317655) (xy 154.473425 -324.364252) (xy 154.510998 -324.415967)
			(xy 154.541792 -324.471982) (xy 154.565324 -324.531415) (xy 154.581221 -324.593329) (xy 154.589232 -324.656747)
			(xy 154.589734 -324.688708) (xy 154.589232 -324.720669) (xy 154.581221 -324.784087) (xy 154.573635 -324.813633)
			(xy 156.657288 -324.813633) (xy 156.657288 -324.749711) (xy 156.665299 -324.686293) (xy 156.681196 -324.624379)
			(xy 156.704728 -324.564946) (xy 156.735522 -324.508931) (xy 156.773095 -324.457216) (xy 156.816852 -324.410619)
			(xy 156.866105 -324.369874) (xy 156.920076 -324.335623) (xy 156.977915 -324.308406) (xy 157.038708 -324.288653)
			(xy 157.101498 -324.276675) (xy 157.165294 -324.272662) (xy 157.22909 -324.276675) (xy 157.29188 -324.288653)
			(xy 157.352673 -324.308406) (xy 157.410512 -324.335623) (xy 157.464483 -324.369874) (xy 157.513736 -324.410619)
			(xy 157.518666 -324.415869) (xy 160.805362 -324.415869) (xy 160.805362 -324.351947) (xy 160.813373 -324.288529)
			(xy 160.82927 -324.226615) (xy 160.852802 -324.167182) (xy 160.883596 -324.111167) (xy 160.921169 -324.059452)
			(xy 160.964926 -324.012855) (xy 161.014179 -323.97211) (xy 161.06815 -323.937859) (xy 161.125989 -323.910642)
			(xy 161.186782 -323.890889) (xy 161.249572 -323.878911) (xy 161.313368 -323.874898) (xy 161.377164 -323.878911)
			(xy 161.439954 -323.890889) (xy 161.500747 -323.910642) (xy 161.558586 -323.937859) (xy 161.612557 -323.97211)
			(xy 161.66181 -324.012855) (xy 161.705567 -324.059452) (xy 161.74314 -324.111167) (xy 161.773934 -324.167182)
			(xy 161.797466 -324.226615) (xy 161.813363 -324.288529) (xy 161.821374 -324.351947) (xy 161.821876 -324.383908)
			(xy 161.821374 -324.415869) (xy 161.813363 -324.479287) (xy 161.798981 -324.5353) (xy 164.610084 -324.5353)
			(xy 164.614076 -324.446415) (xy 164.626019 -324.358246) (xy 164.645817 -324.271502) (xy 164.673311 -324.186882)
			(xy 164.708279 -324.105067) (xy 164.75044 -324.026716) (xy 164.799454 -323.952459) (xy 164.854928 -323.882895)
			(xy 164.916413 -323.818583) (xy 164.983415 -323.760042) (xy 165.055396 -323.707742) (xy 165.131774 -323.662104)
			(xy 165.211936 -323.623497) (xy 165.295236 -323.59223) (xy 165.381003 -323.568556) (xy 165.468547 -323.552665)
			(xy 165.557163 -323.544685) (xy 165.60165 -323.544184) (xy 167.35425 -323.544184) (xy 167.39874 -323.544682)
			(xy 167.487362 -323.552654) (xy 167.574913 -323.568538) (xy 167.660688 -323.592207) (xy 167.743995 -323.623469)
			(xy 167.824165 -323.662073) (xy 167.900551 -323.707708) (xy 167.972539 -323.760007) (xy 168.039549 -323.818549)
			(xy 168.101041 -323.882862) (xy 168.156521 -323.952428) (xy 168.205541 -324.026687) (xy 168.247707 -324.105042)
			(xy 168.28268 -324.186861) (xy 168.310177 -324.271486) (xy 168.329977 -324.358235) (xy 168.341922 -324.44641)
			(xy 168.345914 -324.5353) (xy 172.15407 -324.5353) (xy 172.158062 -324.446411) (xy 172.170006 -324.358237)
			(xy 172.189806 -324.271489) (xy 172.217302 -324.186865) (xy 172.252273 -324.105047) (xy 172.294437 -324.026693)
			(xy 172.343455 -323.952433) (xy 172.398933 -323.882867) (xy 172.460423 -323.818554) (xy 172.527431 -323.760011)
			(xy 172.599416 -323.707711) (xy 172.6758 -323.662074) (xy 172.755967 -323.623468) (xy 172.839273 -323.592203)
			(xy 172.925045 -323.568531) (xy 173.012594 -323.552644) (xy 173.101215 -323.544668) (xy 173.145704 -323.544184)
			(xy 174.898304 -323.544184) (xy 174.942792 -323.544699) (xy 175.031409 -323.552675) (xy 175.118955 -323.568563)
			(xy 175.204724 -323.592234) (xy 175.288026 -323.623498) (xy 175.36819 -323.662103) (xy 175.444571 -323.707739)
			(xy 175.516554 -323.760038) (xy 175.583559 -323.818578) (xy 175.645046 -323.88289) (xy 175.700522 -323.952454)
			(xy 175.749538 -324.026711) (xy 175.791701 -324.105062) (xy 175.82667 -324.186878) (xy 175.854165 -324.271499)
			(xy 175.873964 -324.358244) (xy 175.885908 -324.446414) (xy 175.8899 -324.5353) (xy 179.698184 -324.5353)
			(xy 179.702176 -324.446415) (xy 179.714119 -324.358245) (xy 179.733918 -324.271501) (xy 179.761412 -324.18688)
			(xy 179.79638 -324.105065) (xy 179.838541 -324.026713) (xy 179.887556 -323.952457) (xy 179.94303 -323.882892)
			(xy 180.004516 -323.81858) (xy 180.071519 -323.760039) (xy 180.1435 -323.707739) (xy 180.219879 -323.662101)
			(xy 180.300042 -323.623494) (xy 180.383342 -323.592228) (xy 180.46911 -323.568554) (xy 180.556654 -323.552664)
			(xy 180.645271 -323.544685) (xy 180.689758 -323.544184) (xy 182.442358 -323.544184) (xy 182.486848 -323.544683)
			(xy 182.57547 -323.552655) (xy 182.66302 -323.56854) (xy 182.748794 -323.592209) (xy 182.8321 -323.623471)
			(xy 182.912269 -323.662075) (xy 182.988655 -323.707711) (xy 183.060642 -323.76001) (xy 183.127652 -323.818552)
			(xy 183.189144 -323.882864) (xy 183.244623 -323.95243) (xy 183.293642 -324.02669) (xy 183.335808 -324.105044)
			(xy 183.37078 -324.186863) (xy 183.398277 -324.271487) (xy 183.418077 -324.358236) (xy 183.430022 -324.44641)
			(xy 183.434014 -324.5353) (xy 187.24217 -324.5353) (xy 187.246162 -324.44641) (xy 187.258106 -324.358236)
			(xy 187.277906 -324.271488) (xy 187.305402 -324.186864) (xy 187.340374 -324.105045) (xy 187.382539 -324.02669)
			(xy 187.431557 -323.952431) (xy 187.487035 -323.882864) (xy 187.548526 -323.818551) (xy 187.615534 -323.760008)
			(xy 187.68752 -323.707708) (xy 187.763905 -323.662071) (xy 187.844073 -323.623465) (xy 187.927379 -323.592201)
			(xy 188.013152 -323.56853) (xy 188.100701 -323.552643) (xy 188.189322 -323.544668) (xy 188.233812 -323.544184)
			(xy 189.986412 -323.544184) (xy 190.0309 -323.544699) (xy 190.119517 -323.552676) (xy 190.207062 -323.568564)
			(xy 190.29283 -323.592236) (xy 190.376132 -323.6235) (xy 190.456295 -323.662106) (xy 190.532675 -323.707742)
			(xy 190.604658 -323.760041) (xy 190.671662 -323.818581) (xy 190.733149 -323.882892) (xy 190.788624 -323.952456)
			(xy 190.83764 -324.026713) (xy 190.879802 -324.105064) (xy 190.914771 -324.186879) (xy 190.942266 -324.2715)
			(xy 190.962064 -324.358244) (xy 190.974008 -324.446414) (xy 190.978 -324.5353) (xy 190.974008 -324.624186)
			(xy 190.962064 -324.712356) (xy 190.942266 -324.7991) (xy 190.914771 -324.883721) (xy 190.879802 -324.965536)
			(xy 190.83764 -325.043887) (xy 190.788624 -325.118144) (xy 190.733149 -325.187708) (xy 190.671662 -325.252019)
			(xy 190.604658 -325.310559) (xy 190.532675 -325.362858) (xy 190.456295 -325.408494) (xy 190.376132 -325.4471)
			(xy 190.29283 -325.478364) (xy 190.207062 -325.502036) (xy 190.119517 -325.517924) (xy 190.0309 -325.525901)
			(xy 189.986412 -325.5264) (xy 188.233812 -325.5264) (xy 188.189322 -325.525932) (xy 188.100701 -325.517957)
			(xy 188.013152 -325.50207) (xy 187.927379 -325.478399) (xy 187.844073 -325.447135) (xy 187.763905 -325.408529)
			(xy 187.68752 -325.362892) (xy 187.615534 -325.310592) (xy 187.548526 -325.252049) (xy 187.487035 -325.187736)
			(xy 187.431557 -325.118169) (xy 187.382539 -325.04391) (xy 187.340374 -324.965555) (xy 187.305402 -324.883736)
			(xy 187.277906 -324.799112) (xy 187.258106 -324.712364) (xy 187.246162 -324.62419) (xy 187.24217 -324.5353)
			(xy 183.434014 -324.5353) (xy 183.430022 -324.62419) (xy 183.418077 -324.712364) (xy 183.398277 -324.799113)
			(xy 183.37078 -324.883737) (xy 183.335808 -324.965556) (xy 183.293642 -325.04391) (xy 183.244623 -325.11817)
			(xy 183.189144 -325.187736) (xy 183.127652 -325.252048) (xy 183.060642 -325.31059) (xy 182.988655 -325.362889)
			(xy 182.912269 -325.408525) (xy 182.8321 -325.447129) (xy 182.748794 -325.478391) (xy 182.66302 -325.50206)
			(xy 182.57547 -325.517945) (xy 182.486848 -325.525917) (xy 182.442358 -325.5264) (xy 180.689758 -325.5264)
			(xy 180.645271 -325.525915) (xy 180.556654 -325.517936) (xy 180.46911 -325.502046) (xy 180.383342 -325.478372)
			(xy 180.300042 -325.447106) (xy 180.219879 -325.408499) (xy 180.1435 -325.362861) (xy 180.071519 -325.310561)
			(xy 180.004516 -325.25202) (xy 179.94303 -325.187708) (xy 179.887556 -325.118143) (xy 179.838541 -325.043887)
			(xy 179.79638 -324.965535) (xy 179.761412 -324.88372) (xy 179.733918 -324.799099) (xy 179.714119 -324.712355)
			(xy 179.702176 -324.624185) (xy 179.698184 -324.5353) (xy 175.8899 -324.5353) (xy 175.885908 -324.624186)
			(xy 175.873964 -324.712356) (xy 175.854165 -324.799101) (xy 175.82667 -324.883722) (xy 175.791701 -324.965538)
			(xy 175.749538 -325.043889) (xy 175.700522 -325.118146) (xy 175.645046 -325.18771) (xy 175.583559 -325.252022)
			(xy 175.516554 -325.310562) (xy 175.444571 -325.362861) (xy 175.36819 -325.408497) (xy 175.288026 -325.447102)
			(xy 175.204724 -325.478366) (xy 175.118955 -325.502037) (xy 175.031409 -325.517925) (xy 174.942792 -325.525901)
			(xy 174.898304 -325.5264) (xy 173.145704 -325.5264) (xy 173.101215 -325.525932) (xy 173.012594 -325.517956)
			(xy 172.925045 -325.502069) (xy 172.839273 -325.478397) (xy 172.755967 -325.447132) (xy 172.6758 -325.408526)
			(xy 172.599416 -325.362889) (xy 172.527431 -325.310589) (xy 172.460423 -325.252046) (xy 172.398933 -325.187733)
			(xy 172.343455 -325.118167) (xy 172.294437 -325.043907) (xy 172.252273 -324.965553) (xy 172.217302 -324.883735)
			(xy 172.189806 -324.799111) (xy 172.170006 -324.712363) (xy 172.158062 -324.624189) (xy 172.15407 -324.5353)
			(xy 168.345914 -324.5353) (xy 168.341922 -324.62419) (xy 168.329977 -324.712365) (xy 168.310177 -324.799114)
			(xy 168.28268 -324.883739) (xy 168.247707 -324.965558) (xy 168.205541 -325.043913) (xy 168.156521 -325.118172)
			(xy 168.101041 -325.187738) (xy 168.039549 -325.252051) (xy 167.972539 -325.310593) (xy 167.900551 -325.362892)
			(xy 167.824165 -325.408527) (xy 167.743995 -325.447131) (xy 167.660688 -325.478393) (xy 167.574913 -325.502062)
			(xy 167.487362 -325.517946) (xy 167.39874 -325.525918) (xy 167.35425 -325.5264) (xy 165.60165 -325.5264)
			(xy 165.557163 -325.525915) (xy 165.468547 -325.517935) (xy 165.381003 -325.502044) (xy 165.295236 -325.47837)
			(xy 165.211936 -325.447103) (xy 165.131774 -325.408496) (xy 165.055396 -325.362858) (xy 164.983415 -325.310558)
			(xy 164.916413 -325.252017) (xy 164.854928 -325.187705) (xy 164.799454 -325.118141) (xy 164.75044 -325.043884)
			(xy 164.708279 -324.965533) (xy 164.673311 -324.883718) (xy 164.645817 -324.799098) (xy 164.626019 -324.712354)
			(xy 164.614076 -324.624185) (xy 164.610084 -324.5353) (xy 161.798981 -324.5353) (xy 161.797466 -324.541201)
			(xy 161.773934 -324.600634) (xy 161.74314 -324.656649) (xy 161.705567 -324.708364) (xy 161.66181 -324.754961)
			(xy 161.612557 -324.795706) (xy 161.558586 -324.829957) (xy 161.500747 -324.857174) (xy 161.439954 -324.876927)
			(xy 161.377164 -324.888905) (xy 161.313368 -324.892919) (xy 161.249572 -324.888905) (xy 161.186782 -324.876927)
			(xy 161.125989 -324.857174) (xy 161.06815 -324.829957) (xy 161.014179 -324.795706) (xy 160.964926 -324.754961)
			(xy 160.921169 -324.708364) (xy 160.883596 -324.656649) (xy 160.852802 -324.600634) (xy 160.82927 -324.541201)
			(xy 160.813373 -324.479287) (xy 160.805362 -324.415869) (xy 157.518666 -324.415869) (xy 157.557493 -324.457216)
			(xy 157.595066 -324.508931) (xy 157.62586 -324.564946) (xy 157.649392 -324.624379) (xy 157.665289 -324.686293)
			(xy 157.6733 -324.749711) (xy 157.673802 -324.781672) (xy 157.6733 -324.813633) (xy 157.665289 -324.877051)
			(xy 157.649392 -324.938965) (xy 157.62586 -324.998398) (xy 157.595066 -325.054413) (xy 157.557493 -325.106128)
			(xy 157.513736 -325.152725) (xy 157.464483 -325.19347) (xy 157.410512 -325.227721) (xy 157.352673 -325.254938)
			(xy 157.29188 -325.274691) (xy 157.22909 -325.286669) (xy 157.165294 -325.290683) (xy 157.101498 -325.286669)
			(xy 157.038708 -325.274691) (xy 156.977915 -325.254938) (xy 156.920076 -325.227721) (xy 156.866105 -325.19347)
			(xy 156.816852 -325.152725) (xy 156.773095 -325.106128) (xy 156.735522 -325.054413) (xy 156.704728 -324.998398)
			(xy 156.681196 -324.938965) (xy 156.665299 -324.877051) (xy 156.657288 -324.813633) (xy 154.573635 -324.813633)
			(xy 154.565324 -324.846001) (xy 154.541792 -324.905434) (xy 154.510998 -324.961449) (xy 154.473425 -325.013164)
			(xy 154.429668 -325.059761) (xy 154.380415 -325.100506) (xy 154.326444 -325.134757) (xy 154.268605 -325.161974)
			(xy 154.207812 -325.181727) (xy 154.145022 -325.193705) (xy 154.081226 -325.197719) (xy 154.01743 -325.193705)
			(xy 153.95464 -325.181727) (xy 153.893847 -325.161974) (xy 153.836008 -325.134757) (xy 153.782037 -325.100506)
			(xy 153.732784 -325.059761) (xy 153.689027 -325.013164) (xy 153.651454 -324.961449) (xy 153.62066 -324.905434)
			(xy 153.597128 -324.846001) (xy 153.581231 -324.784087) (xy 153.57322 -324.720669) (xy 145.668833 -324.720669)
			(xy 145.879157 -325.669613) (xy 155.852108 -325.669613) (xy 155.852108 -325.605691) (xy 155.860119 -325.542273)
			(xy 155.876016 -325.480359) (xy 155.899548 -325.420926) (xy 155.930342 -325.364911) (xy 155.967915 -325.313196)
			(xy 156.011672 -325.266599) (xy 156.060925 -325.225854) (xy 156.114896 -325.191603) (xy 156.172735 -325.164386)
			(xy 156.233528 -325.144633) (xy 156.296318 -325.132655) (xy 156.360114 -325.128642) (xy 156.42391 -325.132655)
			(xy 156.4867 -325.144633) (xy 156.547493 -325.164386) (xy 156.605332 -325.191603) (xy 156.659303 -325.225854)
			(xy 156.708556 -325.266599) (xy 156.752313 -325.313196) (xy 156.789886 -325.364911) (xy 156.82068 -325.420926)
			(xy 156.844212 -325.480359) (xy 156.860109 -325.542273) (xy 156.86812 -325.605691) (xy 156.868622 -325.637652)
			(xy 156.86812 -325.669613) (xy 156.860109 -325.733031) (xy 156.844212 -325.794945) (xy 156.82068 -325.854378)
			(xy 156.789886 -325.910393) (xy 156.752313 -325.962108) (xy 156.708556 -326.008705) (xy 156.659303 -326.04945)
			(xy 156.605332 -326.083701) (xy 156.547493 -326.110918) (xy 156.4867 -326.130671) (xy 156.42391 -326.142649)
			(xy 156.360114 -326.146663) (xy 156.296318 -326.142649) (xy 156.233528 -326.130671) (xy 156.172735 -326.110918)
			(xy 156.114896 -326.083701) (xy 156.060925 -326.04945) (xy 156.011672 -326.008705) (xy 155.967915 -325.962108)
			(xy 155.930342 -325.910393) (xy 155.899548 -325.854378) (xy 155.876016 -325.794945) (xy 155.860119 -325.733031)
			(xy 155.852108 -325.669613) (xy 145.879157 -325.669613) (xy 146.296776 -327.553828) (xy 150.365206 -327.553828)
			(xy 150.365667 -327.517078) (xy 150.372769 -327.443921) (xy 150.386872 -327.371785) (xy 150.407844 -327.30134)
			(xy 150.435492 -327.233237) (xy 150.469559 -327.168107) (xy 150.50973 -327.106555) (xy 150.532338 -327.077578)
			(xy 150.538967 -327.06819) (xy 150.54408 -327.045822) (xy 150.538986 -327.02345) (xy 150.532338 -327.014078)
			(xy 150.509698 -326.985122) (xy 150.469494 -326.923583) (xy 150.435406 -326.858457) (xy 150.40775 -326.79035)
			(xy 150.386785 -326.719896) (xy 150.372704 -326.647749) (xy 150.365639 -326.574582) (xy 150.365206 -326.537828)
			(xy 150.365695 -326.499183) (xy 150.373515 -326.422289) (xy 150.389073 -326.346581) (xy 150.412211 -326.272835)
			(xy 150.442691 -326.201808) (xy 150.4802 -326.13423) (xy 150.524354 -326.070792) (xy 150.574699 -326.012148)
			(xy 150.630718 -325.958897) (xy 150.691837 -325.911587) (xy 150.75743 -325.870703) (xy 150.826821 -325.836665)
			(xy 150.899301 -325.809822) (xy 150.974124 -325.790449) (xy 151.050523 -325.778745) (xy 151.127714 -325.77483)
			(xy 151.204905 -325.778745) (xy 151.281304 -325.790449) (xy 151.356127 -325.809822) (xy 151.428607 -325.836665)
			(xy 151.497998 -325.870703) (xy 151.563591 -325.911587) (xy 151.62471 -325.958897) (xy 151.680729 -326.012148)
			(xy 151.731074 -326.070792) (xy 151.775228 -326.13423) (xy 151.812737 -326.201808) (xy 151.843217 -326.272835)
			(xy 151.866355 -326.346581) (xy 151.881913 -326.422289) (xy 151.889733 -326.499183) (xy 151.890222 -326.537828)
			(xy 151.889787 -326.574579) (xy 151.88268 -326.647737) (xy 151.868573 -326.719873) (xy 151.847596 -326.790318)
			(xy 151.819944 -326.858421) (xy 151.785874 -326.92355) (xy 151.7457 -326.985102) (xy 151.72309 -327.014078)
			(xy 151.716418 -327.023437) (xy 151.711328 -327.045822) (xy 151.716437 -327.068203) (xy 151.72309 -327.077578)
			(xy 151.745714 -327.106546) (xy 151.785918 -327.168083) (xy 151.820008 -327.233207) (xy 151.847666 -327.301312)
			(xy 151.868634 -327.371764) (xy 151.882718 -327.443909) (xy 151.889787 -327.517075) (xy 151.890222 -327.553828)
			(xy 151.889733 -327.592473) (xy 151.881913 -327.669367) (xy 151.866355 -327.745075) (xy 151.843217 -327.818821)
			(xy 151.812737 -327.889848) (xy 151.775228 -327.957426) (xy 151.731074 -328.020864) (xy 151.680729 -328.079508)
			(xy 151.62471 -328.132759) (xy 151.563591 -328.180069) (xy 151.497998 -328.220953) (xy 151.428607 -328.254991)
			(xy 151.356127 -328.281834) (xy 151.281304 -328.301207) (xy 151.204905 -328.312911) (xy 151.127714 -328.316826)
			(xy 151.050523 -328.312911) (xy 150.974124 -328.301207) (xy 150.899301 -328.281834) (xy 150.826821 -328.254991)
			(xy 150.75743 -328.220953) (xy 150.691837 -328.180069) (xy 150.630718 -328.132759) (xy 150.574699 -328.079508)
			(xy 150.524354 -328.020864) (xy 150.4802 -327.957426) (xy 150.442691 -327.889848) (xy 150.412211 -327.818821)
			(xy 150.389073 -327.745075) (xy 150.373515 -327.669367) (xy 150.365695 -327.592473) (xy 150.365206 -327.553828)
			(xy 146.296776 -327.553828) (xy 147.176356 -331.522324) (xy 174.389796 -331.522324) (xy 174.390335 -331.493586)
			(xy 174.398954 -331.436759) (xy 174.416001 -331.381869) (xy 174.441089 -331.330157) (xy 174.473651 -331.282793)
			(xy 174.49292 -331.261466) (xy 174.499524 -331.254354) (xy 174.506636 -331.236828) (xy 174.506636 -331.14742)
			(xy 174.499524 -331.129894) (xy 174.49292 -331.122782) (xy 174.473673 -331.101435) (xy 174.441107 -331.054075)
			(xy 174.416015 -331.002367) (xy 174.398963 -330.94748) (xy 174.390338 -330.890655) (xy 174.390336 -330.83318)
			(xy 174.398955 -330.776355) (xy 174.416002 -330.721466) (xy 174.44109 -330.669755) (xy 174.473651 -330.622393)
			(xy 174.49292 -330.601066) (xy 174.499524 -330.593954) (xy 174.506636 -330.576428) (xy 174.506636 -330.48702)
			(xy 174.499524 -330.469494) (xy 174.49292 -330.462382) (xy 174.473658 -330.441048) (xy 174.441091 -330.393687)
			(xy 174.415997 -330.341978) (xy 174.398944 -330.287088) (xy 174.390319 -330.230262) (xy 174.389796 -330.201524)
			(xy 174.390277 -330.174154) (xy 174.398091 -330.119976) (xy 174.413577 -330.067473) (xy 174.436415 -330.017726)
			(xy 174.466136 -329.971758) (xy 174.483776 -329.950826) (xy 174.489872 -329.943714) (xy 174.496222 -329.926696)
			(xy 174.496222 -329.841352) (xy 174.489872 -329.824334) (xy 174.483776 -329.817222) (xy 174.46613 -329.796296)
			(xy 174.43642 -329.750321) (xy 174.413586 -329.700572) (xy 174.398096 -329.64807) (xy 174.390269 -329.593893)
			(xy 174.389796 -329.566524) (xy 174.390282 -329.539273) (xy 174.398038 -329.485325) (xy 174.413393 -329.43303)
			(xy 174.436035 -329.383453) (xy 174.465501 -329.337603) (xy 174.501192 -329.296412) (xy 174.542383 -329.260721)
			(xy 174.588233 -329.231255) (xy 174.63781 -329.208613) (xy 174.690105 -329.193258) (xy 174.744053 -329.185502)
			(xy 174.798555 -329.185502) (xy 174.852503 -329.193258) (xy 174.904798 -329.208613) (xy 174.954375 -329.231255)
			(xy 175.000225 -329.260721) (xy 175.041416 -329.296412) (xy 175.077107 -329.337603) (xy 175.106573 -329.383453)
			(xy 175.129215 -329.43303) (xy 175.14457 -329.485325) (xy 175.152326 -329.539273) (xy 175.152812 -329.566524)
			(xy 175.152357 -329.593895) (xy 175.144536 -329.648074) (xy 175.129044 -329.700577) (xy 175.1062 -329.750324)
			(xy 175.076474 -329.79629) (xy 175.058832 -329.817222) (xy 175.052736 -329.824334) (xy 175.046386 -329.841352)
			(xy 175.046386 -329.926696) (xy 175.052736 -329.943714) (xy 175.058832 -329.950826) (xy 175.076455 -329.971771)
			(xy 175.106168 -330.017741) (xy 175.129007 -330.067485) (xy 175.144502 -330.119983) (xy 175.152335 -330.174156)
			(xy 175.152812 -330.201524) (xy 175.1523 -330.230263) (xy 175.143674 -330.287091) (xy 175.126621 -330.341982)
			(xy 175.101527 -330.393693) (xy 175.06896 -330.441055) (xy 175.049688 -330.462382) (xy 175.043084 -330.469494)
			(xy 175.035972 -330.48702) (xy 175.035972 -330.576428) (xy 175.043084 -330.593954) (xy 175.049688 -330.601066)
			(xy 175.068982 -330.622372) (xy 175.101546 -330.669739) (xy 175.126635 -330.721454) (xy 175.143683 -330.776348)
			(xy 175.152303 -330.833178) (xy 175.1523 -330.890657) (xy 175.143675 -330.947487) (xy 175.126622 -331.002379)
			(xy 175.101528 -331.054092) (xy 175.06896 -331.101455) (xy 175.049688 -331.122782) (xy 175.043084 -331.129894)
			(xy 175.035972 -331.14742) (xy 175.035972 -331.236828) (xy 175.043084 -331.254354) (xy 175.049688 -331.261466)
			(xy 175.068974 -331.282779) (xy 175.101538 -331.330146) (xy 175.126627 -331.381861) (xy 175.143674 -331.436754)
			(xy 175.152293 -331.493584) (xy 175.152812 -331.522324) (xy 176.779174 -331.522324) (xy 176.779719 -331.493586)
			(xy 176.788338 -331.43676) (xy 176.805383 -331.38187) (xy 176.83047 -331.330158) (xy 176.86303 -331.282794)
			(xy 176.882298 -331.261466) (xy 176.888902 -331.254354) (xy 176.896014 -331.236828) (xy 176.896014 -331.14742)
			(xy 176.888902 -331.129894) (xy 176.882298 -331.122782) (xy 176.863052 -331.101434) (xy 176.830488 -331.054074)
			(xy 176.805397 -331.002366) (xy 176.788347 -330.947479) (xy 176.779722 -330.890655) (xy 176.77972 -330.83318)
			(xy 176.788339 -330.776355) (xy 176.805384 -330.721467) (xy 176.830471 -330.669756) (xy 176.86303 -330.622393)
			(xy 176.882298 -330.601066) (xy 176.888902 -330.593954) (xy 176.896014 -330.576428) (xy 176.896014 -330.48702)
			(xy 176.888902 -330.469494) (xy 176.882298 -330.462382) (xy 176.863049 -330.441036) (xy 176.830478 -330.39368)
			(xy 176.80538 -330.341974) (xy 176.788325 -330.287087) (xy 176.779697 -330.230262) (xy 176.779174 -330.201524)
			(xy 176.779636 -330.174153) (xy 176.787452 -330.119973) (xy 176.802941 -330.06747) (xy 176.825784 -330.017723)
			(xy 176.855511 -329.971757) (xy 176.873154 -329.950826) (xy 176.87925 -329.943714) (xy 176.8856 -329.926696)
			(xy 176.8856 -329.841352) (xy 176.87925 -329.824334) (xy 176.873154 -329.817222) (xy 176.85552 -329.796286)
			(xy 176.825806 -329.750315) (xy 176.802968 -329.700568) (xy 176.787476 -329.648068) (xy 176.779648 -329.593893)
			(xy 176.779174 -329.566524) (xy 176.77966 -329.539273) (xy 176.787416 -329.485325) (xy 176.802771 -329.43303)
			(xy 176.825413 -329.383453) (xy 176.854879 -329.337603) (xy 176.89057 -329.296412) (xy 176.931761 -329.260721)
			(xy 176.977611 -329.231255) (xy 177.027188 -329.208613) (xy 177.079483 -329.193258) (xy 177.133431 -329.185502)
			(xy 177.187933 -329.185502) (xy 177.241881 -329.193258) (xy 177.294176 -329.208613) (xy 177.343753 -329.231255)
			(xy 177.389603 -329.260721) (xy 177.430794 -329.296412) (xy 177.466485 -329.337603) (xy 177.495951 -329.383453)
			(xy 177.518593 -329.43303) (xy 177.533948 -329.485325) (xy 177.541704 -329.539273) (xy 177.54219 -329.566524)
			(xy 177.54174 -329.593895) (xy 177.533919 -329.648075) (xy 177.518426 -329.700578) (xy 177.495581 -329.750325)
			(xy 177.465853 -329.796291) (xy 177.44821 -329.817222) (xy 177.442114 -329.824334) (xy 177.435764 -329.841352)
			(xy 177.435764 -329.926696) (xy 177.442114 -329.943714) (xy 177.44821 -329.950826) (xy 177.465829 -329.971774)
			(xy 177.495544 -330.017742) (xy 177.518383 -330.067486) (xy 177.533879 -330.119983) (xy 177.541713 -330.174156)
			(xy 177.54219 -330.201524) (xy 177.541684 -330.230264) (xy 177.533057 -330.287092) (xy 177.516003 -330.341983)
			(xy 177.490908 -330.393694) (xy 177.458339 -330.441056) (xy 177.439066 -330.462382) (xy 177.432462 -330.469494)
			(xy 177.42535 -330.48702) (xy 177.42535 -330.576428) (xy 177.432462 -330.593954) (xy 177.439066 -330.601066)
			(xy 177.458361 -330.622372) (xy 177.490926 -330.669738) (xy 177.516017 -330.721453) (xy 177.533066 -330.776347)
			(xy 177.541687 -330.833177) (xy 177.541684 -330.890658) (xy 177.533058 -330.947487) (xy 177.516004 -331.00238)
			(xy 177.490909 -331.054093) (xy 177.458339 -331.101455) (xy 177.439066 -331.122782) (xy 177.432462 -331.129894)
			(xy 177.42535 -331.14742) (xy 177.42535 -331.236828) (xy 177.432462 -331.254354) (xy 177.439066 -331.261466)
			(xy 177.458349 -331.282783) (xy 177.490913 -331.330148) (xy 177.516003 -331.381862) (xy 177.533051 -331.436755)
			(xy 177.541671 -331.493584) (xy 177.54219 -331.522324) (xy 177.542009 -331.532484) (xy 180.454808 -331.532484)
			(xy 180.45532 -331.503745) (xy 180.463945 -331.446917) (xy 180.480998 -331.392026) (xy 180.506092 -331.340314)
			(xy 180.53866 -331.292952) (xy 180.557932 -331.271626) (xy 180.564536 -331.264514) (xy 180.571648 -331.246988)
			(xy 180.571648 -331.15758) (xy 180.564536 -331.140054) (xy 180.557932 -331.132942) (xy 180.538645 -331.111629)
			(xy 180.50608 -331.064265) (xy 180.480988 -331.012551) (xy 180.463939 -330.957658) (xy 180.455318 -330.900828)
			(xy 180.45532 -330.843349) (xy 180.463944 -330.78652) (xy 180.480997 -330.731628) (xy 180.506091 -330.679915)
			(xy 180.53866 -330.632553) (xy 180.557932 -330.611226) (xy 180.564536 -330.604114) (xy 180.571648 -330.586588)
			(xy 180.571648 -330.49718) (xy 180.564536 -330.479654) (xy 180.557932 -330.472542) (xy 180.538653 -330.451222)
			(xy 180.506088 -330.403858) (xy 180.480997 -330.352145) (xy 180.463948 -330.297252) (xy 180.455328 -330.240424)
			(xy 180.454808 -330.211684) (xy 180.455263 -330.184313) (xy 180.463083 -330.130134) (xy 180.478575 -330.07763)
			(xy 180.501419 -330.027884) (xy 180.531146 -329.981917) (xy 180.548788 -329.960986) (xy 180.554884 -329.953874)
			(xy 180.561234 -329.936856) (xy 180.561234 -329.851512) (xy 180.554884 -329.834494) (xy 180.548788 -329.827382)
			(xy 180.531172 -329.806431) (xy 180.501457 -329.760463) (xy 180.478617 -329.710721) (xy 180.46312 -329.658224)
			(xy 180.455286 -329.604052) (xy 180.454808 -329.576684) (xy 180.455294 -329.549433) (xy 180.46305 -329.495485)
			(xy 180.478405 -329.44319) (xy 180.501047 -329.393613) (xy 180.530513 -329.347763) (xy 180.566204 -329.306572)
			(xy 180.607395 -329.270881) (xy 180.653245 -329.241415) (xy 180.702822 -329.218773) (xy 180.755117 -329.203418)
			(xy 180.809065 -329.195662) (xy 180.863567 -329.195662) (xy 180.917515 -329.203418) (xy 180.96981 -329.218773)
			(xy 181.019387 -329.241415) (xy 181.065237 -329.270881) (xy 181.106428 -329.306572) (xy 181.142119 -329.347763)
			(xy 181.171585 -329.393613) (xy 181.194227 -329.44319) (xy 181.209582 -329.495485) (xy 181.217338 -329.549433)
			(xy 181.217824 -329.576684) (xy 181.217367 -329.604055) (xy 181.20955 -329.658235) (xy 181.19406 -329.710739)
			(xy 181.171215 -329.760486) (xy 181.141487 -329.806451) (xy 181.123844 -329.827382) (xy 181.117748 -329.834494)
			(xy 181.111398 -329.851512) (xy 181.111398 -329.936856) (xy 181.117748 -329.953874) (xy 181.123844 -329.960986)
			(xy 181.141497 -329.981907) (xy 181.171206 -330.027883) (xy 181.194038 -330.077634) (xy 181.209526 -330.130137)
			(xy 181.217352 -330.184314) (xy 181.217824 -330.211684) (xy 181.217284 -330.240422) (xy 181.208664 -330.297249)
			(xy 181.191618 -330.352139) (xy 181.16653 -330.403851) (xy 181.133969 -330.451214) (xy 181.1147 -330.472542)
			(xy 181.108096 -330.479654) (xy 181.100984 -330.49718) (xy 181.100984 -330.586588) (xy 181.108096 -330.604114)
			(xy 181.1147 -330.611226) (xy 181.133954 -330.632567) (xy 181.166518 -330.679928) (xy 181.191608 -330.731637)
			(xy 181.208659 -330.786526) (xy 181.217282 -330.843351) (xy 181.217284 -330.900826) (xy 181.208664 -330.957652)
			(xy 181.191617 -331.012541) (xy 181.166529 -331.064252) (xy 181.133969 -331.111615) (xy 181.1147 -331.132942)
			(xy 181.108096 -331.140054) (xy 181.100984 -331.15758) (xy 181.100984 -331.246988) (xy 181.108096 -331.264514)
			(xy 181.1147 -331.271626) (xy 181.133952 -331.292969) (xy 181.166524 -331.340326) (xy 181.19162 -331.392033)
			(xy 181.208675 -331.446921) (xy 181.217301 -331.503746) (xy 181.217824 -331.532484) (xy 182.844186 -331.532484)
			(xy 182.844704 -331.503745) (xy 182.853328 -331.446917) (xy 182.87038 -331.392027) (xy 182.895473 -331.340315)
			(xy 182.928039 -331.292953) (xy 182.94731 -331.271626) (xy 182.953914 -331.264514) (xy 182.961026 -331.246988)
			(xy 182.961026 -331.15758) (xy 182.953914 -331.140054) (xy 182.94731 -331.132942) (xy 182.928024 -331.111629)
			(xy 182.89546 -331.064264) (xy 182.870371 -331.012549) (xy 182.853322 -330.957657) (xy 182.844702 -330.900828)
			(xy 182.844703 -330.843349) (xy 182.853328 -330.78652) (xy 182.870379 -330.731629) (xy 182.895472 -330.679916)
			(xy 182.928039 -330.632553) (xy 182.94731 -330.611226) (xy 182.953914 -330.604114) (xy 182.961026 -330.586588)
			(xy 182.961026 -330.49718) (xy 182.953914 -330.479654) (xy 182.94731 -330.472542) (xy 182.928027 -330.451226)
			(xy 182.895464 -330.40386) (xy 182.870374 -330.352146) (xy 182.853326 -330.297253) (xy 182.844706 -330.240424)
			(xy 182.844186 -330.211684) (xy 182.844646 -330.184314) (xy 182.852466 -330.130134) (xy 182.867957 -330.077631)
			(xy 182.890799 -330.027885) (xy 182.920525 -329.981918) (xy 182.938166 -329.960986) (xy 182.944262 -329.953874)
			(xy 182.950612 -329.936856) (xy 182.950612 -329.851512) (xy 182.944262 -329.834494) (xy 182.938166 -329.827382)
			(xy 182.920547 -329.806434) (xy 182.890833 -329.760465) (xy 182.867994 -329.710722) (xy 182.852498 -329.658225)
			(xy 182.844664 -329.604052) (xy 182.844186 -329.576684) (xy 182.844672 -329.549433) (xy 182.852428 -329.495485)
			(xy 182.867783 -329.44319) (xy 182.890425 -329.393613) (xy 182.919891 -329.347763) (xy 182.955582 -329.306572)
			(xy 182.996773 -329.270881) (xy 183.042623 -329.241415) (xy 183.0922 -329.218773) (xy 183.144495 -329.203418)
			(xy 183.198443 -329.195662) (xy 183.252945 -329.195662) (xy 183.306893 -329.203418) (xy 183.359188 -329.218773)
			(xy 183.408765 -329.241415) (xy 183.454615 -329.270881) (xy 183.495806 -329.306572) (xy 183.531497 -329.347763)
			(xy 183.560963 -329.393613) (xy 183.583605 -329.44319) (xy 183.59896 -329.495485) (xy 183.606716 -329.549433)
			(xy 183.607202 -329.576684) (xy 183.606726 -329.604054) (xy 183.598911 -329.658233) (xy 183.583424 -329.710736)
			(xy 183.560584 -329.760483) (xy 183.530862 -329.80645) (xy 183.513222 -329.827382) (xy 183.507126 -329.834494)
			(xy 183.500776 -329.851512) (xy 183.500776 -329.936856) (xy 183.507126 -329.953874) (xy 183.513222 -329.960986)
			(xy 183.530871 -329.98191) (xy 183.560581 -330.027885) (xy 183.583415 -330.077635) (xy 183.598903 -330.130137)
			(xy 183.606729 -330.184314) (xy 183.607202 -330.211684) (xy 183.606668 -330.240423) (xy 183.598048 -330.297249)
			(xy 183.581 -330.35214) (xy 183.555911 -330.403852) (xy 183.523348 -330.451215) (xy 183.504078 -330.472542)
			(xy 183.497474 -330.479654) (xy 183.490362 -330.49718) (xy 183.490362 -330.586588) (xy 183.497474 -330.604114)
			(xy 183.504078 -330.611226) (xy 183.523333 -330.632567) (xy 183.555898 -330.679927) (xy 183.580991 -330.731636)
			(xy 183.598042 -330.786525) (xy 183.606666 -330.84335) (xy 183.606668 -330.900826) (xy 183.598047 -330.957652)
			(xy 183.580999 -331.012542) (xy 183.55591 -331.064253) (xy 183.523348 -331.111615) (xy 183.504078 -331.132942)
			(xy 183.497474 -331.140054) (xy 183.490362 -331.15758) (xy 183.490362 -331.246988) (xy 183.497474 -331.264514)
			(xy 183.504078 -331.271626) (xy 183.523344 -331.292957) (xy 183.55591 -331.340318) (xy 183.581003 -331.392029)
			(xy 183.598055 -331.446919) (xy 183.60668 -331.503745) (xy 183.607202 -331.532484) (xy 186.550808 -331.532484)
			(xy 186.55132 -331.503745) (xy 186.559945 -331.446917) (xy 186.576998 -331.392026) (xy 186.602092 -331.340314)
			(xy 186.63466 -331.292952) (xy 186.653932 -331.271626) (xy 186.660536 -331.264514) (xy 186.667648 -331.246988)
			(xy 186.667648 -331.15758) (xy 186.660536 -331.140054) (xy 186.653932 -331.132942) (xy 186.634645 -331.111629)
			(xy 186.60208 -331.064265) (xy 186.576988 -331.012551) (xy 186.559939 -330.957658) (xy 186.551318 -330.900828)
			(xy 186.55132 -330.843349) (xy 186.559944 -330.78652) (xy 186.576997 -330.731628) (xy 186.602091 -330.679915)
			(xy 186.63466 -330.632553) (xy 186.653932 -330.611226) (xy 186.660536 -330.604114) (xy 186.667648 -330.586588)
			(xy 186.667648 -330.49718) (xy 186.660536 -330.479654) (xy 186.653932 -330.472542) (xy 186.634653 -330.451222)
			(xy 186.602088 -330.403858) (xy 186.576997 -330.352145) (xy 186.559948 -330.297252) (xy 186.551328 -330.240424)
			(xy 186.550808 -330.211684) (xy 186.551263 -330.184313) (xy 186.559083 -330.130134) (xy 186.574575 -330.07763)
			(xy 186.597419 -330.027884) (xy 186.627146 -329.981917) (xy 186.644788 -329.960986) (xy 186.650884 -329.953874)
			(xy 186.657234 -329.936856) (xy 186.657234 -329.851512) (xy 186.650884 -329.834494) (xy 186.644788 -329.827382)
			(xy 186.627172 -329.806431) (xy 186.597457 -329.760463) (xy 186.574617 -329.710721) (xy 186.55912 -329.658224)
			(xy 186.551286 -329.604052) (xy 186.550808 -329.576684) (xy 186.551294 -329.549433) (xy 186.55905 -329.495485)
			(xy 186.574405 -329.44319) (xy 186.597047 -329.393613) (xy 186.626513 -329.347763) (xy 186.662204 -329.306572)
			(xy 186.703395 -329.270881) (xy 186.749245 -329.241415) (xy 186.798822 -329.218773) (xy 186.851117 -329.203418)
			(xy 186.905065 -329.195662) (xy 186.959567 -329.195662) (xy 187.013515 -329.203418) (xy 187.06581 -329.218773)
			(xy 187.115387 -329.241415) (xy 187.161237 -329.270881) (xy 187.202428 -329.306572) (xy 187.238119 -329.347763)
			(xy 187.267585 -329.393613) (xy 187.290227 -329.44319) (xy 187.305582 -329.495485) (xy 187.313338 -329.549433)
			(xy 187.313824 -329.576684) (xy 187.313367 -329.604055) (xy 187.30555 -329.658235) (xy 187.29006 -329.710739)
			(xy 187.267215 -329.760486) (xy 187.237487 -329.806451) (xy 187.219844 -329.827382) (xy 187.213748 -329.834494)
			(xy 187.207398 -329.851512) (xy 187.207398 -329.936856) (xy 187.213748 -329.953874) (xy 187.219844 -329.960986)
			(xy 187.237497 -329.981907) (xy 187.267206 -330.027883) (xy 187.290038 -330.077634) (xy 187.305526 -330.130137)
			(xy 187.313352 -330.184314) (xy 187.313824 -330.211684) (xy 187.313284 -330.240422) (xy 187.304664 -330.297249)
			(xy 187.287618 -330.352139) (xy 187.26253 -330.403851) (xy 187.229969 -330.451214) (xy 187.2107 -330.472542)
			(xy 187.204096 -330.479654) (xy 187.196984 -330.49718) (xy 187.196984 -330.586588) (xy 187.204096 -330.604114)
			(xy 187.2107 -330.611226) (xy 187.229954 -330.632567) (xy 187.262518 -330.679928) (xy 187.287608 -330.731637)
			(xy 187.304659 -330.786526) (xy 187.313282 -330.843351) (xy 187.313284 -330.900826) (xy 187.304664 -330.957652)
			(xy 187.287617 -331.012541) (xy 187.262529 -331.064252) (xy 187.229969 -331.111615) (xy 187.2107 -331.132942)
			(xy 187.204096 -331.140054) (xy 187.196984 -331.15758) (xy 187.196984 -331.246988) (xy 187.204096 -331.264514)
			(xy 187.2107 -331.271626) (xy 187.229952 -331.292969) (xy 187.262524 -331.340326) (xy 187.28762 -331.392033)
			(xy 187.304675 -331.446921) (xy 187.306096 -331.456284) (xy 188.969142 -331.456284) (xy 188.969672 -331.427546)
			(xy 188.978295 -331.370719) (xy 188.995345 -331.315829) (xy 189.020434 -331.264117) (xy 189.052997 -331.216754)
			(xy 189.072266 -331.195426) (xy 189.07887 -331.188314) (xy 189.085982 -331.170788) (xy 189.085982 -331.08138)
			(xy 189.07887 -331.063854) (xy 189.072266 -331.056742) (xy 189.052982 -331.035428) (xy 189.020422 -330.988061)
			(xy 188.995335 -330.936347) (xy 188.978289 -330.881455) (xy 188.969669 -330.824627) (xy 188.969671 -330.767149)
			(xy 188.978294 -330.710322) (xy 188.995344 -330.655431) (xy 189.020434 -330.603718) (xy 189.052997 -330.556354)
			(xy 189.072266 -330.535026) (xy 189.07887 -330.527914) (xy 189.085982 -330.510388) (xy 189.085982 -330.42098)
			(xy 189.07887 -330.403454) (xy 189.072266 -330.396342) (xy 189.052992 -330.375017) (xy 189.020425 -330.327655)
			(xy 188.995333 -330.275943) (xy 188.978283 -330.221052) (xy 188.969662 -330.164223) (xy 188.969142 -330.135484)
			(xy 188.969588 -330.108113) (xy 188.977409 -330.053933) (xy 188.992903 -330.001429) (xy 189.015749 -329.951682)
			(xy 189.045478 -329.905717) (xy 189.063122 -329.884786) (xy 189.069218 -329.877674) (xy 189.075568 -329.860656)
			(xy 189.075568 -329.775312) (xy 189.069218 -329.758294) (xy 189.063122 -329.751182) (xy 189.045511 -329.730227)
			(xy 189.015794 -329.684261) (xy 188.992953 -329.634519) (xy 188.977455 -329.582023) (xy 188.96962 -329.527852)
			(xy 188.969142 -329.500484) (xy 188.969628 -329.473233) (xy 188.977384 -329.419285) (xy 188.992739 -329.36699)
			(xy 189.015381 -329.317413) (xy 189.044847 -329.271563) (xy 189.080538 -329.230372) (xy 189.121729 -329.194681)
			(xy 189.167579 -329.165215) (xy 189.217156 -329.142573) (xy 189.269451 -329.127218) (xy 189.323399 -329.119462)
			(xy 189.377901 -329.119462) (xy 189.431849 -329.127218) (xy 189.484144 -329.142573) (xy 189.533721 -329.165215)
			(xy 189.579571 -329.194681) (xy 189.620762 -329.230372) (xy 189.656453 -329.271563) (xy 189.685919 -329.317413)
			(xy 189.708561 -329.36699) (xy 189.723916 -329.419285) (xy 189.731672 -329.473233) (xy 189.732158 -329.500484)
			(xy 189.731693 -329.527854) (xy 189.723876 -329.582034) (xy 189.708388 -329.634537) (xy 189.685545 -329.684284)
			(xy 189.65582 -329.730251) (xy 189.638178 -329.751182) (xy 189.632082 -329.758294) (xy 189.625732 -329.775312)
			(xy 189.625732 -329.860656) (xy 189.632082 -329.877674) (xy 189.638178 -329.884786) (xy 189.655821 -329.905715)
			(xy 189.685533 -329.951689) (xy 189.708368 -330.001437) (xy 189.723858 -330.053938) (xy 189.731685 -330.108115)
			(xy 189.732158 -330.135484) (xy 189.731609 -330.164222) (xy 189.72299 -330.221047) (xy 189.705945 -330.275937)
			(xy 189.68086 -330.327649) (xy 189.648301 -330.375014) (xy 189.629034 -330.396342) (xy 189.62243 -330.403454)
			(xy 189.615318 -330.42098) (xy 189.615318 -330.510388) (xy 189.62243 -330.527914) (xy 189.629034 -330.535026)
			(xy 189.648286 -330.556368) (xy 189.680847 -330.603729) (xy 189.705936 -330.655439) (xy 189.722984 -330.710327)
			(xy 189.731607 -330.767151) (xy 189.731609 -330.824626) (xy 189.72299 -330.88145) (xy 189.705944 -330.936339)
			(xy 189.680859 -330.98805) (xy 189.648301 -331.035414) (xy 189.629034 -331.056742) (xy 189.62243 -331.063854)
			(xy 189.615318 -331.08138) (xy 189.615318 -331.170788) (xy 189.62243 -331.188314) (xy 189.629034 -331.195426)
			(xy 189.648292 -331.216764) (xy 189.680862 -331.264122) (xy 189.705957 -331.315831) (xy 189.72301 -331.37072)
			(xy 189.731636 -331.427546) (xy 189.732158 -331.456284) (xy 192.621408 -331.456284) (xy 192.62192 -331.427545)
			(xy 192.630545 -331.370717) (xy 192.647598 -331.315826) (xy 192.672692 -331.264114) (xy 192.70526 -331.216752)
			(xy 192.724532 -331.195426) (xy 192.731136 -331.188314) (xy 192.738248 -331.170788) (xy 192.738248 -331.08138)
			(xy 192.731136 -331.063854) (xy 192.724532 -331.056742) (xy 192.705245 -331.035429) (xy 192.67268 -330.988065)
			(xy 192.647588 -330.936351) (xy 192.630539 -330.881458) (xy 192.621918 -330.824628) (xy 192.62192 -330.767149)
			(xy 192.630544 -330.71032) (xy 192.647597 -330.655428) (xy 192.672691 -330.603715) (xy 192.70526 -330.556353)
			(xy 192.724532 -330.535026) (xy 192.731136 -330.527914) (xy 192.738248 -330.510388) (xy 192.738248 -330.42098)
			(xy 192.731136 -330.403454) (xy 192.724532 -330.396342) (xy 192.705253 -330.375022) (xy 192.672688 -330.327658)
			(xy 192.647597 -330.275945) (xy 192.630548 -330.221052) (xy 192.621928 -330.164224) (xy 192.621408 -330.135484)
			(xy 192.621863 -330.108113) (xy 192.629683 -330.053934) (xy 192.645175 -330.00143) (xy 192.668019 -329.951684)
			(xy 192.697746 -329.905717) (xy 192.715388 -329.884786) (xy 192.721484 -329.877674) (xy 192.727834 -329.860656)
			(xy 192.727834 -329.775312) (xy 192.721484 -329.758294) (xy 192.715388 -329.751182) (xy 192.697772 -329.730231)
			(xy 192.668057 -329.684263) (xy 192.645217 -329.634521) (xy 192.62972 -329.582024) (xy 192.621886 -329.527852)
			(xy 192.621408 -329.500484) (xy 192.621894 -329.473233) (xy 192.62965 -329.419285) (xy 192.645005 -329.36699)
			(xy 192.667647 -329.317413) (xy 192.697113 -329.271563) (xy 192.732804 -329.230372) (xy 192.773995 -329.194681)
			(xy 192.819845 -329.165215) (xy 192.869422 -329.142573) (xy 192.921717 -329.127218) (xy 192.975665 -329.119462)
			(xy 193.030167 -329.119462) (xy 193.084115 -329.127218) (xy 193.13641 -329.142573) (xy 193.185987 -329.165215)
			(xy 193.231837 -329.194681) (xy 193.273028 -329.230372) (xy 193.308719 -329.271563) (xy 193.338185 -329.317413)
			(xy 193.360827 -329.36699) (xy 193.376182 -329.419285) (xy 193.383938 -329.473233) (xy 193.384424 -329.500484)
			(xy 193.383967 -329.527855) (xy 193.37615 -329.582035) (xy 193.36066 -329.634539) (xy 193.337815 -329.684286)
			(xy 193.308087 -329.730251) (xy 193.290444 -329.751182) (xy 193.284348 -329.758294) (xy 193.277998 -329.775312)
			(xy 193.277998 -329.860656) (xy 193.284348 -329.877674) (xy 193.290444 -329.884786) (xy 193.308097 -329.905707)
			(xy 193.337806 -329.951683) (xy 193.360638 -330.001434) (xy 193.376126 -330.053937) (xy 193.383952 -330.108114)
			(xy 193.384424 -330.135484) (xy 193.383884 -330.164222) (xy 193.375264 -330.221049) (xy 193.358218 -330.275939)
			(xy 193.33313 -330.327651) (xy 193.300569 -330.375014) (xy 193.2813 -330.396342) (xy 193.274696 -330.403454)
			(xy 193.267584 -330.42098) (xy 193.267584 -330.510388) (xy 193.274696 -330.527914) (xy 193.2813 -330.535026)
			(xy 193.300554 -330.556367) (xy 193.333118 -330.603728) (xy 193.358208 -330.655437) (xy 193.375259 -330.710326)
			(xy 193.383882 -330.767151) (xy 193.383884 -330.824626) (xy 193.375264 -330.881452) (xy 193.358217 -330.936341)
			(xy 193.333129 -330.988052) (xy 193.300569 -331.035415) (xy 193.2813 -331.056742) (xy 193.274696 -331.063854)
			(xy 193.267584 -331.08138) (xy 193.267584 -331.170788) (xy 193.274696 -331.188314) (xy 193.2813 -331.195426)
			(xy 193.300552 -331.216769) (xy 193.333124 -331.264126) (xy 193.35822 -331.315833) (xy 193.375275 -331.370721)
			(xy 193.383901 -331.427546) (xy 193.384207 -331.444346) (xy 195.076826 -331.444346) (xy 195.077337 -331.415607)
			(xy 195.085965 -331.35878) (xy 195.10302 -331.30389) (xy 195.128114 -331.252178) (xy 195.160679 -331.204815)
			(xy 195.17995 -331.183488) (xy 195.186554 -331.176376) (xy 195.193666 -331.15885) (xy 195.193666 -331.069442)
			(xy 195.186554 -331.051916) (xy 195.17995 -331.044804) (xy 195.160724 -331.023438) (xy 195.128155 -330.976083)
			(xy 195.103059 -330.924378) (xy 195.086004 -330.869493) (xy 195.077377 -330.81267) (xy 195.077372 -330.755197)
			(xy 195.085989 -330.698373) (xy 195.103034 -330.643485) (xy 195.128121 -330.591775) (xy 195.160681 -330.544414)
			(xy 195.17995 -330.523088) (xy 195.186554 -330.515976) (xy 195.193666 -330.49845) (xy 195.193666 -330.409042)
			(xy 195.186554 -330.391516) (xy 195.17995 -330.384404) (xy 195.160656 -330.363097) (xy 195.128092 -330.31573)
			(xy 195.103004 -330.264013) (xy 195.085959 -330.209118) (xy 195.077343 -330.152286) (xy 195.076826 -330.123546)
			(xy 195.077313 -330.096176) (xy 195.085125 -330.041998) (xy 195.100608 -329.989495) (xy 195.123446 -329.939748)
			(xy 195.153166 -329.89378) (xy 195.170806 -329.872848) (xy 195.176902 -329.865736) (xy 195.183252 -329.848718)
			(xy 195.183252 -329.763374) (xy 195.176902 -329.746356) (xy 195.170806 -329.739244) (xy 195.153175 -329.718305)
			(xy 195.123462 -329.672334) (xy 195.100624 -329.622589) (xy 195.085131 -329.570089) (xy 195.077301 -329.515915)
			(xy 195.076826 -329.488546) (xy 195.077312 -329.461295) (xy 195.085068 -329.407347) (xy 195.100423 -329.355052)
			(xy 195.123065 -329.305475) (xy 195.152531 -329.259625) (xy 195.188222 -329.218434) (xy 195.229413 -329.182743)
			(xy 195.275263 -329.153277) (xy 195.32484 -329.130635) (xy 195.377135 -329.11528) (xy 195.431083 -329.107524)
			(xy 195.485585 -329.107524) (xy 195.539533 -329.11528) (xy 195.591828 -329.130635) (xy 195.641405 -329.153277)
			(xy 195.687255 -329.182743) (xy 195.728446 -329.218434) (xy 195.764137 -329.259625) (xy 195.793603 -329.305475)
			(xy 195.816245 -329.355052) (xy 195.8316 -329.407347) (xy 195.839356 -329.461295) (xy 195.839842 -329.488546)
			(xy 195.839358 -329.515916) (xy 195.831547 -329.570095) (xy 195.816063 -329.622598) (xy 195.793225 -329.672345)
			(xy 195.763502 -329.718312) (xy 195.745862 -329.739244) (xy 195.739766 -329.746356) (xy 195.733416 -329.763374)
			(xy 195.733416 -329.848718) (xy 195.739766 -329.865736) (xy 195.745862 -329.872848) (xy 195.763484 -329.893794)
			(xy 195.7932 -329.939762) (xy 195.81604 -329.989506) (xy 195.831535 -330.042004) (xy 195.839366 -330.096178)
			(xy 195.839842 -330.123546) (xy 195.839335 -330.152285) (xy 195.830707 -330.209113) (xy 195.813652 -330.264003)
			(xy 195.788557 -330.315715) (xy 195.75599 -330.363077) (xy 195.736718 -330.384404) (xy 195.730114 -330.391516)
			(xy 195.723002 -330.409042) (xy 195.723002 -330.49845) (xy 195.730114 -330.515976) (xy 195.736718 -330.523088)
			(xy 195.756032 -330.544376) (xy 195.788593 -330.591746) (xy 195.813679 -330.643465) (xy 195.830724 -330.698361)
			(xy 195.839341 -330.755193) (xy 195.839336 -330.812674) (xy 195.830709 -330.869505) (xy 195.813654 -330.924398)
			(xy 195.788559 -330.976112) (xy 195.75599 -331.023476) (xy 195.736718 -331.044804) (xy 195.730114 -331.051916)
			(xy 195.723002 -331.069442) (xy 195.723002 -331.15885) (xy 195.730114 -331.176376) (xy 195.736718 -331.183488)
			(xy 195.756003 -331.204803) (xy 195.788569 -331.252167) (xy 195.81366 -331.303882) (xy 195.830707 -331.358776)
			(xy 195.839324 -331.415606) (xy 195.839842 -331.444346) (xy 195.839356 -331.471597) (xy 195.8316 -331.525545)
			(xy 195.816245 -331.57784) (xy 195.793603 -331.627417) (xy 195.764137 -331.673267) (xy 195.728446 -331.714458)
			(xy 195.687255 -331.750149) (xy 195.641405 -331.779615) (xy 195.591828 -331.802257) (xy 195.539533 -331.817612)
			(xy 195.485585 -331.825368) (xy 195.431083 -331.825368) (xy 195.377135 -331.817612) (xy 195.32484 -331.802257)
			(xy 195.275263 -331.779615) (xy 195.229413 -331.750149) (xy 195.188222 -331.714458) (xy 195.152531 -331.673267)
			(xy 195.123065 -331.627417) (xy 195.100423 -331.57784) (xy 195.085068 -331.525545) (xy 195.077312 -331.471597)
			(xy 195.076826 -331.444346) (xy 193.384207 -331.444346) (xy 193.384424 -331.456284) (xy 193.383938 -331.483535)
			(xy 193.376182 -331.537483) (xy 193.360827 -331.589778) (xy 193.338185 -331.639355) (xy 193.308719 -331.685205)
			(xy 193.273028 -331.726396) (xy 193.231837 -331.762087) (xy 193.185987 -331.791553) (xy 193.13641 -331.814195)
			(xy 193.084115 -331.82955) (xy 193.030167 -331.837306) (xy 192.975665 -331.837306) (xy 192.921717 -331.82955)
			(xy 192.869422 -331.814195) (xy 192.819845 -331.791553) (xy 192.773995 -331.762087) (xy 192.732804 -331.726396)
			(xy 192.697113 -331.685205) (xy 192.667647 -331.639355) (xy 192.645005 -331.589778) (xy 192.62965 -331.537483)
			(xy 192.621894 -331.483535) (xy 192.621408 -331.456284) (xy 189.732158 -331.456284) (xy 189.731672 -331.483535)
			(xy 189.723916 -331.537483) (xy 189.708561 -331.589778) (xy 189.685919 -331.639355) (xy 189.656453 -331.685205)
			(xy 189.620762 -331.726396) (xy 189.579571 -331.762087) (xy 189.533721 -331.791553) (xy 189.484144 -331.814195)
			(xy 189.431849 -331.82955) (xy 189.377901 -331.837306) (xy 189.323399 -331.837306) (xy 189.269451 -331.82955)
			(xy 189.217156 -331.814195) (xy 189.167579 -331.791553) (xy 189.121729 -331.762087) (xy 189.080538 -331.726396)
			(xy 189.044847 -331.685205) (xy 189.015381 -331.639355) (xy 188.992739 -331.589778) (xy 188.977384 -331.537483)
			(xy 188.969628 -331.483535) (xy 188.969142 -331.456284) (xy 187.306096 -331.456284) (xy 187.313301 -331.503746)
			(xy 187.313824 -331.532484) (xy 187.313338 -331.559735) (xy 187.305582 -331.613683) (xy 187.290227 -331.665978)
			(xy 187.267585 -331.715555) (xy 187.238119 -331.761405) (xy 187.202428 -331.802596) (xy 187.161237 -331.838287)
			(xy 187.115387 -331.867753) (xy 187.06581 -331.890395) (xy 187.013515 -331.90575) (xy 186.959567 -331.913506)
			(xy 186.905065 -331.913506) (xy 186.851117 -331.90575) (xy 186.798822 -331.890395) (xy 186.749245 -331.867753)
			(xy 186.703395 -331.838287) (xy 186.662204 -331.802596) (xy 186.626513 -331.761405) (xy 186.597047 -331.715555)
			(xy 186.574405 -331.665978) (xy 186.55905 -331.613683) (xy 186.551294 -331.559735) (xy 186.550808 -331.532484)
			(xy 183.607202 -331.532484) (xy 183.606716 -331.559735) (xy 183.59896 -331.613683) (xy 183.583605 -331.665978)
			(xy 183.560963 -331.715555) (xy 183.531497 -331.761405) (xy 183.495806 -331.802596) (xy 183.454615 -331.838287)
			(xy 183.408765 -331.867753) (xy 183.359188 -331.890395) (xy 183.306893 -331.90575) (xy 183.252945 -331.913506)
			(xy 183.198443 -331.913506) (xy 183.144495 -331.90575) (xy 183.0922 -331.890395) (xy 183.042623 -331.867753)
			(xy 182.996773 -331.838287) (xy 182.955582 -331.802596) (xy 182.919891 -331.761405) (xy 182.890425 -331.715555)
			(xy 182.867783 -331.665978) (xy 182.852428 -331.613683) (xy 182.844672 -331.559735) (xy 182.844186 -331.532484)
			(xy 181.217824 -331.532484) (xy 181.217338 -331.559735) (xy 181.209582 -331.613683) (xy 181.194227 -331.665978)
			(xy 181.171585 -331.715555) (xy 181.142119 -331.761405) (xy 181.106428 -331.802596) (xy 181.065237 -331.838287)
			(xy 181.019387 -331.867753) (xy 180.96981 -331.890395) (xy 180.917515 -331.90575) (xy 180.863567 -331.913506)
			(xy 180.809065 -331.913506) (xy 180.755117 -331.90575) (xy 180.702822 -331.890395) (xy 180.653245 -331.867753)
			(xy 180.607395 -331.838287) (xy 180.566204 -331.802596) (xy 180.530513 -331.761405) (xy 180.501047 -331.715555)
			(xy 180.478405 -331.665978) (xy 180.46305 -331.613683) (xy 180.455294 -331.559735) (xy 180.454808 -331.532484)
			(xy 177.542009 -331.532484) (xy 177.541704 -331.549575) (xy 177.533948 -331.603523) (xy 177.518593 -331.655818)
			(xy 177.495951 -331.705395) (xy 177.466485 -331.751245) (xy 177.430794 -331.792436) (xy 177.389603 -331.828127)
			(xy 177.343753 -331.857593) (xy 177.294176 -331.880235) (xy 177.241881 -331.89559) (xy 177.187933 -331.903346)
			(xy 177.133431 -331.903346) (xy 177.079483 -331.89559) (xy 177.027188 -331.880235) (xy 176.977611 -331.857593)
			(xy 176.931761 -331.828127) (xy 176.89057 -331.792436) (xy 176.854879 -331.751245) (xy 176.825413 -331.705395)
			(xy 176.802771 -331.655818) (xy 176.787416 -331.603523) (xy 176.77966 -331.549575) (xy 176.779174 -331.522324)
			(xy 175.152812 -331.522324) (xy 175.152326 -331.549575) (xy 175.14457 -331.603523) (xy 175.129215 -331.655818)
			(xy 175.106573 -331.705395) (xy 175.077107 -331.751245) (xy 175.041416 -331.792436) (xy 175.000225 -331.828127)
			(xy 174.954375 -331.857593) (xy 174.904798 -331.880235) (xy 174.852503 -331.89559) (xy 174.798555 -331.903346)
			(xy 174.744053 -331.903346) (xy 174.690105 -331.89559) (xy 174.63781 -331.880235) (xy 174.588233 -331.857593)
			(xy 174.542383 -331.828127) (xy 174.501192 -331.792436) (xy 174.465501 -331.751245) (xy 174.436035 -331.705395)
			(xy 174.413393 -331.655818) (xy 174.398038 -331.603523) (xy 174.390282 -331.549575) (xy 174.389796 -331.522324)
			(xy 147.176356 -331.522324) (xy 147.5308 -333.121508) (xy 167.537892 -333.121508) (xy 167.53833 -333.08433)
			(xy 167.545581 -333.010329) (xy 167.560006 -332.937387) (xy 167.581466 -332.866196) (xy 167.609759 -332.797433)
			(xy 167.626792 -332.764384) (xy 167.632093 -332.753025) (xy 167.632097 -332.727989) (xy 167.626792 -332.716632)
			(xy 167.609761 -332.683583) (xy 167.581488 -332.614815) (xy 167.560038 -332.543623) (xy 167.545614 -332.470682)
			(xy 167.538353 -332.396684) (xy 167.537892 -332.359508) (xy 167.538381 -332.320863) (xy 167.546201 -332.243969)
			(xy 167.561759 -332.168261) (xy 167.584897 -332.094515) (xy 167.615377 -332.023488) (xy 167.652886 -331.95591)
			(xy 167.69704 -331.892472) (xy 167.747385 -331.833828) (xy 167.803404 -331.780577) (xy 167.864523 -331.733267)
			(xy 167.930116 -331.692383) (xy 167.999507 -331.658345) (xy 168.071987 -331.631502) (xy 168.14681 -331.612129)
			(xy 168.223209 -331.600425) (xy 168.3004 -331.59651) (xy 168.377591 -331.600425) (xy 168.45399 -331.612129)
			(xy 168.528813 -331.631502) (xy 168.601293 -331.658345) (xy 168.670684 -331.692383) (xy 168.736277 -331.733267)
			(xy 168.797396 -331.780577) (xy 168.853415 -331.833828) (xy 168.90376 -331.892472) (xy 168.947914 -331.95591)
			(xy 168.985423 -332.023488) (xy 169.015903 -332.094515) (xy 169.039041 -332.168261) (xy 169.054599 -332.243969)
			(xy 169.062419 -332.320863) (xy 169.062908 -332.359508) (xy 169.062477 -332.396686) (xy 169.055224 -332.470687)
			(xy 169.040798 -332.54363) (xy 169.019336 -332.614821) (xy 168.991041 -332.683583) (xy 168.974008 -332.716632)
			(xy 168.968696 -332.727987) (xy 168.968699 -332.753027) (xy 168.974008 -332.764384) (xy 168.991045 -332.79743)
			(xy 169.019317 -332.866199) (xy 169.040765 -332.937392) (xy 169.055188 -333.010333) (xy 169.062448 -333.084331)
			(xy 169.062908 -333.121508) (xy 169.062419 -333.160153) (xy 169.054599 -333.237047) (xy 169.039041 -333.312755)
			(xy 169.015903 -333.386501) (xy 168.985423 -333.457528) (xy 168.947914 -333.525106) (xy 168.90376 -333.588544)
			(xy 168.853415 -333.647188) (xy 168.797396 -333.700439) (xy 168.736277 -333.747749) (xy 168.670684 -333.788633)
			(xy 168.601293 -333.822671) (xy 168.528813 -333.849514) (xy 168.45399 -333.868887) (xy 168.377591 -333.880591)
			(xy 168.3004 -333.884506) (xy 168.223209 -333.880591) (xy 168.14681 -333.868887) (xy 168.071987 -333.849514)
			(xy 167.999507 -333.822671) (xy 167.930116 -333.788633) (xy 167.864523 -333.747749) (xy 167.803404 -333.700439)
			(xy 167.747385 -333.647188) (xy 167.69704 -333.588544) (xy 167.652886 -333.525106) (xy 167.615377 -333.457528)
			(xy 167.584897 -333.386501) (xy 167.561759 -333.312755) (xy 167.546201 -333.237047) (xy 167.538381 -333.160153)
			(xy 167.537892 -333.121508) (xy 147.5308 -333.121508) (xy 147.88896 -334.737456) (xy 147.890516 -334.743526)
			(xy 147.896165 -334.754707) (xy 147.900136 -334.759554) (xy 147.901406 -334.761078) (xy 152.453086 -339.312504)
			(xy 152.460416 -339.319223) (xy 152.478718 -339.326946) (xy 152.488646 -339.32749) (xy 152.51811 -339.32749)
			(xy 152.528036 -339.328056) (xy 152.546346 -339.335755) (xy 152.55367 -339.342476) (xy 153.386028 -340.174834)
			(xy 153.392704 -340.182247) (xy 153.400269 -340.200683) (xy 153.40076 -340.210648) (xy 153.40076 -340.23935)
			(xy 153.40129 -340.24934) (xy 153.408997 -340.26778) (xy 153.415746 -340.275164) (xy 155.166568 -342.025986)
			(xy 155.17397 -342.032823) (xy 155.192568 -342.040535) (xy 155.202636 -342.040972)
		)
		(stroke
			(width 0)
			(type solid)
		)
		(fill yes)
		(layer "In11.Cu")
		(net "PVDD11_S3_P1")
	)
	(gr_poly
		(pts
			(xy 121.098564 -263.611106) (xy 121.105676 -263.604502) (xy 121.15419 -263.560306) (xy 121.160823 -263.553787)
			(xy 121.169278 -263.53724) (xy 121.1707 -263.528048) (xy 121.1707 -263.527286) (xy 121.173619 -263.501987)
			(xy 121.186788 -263.452795) (xy 121.207936 -263.406471) (xy 121.236478 -263.364298) (xy 121.271622 -263.327445)
			(xy 121.312395 -263.296936) (xy 121.357664 -263.273614) (xy 121.406176 -263.258128) (xy 121.431304 -263.253982)
			(xy 121.441972 -263.252458) (xy 121.474738 -263.25068) (xy 121.499937 -263.251191) (xy 121.549653 -263.259455)
			(xy 121.597338 -263.275768) (xy 121.641697 -263.299689) (xy 121.681528 -263.330567) (xy 121.715749 -263.367566)
			(xy 121.730008 -263.388348) (xy 121.733056 -263.393174) (xy 121.741946 -263.402064) (xy 121.748254 -263.407863)
			(xy 121.763699 -263.415262) (xy 121.772172 -263.416542) (xy 121.847102 -263.424924) (xy 121.858491 -263.425559)
			(xy 121.879992 -263.418039) (xy 121.888504 -263.410446) (xy 122.174254 -263.124696) (xy 122.181494 -263.117989)
			(xy 122.199699 -263.110409) (xy 122.20956 -263.109964) (xy 123.082812 -263.109964) (xy 123.092656 -263.10944)
			(xy 123.110838 -263.101875) (xy 123.118118 -263.095232) (xy 123.190254 -263.023096) (xy 123.196964 -263.015856)
			(xy 123.204554 -262.997652) (xy 123.204986 -262.98779) (xy 123.204986 -262.435086) (xy 123.197366 -262.41629)
			(xy 123.19 -262.409178) (xy 122.841512 -262.06069) (xy 122.83313 -262.052054) (xy 122.81027 -262.044434)
			(xy 122.707908 -262.059166) (xy 122.68835 -262.072628) (xy 122.682508 -262.083296) (xy 122.670882 -262.103513)
			(xy 122.642454 -262.14048) (xy 122.608739 -262.172699) (xy 122.570519 -262.19942) (xy 122.528683 -262.220023)
			(xy 122.484202 -262.23403) (xy 122.438109 -262.241115) (xy 122.414792 -262.241538) (xy 122.3908 -262.241067)
			(xy 122.343408 -262.23356) (xy 122.297773 -262.218732) (xy 122.255019 -262.196949) (xy 122.216199 -262.168746)
			(xy 122.182269 -262.134818) (xy 122.154063 -262.096) (xy 122.132276 -262.053247) (xy 122.117445 -262.007614)
			(xy 122.109935 -261.960222) (xy 122.109484 -261.93623) (xy 122.109922 -261.912912) (xy 122.117002 -261.866817)
			(xy 122.131004 -261.822333) (xy 122.151601 -261.780493) (xy 122.178317 -261.742268) (xy 122.210529 -261.708545)
			(xy 122.247491 -261.680108) (xy 122.267726 -261.668514) (xy 122.277805 -261.662265) (xy 122.291308 -261.642804)
			(xy 122.293634 -261.631176) (xy 122.30481 -261.55269) (xy 122.305849 -261.540846) (xy 122.298304 -261.51833)
			(xy 122.290332 -261.50951) (xy 122.177302 -261.39648) (xy 122.176794 -261.395972) (xy 122.166888 -261.383526)
			(xy 122.136154 -261.374382) (xy 122.10923 -261.383526) (xy 122.100594 -261.38886) (xy 122.095514 -261.391654)
			(xy 122.09526 -261.391908) (xy 122.071939 -261.404457) (xy 122.022049 -261.422206) (xy 121.969847 -261.431098)
			(xy 121.943368 -261.431532) (xy 121.942606 -261.431532) (xy 121.918818 -261.430922) (xy 121.87186 -261.423234)
			(xy 121.826664 -261.408354) (xy 121.784323 -261.386644) (xy 121.745862 -261.358629) (xy 121.712212 -261.324986)
			(xy 121.684189 -261.286531) (xy 121.66247 -261.244194) (xy 121.647581 -261.199) (xy 121.639884 -261.152044)
			(xy 121.63933 -261.128256) (xy 121.63933 -261.127494) (xy 121.639767 -261.101151) (xy 121.648594 -261.049214)
			(xy 121.666224 -260.99957) (xy 121.6787 -260.976364) (xy 121.6787 -260.97611) (xy 121.682002 -260.970268)
			(xy 121.687336 -260.961632) (xy 121.693686 -260.941566) (xy 121.693432 -260.93293) (xy 121.692986 -260.925086)
			(xy 121.687948 -260.910213) (xy 121.683526 -260.90372) (xy 121.680478 -260.899656) (xy 121.518172 -260.73735)
			(xy 121.51106 -260.729984) (xy 121.492264 -260.722364) (xy 118.29796 -260.722364) (xy 118.288119 -260.721835)
			(xy 118.269944 -260.714263) (xy 118.262654 -260.707632) (xy 117.925088 -260.370066) (xy 117.915579 -260.361598)
			(xy 117.891189 -260.3544) (xy 117.878606 -260.35635) (xy 117.785134 -260.376416) (xy 117.765576 -260.392926)
			(xy 117.761004 -260.404864) (xy 117.751226 -260.428726) (xy 117.725558 -260.473451) (xy 117.693495 -260.513837)
			(xy 117.655756 -260.548979) (xy 117.613189 -260.578086) (xy 117.566751 -260.600504) (xy 117.517483 -260.615731)
			(xy 117.466494 -260.623424) (xy 117.44071 -260.623812) (xy 117.413722 -260.623311) (xy 117.360411 -260.614869)
			(xy 117.309076 -260.598191) (xy 117.260983 -260.573687) (xy 117.217315 -260.541962) (xy 117.179147 -260.503796)
			(xy 117.14742 -260.460129) (xy 117.122915 -260.412037) (xy 117.106235 -260.360703) (xy 117.09779 -260.307392)
			(xy 117.097302 -260.280404) (xy 117.097769 -260.254628) (xy 117.105481 -260.203657) (xy 117.120716 -260.154408)
			(xy 117.143133 -260.107986) (xy 117.172231 -260.065431) (xy 117.207356 -260.027698) (xy 117.247721 -259.995632)
			(xy 117.292422 -259.969952) (xy 117.31625 -259.96011) (xy 117.328188 -259.955538) (xy 117.344698 -259.93598)
			(xy 117.364764 -259.842508) (xy 117.366245 -259.834181) (xy 117.364225 -259.817398) (xy 117.35683 -259.802197)
			(xy 117.351048 -259.796026) (xy 116.844572 -259.28955) (xy 116.83746 -259.282184) (xy 116.818664 -259.274564)
			(xy 112.48136 -259.274564) (xy 112.471519 -259.274035) (xy 112.453344 -259.266463) (xy 112.446054 -259.259832)
			(xy 112.196118 -259.009896) (xy 112.1894 -259.00266) (xy 112.181798 -258.984455) (xy 112.181386 -258.97459)
			(xy 112.181386 -256.692908) (xy 112.180116 -256.68224) (xy 112.178084 -256.672334) (xy 112.177068 -256.666746)
			(xy 112.165384 -256.640584) (xy 112.158272 -256.633726) (xy 112.138968 -256.614194) (xy 112.106205 -256.570126)
			(xy 112.080877 -256.521404) (xy 112.063629 -256.469271) (xy 112.054902 -256.415056) (xy 112.054386 -256.3876)
			(xy 112.055148 -256.364232) (xy 112.055148 -256.363978) (xy 112.056164 -256.351278) (xy 112.05718 -256.343404)
			(xy 112.058697 -256.332176) (xy 112.063022 -256.309934) (xy 112.065816 -256.298954) (xy 112.069372 -256.285746)
			(xy 112.06226 -256.259838) (xy 111.688372 -255.88595) (xy 111.68126 -255.878584) (xy 111.662464 -255.870964)
			(xy 107.62996 -255.870964) (xy 107.620119 -255.870435) (xy 107.601944 -255.862863) (xy 107.594654 -255.856232)
			(xy 107.536742 -255.79832) (xy 107.526582 -255.79451) (xy 107.504009 -255.785531) (xy 107.461438 -255.762126)
			(xy 107.422589 -255.732957) (xy 107.388238 -255.698605) (xy 107.35907 -255.659756) (xy 107.335666 -255.617184)
			(xy 107.326684 -255.594612) (xy 107.322874 -255.584452) (xy 107.166918 -255.428496) (xy 107.1602 -255.42126)
			(xy 107.152598 -255.403055) (xy 107.152186 -255.39319) (xy 107.152186 -254.840486) (xy 107.144566 -254.82169)
			(xy 107.1372 -254.814578) (xy 106.278172 -253.95555) (xy 106.27106 -253.948184) (xy 106.252264 -253.940564)
			(xy 104.273858 -253.940564) (xy 104.264017 -253.940035) (xy 104.245842 -253.932462) (xy 104.238552 -253.925832)
			(xy 103.987346 -253.674626) (xy 103.980921 -253.668658) (xy 103.965106 -253.661115) (xy 103.94767 -253.659374)
			(xy 103.939086 -253.661164) (xy 103.926894 -253.664212) (xy 103.922068 -253.666752) (xy 103.901082 -253.676541)
			(xy 103.856887 -253.690364) (xy 103.811109 -253.697337) (xy 103.787956 -253.69774) (xy 103.784908 -253.69774)
			(xy 103.761227 -253.697054) (xy 103.714498 -253.689264) (xy 103.669533 -253.674351) (xy 103.62741 -253.652672)
			(xy 103.589141 -253.624748) (xy 103.555644 -253.591249) (xy 103.527722 -253.552979) (xy 103.506045 -253.510856)
			(xy 103.491133 -253.46589) (xy 103.483345 -253.419161) (xy 103.482648 -253.39548) (xy 103.482648 -253.392178)
			(xy 103.483094 -253.369069) (xy 103.490089 -253.323384) (xy 103.503872 -253.279269) (xy 103.513636 -253.25832)
			(xy 103.516176 -253.253494) (xy 103.519224 -253.241302) (xy 103.520971 -253.232717) (xy 103.519211 -253.215297)
			(xy 103.511705 -253.199479) (xy 103.505762 -253.193042) (xy 102.856538 -252.543818) (xy 102.849378 -252.537268)
			(xy 102.831557 -252.529629) (xy 102.812174 -252.529143) (xy 102.802944 -252.532134) (xy 102.704392 -252.56871)
			(xy 102.686612 -252.592332) (xy 102.685596 -252.607318) (xy 102.683195 -252.632603) (xy 102.671068 -252.681923)
			(xy 102.650946 -252.728555) (xy 102.623384 -252.771214) (xy 102.589141 -252.808722) (xy 102.549162 -252.840046)
			(xy 102.50455 -252.864321) (xy 102.456536 -252.880877) (xy 102.406444 -252.889258) (xy 102.38105 -252.889766)
			(xy 102.357063 -252.889292) (xy 102.309679 -252.881779) (xy 102.264055 -252.866947) (xy 102.221312 -252.84516)
			(xy 102.182504 -252.816955) (xy 102.148585 -252.783026) (xy 102.120392 -252.744209) (xy 102.098618 -252.70146)
			(xy 102.083799 -252.655831) (xy 102.076301 -252.608446) (xy 102.075742 -252.584458) (xy 102.076249 -252.559067)
			(xy 102.084654 -252.508986) (xy 102.101225 -252.460984) (xy 102.125507 -252.416383) (xy 102.15683 -252.376412)
			(xy 102.194333 -252.342172) (xy 102.236981 -252.314606) (xy 102.283601 -252.294471) (xy 102.332909 -252.282324)
			(xy 102.35819 -252.279912) (xy 102.373176 -252.278896) (xy 102.396798 -252.261116) (xy 102.433374 -252.162564)
			(xy 102.436377 -252.153331) (xy 102.435926 -252.133937) (xy 102.428264 -252.116115) (xy 102.42169 -252.10897)
			(xy 102.285292 -251.972572) (xy 102.277598 -251.965617) (xy 102.258324 -251.958012) (xy 102.247954 -251.95784)
			(xy 102.16515 -251.96038) (xy 102.146608 -251.969016) (xy 102.139496 -251.977144) (xy 102.121958 -251.996089)
			(xy 102.081684 -252.028382) (xy 102.036552 -252.05344) (xy 101.987849 -252.070551) (xy 101.936961 -252.079225)
			(xy 101.91115 -252.07976) (xy 101.887163 -252.079286) (xy 101.83978 -252.071773) (xy 101.794156 -252.056941)
			(xy 101.751413 -252.035154) (xy 101.712606 -252.006949) (xy 101.678688 -251.97302) (xy 101.650495 -251.934203)
			(xy 101.628722 -251.891454) (xy 101.613904 -251.845825) (xy 101.606407 -251.798439) (xy 101.605842 -251.774452)
			(xy 101.606384 -251.748643) (xy 101.615069 -251.697759) (xy 101.632182 -251.649059) (xy 101.657238 -251.603929)
			(xy 101.689522 -251.563652) (xy 101.708458 -251.546106) (xy 101.716586 -251.538994) (xy 101.725222 -251.520452)
			(xy 101.727762 -251.437648) (xy 101.727592 -251.427276) (xy 101.719999 -251.407993) (xy 101.71303 -251.40031)
			(xy 101.571552 -251.258832) (xy 101.544374 -251.251974) (xy 101.530658 -251.256292) (xy 101.508777 -251.262575)
			(xy 101.463758 -251.269336) (xy 101.440996 -251.269754) (xy 101.417004 -251.269283) (xy 101.36961 -251.261777)
			(xy 101.323973 -251.24695) (xy 101.281218 -251.225167) (xy 101.242396 -251.196964) (xy 101.208463 -251.163036)
			(xy 101.180255 -251.124218) (xy 101.158466 -251.081466) (xy 101.143633 -251.035831) (xy 101.13612 -250.988438)
			(xy 101.135688 -250.964446) (xy 101.136105 -250.941684) (xy 101.142858 -250.896663) (xy 101.14915 -250.874784)
			(xy 101.153468 -250.861068) (xy 101.14661 -250.83389) (xy 101.05009 -250.73737) (xy 101.042978 -250.730004)
			(xy 101.024182 -250.722384) (xy 100.435918 -250.722384) (xy 100.426082 -250.721845) (xy 100.407925 -250.714254)
			(xy 100.400612 -250.707652) (xy 100.156518 -250.463558) (xy 100.150422 -250.458478) (xy 100.141024 -250.451366)
			(xy 100.118926 -250.447302) (xy 100.10775 -250.450096) (xy 100.089026 -250.454618) (xy 100.05081 -250.459455)
			(xy 100.03155 -250.459748) (xy 100.031042 -250.459748) (xy 100.007046 -250.459305) (xy 99.959643 -250.451804)
			(xy 99.913997 -250.436979) (xy 99.871232 -250.415197) (xy 99.832401 -250.386993) (xy 99.798461 -250.353061)
			(xy 99.770246 -250.314238) (xy 99.748452 -250.271479) (xy 99.733615 -250.225837) (xy 99.726101 -250.178436)
			(xy 99.725734 -250.15444) (xy 99.725734 -250.153932) (xy 99.726029 -250.134672) (xy 99.730873 -250.096458)
			(xy 99.735386 -250.077732) (xy 99.737235 -250.069125) (xy 99.735616 -250.051609) (xy 99.728153 -250.03568)
			(xy 99.722178 -250.029218) (xy 98.74885 -249.05589) (xy 98.741738 -249.048524) (xy 98.722942 -249.040904)
			(xy 98.032062 -249.040904) (xy 98.02317 -249.041236) (xy 98.006458 -249.047318) (xy 97.992848 -249.058765)
			(xy 97.98812 -249.066304) (xy 97.945194 -249.140218) (xy 97.942027 -249.146154) (xy 97.93855 -249.159147)
			(xy 97.938336 -249.165872) (xy 97.938336 -249.179588) (xy 97.945194 -249.191272) (xy 97.949004 -249.19813)
			(xy 97.949766 -249.199654) (xy 97.95002 -249.199908) (xy 97.950782 -249.201432) (xy 97.951036 -249.20194)
			(xy 97.957894 -249.21591) (xy 97.958148 -249.21591) (xy 97.963129 -249.22697) (xy 97.971518 -249.249731)
			(xy 97.974912 -249.261376) (xy 97.974912 -249.26163) (xy 97.975674 -249.264678) (xy 97.980611 -249.284054)
			(xy 97.985964 -249.32368) (xy 97.986342 -249.343672) (xy 97.986342 -249.348752) (xy 97.985557 -249.372523)
			(xy 97.977528 -249.419399) (xy 97.962326 -249.464463) (xy 97.94032 -249.506624) (xy 97.912042 -249.544862)
			(xy 97.878176 -249.578253) (xy 97.839541 -249.605987) (xy 97.797073 -249.627395) (xy 97.751798 -249.641957)
			(xy 97.704813 -249.649323) (xy 97.681034 -249.649742) (xy 97.65704 -249.649274) (xy 97.609642 -249.641772)
			(xy 97.564002 -249.626948) (xy 97.521242 -249.605167) (xy 97.482416 -249.576965) (xy 97.448479 -249.543036)
			(xy 97.420268 -249.504216) (xy 97.398478 -249.461461) (xy 97.383644 -249.415824) (xy 97.376131 -249.368428)
			(xy 97.375726 -249.344434) (xy 97.375726 -249.331988) (xy 97.377207 -249.30735) (xy 97.387123 -249.259001)
			(xy 97.404676 -249.212872) (xy 97.41662 -249.191272) (xy 97.423478 -249.179334) (xy 97.423478 -249.152156)
			(xy 97.376742 -249.071892) (xy 97.368868 -249.061732) (xy 97.363026 -249.05589) (xy 97.355628 -249.049045)
			(xy 97.337028 -249.041324) (xy 97.326958 -249.040904) (xy 96.633538 -249.040904) (xy 96.6237 -249.040369)
			(xy 96.605536 -249.032785) (xy 96.598232 -249.026172) (xy 96.487996 -248.915936) (xy 96.481274 -248.908701)
			(xy 96.473662 -248.890496) (xy 96.473264 -248.88063) (xy 96.473264 -248.856754) (xy 96.472768 -248.846755)
			(xy 96.465099 -248.828285) (xy 96.450946 -248.814155) (xy 96.432464 -248.806516) (xy 96.422464 -248.805954)
			(xy 96.411034 -248.805954) (xy 96.400874 -248.81078) (xy 96.380475 -248.819934) (xy 96.337668 -248.83284)
			(xy 96.293435 -248.839361) (xy 96.27108 -248.839736) (xy 96.245823 -248.839213) (xy 96.196 -248.830896)
			(xy 96.148224 -248.814492) (xy 96.1038 -248.790448) (xy 96.06394 -248.759421) (xy 96.029729 -248.722256)
			(xy 96.002102 -248.679967) (xy 95.981812 -248.633708) (xy 95.969412 -248.584741) (xy 95.965241 -248.5344)
			(xy 95.969412 -248.484059) (xy 95.981812 -248.435092) (xy 96.002102 -248.388833) (xy 96.029729 -248.346544)
			(xy 96.06394 -248.309379) (xy 96.1038 -248.278352) (xy 96.148224 -248.254308) (xy 96.196 -248.237904)
			(xy 96.245823 -248.229587) (xy 96.27108 -248.22912) (xy 96.289752 -248.229418) (xy 96.326812 -248.234004)
			(xy 96.344994 -248.238264) (xy 96.348804 -248.239026) (xy 96.35617 -248.239788) (xy 96.365809 -248.240277)
			(xy 96.384336 -248.234918) (xy 96.392238 -248.229374) (xy 96.453706 -248.181622) (xy 96.462535 -248.174032)
			(xy 96.472717 -248.153121) (xy 96.473264 -248.14149) (xy 96.473264 -247.878346) (xy 96.47047 -247.866662)
			(xy 96.46793 -247.861328) (xy 96.467676 -247.86082) (xy 96.457537 -247.839527) (xy 96.443212 -247.794597)
			(xy 96.435962 -247.747999) (xy 96.435959 -247.70084) (xy 96.443203 -247.654241) (xy 96.457523 -247.609309)
			(xy 96.467676 -247.588024) (xy 96.46793 -247.587516) (xy 96.47047 -247.582182) (xy 96.473264 -247.570498)
			(xy 96.473264 -247.307354) (xy 96.472697 -247.29573) (xy 96.462514 -247.274828) (xy 96.453706 -247.267222)
			(xy 96.393762 -247.220486) (xy 96.38692 -247.215543) (xy 96.370956 -247.210094) (xy 96.36252 -247.209818)
			(xy 96.350836 -247.209818) (xy 96.344994 -247.211342) (xy 96.32698 -247.215379) (xy 96.290302 -247.219584)
			(xy 96.271842 -247.219724) (xy 96.27108 -247.219724) (xy 96.245824 -247.219201) (xy 96.196003 -247.210884)
			(xy 96.148229 -247.194481) (xy 96.103807 -247.170438) (xy 96.063948 -247.139412) (xy 96.029739 -247.102248)
			(xy 96.002113 -247.059962) (xy 95.981823 -247.013704) (xy 95.969424 -246.964739) (xy 95.965253 -246.9144)
			(xy 95.969424 -246.864061) (xy 95.981823 -246.815096) (xy 96.002113 -246.768838) (xy 96.029739 -246.726552)
			(xy 96.063948 -246.689388) (xy 96.103807 -246.658362) (xy 96.148229 -246.634319) (xy 96.196003 -246.617916)
			(xy 96.245824 -246.609599) (xy 96.27108 -246.609108) (xy 96.289752 -246.609405) (xy 96.326813 -246.613991)
			(xy 96.344994 -246.618252) (xy 96.348804 -246.619014) (xy 96.35617 -246.619776) (xy 96.365809 -246.620265)
			(xy 96.384336 -246.614905) (xy 96.392238 -246.609362) (xy 96.453706 -246.56161) (xy 96.462533 -246.554019)
			(xy 96.47271 -246.533108) (xy 96.473264 -246.521478) (xy 96.473264 -246.258334) (xy 96.47047 -246.24665)
			(xy 96.46793 -246.241316) (xy 96.467676 -246.240808) (xy 96.457538 -246.219515) (xy 96.443215 -246.174585)
			(xy 96.435966 -246.127988) (xy 96.435965 -246.08083) (xy 96.443211 -246.034232) (xy 96.457532 -245.989301)
			(xy 96.467676 -245.968012) (xy 96.46793 -245.967504) (xy 96.47047 -245.96217) (xy 96.473264 -245.950486)
			(xy 96.473264 -245.646194) (xy 96.465644 -245.627398) (xy 96.458278 -245.620286) (xy 96.430592 -245.5926)
			(xy 96.422466 -245.585239) (xy 96.401931 -245.577621) (xy 96.390968 -245.577868) (xy 96.383348 -245.578376)
			(xy 96.375982 -245.58117) (xy 96.35064 -245.589908) (xy 96.29788 -245.599368) (xy 96.27108 -245.599966)
			(xy 96.24707 -245.599494) (xy 96.199641 -245.591979) (xy 96.153971 -245.577137) (xy 96.111185 -245.555335)
			(xy 96.072337 -245.527108) (xy 96.038382 -245.493151) (xy 96.010157 -245.454301) (xy 95.988357 -245.411514)
			(xy 95.973517 -245.365844) (xy 95.966005 -245.318414) (xy 95.965518 -245.294404) (xy 95.965518 -245.293388)
			(xy 95.966069 -245.267004) (xy 95.975129 -245.215019) (xy 95.983552 -245.19001) (xy 95.985076 -245.185946)
			(xy 95.988886 -245.165626) (xy 95.98279 -245.143274) (xy 95.974916 -245.134384) (xy 95.973138 -245.132098)
			(xy 95.970336 -245.128548) (xy 95.963696 -245.12241) (xy 95.95993 -245.119906) (xy 95.951294 -245.113302)
			(xy 95.679006 -244.841014) (xy 95.672287 -244.833778) (xy 95.664681 -244.815573) (xy 95.664274 -244.805708)
			(xy 95.664274 -244.799866) (xy 95.66402 -244.786404) (xy 95.653606 -244.767862) (xy 95.644716 -244.758718)
			(xy 95.638874 -244.755162) (xy 95.615862 -244.740746) (xy 95.574711 -244.705322) (xy 95.540228 -244.663379)
			(xy 95.51343 -244.616154) (xy 95.495108 -244.565041) (xy 95.485801 -244.511547) (xy 95.485204 -244.484398)
			(xy 95.485753 -244.457429) (xy 95.494915 -244.404274) (xy 95.512973 -244.353448) (xy 95.539401 -244.306427)
			(xy 95.573432 -244.264579) (xy 95.614077 -244.22912) (xy 95.636842 -244.21465) (xy 95.647256 -244.208554)
			(xy 95.659956 -244.188488) (xy 95.661734 -244.169692) (xy 95.663004 -244.15623) (xy 95.646494 -244.118384)
			(xy 95.6399 -244.094796) (xy 95.62796 -244.04729) (xy 95.622618 -244.023388) (xy 95.620078 -244.011704)
			(xy 95.598996 -243.985288) (xy 95.59417 -243.980462) (xy 95.587566 -243.974112) (xy 95.565214 -243.963698)
			(xy 95.555308 -243.957602) (xy 95.551244 -243.954046) (xy 95.50654 -243.948712) (xy 95.498945 -243.948044)
			(xy 95.483947 -243.950745) (xy 95.477076 -243.954046) (xy 95.454396 -243.965315) (xy 95.406337 -243.981276)
			(xy 95.356346 -243.989362) (xy 95.331026 -243.98986) (xy 95.306234 -243.989401) (xy 95.257259 -243.981648)
			(xy 95.2101 -243.966328) (xy 95.165919 -243.94382) (xy 95.125803 -243.914677) (xy 95.09074 -243.879617)
			(xy 95.061593 -243.839503) (xy 95.039082 -243.795324) (xy 95.023758 -243.748166) (xy 95.016001 -243.699192)
			(xy 95.016001 -243.649608) (xy 95.023758 -243.600634) (xy 95.039082 -243.553476) (xy 95.061593 -243.509297)
			(xy 95.09074 -243.469183) (xy 95.125803 -243.434123) (xy 95.165919 -243.40498) (xy 95.2101 -243.382472)
			(xy 95.257259 -243.367152) (xy 95.306234 -243.359399) (xy 95.331026 -243.358924) (xy 95.357547 -243.359445)
			(xy 95.409848 -243.36827) (xy 95.459937 -243.385717) (xy 95.483426 -243.39804) (xy 95.491554 -243.402612)
			(xy 95.509588 -243.405152) (xy 95.526606 -243.401342) (xy 95.537274 -243.397786) (xy 95.58147 -243.376958)
			(xy 95.586652 -243.374349) (xy 95.595759 -243.367165) (xy 95.599504 -243.362734) (xy 95.620078 -243.33708)
			(xy 95.622618 -243.325396) (xy 95.630049 -243.292198) (xy 95.647329 -243.226391) (xy 95.657162 -243.193824)
			(xy 95.66021 -243.183664) (xy 95.658178 -243.163344) (xy 95.647764 -243.144548) (xy 95.638874 -243.135404)
			(xy 95.63354 -243.131848) (xy 95.611261 -243.117266) (xy 95.571492 -243.081863) (xy 95.538227 -243.040291)
			(xy 95.512407 -242.993727) (xy 95.494766 -242.943491) (xy 95.485802 -242.891007) (xy 95.485204 -242.864386)
			(xy 95.485777 -242.837441) (xy 95.494976 -242.78434) (xy 95.513053 -242.73357) (xy 95.539484 -242.686605)
			(xy 95.573502 -242.644807) (xy 95.61412 -242.609388) (xy 95.636842 -242.594892) (xy 95.647256 -242.588542)
			(xy 95.659956 -242.568476) (xy 95.661734 -242.549172) (xy 95.662149 -242.542673) (xy 95.660087 -242.529819)
			(xy 95.65767 -242.523772) (xy 95.646494 -242.498372) (xy 95.6399 -242.474784) (xy 95.62796 -242.427278)
			(xy 95.622618 -242.403376) (xy 95.620078 -242.391692) (xy 95.598996 -242.365276) (xy 95.59417 -242.36045)
			(xy 95.587566 -242.3541) (xy 95.565214 -242.343686) (xy 95.555308 -242.33759) (xy 95.551244 -242.334034)
			(xy 95.50654 -242.3287) (xy 95.498946 -242.328031) (xy 95.483949 -242.330737) (xy 95.477076 -242.334034)
			(xy 95.454396 -242.345303) (xy 95.406337 -242.361265) (xy 95.356346 -242.369351) (xy 95.331026 -242.369848)
			(xy 95.306235 -242.369389) (xy 95.257262 -242.361636) (xy 95.210105 -242.346317) (xy 95.165925 -242.32381)
			(xy 95.125811 -242.294668) (xy 95.090749 -242.259609) (xy 95.061604 -242.219497) (xy 95.039093 -242.175319)
			(xy 95.02377 -242.128163) (xy 95.016013 -242.079191) (xy 95.016013 -242.029609) (xy 95.02377 -241.980637)
			(xy 95.039093 -241.933481) (xy 95.061604 -241.889303) (xy 95.090749 -241.849191) (xy 95.125811 -241.814132)
			(xy 95.165925 -241.78499) (xy 95.210105 -241.762483) (xy 95.257262 -241.747164) (xy 95.306235 -241.739411)
			(xy 95.331026 -241.738912) (xy 95.357546 -241.739434) (xy 95.409846 -241.748261) (xy 95.459933 -241.765712)
			(xy 95.483426 -241.778028) (xy 95.491554 -241.7826) (xy 95.509588 -241.78514) (xy 95.526606 -241.78133)
			(xy 95.537274 -241.777774) (xy 95.58147 -241.756946) (xy 95.586652 -241.754337) (xy 95.595757 -241.747151)
			(xy 95.599504 -241.742722) (xy 95.620078 -241.717068) (xy 95.622618 -241.705384) (xy 95.630048 -241.672186)
			(xy 95.647323 -241.606378) (xy 95.657162 -241.573812) (xy 95.66021 -241.563652) (xy 95.658178 -241.543332)
			(xy 95.647764 -241.524536) (xy 95.638874 -241.515392) (xy 95.63354 -241.511836) (xy 95.611261 -241.497253)
			(xy 95.571494 -241.461851) (xy 95.53823 -241.420278) (xy 95.512412 -241.373714) (xy 95.494773 -241.323478)
			(xy 95.485811 -241.270995) (xy 95.485204 -241.244374) (xy 95.48577 -241.217425) (xy 95.494956 -241.164315)
			(xy 95.513024 -241.113534) (xy 95.539448 -241.066557) (xy 95.573463 -241.024747) (xy 95.61408 -240.989317)
			(xy 95.636842 -240.97488) (xy 95.647256 -240.96853) (xy 95.659956 -240.948464) (xy 95.661734 -240.92916)
			(xy 95.662148 -240.922662) (xy 95.660082 -240.909809) (xy 95.65767 -240.90376) (xy 95.646494 -240.87836)
			(xy 95.6399 -240.854772) (xy 95.627961 -240.807266) (xy 95.622618 -240.783364) (xy 95.620078 -240.77168)
			(xy 95.598996 -240.745264) (xy 95.59417 -240.740438) (xy 95.587566 -240.734088) (xy 95.565214 -240.723674)
			(xy 95.555308 -240.717578) (xy 95.551244 -240.714022) (xy 95.50654 -240.708688) (xy 95.498946 -240.708019)
			(xy 95.483949 -240.710725) (xy 95.477076 -240.714022) (xy 95.454396 -240.725291) (xy 95.406337 -240.741254)
			(xy 95.356346 -240.749341) (xy 95.331026 -240.749836) (xy 95.306236 -240.749377) (xy 95.257265 -240.741624)
			(xy 95.21011 -240.726306) (xy 95.165932 -240.7038) (xy 95.125818 -240.674659) (xy 95.090758 -240.639601)
			(xy 95.061614 -240.599491) (xy 95.039104 -240.555314) (xy 95.023782 -240.508161) (xy 95.016025 -240.45919)
			(xy 95.016025 -240.40961) (xy 95.023782 -240.360639) (xy 95.039104 -240.313486) (xy 95.061614 -240.269309)
			(xy 95.090758 -240.229199) (xy 95.125818 -240.194141) (xy 95.165932 -240.165) (xy 95.21011 -240.142494)
			(xy 95.257265 -240.127176) (xy 95.306236 -240.119423) (xy 95.331026 -240.1189) (xy 95.357546 -240.119422)
			(xy 95.409847 -240.128248) (xy 95.459934 -240.145699) (xy 95.483426 -240.158016) (xy 95.491554 -240.162588)
			(xy 95.509588 -240.165128) (xy 95.526606 -240.161318) (xy 95.537274 -240.157762) (xy 95.58147 -240.136934)
			(xy 95.586651 -240.134324) (xy 95.595755 -240.127138) (xy 95.599504 -240.12271) (xy 95.620078 -240.097056)
			(xy 95.622618 -240.085372) (xy 95.630048 -240.052174) (xy 95.647324 -239.986366) (xy 95.657162 -239.9538)
			(xy 95.66021 -239.94364) (xy 95.658178 -239.92332) (xy 95.647764 -239.904524) (xy 95.638874 -239.89538)
			(xy 95.63354 -239.891824) (xy 95.611262 -239.877241) (xy 95.571496 -239.841838) (xy 95.538234 -239.800265)
			(xy 95.512418 -239.753701) (xy 95.49478 -239.703465) (xy 95.48582 -239.650983) (xy 95.485204 -239.624362)
			(xy 95.485771 -239.597413) (xy 95.494959 -239.544305) (xy 95.513028 -239.493526) (xy 95.539453 -239.44655)
			(xy 95.573468 -239.404742) (xy 95.614086 -239.369313) (xy 95.636842 -239.354868) (xy 95.647256 -239.348518)
			(xy 95.659956 -239.328452) (xy 95.661734 -239.309148) (xy 95.662146 -239.30265) (xy 95.660078 -239.289798)
			(xy 95.65767 -239.283748) (xy 95.646494 -239.258348) (xy 95.6399 -239.23476) (xy 95.627961 -239.187254)
			(xy 95.622618 -239.163352) (xy 95.620078 -239.151668) (xy 95.598996 -239.125252) (xy 95.59417 -239.120426)
			(xy 95.587566 -239.114076) (xy 95.565214 -239.103662) (xy 95.555308 -239.097566) (xy 95.551244 -239.09401)
			(xy 95.50654 -239.088676) (xy 95.498946 -239.088008) (xy 95.483949 -239.090712) (xy 95.477076 -239.09401)
			(xy 95.454396 -239.10528) (xy 95.406337 -239.121243) (xy 95.356346 -239.12933) (xy 95.331026 -239.129824)
			(xy 95.306237 -239.129365) (xy 95.257267 -239.121613) (xy 95.210114 -239.106295) (xy 95.165938 -239.083789)
			(xy 95.125826 -239.05465) (xy 95.090767 -239.019594) (xy 95.061624 -238.979484) (xy 95.039115 -238.93531)
			(xy 95.023793 -238.888158) (xy 95.016037 -238.839189) (xy 95.016037 -238.789611) (xy 95.023793 -238.740642)
			(xy 95.039115 -238.69349) (xy 95.061624 -238.649316) (xy 95.090767 -238.609206) (xy 95.125826 -238.57415)
			(xy 95.165938 -238.545011) (xy 95.210114 -238.522505) (xy 95.257267 -238.507187) (xy 95.306237 -238.499435)
			(xy 95.331026 -238.498888) (xy 95.357546 -238.49941) (xy 95.409847 -238.508236) (xy 95.459934 -238.525686)
			(xy 95.483426 -238.538004) (xy 95.491554 -238.542576) (xy 95.509588 -238.545116) (xy 95.526606 -238.541306)
			(xy 95.537274 -238.53775) (xy 95.58147 -238.516922) (xy 95.586651 -238.514312) (xy 95.595753 -238.507124)
			(xy 95.599504 -238.502698) (xy 95.620078 -238.477044) (xy 95.622618 -238.46536) (xy 95.630048 -238.432162)
			(xy 95.647325 -238.366354) (xy 95.657162 -238.333788) (xy 95.66021 -238.323628) (xy 95.658178 -238.303308)
			(xy 95.647764 -238.284512) (xy 95.638874 -238.275368) (xy 95.63354 -238.271812) (xy 95.611257 -238.257231)
			(xy 95.571481 -238.221831) (xy 95.538207 -238.18026) (xy 95.512379 -238.133696) (xy 95.494727 -238.083459)
			(xy 95.485753 -238.030973) (xy 95.485204 -238.00435) (xy 95.485772 -237.977402) (xy 95.494962 -237.924294)
			(xy 95.513032 -237.873517) (xy 95.539458 -237.826543) (xy 95.573474 -237.784736) (xy 95.614091 -237.749309)
			(xy 95.636842 -237.734856) (xy 95.647256 -237.728506) (xy 95.659956 -237.70844) (xy 95.661734 -237.689136)
			(xy 95.662157 -237.682636) (xy 95.660109 -237.669775) (xy 95.65767 -237.663736) (xy 95.646494 -237.638336)
			(xy 95.639899 -237.614749) (xy 95.627958 -237.567243) (xy 95.622618 -237.54334) (xy 95.620078 -237.531656)
			(xy 95.598996 -237.50524) (xy 95.59417 -237.500414) (xy 95.587566 -237.494064) (xy 95.565214 -237.48365)
			(xy 95.555308 -237.477554) (xy 95.551244 -237.473998) (xy 95.50654 -237.468664) (xy 95.498946 -237.467996)
			(xy 95.483949 -237.4707) (xy 95.477076 -237.473998) (xy 95.454396 -237.485265) (xy 95.406336 -237.501223)
			(xy 95.356346 -237.509308) (xy 95.331026 -237.509812) (xy 95.30623 -237.509353) (xy 95.257247 -237.501598)
			(xy 95.210081 -237.486277) (xy 95.165892 -237.463764) (xy 95.125769 -237.434617) (xy 95.0907 -237.399551)
			(xy 95.061549 -237.35943) (xy 95.039033 -237.315244) (xy 95.023708 -237.268078) (xy 95.015949 -237.219096)
			(xy 95.015949 -237.169504) (xy 95.023708 -237.120522) (xy 95.039033 -237.073356) (xy 95.061549 -237.02917)
			(xy 95.0907 -236.989049) (xy 95.125769 -236.953983) (xy 95.165892 -236.924836) (xy 95.210081 -236.902323)
			(xy 95.257247 -236.887002) (xy 95.30623 -236.879247) (xy 95.331026 -236.878876) (xy 95.357546 -236.879398)
			(xy 95.409847 -236.888224) (xy 95.459935 -236.905673) (xy 95.483426 -236.917992) (xy 95.491554 -236.922564)
			(xy 95.509588 -236.925104) (xy 95.526606 -236.921294) (xy 95.537274 -236.917738) (xy 95.58147 -236.89691)
			(xy 95.58665 -236.894299) (xy 95.595752 -236.887111) (xy 95.599504 -236.882686) (xy 95.620078 -236.857032)
			(xy 95.622618 -236.845348) (xy 95.630048 -236.81215) (xy 95.647326 -236.746342) (xy 95.657162 -236.713776)
			(xy 95.66021 -236.703616) (xy 95.658178 -236.683296) (xy 95.647764 -236.6645) (xy 95.638874 -236.655356)
			(xy 95.63354 -236.6518) (xy 95.611258 -236.637219) (xy 95.571483 -236.601818) (xy 95.538211 -236.560247)
			(xy 95.512384 -236.513683) (xy 95.494734 -236.463446) (xy 95.485762 -236.410961) (xy 95.485204 -236.384338)
			(xy 95.485773 -236.35739) (xy 95.494964 -236.304284) (xy 95.513036 -236.253508) (xy 95.539463 -236.206536)
			(xy 95.573479 -236.164731) (xy 95.614097 -236.129305) (xy 95.636842 -236.114844) (xy 95.647256 -236.108494)
			(xy 95.659956 -236.088428) (xy 95.661734 -236.069124) (xy 95.662156 -236.062624) (xy 95.660105 -236.049765)
			(xy 95.65767 -236.043724) (xy 95.646494 -236.018324) (xy 95.639899 -235.994737) (xy 95.627958 -235.947231)
			(xy 95.622618 -235.923328) (xy 95.620078 -235.911644) (xy 95.598996 -235.885228) (xy 95.59417 -235.880402)
			(xy 95.587566 -235.874052) (xy 95.565214 -235.863638) (xy 95.555308 -235.857542) (xy 95.551244 -235.853986)
			(xy 95.50654 -235.848652) (xy 95.498946 -235.847984) (xy 95.483948 -235.850687) (xy 95.477076 -235.853986)
			(xy 95.454396 -235.865253) (xy 95.406336 -235.881212) (xy 95.356346 -235.889298) (xy 95.331026 -235.8898)
			(xy 95.306231 -235.889341) (xy 95.25725 -235.881587) (xy 95.210085 -235.866265) (xy 95.165898 -235.843754)
			(xy 95.125777 -235.814607) (xy 95.090709 -235.779543) (xy 95.061559 -235.739424) (xy 95.039045 -235.695239)
			(xy 95.023719 -235.648076) (xy 95.015961 -235.599095) (xy 95.015961 -235.549505) (xy 95.023719 -235.500524)
			(xy 95.039045 -235.453361) (xy 95.061559 -235.409176) (xy 95.090709 -235.369057) (xy 95.125777 -235.333993)
			(xy 95.165898 -235.304846) (xy 95.210085 -235.282335) (xy 95.25725 -235.267013) (xy 95.306231 -235.259259)
			(xy 95.331026 -235.258864) (xy 95.357547 -235.259386) (xy 95.409847 -235.268211) (xy 95.459935 -235.28566)
			(xy 95.483426 -235.29798) (xy 95.491554 -235.302552) (xy 95.509588 -235.305092) (xy 95.526606 -235.301282)
			(xy 95.537274 -235.297726) (xy 95.58147 -235.276898) (xy 95.58665 -235.274287) (xy 95.59575 -235.267097)
			(xy 95.599504 -235.262674) (xy 95.620078 -235.23702) (xy 95.622618 -235.225336) (xy 95.630049 -235.192138)
			(xy 95.647326 -235.126331) (xy 95.657162 -235.093764) (xy 95.66021 -235.083604) (xy 95.658178 -235.063284)
			(xy 95.647764 -235.044488) (xy 95.638874 -235.035344) (xy 95.63354 -235.031788) (xy 95.611258 -235.017206)
			(xy 95.571485 -234.981805) (xy 95.538215 -234.940234) (xy 95.512389 -234.89367) (xy 95.494742 -234.843434)
			(xy 95.485772 -234.790949) (xy 95.485204 -234.764326) (xy 95.485774 -234.737379) (xy 95.494967 -234.684274)
			(xy 95.51304 -234.633499) (xy 95.539468 -234.586529) (xy 95.573484 -234.544725) (xy 95.614102 -234.509301)
			(xy 95.636842 -234.494832) (xy 95.647256 -234.488482) (xy 95.659956 -234.468416) (xy 95.661734 -234.449112)
			(xy 95.662154 -234.442612) (xy 95.660101 -234.429754) (xy 95.65767 -234.423712) (xy 95.646494 -234.398312)
			(xy 95.639899 -234.374725) (xy 95.627959 -234.327219) (xy 95.622618 -234.303316) (xy 95.620078 -234.291632)
			(xy 95.598996 -234.265216) (xy 95.59417 -234.26039) (xy 95.587566 -234.25404) (xy 95.565214 -234.243626)
			(xy 95.555308 -234.23753) (xy 95.551244 -234.233974) (xy 95.50654 -234.22864) (xy 95.498946 -234.227972)
			(xy 95.483948 -234.230675) (xy 95.477076 -234.233974) (xy 95.454396 -234.245242) (xy 95.406336 -234.261201)
			(xy 95.356346 -234.269287) (xy 95.331026 -234.269788) (xy 95.306232 -234.269329) (xy 95.257253 -234.261575)
			(xy 95.21009 -234.246254) (xy 95.165904 -234.223744) (xy 95.125785 -234.194598) (xy 95.090719 -234.159535)
			(xy 95.06157 -234.119418) (xy 95.039056 -234.075234) (xy 95.023731 -234.028073) (xy 95.015973 -233.979094)
			(xy 95.015973 -233.929506) (xy 95.023731 -233.880527) (xy 95.039056 -233.833366) (xy 95.06157 -233.789182)
			(xy 95.090719 -233.749065) (xy 95.125785 -233.714002) (xy 95.165904 -233.684856) (xy 95.21009 -233.662346)
			(xy 95.257253 -233.647025) (xy 95.306232 -233.639271) (xy 95.331026 -233.638852) (xy 95.357547 -233.639373)
			(xy 95.409847 -233.648199) (xy 95.459936 -233.665647) (xy 95.483426 -233.677968) (xy 95.491554 -233.68254)
			(xy 95.509588 -233.68508) (xy 95.526606 -233.68127) (xy 95.537274 -233.677714) (xy 95.58147 -233.656886)
			(xy 95.586649 -233.654274) (xy 95.595748 -233.647084) (xy 95.599504 -233.642662) (xy 95.620078 -233.617008)
			(xy 95.622618 -233.605324) (xy 95.630049 -233.572126) (xy 95.647327 -233.506319) (xy 95.657162 -233.473752)
			(xy 95.66021 -233.463592) (xy 95.658178 -233.443272) (xy 95.647764 -233.424476) (xy 95.638874 -233.415332)
			(xy 95.63354 -233.411776) (xy 95.611259 -233.397194) (xy 95.571487 -233.361793) (xy 95.538218 -233.320221)
			(xy 95.512395 -233.273657) (xy 95.494749 -233.223421) (xy 95.485781 -233.170936) (xy 95.485204 -233.144314)
			(xy 95.485775 -233.117367) (xy 95.49497 -233.064264) (xy 95.513044 -233.013491) (xy 95.539473 -232.966522)
			(xy 95.57349 -232.92472) (xy 95.614107 -232.889297) (xy 95.636842 -232.87482) (xy 95.647256 -232.86847)
			(xy 95.659956 -232.848404) (xy 95.661734 -232.8291) (xy 95.662153 -232.822601) (xy 95.660097 -232.809744)
			(xy 95.65767 -232.8037) (xy 95.646494 -232.7783) (xy 95.639899 -232.754713) (xy 95.627959 -232.707206)
			(xy 95.622618 -232.683304) (xy 95.620078 -232.67162) (xy 95.598996 -232.645204) (xy 95.59417 -232.640378)
			(xy 95.587566 -232.634028) (xy 95.565214 -232.623614) (xy 95.555308 -232.617518) (xy 95.551244 -232.613962)
			(xy 95.50654 -232.608628) (xy 95.498945 -232.607959) (xy 95.483948 -232.610662) (xy 95.477076 -232.613962)
			(xy 95.454396 -232.62523) (xy 95.406337 -232.64119) (xy 95.356346 -232.649276) (xy 95.331026 -232.649776)
			(xy 95.306232 -232.649317) (xy 95.257255 -232.641563) (xy 95.210094 -232.626243) (xy 95.165911 -232.603734)
			(xy 95.125792 -232.574589) (xy 95.090728 -232.539527) (xy 95.06158 -232.499412) (xy 95.039067 -232.45523)
			(xy 95.023743 -232.40807) (xy 95.015985 -232.359094) (xy 95.015985 -232.309506) (xy 95.023743 -232.26053)
			(xy 95.039067 -232.21337) (xy 95.06158 -232.169188) (xy 95.090728 -232.129073) (xy 95.125792 -232.094011)
			(xy 95.165911 -232.064866) (xy 95.210094 -232.042357) (xy 95.257255 -232.027037) (xy 95.306232 -232.019283)
			(xy 95.331026 -232.01884) (xy 95.357547 -232.019361) (xy 95.409848 -232.028186) (xy 95.459936 -232.045634)
			(xy 95.483426 -232.057956) (xy 95.491554 -232.062528) (xy 95.509588 -232.065068) (xy 95.526606 -232.061258)
			(xy 95.537274 -232.057702) (xy 95.58147 -232.036874) (xy 95.586649 -232.034262) (xy 95.595746 -232.02707)
			(xy 95.599504 -232.02265) (xy 95.620078 -231.996996) (xy 95.622618 -231.985312) (xy 95.630049 -231.952114)
			(xy 95.647328 -231.886307) (xy 95.657162 -231.85374) (xy 95.66021 -231.84358) (xy 95.658178 -231.82326)
			(xy 95.647764 -231.804464) (xy 95.638874 -231.79532) (xy 95.63354 -231.791764) (xy 95.61126 -231.777182)
			(xy 95.571489 -231.74178) (xy 95.538222 -231.700208) (xy 95.5124 -231.653644) (xy 95.494756 -231.603408)
			(xy 95.48579 -231.550924) (xy 95.485204 -231.524302) (xy 95.485776 -231.497356) (xy 95.494972 -231.444253)
			(xy 95.513048 -231.393482) (xy 95.539478 -231.346515) (xy 95.573495 -231.304714) (xy 95.614113 -231.269293)
			(xy 95.636842 -231.254808) (xy 95.647256 -231.248458) (xy 95.659956 -231.228392) (xy 95.661734 -231.209088)
			(xy 95.662151 -231.202589) (xy 95.660092 -231.189733) (xy 95.65767 -231.183688) (xy 95.646494 -231.158288)
			(xy 95.639905 -231.134763) (xy 95.627966 -231.087384) (xy 95.622618 -231.063546) (xy 95.620078 -231.051862)
			(xy 95.598996 -231.025446) (xy 95.59417 -231.02062) (xy 95.587566 -231.01427) (xy 95.565214 -231.003856)
			(xy 95.555308 -230.99776) (xy 95.551244 -230.994204) (xy 95.50654 -230.98887) (xy 95.498946 -230.988202)
			(xy 95.483949 -230.990906) (xy 95.477076 -230.994204) (xy 95.454428 -231.005569) (xy 95.406374 -231.02164)
			(xy 95.356361 -231.029776) (xy 95.331026 -231.030272) (xy 95.306209 -231.029812) (xy 95.257186 -231.022052)
			(xy 95.209981 -231.006717) (xy 95.165756 -230.984187) (xy 95.1256 -230.955015) (xy 95.090502 -230.91992)
			(xy 95.061327 -230.879766) (xy 95.038793 -230.835543) (xy 95.023454 -230.788339) (xy 95.01569 -230.739317)
			(xy 95.01569 -230.689683) (xy 95.023454 -230.640661) (xy 95.038793 -230.593457) (xy 95.061327 -230.549234)
			(xy 95.090502 -230.50908) (xy 95.1256 -230.473985) (xy 95.165756 -230.444813) (xy 95.209981 -230.422283)
			(xy 95.257186 -230.406948) (xy 95.306209 -230.399188) (xy 95.331026 -230.398828) (xy 95.357556 -230.399392)
			(xy 95.409864 -230.408304) (xy 95.459944 -230.425838) (xy 95.483426 -230.438198) (xy 95.491554 -230.44277)
			(xy 95.509588 -230.44531) (xy 95.526606 -230.4415) (xy 95.537274 -230.437944) (xy 95.58147 -230.417116)
			(xy 95.586651 -230.414505) (xy 95.595753 -230.407318) (xy 95.599504 -230.402892) (xy 95.620078 -230.377238)
			(xy 95.622618 -230.365808) (xy 95.629491 -230.335645) (xy 95.645244 -230.275812) (xy 95.654114 -230.246174)
			(xy 95.654368 -230.245158) (xy 95.655638 -230.24084) (xy 95.663512 -230.215186) (xy 95.651066 -230.182674)
			(xy 95.636334 -230.17353) (xy 95.613657 -230.159045) (xy 95.573155 -230.123623) (xy 95.539246 -230.081846)
			(xy 95.512912 -230.034925) (xy 95.494915 -229.984217) (xy 95.485777 -229.931193) (xy 95.485204 -229.90429)
			(xy 95.485777 -229.877344) (xy 95.494975 -229.824243) (xy 95.513052 -229.773473) (xy 95.539482 -229.726507)
			(xy 95.5735 -229.684708) (xy 95.614118 -229.649289) (xy 95.636842 -229.634796) (xy 95.647256 -229.628446)
			(xy 95.659956 -229.60838) (xy 95.661734 -229.589076) (xy 95.66215 -229.582577) (xy 95.660088 -229.569723)
			(xy 95.65767 -229.563676) (xy 95.646494 -229.538276) (xy 95.639905 -229.514751) (xy 95.627967 -229.467372)
			(xy 95.622618 -229.443534) (xy 95.620078 -229.43185) (xy 95.598996 -229.405434) (xy 95.59417 -229.400608)
			(xy 95.587566 -229.394258) (xy 95.565214 -229.383844) (xy 95.555308 -229.377748) (xy 95.551244 -229.374192)
			(xy 95.50654 -229.368858) (xy 95.498946 -229.36819) (xy 95.483948 -229.370894) (xy 95.477076 -229.374192)
			(xy 95.454427 -229.385554) (xy 95.406373 -229.401621) (xy 95.356361 -229.409754) (xy 95.331026 -229.41026)
			(xy 95.30621 -229.4098) (xy 95.257189 -229.40204) (xy 95.209985 -229.386706) (xy 95.165762 -229.364176)
			(xy 95.125608 -229.335006) (xy 95.090511 -229.299912) (xy 95.061337 -229.25976) (xy 95.038804 -229.215539)
			(xy 95.023466 -229.168336) (xy 95.015702 -229.119316) (xy 95.015702 -229.069684) (xy 95.023466 -229.020664)
			(xy 95.038804 -228.973461) (xy 95.061337 -228.92924) (xy 95.090511 -228.889088) (xy 95.125608 -228.853994)
			(xy 95.165762 -228.824824) (xy 95.209985 -228.802294) (xy 95.257189 -228.78696) (xy 95.30621 -228.7792)
			(xy 95.331026 -228.778816) (xy 95.357556 -228.77938) (xy 95.409864 -228.788291) (xy 95.459945 -228.805825)
			(xy 95.483426 -228.818186) (xy 95.491554 -228.822758) (xy 95.509588 -228.825298) (xy 95.526606 -228.821488)
			(xy 95.537274 -228.817932) (xy 95.58147 -228.797104) (xy 95.58665 -228.794493) (xy 95.595751 -228.787304)
			(xy 95.599504 -228.78288) (xy 95.620078 -228.757226) (xy 95.622618 -228.745542) (xy 95.630048 -228.712344)
			(xy 95.647326 -228.646536) (xy 95.657162 -228.61397) (xy 95.66021 -228.60381) (xy 95.658178 -228.58349)
			(xy 95.647764 -228.564694) (xy 95.638874 -228.55555) (xy 95.63354 -228.551994) (xy 95.611258 -228.537413)
			(xy 95.571484 -228.502012) (xy 95.538213 -228.46044) (xy 95.512387 -228.413876) (xy 95.494738 -228.36364)
			(xy 95.485767 -228.311155) (xy 95.485204 -228.284532) (xy 95.485774 -228.257585) (xy 95.494966 -228.204479)
			(xy 95.513038 -228.153704) (xy 95.539465 -228.106732) (xy 95.573482 -228.064928) (xy 95.614099 -228.029503)
			(xy 95.636842 -228.015038) (xy 95.647256 -228.008688) (xy 95.659956 -227.988622) (xy 95.661734 -227.969318)
			(xy 95.662155 -227.962818) (xy 95.660103 -227.94996) (xy 95.65767 -227.943918) (xy 95.646494 -227.918518)
			(xy 95.639899 -227.894931) (xy 95.627958 -227.847425) (xy 95.622618 -227.823522) (xy 95.620078 -227.811838)
			(xy 95.598996 -227.785422) (xy 95.59417 -227.780596) (xy 95.587566 -227.774246) (xy 95.565214 -227.763832)
			(xy 95.555308 -227.757736) (xy 95.551244 -227.75418) (xy 95.50654 -227.748846) (xy 95.498946 -227.748178)
			(xy 95.483948 -227.750881) (xy 95.477076 -227.75418) (xy 95.454427 -227.765542) (xy 95.406373 -227.78161)
			(xy 95.356361 -227.789744) (xy 95.331026 -227.790248) (xy 95.306211 -227.789789) (xy 95.257192 -227.782028)
			(xy 95.20999 -227.766695) (xy 95.165768 -227.744166) (xy 95.125615 -227.714996) (xy 95.09052 -227.679904)
			(xy 95.061348 -227.639754) (xy 95.038815 -227.595534) (xy 95.023478 -227.548334) (xy 95.015714 -227.499315)
			(xy 95.015714 -227.449685) (xy 95.023478 -227.400666) (xy 95.038815 -227.353466) (xy 95.061348 -227.309246)
			(xy 95.09052 -227.269096) (xy 95.125615 -227.234004) (xy 95.165768 -227.204834) (xy 95.20999 -227.182305)
			(xy 95.257192 -227.166972) (xy 95.306211 -227.159211) (xy 95.331026 -227.158804) (xy 95.357556 -227.159368)
			(xy 95.409864 -227.168279) (xy 95.459945 -227.185812) (xy 95.483426 -227.198174) (xy 95.491554 -227.202746)
			(xy 95.509588 -227.205286) (xy 95.526606 -227.201476) (xy 95.537274 -227.19792) (xy 95.58147 -227.177092)
			(xy 95.58665 -227.17448) (xy 95.595749 -227.16729) (xy 95.599504 -227.162868) (xy 95.620078 -227.137214)
			(xy 95.622618 -227.12553) (xy 95.630049 -227.092332) (xy 95.647327 -227.026525) (xy 95.657162 -226.993958)
			(xy 95.66021 -226.983798) (xy 95.658178 -226.963478) (xy 95.647764 -226.944682) (xy 95.638874 -226.935538)
			(xy 95.63354 -226.931982) (xy 95.611259 -226.9174) (xy 95.571486 -226.881999) (xy 95.538216 -226.840427)
			(xy 95.512392 -226.793863) (xy 95.494745 -226.743627) (xy 95.485776 -226.691142) (xy 95.485204 -226.66452)
			(xy 95.485764 -226.637784) (xy 95.494772 -226.585075) (xy 95.512534 -226.534639) (xy 95.538541 -226.487917)
			(xy 95.57205 -226.446246) (xy 95.612102 -226.410819) (xy 95.634556 -226.396296) (xy 95.641712 -226.39146)
			(xy 95.652535 -226.378016) (xy 95.658292 -226.361745) (xy 95.658686 -226.353116) (xy 95.658686 -226.339908)
			(xy 95.6564 -226.332542) (xy 95.650426 -226.312602) (xy 95.639374 -226.272466) (xy 95.634302 -226.252278)
			(xy 95.632524 -226.245166) (xy 95.6183 -226.220528) (xy 95.612966 -226.215448) (xy 95.595359 -226.19838)
			(xy 95.561062 -226.163323) (xy 95.544386 -226.145344) (xy 95.53702 -226.137216) (xy 95.517716 -226.128834)
			(xy 95.493586 -226.128834) (xy 95.482156 -226.131628) (xy 95.476568 -226.134676) (xy 95.453954 -226.145861)
			(xy 95.406056 -226.161696) (xy 95.35625 -226.169718) (xy 95.331026 -226.170236) (xy 95.306213 -226.169777)
			(xy 95.257197 -226.162017) (xy 95.209998 -226.146685) (xy 95.165779 -226.124158) (xy 95.125628 -226.094991)
			(xy 95.090535 -226.059902) (xy 95.061362 -226.019755) (xy 95.03883 -225.975539) (xy 95.023492 -225.928342)
			(xy 95.015727 -225.879327) (xy 95.015304 -225.854514) (xy 95.015804 -225.829485) (xy 95.023744 -225.780059)
			(xy 95.03938 -225.732505) (xy 95.062319 -225.688011) (xy 95.076772 -225.66757) (xy 95.081816 -225.660053)
			(xy 95.086766 -225.642653) (xy 95.085385 -225.624615) (xy 95.077842 -225.608171) (xy 95.071692 -225.60153)
			(xy 94.828106 -225.357944) (xy 94.819978 -225.351086) (xy 94.804992 -225.344736) (xy 94.799912 -225.34372)
			(xy 94.774931 -225.338081) (xy 94.727176 -225.319596) (xy 94.683177 -225.293398) (xy 94.64417 -225.260221)
			(xy 94.611249 -225.220999) (xy 94.585337 -225.17683) (xy 94.567164 -225.128955) (xy 94.56166 -225.103944)
			(xy 94.560136 -225.096324) (xy 94.55277 -225.082862) (xy 94.54769 -225.077528) (xy 93.982286 -224.512124)
			(xy 93.975567 -224.504888) (xy 93.96796 -224.486683) (xy 93.967554 -224.476818) (xy 93.967554 -223.931734)
			(xy 93.959934 -223.912938) (xy 93.952568 -223.905826) (xy 93.586046 -223.539304) (xy 93.579335 -223.532065)
			(xy 93.571742 -223.51386) (xy 93.571314 -223.503998) (xy 93.571314 -223.322134) (xy 93.563694 -223.303338)
			(xy 93.556328 -223.296226) (xy 93.37548 -223.115378) (xy 93.368368 -223.108012) (xy 93.349572 -223.100392)
			(xy 92.349828 -223.100392) (xy 92.339991 -223.099855) (xy 92.321831 -223.092267) (xy 92.314522 -223.08566)
			(xy 92.115386 -222.886524) (xy 92.108667 -222.879288) (xy 92.10106 -222.861083) (xy 92.100654 -222.851218)
			(xy 92.100654 -222.356426) (xy 92.10119 -222.346588) (xy 92.108772 -222.328424) (xy 92.115386 -222.32112)
			(xy 93.746574 -220.689932) (xy 93.753298 -220.682698) (xy 93.760914 -220.664493) (xy 93.761306 -220.654626)
			(xy 93.761306 -219.153486) (xy 93.760838 -219.142764) (xy 93.752083 -219.123191) (xy 93.736075 -219.108925)
			(xy 93.726 -219.105226) (xy 93.725238 -219.104972) (xy 93.695186 -219.094492) (xy 93.637743 -219.067086)
			(xy 93.584167 -219.032729) (xy 93.535295 -218.991957) (xy 93.491892 -218.945407) (xy 93.454634 -218.893806)
			(xy 93.424104 -218.83796) (xy 93.400779 -218.778742) (xy 93.385024 -218.717077) (xy 93.377083 -218.653929)
			(xy 93.377083 -218.590283) (xy 93.385021 -218.527134) (xy 93.400776 -218.465469) (xy 93.424099 -218.40625)
			(xy 93.454628 -218.350404) (xy 93.491885 -218.298802) (xy 93.535287 -218.252251) (xy 93.584158 -218.211478)
			(xy 93.637733 -218.177119) (xy 93.695176 -218.149712) (xy 93.725238 -218.139264) (xy 93.726 -218.13901)
			(xy 93.735999 -218.135195) (xy 93.751918 -218.12093) (xy 93.760684 -218.101435) (xy 93.761306 -218.09075)
			(xy 93.761306 -217.93581) (xy 93.760888 -217.925787) (xy 93.75322 -217.907266) (xy 93.739048 -217.893089)
			(xy 93.720529 -217.885415) (xy 93.710506 -217.88501) (xy 93.69425 -217.88501) (xy 93.668088 -217.903552)
			(xy 93.662754 -217.918792) (xy 93.651757 -217.948029) (xy 93.623622 -218.003802) (xy 93.588879 -218.055715)
			(xy 93.548049 -218.102991) (xy 93.501744 -218.144919) (xy 93.45066 -218.18087) (xy 93.395562 -218.210305)
			(xy 93.337279 -218.232782) (xy 93.276685 -218.247963) (xy 93.214689 -218.25562) (xy 93.183456 -218.256104)
			(xy 93.151497 -218.255599) (xy 93.088084 -218.247583) (xy 93.026175 -218.231683) (xy 92.966747 -218.208149)
			(xy 92.910737 -218.177353) (xy 92.859028 -218.139781) (xy 92.812436 -218.096024) (xy 92.771695 -218.046772)
			(xy 92.737447 -217.992803) (xy 92.710234 -217.934968) (xy 92.690483 -217.874178) (xy 92.678507 -217.811392)
			(xy 92.674493 -217.7476) (xy 92.678507 -217.683808) (xy 92.690483 -217.621022) (xy 92.710234 -217.560232)
			(xy 92.737447 -217.502397) (xy 92.771695 -217.448428) (xy 92.812436 -217.399176) (xy 92.859028 -217.355419)
			(xy 92.910737 -217.317847) (xy 92.966747 -217.287051) (xy 93.026175 -217.263517) (xy 93.088084 -217.247617)
			(xy 93.151497 -217.239601) (xy 93.183456 -217.239088) (xy 93.216007 -217.239603) (xy 93.280576 -217.247907)
			(xy 93.343557 -217.264383) (xy 93.403921 -217.288763) (xy 93.46068 -217.320647) (xy 93.512904 -217.359515)
			(xy 93.559741 -217.40473) (xy 93.580458 -217.429842) (xy 93.590618 -217.442542) (xy 93.621606 -217.451432)
			(xy 93.72727 -217.414094) (xy 93.733366 -217.411554) (xy 93.740825 -217.407457) (xy 93.752682 -217.395263)
			(xy 93.759871 -217.37985) (xy 93.761052 -217.371422) (xy 93.761306 -217.366088) (xy 93.761306 -210.871054)
			(xy 93.761838 -210.861215) (xy 93.769419 -210.843048) (xy 93.776038 -210.835748) (xy 94.10065 -210.511136)
			(xy 94.108016 -210.495896) (xy 94.109032 -210.48726) (xy 94.112837 -210.458772) (xy 94.127903 -210.403308)
			(xy 94.151118 -210.350732) (xy 94.181958 -210.302234) (xy 94.200472 -210.28025) (xy 94.206568 -210.273138)
			(xy 94.212918 -210.256374) (xy 94.212918 -210.170522) (xy 94.206568 -210.153758) (xy 94.200472 -210.146646)
			(xy 94.182834 -210.125713) (xy 94.153117 -210.079745) (xy 94.130282 -210.029997) (xy 94.114801 -209.977495)
			(xy 94.106991 -209.923317) (xy 94.106492 -209.895948) (xy 94.106944 -209.869531) (xy 94.114242 -209.817204)
			(xy 94.128689 -209.766385) (xy 94.150012 -209.718045) (xy 94.1778 -209.67311) (xy 94.211523 -209.632439)
			(xy 94.230698 -209.614262) (xy 94.239334 -209.606388) (xy 94.24797 -209.58429) (xy 94.238826 -209.48015)
			(xy 94.226126 -209.45983) (xy 94.215966 -209.45348) (xy 94.189146 -209.435953) (xy 94.139715 -209.395192)
			(xy 94.095791 -209.348549) (xy 94.058068 -209.296762) (xy 94.027144 -209.240649) (xy 94.003508 -209.181099)
			(xy 93.987532 -209.119053) (xy 93.979471 -209.055493) (xy 93.978984 -209.023458) (xy 93.980254 -208.988914)
			(xy 93.98127 -208.97723) (xy 93.984366 -208.947952) (xy 93.996451 -208.89033) (xy 94.015106 -208.834487)
			(xy 94.040081 -208.781171) (xy 94.071043 -208.731093) (xy 94.088966 -208.707736) (xy 94.08922 -208.707482)
			(xy 94.094554 -208.700624) (xy 94.10319 -208.67624) (xy 94.104492 -208.672171) (xy 94.1059 -208.663747)
			(xy 94.105984 -208.659476) (xy 94.105984 -208.52384) (xy 94.105924 -208.519567) (xy 94.104517 -208.511138)
			(xy 94.10319 -208.507076) (xy 94.094554 -208.482692) (xy 94.08922 -208.475834) (xy 94.088966 -208.47558)
			(xy 94.068258 -208.448518) (xy 94.033497 -208.389907) (xy 94.006868 -208.327182) (xy 93.988849 -208.261464)
			(xy 93.97976 -208.19393) (xy 93.979238 -208.159858) (xy 93.979678 -208.129741) (xy 93.986784 -208.069926)
			(xy 94.000904 -208.01137) (xy 94.021839 -207.95489) (xy 94.049297 -207.901278) (xy 94.082893 -207.851283)
			(xy 94.122158 -207.805605) (xy 94.144084 -207.784954) (xy 94.150434 -207.779112) (xy 94.166944 -207.748632)
			(xy 94.168214 -207.739488) (xy 94.171262 -207.718406) (xy 94.171262 -207.718152) (xy 94.172532 -207.709262)
			(xy 94.171008 -207.701388) (xy 94.169945 -207.697019) (xy 94.166495 -207.688715) (xy 94.16415 -207.684878)
			(xy 94.150475 -207.662052) (xy 94.128891 -207.613416) (xy 94.114277 -207.562252) (xy 94.106916 -207.509553)
			(xy 94.106492 -207.482948) (xy 94.106978 -207.455697) (xy 94.114734 -207.401749) (xy 94.130089 -207.349454)
			(xy 94.152731 -207.299877) (xy 94.182197 -207.254027) (xy 94.217888 -207.212836) (xy 94.259079 -207.177145)
			(xy 94.304929 -207.147679) (xy 94.354506 -207.125037) (xy 94.406801 -207.109682) (xy 94.460749 -207.101926)
			(xy 94.515251 -207.101926) (xy 94.569199 -207.109682) (xy 94.621494 -207.125037) (xy 94.671071 -207.147679)
			(xy 94.716921 -207.177145) (xy 94.758112 -207.212836) (xy 94.793803 -207.254027) (xy 94.823269 -207.299877)
			(xy 94.845911 -207.349454) (xy 94.861266 -207.401749) (xy 94.869022 -207.455697) (xy 94.869508 -207.482948)
			(xy 94.869064 -207.509553) (xy 94.861707 -207.56225) (xy 94.8471 -207.613415) (xy 94.825527 -207.662054)
			(xy 94.81185 -207.684878) (xy 94.808802 -207.689704) (xy 94.804992 -207.700372) (xy 94.803722 -207.712818)
			(xy 94.808802 -207.748378) (xy 94.810834 -207.757268) (xy 94.813374 -207.76438) (xy 94.820486 -207.775302)
			(xy 94.825566 -207.779874) (xy 94.848188 -207.800584) (xy 94.888808 -207.84654) (xy 94.923602 -207.89705)
			(xy 94.952062 -207.951381) (xy 94.973776 -208.008743) (xy 94.988427 -208.068302) (xy 94.995803 -208.129191)
			(xy 94.996254 -208.159858) (xy 94.995705 -208.193928) (xy 94.98661 -208.261457) (xy 94.968589 -208.32717)
			(xy 94.941964 -208.389892) (xy 94.907212 -208.448504) (xy 94.886526 -208.47558) (xy 94.886272 -208.475834)
			(xy 94.880938 -208.482692) (xy 94.872302 -208.507076) (xy 94.871002 -208.511145) (xy 94.869596 -208.51957)
			(xy 94.869508 -208.52384) (xy 94.869508 -208.659476) (xy 94.86957 -208.663749) (xy 94.870979 -208.672177)
			(xy 94.872302 -208.67624) (xy 94.880938 -208.700624) (xy 94.886272 -208.707482) (xy 94.886526 -208.707736)
			(xy 94.907229 -208.7348) (xy 94.941983 -208.793412) (xy 94.968605 -208.856138) (xy 94.986619 -208.921855)
			(xy 94.995703 -208.989387) (xy 94.996254 -209.023458) (xy 94.995771 -209.055495) (xy 94.987728 -209.119061)
			(xy 94.971764 -209.181113) (xy 94.948132 -209.240669) (xy 94.917206 -209.296784) (xy 94.879477 -209.34857)
			(xy 94.835541 -209.395207) (xy 94.786095 -209.435956) (xy 94.759272 -209.45348) (xy 94.749112 -209.45983)
			(xy 94.73692 -209.479896) (xy 94.727776 -209.584036) (xy 94.736412 -209.606134) (xy 94.745048 -209.614008)
			(xy 94.745302 -209.614262) (xy 94.746064 -209.615024) (xy 94.756217 -209.624509) (xy 94.775285 -209.644722)
			(xy 94.784164 -209.65541) (xy 94.78899 -209.661506) (xy 94.792546 -209.666078) (xy 94.800928 -209.672936)
			(xy 94.80677 -209.67573) (xy 94.811386 -209.677916) (xy 94.821241 -209.680593) (xy 94.826328 -209.681064)
			(xy 94.90202 -209.685636) (xy 94.912793 -209.685798) (xy 94.932917 -209.67816) (xy 94.940882 -209.670904)
			(xy 97.331022 -207.280764) (xy 97.334832 -207.273144) (xy 97.346923 -207.249545) (xy 97.375304 -207.204751)
			(xy 97.391474 -207.183736) (xy 97.391728 -207.183482) (xy 97.397062 -207.176624) (xy 97.405698 -207.15224)
			(xy 97.406999 -207.148171) (xy 97.408408 -207.139747) (xy 97.408492 -207.135476) (xy 97.408492 -206.99984)
			(xy 97.408432 -206.995567) (xy 97.407025 -206.987138) (xy 97.405698 -206.983076) (xy 97.397062 -206.958692)
			(xy 97.391728 -206.951834) (xy 97.391474 -206.95158) (xy 97.37077 -206.924516) (xy 97.336015 -206.865904)
			(xy 97.309391 -206.803179) (xy 97.291375 -206.737462) (xy 97.282288 -206.669929) (xy 97.281746 -206.635858)
			(xy 97.282293 -206.601717) (xy 97.29142 -206.534048) (xy 97.309519 -206.468208) (xy 97.336262 -206.405381)
			(xy 97.37117 -206.346697) (xy 97.391982 -206.319628) (xy 97.397824 -206.312262) (xy 97.403412 -206.294482)
			(xy 97.401634 -206.264002) (xy 97.401286 -206.259615) (xy 97.399243 -206.251055) (xy 97.39757 -206.246984)
			(xy 97.386902 -206.222346) (xy 97.381314 -206.21625) (xy 97.36264 -206.195044) (xy 97.331108 -206.148158)
			(xy 97.306837 -206.097133) (xy 97.290357 -206.043086) (xy 97.28203 -205.9872) (xy 97.281492 -205.958948)
			(xy 97.281978 -205.931697) (xy 97.289734 -205.877749) (xy 97.305089 -205.825454) (xy 97.327731 -205.775877)
			(xy 97.357197 -205.730027) (xy 97.392888 -205.688836) (xy 97.434079 -205.653145) (xy 97.479929 -205.623679)
			(xy 97.529506 -205.601037) (xy 97.581801 -205.585682) (xy 97.635749 -205.577926) (xy 97.690251 -205.577926)
			(xy 97.744199 -205.585682) (xy 97.796494 -205.601037) (xy 97.846071 -205.623679) (xy 97.891921 -205.653145)
			(xy 97.933112 -205.688836) (xy 97.968803 -205.730027) (xy 97.998269 -205.775877) (xy 98.020911 -205.825454)
			(xy 98.036266 -205.877749) (xy 98.044022 -205.931697) (xy 98.044508 -205.958948) (xy 98.044508 -205.95971)
			(xy 98.044148 -205.98374) (xy 98.038113 -206.031421) (xy 98.026129 -206.077963) (xy 98.017584 -206.100426)
			(xy 98.015806 -206.104744) (xy 98.01225 -206.121508) (xy 98.013012 -206.13497) (xy 98.015298 -206.141574)
			(xy 98.02114 -206.159608) (xy 98.02266 -206.163922) (xy 98.027008 -206.171968) (xy 98.029776 -206.17561)
			(xy 98.04654 -206.196438) (xy 98.05416 -206.20101) (xy 98.081009 -206.217924) (xy 98.130686 -206.257408)
			(xy 98.15322 -206.27975) (xy 98.160332 -206.287116) (xy 98.16719 -206.294228) (xy 98.203258 -206.310992)
			(xy 98.213926 -206.311246) (xy 98.276664 -206.31277) (xy 98.284405 -206.312699) (xy 98.29928 -206.308442)
			(xy 98.305874 -206.304388) (xy 98.310192 -206.301594) (xy 99.154234 -205.457552) (xy 99.154742 -205.457044)
			(xy 99.161325 -205.449663) (xy 99.168776 -205.431364) (xy 99.16922 -205.421484) (xy 99.16922 -191.656462)
			(xy 99.168791 -191.646394) (xy 99.161069 -191.627798) (xy 99.154234 -191.620394) (xy 98.608642 -191.074802)
			(xy 98.60124 -191.067964) (xy 98.582642 -191.060251) (xy 98.572574 -191.059816) (xy 78.431898 -191.059816)
			(xy 78.421828 -191.059393) (xy 78.403222 -191.05168) (xy 78.39583 -191.04483) (xy 77.118972 -189.767972)
			(xy 77.109678 -189.759521) (xy 77.085684 -189.752197) (xy 77.073252 -189.754002) (xy 76.990448 -189.770258)
			(xy 76.978461 -189.773397) (xy 76.959189 -189.788911) (xy 76.953618 -189.799976) (xy 76.95184 -189.80404)
			(xy 76.95184 -189.804294) (xy 76.9493 -189.809882) (xy 76.948538 -189.81166) (xy 76.946252 -189.816486)
			(xy 76.946252 -189.81674) (xy 76.937358 -189.835741) (xy 76.916884 -189.872362) (xy 76.905358 -189.889892)
			(xy 76.901294 -189.895734) (xy 76.89469 -189.9158) (xy 76.89469 -189.931802) (xy 76.89723 -189.939422)
			(xy 76.901294 -189.952884) (xy 76.905612 -189.959234) (xy 76.922224 -189.984511) (xy 76.949988 -190.038251)
			(xy 76.971182 -190.094905) (xy 76.985505 -190.153672) (xy 76.992755 -190.213725) (xy 76.993242 -190.243968)
			(xy 76.993242 -190.244984) (xy 76.992764 -190.275679) (xy 76.985345 -190.336621) (xy 76.970649 -190.396227)
			(xy 76.948889 -190.453632) (xy 76.920382 -190.508003) (xy 76.903326 -190.533528) (xy 76.897848 -190.542279)
			(xy 76.893711 -190.562487) (xy 76.897838 -190.582696) (xy 76.903326 -190.59144) (xy 76.920377 -190.616968)
			(xy 76.948899 -190.671332) (xy 76.970663 -190.728736) (xy 76.985351 -190.788344) (xy 76.99275 -190.849288)
			(xy 76.993242 -190.879984) (xy 76.992764 -190.910679) (xy 76.985345 -190.971621) (xy 76.970649 -191.031227)
			(xy 76.948889 -191.088632) (xy 76.920382 -191.143003) (xy 76.903326 -191.168528) (xy 76.897848 -191.177279)
			(xy 76.893711 -191.197487) (xy 76.897838 -191.217696) (xy 76.903326 -191.22644) (xy 76.920377 -191.251968)
			(xy 76.948899 -191.306332) (xy 76.970663 -191.363736) (xy 76.985351 -191.423344) (xy 76.99275 -191.484288)
			(xy 76.993242 -191.514984) (xy 76.992764 -191.545679) (xy 76.985345 -191.606621) (xy 76.970649 -191.666227)
			(xy 76.948889 -191.723632) (xy 76.920382 -191.778003) (xy 76.903326 -191.803528) (xy 76.897848 -191.812279)
			(xy 76.893711 -191.832487) (xy 76.897838 -191.852696) (xy 76.903326 -191.86144) (xy 76.920377 -191.886968)
			(xy 76.948899 -191.941332) (xy 76.970663 -191.998736) (xy 76.985351 -192.058344) (xy 76.99275 -192.119288)
			(xy 76.993242 -192.149984) (xy 76.992733 -192.182398) (xy 76.984493 -192.246699) (xy 76.968145 -192.309431)
			(xy 76.943954 -192.369575) (xy 76.912313 -192.426156) (xy 76.89342 -192.452498) (xy 76.887378 -192.461473)
			(xy 76.882806 -192.482598) (xy 76.887376 -192.503723) (xy 76.89342 -192.512696) (xy 76.912123 -192.538976)
			(xy 76.943451 -192.595361) (xy 76.967394 -192.655257) (xy 76.983567 -192.7177) (xy 76.991711 -192.781688)
			(xy 76.992226 -192.81394) (xy 76.991745 -192.844635) (xy 76.984321 -192.905574) (xy 76.969621 -192.965178)
			(xy 76.947859 -193.022581) (xy 76.919351 -193.07695) (xy 76.90231 -193.102484) (xy 76.896845 -193.111235)
			(xy 76.892731 -193.131433) (xy 76.896871 -193.151626) (xy 76.90231 -193.160396) (xy 76.919364 -193.185923)
			(xy 76.947892 -193.240286) (xy 76.969661 -193.29769) (xy 76.984355 -193.357299) (xy 76.99176 -193.418244)
			(xy 76.992226 -193.44894) (xy 76.991745 -193.479635) (xy 76.984321 -193.540574) (xy 76.969621 -193.600178)
			(xy 76.947859 -193.657581) (xy 76.919351 -193.71195) (xy 76.90231 -193.737484) (xy 76.896845 -193.746235)
			(xy 76.892731 -193.766433) (xy 76.896871 -193.786626) (xy 76.90231 -193.795396) (xy 76.919364 -193.820923)
			(xy 76.947892 -193.875286) (xy 76.969661 -193.93269) (xy 76.984355 -193.992299) (xy 76.99176 -194.053244)
			(xy 76.992226 -194.08394) (xy 76.991745 -194.114635) (xy 76.984321 -194.175574) (xy 76.969621 -194.235178)
			(xy 76.947859 -194.292581) (xy 76.919351 -194.34695) (xy 76.90231 -194.372484) (xy 76.896845 -194.381235)
			(xy 76.892731 -194.401433) (xy 76.896871 -194.421626) (xy 76.90231 -194.430396) (xy 76.919364 -194.455923)
			(xy 76.947892 -194.510286) (xy 76.969661 -194.56769) (xy 76.984355 -194.627299) (xy 76.99176 -194.688244)
			(xy 76.992226 -194.71894) (xy 76.991745 -194.749635) (xy 76.984321 -194.810574) (xy 76.969621 -194.870178)
			(xy 76.947859 -194.927581) (xy 76.919351 -194.98195) (xy 76.90231 -195.007484) (xy 76.896845 -195.016235)
			(xy 76.892731 -195.036433) (xy 76.896871 -195.056626) (xy 76.90231 -195.065396) (xy 76.919364 -195.090923)
			(xy 76.947892 -195.145286) (xy 76.969661 -195.20269) (xy 76.984355 -195.262299) (xy 76.99176 -195.323244)
			(xy 76.992226 -195.35394) (xy 76.991745 -195.384635) (xy 76.984321 -195.445574) (xy 76.969621 -195.505178)
			(xy 76.947859 -195.562581) (xy 76.919351 -195.61695) (xy 76.90231 -195.642484) (xy 76.896845 -195.651235)
			(xy 76.892731 -195.671433) (xy 76.896871 -195.691626) (xy 76.90231 -195.700396) (xy 76.919364 -195.725923)
			(xy 76.947892 -195.780286) (xy 76.969661 -195.83769) (xy 76.984355 -195.897299) (xy 76.99176 -195.958244)
			(xy 76.992226 -195.98894) (xy 76.99176 -196.01967) (xy 76.984347 -196.080681) (xy 76.969635 -196.140354)
			(xy 76.947838 -196.197818) (xy 76.919274 -196.252237) (xy 76.884359 -196.302816) (xy 76.843603 -196.348818)
			(xy 76.797599 -196.389573) (xy 76.747018 -196.424486) (xy 76.692598 -196.453047) (xy 76.635133 -196.474842)
			(xy 76.575459 -196.489551) (xy 76.514448 -196.496961) (xy 76.483718 -196.497448) (xy 76.453023 -196.49697)
			(xy 76.392081 -196.489552) (xy 76.332475 -196.474856) (xy 76.275069 -196.453096) (xy 76.220698 -196.424589)
			(xy 76.195174 -196.407532) (xy 76.186422 -196.402061) (xy 76.166218 -196.397933) (xy 76.146014 -196.402061)
			(xy 76.137262 -196.407532) (xy 76.111735 -196.424586) (xy 76.057373 -196.453114) (xy 75.999968 -196.474882)
			(xy 75.940359 -196.489573) (xy 75.879414 -196.496974) (xy 75.848718 -196.497448) (xy 75.818023 -196.49697)
			(xy 75.757081 -196.489552) (xy 75.697475 -196.474856) (xy 75.640069 -196.453096) (xy 75.585698 -196.424589)
			(xy 75.560174 -196.407532) (xy 75.551422 -196.402061) (xy 75.531218 -196.397933) (xy 75.511014 -196.402061)
			(xy 75.502262 -196.407532) (xy 75.476735 -196.424586) (xy 75.422373 -196.453114) (xy 75.364968 -196.474882)
			(xy 75.305359 -196.489573) (xy 75.244414 -196.496974) (xy 75.213718 -196.497448) (xy 75.182985 -196.496985)
			(xy 75.121968 -196.489579) (xy 75.062288 -196.474872) (xy 75.004816 -196.453079) (xy 74.95039 -196.424517)
			(xy 74.899804 -196.389603) (xy 74.853794 -196.348847) (xy 74.813032 -196.302842) (xy 74.778113 -196.252259)
			(xy 74.749545 -196.197837) (xy 74.727745 -196.140367) (xy 74.713031 -196.080689) (xy 74.705618 -196.019673)
			(xy 74.70521 -195.98894) (xy 74.705692 -195.958246) (xy 74.713119 -195.897308) (xy 74.727822 -195.837706)
			(xy 74.749587 -195.780305) (xy 74.778098 -195.725938) (xy 74.795126 -195.700396) (xy 74.800604 -195.691643)
			(xy 74.804746 -195.671433) (xy 74.80063 -195.651218) (xy 74.795126 -195.642484) (xy 74.778072 -195.616957)
			(xy 74.749544 -195.562594) (xy 74.727776 -195.50519) (xy 74.713083 -195.445581) (xy 74.70568 -195.384636)
			(xy 74.70521 -195.35394) (xy 74.705692 -195.323246) (xy 74.713119 -195.262308) (xy 74.727822 -195.202706)
			(xy 74.749587 -195.145305) (xy 74.778098 -195.090938) (xy 74.795126 -195.065396) (xy 74.800604 -195.056643)
			(xy 74.804746 -195.036433) (xy 74.80063 -195.016218) (xy 74.795126 -195.007484) (xy 74.778072 -194.981957)
			(xy 74.749544 -194.927594) (xy 74.727776 -194.87019) (xy 74.713083 -194.810581) (xy 74.70568 -194.749636)
			(xy 74.70521 -194.71894) (xy 74.705692 -194.688246) (xy 74.713119 -194.627308) (xy 74.727822 -194.567706)
			(xy 74.749587 -194.510305) (xy 74.778098 -194.455938) (xy 74.795126 -194.430396) (xy 74.800604 -194.421643)
			(xy 74.804746 -194.401433) (xy 74.80063 -194.381218) (xy 74.795126 -194.372484) (xy 74.778072 -194.346957)
			(xy 74.749544 -194.292594) (xy 74.727776 -194.23519) (xy 74.713083 -194.175581) (xy 74.70568 -194.114636)
			(xy 74.70521 -194.08394) (xy 74.705692 -194.053246) (xy 74.713119 -193.992308) (xy 74.727822 -193.932706)
			(xy 74.749587 -193.875305) (xy 74.778098 -193.820938) (xy 74.795126 -193.795396) (xy 74.800604 -193.786643)
			(xy 74.804746 -193.766433) (xy 74.80063 -193.746218) (xy 74.795126 -193.737484) (xy 74.778072 -193.711957)
			(xy 74.749544 -193.657594) (xy 74.727776 -193.60019) (xy 74.713083 -193.540581) (xy 74.70568 -193.479636)
			(xy 74.70521 -193.44894) (xy 74.705692 -193.418246) (xy 74.713119 -193.357308) (xy 74.727822 -193.297706)
			(xy 74.749587 -193.240305) (xy 74.778098 -193.185938) (xy 74.795126 -193.160396) (xy 74.800604 -193.151643)
			(xy 74.804746 -193.131433) (xy 74.80063 -193.111218) (xy 74.795126 -193.102484) (xy 74.778072 -193.076957)
			(xy 74.749544 -193.022594) (xy 74.727776 -192.96519) (xy 74.713083 -192.905581) (xy 74.70568 -192.844636)
			(xy 74.70521 -192.81394) (xy 74.705712 -192.781271) (xy 74.714079 -192.716471) (xy 74.730681 -192.653278)
			(xy 74.755244 -192.592733) (xy 74.787363 -192.535834) (xy 74.806556 -192.509394) (xy 74.812635 -192.500336)
			(xy 74.817239 -192.479033) (xy 74.812663 -192.457725) (xy 74.806556 -192.448688) (xy 74.787582 -192.422289)
			(xy 74.755773 -192.36559) (xy 74.731451 -192.305299) (xy 74.715011 -192.2424) (xy 74.706723 -192.177918)
			(xy 74.706226 -192.145412) (xy 74.706704 -192.114717) (xy 74.714123 -192.053775) (xy 74.728819 -191.994169)
			(xy 74.750578 -191.936763) (xy 74.779084 -191.882392) (xy 74.796142 -191.856868) (xy 74.801613 -191.848115)
			(xy 74.805743 -191.82791) (xy 74.801621 -191.807703) (xy 74.796142 -191.798956) (xy 74.779089 -191.773429)
			(xy 74.750564 -191.719066) (xy 74.728797 -191.661662) (xy 74.714107 -191.602053) (xy 74.706708 -191.541108)
			(xy 74.706226 -191.510412) (xy 74.706704 -191.479717) (xy 74.714123 -191.418775) (xy 74.728819 -191.359169)
			(xy 74.750578 -191.301763) (xy 74.779084 -191.247392) (xy 74.796142 -191.221868) (xy 74.801613 -191.213115)
			(xy 74.805743 -191.19291) (xy 74.801621 -191.172703) (xy 74.796142 -191.163956) (xy 74.779089 -191.138429)
			(xy 74.750564 -191.084066) (xy 74.728797 -191.026662) (xy 74.714107 -190.967053) (xy 74.706708 -190.906108)
			(xy 74.706226 -190.875412) (xy 74.706704 -190.844717) (xy 74.714123 -190.783775) (xy 74.728819 -190.724169)
			(xy 74.750578 -190.666763) (xy 74.779084 -190.612392) (xy 74.796142 -190.586868) (xy 74.801613 -190.578115)
			(xy 74.805743 -190.55791) (xy 74.801621 -190.537703) (xy 74.796142 -190.528956) (xy 74.779089 -190.503429)
			(xy 74.750564 -190.449066) (xy 74.728797 -190.391662) (xy 74.714107 -190.332053) (xy 74.706708 -190.271108)
			(xy 74.706226 -190.240412) (xy 74.706304 -190.22769) (xy 74.707573 -190.202278) (xy 74.708766 -190.189612)
			(xy 74.708512 -190.189612) (xy 74.712235 -190.157891) (xy 74.726584 -190.095653) (xy 74.748601 -190.035698)
			(xy 74.77794 -189.978966) (xy 74.795634 -189.952376) (xy 74.801059 -189.943641) (xy 74.805101 -189.9235)
			(xy 74.800902 -189.90339) (xy 74.79538 -189.894718) (xy 74.778254 -189.869139) (xy 74.749633 -189.814636)
			(xy 74.727798 -189.757078) (xy 74.71307 -189.697305) (xy 74.705663 -189.636192) (xy 74.70521 -189.605412)
			(xy 74.705655 -189.57468) (xy 74.713062 -189.513663) (xy 74.727771 -189.453985) (xy 74.749566 -189.396515)
			(xy 74.77813 -189.34209) (xy 74.813045 -189.291506) (xy 74.853804 -189.2455) (xy 74.899811 -189.204742)
			(xy 74.950396 -189.169826) (xy 75.00482 -189.141264) (xy 75.062291 -189.119469) (xy 75.121969 -189.104761)
			(xy 75.182986 -189.097355) (xy 75.213718 -189.096904) (xy 75.244413 -189.097384) (xy 75.305353 -189.104806)
			(xy 75.364958 -189.119504) (xy 75.422362 -189.141265) (xy 75.476732 -189.169773) (xy 75.502262 -189.18682)
			(xy 75.511014 -189.192291) (xy 75.531218 -189.196419) (xy 75.551422 -189.192291) (xy 75.560174 -189.18682)
			(xy 75.585701 -189.169764) (xy 75.640063 -189.141232) (xy 75.697466 -189.119459) (xy 75.757075 -189.104762)
			(xy 75.818021 -189.097354) (xy 75.848718 -189.096904) (xy 75.879413 -189.097384) (xy 75.940353 -189.104806)
			(xy 75.999958 -189.119504) (xy 76.057362 -189.141265) (xy 76.111732 -189.169773) (xy 76.137262 -189.18682)
			(xy 76.146014 -189.192291) (xy 76.166218 -189.196419) (xy 76.186422 -189.192291) (xy 76.195174 -189.18682)
			(xy 76.211087 -189.176018) (xy 76.244268 -189.156564) (xy 76.261468 -189.147958) (xy 76.288646 -189.135766)
			(xy 76.30033 -189.13094) (xy 76.316332 -189.111382) (xy 76.335128 -189.015878) (xy 76.336857 -189.003457)
			(xy 76.329522 -188.979505) (xy 76.321158 -188.970158) (xy 71.4629 -184.1119) (xy 71.455739 -184.105358)
			(xy 71.43792 -184.097736) (xy 71.418546 -184.097262) (xy 71.409306 -184.100216) (xy 71.322946 -184.132474)
			(xy 71.315834 -184.135014) (xy 71.304658 -184.14365) (xy 71.295514 -184.155588) (xy 71.290434 -184.168796)
			(xy 71.289926 -184.176162) (xy 71.287216 -184.204559) (xy 71.274434 -184.260149) (xy 71.253517 -184.313217)
			(xy 71.22493 -184.362578) (xy 71.189311 -184.407131) (xy 71.147455 -184.445884) (xy 71.100295 -184.477971)
			(xy 71.048882 -184.502678) (xy 70.994364 -184.519454) (xy 70.937955 -184.527924) (xy 70.909434 -184.52846)
			(xy 70.882181 -184.527999) (xy 70.828229 -184.520246) (xy 70.77593 -184.504892) (xy 70.726348 -184.482251)
			(xy 70.680494 -184.452783) (xy 70.639301 -184.417089) (xy 70.603609 -184.375895) (xy 70.574142 -184.330039)
			(xy 70.551503 -184.280457) (xy 70.536151 -184.228158) (xy 70.5284 -184.174205) (xy 70.527926 -184.146952)
			(xy 70.528276 -184.123858) (xy 70.533876 -184.07801) (xy 70.539102 -184.055512) (xy 70.54215 -184.04332)
			(xy 70.536054 -184.018936) (xy 70.471538 -183.947308) (xy 70.463994 -183.939797) (xy 70.444575 -183.931129)
			(xy 70.433946 -183.930544) (xy 70.427088 -183.930544) (xy 70.423786 -183.931052) (xy 70.411081 -183.932623)
			(xy 70.385533 -183.934274) (xy 70.372732 -183.934354) (xy 70.37197 -183.934354) (xy 70.344719 -183.933866)
			(xy 70.290772 -183.926106) (xy 70.238478 -183.910749) (xy 70.188902 -183.888107) (xy 70.143052 -183.858641)
			(xy 70.101862 -183.82295) (xy 70.066169 -183.781761) (xy 70.036701 -183.735912) (xy 70.014056 -183.686337)
			(xy 69.998697 -183.634044) (xy 69.990935 -183.580097) (xy 69.990462 -183.552846) (xy 69.990922 -183.526324)
			(xy 69.998279 -183.473793) (xy 70.012844 -183.422788) (xy 70.034336 -183.374293) (xy 70.062339 -183.329243)
			(xy 70.096315 -183.288508) (xy 70.135606 -183.252874) (xy 70.179457 -183.223027) (xy 70.22702 -183.199545)
			(xy 70.277377 -183.182879) (xy 70.30339 -183.177688) (xy 70.311518 -183.176164) (xy 70.325742 -183.168036)
			(xy 70.331584 -183.16194) (xy 70.335296 -183.157706) (xy 70.340933 -183.147962) (xy 70.34276 -183.142636)
			(xy 70.36943 -183.056784) (xy 70.371739 -183.048073) (xy 70.370772 -183.03009) (xy 70.363664 -183.013543)
			(xy 70.357746 -183.006746) (xy 70.357238 -183.006238) (xy 68.216526 -180.865526) (xy 68.209274 -180.858956)
			(xy 68.19126 -180.85136) (xy 68.171712 -180.851018) (xy 68.162424 -180.854096) (xy 68.061586 -180.892958)
			(xy 68.04406 -180.917088) (xy 68.043298 -180.932582) (xy 68.041071 -180.966839) (xy 68.028556 -181.034338)
			(xy 68.007082 -181.099543) (xy 67.977039 -181.16127) (xy 67.958462 -181.190138) (xy 67.958462 -181.190392)
			(xy 67.954398 -181.196488) (xy 67.946016 -181.223412) (xy 67.949318 -181.246272) (xy 67.955922 -181.256178)
			(xy 67.97279 -181.281609) (xy 68.000995 -181.335726) (xy 68.022517 -181.39283) (xy 68.037048 -181.452101)
			(xy 68.044378 -181.512685) (xy 68.044822 -181.543198) (xy 68.044344 -181.573893) (xy 68.036924 -181.634835)
			(xy 68.022228 -181.694441) (xy 68.00047 -181.751847) (xy 67.971965 -181.806219) (xy 67.954906 -181.831742)
			(xy 67.949433 -181.840494) (xy 67.945303 -181.860698) (xy 67.949431 -181.880903) (xy 67.954906 -181.889654)
			(xy 67.971957 -181.915182) (xy 68.000479 -181.969546) (xy 68.022242 -182.02695) (xy 68.036929 -182.086559)
			(xy 68.044327 -182.147502) (xy 68.044822 -182.178198) (xy 68.044344 -182.208893) (xy 68.036924 -182.269835)
			(xy 68.022228 -182.329441) (xy 68.00047 -182.386847) (xy 67.971965 -182.441219) (xy 67.954906 -182.466742)
			(xy 67.949433 -182.475494) (xy 67.945303 -182.495698) (xy 67.949431 -182.515903) (xy 67.954906 -182.524654)
			(xy 67.971957 -182.550182) (xy 68.000479 -182.604546) (xy 68.022242 -182.66195) (xy 68.036929 -182.721559)
			(xy 68.044327 -182.782502) (xy 68.044822 -182.813198) (xy 68.044344 -182.843893) (xy 68.036924 -182.904835)
			(xy 68.022228 -182.964441) (xy 68.00047 -183.021847) (xy 67.971965 -183.076219) (xy 67.954906 -183.101742)
			(xy 67.949433 -183.110494) (xy 67.945303 -183.130698) (xy 67.949431 -183.150903) (xy 67.954906 -183.159654)
			(xy 67.971957 -183.185182) (xy 68.000479 -183.239546) (xy 68.022242 -183.29695) (xy 68.036929 -183.356559)
			(xy 68.044327 -183.417502) (xy 68.044822 -183.448198) (xy 68.044305 -183.481365) (xy 68.035717 -183.547141)
			(xy 68.018648 -183.611241) (xy 67.993387 -183.672577) (xy 67.960364 -183.730107) (xy 67.940682 -183.756808)
			(xy 67.934743 -183.765337) (xy 67.92965 -183.785465) (xy 67.932968 -183.80596) (xy 67.938142 -183.814974)
			(xy 67.9534 -183.839584) (xy 67.978868 -183.89159) (xy 67.998273 -183.94615) (xy 68.011364 -184.002558)
			(xy 68.017973 -184.060087) (xy 68.018406 -184.08904) (xy 68.017925 -184.119735) (xy 68.0105 -184.180674)
			(xy 67.9958 -184.240277) (xy 67.974038 -184.29768) (xy 67.945529 -184.352048) (xy 67.92849 -184.377584)
			(xy 67.923027 -184.386336) (xy 67.918914 -184.406533) (xy 67.923053 -184.426726) (xy 67.92849 -184.435496)
			(xy 67.945545 -184.461023) (xy 67.974073 -184.515386) (xy 67.995844 -184.572789) (xy 68.010538 -184.632398)
			(xy 68.017943 -184.693343) (xy 68.018406 -184.72404) (xy 68.017925 -184.754735) (xy 68.0105 -184.815674)
			(xy 67.9958 -184.875277) (xy 67.974038 -184.93268) (xy 67.945529 -184.987048) (xy 67.92849 -185.012584)
			(xy 67.923027 -185.021336) (xy 67.918914 -185.041533) (xy 67.923053 -185.061726) (xy 67.92849 -185.070496)
			(xy 67.945545 -185.096023) (xy 67.974073 -185.150386) (xy 67.995844 -185.207789) (xy 68.010538 -185.267398)
			(xy 68.017943 -185.328343) (xy 68.018406 -185.35904) (xy 68.017925 -185.389735) (xy 68.0105 -185.450674)
			(xy 67.9958 -185.510277) (xy 67.974038 -185.56768) (xy 67.945529 -185.622048) (xy 67.92849 -185.647584)
			(xy 67.923027 -185.656336) (xy 67.918914 -185.676533) (xy 67.923053 -185.696726) (xy 67.92849 -185.705496)
			(xy 67.945545 -185.731023) (xy 67.974073 -185.785386) (xy 67.995844 -185.842789) (xy 68.010538 -185.902398)
			(xy 68.017943 -185.963343) (xy 68.018406 -185.99404) (xy 68.017925 -186.024735) (xy 68.0105 -186.085674)
			(xy 67.9958 -186.145277) (xy 67.974038 -186.20268) (xy 67.945529 -186.257048) (xy 67.92849 -186.282584)
			(xy 67.923027 -186.291336) (xy 67.918914 -186.311533) (xy 67.923053 -186.331726) (xy 67.92849 -186.340496)
			(xy 67.945545 -186.366023) (xy 67.974073 -186.420386) (xy 67.995844 -186.477789) (xy 68.010538 -186.537398)
			(xy 68.017943 -186.598343) (xy 68.018406 -186.62904) (xy 68.017925 -186.659735) (xy 68.0105 -186.720674)
			(xy 67.9958 -186.780277) (xy 67.974038 -186.83768) (xy 67.945529 -186.892048) (xy 67.92849 -186.917584)
			(xy 67.923027 -186.926336) (xy 67.918914 -186.946533) (xy 67.923053 -186.966726) (xy 67.92849 -186.975496)
			(xy 67.945545 -187.001023) (xy 67.974073 -187.055386) (xy 67.995844 -187.112789) (xy 68.010538 -187.172398)
			(xy 68.017943 -187.233343) (xy 68.018406 -187.26404) (xy 68.01794 -187.294769) (xy 68.010527 -187.35578)
			(xy 67.995815 -187.415452) (xy 67.974018 -187.472915) (xy 67.945454 -187.527333) (xy 67.910538 -187.577911)
			(xy 67.869782 -187.623911) (xy 67.823777 -187.664664) (xy 67.773197 -187.699575) (xy 67.718777 -187.728135)
			(xy 67.661311 -187.749928) (xy 67.601638 -187.764635) (xy 67.540627 -187.772042) (xy 67.509898 -187.772548)
			(xy 67.479203 -187.772069) (xy 67.418263 -187.764648) (xy 67.358657 -187.74995) (xy 67.301253 -187.728189)
			(xy 67.246884 -187.69968) (xy 67.221354 -187.682632) (xy 67.212602 -187.677161) (xy 67.192398 -187.673033)
			(xy 67.172194 -187.677161) (xy 67.163442 -187.682632) (xy 67.137916 -187.69969) (xy 67.083555 -187.728226)
			(xy 67.026152 -187.750003) (xy 66.966542 -187.764704) (xy 66.905596 -187.772114) (xy 66.874898 -187.772548)
			(xy 66.844166 -187.772084) (xy 66.783151 -187.764676) (xy 66.723473 -187.749967) (xy 66.666003 -187.728173)
			(xy 66.611579 -187.69961) (xy 66.560995 -187.664696) (xy 66.514987 -187.62394) (xy 66.474227 -187.577935)
			(xy 66.439309 -187.527353) (xy 66.410743 -187.472932) (xy 66.388944 -187.415463) (xy 66.374231 -187.355787)
			(xy 66.366818 -187.294772) (xy 66.36639 -187.26404) (xy 66.366872 -187.233346) (xy 66.374299 -187.172408)
			(xy 66.389001 -187.112805) (xy 66.410765 -187.055404) (xy 66.439275 -187.001037) (xy 66.456306 -186.975496)
			(xy 66.461786 -186.966744) (xy 66.465929 -186.946533) (xy 66.461812 -186.926318) (xy 66.456306 -186.917584)
			(xy 66.439252 -186.892057) (xy 66.410726 -186.837694) (xy 66.388958 -186.78029) (xy 66.374266 -186.720681)
			(xy 66.366864 -186.659736) (xy 66.36639 -186.62904) (xy 66.366872 -186.598346) (xy 66.374299 -186.537408)
			(xy 66.389001 -186.477805) (xy 66.410765 -186.420404) (xy 66.439275 -186.366037) (xy 66.456306 -186.340496)
			(xy 66.461786 -186.331744) (xy 66.465929 -186.311533) (xy 66.461812 -186.291318) (xy 66.456306 -186.282584)
			(xy 66.439252 -186.257057) (xy 66.410726 -186.202694) (xy 66.388958 -186.14529) (xy 66.374266 -186.085681)
			(xy 66.366864 -186.024736) (xy 66.36639 -185.99404) (xy 66.366872 -185.963346) (xy 66.374299 -185.902408)
			(xy 66.389001 -185.842805) (xy 66.410765 -185.785404) (xy 66.439275 -185.731037) (xy 66.456306 -185.705496)
			(xy 66.461786 -185.696744) (xy 66.465929 -185.676533) (xy 66.461812 -185.656318) (xy 66.456306 -185.647584)
			(xy 66.439252 -185.622057) (xy 66.410726 -185.567694) (xy 66.388958 -185.51029) (xy 66.374266 -185.450681)
			(xy 66.366864 -185.389736) (xy 66.36639 -185.35904) (xy 66.366872 -185.328346) (xy 66.374299 -185.267408)
			(xy 66.389001 -185.207805) (xy 66.410765 -185.150404) (xy 66.439275 -185.096037) (xy 66.456306 -185.070496)
			(xy 66.461786 -185.061744) (xy 66.465929 -185.041533) (xy 66.461812 -185.021318) (xy 66.456306 -185.012584)
			(xy 66.439252 -184.987057) (xy 66.410726 -184.932694) (xy 66.388958 -184.87529) (xy 66.374266 -184.815681)
			(xy 66.366864 -184.754736) (xy 66.36639 -184.72404) (xy 66.366872 -184.693346) (xy 66.374299 -184.632408)
			(xy 66.389001 -184.572805) (xy 66.410765 -184.515404) (xy 66.439275 -184.461037) (xy 66.456306 -184.435496)
			(xy 66.461786 -184.426744) (xy 66.465929 -184.406533) (xy 66.461812 -184.386318) (xy 66.456306 -184.377584)
			(xy 66.439252 -184.352057) (xy 66.410726 -184.297694) (xy 66.388958 -184.24029) (xy 66.374266 -184.180681)
			(xy 66.366864 -184.119736) (xy 66.36639 -184.08904) (xy 66.366928 -184.0559) (xy 66.375546 -183.990182)
			(xy 66.392627 -183.92614) (xy 66.417883 -183.86486) (xy 66.450885 -183.80738) (xy 66.47053 -183.780684)
			(xy 66.475356 -183.774334) (xy 66.48196 -183.755284) (xy 66.47942 -183.73217) (xy 66.47307 -183.722264)
			(xy 66.457812 -183.697653) (xy 66.432345 -183.645647) (xy 66.41294 -183.591088) (xy 66.399847 -183.53468)
			(xy 66.393235 -183.477151) (xy 66.392806 -183.448198) (xy 66.393285 -183.417503) (xy 66.400705 -183.356562)
			(xy 66.415402 -183.296956) (xy 66.437162 -183.239551) (xy 66.465668 -183.18518) (xy 66.482722 -183.159654)
			(xy 66.488192 -183.150902) (xy 66.492318 -183.130698) (xy 66.488191 -183.110495) (xy 66.482722 -183.101742)
			(xy 66.465665 -183.076216) (xy 66.437132 -183.021854) (xy 66.415357 -182.96445) (xy 66.400657 -182.904841)
			(xy 66.393248 -182.843895) (xy 66.392806 -182.813198) (xy 66.393285 -182.782503) (xy 66.400705 -182.721562)
			(xy 66.415402 -182.661956) (xy 66.437162 -182.604551) (xy 66.465668 -182.55018) (xy 66.482722 -182.524654)
			(xy 66.488192 -182.515902) (xy 66.492318 -182.495698) (xy 66.488191 -182.475495) (xy 66.482722 -182.466742)
			(xy 66.465665 -182.441216) (xy 66.437132 -182.386854) (xy 66.415357 -182.32945) (xy 66.400657 -182.269841)
			(xy 66.393248 -182.208895) (xy 66.392806 -182.178198) (xy 66.393285 -182.147503) (xy 66.400705 -182.086562)
			(xy 66.415402 -182.026956) (xy 66.437162 -181.969551) (xy 66.465668 -181.91518) (xy 66.482722 -181.889654)
			(xy 66.488192 -181.880902) (xy 66.492318 -181.860698) (xy 66.488191 -181.840495) (xy 66.482722 -181.831742)
			(xy 66.465665 -181.806216) (xy 66.437132 -181.751854) (xy 66.415357 -181.69445) (xy 66.400657 -181.634841)
			(xy 66.393248 -181.573895) (xy 66.392806 -181.543198) (xy 66.392884 -181.530476) (xy 66.394154 -181.505064)
			(xy 66.395346 -181.492398) (xy 66.395092 -181.492398) (xy 66.398816 -181.460677) (xy 66.413165 -181.39844)
			(xy 66.435183 -181.338485) (xy 66.464522 -181.281753) (xy 66.482214 -181.255162) (xy 66.487638 -181.246428)
			(xy 66.491677 -181.226288) (xy 66.487472 -181.206182) (xy 66.48196 -181.197504) (xy 66.46483 -181.171926)
			(xy 66.436201 -181.117424) (xy 66.414358 -181.059867) (xy 66.39962 -181.000094) (xy 66.392203 -180.93898)
			(xy 66.39179 -180.908198) (xy 66.392254 -180.877467) (xy 66.399663 -180.816453) (xy 66.414372 -180.756777)
			(xy 66.436167 -180.69931) (xy 66.464729 -180.644888) (xy 66.499644 -180.594306) (xy 66.540401 -180.548301)
			(xy 66.586406 -180.507544) (xy 66.636988 -180.472629) (xy 66.69141 -180.444067) (xy 66.748877 -180.422272)
			(xy 66.808553 -180.407563) (xy 66.869567 -180.400154) (xy 66.900298 -180.39969) (xy 66.930993 -180.400169)
			(xy 66.991934 -180.407588) (xy 67.051541 -180.422284) (xy 67.108947 -180.444043) (xy 67.163319 -180.472548)
			(xy 67.188842 -180.489606) (xy 67.197594 -180.495077) (xy 67.217798 -180.499205) (xy 67.238002 -180.495077)
			(xy 67.246754 -180.489606) (xy 67.276179 -180.47005) (xy 67.339328 -180.438371) (xy 67.406251 -180.415726)
			(xy 67.475662 -180.402551) (xy 67.510914 -180.400198) (xy 67.526408 -180.399436) (xy 67.550538 -180.382164)
			(xy 67.5894 -180.281072) (xy 67.592509 -180.271785) (xy 67.592198 -180.252221) (xy 67.584573 -180.234202)
			(xy 67.57797 -180.22697) (xy 59.585098 -172.234098) (xy 59.54776 -172.23105) (xy 59.53252 -172.242226)
			(xy 59.507863 -172.259498) (xy 59.454258 -172.286893) (xy 59.397025 -172.305556) (xy 59.337575 -172.315026)
			(xy 59.307476 -172.315632) (xy 59.307222 -172.315632) (xy 59.278305 -172.315099) (xy 59.221134 -172.306374)
			(xy 59.165934 -172.28912) (xy 59.113971 -172.263733) (xy 59.066434 -172.230794) (xy 59.024414 -172.191058)
			(xy 59.006232 -172.168566) (xy 58.99864 -172.159739) (xy 58.977731 -172.149558) (xy 58.9661 -172.149008)
			(xy 58.886344 -172.149008) (xy 58.87472 -172.149576) (xy 58.853818 -172.159758) (xy 58.846212 -172.168566)
			(xy 58.829459 -172.189349) (xy 58.791105 -172.226479) (xy 58.747951 -172.257901) (xy 58.700837 -172.283)
			(xy 58.650685 -172.301286) (xy 58.598474 -172.312403) (xy 58.545222 -172.316133) (xy 58.49197 -172.312403)
			(xy 58.439759 -172.301286) (xy 58.389607 -172.283) (xy 58.342493 -172.257901) (xy 58.299339 -172.226479)
			(xy 58.260985 -172.189349) (xy 58.244232 -172.168566) (xy 58.23664 -172.159739) (xy 58.215731 -172.149558)
			(xy 58.2041 -172.149008) (xy 58.124344 -172.149008) (xy 58.11272 -172.149576) (xy 58.091818 -172.159758)
			(xy 58.084212 -172.168566) (xy 58.067459 -172.189349) (xy 58.029105 -172.226479) (xy 57.985951 -172.257901)
			(xy 57.938837 -172.283) (xy 57.888685 -172.301286) (xy 57.836474 -172.312403) (xy 57.783222 -172.316133)
			(xy 57.72997 -172.312403) (xy 57.677759 -172.301286) (xy 57.627607 -172.283) (xy 57.580493 -172.257901)
			(xy 57.537339 -172.226479) (xy 57.498985 -172.189349) (xy 57.482232 -172.168566) (xy 57.47464 -172.159739)
			(xy 57.453731 -172.149558) (xy 57.4421 -172.149008) (xy 57.362344 -172.149008) (xy 57.35072 -172.149576)
			(xy 57.329818 -172.159758) (xy 57.322212 -172.168566) (xy 57.305459 -172.189349) (xy 57.267105 -172.226479)
			(xy 57.223951 -172.257901) (xy 57.176837 -172.283) (xy 57.126685 -172.301286) (xy 57.074474 -172.312403)
			(xy 57.021222 -172.316133) (xy 56.96797 -172.312403) (xy 56.915759 -172.301286) (xy 56.865607 -172.283)
			(xy 56.818493 -172.257901) (xy 56.775339 -172.226479) (xy 56.736985 -172.189349) (xy 56.720232 -172.168566)
			(xy 56.71264 -172.159739) (xy 56.691731 -172.149558) (xy 56.6801 -172.149008) (xy 56.600344 -172.149008)
			(xy 56.58872 -172.149576) (xy 56.567818 -172.159758) (xy 56.560212 -172.168566) (xy 56.542022 -172.19105)
			(xy 56.500005 -172.230788) (xy 56.452471 -172.263728) (xy 56.400508 -172.289114) (xy 56.345309 -172.306364)
			(xy 56.288138 -172.315083) (xy 56.259222 -172.315632) (xy 56.231966 -172.315171) (xy 56.17801 -172.307416)
			(xy 56.125706 -172.292061) (xy 56.07612 -172.269418) (xy 56.030261 -172.239949) (xy 55.989063 -172.204253)
			(xy 55.953365 -172.163057) (xy 55.923893 -172.1172) (xy 55.901247 -172.067615) (xy 55.885889 -172.015312)
			(xy 55.878131 -171.961356) (xy 55.878131 -171.906844) (xy 55.885889 -171.852888) (xy 55.901247 -171.800585)
			(xy 55.923893 -171.751) (xy 55.953365 -171.705143) (xy 55.989063 -171.663947) (xy 56.030261 -171.628251)
			(xy 56.07612 -171.598782) (xy 56.125706 -171.576139) (xy 56.17801 -171.560784) (xy 56.231966 -171.553029)
			(xy 56.259222 -171.552616) (xy 56.288138 -171.553152) (xy 56.345307 -171.561882) (xy 56.400504 -171.579139)
			(xy 56.452464 -171.604527) (xy 56.499999 -171.637466) (xy 56.542019 -171.677201) (xy 56.560212 -171.699682)
			(xy 56.567796 -171.708526) (xy 56.588707 -171.71874) (xy 56.600344 -171.71924) (xy 56.6801 -171.71924)
			(xy 56.691721 -171.718665) (xy 56.712615 -171.708479) (xy 56.720232 -171.699682) (xy 56.736985 -171.678899)
			(xy 56.775339 -171.641769) (xy 56.818493 -171.610347) (xy 56.865607 -171.585248) (xy 56.915759 -171.566962)
			(xy 56.96797 -171.555845) (xy 57.021222 -171.552115) (xy 57.074474 -171.555845) (xy 57.126685 -171.566962)
			(xy 57.176837 -171.585248) (xy 57.223951 -171.610347) (xy 57.267105 -171.641769) (xy 57.305459 -171.678899)
			(xy 57.322212 -171.699682) (xy 57.329796 -171.708526) (xy 57.350707 -171.71874) (xy 57.362344 -171.71924)
			(xy 57.4421 -171.71924) (xy 57.453721 -171.718665) (xy 57.474615 -171.708479) (xy 57.482232 -171.699682)
			(xy 57.498985 -171.678899) (xy 57.537339 -171.641769) (xy 57.580493 -171.610347) (xy 57.627607 -171.585248)
			(xy 57.677759 -171.566962) (xy 57.72997 -171.555845) (xy 57.783222 -171.552115) (xy 57.836474 -171.555845)
			(xy 57.888685 -171.566962) (xy 57.938837 -171.585248) (xy 57.985951 -171.610347) (xy 58.029105 -171.641769)
			(xy 58.067459 -171.678899) (xy 58.084212 -171.699682) (xy 58.091796 -171.708526) (xy 58.112707 -171.71874)
			(xy 58.124344 -171.71924) (xy 58.2041 -171.71924) (xy 58.215721 -171.718665) (xy 58.236615 -171.708479)
			(xy 58.244232 -171.699682) (xy 58.262422 -171.677197) (xy 58.30444 -171.637458) (xy 58.351974 -171.604516)
			(xy 58.403935 -171.579126) (xy 58.459134 -171.56187) (xy 58.516305 -171.553144) (xy 58.545222 -171.552616)
			(xy 58.571825 -171.553079) (xy 58.624514 -171.560471) (xy 58.675665 -171.57511) (xy 58.724288 -171.596711)
			(xy 58.76944 -171.624857) (xy 58.810244 -171.659) (xy 58.845911 -171.69848) (xy 58.861198 -171.720256)
			(xy 58.864754 -171.72559) (xy 58.87339 -171.733464) (xy 58.90006 -171.747688) (xy 58.905688 -171.750515)
			(xy 58.917895 -171.753602) (xy 58.92419 -171.753784) (xy 58.928508 -171.753784) (xy 58.934803 -171.753595)
			(xy 58.947007 -171.750508) (xy 58.952638 -171.747688) (xy 58.978546 -171.733718) (xy 58.98769 -171.72559)
			(xy 58.991246 -171.720256) (xy 58.994802 -171.715176) (xy 58.99912 -171.70908) (xy 59.009026 -171.678854)
			(xy 59.008264 -171.668694) (xy 59.00166 -171.576746) (xy 59.00166 -157.539182) (xy 59.001232 -157.529114)
			(xy 58.993509 -157.510518) (xy 58.986674 -157.503114) (xy 58.46699 -156.98343) (xy 58.460145 -156.976032)
			(xy 58.452422 -156.957433) (xy 58.452004 -156.947362) (xy 58.452004 -148.113496) (xy 58.455814 -148.109686)
			(xy 58.455814 -145.238724) (xy 58.455378 -145.22866) (xy 58.447645 -145.210074) (xy 58.440828 -145.202656)
			(xy 57.93105 -144.692878) (xy 57.923653 -144.686031) (xy 57.905053 -144.678302) (xy 57.894982 -144.677892)
			(xy 51.253898 -144.677892) (xy 51.243828 -144.678315) (xy 51.225223 -144.686029) (xy 51.21783 -144.692878)
			(xy 48.347122 -147.563586) (xy 48.343394 -147.567111) (xy 48.334823 -147.572749) (xy 48.330104 -147.574762)
			(xy 48.321468 -147.578318) (xy 46.22292 -149.676866) (xy 46.215554 -149.683978) (xy 46.207934 -149.702774)
			(xy 46.207934 -151.201454) (xy 50.610451 -151.201454) (xy 50.610451 -151.146946) (xy 50.618209 -151.092993)
			(xy 50.633566 -151.040694) (xy 50.65621 -150.991112) (xy 50.68568 -150.945258) (xy 50.721375 -150.904064)
			(xy 50.76257 -150.86837) (xy 50.808426 -150.838902) (xy 50.858009 -150.81626) (xy 50.910309 -150.800905)
			(xy 50.964262 -150.79315) (xy 50.991516 -150.792688) (xy 51.020432 -150.793233) (xy 51.077604 -150.801952)
			(xy 51.132803 -150.819202) (xy 51.184766 -150.844589) (xy 51.2323 -150.877529) (xy 51.274316 -150.917269)
			(xy 51.292506 -150.939754) (xy 51.30006 -150.948523) (xy 51.320825 -150.958701) (xy 51.332384 -150.959312)
			(xy 51.412648 -150.959312) (xy 51.424211 -150.958708) (xy 51.444983 -150.948537) (xy 51.452526 -150.939754)
			(xy 51.470691 -150.917248) (xy 51.512717 -150.877517) (xy 51.560258 -150.844582) (xy 51.612224 -150.819198)
			(xy 51.667426 -150.801946) (xy 51.724599 -150.793221) (xy 51.753516 -150.792688) (xy 51.780766 -150.793183)
			(xy 51.834712 -150.800941) (xy 51.887004 -150.816297) (xy 51.936579 -150.838939) (xy 51.982427 -150.868406)
			(xy 52.023614 -150.904097) (xy 52.059304 -150.945286) (xy 52.088768 -150.991135) (xy 52.111408 -151.040711)
			(xy 52.126762 -151.093004) (xy 52.134518 -151.14695) (xy 52.134518 -151.20145) (xy 52.126762 -151.255396)
			(xy 52.111408 -151.307689) (xy 52.088768 -151.357265) (xy 52.059304 -151.403114) (xy 52.023614 -151.444303)
			(xy 51.982427 -151.479994) (xy 51.936579 -151.509461) (xy 51.887004 -151.532103) (xy 51.834712 -151.547459)
			(xy 51.780766 -151.555217) (xy 51.753516 -151.555704) (xy 51.724598 -151.555211) (xy 51.667424 -151.546482)
			(xy 51.612223 -151.529221) (xy 51.56026 -151.503825) (xy 51.512727 -151.470875) (xy 51.470714 -151.431127)
			(xy 51.452526 -151.408638) (xy 51.444959 -151.399882) (xy 51.424204 -151.389698) (xy 51.412648 -151.38908)
			(xy 51.332384 -151.38908) (xy 51.320816 -151.389648) (xy 51.300046 -151.399845) (xy 51.292506 -151.408638)
			(xy 51.274321 -151.431127) (xy 51.232299 -151.47086) (xy 51.184762 -151.503797) (xy 51.1328 -151.529184)
			(xy 51.077602 -151.54644) (xy 51.020432 -151.555169) (xy 50.991516 -151.555704) (xy 50.964262 -151.55525)
			(xy 50.910309 -151.547495) (xy 50.858009 -151.53214) (xy 50.808426 -151.509498) (xy 50.76257 -151.48003)
			(xy 50.721375 -151.444336) (xy 50.68568 -151.403142) (xy 50.65621 -151.357288) (xy 50.633566 -151.307706)
			(xy 50.618209 -151.255407) (xy 50.610451 -151.201454) (xy 46.207934 -151.201454) (xy 46.207934 -153.258854)
			(xy 50.610451 -153.258854) (xy 50.610451 -153.204346) (xy 50.618209 -153.150393) (xy 50.633566 -153.098094)
			(xy 50.65621 -153.048512) (xy 50.68568 -153.002658) (xy 50.721375 -152.961464) (xy 50.76257 -152.92577)
			(xy 50.808426 -152.896302) (xy 50.858009 -152.87366) (xy 50.910309 -152.858305) (xy 50.964262 -152.85055)
			(xy 50.991516 -152.850088) (xy 51.020432 -152.850633) (xy 51.077604 -152.859352) (xy 51.132803 -152.876602)
			(xy 51.184766 -152.901989) (xy 51.2323 -152.934929) (xy 51.274316 -152.974669) (xy 51.292506 -152.997154)
			(xy 51.30006 -153.005923) (xy 51.320825 -153.016101) (xy 51.332384 -153.016712) (xy 51.412648 -153.016712)
			(xy 51.424211 -153.016108) (xy 51.444983 -153.005937) (xy 51.452526 -152.997154) (xy 51.470691 -152.974648)
			(xy 51.512717 -152.934917) (xy 51.560258 -152.901982) (xy 51.612224 -152.876598) (xy 51.667426 -152.859346)
			(xy 51.724599 -152.850621) (xy 51.753516 -152.850088) (xy 51.780766 -152.850583) (xy 51.834712 -152.858341)
			(xy 51.887004 -152.873697) (xy 51.936579 -152.896339) (xy 51.982427 -152.925806) (xy 52.023614 -152.961497)
			(xy 52.059304 -153.002686) (xy 52.088768 -153.048535) (xy 52.111408 -153.098111) (xy 52.126762 -153.150404)
			(xy 52.134518 -153.20435) (xy 52.134518 -153.25885) (xy 52.126762 -153.312796) (xy 52.111408 -153.365089)
			(xy 52.088768 -153.414665) (xy 52.059304 -153.460514) (xy 52.023614 -153.501703) (xy 51.982427 -153.537394)
			(xy 51.936579 -153.566861) (xy 51.887004 -153.589503) (xy 51.834712 -153.604859) (xy 51.780766 -153.612617)
			(xy 51.753516 -153.613104) (xy 51.724598 -153.612611) (xy 51.667424 -153.603882) (xy 51.612223 -153.586621)
			(xy 51.56026 -153.561225) (xy 51.512727 -153.528275) (xy 51.470714 -153.488527) (xy 51.452526 -153.466038)
			(xy 51.444959 -153.457282) (xy 51.424204 -153.447098) (xy 51.412648 -153.44648) (xy 51.332384 -153.44648)
			(xy 51.320816 -153.447048) (xy 51.300046 -153.457245) (xy 51.292506 -153.466038) (xy 51.274321 -153.488527)
			(xy 51.232299 -153.52826) (xy 51.184762 -153.561197) (xy 51.1328 -153.586584) (xy 51.077602 -153.60384)
			(xy 51.020432 -153.612569) (xy 50.991516 -153.613104) (xy 50.964262 -153.61265) (xy 50.910309 -153.604895)
			(xy 50.858009 -153.58954) (xy 50.808426 -153.566898) (xy 50.76257 -153.53743) (xy 50.721375 -153.501736)
			(xy 50.68568 -153.460542) (xy 50.65621 -153.414688) (xy 50.633566 -153.365106) (xy 50.618209 -153.312807)
			(xy 50.610451 -153.258854) (xy 46.207934 -153.258854) (xy 46.207934 -158.113051) (xy 50.521868 -158.113051)
			(xy 50.521868 -158.058549) (xy 50.529624 -158.004603) (xy 50.544978 -157.952309) (xy 50.567617 -157.902733)
			(xy 50.597081 -157.856882) (xy 50.632771 -157.815692) (xy 50.673958 -157.779999) (xy 50.719806 -157.750532)
			(xy 50.769381 -157.727888) (xy 50.821674 -157.71253) (xy 50.875619 -157.70477) (xy 50.90287 -157.704282)
			(xy 50.930128 -157.704768) (xy 50.984087 -157.712532) (xy 51.036394 -157.727892) (xy 51.085985 -157.750535)
			(xy 51.13185 -157.780001) (xy 51.173059 -157.815691) (xy 51.208772 -157.85688) (xy 51.223926 -157.879542)
			(xy 51.228744 -157.886536) (xy 51.242068 -157.897053) (xy 51.25811 -157.902603) (xy 51.266598 -157.90291)
			(xy 51.351942 -157.90291) (xy 51.360422 -157.902595) (xy 51.376436 -157.897002) (xy 51.38976 -157.886504)
			(xy 51.394614 -157.879542) (xy 51.409767 -157.85688) (xy 51.44548 -157.815693) (xy 51.486688 -157.780005)
			(xy 51.532555 -157.750542) (xy 51.582146 -157.727905) (xy 51.634454 -157.712552) (xy 51.688413 -157.704797)
			(xy 51.742927 -157.704797) (xy 51.796886 -157.712552) (xy 51.849194 -157.727905) (xy 51.898785 -157.750542)
			(xy 51.944652 -157.780005) (xy 51.98586 -157.815693) (xy 52.021573 -157.85688) (xy 52.036726 -157.879542)
			(xy 52.041544 -157.886536) (xy 52.054868 -157.897053) (xy 52.07091 -157.902603) (xy 52.079398 -157.90291)
			(xy 52.164742 -157.90291) (xy 52.173222 -157.902595) (xy 52.189236 -157.897002) (xy 52.20256 -157.886504)
			(xy 52.207414 -157.879542) (xy 52.222528 -157.856849) (xy 52.258239 -157.81565) (xy 52.299451 -157.779952)
			(xy 52.345323 -157.750482) (xy 52.394923 -157.727841) (xy 52.447239 -157.71249) (xy 52.501209 -157.70474)
			(xy 52.52847 -157.704282) (xy 52.555724 -157.704763) (xy 52.609676 -157.712517) (xy 52.661976 -157.72787)
			(xy 52.711559 -157.75051) (xy 52.757415 -157.779976) (xy 52.79861 -157.815669) (xy 52.834306 -157.856861)
			(xy 52.863776 -157.902715) (xy 52.88642 -157.952295) (xy 52.901777 -158.004594) (xy 52.909535 -158.058547)
			(xy 52.909535 -158.113054) (xy 52.901777 -158.167006) (xy 52.88642 -158.219305) (xy 52.863776 -158.268885)
			(xy 52.834306 -158.314739) (xy 52.79861 -158.355931) (xy 52.757415 -158.391624) (xy 52.711559 -158.42109)
			(xy 52.661976 -158.44373) (xy 52.609676 -158.459083) (xy 52.555724 -158.466837) (xy 52.52847 -158.467298)
			(xy 52.501213 -158.466822) (xy 52.447254 -158.459052) (xy 52.394948 -158.443688) (xy 52.345359 -158.421042)
			(xy 52.299494 -158.391575) (xy 52.258285 -158.355886) (xy 52.22257 -158.314699) (xy 52.207414 -158.292038)
			(xy 52.202578 -158.285058) (xy 52.189261 -158.27454) (xy 52.173227 -158.268982) (xy 52.164742 -158.26867)
			(xy 52.079398 -158.26867) (xy 52.070921 -158.269021) (xy 52.05491 -158.274599) (xy 52.041583 -158.285082)
			(xy 52.036726 -158.292038) (xy 52.021573 -158.3147) (xy 51.98586 -158.355887) (xy 51.944652 -158.391575)
			(xy 51.898785 -158.421038) (xy 51.849194 -158.443675) (xy 51.796886 -158.459028) (xy 51.742927 -158.466783)
			(xy 51.688413 -158.466783) (xy 51.634454 -158.459028) (xy 51.582146 -158.443675) (xy 51.532555 -158.421038)
			(xy 51.486688 -158.391575) (xy 51.44548 -158.355887) (xy 51.409767 -158.3147) (xy 51.394614 -158.292038)
			(xy 51.389778 -158.285058) (xy 51.376461 -158.27454) (xy 51.360427 -158.268982) (xy 51.351942 -158.26867)
			(xy 51.266598 -158.26867) (xy 51.258121 -158.269021) (xy 51.24211 -158.274599) (xy 51.228783 -158.285082)
			(xy 51.223926 -158.292038) (xy 51.20878 -158.314708) (xy 51.173074 -158.355909) (xy 51.131869 -158.391609)
			(xy 51.086002 -158.421081) (xy 51.036407 -158.443726) (xy 50.984095 -158.459082) (xy 50.93013 -158.466837)
			(xy 50.90287 -158.467298) (xy 50.875619 -158.46683) (xy 50.821674 -158.45907) (xy 50.769381 -158.443712)
			(xy 50.719806 -158.421068) (xy 50.673958 -158.391601) (xy 50.632771 -158.355908) (xy 50.597081 -158.314718)
			(xy 50.567617 -158.268867) (xy 50.544978 -158.219291) (xy 50.529624 -158.166997) (xy 50.521868 -158.113051)
			(xy 46.207934 -158.113051) (xy 46.207934 -160.653051) (xy 50.521868 -160.653051) (xy 50.521868 -160.598549)
			(xy 50.529624 -160.544603) (xy 50.544978 -160.492309) (xy 50.567617 -160.442733) (xy 50.597081 -160.396882)
			(xy 50.632771 -160.355692) (xy 50.673958 -160.319999) (xy 50.719806 -160.290532) (xy 50.769381 -160.267888)
			(xy 50.821674 -160.25253) (xy 50.875619 -160.24477) (xy 50.90287 -160.244282) (xy 50.930128 -160.244768)
			(xy 50.984087 -160.252532) (xy 51.036394 -160.267892) (xy 51.085985 -160.290535) (xy 51.13185 -160.320001)
			(xy 51.173059 -160.355691) (xy 51.208772 -160.39688) (xy 51.223926 -160.419542) (xy 51.228744 -160.426536)
			(xy 51.242068 -160.437053) (xy 51.25811 -160.442603) (xy 51.266598 -160.44291) (xy 51.351942 -160.44291)
			(xy 51.360422 -160.442595) (xy 51.376436 -160.437002) (xy 51.38976 -160.426504) (xy 51.394614 -160.419542)
			(xy 51.409767 -160.39688) (xy 51.44548 -160.355693) (xy 51.486688 -160.320005) (xy 51.532555 -160.290542)
			(xy 51.582146 -160.267905) (xy 51.634454 -160.252552) (xy 51.688413 -160.244797) (xy 51.742927 -160.244797)
			(xy 51.796886 -160.252552) (xy 51.849194 -160.267905) (xy 51.898785 -160.290542) (xy 51.944652 -160.320005)
			(xy 51.98586 -160.355693) (xy 52.021573 -160.39688) (xy 52.036726 -160.419542) (xy 52.041544 -160.426536)
			(xy 52.054868 -160.437053) (xy 52.07091 -160.442603) (xy 52.079398 -160.44291) (xy 52.164742 -160.44291)
			(xy 52.173222 -160.442595) (xy 52.189236 -160.437002) (xy 52.20256 -160.426504) (xy 52.207414 -160.419542)
			(xy 52.222528 -160.396849) (xy 52.258239 -160.35565) (xy 52.299451 -160.319952) (xy 52.345323 -160.290482)
			(xy 52.394923 -160.267841) (xy 52.447239 -160.25249) (xy 52.501209 -160.24474) (xy 52.52847 -160.244282)
			(xy 52.555724 -160.244763) (xy 52.609676 -160.252517) (xy 52.661976 -160.26787) (xy 52.711559 -160.29051)
			(xy 52.757415 -160.319976) (xy 52.79861 -160.355669) (xy 52.834306 -160.396861) (xy 52.863776 -160.442715)
			(xy 52.88642 -160.492295) (xy 52.901777 -160.544594) (xy 52.909535 -160.598547) (xy 52.909535 -160.653054)
			(xy 52.901777 -160.707006) (xy 52.88642 -160.759305) (xy 52.863776 -160.808885) (xy 52.834306 -160.854739)
			(xy 52.79861 -160.895931) (xy 52.757415 -160.931624) (xy 52.711559 -160.96109) (xy 52.661976 -160.98373)
			(xy 52.609676 -160.999083) (xy 52.555724 -161.006837) (xy 52.52847 -161.007298) (xy 52.501213 -161.006822)
			(xy 52.447254 -160.999052) (xy 52.394948 -160.983688) (xy 52.345359 -160.961042) (xy 52.299494 -160.931575)
			(xy 52.258285 -160.895886) (xy 52.22257 -160.854699) (xy 52.207414 -160.832038) (xy 52.202578 -160.825058)
			(xy 52.189261 -160.81454) (xy 52.173227 -160.808982) (xy 52.164742 -160.80867) (xy 52.079398 -160.80867)
			(xy 52.070921 -160.809021) (xy 52.05491 -160.814599) (xy 52.041583 -160.825082) (xy 52.036726 -160.832038)
			(xy 52.021573 -160.8547) (xy 51.98586 -160.895887) (xy 51.944652 -160.931575) (xy 51.898785 -160.961038)
			(xy 51.849194 -160.983675) (xy 51.796886 -160.999028) (xy 51.742927 -161.006783) (xy 51.688413 -161.006783)
			(xy 51.634454 -160.999028) (xy 51.582146 -160.983675) (xy 51.532555 -160.961038) (xy 51.486688 -160.931575)
			(xy 51.44548 -160.895887) (xy 51.409767 -160.8547) (xy 51.394614 -160.832038) (xy 51.389778 -160.825058)
			(xy 51.376461 -160.81454) (xy 51.360427 -160.808982) (xy 51.351942 -160.80867) (xy 51.266598 -160.80867)
			(xy 51.258121 -160.809021) (xy 51.24211 -160.814599) (xy 51.228783 -160.825082) (xy 51.223926 -160.832038)
			(xy 51.20878 -160.854708) (xy 51.173074 -160.895909) (xy 51.131869 -160.931609) (xy 51.086002 -160.961081)
			(xy 51.036407 -160.983726) (xy 50.984095 -160.999082) (xy 50.93013 -161.006837) (xy 50.90287 -161.007298)
			(xy 50.875619 -161.00683) (xy 50.821674 -160.99907) (xy 50.769381 -160.983712) (xy 50.719806 -160.961068)
			(xy 50.673958 -160.931601) (xy 50.632771 -160.895908) (xy 50.597081 -160.854718) (xy 50.567617 -160.808867)
			(xy 50.544978 -160.759291) (xy 50.529624 -160.706997) (xy 50.521868 -160.653051) (xy 46.207934 -160.653051)
			(xy 46.207934 -167.221794) (xy 51.82056 -167.221794) (xy 51.82056 -167.070146) (xy 51.828497 -166.918705)
			(xy 51.844348 -166.767887) (xy 51.868071 -166.618106) (xy 51.899601 -166.469771) (xy 51.93885 -166.32329)
			(xy 51.985712 -166.179064) (xy 52.040058 -166.037487) (xy 52.101739 -165.89895) (xy 52.170586 -165.76383)
			(xy 52.246411 -165.632498) (xy 52.329004 -165.505315) (xy 52.418141 -165.382629) (xy 52.513577 -165.264776)
			(xy 52.615049 -165.152079) (xy 52.722281 -165.044847) (xy 52.834978 -164.943375) (xy 52.952831 -164.847939)
			(xy 53.075517 -164.758802) (xy 53.2027 -164.676209) (xy 53.334032 -164.600384) (xy 53.469152 -164.531537)
			(xy 53.607689 -164.469856) (xy 53.749266 -164.41551) (xy 53.893492 -164.368648) (xy 54.039973 -164.329399)
			(xy 54.188308 -164.297869) (xy 54.338089 -164.274146) (xy 54.488907 -164.258295) (xy 54.640348 -164.250358)
			(xy 54.791996 -164.250358) (xy 54.943437 -164.258295) (xy 55.094255 -164.274146) (xy 55.244036 -164.297869)
			(xy 55.392371 -164.329399) (xy 55.538852 -164.368648) (xy 55.683078 -164.41551) (xy 55.824655 -164.469856)
			(xy 55.963192 -164.531537) (xy 56.098312 -164.600384) (xy 56.229644 -164.676209) (xy 56.356827 -164.758802)
			(xy 56.479513 -164.847939) (xy 56.597366 -164.943375) (xy 56.710063 -165.044847) (xy 56.817295 -165.152079)
			(xy 56.918767 -165.264776) (xy 57.014203 -165.382629) (xy 57.10334 -165.505315) (xy 57.185933 -165.632498)
			(xy 57.261758 -165.76383) (xy 57.330605 -165.89895) (xy 57.392286 -166.037487) (xy 57.446632 -166.179064)
			(xy 57.493494 -166.32329) (xy 57.532743 -166.469771) (xy 57.564273 -166.618106) (xy 57.587996 -166.767887)
			(xy 57.603847 -166.918705) (xy 57.611784 -167.070146) (xy 57.61228 -167.14597) (xy 57.611784 -167.221794)
			(xy 57.603847 -167.373235) (xy 57.587996 -167.524053) (xy 57.564273 -167.673834) (xy 57.532743 -167.822169)
			(xy 57.493494 -167.96865) (xy 57.446632 -168.112876) (xy 57.392286 -168.254453) (xy 57.330605 -168.39299)
			(xy 57.261758 -168.52811) (xy 57.185933 -168.659442) (xy 57.10334 -168.786625) (xy 57.014203 -168.909311)
			(xy 56.918767 -169.027164) (xy 56.817295 -169.139861) (xy 56.710063 -169.247093) (xy 56.597366 -169.348565)
			(xy 56.479513 -169.444001) (xy 56.356827 -169.533138) (xy 56.229644 -169.615731) (xy 56.098312 -169.691556)
			(xy 55.963192 -169.760403) (xy 55.824655 -169.822084) (xy 55.683078 -169.87643) (xy 55.538852 -169.923292)
			(xy 55.392371 -169.962541) (xy 55.244036 -169.994071) (xy 55.094255 -170.017794) (xy 54.943437 -170.033645)
			(xy 54.791996 -170.041582) (xy 54.640348 -170.041582) (xy 54.488907 -170.033645) (xy 54.338089 -170.017794)
			(xy 54.188308 -169.994071) (xy 54.039973 -169.962541) (xy 53.893492 -169.923292) (xy 53.749266 -169.87643)
			(xy 53.607689 -169.822084) (xy 53.469152 -169.760403) (xy 53.334032 -169.691556) (xy 53.2027 -169.615731)
			(xy 53.075517 -169.533138) (xy 52.952831 -169.444001) (xy 52.834978 -169.348565) (xy 52.722281 -169.247093)
			(xy 52.615049 -169.139861) (xy 52.513577 -169.027164) (xy 52.418141 -168.909311) (xy 52.329004 -168.786625)
			(xy 52.246411 -168.659442) (xy 52.170586 -168.52811) (xy 52.101739 -168.39299) (xy 52.040058 -168.254453)
			(xy 51.985712 -168.112876) (xy 51.93885 -167.96865) (xy 51.899601 -167.822169) (xy 51.868071 -167.673834)
			(xy 51.844348 -167.524053) (xy 51.828497 -167.373235) (xy 51.82056 -167.221794) (xy 46.207934 -167.221794)
			(xy 46.207934 -169.928032) (xy 46.208478 -169.938016) (xy 46.216203 -169.956437) (xy 46.22292 -169.963846)
			(xy 46.70044 -170.441366) (xy 46.70171 -170.442636) (xy 46.728888 -170.470068) (xy 46.72965 -170.47083)
			(xy 46.730412 -170.471592) (xy 46.848268 -170.589702) (xy 46.855082 -170.597046) (xy 46.862818 -170.615508)
			(xy 46.863254 -170.625516) (xy 46.863254 -170.794426) (xy 46.863762 -170.814746) (xy 46.863762 -170.815254)
			(xy 46.863254 -170.835574) (xy 46.863254 -171.004484) (xy 46.862718 -171.014472) (xy 46.855004 -171.032904)
			(xy 46.848268 -171.040298) (xy 46.730412 -171.158408) (xy 46.72965 -171.15917) (xy 46.728888 -171.159932)
			(xy 46.69917 -171.18965) (xy 46.698408 -171.190412) (xy 46.580298 -171.308268) (xy 46.572954 -171.315082)
			(xy 46.554492 -171.322818) (xy 46.544484 -171.323254) (xy 46.375574 -171.323254) (xy 46.355254 -171.323762)
			(xy 46.354746 -171.323762) (xy 46.334426 -171.323254) (xy 46.258734 -171.323254) (xy 46.248718 -171.323736)
			(xy 46.230207 -171.331387) (xy 46.216032 -171.34554) (xy 46.208351 -171.364039) (xy 46.207934 -171.374054)
			(xy 46.207934 -175.545053) (xy 60.437465 -175.545053) (xy 60.437465 -175.490547) (xy 60.445223 -175.436595)
			(xy 60.460579 -175.384297) (xy 60.483223 -175.334717) (xy 60.512692 -175.288864) (xy 60.548387 -175.247672)
			(xy 60.589582 -175.211979) (xy 60.635436 -175.182512) (xy 60.685018 -175.159872) (xy 60.737317 -175.144518)
			(xy 60.791269 -175.136764) (xy 60.818522 -175.136302) (xy 60.845389 -175.136738) (xy 60.898592 -175.144268)
			(xy 60.950212 -175.159192) (xy 60.999226 -175.181212) (xy 61.044665 -175.209894) (xy 61.085628 -175.244669)
			(xy 61.121305 -175.284849) (xy 61.13653 -175.30699) (xy 61.144538 -175.318325) (xy 61.165497 -175.336502)
			(xy 61.190579 -175.348356) (xy 61.217929 -175.35301) (xy 61.245521 -175.35012) (xy 61.271313 -175.339898)
			(xy 61.293394 -175.323103) (xy 61.302138 -175.312324) (xy 61.3203 -175.289331) (xy 61.362477 -175.24866)
			(xy 61.410374 -175.214914) (xy 61.462868 -175.188886) (xy 61.518722 -175.171187) (xy 61.576626 -175.162235)
			(xy 61.605922 -175.161702) (xy 61.633173 -175.162169) (xy 61.68712 -175.169929) (xy 61.739413 -175.185286)
			(xy 61.788989 -175.207929) (xy 61.834838 -175.237397) (xy 61.876026 -175.273089) (xy 61.911717 -175.31428)
			(xy 61.941182 -175.36013) (xy 61.963822 -175.409707) (xy 61.979176 -175.462002) (xy 61.986932 -175.515949)
			(xy 61.986932 -175.570451) (xy 61.979176 -175.624398) (xy 61.963822 -175.676693) (xy 61.941182 -175.72627)
			(xy 61.911717 -175.77212) (xy 61.876026 -175.813311) (xy 61.834838 -175.849003) (xy 61.788989 -175.878471)
			(xy 61.739413 -175.901114) (xy 61.68712 -175.916471) (xy 61.633173 -175.924231) (xy 61.605922 -175.924718)
			(xy 61.579057 -175.92424) (xy 61.525856 -175.916716) (xy 61.474237 -175.901799) (xy 61.425224 -175.879786)
			(xy 61.379785 -175.851111) (xy 61.33882 -175.816342) (xy 61.303141 -175.776168) (xy 61.287914 -175.75403)
			(xy 61.279853 -175.742735) (xy 61.258907 -175.724556) (xy 61.233835 -175.712698) (xy 61.206495 -175.708038)
			(xy 61.178911 -175.710921) (xy 61.153126 -175.721134) (xy 61.131048 -175.737921) (xy 61.122306 -175.748696)
			(xy 61.104155 -175.771699) (xy 61.061979 -175.812373) (xy 61.01408 -175.84612) (xy 60.961584 -175.872148)
			(xy 60.905726 -175.889843) (xy 60.847819 -175.898789) (xy 60.818522 -175.899318) (xy 60.791269 -175.898836)
			(xy 60.737317 -175.891082) (xy 60.685018 -175.875728) (xy 60.635436 -175.853088) (xy 60.589582 -175.823621)
			(xy 60.548387 -175.787928) (xy 60.512692 -175.746736) (xy 60.483223 -175.700883) (xy 60.460579 -175.651303)
			(xy 60.445223 -175.599005) (xy 60.437465 -175.545053) (xy 46.207934 -175.545053) (xy 46.207934 -180.26761)
			(xy 60.538104 -180.26761) (xy 60.542175 -180.211988) (xy 60.554301 -180.157551) (xy 60.574224 -180.10546)
			(xy 60.60152 -180.056825) (xy 60.635606 -180.012682) (xy 60.675755 -179.973973) (xy 60.721113 -179.941522)
			(xy 60.770713 -179.916021) (xy 60.823497 -179.898014) (xy 60.87834 -179.887884) (xy 60.934074 -179.885847)
			(xy 60.989511 -179.891947) (xy 61.043468 -179.906053) (xy 61.094797 -179.927865) (xy 61.142403 -179.956919)
			(xy 61.185271 -179.992594) (xy 61.222488 -180.034131) (xy 61.253261 -180.080644) (xy 61.276933 -180.131141)
			(xy 61.293001 -180.184548) (xy 61.301121 -180.239724) (xy 61.30163 -180.26761) (xy 61.301121 -180.295496)
			(xy 61.293001 -180.350672) (xy 61.276933 -180.404079) (xy 61.253261 -180.454576) (xy 61.222488 -180.501089)
			(xy 61.185271 -180.542626) (xy 61.142403 -180.578301) (xy 61.094797 -180.607355) (xy 61.043468 -180.629167)
			(xy 60.989511 -180.643273) (xy 60.934074 -180.649373) (xy 60.87834 -180.647336) (xy 60.823497 -180.637206)
			(xy 60.770713 -180.619199) (xy 60.721113 -180.593698) (xy 60.675755 -180.561247) (xy 60.635606 -180.522538)
			(xy 60.60152 -180.478395) (xy 60.574224 -180.42976) (xy 60.554301 -180.377669) (xy 60.542175 -180.323232)
			(xy 60.538104 -180.26761) (xy 46.207934 -180.26761) (xy 46.207934 -181.3748) (xy 51.611482 -181.3748)
			(xy 51.615397 -181.297604) (xy 51.627102 -181.2212) (xy 51.646477 -181.146372) (xy 51.673323 -181.073888)
			(xy 51.707365 -181.004493) (xy 51.748253 -180.938897) (xy 51.795567 -180.877775) (xy 51.848823 -180.821754)
			(xy 51.907473 -180.771408) (xy 51.970916 -180.727253) (xy 52.038501 -180.689745) (xy 52.109533 -180.659266)
			(xy 52.183285 -180.63613) (xy 52.258999 -180.620575) (xy 52.335898 -180.612759) (xy 52.374546 -180.612288)
			(xy 52.411296 -180.612768) (xy 52.484452 -180.619867) (xy 52.556587 -180.633967) (xy 52.627033 -180.654936)
			(xy 52.695136 -180.682581) (xy 52.760265 -180.716645) (xy 52.821819 -180.756813) (xy 52.850796 -180.77942)
			(xy 52.860169 -180.78607) (xy 52.882546 -180.791171) (xy 52.904923 -180.78607) (xy 52.914296 -180.77942)
			(xy 52.943259 -180.756789) (xy 53.004797 -180.716585) (xy 53.069922 -180.682496) (xy 53.138027 -180.654839)
			(xy 53.208481 -180.633872) (xy 53.280626 -180.619789) (xy 53.353792 -180.612722) (xy 53.390546 -180.612288)
			(xy 53.429189 -180.612788) (xy 53.50608 -180.620611) (xy 53.581784 -180.636173) (xy 53.655525 -180.659313)
			(xy 53.726547 -180.689795) (xy 53.794122 -180.727305) (xy 53.857554 -180.771459) (xy 53.916195 -180.821804)
			(xy 53.969441 -180.877822) (xy 54.016748 -180.93894) (xy 54.057628 -181.00453) (xy 54.091664 -181.07392)
			(xy 54.118505 -181.146396) (xy 54.137877 -181.221216) (xy 54.14958 -181.297612) (xy 54.153494 -181.3748)
			(xy 54.14958 -181.451988) (xy 54.137877 -181.528384) (xy 54.118505 -181.603204) (xy 54.091664 -181.67568)
			(xy 54.057628 -181.74507) (xy 54.016748 -181.81066) (xy 53.992173 -181.84241) (xy 56.17337 -181.84241)
			(xy 56.173811 -181.805232) (xy 56.181062 -181.731232) (xy 56.195486 -181.658289) (xy 56.216946 -181.587098)
			(xy 56.245238 -181.518336) (xy 56.26227 -181.485286) (xy 56.267571 -181.473927) (xy 56.267576 -181.44889)
			(xy 56.26227 -181.437534) (xy 56.245246 -181.404481) (xy 56.216971 -181.335715) (xy 56.195519 -181.264524)
			(xy 56.181093 -181.191584) (xy 56.173831 -181.117586) (xy 56.17337 -181.08041) (xy 56.173859 -181.041765)
			(xy 56.181679 -180.964871) (xy 56.197237 -180.889163) (xy 56.220375 -180.815417) (xy 56.250855 -180.74439)
			(xy 56.288364 -180.676812) (xy 56.332518 -180.613374) (xy 56.382863 -180.55473) (xy 56.438882 -180.501479)
			(xy 56.500001 -180.454169) (xy 56.565594 -180.413285) (xy 56.634985 -180.379247) (xy 56.707465 -180.352404)
			(xy 56.782288 -180.333031) (xy 56.858687 -180.321327) (xy 56.935878 -180.317412) (xy 57.013069 -180.321327)
			(xy 57.089468 -180.333031) (xy 57.164291 -180.352404) (xy 57.236771 -180.379247) (xy 57.306162 -180.413285)
			(xy 57.371755 -180.454169) (xy 57.432874 -180.501479) (xy 57.488893 -180.55473) (xy 57.539238 -180.613374)
			(xy 57.583392 -180.676812) (xy 57.620901 -180.74439) (xy 57.651381 -180.815417) (xy 57.674519 -180.889163)
			(xy 57.690077 -180.964871) (xy 57.697897 -181.041765) (xy 57.698386 -181.08041) (xy 57.697958 -181.117588)
			(xy 57.690705 -181.191589) (xy 57.676278 -181.264532) (xy 57.654815 -181.335723) (xy 57.62652 -181.404485)
			(xy 57.609486 -181.437534) (xy 57.604167 -181.448887) (xy 57.604172 -181.47393) (xy 57.609486 -181.485286)
			(xy 57.626522 -181.518332) (xy 57.654794 -181.587101) (xy 57.676243 -181.658294) (xy 57.690666 -181.731235)
			(xy 57.697926 -181.805233) (xy 57.698386 -181.84241) (xy 57.697897 -181.881055) (xy 57.690077 -181.957949)
			(xy 57.674519 -182.033657) (xy 57.651381 -182.107403) (xy 57.620901 -182.17843) (xy 57.583392 -182.246008)
			(xy 57.539238 -182.309446) (xy 57.488893 -182.36809) (xy 57.432874 -182.421341) (xy 57.371755 -182.468651)
			(xy 57.306162 -182.509535) (xy 57.236771 -182.543573) (xy 57.164291 -182.570416) (xy 57.089468 -182.589789)
			(xy 57.013069 -182.601493) (xy 56.935878 -182.605408) (xy 56.858687 -182.601493) (xy 56.782288 -182.589789)
			(xy 56.707465 -182.570416) (xy 56.634985 -182.543573) (xy 56.565594 -182.509535) (xy 56.500001 -182.468651)
			(xy 56.438882 -182.421341) (xy 56.382863 -182.36809) (xy 56.332518 -182.309446) (xy 56.288364 -182.246008)
			(xy 56.250855 -182.17843) (xy 56.220375 -182.107403) (xy 56.197237 -182.033657) (xy 56.181679 -181.957949)
			(xy 56.173859 -181.881055) (xy 56.17337 -181.84241) (xy 53.992173 -181.84241) (xy 53.969441 -181.871778)
			(xy 53.916195 -181.927796) (xy 53.857554 -181.978141) (xy 53.794122 -182.022295) (xy 53.726547 -182.059805)
			(xy 53.655525 -182.090287) (xy 53.581784 -182.113427) (xy 53.50608 -182.128989) (xy 53.429189 -182.136812)
			(xy 53.390546 -182.137304) (xy 53.353796 -182.13683) (xy 53.280639 -182.12973) (xy 53.208504 -182.115629)
			(xy 53.138059 -182.094659) (xy 53.069956 -182.067013) (xy 53.004826 -182.032948) (xy 52.943273 -181.992779)
			(xy 52.914296 -181.970172) (xy 52.904923 -181.963522) (xy 52.882546 -181.958421) (xy 52.860169 -181.963522)
			(xy 52.850796 -181.970172) (xy 52.821835 -181.992805) (xy 52.760297 -182.033009) (xy 52.695172 -182.067098)
			(xy 52.627066 -182.094755) (xy 52.556612 -182.115722) (xy 52.484466 -182.129804) (xy 52.4113 -182.13687)
			(xy 52.374546 -182.137304) (xy 52.335898 -182.136841) (xy 52.258999 -182.129025) (xy 52.183285 -182.11347)
			(xy 52.109533 -182.090334) (xy 52.038501 -182.059855) (xy 51.970916 -182.022347) (xy 51.907473 -181.978192)
			(xy 51.848823 -181.927846) (xy 51.795567 -181.871825) (xy 51.748253 -181.810703) (xy 51.707365 -181.745107)
			(xy 51.673323 -181.675712) (xy 51.646477 -181.603228) (xy 51.627102 -181.5284) (xy 51.615397 -181.451996)
			(xy 51.611482 -181.3748) (xy 46.207934 -181.3748) (xy 46.207934 -184.596532) (xy 46.208395 -184.606409)
			(xy 46.215835 -184.62471) (xy 46.222412 -184.632092) (xy 46.222666 -184.632346) (xy 46.687486 -185.097166)
			(xy 46.687994 -185.097674) (xy 46.695378 -185.104248) (xy 46.713677 -185.11168) (xy 46.723554 -185.112152)
			(xy 58.162952 -185.112152) (xy 58.173017 -185.112586) (xy 58.191603 -185.12032) (xy 58.19902 -185.127138)
			(xy 58.430918 -185.35904) (xy 62.37859 -185.35904) (xy 62.379054 -185.328343) (xy 62.386459 -185.267398)
			(xy 62.401153 -185.207789) (xy 62.422923 -185.150386) (xy 62.451451 -185.096023) (xy 62.468506 -185.070496)
			(xy 62.473943 -185.061726) (xy 62.478083 -185.041533) (xy 62.473969 -185.021336) (xy 62.468506 -185.012584)
			(xy 62.451467 -184.987049) (xy 62.422958 -184.93268) (xy 62.401196 -184.875277) (xy 62.386495 -184.815674)
			(xy 62.379071 -184.754735) (xy 62.37859 -184.72404) (xy 62.379054 -184.693343) (xy 62.386459 -184.632398)
			(xy 62.401153 -184.572789) (xy 62.422923 -184.515386) (xy 62.451451 -184.461023) (xy 62.468506 -184.435496)
			(xy 62.473943 -184.426726) (xy 62.478083 -184.406533) (xy 62.473969 -184.386336) (xy 62.468506 -184.377584)
			(xy 62.451467 -184.352049) (xy 62.422958 -184.29768) (xy 62.401196 -184.240277) (xy 62.386495 -184.180674)
			(xy 62.379071 -184.119735) (xy 62.37859 -184.08904) (xy 62.379054 -184.058343) (xy 62.386459 -183.997398)
			(xy 62.401153 -183.937789) (xy 62.422923 -183.880386) (xy 62.451451 -183.826023) (xy 62.468506 -183.800496)
			(xy 62.473943 -183.791726) (xy 62.478083 -183.771533) (xy 62.473969 -183.751336) (xy 62.468506 -183.742584)
			(xy 62.451467 -183.717049) (xy 62.422958 -183.66268) (xy 62.401196 -183.605277) (xy 62.386495 -183.545674)
			(xy 62.379071 -183.484735) (xy 62.37859 -183.45404) (xy 62.379054 -183.423343) (xy 62.386459 -183.362398)
			(xy 62.401153 -183.302789) (xy 62.422923 -183.245386) (xy 62.451451 -183.191023) (xy 62.468506 -183.165496)
			(xy 62.473943 -183.156726) (xy 62.478083 -183.136533) (xy 62.473969 -183.116336) (xy 62.468506 -183.107584)
			(xy 62.451467 -183.082049) (xy 62.422958 -183.02768) (xy 62.401196 -182.970277) (xy 62.386495 -182.910674)
			(xy 62.379071 -182.849735) (xy 62.37859 -182.81904) (xy 62.379054 -182.788343) (xy 62.386459 -182.727398)
			(xy 62.401153 -182.667789) (xy 62.422923 -182.610386) (xy 62.451451 -182.556023) (xy 62.468506 -182.530496)
			(xy 62.473943 -182.521726) (xy 62.478083 -182.501533) (xy 62.473969 -182.481336) (xy 62.468506 -182.472584)
			(xy 62.451467 -182.447049) (xy 62.422958 -182.39268) (xy 62.401196 -182.335277) (xy 62.386495 -182.275674)
			(xy 62.379071 -182.214735) (xy 62.37859 -182.18404) (xy 62.379054 -182.153343) (xy 62.386459 -182.092398)
			(xy 62.401153 -182.032789) (xy 62.422923 -181.975386) (xy 62.451451 -181.921023) (xy 62.468506 -181.895496)
			(xy 62.473943 -181.886726) (xy 62.478083 -181.866533) (xy 62.473969 -181.846336) (xy 62.468506 -181.837584)
			(xy 62.451467 -181.812049) (xy 62.422958 -181.75768) (xy 62.401196 -181.700277) (xy 62.386495 -181.640674)
			(xy 62.379071 -181.579735) (xy 62.37859 -181.54904) (xy 62.379063 -181.518009) (xy 62.386618 -181.456409)
			(xy 62.401608 -181.396185) (xy 62.42381 -181.338231) (xy 62.452895 -181.283407) (xy 62.470284 -181.257702)
			(xy 62.475832 -181.248924) (xy 62.480052 -181.228616) (xy 62.475845 -181.208305) (xy 62.470284 -181.199536)
			(xy 62.452899 -181.173828) (xy 62.423804 -181.119008) (xy 62.401596 -181.061055) (xy 62.386605 -181.00083)
			(xy 62.379053 -180.939229) (xy 62.37859 -180.908198) (xy 62.379054 -180.877467) (xy 62.386463 -180.816453)
			(xy 62.401172 -180.756777) (xy 62.422967 -180.69931) (xy 62.451529 -180.644888) (xy 62.486444 -180.594306)
			(xy 62.527201 -180.548301) (xy 62.573206 -180.507544) (xy 62.623788 -180.472629) (xy 62.67821 -180.444067)
			(xy 62.735677 -180.422272) (xy 62.795353 -180.407563) (xy 62.856367 -180.400154) (xy 62.887098 -180.39969)
			(xy 62.917795 -180.400134) (xy 62.978741 -180.407544) (xy 63.03835 -180.422243) (xy 63.095754 -180.444017)
			(xy 63.150115 -180.472549) (xy 63.175642 -180.489606) (xy 63.184394 -180.495077) (xy 63.204598 -180.499205)
			(xy 63.224802 -180.495077) (xy 63.233554 -180.489606) (xy 63.259079 -180.47255) (xy 63.31345 -180.444044)
			(xy 63.370856 -180.422285) (xy 63.430462 -180.407589) (xy 63.491403 -180.400169) (xy 63.522098 -180.39969)
			(xy 63.552795 -180.400134) (xy 63.613741 -180.407544) (xy 63.67335 -180.422243) (xy 63.730754 -180.444017)
			(xy 63.785115 -180.472549) (xy 63.810642 -180.489606) (xy 63.819394 -180.495077) (xy 63.839598 -180.499205)
			(xy 63.859802 -180.495077) (xy 63.868554 -180.489606) (xy 63.894079 -180.47255) (xy 63.94845 -180.444044)
			(xy 64.005856 -180.422285) (xy 64.065462 -180.407589) (xy 64.126403 -180.400169) (xy 64.157098 -180.39969)
			(xy 64.187829 -180.400158) (xy 64.248843 -180.407566) (xy 64.308518 -180.422275) (xy 64.365986 -180.444069)
			(xy 64.420408 -180.472632) (xy 64.47099 -180.507546) (xy 64.516995 -180.548302) (xy 64.557752 -180.594307)
			(xy 64.592666 -180.644889) (xy 64.621229 -180.69931) (xy 64.643024 -180.756778) (xy 64.657733 -180.816454)
			(xy 64.665142 -180.877467) (xy 64.665606 -180.908198) (xy 64.665158 -180.938827) (xy 64.657792 -180.999641)
			(xy 64.64318 -181.05913) (xy 64.621533 -181.116436) (xy 64.593163 -181.170728) (xy 64.576198 -181.196234)
			(xy 64.57083 -181.204979) (xy 64.566758 -181.225069) (xy 64.570806 -181.245164) (xy 64.576198 -181.253892)
			(xy 64.593364 -181.279454) (xy 64.622029 -181.333952) (xy 64.643912 -181.39151) (xy 64.658693 -181.451287)
			(xy 64.666156 -181.51241) (xy 64.666622 -181.543198) (xy 64.666175 -181.573895) (xy 64.658766 -181.634841)
			(xy 64.644068 -181.69445) (xy 64.622294 -181.751853) (xy 64.593762 -181.806215) (xy 64.576706 -181.831742)
			(xy 64.571235 -181.840494) (xy 64.567105 -181.860698) (xy 64.571234 -181.880902) (xy 64.576706 -181.889654)
			(xy 64.593763 -181.915178) (xy 64.622269 -181.96955) (xy 64.644027 -182.026956) (xy 64.658723 -182.086562)
			(xy 64.666143 -182.147503) (xy 64.666622 -182.178198) (xy 64.666175 -182.208895) (xy 64.658766 -182.269841)
			(xy 64.644068 -182.32945) (xy 64.622294 -182.386853) (xy 64.593762 -182.441215) (xy 64.576706 -182.466742)
			(xy 64.571235 -182.475494) (xy 64.567105 -182.495698) (xy 64.571234 -182.515902) (xy 64.576706 -182.524654)
			(xy 64.593763 -182.550178) (xy 64.622269 -182.60455) (xy 64.644027 -182.661956) (xy 64.658723 -182.721562)
			(xy 64.666143 -182.782503) (xy 64.666622 -182.813198) (xy 64.666175 -182.843895) (xy 64.658766 -182.904841)
			(xy 64.644068 -182.96445) (xy 64.622294 -183.021853) (xy 64.593762 -183.076215) (xy 64.576706 -183.101742)
			(xy 64.571235 -183.110494) (xy 64.567105 -183.130698) (xy 64.571234 -183.150902) (xy 64.576706 -183.159654)
			(xy 64.593763 -183.185178) (xy 64.622269 -183.23955) (xy 64.644027 -183.296956) (xy 64.658723 -183.356562)
			(xy 64.666143 -183.417503) (xy 64.666622 -183.448198) (xy 64.666165 -183.479322) (xy 64.658571 -183.541104)
			(xy 64.643494 -183.601499) (xy 64.621162 -183.659602) (xy 64.591907 -183.714547) (xy 64.57442 -183.740298)
			(xy 64.56894 -183.749097) (xy 64.564787 -183.769384) (xy 64.568927 -183.789674) (xy 64.57442 -183.798464)
			(xy 64.591699 -183.824132) (xy 64.620634 -183.878827) (xy 64.64272 -183.936628) (xy 64.65763 -183.996682)
			(xy 64.665144 -184.058101) (xy 64.665606 -184.08904) (xy 64.665133 -184.119736) (xy 64.65773 -184.180681)
			(xy 64.643038 -184.24029) (xy 64.62127 -184.297694) (xy 64.592744 -184.352057) (xy 64.57569 -184.377584)
			(xy 64.570184 -184.386318) (xy 64.566068 -184.406533) (xy 64.57021 -184.426744) (xy 64.57569 -184.435496)
			(xy 64.59272 -184.461037) (xy 64.621231 -184.515404) (xy 64.642995 -184.572805) (xy 64.657697 -184.632408)
			(xy 64.665124 -184.693346) (xy 64.665606 -184.72404) (xy 64.665133 -184.754736) (xy 64.65773 -184.815681)
			(xy 64.643038 -184.87529) (xy 64.62127 -184.932694) (xy 64.592744 -184.987057) (xy 64.57569 -185.012584)
			(xy 64.570184 -185.021318) (xy 64.566068 -185.041533) (xy 64.57021 -185.061744) (xy 64.57569 -185.070496)
			(xy 64.59272 -185.096037) (xy 64.621231 -185.150404) (xy 64.642995 -185.207805) (xy 64.657697 -185.267408)
			(xy 64.665124 -185.328346) (xy 64.665606 -185.35904) (xy 64.665182 -185.389772) (xy 64.657769 -185.450787)
			(xy 64.643056 -185.510464) (xy 64.621257 -185.567933) (xy 64.59269 -185.622355) (xy 64.557772 -185.672937)
			(xy 64.517012 -185.718941) (xy 64.471004 -185.759698) (xy 64.420419 -185.794612) (xy 64.365994 -185.823174)
			(xy 64.308524 -185.844968) (xy 64.248846 -185.859676) (xy 64.18783 -185.867085) (xy 64.157098 -185.867548)
			(xy 64.126402 -185.867066) (xy 64.065457 -185.859667) (xy 64.005848 -185.844977) (xy 63.948444 -185.823211)
			(xy 63.894081 -185.794686) (xy 63.868554 -185.777632) (xy 63.859802 -185.772161) (xy 63.839598 -185.768033)
			(xy 63.819394 -185.772161) (xy 63.810642 -185.777632) (xy 63.785114 -185.794682) (xy 63.730744 -185.82319)
			(xy 63.673339 -185.844951) (xy 63.613734 -185.859649) (xy 63.552793 -185.867069) (xy 63.522098 -185.867548)
			(xy 63.491402 -185.867066) (xy 63.430457 -185.859667) (xy 63.370848 -185.844977) (xy 63.313444 -185.823211)
			(xy 63.259081 -185.794686) (xy 63.233554 -185.777632) (xy 63.224802 -185.772161) (xy 63.204598 -185.768033)
			(xy 63.184394 -185.772161) (xy 63.175642 -185.777632) (xy 63.150114 -185.794682) (xy 63.095744 -185.82319)
			(xy 63.038339 -185.844951) (xy 62.978734 -185.859649) (xy 62.917793 -185.867069) (xy 62.887098 -185.867548)
			(xy 62.856369 -185.867046) (xy 62.795358 -185.859638) (xy 62.735684 -185.84493) (xy 62.678219 -185.823138)
			(xy 62.623799 -185.794577) (xy 62.573218 -185.759666) (xy 62.527214 -185.718913) (xy 62.486457 -185.672912)
			(xy 62.451542 -185.622334) (xy 62.422978 -185.567916) (xy 62.401181 -185.510452) (xy 62.386469 -185.45078)
			(xy 62.379056 -185.389769) (xy 62.37859 -185.35904) (xy 58.430918 -185.35904) (xy 66.520691 -193.44894)
			(xy 70.69201 -193.44894) (xy 70.69247 -193.418243) (xy 70.699875 -193.357298) (xy 70.71457 -193.297689)
			(xy 70.736341 -193.240285) (xy 70.764871 -193.185923) (xy 70.781926 -193.160396) (xy 70.787362 -193.151625)
			(xy 70.7915 -193.131433) (xy 70.787388 -193.111236) (xy 70.781926 -193.102484) (xy 70.764889 -193.076947)
			(xy 70.736379 -193.022579) (xy 70.714616 -192.965177) (xy 70.699916 -192.905573) (xy 70.692491 -192.844634)
			(xy 70.69201 -192.81394) (xy 70.69247 -192.783243) (xy 70.699875 -192.722298) (xy 70.71457 -192.662689)
			(xy 70.736341 -192.605285) (xy 70.764871 -192.550923) (xy 70.781926 -192.525396) (xy 70.787362 -192.516625)
			(xy 70.7915 -192.496433) (xy 70.787388 -192.476236) (xy 70.781926 -192.467484) (xy 70.764889 -192.441947)
			(xy 70.736379 -192.387579) (xy 70.714616 -192.330177) (xy 70.699916 -192.270573) (xy 70.692491 -192.209634)
			(xy 70.69201 -192.17894) (xy 70.69247 -192.148243) (xy 70.699875 -192.087298) (xy 70.71457 -192.027689)
			(xy 70.736341 -191.970285) (xy 70.764871 -191.915923) (xy 70.781926 -191.890396) (xy 70.787362 -191.881625)
			(xy 70.7915 -191.861433) (xy 70.787388 -191.841236) (xy 70.781926 -191.832484) (xy 70.764889 -191.806947)
			(xy 70.736379 -191.752579) (xy 70.714616 -191.695177) (xy 70.699916 -191.635573) (xy 70.692491 -191.574634)
			(xy 70.69201 -191.54394) (xy 70.69247 -191.513243) (xy 70.699875 -191.452298) (xy 70.71457 -191.392689)
			(xy 70.736341 -191.335285) (xy 70.764871 -191.280923) (xy 70.781926 -191.255396) (xy 70.787362 -191.246625)
			(xy 70.7915 -191.226433) (xy 70.787388 -191.206236) (xy 70.781926 -191.197484) (xy 70.764889 -191.171947)
			(xy 70.736379 -191.117579) (xy 70.714616 -191.060177) (xy 70.699916 -191.000573) (xy 70.692491 -190.939634)
			(xy 70.69201 -190.90894) (xy 70.69247 -190.878243) (xy 70.699875 -190.817298) (xy 70.71457 -190.757689)
			(xy 70.736341 -190.700285) (xy 70.764871 -190.645923) (xy 70.781926 -190.620396) (xy 70.787362 -190.611625)
			(xy 70.7915 -190.591433) (xy 70.787388 -190.571236) (xy 70.781926 -190.562484) (xy 70.764889 -190.536947)
			(xy 70.736379 -190.482579) (xy 70.714616 -190.425177) (xy 70.699916 -190.365573) (xy 70.692491 -190.304634)
			(xy 70.69201 -190.27394) (xy 70.692515 -190.241366) (xy 70.700851 -190.176752) (xy 70.717377 -190.113734)
			(xy 70.741822 -190.053345) (xy 70.773787 -189.996576) (xy 70.792848 -189.970156) (xy 70.799019 -189.961091)
			(xy 70.803674 -189.939681) (xy 70.799003 -189.918274) (xy 70.792848 -189.909196) (xy 70.773796 -189.882772)
			(xy 70.741859 -189.825993) (xy 70.717427 -189.765604) (xy 70.7009 -189.702591) (xy 70.692548 -189.637984)
			(xy 70.69201 -189.605412) (xy 70.692449 -189.574679) (xy 70.699857 -189.513662) (xy 70.714565 -189.453983)
			(xy 70.736361 -189.396512) (xy 70.764924 -189.342087) (xy 70.799841 -189.291502) (xy 70.8406 -189.245495)
			(xy 70.886607 -189.204737) (xy 70.937192 -189.169821) (xy 70.991618 -189.141258) (xy 71.049089 -189.119463)
			(xy 71.108768 -189.104756) (xy 71.169785 -189.097349) (xy 71.200518 -189.096904) (xy 71.231214 -189.097387)
			(xy 71.292159 -189.104787) (xy 71.351767 -189.119477) (xy 71.409171 -189.141242) (xy 71.463534 -189.169767)
			(xy 71.489062 -189.18682) (xy 71.497814 -189.192291) (xy 71.518018 -189.196419) (xy 71.538222 -189.192291)
			(xy 71.546974 -189.18682) (xy 71.572494 -189.169757) (xy 71.626867 -189.141252) (xy 71.684274 -189.119494)
			(xy 71.743881 -189.1048) (xy 71.804822 -189.097382) (xy 71.835518 -189.096904) (xy 71.866214 -189.097387)
			(xy 71.927159 -189.104787) (xy 71.986767 -189.119477) (xy 72.044171 -189.141242) (xy 72.098534 -189.169767)
			(xy 72.124062 -189.18682) (xy 72.132814 -189.192291) (xy 72.153018 -189.196419) (xy 72.173222 -189.192291)
			(xy 72.181974 -189.18682) (xy 72.207494 -189.169757) (xy 72.261867 -189.141252) (xy 72.319274 -189.119494)
			(xy 72.378881 -189.1048) (xy 72.439822 -189.097382) (xy 72.470518 -189.096904) (xy 72.50125 -189.097339)
			(xy 72.562265 -189.10475) (xy 72.621942 -189.119461) (xy 72.679411 -189.141258) (xy 72.733834 -189.169824)
			(xy 72.784416 -189.204741) (xy 72.830421 -189.2455) (xy 72.871178 -189.291507) (xy 72.906092 -189.342092)
			(xy 72.934654 -189.396516) (xy 72.956448 -189.453986) (xy 72.971155 -189.513664) (xy 72.978563 -189.57468)
			(xy 72.979026 -189.605412) (xy 72.978581 -189.636041) (xy 72.971215 -189.696855) (xy 72.956602 -189.756344)
			(xy 72.934953 -189.81365) (xy 72.906583 -189.867942) (xy 72.889618 -189.893448) (xy 72.884237 -189.902186)
			(xy 72.880166 -189.922281) (xy 72.884222 -189.942378) (xy 72.889618 -189.951106) (xy 72.90675 -189.976691)
			(xy 72.93542 -190.031182) (xy 72.95731 -190.088734) (xy 72.972099 -190.148506) (xy 72.979572 -190.209625)
			(xy 72.980042 -190.240412) (xy 72.979548 -190.271108) (xy 72.97215 -190.332051) (xy 72.957462 -190.39166)
			(xy 72.935699 -190.449064) (xy 72.907177 -190.503428) (xy 72.890126 -190.528956) (xy 72.884641 -190.537701)
			(xy 72.880514 -190.55791) (xy 72.884649 -190.578117) (xy 72.890126 -190.586868) (xy 72.90718 -190.612394)
			(xy 72.935688 -190.666765) (xy 72.957448 -190.72417) (xy 72.972144 -190.783776) (xy 72.979564 -190.844717)
			(xy 72.980042 -190.875412) (xy 72.979548 -190.906108) (xy 72.97215 -190.967051) (xy 72.957462 -191.02666)
			(xy 72.935699 -191.084064) (xy 72.907177 -191.138428) (xy 72.890126 -191.163956) (xy 72.884641 -191.172701)
			(xy 72.880514 -191.19291) (xy 72.884649 -191.213117) (xy 72.890126 -191.221868) (xy 72.90718 -191.247394)
			(xy 72.935688 -191.301765) (xy 72.957448 -191.35917) (xy 72.972144 -191.418776) (xy 72.979564 -191.479717)
			(xy 72.980042 -191.510412) (xy 72.979548 -191.541108) (xy 72.97215 -191.602051) (xy 72.957462 -191.66166)
			(xy 72.935699 -191.719064) (xy 72.907177 -191.773428) (xy 72.890126 -191.798956) (xy 72.884641 -191.807701)
			(xy 72.880514 -191.82791) (xy 72.884649 -191.848117) (xy 72.890126 -191.856868) (xy 72.90718 -191.882394)
			(xy 72.935688 -191.936765) (xy 72.957448 -191.99417) (xy 72.972144 -192.053776) (xy 72.979564 -192.114717)
			(xy 72.980042 -192.145412) (xy 72.979547 -192.17808) (xy 72.971172 -192.242878) (xy 72.954563 -192.306068)
			(xy 72.929993 -192.366609) (xy 72.897868 -192.423502) (xy 72.878696 -192.449958) (xy 72.872611 -192.459009)
			(xy 72.868021 -192.480309) (xy 72.872619 -192.501608) (xy 72.878696 -192.510664) (xy 72.897685 -192.537052)
			(xy 72.929486 -192.593756) (xy 72.9538 -192.65405) (xy 72.970232 -192.716951) (xy 72.978513 -192.781434)
			(xy 72.979026 -192.81394) (xy 72.978549 -192.844636) (xy 72.971147 -192.905581) (xy 72.956455 -192.965189)
			(xy 72.934688 -193.022593) (xy 72.906163 -193.076956) (xy 72.88911 -193.102484) (xy 72.883603 -193.111217)
			(xy 72.879485 -193.131433) (xy 72.883629 -193.151644) (xy 72.88911 -193.160396) (xy 72.906143 -193.185936)
			(xy 72.934652 -193.240303) (xy 72.956416 -193.297705) (xy 72.971117 -193.357308) (xy 72.978544 -193.418246)
			(xy 72.979026 -193.44894) (xy 72.978582 -193.479671) (xy 72.971169 -193.540685) (xy 72.956457 -193.60036)
			(xy 72.934659 -193.657828) (xy 72.906093 -193.712249) (xy 72.871177 -193.76283) (xy 72.830419 -193.808834)
			(xy 72.784413 -193.849591) (xy 72.73383 -193.884505) (xy 72.679408 -193.913068) (xy 72.621939 -193.934863)
			(xy 72.562263 -193.949573) (xy 72.501249 -193.956983) (xy 72.470518 -193.957448) (xy 72.439821 -193.957006)
			(xy 72.378874 -193.949598) (xy 72.319265 -193.934899) (xy 72.261861 -193.913124) (xy 72.2075 -193.88459)
			(xy 72.181974 -193.867532) (xy 72.173222 -193.862061) (xy 72.153018 -193.857933) (xy 72.132814 -193.862061)
			(xy 72.124062 -193.867532) (xy 72.098528 -193.884573) (xy 72.04416 -193.913083) (xy 71.986756 -193.934846)
			(xy 71.927152 -193.949545) (xy 71.866213 -193.956968) (xy 71.835518 -193.957448) (xy 71.804821 -193.957006)
			(xy 71.743874 -193.949598) (xy 71.684265 -193.934899) (xy 71.626861 -193.913124) (xy 71.5725 -193.88459)
			(xy 71.546974 -193.867532) (xy 71.538222 -193.862061) (xy 71.518018 -193.857933) (xy 71.497814 -193.862061)
			(xy 71.489062 -193.867532) (xy 71.463528 -193.884573) (xy 71.40916 -193.913083) (xy 71.351756 -193.934846)
			(xy 71.292152 -193.949545) (xy 71.231213 -193.956968) (xy 71.200518 -193.957448) (xy 71.169789 -193.956927)
			(xy 71.108779 -193.949521) (xy 71.049106 -193.934816) (xy 70.99164 -193.913025) (xy 70.937221 -193.884467)
			(xy 70.88664 -193.849557) (xy 70.840635 -193.808806) (xy 70.799878 -193.762806) (xy 70.764963 -193.712229)
			(xy 70.736398 -193.657813) (xy 70.714601 -193.60035) (xy 70.699889 -193.540678) (xy 70.692476 -193.479669)
			(xy 70.69201 -193.44894) (xy 66.520691 -193.44894) (xy 74.153271 -201.08164) (xy 79.01559 -201.08164)
			(xy 79.016054 -201.050943) (xy 79.023459 -200.989998) (xy 79.038153 -200.930389) (xy 79.059923 -200.872986)
			(xy 79.088451 -200.818623) (xy 79.105506 -200.793096) (xy 79.110943 -200.784326) (xy 79.115083 -200.764133)
			(xy 79.110969 -200.743936) (xy 79.105506 -200.735184) (xy 79.088467 -200.709649) (xy 79.059958 -200.65528)
			(xy 79.038196 -200.597877) (xy 79.023495 -200.538274) (xy 79.016071 -200.477335) (xy 79.01559 -200.44664)
			(xy 79.016054 -200.415943) (xy 79.023459 -200.354998) (xy 79.038153 -200.295389) (xy 79.059923 -200.237986)
			(xy 79.088451 -200.183623) (xy 79.105506 -200.158096) (xy 79.110943 -200.149326) (xy 79.115083 -200.129133)
			(xy 79.110969 -200.108936) (xy 79.105506 -200.100184) (xy 79.088467 -200.074649) (xy 79.059958 -200.02028)
			(xy 79.038196 -199.962877) (xy 79.023495 -199.903274) (xy 79.016071 -199.842335) (xy 79.01559 -199.81164)
			(xy 79.016054 -199.780943) (xy 79.023459 -199.719998) (xy 79.038153 -199.660389) (xy 79.059923 -199.602986)
			(xy 79.088451 -199.548623) (xy 79.105506 -199.523096) (xy 79.110943 -199.514326) (xy 79.115083 -199.494133)
			(xy 79.110969 -199.473936) (xy 79.105506 -199.465184) (xy 79.088467 -199.439649) (xy 79.059958 -199.38528)
			(xy 79.038196 -199.327877) (xy 79.023495 -199.268274) (xy 79.016071 -199.207335) (xy 79.01559 -199.17664)
			(xy 79.016054 -199.145943) (xy 79.023459 -199.084998) (xy 79.038153 -199.025389) (xy 79.059923 -198.967986)
			(xy 79.088451 -198.913623) (xy 79.105506 -198.888096) (xy 79.110943 -198.879326) (xy 79.115083 -198.859133)
			(xy 79.110969 -198.838936) (xy 79.105506 -198.830184) (xy 79.088467 -198.804649) (xy 79.059958 -198.75028)
			(xy 79.038196 -198.692877) (xy 79.023495 -198.633274) (xy 79.016071 -198.572335) (xy 79.01559 -198.54164)
			(xy 79.016054 -198.510943) (xy 79.023459 -198.449998) (xy 79.038153 -198.390389) (xy 79.059923 -198.332986)
			(xy 79.088451 -198.278623) (xy 79.105506 -198.253096) (xy 79.110943 -198.244326) (xy 79.115083 -198.224133)
			(xy 79.110969 -198.203936) (xy 79.105506 -198.195184) (xy 79.088467 -198.169649) (xy 79.059958 -198.11528)
			(xy 79.038196 -198.057877) (xy 79.023495 -197.998274) (xy 79.016071 -197.937335) (xy 79.01559 -197.90664)
			(xy 79.016054 -197.875943) (xy 79.023459 -197.814998) (xy 79.038153 -197.755389) (xy 79.059923 -197.697986)
			(xy 79.088451 -197.643623) (xy 79.105506 -197.618096) (xy 79.110943 -197.609326) (xy 79.115083 -197.589133)
			(xy 79.110969 -197.568936) (xy 79.105506 -197.560184) (xy 79.088467 -197.534649) (xy 79.059958 -197.48028)
			(xy 79.038196 -197.422877) (xy 79.023495 -197.363274) (xy 79.016071 -197.302335) (xy 79.01559 -197.27164)
			(xy 79.016054 -197.240943) (xy 79.023459 -197.179998) (xy 79.038153 -197.120389) (xy 79.059923 -197.062986)
			(xy 79.088451 -197.008623) (xy 79.105506 -196.983096) (xy 79.110943 -196.974326) (xy 79.115083 -196.954133)
			(xy 79.110969 -196.933936) (xy 79.105506 -196.925184) (xy 79.088467 -196.899649) (xy 79.059958 -196.84528)
			(xy 79.038196 -196.787877) (xy 79.023495 -196.728274) (xy 79.016071 -196.667335) (xy 79.01559 -196.63664)
			(xy 79.016054 -196.605943) (xy 79.023459 -196.544998) (xy 79.038153 -196.485389) (xy 79.059923 -196.427986)
			(xy 79.088451 -196.373623) (xy 79.105506 -196.348096) (xy 79.110943 -196.339326) (xy 79.115083 -196.319133)
			(xy 79.110969 -196.298936) (xy 79.105506 -196.290184) (xy 79.088467 -196.264649) (xy 79.059958 -196.21028)
			(xy 79.038196 -196.152877) (xy 79.023495 -196.093274) (xy 79.016071 -196.032335) (xy 79.01559 -196.00164)
			(xy 79.016054 -195.970943) (xy 79.023459 -195.909998) (xy 79.038153 -195.850389) (xy 79.059923 -195.792986)
			(xy 79.088451 -195.738623) (xy 79.105506 -195.713096) (xy 79.110943 -195.704326) (xy 79.115083 -195.684133)
			(xy 79.110969 -195.663936) (xy 79.105506 -195.655184) (xy 79.088467 -195.629649) (xy 79.059958 -195.57528)
			(xy 79.038196 -195.517877) (xy 79.023495 -195.458274) (xy 79.016071 -195.397335) (xy 79.01559 -195.36664)
			(xy 79.016059 -195.335483) (xy 79.023679 -195.273636) (xy 79.038798 -195.213184) (xy 79.06119 -195.155031)
			(xy 79.090518 -195.10005) (xy 79.108046 -195.074286) (xy 79.11364 -195.065485) (xy 79.117851 -195.04508)
			(xy 79.113624 -195.024678) (xy 79.108046 -195.015866) (xy 79.090527 -194.990096) (xy 79.061194 -194.935118)
			(xy 79.038799 -194.876967) (xy 79.02368 -194.816516) (xy 79.016062 -194.754669) (xy 79.01559 -194.723512)
			(xy 79.016049 -194.69278) (xy 79.023456 -194.631765) (xy 79.038164 -194.572087) (xy 79.059958 -194.514617)
			(xy 79.088521 -194.460193) (xy 79.123435 -194.409609) (xy 79.164193 -194.363602) (xy 79.210198 -194.322844)
			(xy 79.260781 -194.287928) (xy 79.315204 -194.259364) (xy 79.372673 -194.237568) (xy 79.432351 -194.222859)
			(xy 79.493366 -194.21545) (xy 79.524098 -194.215004) (xy 79.554795 -194.215446) (xy 79.615741 -194.222856)
			(xy 79.67535 -194.237555) (xy 79.732754 -194.25933) (xy 79.787115 -194.287863) (xy 79.812642 -194.30492)
			(xy 79.821394 -194.310391) (xy 79.841598 -194.314519) (xy 79.861802 -194.310391) (xy 79.870554 -194.30492)
			(xy 79.89608 -194.287866) (xy 79.950451 -194.259359) (xy 80.007856 -194.2376) (xy 80.067462 -194.222903)
			(xy 80.128403 -194.215483) (xy 80.159098 -194.215004) (xy 80.189795 -194.215446) (xy 80.250741 -194.222856)
			(xy 80.31035 -194.237555) (xy 80.367754 -194.25933) (xy 80.422115 -194.287863) (xy 80.447642 -194.30492)
			(xy 80.456394 -194.310391) (xy 80.476598 -194.314519) (xy 80.496802 -194.310391) (xy 80.505554 -194.30492)
			(xy 80.53108 -194.287866) (xy 80.585451 -194.259359) (xy 80.642856 -194.2376) (xy 80.702462 -194.222903)
			(xy 80.763403 -194.215483) (xy 80.794098 -194.215004) (xy 80.824831 -194.21544) (xy 80.885847 -194.222848)
			(xy 80.945526 -194.237558) (xy 81.002997 -194.259354) (xy 81.057422 -194.287918) (xy 81.108006 -194.322835)
			(xy 81.154013 -194.363594) (xy 81.194771 -194.409602) (xy 81.229687 -194.460187) (xy 81.25825 -194.514612)
			(xy 81.280045 -194.572083) (xy 81.294754 -194.631762) (xy 81.302161 -194.692779) (xy 81.302606 -194.723512)
			(xy 81.302165 -194.754141) (xy 81.294798 -194.814955) (xy 81.280184 -194.874445) (xy 81.258535 -194.93175)
			(xy 81.230163 -194.986042) (xy 81.213198 -195.011548) (xy 81.207818 -195.020287) (xy 81.20375 -195.040381)
			(xy 81.207803 -195.060478) (xy 81.213198 -195.069206) (xy 81.230327 -195.094792) (xy 81.258999 -195.149284)
			(xy 81.280889 -195.206835) (xy 81.295678 -195.266607) (xy 81.303151 -195.327725) (xy 81.303622 -195.358512)
			(xy 81.303132 -195.389208) (xy 81.295733 -195.450152) (xy 81.281044 -195.50976) (xy 81.25928 -195.567164)
			(xy 81.230758 -195.621528) (xy 81.213706 -195.647056) (xy 81.208223 -195.655802) (xy 81.204097 -195.67601)
			(xy 81.208231 -195.696216) (xy 81.213706 -195.704968) (xy 81.230769 -195.730488) (xy 81.259274 -195.784861)
			(xy 81.281031 -195.842268) (xy 81.295726 -195.901875) (xy 81.303144 -195.962816) (xy 81.303622 -195.993512)
			(xy 81.303132 -196.024208) (xy 81.295733 -196.085152) (xy 81.281044 -196.14476) (xy 81.25928 -196.202164)
			(xy 81.230758 -196.256528) (xy 81.213706 -196.282056) (xy 81.208223 -196.290802) (xy 81.204097 -196.31101)
			(xy 81.208231 -196.331216) (xy 81.213706 -196.339968) (xy 81.230769 -196.365488) (xy 81.259274 -196.419861)
			(xy 81.281031 -196.477268) (xy 81.295726 -196.536875) (xy 81.303144 -196.597816) (xy 81.303622 -196.628512)
			(xy 81.303132 -196.659208) (xy 81.295733 -196.720152) (xy 81.281044 -196.77976) (xy 81.25928 -196.837164)
			(xy 81.230758 -196.891528) (xy 81.213706 -196.917056) (xy 81.208223 -196.925802) (xy 81.204097 -196.94601)
			(xy 81.208231 -196.966216) (xy 81.213706 -196.974968) (xy 81.230769 -197.000488) (xy 81.259274 -197.054861)
			(xy 81.281031 -197.112268) (xy 81.295726 -197.171875) (xy 81.303144 -197.232816) (xy 81.303622 -197.263512)
			(xy 81.303128 -197.294761) (xy 81.295478 -197.356789) (xy 81.280282 -197.417411) (xy 81.257769 -197.475714)
			(xy 81.228279 -197.530817) (xy 81.210658 -197.556628) (xy 81.205051 -197.565422) (xy 81.200844 -197.585831)
			(xy 81.205076 -197.606236) (xy 81.210658 -197.615048) (xy 81.228079 -197.640773) (xy 81.257251 -197.695627)
			(xy 81.279521 -197.753628) (xy 81.294558 -197.81391) (xy 81.302136 -197.875575) (xy 81.302606 -197.90664)
			(xy 81.302133 -197.937336) (xy 81.29473 -197.998281) (xy 81.280038 -198.05789) (xy 81.25827 -198.115294)
			(xy 81.229744 -198.169657) (xy 81.21269 -198.195184) (xy 81.207184 -198.203918) (xy 81.203068 -198.224133)
			(xy 81.20721 -198.244344) (xy 81.21269 -198.253096) (xy 81.22972 -198.278637) (xy 81.258231 -198.333004)
			(xy 81.279995 -198.390405) (xy 81.294697 -198.450008) (xy 81.302124 -198.510946) (xy 81.302606 -198.54164)
			(xy 81.302133 -198.572336) (xy 81.29473 -198.633281) (xy 81.280038 -198.69289) (xy 81.25827 -198.750294)
			(xy 81.229744 -198.804657) (xy 81.21269 -198.830184) (xy 81.207184 -198.838918) (xy 81.203068 -198.859133)
			(xy 81.20721 -198.879344) (xy 81.21269 -198.888096) (xy 81.22972 -198.913637) (xy 81.258231 -198.968004)
			(xy 81.279995 -199.025405) (xy 81.294697 -199.085008) (xy 81.302124 -199.145946) (xy 81.302606 -199.17664)
			(xy 81.302133 -199.207336) (xy 81.29473 -199.268281) (xy 81.280038 -199.32789) (xy 81.25827 -199.385294)
			(xy 81.229744 -199.439657) (xy 81.21269 -199.465184) (xy 81.207184 -199.473918) (xy 81.203068 -199.494133)
			(xy 81.20721 -199.514344) (xy 81.21269 -199.523096) (xy 81.22972 -199.548637) (xy 81.258231 -199.603004)
			(xy 81.279995 -199.660405) (xy 81.294697 -199.720008) (xy 81.302124 -199.780946) (xy 81.302606 -199.81164)
			(xy 81.302133 -199.842336) (xy 81.29473 -199.903281) (xy 81.280038 -199.96289) (xy 81.25827 -200.020294)
			(xy 81.229744 -200.074657) (xy 81.21269 -200.100184) (xy 81.207184 -200.108918) (xy 81.203068 -200.129133)
			(xy 81.20721 -200.149344) (xy 81.21269 -200.158096) (xy 81.22972 -200.183637) (xy 81.258231 -200.238004)
			(xy 81.279995 -200.295405) (xy 81.294697 -200.355008) (xy 81.302124 -200.415946) (xy 81.302606 -200.44664)
			(xy 81.302133 -200.477336) (xy 81.29473 -200.538281) (xy 81.280038 -200.59789) (xy 81.25827 -200.655294)
			(xy 81.229744 -200.709657) (xy 81.21269 -200.735184) (xy 81.207184 -200.743918) (xy 81.203068 -200.764133)
			(xy 81.20721 -200.784344) (xy 81.21269 -200.793096) (xy 81.22972 -200.818637) (xy 81.258231 -200.873004)
			(xy 81.279995 -200.930405) (xy 81.294697 -200.990008) (xy 81.302124 -201.050946) (xy 81.302606 -201.08164)
			(xy 83.02879 -201.08164) (xy 83.029254 -201.050943) (xy 83.036659 -200.989998) (xy 83.051353 -200.930389)
			(xy 83.073123 -200.872986) (xy 83.101651 -200.818623) (xy 83.118706 -200.793096) (xy 83.124143 -200.784326)
			(xy 83.128283 -200.764133) (xy 83.124169 -200.743936) (xy 83.118706 -200.735184) (xy 83.101667 -200.709649)
			(xy 83.073158 -200.65528) (xy 83.051396 -200.597877) (xy 83.036695 -200.538274) (xy 83.029271 -200.477335)
			(xy 83.02879 -200.44664) (xy 83.029254 -200.415943) (xy 83.036659 -200.354998) (xy 83.051353 -200.295389)
			(xy 83.073123 -200.237986) (xy 83.101651 -200.183623) (xy 83.118706 -200.158096) (xy 83.124143 -200.149326)
			(xy 83.128283 -200.129133) (xy 83.124169 -200.108936) (xy 83.118706 -200.100184) (xy 83.101667 -200.074649)
			(xy 83.073158 -200.02028) (xy 83.051396 -199.962877) (xy 83.036695 -199.903274) (xy 83.029271 -199.842335)
			(xy 83.02879 -199.81164) (xy 83.029254 -199.780943) (xy 83.036659 -199.719998) (xy 83.051353 -199.660389)
			(xy 83.073123 -199.602986) (xy 83.101651 -199.548623) (xy 83.118706 -199.523096) (xy 83.124143 -199.514326)
			(xy 83.128283 -199.494133) (xy 83.124169 -199.473936) (xy 83.118706 -199.465184) (xy 83.101667 -199.439649)
			(xy 83.073158 -199.38528) (xy 83.051396 -199.327877) (xy 83.036695 -199.268274) (xy 83.029271 -199.207335)
			(xy 83.02879 -199.17664) (xy 83.029254 -199.145943) (xy 83.036659 -199.084998) (xy 83.051353 -199.025389)
			(xy 83.073123 -198.967986) (xy 83.101651 -198.913623) (xy 83.118706 -198.888096) (xy 83.124143 -198.879326)
			(xy 83.128283 -198.859133) (xy 83.124169 -198.838936) (xy 83.118706 -198.830184) (xy 83.101667 -198.804649)
			(xy 83.073158 -198.75028) (xy 83.051396 -198.692877) (xy 83.036695 -198.633274) (xy 83.029271 -198.572335)
			(xy 83.02879 -198.54164) (xy 83.029254 -198.510943) (xy 83.036659 -198.449998) (xy 83.051353 -198.390389)
			(xy 83.073123 -198.332986) (xy 83.101651 -198.278623) (xy 83.118706 -198.253096) (xy 83.124143 -198.244326)
			(xy 83.128283 -198.224133) (xy 83.124169 -198.203936) (xy 83.118706 -198.195184) (xy 83.101667 -198.169649)
			(xy 83.073158 -198.11528) (xy 83.051396 -198.057877) (xy 83.036695 -197.998274) (xy 83.029271 -197.937335)
			(xy 83.02879 -197.90664) (xy 83.029257 -197.87539) (xy 83.036913 -197.813361) (xy 83.052116 -197.752738)
			(xy 83.074634 -197.694436) (xy 83.10413 -197.639335) (xy 83.121754 -197.613524) (xy 83.127314 -197.604705)
			(xy 83.131535 -197.584312) (xy 83.127324 -197.563916) (xy 83.121754 -197.555104) (xy 83.104314 -197.529392)
			(xy 83.075144 -197.474534) (xy 83.052878 -197.41653) (xy 83.037846 -197.356245) (xy 83.030273 -197.294577)
			(xy 83.029806 -197.263512) (xy 83.030253 -197.232815) (xy 83.037661 -197.171869) (xy 83.052359 -197.11226)
			(xy 83.074133 -197.054856) (xy 83.102665 -197.000495) (xy 83.119722 -196.974968) (xy 83.125182 -196.96621)
			(xy 83.129312 -196.94601) (xy 83.12519 -196.925808) (xy 83.119722 -196.917056) (xy 83.102672 -196.891527)
			(xy 83.074165 -196.837157) (xy 83.052405 -196.779752) (xy 83.037707 -196.720147) (xy 83.030285 -196.659207)
			(xy 83.029806 -196.628512) (xy 83.030253 -196.597815) (xy 83.037661 -196.536869) (xy 83.052359 -196.47726)
			(xy 83.074133 -196.419856) (xy 83.102665 -196.365495) (xy 83.119722 -196.339968) (xy 83.125182 -196.33121)
			(xy 83.129312 -196.31101) (xy 83.12519 -196.290808) (xy 83.119722 -196.282056) (xy 83.102672 -196.256527)
			(xy 83.074165 -196.202157) (xy 83.052405 -196.144752) (xy 83.037707 -196.085147) (xy 83.030285 -196.024207)
			(xy 83.029806 -195.993512) (xy 83.030253 -195.962815) (xy 83.037661 -195.901869) (xy 83.052359 -195.84226)
			(xy 83.074133 -195.784856) (xy 83.102665 -195.730495) (xy 83.119722 -195.704968) (xy 83.125182 -195.69621)
			(xy 83.129312 -195.67601) (xy 83.12519 -195.655808) (xy 83.119722 -195.647056) (xy 83.102672 -195.621527)
			(xy 83.074165 -195.567157) (xy 83.052405 -195.509752) (xy 83.037707 -195.450147) (xy 83.030285 -195.389207)
			(xy 83.029806 -195.358512) (xy 83.030257 -195.327883) (xy 83.037622 -195.26707) (xy 83.052233 -195.20758)
			(xy 83.07388 -195.150274) (xy 83.102249 -195.095982) (xy 83.119214 -195.070476) (xy 83.124639 -195.061746)
			(xy 83.12878 -195.041639) (xy 83.12467 -195.021526) (xy 83.119214 -195.012818) (xy 83.102053 -194.987252)
			(xy 83.073387 -194.932755) (xy 83.051503 -194.875198) (xy 83.036721 -194.815423) (xy 83.029256 -194.7543)
			(xy 83.02879 -194.723512) (xy 83.029249 -194.69278) (xy 83.036656 -194.631765) (xy 83.051364 -194.572087)
			(xy 83.073158 -194.514617) (xy 83.101721 -194.460193) (xy 83.136635 -194.409609) (xy 83.177393 -194.363602)
			(xy 83.223398 -194.322844) (xy 83.273981 -194.287928) (xy 83.328404 -194.259364) (xy 83.385873 -194.237568)
			(xy 83.445551 -194.222859) (xy 83.506566 -194.21545) (xy 83.537298 -194.215004) (xy 83.567995 -194.215446)
			(xy 83.628941 -194.222856) (xy 83.68855 -194.237555) (xy 83.745954 -194.25933) (xy 83.800315 -194.287863)
			(xy 83.825842 -194.30492) (xy 83.834594 -194.310391) (xy 83.854798 -194.314519) (xy 83.875002 -194.310391)
			(xy 83.883754 -194.30492) (xy 83.90928 -194.287866) (xy 83.963651 -194.259359) (xy 84.021056 -194.2376)
			(xy 84.080662 -194.222903) (xy 84.141603 -194.215483) (xy 84.172298 -194.215004) (xy 84.202995 -194.215446)
			(xy 84.263941 -194.222856) (xy 84.32355 -194.237555) (xy 84.380954 -194.25933) (xy 84.435315 -194.287863)
			(xy 84.460842 -194.30492) (xy 84.469594 -194.310391) (xy 84.489798 -194.314519) (xy 84.510002 -194.310391)
			(xy 84.518754 -194.30492) (xy 84.54428 -194.287866) (xy 84.598651 -194.259359) (xy 84.656056 -194.2376)
			(xy 84.715662 -194.222903) (xy 84.776603 -194.215483) (xy 84.807298 -194.215004) (xy 84.838031 -194.21544)
			(xy 84.899047 -194.222848) (xy 84.958726 -194.237558) (xy 85.016197 -194.259354) (xy 85.070622 -194.287918)
			(xy 85.121206 -194.322835) (xy 85.167213 -194.363594) (xy 85.207971 -194.409602) (xy 85.242887 -194.460187)
			(xy 85.27145 -194.514612) (xy 85.293245 -194.572083) (xy 85.307954 -194.631762) (xy 85.315361 -194.692779)
			(xy 85.315806 -194.723512) (xy 85.315318 -194.754391) (xy 85.307811 -194.815691) (xy 85.292944 -194.875633)
			(xy 85.270937 -194.933338) (xy 85.242112 -194.987956) (xy 85.224874 -195.01358) (xy 85.219427 -195.022401)
			(xy 85.215356 -195.042709) (xy 85.21959 -195.062982) (xy 85.225128 -195.071746) (xy 85.242507 -195.097458)
			(xy 85.271603 -195.152277) (xy 85.293812 -195.210229) (xy 85.308805 -195.270453) (xy 85.316358 -195.332053)
			(xy 85.316822 -195.363084) (xy 85.316368 -195.393781) (xy 85.308961 -195.454726) (xy 85.294264 -195.514335)
			(xy 85.272492 -195.571739) (xy 85.243961 -195.626101) (xy 85.226906 -195.651628) (xy 85.221447 -195.660387)
			(xy 85.217313 -195.680587) (xy 85.221436 -195.700789) (xy 85.226906 -195.70954) (xy 85.243957 -195.735068)
			(xy 85.272464 -195.789438) (xy 85.294223 -195.846843) (xy 85.308921 -195.906449) (xy 85.316342 -195.967389)
			(xy 85.316822 -195.998084) (xy 85.316368 -196.028781) (xy 85.308961 -196.089726) (xy 85.294264 -196.149335)
			(xy 85.272492 -196.206739) (xy 85.243961 -196.261101) (xy 85.226906 -196.286628) (xy 85.221447 -196.295387)
			(xy 85.217313 -196.315587) (xy 85.221436 -196.335789) (xy 85.226906 -196.34454) (xy 85.243957 -196.370068)
			(xy 85.272464 -196.424438) (xy 85.294223 -196.481843) (xy 85.308921 -196.541449) (xy 85.316342 -196.602389)
			(xy 85.316822 -196.633084) (xy 85.316368 -196.663781) (xy 85.308961 -196.724726) (xy 85.294264 -196.784335)
			(xy 85.272492 -196.841739) (xy 85.243961 -196.896101) (xy 85.226906 -196.921628) (xy 85.221447 -196.930387)
			(xy 85.217313 -196.950587) (xy 85.221436 -196.970789) (xy 85.226906 -196.97954) (xy 85.243957 -197.005068)
			(xy 85.272464 -197.059438) (xy 85.294223 -197.116843) (xy 85.308921 -197.176449) (xy 85.316342 -197.237389)
			(xy 85.316822 -197.268084) (xy 85.316335 -197.299057) (xy 85.308809 -197.360543) (xy 85.293866 -197.420659)
			(xy 85.271729 -197.478513) (xy 85.242725 -197.533248) (xy 85.225382 -197.558914) (xy 85.219883 -197.567704)
			(xy 85.21573 -197.587998) (xy 85.219881 -197.608292) (xy 85.225382 -197.61708) (xy 85.24253 -197.642685)
			(xy 85.271224 -197.697223) (xy 85.293122 -197.754827) (xy 85.307904 -197.814653) (xy 85.315353 -197.875827)
			(xy 85.315806 -197.90664) (xy 85.315333 -197.937336) (xy 85.30793 -197.998281) (xy 85.293238 -198.05789)
			(xy 85.27147 -198.115294) (xy 85.242944 -198.169657) (xy 85.22589 -198.195184) (xy 85.220384 -198.203918)
			(xy 85.216268 -198.224133) (xy 85.22041 -198.244344) (xy 85.22589 -198.253096) (xy 85.24292 -198.278637)
			(xy 85.271431 -198.333004) (xy 85.293195 -198.390405) (xy 85.307897 -198.450008) (xy 85.315324 -198.510946)
			(xy 85.315806 -198.54164) (xy 85.315333 -198.572336) (xy 85.30793 -198.633281) (xy 85.293238 -198.69289)
			(xy 85.27147 -198.750294) (xy 85.242944 -198.804657) (xy 85.22589 -198.830184) (xy 85.220384 -198.838918)
			(xy 85.216268 -198.859133) (xy 85.22041 -198.879344) (xy 85.22589 -198.888096) (xy 85.24292 -198.913637)
			(xy 85.271431 -198.968004) (xy 85.293195 -199.025405) (xy 85.307897 -199.085008) (xy 85.315324 -199.145946)
			(xy 85.315806 -199.17664) (xy 85.315333 -199.207336) (xy 85.30793 -199.268281) (xy 85.293238 -199.32789)
			(xy 85.27147 -199.385294) (xy 85.242944 -199.439657) (xy 85.22589 -199.465184) (xy 85.220384 -199.473918)
			(xy 85.216268 -199.494133) (xy 85.22041 -199.514344) (xy 85.22589 -199.523096) (xy 85.24292 -199.548637)
			(xy 85.271431 -199.603004) (xy 85.293195 -199.660405) (xy 85.307897 -199.720008) (xy 85.315324 -199.780946)
			(xy 85.315806 -199.81164) (xy 85.315333 -199.842336) (xy 85.30793 -199.903281) (xy 85.293238 -199.96289)
			(xy 85.27147 -200.020294) (xy 85.242944 -200.074657) (xy 85.22589 -200.100184) (xy 85.220384 -200.108918)
			(xy 85.216268 -200.129133) (xy 85.22041 -200.149344) (xy 85.22589 -200.158096) (xy 85.24292 -200.183637)
			(xy 85.271431 -200.238004) (xy 85.293195 -200.295405) (xy 85.307897 -200.355008) (xy 85.315324 -200.415946)
			(xy 85.315806 -200.44664) (xy 85.315333 -200.477336) (xy 85.30793 -200.538281) (xy 85.293238 -200.59789)
			(xy 85.27147 -200.655294) (xy 85.242944 -200.709657) (xy 85.22589 -200.735184) (xy 85.220384 -200.743918)
			(xy 85.216268 -200.764133) (xy 85.22041 -200.784344) (xy 85.22589 -200.793096) (xy 85.24292 -200.818637)
			(xy 85.271431 -200.873004) (xy 85.293195 -200.930405) (xy 85.307897 -200.990008) (xy 85.315324 -201.050946)
			(xy 85.315399 -201.055732) (xy 87.388446 -201.055732) (xy 87.388896 -201.025035) (xy 87.396302 -200.964089)
			(xy 87.411 -200.90448) (xy 87.432773 -200.847076) (xy 87.461305 -200.792714) (xy 87.478362 -200.767188)
			(xy 87.48381 -200.758423) (xy 87.487951 -200.738227) (xy 87.483831 -200.718026) (xy 87.478362 -200.709276)
			(xy 87.461326 -200.683739) (xy 87.432815 -200.629371) (xy 87.411052 -200.571969) (xy 87.396351 -200.512365)
			(xy 87.388927 -200.451426) (xy 87.388446 -200.420732) (xy 87.388896 -200.390035) (xy 87.396302 -200.329089)
			(xy 87.411 -200.26948) (xy 87.432773 -200.212076) (xy 87.461305 -200.157714) (xy 87.478362 -200.132188)
			(xy 87.48381 -200.123423) (xy 87.487951 -200.103227) (xy 87.483831 -200.083026) (xy 87.478362 -200.074276)
			(xy 87.461326 -200.048739) (xy 87.432815 -199.994371) (xy 87.411052 -199.936969) (xy 87.396351 -199.877365)
			(xy 87.388927 -199.816426) (xy 87.388446 -199.785732) (xy 87.388896 -199.755035) (xy 87.396302 -199.694089)
			(xy 87.411 -199.63448) (xy 87.432773 -199.577076) (xy 87.461305 -199.522714) (xy 87.478362 -199.497188)
			(xy 87.48381 -199.488423) (xy 87.487951 -199.468227) (xy 87.483831 -199.448026) (xy 87.478362 -199.439276)
			(xy 87.461326 -199.413739) (xy 87.432815 -199.359371) (xy 87.411052 -199.301969) (xy 87.396351 -199.242365)
			(xy 87.388927 -199.181426) (xy 87.388446 -199.150732) (xy 87.388896 -199.120035) (xy 87.396302 -199.059089)
			(xy 87.411 -198.99948) (xy 87.432773 -198.942076) (xy 87.461305 -198.887714) (xy 87.478362 -198.862188)
			(xy 87.48381 -198.853423) (xy 87.487951 -198.833227) (xy 87.483831 -198.813026) (xy 87.478362 -198.804276)
			(xy 87.461326 -198.778739) (xy 87.432815 -198.724371) (xy 87.411052 -198.666969) (xy 87.396351 -198.607365)
			(xy 87.388927 -198.546426) (xy 87.388446 -198.515732) (xy 87.388896 -198.485035) (xy 87.396302 -198.424089)
			(xy 87.411 -198.36448) (xy 87.432773 -198.307076) (xy 87.461305 -198.252714) (xy 87.478362 -198.227188)
			(xy 87.48381 -198.218423) (xy 87.487951 -198.198227) (xy 87.483831 -198.178026) (xy 87.478362 -198.169276)
			(xy 87.461326 -198.143739) (xy 87.432815 -198.089371) (xy 87.411052 -198.031969) (xy 87.396351 -197.972365)
			(xy 87.388927 -197.911426) (xy 87.388446 -197.880732) (xy 87.388896 -197.850035) (xy 87.396302 -197.789089)
			(xy 87.411 -197.72948) (xy 87.432773 -197.672076) (xy 87.461305 -197.617714) (xy 87.478362 -197.592188)
			(xy 87.48381 -197.583423) (xy 87.487951 -197.563227) (xy 87.483831 -197.543026) (xy 87.478362 -197.534276)
			(xy 87.461326 -197.508739) (xy 87.432815 -197.454371) (xy 87.411052 -197.396969) (xy 87.396351 -197.337365)
			(xy 87.388927 -197.276426) (xy 87.388446 -197.245732) (xy 87.388896 -197.215035) (xy 87.396302 -197.154089)
			(xy 87.411 -197.09448) (xy 87.432773 -197.037076) (xy 87.461305 -196.982714) (xy 87.478362 -196.957188)
			(xy 87.48381 -196.948423) (xy 87.487951 -196.928227) (xy 87.483831 -196.908026) (xy 87.478362 -196.899276)
			(xy 87.461326 -196.873739) (xy 87.432815 -196.819371) (xy 87.411052 -196.761969) (xy 87.396351 -196.702365)
			(xy 87.388927 -196.641426) (xy 87.388446 -196.610732) (xy 87.388896 -196.580035) (xy 87.396302 -196.519089)
			(xy 87.411 -196.45948) (xy 87.432773 -196.402076) (xy 87.461305 -196.347714) (xy 87.478362 -196.322188)
			(xy 87.48381 -196.313423) (xy 87.487951 -196.293227) (xy 87.483831 -196.273026) (xy 87.478362 -196.264276)
			(xy 87.461326 -196.238739) (xy 87.432815 -196.184371) (xy 87.411052 -196.126969) (xy 87.396351 -196.067365)
			(xy 87.388927 -196.006426) (xy 87.388446 -195.975732) (xy 87.388896 -195.945035) (xy 87.396302 -195.884089)
			(xy 87.411 -195.82448) (xy 87.432773 -195.767076) (xy 87.461305 -195.712714) (xy 87.478362 -195.687188)
			(xy 87.48381 -195.678423) (xy 87.487951 -195.658227) (xy 87.483831 -195.638026) (xy 87.478362 -195.629276)
			(xy 87.461326 -195.603739) (xy 87.432815 -195.549371) (xy 87.411052 -195.491969) (xy 87.396351 -195.432365)
			(xy 87.388927 -195.371426) (xy 87.388446 -195.340732) (xy 87.38898 -195.307811) (xy 87.397479 -195.242519)
			(xy 87.414338 -195.178871) (xy 87.439276 -195.117934) (xy 87.471875 -195.060727) (xy 87.491316 -195.034154)
			(xy 87.497155 -195.025574) (xy 87.502125 -195.005446) (xy 87.498767 -194.984989) (xy 87.493602 -194.975988)
			(xy 87.478261 -194.951321) (xy 87.452628 -194.899193) (xy 87.433095 -194.844486) (xy 87.419916 -194.787912)
			(xy 87.413263 -194.730204) (xy 87.41283 -194.70116) (xy 87.413218 -194.670427) (xy 87.420632 -194.609409)
			(xy 87.435346 -194.549729) (xy 87.457147 -194.492259) (xy 87.485717 -194.437835) (xy 87.520638 -194.387251)
			(xy 87.561401 -194.341246) (xy 87.607413 -194.300489) (xy 87.658001 -194.265576) (xy 87.71243 -194.237015)
			(xy 87.769904 -194.215223) (xy 87.829585 -194.200518) (xy 87.890605 -194.193113) (xy 87.921338 -194.192652)
			(xy 87.952035 -194.193116) (xy 88.01298 -194.200519) (xy 88.072589 -194.215213) (xy 88.129993 -194.236983)
			(xy 88.184355 -194.265513) (xy 88.209882 -194.282568) (xy 88.218634 -194.288039) (xy 88.238838 -194.292167)
			(xy 88.259042 -194.288039) (xy 88.267794 -194.282568) (xy 88.29334 -194.265546) (xy 88.347705 -194.237033)
			(xy 88.405105 -194.215266) (xy 88.464707 -194.200562) (xy 88.525644 -194.193134) (xy 88.556338 -194.192652)
			(xy 88.587035 -194.193116) (xy 88.64798 -194.200519) (xy 88.707589 -194.215213) (xy 88.764993 -194.236983)
			(xy 88.819355 -194.265513) (xy 88.844882 -194.282568) (xy 88.853634 -194.288039) (xy 88.873838 -194.292167)
			(xy 88.894042 -194.288039) (xy 88.902794 -194.282568) (xy 88.92834 -194.265546) (xy 88.982705 -194.237033)
			(xy 89.040105 -194.215266) (xy 89.099707 -194.200562) (xy 89.160644 -194.193134) (xy 89.191338 -194.192652)
			(xy 89.222068 -194.19312) (xy 89.28308 -194.200532) (xy 89.342754 -194.215243) (xy 89.40022 -194.23704)
			(xy 89.45464 -194.265604) (xy 89.505221 -194.300518) (xy 89.551224 -194.341274) (xy 89.591981 -194.387278)
			(xy 89.626895 -194.437858) (xy 89.655459 -194.492278) (xy 89.677256 -194.549744) (xy 89.691968 -194.609418)
			(xy 89.69938 -194.67043) (xy 89.699846 -194.70116) (xy 91.42603 -194.70116) (xy 91.426418 -194.670427)
			(xy 91.433832 -194.609409) (xy 91.448546 -194.549729) (xy 91.470347 -194.492259) (xy 91.498917 -194.437835)
			(xy 91.533838 -194.387251) (xy 91.574601 -194.341246) (xy 91.620613 -194.300489) (xy 91.671201 -194.265576)
			(xy 91.72563 -194.237015) (xy 91.783104 -194.215223) (xy 91.842785 -194.200518) (xy 91.903805 -194.193113)
			(xy 91.934538 -194.192652) (xy 91.965235 -194.193116) (xy 92.02618 -194.200519) (xy 92.085789 -194.215213)
			(xy 92.143193 -194.236983) (xy 92.197555 -194.265513) (xy 92.223082 -194.282568) (xy 92.231834 -194.288039)
			(xy 92.252038 -194.292167) (xy 92.272242 -194.288039) (xy 92.280994 -194.282568) (xy 92.30654 -194.265546)
			(xy 92.360905 -194.237033) (xy 92.418305 -194.215266) (xy 92.477907 -194.200562) (xy 92.538844 -194.193134)
			(xy 92.569538 -194.192652) (xy 92.600235 -194.193116) (xy 92.66118 -194.200519) (xy 92.720789 -194.215213)
			(xy 92.778193 -194.236983) (xy 92.832555 -194.265513) (xy 92.858082 -194.282568) (xy 92.866834 -194.288039)
			(xy 92.887038 -194.292167) (xy 92.907242 -194.288039) (xy 92.915994 -194.282568) (xy 92.94154 -194.265546)
			(xy 92.995905 -194.237033) (xy 93.053305 -194.215266) (xy 93.112907 -194.200562) (xy 93.173844 -194.193134)
			(xy 93.204538 -194.192652) (xy 93.235268 -194.19312) (xy 93.29628 -194.200532) (xy 93.355954 -194.215243)
			(xy 93.41342 -194.23704) (xy 93.46784 -194.265604) (xy 93.518421 -194.300518) (xy 93.564424 -194.341274)
			(xy 93.605181 -194.387278) (xy 93.640095 -194.437858) (xy 93.668659 -194.492278) (xy 93.690456 -194.549744)
			(xy 93.705168 -194.609418) (xy 93.71258 -194.67043) (xy 93.713046 -194.70116) (xy 93.712575 -194.732039)
			(xy 93.705063 -194.79334) (xy 93.690192 -194.853282) (xy 93.668181 -194.910986) (xy 93.639353 -194.965605)
			(xy 93.622114 -194.991228) (xy 93.616622 -195.000026) (xy 93.612561 -195.020349) (xy 93.616817 -195.040631)
			(xy 93.622368 -195.049394) (xy 93.63976 -195.075098) (xy 93.668855 -195.129918) (xy 93.691062 -195.187872)
			(xy 93.706051 -195.248098) (xy 93.7136 -195.3097) (xy 93.714062 -195.340732) (xy 93.713592 -195.371428)
			(xy 93.70619 -195.432374) (xy 93.691498 -195.491983) (xy 93.669729 -195.549387) (xy 93.641201 -195.603749)
			(xy 93.624146 -195.629276) (xy 93.618651 -195.638015) (xy 93.614536 -195.658227) (xy 93.618672 -195.678434)
			(xy 93.624146 -195.687188) (xy 93.641167 -195.712735) (xy 93.66968 -195.7671) (xy 93.691447 -195.8245)
			(xy 93.706151 -195.884101) (xy 93.713579 -195.945038) (xy 93.714062 -195.975732) (xy 93.713592 -196.006428)
			(xy 93.70619 -196.067374) (xy 93.691498 -196.126983) (xy 93.669729 -196.184387) (xy 93.641201 -196.238749)
			(xy 93.624146 -196.264276) (xy 93.618651 -196.273015) (xy 93.614536 -196.293227) (xy 93.618672 -196.313434)
			(xy 93.624146 -196.322188) (xy 93.641167 -196.347735) (xy 93.66968 -196.4021) (xy 93.691447 -196.4595)
			(xy 93.706151 -196.519101) (xy 93.713579 -196.580038) (xy 93.714062 -196.610732) (xy 93.713592 -196.641428)
			(xy 93.70619 -196.702374) (xy 93.691498 -196.761983) (xy 93.669729 -196.819387) (xy 93.641201 -196.873749)
			(xy 93.624146 -196.899276) (xy 93.618651 -196.908015) (xy 93.614536 -196.928227) (xy 93.618672 -196.948434)
			(xy 93.624146 -196.957188) (xy 93.641167 -196.982735) (xy 93.66968 -197.0371) (xy 93.691447 -197.0945)
			(xy 93.706151 -197.154101) (xy 93.713579 -197.215038) (xy 93.714062 -197.245732) (xy 93.713592 -197.276428)
			(xy 93.70619 -197.337374) (xy 93.691498 -197.396983) (xy 93.669729 -197.454387) (xy 93.641201 -197.508749)
			(xy 93.624146 -197.534276) (xy 93.618651 -197.543015) (xy 93.614536 -197.563227) (xy 93.618672 -197.583434)
			(xy 93.624146 -197.592188) (xy 93.641167 -197.617735) (xy 93.66968 -197.6721) (xy 93.691447 -197.7295)
			(xy 93.706151 -197.789101) (xy 93.713579 -197.850038) (xy 93.714062 -197.880732) (xy 93.713592 -197.911428)
			(xy 93.70619 -197.972374) (xy 93.691498 -198.031983) (xy 93.669729 -198.089387) (xy 93.641201 -198.143749)
			(xy 93.624146 -198.169276) (xy 93.618651 -198.178015) (xy 93.614536 -198.198227) (xy 93.618672 -198.218434)
			(xy 93.624146 -198.227188) (xy 93.641167 -198.252735) (xy 93.66968 -198.3071) (xy 93.691447 -198.3645)
			(xy 93.706151 -198.424101) (xy 93.713579 -198.485038) (xy 93.714062 -198.515732) (xy 93.713592 -198.546428)
			(xy 93.70619 -198.607374) (xy 93.691498 -198.666983) (xy 93.669729 -198.724387) (xy 93.641201 -198.778749)
			(xy 93.624146 -198.804276) (xy 93.618651 -198.813015) (xy 93.614536 -198.833227) (xy 93.618672 -198.853434)
			(xy 93.624146 -198.862188) (xy 93.641167 -198.887735) (xy 93.66968 -198.9421) (xy 93.691447 -198.9995)
			(xy 93.706151 -199.059101) (xy 93.713579 -199.120038) (xy 93.714062 -199.150732) (xy 93.713592 -199.181428)
			(xy 93.70619 -199.242374) (xy 93.691498 -199.301983) (xy 93.669729 -199.359387) (xy 93.641201 -199.413749)
			(xy 93.624146 -199.439276) (xy 93.618651 -199.448015) (xy 93.614536 -199.468227) (xy 93.618672 -199.488434)
			(xy 93.624146 -199.497188) (xy 93.641167 -199.522735) (xy 93.66968 -199.5771) (xy 93.691447 -199.6345)
			(xy 93.706151 -199.694101) (xy 93.713579 -199.755038) (xy 93.714062 -199.785732) (xy 93.713592 -199.816428)
			(xy 93.70619 -199.877374) (xy 93.691498 -199.936983) (xy 93.669729 -199.994387) (xy 93.641201 -200.048749)
			(xy 93.624146 -200.074276) (xy 93.618651 -200.083015) (xy 93.614536 -200.103227) (xy 93.618672 -200.123434)
			(xy 93.624146 -200.132188) (xy 93.641167 -200.157735) (xy 93.66968 -200.2121) (xy 93.691447 -200.2695)
			(xy 93.706151 -200.329101) (xy 93.713579 -200.390038) (xy 93.714062 -200.420732) (xy 93.713592 -200.451428)
			(xy 93.70619 -200.512374) (xy 93.691498 -200.571983) (xy 93.669729 -200.629387) (xy 93.641201 -200.683749)
			(xy 93.624146 -200.709276) (xy 93.618651 -200.718015) (xy 93.614536 -200.738227) (xy 93.618672 -200.758434)
			(xy 93.624146 -200.767188) (xy 93.641167 -200.792735) (xy 93.66968 -200.8471) (xy 93.691447 -200.9045)
			(xy 93.706151 -200.964101) (xy 93.713579 -201.025038) (xy 93.71367 -201.03084) (xy 95.80499 -201.03084)
			(xy 95.805454 -201.000143) (xy 95.812859 -200.939198) (xy 95.827553 -200.879589) (xy 95.849323 -200.822186)
			(xy 95.877851 -200.767823) (xy 95.894906 -200.742296) (xy 95.900343 -200.733526) (xy 95.904483 -200.713333)
			(xy 95.900369 -200.693136) (xy 95.894906 -200.684384) (xy 95.877867 -200.658849) (xy 95.849358 -200.60448)
			(xy 95.827596 -200.547077) (xy 95.812895 -200.487474) (xy 95.805471 -200.426535) (xy 95.80499 -200.39584)
			(xy 95.805454 -200.365143) (xy 95.812859 -200.304198) (xy 95.827553 -200.244589) (xy 95.849323 -200.187186)
			(xy 95.877851 -200.132823) (xy 95.894906 -200.107296) (xy 95.900343 -200.098526) (xy 95.904483 -200.078333)
			(xy 95.900369 -200.058136) (xy 95.894906 -200.049384) (xy 95.877867 -200.023849) (xy 95.849358 -199.96948)
			(xy 95.827596 -199.912077) (xy 95.812895 -199.852474) (xy 95.805471 -199.791535) (xy 95.80499 -199.76084)
			(xy 95.805454 -199.730143) (xy 95.812859 -199.669198) (xy 95.827553 -199.609589) (xy 95.849323 -199.552186)
			(xy 95.877851 -199.497823) (xy 95.894906 -199.472296) (xy 95.900343 -199.463526) (xy 95.904483 -199.443333)
			(xy 95.900369 -199.423136) (xy 95.894906 -199.414384) (xy 95.877867 -199.388849) (xy 95.849358 -199.33448)
			(xy 95.827596 -199.277077) (xy 95.812895 -199.217474) (xy 95.805471 -199.156535) (xy 95.80499 -199.12584)
			(xy 95.805454 -199.095143) (xy 95.812859 -199.034198) (xy 95.827553 -198.974589) (xy 95.849323 -198.917186)
			(xy 95.877851 -198.862823) (xy 95.894906 -198.837296) (xy 95.900343 -198.828526) (xy 95.904483 -198.808333)
			(xy 95.900369 -198.788136) (xy 95.894906 -198.779384) (xy 95.877867 -198.753849) (xy 95.849358 -198.69948)
			(xy 95.827596 -198.642077) (xy 95.812895 -198.582474) (xy 95.805471 -198.521535) (xy 95.80499 -198.49084)
			(xy 95.805454 -198.460143) (xy 95.812859 -198.399198) (xy 95.827553 -198.339589) (xy 95.849323 -198.282186)
			(xy 95.877851 -198.227823) (xy 95.894906 -198.202296) (xy 95.900343 -198.193526) (xy 95.904483 -198.173333)
			(xy 95.900369 -198.153136) (xy 95.894906 -198.144384) (xy 95.877867 -198.118849) (xy 95.849358 -198.06448)
			(xy 95.827596 -198.007077) (xy 95.812895 -197.947474) (xy 95.805471 -197.886535) (xy 95.80499 -197.85584)
			(xy 95.805454 -197.825143) (xy 95.812859 -197.764198) (xy 95.827553 -197.704589) (xy 95.849323 -197.647186)
			(xy 95.877851 -197.592823) (xy 95.894906 -197.567296) (xy 95.900343 -197.558526) (xy 95.904483 -197.538333)
			(xy 95.900369 -197.518136) (xy 95.894906 -197.509384) (xy 95.877867 -197.483849) (xy 95.849358 -197.42948)
			(xy 95.827596 -197.372077) (xy 95.812895 -197.312474) (xy 95.805471 -197.251535) (xy 95.80499 -197.22084)
			(xy 95.805454 -197.190143) (xy 95.812859 -197.129198) (xy 95.827553 -197.069589) (xy 95.849323 -197.012186)
			(xy 95.877851 -196.957823) (xy 95.894906 -196.932296) (xy 95.900343 -196.923526) (xy 95.904483 -196.903333)
			(xy 95.900369 -196.883136) (xy 95.894906 -196.874384) (xy 95.877867 -196.848849) (xy 95.849358 -196.79448)
			(xy 95.827596 -196.737077) (xy 95.812895 -196.677474) (xy 95.805471 -196.616535) (xy 95.80499 -196.58584)
			(xy 95.805454 -196.555143) (xy 95.812859 -196.494198) (xy 95.827553 -196.434589) (xy 95.849323 -196.377186)
			(xy 95.877851 -196.322823) (xy 95.894906 -196.297296) (xy 95.900343 -196.288526) (xy 95.904483 -196.268333)
			(xy 95.900369 -196.248136) (xy 95.894906 -196.239384) (xy 95.877867 -196.213849) (xy 95.849358 -196.15948)
			(xy 95.827596 -196.102077) (xy 95.812895 -196.042474) (xy 95.805471 -195.981535) (xy 95.80499 -195.95084)
			(xy 95.805454 -195.920143) (xy 95.812859 -195.859198) (xy 95.827553 -195.799589) (xy 95.849323 -195.742186)
			(xy 95.877851 -195.687823) (xy 95.894906 -195.662296) (xy 95.900343 -195.653526) (xy 95.904483 -195.633333)
			(xy 95.900369 -195.613136) (xy 95.894906 -195.604384) (xy 95.877867 -195.578849) (xy 95.849358 -195.52448)
			(xy 95.827596 -195.467077) (xy 95.812895 -195.407474) (xy 95.805471 -195.346535) (xy 95.80499 -195.31584)
			(xy 95.805459 -195.284683) (xy 95.813079 -195.222836) (xy 95.828198 -195.162384) (xy 95.85059 -195.104231)
			(xy 95.879918 -195.04925) (xy 95.897446 -195.023486) (xy 95.90304 -195.014685) (xy 95.907251 -194.99428)
			(xy 95.903024 -194.973878) (xy 95.897446 -194.965066) (xy 95.879927 -194.939296) (xy 95.850594 -194.884318)
			(xy 95.828199 -194.826167) (xy 95.81308 -194.765716) (xy 95.805462 -194.703869) (xy 95.80499 -194.672712)
			(xy 95.805449 -194.64198) (xy 95.812856 -194.580965) (xy 95.827564 -194.521287) (xy 95.849358 -194.463817)
			(xy 95.877921 -194.409393) (xy 95.912835 -194.358809) (xy 95.953593 -194.312802) (xy 95.999598 -194.272044)
			(xy 96.050181 -194.237128) (xy 96.104604 -194.208564) (xy 96.162073 -194.186768) (xy 96.221751 -194.172059)
			(xy 96.282766 -194.16465) (xy 96.313498 -194.164204) (xy 96.344195 -194.164646) (xy 96.405141 -194.172056)
			(xy 96.46475 -194.186755) (xy 96.522154 -194.20853) (xy 96.576515 -194.237063) (xy 96.602042 -194.25412)
			(xy 96.610794 -194.259591) (xy 96.630998 -194.263719) (xy 96.651202 -194.259591) (xy 96.659954 -194.25412)
			(xy 96.68548 -194.237066) (xy 96.739851 -194.208559) (xy 96.797256 -194.1868) (xy 96.856862 -194.172103)
			(xy 96.917803 -194.164683) (xy 96.948498 -194.164204) (xy 96.979195 -194.164646) (xy 97.040141 -194.172056)
			(xy 97.09975 -194.186755) (xy 97.157154 -194.20853) (xy 97.211515 -194.237063) (xy 97.237042 -194.25412)
			(xy 97.245794 -194.259591) (xy 97.265998 -194.263719) (xy 97.286202 -194.259591) (xy 97.294954 -194.25412)
			(xy 97.32048 -194.237066) (xy 97.374851 -194.208559) (xy 97.432256 -194.1868) (xy 97.491862 -194.172103)
			(xy 97.552803 -194.164683) (xy 97.583498 -194.164204) (xy 97.614231 -194.16464) (xy 97.675247 -194.172048)
			(xy 97.734926 -194.186758) (xy 97.792397 -194.208554) (xy 97.846822 -194.237118) (xy 97.897406 -194.272035)
			(xy 97.943413 -194.312794) (xy 97.984171 -194.358802) (xy 98.019087 -194.409387) (xy 98.04765 -194.463812)
			(xy 98.069445 -194.521283) (xy 98.084154 -194.580962) (xy 98.091561 -194.641979) (xy 98.092006 -194.672712)
			(xy 98.091565 -194.703341) (xy 98.084198 -194.764155) (xy 98.069584 -194.823645) (xy 98.047935 -194.88095)
			(xy 98.019563 -194.935242) (xy 98.002598 -194.960748) (xy 97.997218 -194.969487) (xy 97.99315 -194.989581)
			(xy 97.997203 -195.009678) (xy 98.002598 -195.018406) (xy 98.019727 -195.043992) (xy 98.048399 -195.098484)
			(xy 98.070289 -195.156035) (xy 98.085078 -195.215807) (xy 98.092551 -195.276925) (xy 98.093022 -195.307712)
			(xy 98.092532 -195.338408) (xy 98.085133 -195.399352) (xy 98.070444 -195.45896) (xy 98.04868 -195.516364)
			(xy 98.020158 -195.570728) (xy 98.003106 -195.596256) (xy 97.997623 -195.605002) (xy 97.993497 -195.62521)
			(xy 97.997631 -195.645416) (xy 98.003106 -195.654168) (xy 98.020169 -195.679688) (xy 98.048674 -195.734061)
			(xy 98.070431 -195.791468) (xy 98.085126 -195.851075) (xy 98.092544 -195.912016) (xy 98.093022 -195.942712)
			(xy 98.092532 -195.973408) (xy 98.085133 -196.034352) (xy 98.070444 -196.09396) (xy 98.04868 -196.151364)
			(xy 98.020158 -196.205728) (xy 98.003106 -196.231256) (xy 97.997623 -196.240002) (xy 97.993497 -196.26021)
			(xy 97.997631 -196.280416) (xy 98.003106 -196.289168) (xy 98.020169 -196.314688) (xy 98.048674 -196.369061)
			(xy 98.070431 -196.426468) (xy 98.085126 -196.486075) (xy 98.092544 -196.547016) (xy 98.093022 -196.577712)
			(xy 98.092532 -196.608408) (xy 98.085133 -196.669352) (xy 98.070444 -196.72896) (xy 98.04868 -196.786364)
			(xy 98.020158 -196.840728) (xy 98.003106 -196.866256) (xy 97.997623 -196.875002) (xy 97.993497 -196.89521)
			(xy 97.997631 -196.915416) (xy 98.003106 -196.924168) (xy 98.020169 -196.949688) (xy 98.048674 -197.004061)
			(xy 98.070431 -197.061468) (xy 98.085126 -197.121075) (xy 98.092544 -197.182016) (xy 98.093022 -197.212712)
			(xy 98.092528 -197.243961) (xy 98.084878 -197.305989) (xy 98.069682 -197.366611) (xy 98.047169 -197.424914)
			(xy 98.017679 -197.480017) (xy 98.000058 -197.505828) (xy 97.994451 -197.514622) (xy 97.990244 -197.535031)
			(xy 97.994476 -197.555436) (xy 98.000058 -197.564248) (xy 98.017479 -197.589973) (xy 98.046651 -197.644827)
			(xy 98.068921 -197.702828) (xy 98.083958 -197.76311) (xy 98.091536 -197.824775) (xy 98.092006 -197.85584)
			(xy 98.091533 -197.886536) (xy 98.08413 -197.947481) (xy 98.069438 -198.00709) (xy 98.04767 -198.064494)
			(xy 98.019144 -198.118857) (xy 98.00209 -198.144384) (xy 97.996584 -198.153118) (xy 97.992468 -198.173333)
			(xy 97.99661 -198.193544) (xy 98.00209 -198.202296) (xy 98.01912 -198.227837) (xy 98.047631 -198.282204)
			(xy 98.069395 -198.339605) (xy 98.084097 -198.399208) (xy 98.091524 -198.460146) (xy 98.092006 -198.49084)
			(xy 98.091533 -198.521536) (xy 98.08413 -198.582481) (xy 98.069438 -198.64209) (xy 98.04767 -198.699494)
			(xy 98.019144 -198.753857) (xy 98.00209 -198.779384) (xy 97.996584 -198.788118) (xy 97.992468 -198.808333)
			(xy 97.99661 -198.828544) (xy 98.00209 -198.837296) (xy 98.01912 -198.862837) (xy 98.047631 -198.917204)
			(xy 98.069395 -198.974605) (xy 98.084097 -199.034208) (xy 98.091524 -199.095146) (xy 98.092006 -199.12584)
			(xy 98.091533 -199.156536) (xy 98.08413 -199.217481) (xy 98.069438 -199.27709) (xy 98.04767 -199.334494)
			(xy 98.019144 -199.388857) (xy 98.00209 -199.414384) (xy 97.996584 -199.423118) (xy 97.992468 -199.443333)
			(xy 97.99661 -199.463544) (xy 98.00209 -199.472296) (xy 98.01912 -199.497837) (xy 98.047631 -199.552204)
			(xy 98.069395 -199.609605) (xy 98.084097 -199.669208) (xy 98.091524 -199.730146) (xy 98.092006 -199.76084)
			(xy 98.091533 -199.791536) (xy 98.08413 -199.852481) (xy 98.069438 -199.91209) (xy 98.04767 -199.969494)
			(xy 98.019144 -200.023857) (xy 98.00209 -200.049384) (xy 97.996584 -200.058118) (xy 97.992468 -200.078333)
			(xy 97.99661 -200.098544) (xy 98.00209 -200.107296) (xy 98.01912 -200.132837) (xy 98.047631 -200.187204)
			(xy 98.069395 -200.244605) (xy 98.084097 -200.304208) (xy 98.091524 -200.365146) (xy 98.092006 -200.39584)
			(xy 98.091533 -200.426536) (xy 98.08413 -200.487481) (xy 98.069438 -200.54709) (xy 98.04767 -200.604494)
			(xy 98.019144 -200.658857) (xy 98.00209 -200.684384) (xy 97.996584 -200.693118) (xy 97.992468 -200.713333)
			(xy 97.99661 -200.733544) (xy 98.00209 -200.742296) (xy 98.01912 -200.767837) (xy 98.047631 -200.822204)
			(xy 98.069395 -200.879605) (xy 98.084097 -200.939208) (xy 98.091524 -201.000146) (xy 98.092006 -201.03084)
			(xy 98.091582 -201.061572) (xy 98.084169 -201.122587) (xy 98.069456 -201.182264) (xy 98.047657 -201.239733)
			(xy 98.01909 -201.294155) (xy 97.984172 -201.344737) (xy 97.943412 -201.390741) (xy 97.897404 -201.431498)
			(xy 97.846819 -201.466412) (xy 97.792394 -201.494974) (xy 97.734924 -201.516768) (xy 97.675246 -201.531476)
			(xy 97.61423 -201.538885) (xy 97.583498 -201.539348) (xy 97.552802 -201.538866) (xy 97.491857 -201.531467)
			(xy 97.432248 -201.516777) (xy 97.374844 -201.495011) (xy 97.320481 -201.466486) (xy 97.294954 -201.449432)
			(xy 97.286202 -201.443961) (xy 97.265998 -201.439833) (xy 97.245794 -201.443961) (xy 97.237042 -201.449432)
			(xy 97.211514 -201.466482) (xy 97.157144 -201.49499) (xy 97.099739 -201.516751) (xy 97.040134 -201.531449)
			(xy 96.979193 -201.538869) (xy 96.948498 -201.539348) (xy 96.917802 -201.538866) (xy 96.856857 -201.531467)
			(xy 96.797248 -201.516777) (xy 96.739844 -201.495011) (xy 96.685481 -201.466486) (xy 96.659954 -201.449432)
			(xy 96.651202 -201.443961) (xy 96.630998 -201.439833) (xy 96.610794 -201.443961) (xy 96.602042 -201.449432)
			(xy 96.576514 -201.466482) (xy 96.522144 -201.49499) (xy 96.464739 -201.516751) (xy 96.405134 -201.531449)
			(xy 96.344193 -201.538869) (xy 96.313498 -201.539348) (xy 96.282769 -201.538846) (xy 96.221758 -201.531438)
			(xy 96.162084 -201.51673) (xy 96.104619 -201.494938) (xy 96.050199 -201.466377) (xy 95.999618 -201.431466)
			(xy 95.953614 -201.390713) (xy 95.912857 -201.344712) (xy 95.877942 -201.294134) (xy 95.849378 -201.239716)
			(xy 95.827581 -201.182252) (xy 95.812869 -201.12258) (xy 95.805456 -201.061569) (xy 95.80499 -201.03084)
			(xy 93.71367 -201.03084) (xy 93.714062 -201.055732) (xy 93.713692 -201.086467) (xy 93.706279 -201.147487)
			(xy 93.691565 -201.207169) (xy 93.669763 -201.264642) (xy 93.641193 -201.319068) (xy 93.606271 -201.369654)
			(xy 93.565506 -201.415661) (xy 93.519493 -201.456419) (xy 93.468902 -201.491334) (xy 93.414471 -201.519895)
			(xy 93.356995 -201.541688) (xy 93.29731 -201.556393) (xy 93.236289 -201.563797) (xy 93.205554 -201.56424)
			(xy 93.174858 -201.563764) (xy 93.113913 -201.556361) (xy 93.054305 -201.541669) (xy 92.996901 -201.519902)
			(xy 92.942538 -201.491377) (xy 92.91701 -201.474324) (xy 92.908258 -201.468853) (xy 92.888054 -201.464725)
			(xy 92.86785 -201.468853) (xy 92.859098 -201.474324) (xy 92.833553 -201.491349) (xy 92.779188 -201.519862)
			(xy 92.721788 -201.541628) (xy 92.662186 -201.556331) (xy 92.601248 -201.563758) (xy 92.570554 -201.56424)
			(xy 92.539858 -201.563764) (xy 92.478913 -201.556361) (xy 92.419305 -201.541669) (xy 92.361901 -201.519902)
			(xy 92.307538 -201.491377) (xy 92.28201 -201.474324) (xy 92.273258 -201.468853) (xy 92.253054 -201.464725)
			(xy 92.23285 -201.468853) (xy 92.224098 -201.474324) (xy 92.198553 -201.491349) (xy 92.144188 -201.519862)
			(xy 92.086788 -201.541628) (xy 92.027186 -201.556331) (xy 91.966248 -201.563758) (xy 91.935554 -201.56424)
			(xy 91.904823 -201.563788) (xy 91.84381 -201.556375) (xy 91.784136 -201.541662) (xy 91.726669 -201.519864)
			(xy 91.672249 -201.491299) (xy 91.621668 -201.456383) (xy 91.575664 -201.415626) (xy 91.534908 -201.369621)
			(xy 91.499994 -201.319039) (xy 91.47143 -201.264618) (xy 91.449634 -201.207151) (xy 91.434923 -201.147476)
			(xy 91.427511 -201.086463) (xy 91.427046 -201.055732) (xy 91.427496 -201.025035) (xy 91.434902 -200.964089)
			(xy 91.4496 -200.90448) (xy 91.471373 -200.847076) (xy 91.499905 -200.792714) (xy 91.516962 -200.767188)
			(xy 91.52241 -200.758423) (xy 91.526551 -200.738227) (xy 91.522431 -200.718026) (xy 91.516962 -200.709276)
			(xy 91.499926 -200.683739) (xy 91.471415 -200.629371) (xy 91.449652 -200.571969) (xy 91.434951 -200.512365)
			(xy 91.427527 -200.451426) (xy 91.427046 -200.420732) (xy 91.427496 -200.390035) (xy 91.434902 -200.329089)
			(xy 91.4496 -200.26948) (xy 91.471373 -200.212076) (xy 91.499905 -200.157714) (xy 91.516962 -200.132188)
			(xy 91.52241 -200.123423) (xy 91.526551 -200.103227) (xy 91.522431 -200.083026) (xy 91.516962 -200.074276)
			(xy 91.499926 -200.048739) (xy 91.471415 -199.994371) (xy 91.449652 -199.936969) (xy 91.434951 -199.877365)
			(xy 91.427527 -199.816426) (xy 91.427046 -199.785732) (xy 91.427496 -199.755035) (xy 91.434902 -199.694089)
			(xy 91.4496 -199.63448) (xy 91.471373 -199.577076) (xy 91.499905 -199.522714) (xy 91.516962 -199.497188)
			(xy 91.52241 -199.488423) (xy 91.526551 -199.468227) (xy 91.522431 -199.448026) (xy 91.516962 -199.439276)
			(xy 91.499926 -199.413739) (xy 91.471415 -199.359371) (xy 91.449652 -199.301969) (xy 91.434951 -199.242365)
			(xy 91.427527 -199.181426) (xy 91.427046 -199.150732) (xy 91.427496 -199.120035) (xy 91.434902 -199.059089)
			(xy 91.4496 -198.99948) (xy 91.471373 -198.942076) (xy 91.499905 -198.887714) (xy 91.516962 -198.862188)
			(xy 91.52241 -198.853423) (xy 91.526551 -198.833227) (xy 91.522431 -198.813026) (xy 91.516962 -198.804276)
			(xy 91.499926 -198.778739) (xy 91.471415 -198.724371) (xy 91.449652 -198.666969) (xy 91.434951 -198.607365)
			(xy 91.427527 -198.546426) (xy 91.427046 -198.515732) (xy 91.427496 -198.485035) (xy 91.434902 -198.424089)
			(xy 91.4496 -198.36448) (xy 91.471373 -198.307076) (xy 91.499905 -198.252714) (xy 91.516962 -198.227188)
			(xy 91.52241 -198.218423) (xy 91.526551 -198.198227) (xy 91.522431 -198.178026) (xy 91.516962 -198.169276)
			(xy 91.499926 -198.143739) (xy 91.471415 -198.089371) (xy 91.449652 -198.031969) (xy 91.434951 -197.972365)
			(xy 91.427527 -197.911426) (xy 91.427046 -197.880732) (xy 91.427496 -197.849758) (xy 91.435032 -197.788271)
			(xy 91.449983 -197.728155) (xy 91.472128 -197.670301) (xy 91.50114 -197.615567) (xy 91.518486 -197.589902)
			(xy 91.52392 -197.581129) (xy 91.528063 -197.560938) (xy 91.52395 -197.540741) (xy 91.518486 -197.53199)
			(xy 91.50113 -197.506332) (xy 91.472118 -197.451597) (xy 91.449976 -197.393741) (xy 91.43503 -197.333623)
			(xy 91.427505 -197.272134) (xy 91.427046 -197.24116) (xy 91.42751 -197.210463) (xy 91.434913 -197.149518)
			(xy 91.449607 -197.089909) (xy 91.471377 -197.032505) (xy 91.499907 -196.978143) (xy 91.516962 -196.952616)
			(xy 91.522472 -196.943884) (xy 91.526592 -196.923667) (xy 91.522446 -196.903455) (xy 91.516962 -196.894704)
			(xy 91.499938 -196.869159) (xy 91.471425 -196.814793) (xy 91.449659 -196.757393) (xy 91.434956 -196.697792)
			(xy 91.427528 -196.636854) (xy 91.427046 -196.60616) (xy 91.42751 -196.575463) (xy 91.434913 -196.514518)
			(xy 91.449607 -196.454909) (xy 91.471377 -196.397505) (xy 91.499907 -196.343143) (xy 91.516962 -196.317616)
			(xy 91.522472 -196.308884) (xy 91.526592 -196.288667) (xy 91.522446 -196.268455) (xy 91.516962 -196.259704)
			(xy 91.499938 -196.234159) (xy 91.471425 -196.179793) (xy 91.449659 -196.122393) (xy 91.434956 -196.062792)
			(xy 91.427528 -196.001854) (xy 91.427046 -195.97116) (xy 91.42751 -195.940463) (xy 91.434913 -195.879518)
			(xy 91.449607 -195.819909) (xy 91.471377 -195.762505) (xy 91.499907 -195.708143) (xy 91.516962 -195.682616)
			(xy 91.522472 -195.673884) (xy 91.526592 -195.653667) (xy 91.522446 -195.633455) (xy 91.516962 -195.624704)
			(xy 91.499938 -195.599159) (xy 91.471425 -195.544793) (xy 91.449659 -195.487393) (xy 91.434956 -195.427792)
			(xy 91.427528 -195.366854) (xy 91.427046 -195.33616) (xy 91.427532 -195.305532) (xy 91.43489 -195.24472)
			(xy 91.449493 -195.185231) (xy 91.471132 -195.127925) (xy 91.499494 -195.073631) (xy 91.516454 -195.048124)
			(xy 91.52192 -195.039417) (xy 91.526043 -195.019296) (xy 91.521917 -194.999175) (xy 91.516454 -194.990466)
			(xy 91.499307 -194.964892) (xy 91.470639 -194.910397) (xy 91.448753 -194.852842) (xy 91.433968 -194.793068)
			(xy 91.426499 -194.731947) (xy 91.42603 -194.70116) (xy 89.699846 -194.70116) (xy 89.699371 -194.731788)
			(xy 89.692011 -194.7926) (xy 89.677405 -194.85209) (xy 89.655763 -194.909396) (xy 89.6274 -194.963689)
			(xy 89.610438 -194.989196) (xy 89.605022 -194.997915) (xy 89.600972 -195.018021) (xy 89.605039 -195.038124)
			(xy 89.610438 -195.046854) (xy 89.627593 -195.072423) (xy 89.656259 -195.12692) (xy 89.678144 -195.184476)
			(xy 89.692928 -195.244251) (xy 89.700395 -195.305372) (xy 89.700862 -195.33616) (xy 89.700407 -195.366857)
			(xy 89.693001 -195.427803) (xy 89.678305 -195.487412) (xy 89.656533 -195.544816) (xy 89.628002 -195.599177)
			(xy 89.610946 -195.624704) (xy 89.605513 -195.633476) (xy 89.601377 -195.653667) (xy 89.605487 -195.673863)
			(xy 89.610946 -195.682616) (xy 89.62798 -195.708155) (xy 89.65649 -195.762522) (xy 89.678254 -195.819924)
			(xy 89.692956 -195.879527) (xy 89.700381 -195.940466) (xy 89.700862 -195.97116) (xy 89.700407 -196.001857)
			(xy 89.693001 -196.062803) (xy 89.678305 -196.122412) (xy 89.656533 -196.179816) (xy 89.628002 -196.234177)
			(xy 89.610946 -196.259704) (xy 89.605513 -196.268476) (xy 89.601377 -196.288667) (xy 89.605487 -196.308863)
			(xy 89.610946 -196.317616) (xy 89.62798 -196.343155) (xy 89.65649 -196.397522) (xy 89.678254 -196.454924)
			(xy 89.692956 -196.514527) (xy 89.700381 -196.575466) (xy 89.700862 -196.60616) (xy 89.700407 -196.636857)
			(xy 89.693001 -196.697803) (xy 89.678305 -196.757412) (xy 89.656533 -196.814816) (xy 89.628002 -196.869177)
			(xy 89.610946 -196.894704) (xy 89.605513 -196.903476) (xy 89.601377 -196.923667) (xy 89.605487 -196.943863)
			(xy 89.610946 -196.952616) (xy 89.62798 -196.978155) (xy 89.65649 -197.032522) (xy 89.678254 -197.089924)
			(xy 89.692956 -197.149527) (xy 89.700381 -197.210466) (xy 89.700862 -197.24116) (xy 89.700331 -197.274174)
			(xy 89.691789 -197.339648) (xy 89.674843 -197.403465) (xy 89.649779 -197.464552) (xy 89.617018 -197.52188)
			(xy 89.597484 -197.5485) (xy 89.591584 -197.55705) (xy 89.5866 -197.577197) (xy 89.589999 -197.597672)
			(xy 89.595198 -197.606666) (xy 89.610476 -197.631267) (xy 89.635979 -197.683262) (xy 89.655398 -197.737822)
			(xy 89.668481 -197.794238) (xy 89.675058 -197.851776) (xy 89.675462 -197.880732) (xy 89.674992 -197.911428)
			(xy 89.66759 -197.972374) (xy 89.652898 -198.031983) (xy 89.631129 -198.089387) (xy 89.602601 -198.143749)
			(xy 89.585546 -198.169276) (xy 89.580051 -198.178015) (xy 89.575936 -198.198227) (xy 89.580072 -198.218434)
			(xy 89.585546 -198.227188) (xy 89.602567 -198.252735) (xy 89.63108 -198.3071) (xy 89.652847 -198.3645)
			(xy 89.667551 -198.424101) (xy 89.674979 -198.485038) (xy 89.675462 -198.515732) (xy 89.674992 -198.546428)
			(xy 89.66759 -198.607374) (xy 89.652898 -198.666983) (xy 89.631129 -198.724387) (xy 89.602601 -198.778749)
			(xy 89.585546 -198.804276) (xy 89.580051 -198.813015) (xy 89.575936 -198.833227) (xy 89.580072 -198.853434)
			(xy 89.585546 -198.862188) (xy 89.602567 -198.887735) (xy 89.63108 -198.9421) (xy 89.652847 -198.9995)
			(xy 89.667551 -199.059101) (xy 89.674979 -199.120038) (xy 89.675462 -199.150732) (xy 89.674992 -199.181428)
			(xy 89.66759 -199.242374) (xy 89.652898 -199.301983) (xy 89.631129 -199.359387) (xy 89.602601 -199.413749)
			(xy 89.585546 -199.439276) (xy 89.580051 -199.448015) (xy 89.575936 -199.468227) (xy 89.580072 -199.488434)
			(xy 89.585546 -199.497188) (xy 89.602567 -199.522735) (xy 89.63108 -199.5771) (xy 89.652847 -199.6345)
			(xy 89.667551 -199.694101) (xy 89.674979 -199.755038) (xy 89.675462 -199.785732) (xy 89.674992 -199.816428)
			(xy 89.66759 -199.877374) (xy 89.652898 -199.936983) (xy 89.631129 -199.994387) (xy 89.602601 -200.048749)
			(xy 89.585546 -200.074276) (xy 89.580051 -200.083015) (xy 89.575936 -200.103227) (xy 89.580072 -200.123434)
			(xy 89.585546 -200.132188) (xy 89.602567 -200.157735) (xy 89.63108 -200.2121) (xy 89.652847 -200.2695)
			(xy 89.667551 -200.329101) (xy 89.674979 -200.390038) (xy 89.675462 -200.420732) (xy 89.674992 -200.451428)
			(xy 89.66759 -200.512374) (xy 89.652898 -200.571983) (xy 89.631129 -200.629387) (xy 89.602601 -200.683749)
			(xy 89.585546 -200.709276) (xy 89.580051 -200.718015) (xy 89.575936 -200.738227) (xy 89.580072 -200.758434)
			(xy 89.585546 -200.767188) (xy 89.602567 -200.792735) (xy 89.63108 -200.8471) (xy 89.652847 -200.9045)
			(xy 89.667551 -200.964101) (xy 89.674979 -201.025038) (xy 89.675462 -201.055732) (xy 89.675092 -201.086467)
			(xy 89.667679 -201.147487) (xy 89.652965 -201.207169) (xy 89.631163 -201.264642) (xy 89.602593 -201.319068)
			(xy 89.567671 -201.369654) (xy 89.526906 -201.415661) (xy 89.480893 -201.456419) (xy 89.430302 -201.491334)
			(xy 89.375871 -201.519895) (xy 89.318395 -201.541688) (xy 89.25871 -201.556393) (xy 89.197689 -201.563797)
			(xy 89.166954 -201.56424) (xy 89.136258 -201.563764) (xy 89.075313 -201.556361) (xy 89.015705 -201.541669)
			(xy 88.958301 -201.519902) (xy 88.903938 -201.491377) (xy 88.87841 -201.474324) (xy 88.869658 -201.468853)
			(xy 88.849454 -201.464725) (xy 88.82925 -201.468853) (xy 88.820498 -201.474324) (xy 88.794953 -201.491349)
			(xy 88.740588 -201.519862) (xy 88.683188 -201.541628) (xy 88.623586 -201.556331) (xy 88.562648 -201.563758)
			(xy 88.531954 -201.56424) (xy 88.501258 -201.563764) (xy 88.440313 -201.556361) (xy 88.380705 -201.541669)
			(xy 88.323301 -201.519902) (xy 88.268938 -201.491377) (xy 88.24341 -201.474324) (xy 88.234658 -201.468853)
			(xy 88.214454 -201.464725) (xy 88.19425 -201.468853) (xy 88.185498 -201.474324) (xy 88.159953 -201.491349)
			(xy 88.105588 -201.519862) (xy 88.048188 -201.541628) (xy 87.988586 -201.556331) (xy 87.927648 -201.563758)
			(xy 87.896954 -201.56424) (xy 87.866223 -201.563788) (xy 87.80521 -201.556375) (xy 87.745536 -201.541662)
			(xy 87.688069 -201.519864) (xy 87.633649 -201.491299) (xy 87.583068 -201.456383) (xy 87.537064 -201.415626)
			(xy 87.496308 -201.369621) (xy 87.461394 -201.319039) (xy 87.43283 -201.264618) (xy 87.411034 -201.207151)
			(xy 87.396323 -201.147476) (xy 87.388911 -201.086463) (xy 87.388446 -201.055732) (xy 85.315399 -201.055732)
			(xy 85.315806 -201.08164) (xy 85.315382 -201.112372) (xy 85.307969 -201.173387) (xy 85.293256 -201.233064)
			(xy 85.271457 -201.290533) (xy 85.24289 -201.344955) (xy 85.207972 -201.395537) (xy 85.167212 -201.441541)
			(xy 85.121204 -201.482298) (xy 85.070619 -201.517212) (xy 85.016194 -201.545774) (xy 84.958724 -201.567568)
			(xy 84.899046 -201.582276) (xy 84.83803 -201.589685) (xy 84.807298 -201.590148) (xy 84.776602 -201.589666)
			(xy 84.715657 -201.582267) (xy 84.656048 -201.567577) (xy 84.598644 -201.545811) (xy 84.544281 -201.517286)
			(xy 84.518754 -201.500232) (xy 84.510002 -201.494761) (xy 84.489798 -201.490633) (xy 84.469594 -201.494761)
			(xy 84.460842 -201.500232) (xy 84.435314 -201.517282) (xy 84.380944 -201.54579) (xy 84.323539 -201.567551)
			(xy 84.263934 -201.582249) (xy 84.202993 -201.589669) (xy 84.172298 -201.590148) (xy 84.141602 -201.589666)
			(xy 84.080657 -201.582267) (xy 84.021048 -201.567577) (xy 83.963644 -201.545811) (xy 83.909281 -201.517286)
			(xy 83.883754 -201.500232) (xy 83.875002 -201.494761) (xy 83.854798 -201.490633) (xy 83.834594 -201.494761)
			(xy 83.825842 -201.500232) (xy 83.800314 -201.517282) (xy 83.745944 -201.54579) (xy 83.688539 -201.567551)
			(xy 83.628934 -201.582249) (xy 83.567993 -201.589669) (xy 83.537298 -201.590148) (xy 83.506569 -201.589646)
			(xy 83.445558 -201.582238) (xy 83.385884 -201.56753) (xy 83.328419 -201.545738) (xy 83.273999 -201.517177)
			(xy 83.223418 -201.482266) (xy 83.177414 -201.441513) (xy 83.136657 -201.395512) (xy 83.101742 -201.344934)
			(xy 83.073178 -201.290516) (xy 83.051381 -201.233052) (xy 83.036669 -201.17338) (xy 83.029256 -201.112369)
			(xy 83.02879 -201.08164) (xy 81.302606 -201.08164) (xy 81.302182 -201.112372) (xy 81.294769 -201.173387)
			(xy 81.280056 -201.233064) (xy 81.258257 -201.290533) (xy 81.22969 -201.344955) (xy 81.194772 -201.395537)
			(xy 81.154012 -201.441541) (xy 81.108004 -201.482298) (xy 81.057419 -201.517212) (xy 81.002994 -201.545774)
			(xy 80.945524 -201.567568) (xy 80.885846 -201.582276) (xy 80.82483 -201.589685) (xy 80.794098 -201.590148)
			(xy 80.763402 -201.589666) (xy 80.702457 -201.582267) (xy 80.642848 -201.567577) (xy 80.585444 -201.545811)
			(xy 80.531081 -201.517286) (xy 80.505554 -201.500232) (xy 80.496802 -201.494761) (xy 80.476598 -201.490633)
			(xy 80.456394 -201.494761) (xy 80.447642 -201.500232) (xy 80.422114 -201.517282) (xy 80.367744 -201.54579)
			(xy 80.310339 -201.567551) (xy 80.250734 -201.582249) (xy 80.189793 -201.589669) (xy 80.159098 -201.590148)
			(xy 80.128402 -201.589666) (xy 80.067457 -201.582267) (xy 80.007848 -201.567577) (xy 79.950444 -201.545811)
			(xy 79.896081 -201.517286) (xy 79.870554 -201.500232) (xy 79.861802 -201.494761) (xy 79.841598 -201.490633)
			(xy 79.821394 -201.494761) (xy 79.812642 -201.500232) (xy 79.787114 -201.517282) (xy 79.732744 -201.54579)
			(xy 79.675339 -201.567551) (xy 79.615734 -201.582249) (xy 79.554793 -201.589669) (xy 79.524098 -201.590148)
			(xy 79.493369 -201.589646) (xy 79.432358 -201.582238) (xy 79.372684 -201.56753) (xy 79.315219 -201.545738)
			(xy 79.260799 -201.517177) (xy 79.210218 -201.482266) (xy 79.164214 -201.441513) (xy 79.123457 -201.395512)
			(xy 79.088542 -201.344934) (xy 79.059978 -201.290516) (xy 79.038181 -201.233052) (xy 79.023469 -201.17338)
			(xy 79.016056 -201.112369) (xy 79.01559 -201.08164) (xy 74.153271 -201.08164) (xy 74.367898 -201.29627)
			(xy 74.374734 -201.303672) (xy 74.382443 -201.32227) (xy 74.382884 -201.332338) (xy 74.382884 -206.2958)
			(xy 89.10542 -206.2958) (xy 89.109435 -206.231995) (xy 89.121414 -206.169197) (xy 89.14117 -206.108395)
			(xy 89.168391 -206.050549) (xy 89.202647 -205.99657) (xy 89.243398 -205.94731) (xy 89.290001 -205.903547)
			(xy 89.341723 -205.865969) (xy 89.397746 -205.83517) (xy 89.457187 -205.811636) (xy 89.51911 -205.795737)
			(xy 89.582537 -205.787725) (xy 89.614502 -205.787244) (xy 89.644167 -205.787692) (xy 89.703096 -205.794586)
			(xy 89.760822 -205.808293) (xy 89.81656 -205.828625) (xy 89.869553 -205.855307) (xy 89.91908 -205.887976)
			(xy 89.964467 -205.926187) (xy 89.985088 -205.947518) (xy 89.9922 -205.955138) (xy 90.011504 -205.96352)
			(xy 90.1065 -205.96352) (xy 90.125804 -205.955138) (xy 90.132916 -205.947518) (xy 90.15516 -205.924578)
			(xy 90.204406 -205.883862) (xy 90.258365 -205.849635) (xy 90.316188 -205.822439) (xy 90.376961 -205.802701)
			(xy 90.439729 -205.790732) (xy 90.503502 -205.786722) (xy 90.567275 -205.790732) (xy 90.630043 -205.802701)
			(xy 90.690816 -205.822439) (xy 90.748639 -205.849635) (xy 90.802598 -205.883862) (xy 90.851844 -205.924578)
			(xy 90.874088 -205.947518) (xy 90.8812 -205.955138) (xy 90.900504 -205.96352) (xy 90.9955 -205.96352)
			(xy 91.014804 -205.955138) (xy 91.021916 -205.947518) (xy 91.04252 -205.92617) (xy 91.087913 -205.887962)
			(xy 91.137444 -205.855295) (xy 91.190439 -205.828612) (xy 91.246178 -205.808277) (xy 91.303905 -205.794564)
			(xy 91.362835 -205.787661) (xy 91.392502 -205.787244) (xy 91.425903 -205.787747) (xy 91.492129 -205.796489)
			(xy 91.556639 -205.813834) (xy 91.61832 -205.839483) (xy 91.676108 -205.872994) (xy 91.729005 -205.913789)
			(xy 91.752928 -205.937104) (xy 91.760548 -205.944724) (xy 91.779852 -205.952344) (xy 91.875102 -205.949804)
			(xy 91.894152 -205.940914) (xy 91.90101 -205.93304) (xy 91.921747 -205.910372) (xy 91.967736 -205.869637)
			(xy 92.0183 -205.834742) (xy 92.0727 -205.806195) (xy 92.130145 -205.784412) (xy 92.189796 -205.769712)
			(xy 92.250784 -205.762307) (xy 92.281502 -205.761844) (xy 92.31346 -205.762442) (xy 92.376872 -205.770453)
			(xy 92.43878 -205.786348) (xy 92.498207 -205.809878) (xy 92.554217 -205.840669) (xy 92.605926 -205.878238)
			(xy 92.652518 -205.921992) (xy 92.69326 -205.97124) (xy 92.727508 -206.025206) (xy 92.754722 -206.083039)
			(xy 92.774473 -206.143826) (xy 92.786449 -206.20661) (xy 92.790463 -206.2704) (xy 92.786449 -206.33419)
			(xy 92.774473 -206.396974) (xy 92.754722 -206.457761) (xy 92.727508 -206.515594) (xy 92.69326 -206.56956)
			(xy 92.652518 -206.618808) (xy 92.605926 -206.662562) (xy 92.554217 -206.700131) (xy 92.498207 -206.730922)
			(xy 92.43878 -206.754452) (xy 92.376872 -206.770347) (xy 92.31346 -206.778358) (xy 92.281502 -206.77886)
			(xy 92.248101 -206.778353) (xy 92.181875 -206.769612) (xy 92.117365 -206.752268) (xy 92.055684 -206.726619)
			(xy 91.997897 -206.693109) (xy 91.944999 -206.652314) (xy 91.921076 -206.629) (xy 91.913456 -206.62138)
			(xy 91.894152 -206.61376) (xy 91.798902 -206.6163) (xy 91.779852 -206.62519) (xy 91.772994 -206.633064)
			(xy 91.752256 -206.65573) (xy 91.706267 -206.696465) (xy 91.655704 -206.731361) (xy 91.601303 -206.759908)
			(xy 91.543859 -206.781691) (xy 91.484208 -206.796392) (xy 91.42322 -206.803796) (xy 91.392502 -206.80426)
			(xy 91.362835 -206.80384) (xy 91.303904 -206.796944) (xy 91.246177 -206.783235) (xy 91.190438 -206.762899)
			(xy 91.137445 -206.736212) (xy 91.08792 -206.703538) (xy 91.042535 -206.66532) (xy 91.021916 -206.643986)
			(xy 91.014804 -206.636366) (xy 90.9955 -206.627984) (xy 90.900504 -206.627984) (xy 90.8812 -206.636366)
			(xy 90.874088 -206.643986) (xy 90.851844 -206.666926) (xy 90.802598 -206.707642) (xy 90.748639 -206.741869)
			(xy 90.690816 -206.769065) (xy 90.630043 -206.788803) (xy 90.567275 -206.800772) (xy 90.503502 -206.804782)
			(xy 90.439729 -206.800772) (xy 90.376961 -206.788803) (xy 90.316188 -206.769065) (xy 90.258365 -206.741869)
			(xy 90.204406 -206.707642) (xy 90.15516 -206.666926) (xy 90.132916 -206.643986) (xy 90.125804 -206.636366)
			(xy 90.1065 -206.627984) (xy 90.011504 -206.627984) (xy 89.9922 -206.636366) (xy 89.985088 -206.643986)
			(xy 89.964483 -206.665333) (xy 89.91909 -206.703541) (xy 89.869559 -206.736208) (xy 89.816564 -206.762891)
			(xy 89.760825 -206.783226) (xy 89.703099 -206.796939) (xy 89.644168 -206.803842) (xy 89.614502 -206.80426)
			(xy 89.582537 -206.803875) (xy 89.51911 -206.795863) (xy 89.457187 -206.779964) (xy 89.397746 -206.75643)
			(xy 89.341723 -206.725631) (xy 89.290001 -206.688053) (xy 89.243398 -206.64429) (xy 89.202647 -206.59503)
			(xy 89.168391 -206.541051) (xy 89.14117 -206.483205) (xy 89.121414 -206.422403) (xy 89.109435 -206.359605)
			(xy 89.10542 -206.2958) (xy 74.382884 -206.2958) (xy 74.382884 -208.732882) (xy 74.383355 -208.742754)
			(xy 74.390813 -208.761038) (xy 74.397362 -208.768442) (xy 74.397616 -208.768696) (xy 75.852274 -210.223354)
			(xy 75.852782 -210.223862) (xy 75.860165 -210.230439) (xy 75.878464 -210.237878) (xy 75.888342 -210.23834)
			(xy 82.490818 -210.23834) (xy 82.500886 -210.238768) (xy 82.519482 -210.246491) (xy 82.526886 -210.253326)
			(xy 83.886548 -211.612988) (xy 83.893402 -211.620383) (xy 83.901149 -211.638982) (xy 83.901534 -211.649056)
			(xy 83.901534 -215.857793) (xy 90.051884 -215.857793) (xy 90.051884 -215.793871) (xy 90.059895 -215.730453)
			(xy 90.075792 -215.668539) (xy 90.099324 -215.609106) (xy 90.130118 -215.553091) (xy 90.167691 -215.501376)
			(xy 90.211448 -215.454779) (xy 90.260701 -215.414034) (xy 90.314672 -215.379783) (xy 90.372511 -215.352566)
			(xy 90.433304 -215.332813) (xy 90.496094 -215.320835) (xy 90.55989 -215.316822) (xy 90.623686 -215.320835)
			(xy 90.686476 -215.332813) (xy 90.747269 -215.352566) (xy 90.805108 -215.379783) (xy 90.859079 -215.414034)
			(xy 90.908332 -215.454779) (xy 90.952089 -215.501376) (xy 90.989662 -215.553091) (xy 91.020456 -215.609106)
			(xy 91.043988 -215.668539) (xy 91.059885 -215.730453) (xy 91.067896 -215.793871) (xy 91.068398 -215.825832)
			(xy 91.067896 -215.857793) (xy 91.059885 -215.921211) (xy 91.043988 -215.983125) (xy 91.020456 -216.042558)
			(xy 90.989662 -216.098573) (xy 90.952089 -216.150288) (xy 90.908332 -216.196885) (xy 90.859079 -216.23763)
			(xy 90.805108 -216.271881) (xy 90.747269 -216.299098) (xy 90.686476 -216.318851) (xy 90.623686 -216.330829)
			(xy 90.55989 -216.334843) (xy 90.496094 -216.330829) (xy 90.433304 -216.318851) (xy 90.372511 -216.299098)
			(xy 90.314672 -216.271881) (xy 90.260701 -216.23763) (xy 90.211448 -216.196885) (xy 90.167691 -216.150288)
			(xy 90.130118 -216.098573) (xy 90.099324 -216.042558) (xy 90.075792 -215.983125) (xy 90.059895 -215.921211)
			(xy 90.051884 -215.857793) (xy 83.901534 -215.857793) (xy 83.901534 -216.583217) (xy 92.175832 -216.583217)
			(xy 92.175832 -216.519295) (xy 92.183843 -216.455877) (xy 92.19974 -216.393963) (xy 92.223272 -216.33453)
			(xy 92.254066 -216.278515) (xy 92.291639 -216.2268) (xy 92.335396 -216.180203) (xy 92.384649 -216.139458)
			(xy 92.43862 -216.105207) (xy 92.496459 -216.07799) (xy 92.557252 -216.058237) (xy 92.620042 -216.046259)
			(xy 92.683838 -216.042246) (xy 92.747634 -216.046259) (xy 92.810424 -216.058237) (xy 92.871217 -216.07799)
			(xy 92.929056 -216.105207) (xy 92.983027 -216.139458) (xy 93.03228 -216.180203) (xy 93.076037 -216.2268)
			(xy 93.11361 -216.278515) (xy 93.144404 -216.33453) (xy 93.167936 -216.393963) (xy 93.183833 -216.455877)
			(xy 93.191844 -216.519295) (xy 93.192346 -216.551256) (xy 93.191844 -216.583217) (xy 93.183833 -216.646635)
			(xy 93.167936 -216.708549) (xy 93.144404 -216.767982) (xy 93.11361 -216.823997) (xy 93.076037 -216.875712)
			(xy 93.03228 -216.922309) (xy 92.983027 -216.963054) (xy 92.929056 -216.997305) (xy 92.871217 -217.024522)
			(xy 92.810424 -217.044275) (xy 92.747634 -217.056253) (xy 92.683838 -217.060267) (xy 92.620042 -217.056253)
			(xy 92.557252 -217.044275) (xy 92.496459 -217.024522) (xy 92.43862 -216.997305) (xy 92.384649 -216.963054)
			(xy 92.335396 -216.922309) (xy 92.291639 -216.875712) (xy 92.254066 -216.823997) (xy 92.223272 -216.767982)
			(xy 92.19974 -216.708549) (xy 92.183843 -216.646635) (xy 92.175832 -216.583217) (xy 83.901534 -216.583217)
			(xy 83.901534 -218.3435) (xy 89.224369 -218.3435) (xy 89.228383 -218.279704) (xy 89.240361 -218.216913)
			(xy 89.260113 -218.156119) (xy 89.287329 -218.09828) (xy 89.32158 -218.044308) (xy 89.362324 -217.995054)
			(xy 89.408921 -217.951295) (xy 89.460634 -217.91372) (xy 89.516648 -217.882923) (xy 89.576081 -217.85939)
			(xy 89.637995 -217.84349) (xy 89.701413 -217.835476) (xy 89.733374 -217.834972) (xy 89.766077 -217.835474)
			(xy 89.830943 -217.843873) (xy 89.894195 -217.860522) (xy 89.95479 -217.885147) (xy 90.011725 -217.917341)
			(xy 90.064061 -217.956572) (xy 90.110933 -218.002191) (xy 90.131646 -218.027504) (xy 90.138758 -218.03614)
			(xy 90.158062 -218.046046) (xy 90.256614 -218.050618) (xy 90.276934 -218.042744) (xy 90.284554 -218.034616)
			(xy 90.310893 -218.008173) (xy 90.369936 -217.962521) (xy 90.402156 -217.943684) (xy 90.412824 -217.937588)
			(xy 90.426032 -217.91803) (xy 90.440002 -217.813382) (xy 90.432382 -217.79103) (xy 90.423492 -217.782394)
			(xy 90.399788 -217.758434) (xy 90.358333 -217.70529) (xy 90.324264 -217.647135) (xy 90.298177 -217.584988)
			(xy 90.280531 -217.519939) (xy 90.271635 -217.453128) (xy 90.271092 -217.419428) (xy 90.271594 -217.387467)
			(xy 90.279605 -217.324049) (xy 90.295502 -217.262135) (xy 90.319034 -217.202702) (xy 90.349828 -217.146687)
			(xy 90.387401 -217.094972) (xy 90.431158 -217.048375) (xy 90.480411 -217.00763) (xy 90.534382 -216.973379)
			(xy 90.592221 -216.946162) (xy 90.653014 -216.926409) (xy 90.715804 -216.914431) (xy 90.7796 -216.910418)
			(xy 90.843396 -216.914431) (xy 90.906186 -216.926409) (xy 90.966979 -216.946162) (xy 91.024818 -216.973379)
			(xy 91.078789 -217.00763) (xy 91.128042 -217.048375) (xy 91.171799 -217.094972) (xy 91.209372 -217.146687)
			(xy 91.240166 -217.202702) (xy 91.263698 -217.262135) (xy 91.279595 -217.324049) (xy 91.287606 -217.387467)
			(xy 91.288108 -217.419428) (xy 91.287576 -217.453085) (xy 91.27868 -217.51981) (xy 91.26106 -217.584777)
			(xy 91.235024 -217.646853) (xy 91.201028 -217.704952) (xy 91.159664 -217.758059) (xy 91.111657 -217.805246)
			(xy 91.057845 -217.845688) (xy 91.028774 -217.862658) (xy 91.018106 -217.868754) (xy 91.004898 -217.888312)
			(xy 90.990928 -217.99296) (xy 90.998548 -218.015312) (xy 91.007438 -218.023948) (xy 91.031101 -218.047947)
			(xy 91.072563 -218.101081) (xy 91.106639 -218.159227) (xy 91.132733 -218.221367) (xy 91.150387 -218.28641)
			(xy 91.159291 -218.353216) (xy 91.159838 -218.386914) (xy 91.159357 -218.417644) (xy 91.151948 -218.478656)
			(xy 91.137238 -218.53833) (xy 91.115444 -218.595797) (xy 91.086882 -218.650217) (xy 91.051969 -218.700798)
			(xy 91.011213 -218.746802) (xy 90.965211 -218.787559) (xy 90.914631 -218.822473) (xy 90.860211 -218.851037)
			(xy 90.802746 -218.872834) (xy 90.743072 -218.887545) (xy 90.68206 -218.894956) (xy 90.65133 -218.895422)
			(xy 90.618627 -218.894919) (xy 90.553761 -218.886521) (xy 90.490508 -218.869872) (xy 90.429914 -218.845247)
			(xy 90.372978 -218.813053) (xy 90.320643 -218.773822) (xy 90.273771 -218.728203) (xy 90.253058 -218.70289)
			(xy 90.245946 -218.694254) (xy 90.226642 -218.684348) (xy 90.12809 -218.679776) (xy 90.10777 -218.68765)
			(xy 90.10015 -218.695778) (xy 90.076081 -218.720011) (xy 90.022594 -218.762486) (xy 89.963904 -218.79742)
			(xy 89.901066 -218.824185) (xy 89.835211 -218.8423) (xy 89.767524 -218.851437) (xy 89.733374 -218.851988)
			(xy 89.701413 -218.851524) (xy 89.637995 -218.84351) (xy 89.576081 -218.82761) (xy 89.516648 -218.804077)
			(xy 89.460634 -218.77328) (xy 89.408921 -218.735705) (xy 89.362324 -218.691946) (xy 89.32158 -218.642692)
			(xy 89.287329 -218.58872) (xy 89.260113 -218.530881) (xy 89.240361 -218.470087) (xy 89.228383 -218.407296)
			(xy 89.224369 -218.3435) (xy 83.901534 -218.3435) (xy 83.901534 -218.942369) (xy 92.156528 -218.942369)
			(xy 92.156528 -218.878447) (xy 92.164539 -218.815029) (xy 92.180436 -218.753115) (xy 92.203968 -218.693682)
			(xy 92.234762 -218.637667) (xy 92.272335 -218.585952) (xy 92.316092 -218.539355) (xy 92.365345 -218.49861)
			(xy 92.419316 -218.464359) (xy 92.477155 -218.437142) (xy 92.537948 -218.417389) (xy 92.600738 -218.405411)
			(xy 92.664534 -218.401398) (xy 92.72833 -218.405411) (xy 92.79112 -218.417389) (xy 92.851913 -218.437142)
			(xy 92.909752 -218.464359) (xy 92.963723 -218.49861) (xy 93.012976 -218.539355) (xy 93.056733 -218.585952)
			(xy 93.094306 -218.637667) (xy 93.1251 -218.693682) (xy 93.148632 -218.753115) (xy 93.164529 -218.815029)
			(xy 93.17254 -218.878447) (xy 93.173042 -218.910408) (xy 93.17254 -218.942369) (xy 93.164529 -219.005787)
			(xy 93.148632 -219.067701) (xy 93.1251 -219.127134) (xy 93.094306 -219.183149) (xy 93.056733 -219.234864)
			(xy 93.012976 -219.281461) (xy 92.963723 -219.322206) (xy 92.909752 -219.356457) (xy 92.851913 -219.383674)
			(xy 92.79112 -219.403427) (xy 92.72833 -219.415405) (xy 92.664534 -219.419419) (xy 92.600738 -219.415405)
			(xy 92.537948 -219.403427) (xy 92.477155 -219.383674) (xy 92.419316 -219.356457) (xy 92.365345 -219.322206)
			(xy 92.316092 -219.281461) (xy 92.272335 -219.234864) (xy 92.234762 -219.183149) (xy 92.203968 -219.127134)
			(xy 92.180436 -219.067701) (xy 92.164539 -219.005787) (xy 92.156528 -218.942369) (xy 83.901534 -218.942369)
			(xy 83.901534 -221.504764) (xy 84.682088 -221.504764) (xy 84.686048 -221.45571) (xy 84.697825 -221.407926)
			(xy 84.717116 -221.36265) (xy 84.743419 -221.321054) (xy 84.776054 -221.284217) (xy 84.814175 -221.253092)
			(xy 84.856796 -221.228485) (xy 84.902812 -221.211033) (xy 84.951031 -221.201189) (xy 85.000206 -221.199208)
			(xy 85.049061 -221.20514) (xy 85.096332 -221.218832) (xy 85.140794 -221.23993) (xy 85.181297 -221.267886)
			(xy 85.21679 -221.301978) (xy 85.246355 -221.341322) (xy 85.269226 -221.384899) (xy 85.28481 -221.43158)
			(xy 85.292705 -221.480157) (xy 85.2932 -221.504764) (xy 90.322158 -221.504764) (xy 90.326118 -221.45571)
			(xy 90.337895 -221.407926) (xy 90.357186 -221.36265) (xy 90.383489 -221.321054) (xy 90.416124 -221.284217)
			(xy 90.454245 -221.253092) (xy 90.496866 -221.228485) (xy 90.542882 -221.211033) (xy 90.591101 -221.201189)
			(xy 90.640276 -221.199208) (xy 90.689131 -221.20514) (xy 90.736402 -221.218832) (xy 90.780864 -221.23993)
			(xy 90.821367 -221.267886) (xy 90.85686 -221.301978) (xy 90.886425 -221.341322) (xy 90.909296 -221.384899)
			(xy 90.92488 -221.43158) (xy 90.932775 -221.480157) (xy 90.93327 -221.504764) (xy 90.932775 -221.529371)
			(xy 90.92488 -221.577948) (xy 90.909296 -221.624629) (xy 90.886425 -221.668206) (xy 90.85686 -221.70755)
			(xy 90.821367 -221.741642) (xy 90.780864 -221.769598) (xy 90.736402 -221.790696) (xy 90.689131 -221.804388)
			(xy 90.640276 -221.81032) (xy 90.591101 -221.808339) (xy 90.542882 -221.798495) (xy 90.496866 -221.781043)
			(xy 90.454245 -221.756436) (xy 90.416124 -221.725311) (xy 90.383489 -221.688474) (xy 90.357186 -221.646878)
			(xy 90.337895 -221.601602) (xy 90.326118 -221.553818) (xy 90.322158 -221.504764) (xy 85.2932 -221.504764)
			(xy 85.292705 -221.529371) (xy 85.28481 -221.577948) (xy 85.269226 -221.624629) (xy 85.246355 -221.668206)
			(xy 85.21679 -221.70755) (xy 85.181297 -221.741642) (xy 85.140794 -221.769598) (xy 85.096332 -221.790696)
			(xy 85.049061 -221.804388) (xy 85.000206 -221.81032) (xy 84.951031 -221.808339) (xy 84.902812 -221.798495)
			(xy 84.856796 -221.781043) (xy 84.814175 -221.756436) (xy 84.776054 -221.725311) (xy 84.743419 -221.688474)
			(xy 84.717116 -221.646878) (xy 84.697825 -221.601602) (xy 84.686048 -221.553818) (xy 84.682088 -221.504764)
			(xy 83.901534 -221.504764) (xy 83.901534 -222.61449) (xy 91.26526 -222.61449) (xy 91.26922 -222.565436)
			(xy 91.280997 -222.517652) (xy 91.300288 -222.472376) (xy 91.326591 -222.43078) (xy 91.359226 -222.393943)
			(xy 91.397347 -222.362818) (xy 91.439968 -222.338211) (xy 91.485984 -222.320759) (xy 91.534203 -222.310915)
			(xy 91.583378 -222.308934) (xy 91.632233 -222.314866) (xy 91.679504 -222.328558) (xy 91.723966 -222.349656)
			(xy 91.764469 -222.377612) (xy 91.799962 -222.411704) (xy 91.829527 -222.451048) (xy 91.852398 -222.494625)
			(xy 91.867982 -222.541306) (xy 91.875877 -222.589883) (xy 91.876372 -222.61449) (xy 91.875877 -222.639097)
			(xy 91.867982 -222.687674) (xy 91.852398 -222.734355) (xy 91.829527 -222.777932) (xy 91.799962 -222.817276)
			(xy 91.764469 -222.851368) (xy 91.723966 -222.879324) (xy 91.679504 -222.900422) (xy 91.632233 -222.914114)
			(xy 91.583378 -222.920046) (xy 91.534203 -222.918065) (xy 91.485984 -222.908221) (xy 91.439968 -222.890769)
			(xy 91.397347 -222.866162) (xy 91.359226 -222.835037) (xy 91.326591 -222.7982) (xy 91.300288 -222.756604)
			(xy 91.280997 -222.711328) (xy 91.26922 -222.663544) (xy 91.26526 -222.61449) (xy 83.901534 -222.61449)
			(xy 83.901534 -223.424496) (xy 84.215236 -223.424496) (xy 84.219196 -223.375442) (xy 84.230973 -223.327658)
			(xy 84.250264 -223.282382) (xy 84.276567 -223.240786) (xy 84.309202 -223.203949) (xy 84.347323 -223.172824)
			(xy 84.389944 -223.148217) (xy 84.43596 -223.130765) (xy 84.484179 -223.120921) (xy 84.533354 -223.11894)
			(xy 84.582209 -223.124872) (xy 84.62948 -223.138564) (xy 84.673942 -223.159662) (xy 84.714445 -223.187618)
			(xy 84.749938 -223.22171) (xy 84.779503 -223.261054) (xy 84.802374 -223.304631) (xy 84.817958 -223.351312)
			(xy 84.825853 -223.399889) (xy 84.826062 -223.410272) (xy 86.095344 -223.410272) (xy 86.099304 -223.361218)
			(xy 86.111081 -223.313434) (xy 86.130372 -223.268158) (xy 86.156675 -223.226562) (xy 86.18931 -223.189725)
			(xy 86.227431 -223.1586) (xy 86.270052 -223.133993) (xy 86.316068 -223.116541) (xy 86.364287 -223.106697)
			(xy 86.413462 -223.104716) (xy 86.462317 -223.110648) (xy 86.509588 -223.12434) (xy 86.55405 -223.145438)
			(xy 86.594553 -223.173394) (xy 86.630046 -223.207486) (xy 86.659611 -223.24683) (xy 86.682482 -223.290407)
			(xy 86.698066 -223.337088) (xy 86.705961 -223.385665) (xy 86.706456 -223.410272) (xy 86.70617 -223.424496)
			(xy 87.035144 -223.424496) (xy 87.039104 -223.375442) (xy 87.050881 -223.327658) (xy 87.070172 -223.282382)
			(xy 87.096475 -223.240786) (xy 87.12911 -223.203949) (xy 87.167231 -223.172824) (xy 87.209852 -223.148217)
			(xy 87.255868 -223.130765) (xy 87.304087 -223.120921) (xy 87.353262 -223.11894) (xy 87.402117 -223.124872)
			(xy 87.449388 -223.138564) (xy 87.49385 -223.159662) (xy 87.534353 -223.187618) (xy 87.569846 -223.22171)
			(xy 87.599411 -223.261054) (xy 87.622282 -223.304631) (xy 87.637866 -223.351312) (xy 87.645761 -223.399889)
			(xy 87.64597 -223.410272) (xy 88.915506 -223.410272) (xy 88.919466 -223.361218) (xy 88.931243 -223.313434)
			(xy 88.950534 -223.268158) (xy 88.976837 -223.226562) (xy 89.009472 -223.189725) (xy 89.047593 -223.1586)
			(xy 89.090214 -223.133993) (xy 89.13623 -223.116541) (xy 89.184449 -223.106697) (xy 89.233624 -223.104716)
			(xy 89.282479 -223.110648) (xy 89.32975 -223.12434) (xy 89.374212 -223.145438) (xy 89.414715 -223.173394)
			(xy 89.450208 -223.207486) (xy 89.479773 -223.24683) (xy 89.502644 -223.290407) (xy 89.518228 -223.337088)
			(xy 89.526123 -223.385665) (xy 89.526618 -223.410272) (xy 89.526332 -223.424496) (xy 89.855306 -223.424496)
			(xy 89.859266 -223.375442) (xy 89.871043 -223.327658) (xy 89.890334 -223.282382) (xy 89.916637 -223.240786)
			(xy 89.949272 -223.203949) (xy 89.987393 -223.172824) (xy 90.030014 -223.148217) (xy 90.07603 -223.130765)
			(xy 90.124249 -223.120921) (xy 90.173424 -223.11894) (xy 90.222279 -223.124872) (xy 90.26955 -223.138564)
			(xy 90.314012 -223.159662) (xy 90.354515 -223.187618) (xy 90.390008 -223.22171) (xy 90.419573 -223.261054)
			(xy 90.442444 -223.304631) (xy 90.458028 -223.351312) (xy 90.465923 -223.399889) (xy 90.466418 -223.424496)
			(xy 90.795106 -223.424496) (xy 90.799066 -223.375442) (xy 90.810843 -223.327658) (xy 90.830134 -223.282382)
			(xy 90.856437 -223.240786) (xy 90.889072 -223.203949) (xy 90.927193 -223.172824) (xy 90.969814 -223.148217)
			(xy 91.01583 -223.130765) (xy 91.064049 -223.120921) (xy 91.113224 -223.11894) (xy 91.162079 -223.124872)
			(xy 91.20935 -223.138564) (xy 91.253812 -223.159662) (xy 91.294315 -223.187618) (xy 91.329808 -223.22171)
			(xy 91.359373 -223.261054) (xy 91.382244 -223.304631) (xy 91.397828 -223.351312) (xy 91.405723 -223.399889)
			(xy 91.406218 -223.424496) (xy 91.405723 -223.449103) (xy 91.397828 -223.49768) (xy 91.382244 -223.544361)
			(xy 91.359373 -223.587938) (xy 91.329808 -223.627282) (xy 91.294315 -223.661374) (xy 91.253812 -223.68933)
			(xy 91.20935 -223.710428) (xy 91.162079 -223.72412) (xy 91.113224 -223.730052) (xy 91.064049 -223.728071)
			(xy 91.01583 -223.718227) (xy 90.969814 -223.700775) (xy 90.927193 -223.676168) (xy 90.889072 -223.645043)
			(xy 90.856437 -223.608206) (xy 90.830134 -223.56661) (xy 90.810843 -223.521334) (xy 90.799066 -223.47355)
			(xy 90.795106 -223.424496) (xy 90.466418 -223.424496) (xy 90.465923 -223.449103) (xy 90.458028 -223.49768)
			(xy 90.442444 -223.544361) (xy 90.419573 -223.587938) (xy 90.390008 -223.627282) (xy 90.354515 -223.661374)
			(xy 90.314012 -223.68933) (xy 90.26955 -223.710428) (xy 90.222279 -223.72412) (xy 90.173424 -223.730052)
			(xy 90.124249 -223.728071) (xy 90.07603 -223.718227) (xy 90.030014 -223.700775) (xy 89.987393 -223.676168)
			(xy 89.949272 -223.645043) (xy 89.916637 -223.608206) (xy 89.890334 -223.56661) (xy 89.871043 -223.521334)
			(xy 89.859266 -223.47355) (xy 89.855306 -223.424496) (xy 89.526332 -223.424496) (xy 89.526123 -223.434879)
			(xy 89.518228 -223.483456) (xy 89.502644 -223.530137) (xy 89.479773 -223.573714) (xy 89.450208 -223.613058)
			(xy 89.414715 -223.64715) (xy 89.374212 -223.675106) (xy 89.32975 -223.696204) (xy 89.282479 -223.709896)
			(xy 89.233624 -223.715828) (xy 89.184449 -223.713847) (xy 89.13623 -223.704003) (xy 89.090214 -223.686551)
			(xy 89.047593 -223.661944) (xy 89.009472 -223.630819) (xy 88.976837 -223.593982) (xy 88.950534 -223.552386)
			(xy 88.931243 -223.50711) (xy 88.919466 -223.459326) (xy 88.915506 -223.410272) (xy 87.64597 -223.410272)
			(xy 87.646256 -223.424496) (xy 87.645761 -223.449103) (xy 87.637866 -223.49768) (xy 87.622282 -223.544361)
			(xy 87.599411 -223.587938) (xy 87.569846 -223.627282) (xy 87.534353 -223.661374) (xy 87.49385 -223.68933)
			(xy 87.449388 -223.710428) (xy 87.402117 -223.72412) (xy 87.353262 -223.730052) (xy 87.304087 -223.728071)
			(xy 87.255868 -223.718227) (xy 87.209852 -223.700775) (xy 87.167231 -223.676168) (xy 87.12911 -223.645043)
			(xy 87.096475 -223.608206) (xy 87.070172 -223.56661) (xy 87.050881 -223.521334) (xy 87.039104 -223.47355)
			(xy 87.035144 -223.424496) (xy 86.70617 -223.424496) (xy 86.705961 -223.434879) (xy 86.698066 -223.483456)
			(xy 86.682482 -223.530137) (xy 86.659611 -223.573714) (xy 86.630046 -223.613058) (xy 86.594553 -223.64715)
			(xy 86.55405 -223.675106) (xy 86.509588 -223.696204) (xy 86.462317 -223.709896) (xy 86.413462 -223.715828)
			(xy 86.364287 -223.713847) (xy 86.316068 -223.704003) (xy 86.270052 -223.686551) (xy 86.227431 -223.661944)
			(xy 86.18931 -223.630819) (xy 86.156675 -223.593982) (xy 86.130372 -223.552386) (xy 86.111081 -223.50711)
			(xy 86.099304 -223.459326) (xy 86.095344 -223.410272) (xy 84.826062 -223.410272) (xy 84.826348 -223.424496)
			(xy 84.825853 -223.449103) (xy 84.817958 -223.49768) (xy 84.802374 -223.544361) (xy 84.779503 -223.587938)
			(xy 84.749938 -223.627282) (xy 84.714445 -223.661374) (xy 84.673942 -223.68933) (xy 84.62948 -223.710428)
			(xy 84.582209 -223.72412) (xy 84.533354 -223.730052) (xy 84.484179 -223.728071) (xy 84.43596 -223.718227)
			(xy 84.389944 -223.700775) (xy 84.347323 -223.676168) (xy 84.309202 -223.645043) (xy 84.276567 -223.608206)
			(xy 84.250264 -223.56661) (xy 84.230973 -223.521334) (xy 84.219196 -223.47355) (xy 84.215236 -223.424496)
			(xy 83.901534 -223.424496) (xy 83.901534 -223.63303) (xy 83.901995 -223.642907) (xy 83.909434 -223.661209)
			(xy 83.916012 -223.66859) (xy 83.916266 -223.668844) (xy 84.171028 -223.923606) (xy 84.171536 -223.924114)
			(xy 84.178914 -223.930703) (xy 84.197214 -223.938166) (xy 84.207096 -223.938592) (xy 84.909152 -223.938592)
			(xy 84.918804 -223.937576) (xy 84.922106 -223.936814) (xy 84.945064 -223.93197) (xy 84.991859 -223.928555)
			(xy 85.038627 -223.932324) (xy 85.061552 -223.937322) (xy 85.067394 -223.938592) (xy 85.09 -223.938592)
			(xy 85.099835 -223.939133) (xy 85.117989 -223.946727) (xy 85.125306 -223.953324) (xy 85.139276 -223.967294)
			(xy 85.145118 -223.970596) (xy 85.16744 -223.984261) (xy 85.207468 -224.017973) (xy 85.241172 -224.058007)
			(xy 85.254846 -224.080324) (xy 85.258148 -224.086166) (xy 85.296502 -224.12452) (xy 85.303215 -224.131758)
			(xy 85.310808 -224.149963) (xy 85.311234 -224.159826) (xy 85.311234 -224.234502) (xy 86.565244 -224.234502)
			(xy 86.569204 -224.185448) (xy 86.580981 -224.137664) (xy 86.600272 -224.092388) (xy 86.626575 -224.050792)
			(xy 86.65921 -224.013955) (xy 86.697331 -223.98283) (xy 86.739952 -223.958223) (xy 86.785968 -223.940771)
			(xy 86.834187 -223.930927) (xy 86.883362 -223.928946) (xy 86.932217 -223.934878) (xy 86.979488 -223.94857)
			(xy 87.02395 -223.969668) (xy 87.064453 -223.997624) (xy 87.099946 -224.031716) (xy 87.129511 -224.07106)
			(xy 87.152382 -224.114637) (xy 87.167966 -224.161318) (xy 87.175861 -224.209895) (xy 87.176356 -224.234502)
			(xy 87.505298 -224.234502) (xy 87.509258 -224.185448) (xy 87.521035 -224.137664) (xy 87.540326 -224.092388)
			(xy 87.566629 -224.050792) (xy 87.599264 -224.013955) (xy 87.637385 -223.98283) (xy 87.680006 -223.958223)
			(xy 87.726022 -223.940771) (xy 87.774241 -223.930927) (xy 87.823416 -223.928946) (xy 87.872271 -223.934878)
			(xy 87.919542 -223.94857) (xy 87.964004 -223.969668) (xy 88.004507 -223.997624) (xy 88.04 -224.031716)
			(xy 88.069565 -224.07106) (xy 88.092436 -224.114637) (xy 88.10802 -224.161318) (xy 88.115915 -224.209895)
			(xy 88.11641 -224.234502) (xy 89.385152 -224.234502) (xy 89.389112 -224.185448) (xy 89.400889 -224.137664)
			(xy 89.42018 -224.092388) (xy 89.446483 -224.050792) (xy 89.479118 -224.013955) (xy 89.517239 -223.98283)
			(xy 89.55986 -223.958223) (xy 89.605876 -223.940771) (xy 89.654095 -223.930927) (xy 89.70327 -223.928946)
			(xy 89.752125 -223.934878) (xy 89.799396 -223.94857) (xy 89.843858 -223.969668) (xy 89.884361 -223.997624)
			(xy 89.919854 -224.031716) (xy 89.949419 -224.07106) (xy 89.97229 -224.114637) (xy 89.987874 -224.161318)
			(xy 89.995769 -224.209895) (xy 89.996264 -224.234502) (xy 90.325206 -224.234502) (xy 90.329166 -224.185448)
			(xy 90.340943 -224.137664) (xy 90.360234 -224.092388) (xy 90.386537 -224.050792) (xy 90.419172 -224.013955)
			(xy 90.457293 -223.98283) (xy 90.499914 -223.958223) (xy 90.54593 -223.940771) (xy 90.594149 -223.930927)
			(xy 90.643324 -223.928946) (xy 90.692179 -223.934878) (xy 90.73945 -223.94857) (xy 90.783912 -223.969668)
			(xy 90.824415 -223.997624) (xy 90.859908 -224.031716) (xy 90.889473 -224.07106) (xy 90.912344 -224.114637)
			(xy 90.927928 -224.161318) (xy 90.935823 -224.209895) (xy 90.936318 -224.234502) (xy 91.26526 -224.234502)
			(xy 91.26922 -224.185448) (xy 91.280997 -224.137664) (xy 91.300288 -224.092388) (xy 91.326591 -224.050792)
			(xy 91.359226 -224.013955) (xy 91.397347 -223.98283) (xy 91.439968 -223.958223) (xy 91.485984 -223.940771)
			(xy 91.534203 -223.930927) (xy 91.583378 -223.928946) (xy 91.632233 -223.934878) (xy 91.679504 -223.94857)
			(xy 91.723966 -223.969668) (xy 91.764469 -223.997624) (xy 91.799962 -224.031716) (xy 91.829527 -224.07106)
			(xy 91.852398 -224.114637) (xy 91.867982 -224.161318) (xy 91.875877 -224.209895) (xy 91.876372 -224.234502)
			(xy 93.145114 -224.234502) (xy 93.149074 -224.185448) (xy 93.160851 -224.137664) (xy 93.180142 -224.092388)
			(xy 93.206445 -224.050792) (xy 93.23908 -224.013955) (xy 93.277201 -223.98283) (xy 93.319822 -223.958223)
			(xy 93.365838 -223.940771) (xy 93.414057 -223.930927) (xy 93.463232 -223.928946) (xy 93.512087 -223.934878)
			(xy 93.559358 -223.94857) (xy 93.60382 -223.969668) (xy 93.644323 -223.997624) (xy 93.679816 -224.031716)
			(xy 93.709381 -224.07106) (xy 93.732252 -224.114637) (xy 93.747836 -224.161318) (xy 93.755731 -224.209895)
			(xy 93.756226 -224.234502) (xy 93.755731 -224.259109) (xy 93.747836 -224.307686) (xy 93.732252 -224.354367)
			(xy 93.709381 -224.397944) (xy 93.679816 -224.437288) (xy 93.644323 -224.47138) (xy 93.60382 -224.499336)
			(xy 93.559358 -224.520434) (xy 93.512087 -224.534126) (xy 93.463232 -224.540058) (xy 93.414057 -224.538077)
			(xy 93.365838 -224.528233) (xy 93.319822 -224.510781) (xy 93.277201 -224.486174) (xy 93.23908 -224.455049)
			(xy 93.206445 -224.418212) (xy 93.180142 -224.376616) (xy 93.160851 -224.33134) (xy 93.149074 -224.283556)
			(xy 93.145114 -224.234502) (xy 91.876372 -224.234502) (xy 91.875877 -224.259109) (xy 91.867982 -224.307686)
			(xy 91.852398 -224.354367) (xy 91.829527 -224.397944) (xy 91.799962 -224.437288) (xy 91.764469 -224.47138)
			(xy 91.723966 -224.499336) (xy 91.679504 -224.520434) (xy 91.632233 -224.534126) (xy 91.583378 -224.540058)
			(xy 91.534203 -224.538077) (xy 91.485984 -224.528233) (xy 91.439968 -224.510781) (xy 91.397347 -224.486174)
			(xy 91.359226 -224.455049) (xy 91.326591 -224.418212) (xy 91.300288 -224.376616) (xy 91.280997 -224.33134)
			(xy 91.26922 -224.283556) (xy 91.26526 -224.234502) (xy 90.936318 -224.234502) (xy 90.935823 -224.259109)
			(xy 90.927928 -224.307686) (xy 90.912344 -224.354367) (xy 90.889473 -224.397944) (xy 90.859908 -224.437288)
			(xy 90.824415 -224.47138) (xy 90.783912 -224.499336) (xy 90.73945 -224.520434) (xy 90.692179 -224.534126)
			(xy 90.643324 -224.540058) (xy 90.594149 -224.538077) (xy 90.54593 -224.528233) (xy 90.499914 -224.510781)
			(xy 90.457293 -224.486174) (xy 90.419172 -224.455049) (xy 90.386537 -224.418212) (xy 90.360234 -224.376616)
			(xy 90.340943 -224.33134) (xy 90.329166 -224.283556) (xy 90.325206 -224.234502) (xy 89.996264 -224.234502)
			(xy 89.995769 -224.259109) (xy 89.987874 -224.307686) (xy 89.97229 -224.354367) (xy 89.949419 -224.397944)
			(xy 89.919854 -224.437288) (xy 89.884361 -224.47138) (xy 89.843858 -224.499336) (xy 89.799396 -224.520434)
			(xy 89.752125 -224.534126) (xy 89.70327 -224.540058) (xy 89.654095 -224.538077) (xy 89.605876 -224.528233)
			(xy 89.55986 -224.510781) (xy 89.517239 -224.486174) (xy 89.479118 -224.455049) (xy 89.446483 -224.418212)
			(xy 89.42018 -224.376616) (xy 89.400889 -224.33134) (xy 89.389112 -224.283556) (xy 89.385152 -224.234502)
			(xy 88.11641 -224.234502) (xy 88.115915 -224.259109) (xy 88.10802 -224.307686) (xy 88.092436 -224.354367)
			(xy 88.069565 -224.397944) (xy 88.04 -224.437288) (xy 88.004507 -224.47138) (xy 87.964004 -224.499336)
			(xy 87.919542 -224.520434) (xy 87.872271 -224.534126) (xy 87.823416 -224.540058) (xy 87.774241 -224.538077)
			(xy 87.726022 -224.528233) (xy 87.680006 -224.510781) (xy 87.637385 -224.486174) (xy 87.599264 -224.455049)
			(xy 87.566629 -224.418212) (xy 87.540326 -224.376616) (xy 87.521035 -224.33134) (xy 87.509258 -224.283556)
			(xy 87.505298 -224.234502) (xy 87.176356 -224.234502) (xy 87.175861 -224.259109) (xy 87.167966 -224.307686)
			(xy 87.152382 -224.354367) (xy 87.129511 -224.397944) (xy 87.099946 -224.437288) (xy 87.064453 -224.47138)
			(xy 87.02395 -224.499336) (xy 86.979488 -224.520434) (xy 86.932217 -224.534126) (xy 86.883362 -224.540058)
			(xy 86.834187 -224.538077) (xy 86.785968 -224.528233) (xy 86.739952 -224.510781) (xy 86.697331 -224.486174)
			(xy 86.65921 -224.455049) (xy 86.626575 -224.418212) (xy 86.600272 -224.376616) (xy 86.580981 -224.33134)
			(xy 86.569204 -224.283556) (xy 86.565244 -224.234502) (xy 85.311234 -224.234502) (xy 85.311234 -224.54489)
			(xy 85.311705 -224.554763) (xy 85.31916 -224.573049) (xy 85.325712 -224.58045) (xy 85.325966 -224.580704)
			(xy 85.430868 -224.685606) (xy 85.431376 -224.686114) (xy 85.438757 -224.692697) (xy 85.457056 -224.700145)
			(xy 85.466936 -224.700592) (xy 86.50224 -224.700592) (xy 86.51208 -224.701122) (xy 86.53025 -224.708701)
			(xy 86.537546 -224.715324) (xy 86.693502 -224.87128) (xy 86.700221 -224.878516) (xy 86.707828 -224.896721)
			(xy 86.708234 -224.906586) (xy 86.708234 -225.044508) (xy 87.035144 -225.044508) (xy 87.039104 -224.995454)
			(xy 87.050881 -224.94767) (xy 87.070172 -224.902394) (xy 87.096475 -224.860798) (xy 87.12911 -224.823961)
			(xy 87.167231 -224.792836) (xy 87.209852 -224.768229) (xy 87.255868 -224.750777) (xy 87.304087 -224.740933)
			(xy 87.353262 -224.738952) (xy 87.402117 -224.744884) (xy 87.449388 -224.758576) (xy 87.49385 -224.779674)
			(xy 87.534353 -224.80763) (xy 87.569846 -224.841722) (xy 87.599411 -224.881066) (xy 87.622282 -224.924643)
			(xy 87.637866 -224.971324) (xy 87.645761 -225.019901) (xy 87.646256 -225.044508) (xy 87.975198 -225.044508)
			(xy 87.979158 -224.995454) (xy 87.990935 -224.94767) (xy 88.010226 -224.902394) (xy 88.036529 -224.860798)
			(xy 88.069164 -224.823961) (xy 88.107285 -224.792836) (xy 88.149906 -224.768229) (xy 88.195922 -224.750777)
			(xy 88.244141 -224.740933) (xy 88.293316 -224.738952) (xy 88.342171 -224.744884) (xy 88.389442 -224.758576)
			(xy 88.433904 -224.779674) (xy 88.474407 -224.80763) (xy 88.5099 -224.841722) (xy 88.539465 -224.881066)
			(xy 88.562336 -224.924643) (xy 88.57792 -224.971324) (xy 88.585815 -225.019901) (xy 88.58631 -225.044508)
			(xy 88.915252 -225.044508) (xy 88.919212 -224.995454) (xy 88.930989 -224.94767) (xy 88.95028 -224.902394)
			(xy 88.976583 -224.860798) (xy 89.009218 -224.823961) (xy 89.047339 -224.792836) (xy 89.08996 -224.768229)
			(xy 89.135976 -224.750777) (xy 89.184195 -224.740933) (xy 89.23337 -224.738952) (xy 89.282225 -224.744884)
			(xy 89.329496 -224.758576) (xy 89.373958 -224.779674) (xy 89.414461 -224.80763) (xy 89.449954 -224.841722)
			(xy 89.479519 -224.881066) (xy 89.50239 -224.924643) (xy 89.517974 -224.971324) (xy 89.525869 -225.019901)
			(xy 89.526364 -225.044508) (xy 89.855306 -225.044508) (xy 89.859266 -224.995454) (xy 89.871043 -224.94767)
			(xy 89.890334 -224.902394) (xy 89.916637 -224.860798) (xy 89.949272 -224.823961) (xy 89.987393 -224.792836)
			(xy 90.030014 -224.768229) (xy 90.07603 -224.750777) (xy 90.124249 -224.740933) (xy 90.173424 -224.738952)
			(xy 90.222279 -224.744884) (xy 90.26955 -224.758576) (xy 90.314012 -224.779674) (xy 90.354515 -224.80763)
			(xy 90.390008 -224.841722) (xy 90.419573 -224.881066) (xy 90.442444 -224.924643) (xy 90.458028 -224.971324)
			(xy 90.465923 -225.019901) (xy 90.466418 -225.044508) (xy 90.784675 -225.044508) (xy 90.78877 -224.99378)
			(xy 90.800949 -224.944366) (xy 90.820897 -224.897546) (xy 90.848098 -224.854532) (xy 90.881846 -224.816438)
			(xy 90.921268 -224.784251) (xy 90.965342 -224.758805) (xy 91.012928 -224.740758) (xy 91.062792 -224.730578)
			(xy 91.113644 -224.728529) (xy 91.164165 -224.734663) (xy 91.213049 -224.748823) (xy 91.259028 -224.77064)
			(xy 91.300912 -224.79955) (xy 91.337616 -224.834805) (xy 91.368189 -224.875491) (xy 91.39184 -224.920554)
			(xy 91.407956 -224.968828) (xy 91.41612 -225.019062) (xy 91.416632 -225.044508) (xy 91.73516 -225.044508)
			(xy 91.73912 -224.995454) (xy 91.750897 -224.94767) (xy 91.770188 -224.902394) (xy 91.796491 -224.860798)
			(xy 91.829126 -224.823961) (xy 91.867247 -224.792836) (xy 91.909868 -224.768229) (xy 91.955884 -224.750777)
			(xy 92.004103 -224.740933) (xy 92.053278 -224.738952) (xy 92.102133 -224.744884) (xy 92.149404 -224.758576)
			(xy 92.193866 -224.779674) (xy 92.234369 -224.80763) (xy 92.269862 -224.841722) (xy 92.299427 -224.881066)
			(xy 92.322298 -224.924643) (xy 92.337882 -224.971324) (xy 92.345777 -225.019901) (xy 92.346272 -225.044508)
			(xy 92.675214 -225.044508) (xy 92.679174 -224.995454) (xy 92.690951 -224.94767) (xy 92.710242 -224.902394)
			(xy 92.736545 -224.860798) (xy 92.76918 -224.823961) (xy 92.807301 -224.792836) (xy 92.849922 -224.768229)
			(xy 92.895938 -224.750777) (xy 92.944157 -224.740933) (xy 92.993332 -224.738952) (xy 93.042187 -224.744884)
			(xy 93.089458 -224.758576) (xy 93.13392 -224.779674) (xy 93.174423 -224.80763) (xy 93.209916 -224.841722)
			(xy 93.239481 -224.881066) (xy 93.262352 -224.924643) (xy 93.277936 -224.971324) (xy 93.285831 -225.019901)
			(xy 93.286326 -225.044508) (xy 93.604837 -225.044508) (xy 93.608932 -224.99378) (xy 93.621111 -224.944366)
			(xy 93.641059 -224.897546) (xy 93.66826 -224.854532) (xy 93.702008 -224.816438) (xy 93.74143 -224.784251)
			(xy 93.785504 -224.758805) (xy 93.83309 -224.740758) (xy 93.882954 -224.730578) (xy 93.933806 -224.728529)
			(xy 93.984327 -224.734663) (xy 94.033211 -224.748823) (xy 94.07919 -224.77064) (xy 94.121074 -224.79955)
			(xy 94.157778 -224.834805) (xy 94.188351 -224.875491) (xy 94.212002 -224.920554) (xy 94.228118 -224.968828)
			(xy 94.236282 -225.019062) (xy 94.236794 -225.044508) (xy 94.236282 -225.069954) (xy 94.228118 -225.120188)
			(xy 94.212002 -225.168462) (xy 94.188351 -225.213525) (xy 94.157778 -225.254211) (xy 94.121074 -225.289466)
			(xy 94.07919 -225.318376) (xy 94.033211 -225.340193) (xy 93.984327 -225.354353) (xy 93.933806 -225.360487)
			(xy 93.882954 -225.358438) (xy 93.83309 -225.348258) (xy 93.785504 -225.330211) (xy 93.74143 -225.304765)
			(xy 93.702008 -225.272578) (xy 93.66826 -225.234484) (xy 93.641059 -225.19147) (xy 93.621111 -225.14465)
			(xy 93.608932 -225.095236) (xy 93.604837 -225.044508) (xy 93.286326 -225.044508) (xy 93.285831 -225.069115)
			(xy 93.277936 -225.117692) (xy 93.262352 -225.164373) (xy 93.239481 -225.20795) (xy 93.209916 -225.247294)
			(xy 93.174423 -225.281386) (xy 93.13392 -225.309342) (xy 93.089458 -225.33044) (xy 93.042187 -225.344132)
			(xy 92.993332 -225.350064) (xy 92.944157 -225.348083) (xy 92.895938 -225.338239) (xy 92.849922 -225.320787)
			(xy 92.807301 -225.29618) (xy 92.76918 -225.265055) (xy 92.736545 -225.228218) (xy 92.710242 -225.186622)
			(xy 92.690951 -225.141346) (xy 92.679174 -225.093562) (xy 92.675214 -225.044508) (xy 92.346272 -225.044508)
			(xy 92.345777 -225.069115) (xy 92.337882 -225.117692) (xy 92.322298 -225.164373) (xy 92.299427 -225.20795)
			(xy 92.269862 -225.247294) (xy 92.234369 -225.281386) (xy 92.193866 -225.309342) (xy 92.149404 -225.33044)
			(xy 92.102133 -225.344132) (xy 92.053278 -225.350064) (xy 92.004103 -225.348083) (xy 91.955884 -225.338239)
			(xy 91.909868 -225.320787) (xy 91.867247 -225.29618) (xy 91.829126 -225.265055) (xy 91.796491 -225.228218)
			(xy 91.770188 -225.186622) (xy 91.750897 -225.141346) (xy 91.73912 -225.093562) (xy 91.73516 -225.044508)
			(xy 91.416632 -225.044508) (xy 91.41612 -225.069954) (xy 91.407956 -225.120188) (xy 91.39184 -225.168462)
			(xy 91.368189 -225.213525) (xy 91.337616 -225.254211) (xy 91.300912 -225.289466) (xy 91.259028 -225.318376)
			(xy 91.213049 -225.340193) (xy 91.164165 -225.354353) (xy 91.113644 -225.360487) (xy 91.062792 -225.358438)
			(xy 91.012928 -225.348258) (xy 90.965342 -225.330211) (xy 90.921268 -225.304765) (xy 90.881846 -225.272578)
			(xy 90.848098 -225.234484) (xy 90.820897 -225.19147) (xy 90.800949 -225.14465) (xy 90.78877 -225.095236)
			(xy 90.784675 -225.044508) (xy 90.466418 -225.044508) (xy 90.465923 -225.069115) (xy 90.458028 -225.117692)
			(xy 90.442444 -225.164373) (xy 90.419573 -225.20795) (xy 90.390008 -225.247294) (xy 90.354515 -225.281386)
			(xy 90.314012 -225.309342) (xy 90.26955 -225.33044) (xy 90.222279 -225.344132) (xy 90.173424 -225.350064)
			(xy 90.124249 -225.348083) (xy 90.07603 -225.338239) (xy 90.030014 -225.320787) (xy 89.987393 -225.29618)
			(xy 89.949272 -225.265055) (xy 89.916637 -225.228218) (xy 89.890334 -225.186622) (xy 89.871043 -225.141346)
			(xy 89.859266 -225.093562) (xy 89.855306 -225.044508) (xy 89.526364 -225.044508) (xy 89.525869 -225.069115)
			(xy 89.517974 -225.117692) (xy 89.50239 -225.164373) (xy 89.479519 -225.20795) (xy 89.449954 -225.247294)
			(xy 89.414461 -225.281386) (xy 89.373958 -225.309342) (xy 89.329496 -225.33044) (xy 89.282225 -225.344132)
			(xy 89.23337 -225.350064) (xy 89.184195 -225.348083) (xy 89.135976 -225.338239) (xy 89.08996 -225.320787)
			(xy 89.047339 -225.29618) (xy 89.009218 -225.265055) (xy 88.976583 -225.228218) (xy 88.95028 -225.186622)
			(xy 88.930989 -225.141346) (xy 88.919212 -225.093562) (xy 88.915252 -225.044508) (xy 88.58631 -225.044508)
			(xy 88.585815 -225.069115) (xy 88.57792 -225.117692) (xy 88.562336 -225.164373) (xy 88.539465 -225.20795)
			(xy 88.5099 -225.247294) (xy 88.474407 -225.281386) (xy 88.433904 -225.309342) (xy 88.389442 -225.33044)
			(xy 88.342171 -225.344132) (xy 88.293316 -225.350064) (xy 88.244141 -225.348083) (xy 88.195922 -225.338239)
			(xy 88.149906 -225.320787) (xy 88.107285 -225.29618) (xy 88.069164 -225.265055) (xy 88.036529 -225.228218)
			(xy 88.010226 -225.186622) (xy 87.990935 -225.141346) (xy 87.979158 -225.093562) (xy 87.975198 -225.044508)
			(xy 87.646256 -225.044508) (xy 87.645761 -225.069115) (xy 87.637866 -225.117692) (xy 87.622282 -225.164373)
			(xy 87.599411 -225.20795) (xy 87.569846 -225.247294) (xy 87.534353 -225.281386) (xy 87.49385 -225.309342)
			(xy 87.449388 -225.33044) (xy 87.402117 -225.344132) (xy 87.353262 -225.350064) (xy 87.304087 -225.348083)
			(xy 87.255868 -225.338239) (xy 87.209852 -225.320787) (xy 87.167231 -225.29618) (xy 87.12911 -225.265055)
			(xy 87.096475 -225.228218) (xy 87.070172 -225.186622) (xy 87.050881 -225.141346) (xy 87.039104 -225.093562)
			(xy 87.035144 -225.044508) (xy 86.708234 -225.044508) (xy 86.708234 -225.21037) (xy 86.708702 -225.220244)
			(xy 86.716151 -225.238535) (xy 86.722712 -225.24593) (xy 86.722966 -225.246184) (xy 87.130382 -225.6536)
			(xy 87.1371 -225.660836) (xy 87.144704 -225.679041) (xy 87.145114 -225.688906) (xy 87.145114 -225.701606)
			(xy 87.14613 -225.71202) (xy 87.14994 -225.730054) (xy 87.151972 -225.73488) (xy 87.163228 -225.763174)
			(xy 87.175511 -225.822805) (xy 87.176356 -225.853244) (xy 87.176356 -225.854514) (xy 87.505298 -225.854514)
			(xy 87.509258 -225.80546) (xy 87.521035 -225.757676) (xy 87.540326 -225.7124) (xy 87.566629 -225.670804)
			(xy 87.599264 -225.633967) (xy 87.637385 -225.602842) (xy 87.680006 -225.578235) (xy 87.726022 -225.560783)
			(xy 87.774241 -225.550939) (xy 87.823416 -225.548958) (xy 87.872271 -225.55489) (xy 87.919542 -225.568582)
			(xy 87.964004 -225.58968) (xy 88.004507 -225.617636) (xy 88.04 -225.651728) (xy 88.069565 -225.691072)
			(xy 88.092436 -225.734649) (xy 88.10802 -225.78133) (xy 88.115915 -225.829907) (xy 88.11641 -225.854514)
			(xy 88.445352 -225.854514) (xy 88.449312 -225.80546) (xy 88.461089 -225.757676) (xy 88.48038 -225.7124)
			(xy 88.506683 -225.670804) (xy 88.539318 -225.633967) (xy 88.577439 -225.602842) (xy 88.62006 -225.578235)
			(xy 88.666076 -225.560783) (xy 88.714295 -225.550939) (xy 88.76347 -225.548958) (xy 88.812325 -225.55489)
			(xy 88.859596 -225.568582) (xy 88.904058 -225.58968) (xy 88.944561 -225.617636) (xy 88.980054 -225.651728)
			(xy 89.009619 -225.691072) (xy 89.03249 -225.734649) (xy 89.048074 -225.78133) (xy 89.055969 -225.829907)
			(xy 89.056464 -225.854514) (xy 89.385152 -225.854514) (xy 89.389112 -225.80546) (xy 89.400889 -225.757676)
			(xy 89.42018 -225.7124) (xy 89.446483 -225.670804) (xy 89.479118 -225.633967) (xy 89.517239 -225.602842)
			(xy 89.55986 -225.578235) (xy 89.605876 -225.560783) (xy 89.654095 -225.550939) (xy 89.70327 -225.548958)
			(xy 89.752125 -225.55489) (xy 89.799396 -225.568582) (xy 89.843858 -225.58968) (xy 89.884361 -225.617636)
			(xy 89.919854 -225.651728) (xy 89.949419 -225.691072) (xy 89.97229 -225.734649) (xy 89.987874 -225.78133)
			(xy 89.995769 -225.829907) (xy 89.996264 -225.854514) (xy 90.314775 -225.854514) (xy 90.31887 -225.803786)
			(xy 90.331049 -225.754372) (xy 90.350997 -225.707552) (xy 90.378198 -225.664538) (xy 90.411946 -225.626444)
			(xy 90.451368 -225.594257) (xy 90.495442 -225.568811) (xy 90.543028 -225.550764) (xy 90.592892 -225.540584)
			(xy 90.643744 -225.538535) (xy 90.694265 -225.544669) (xy 90.743149 -225.558829) (xy 90.789128 -225.580646)
			(xy 90.831012 -225.609556) (xy 90.867716 -225.644811) (xy 90.898289 -225.685497) (xy 90.92194 -225.73056)
			(xy 90.938056 -225.778834) (xy 90.94622 -225.829068) (xy 90.946732 -225.854514) (xy 91.26526 -225.854514)
			(xy 91.26922 -225.80546) (xy 91.280997 -225.757676) (xy 91.300288 -225.7124) (xy 91.326591 -225.670804)
			(xy 91.359226 -225.633967) (xy 91.397347 -225.602842) (xy 91.439968 -225.578235) (xy 91.485984 -225.560783)
			(xy 91.534203 -225.550939) (xy 91.583378 -225.548958) (xy 91.632233 -225.55489) (xy 91.679504 -225.568582)
			(xy 91.723966 -225.58968) (xy 91.764469 -225.617636) (xy 91.799962 -225.651728) (xy 91.829527 -225.691072)
			(xy 91.852398 -225.734649) (xy 91.867982 -225.78133) (xy 91.875877 -225.829907) (xy 91.876372 -225.854514)
			(xy 92.194883 -225.854514) (xy 92.198978 -225.803786) (xy 92.211157 -225.754372) (xy 92.231105 -225.707552)
			(xy 92.258306 -225.664538) (xy 92.292054 -225.626444) (xy 92.331476 -225.594257) (xy 92.37555 -225.568811)
			(xy 92.423136 -225.550764) (xy 92.473 -225.540584) (xy 92.523852 -225.538535) (xy 92.574373 -225.544669)
			(xy 92.623257 -225.558829) (xy 92.669236 -225.580646) (xy 92.71112 -225.609556) (xy 92.747824 -225.644811)
			(xy 92.778397 -225.685497) (xy 92.802048 -225.73056) (xy 92.818164 -225.778834) (xy 92.826328 -225.829068)
			(xy 92.82684 -225.854514) (xy 93.145114 -225.854514) (xy 93.149074 -225.80546) (xy 93.160851 -225.757676)
			(xy 93.180142 -225.7124) (xy 93.206445 -225.670804) (xy 93.23908 -225.633967) (xy 93.277201 -225.602842)
			(xy 93.319822 -225.578235) (xy 93.365838 -225.560783) (xy 93.414057 -225.550939) (xy 93.463232 -225.548958)
			(xy 93.512087 -225.55489) (xy 93.559358 -225.568582) (xy 93.60382 -225.58968) (xy 93.644323 -225.617636)
			(xy 93.679816 -225.651728) (xy 93.709381 -225.691072) (xy 93.732252 -225.734649) (xy 93.747836 -225.78133)
			(xy 93.755731 -225.829907) (xy 93.756226 -225.854514) (xy 94.074737 -225.854514) (xy 94.078832 -225.803786)
			(xy 94.091011 -225.754372) (xy 94.110959 -225.707552) (xy 94.13816 -225.664538) (xy 94.171908 -225.626444)
			(xy 94.21133 -225.594257) (xy 94.255404 -225.568811) (xy 94.30299 -225.550764) (xy 94.352854 -225.540584)
			(xy 94.403706 -225.538535) (xy 94.454227 -225.544669) (xy 94.503111 -225.558829) (xy 94.54909 -225.580646)
			(xy 94.590974 -225.609556) (xy 94.627678 -225.644811) (xy 94.658251 -225.685497) (xy 94.681902 -225.73056)
			(xy 94.698018 -225.778834) (xy 94.706182 -225.829068) (xy 94.706694 -225.854514) (xy 94.706182 -225.87996)
			(xy 94.698018 -225.930194) (xy 94.681902 -225.978468) (xy 94.658251 -226.023531) (xy 94.627678 -226.064217)
			(xy 94.590974 -226.099472) (xy 94.54909 -226.128382) (xy 94.503111 -226.150199) (xy 94.454227 -226.164359)
			(xy 94.403706 -226.170493) (xy 94.352854 -226.168444) (xy 94.30299 -226.158264) (xy 94.255404 -226.140217)
			(xy 94.21133 -226.114771) (xy 94.171908 -226.082584) (xy 94.13816 -226.04449) (xy 94.110959 -226.001476)
			(xy 94.091011 -225.954656) (xy 94.078832 -225.905242) (xy 94.074737 -225.854514) (xy 93.756226 -225.854514)
			(xy 93.755731 -225.879121) (xy 93.747836 -225.927698) (xy 93.732252 -225.974379) (xy 93.709381 -226.017956)
			(xy 93.679816 -226.0573) (xy 93.644323 -226.091392) (xy 93.60382 -226.119348) (xy 93.559358 -226.140446)
			(xy 93.512087 -226.154138) (xy 93.463232 -226.16007) (xy 93.414057 -226.158089) (xy 93.365838 -226.148245)
			(xy 93.319822 -226.130793) (xy 93.277201 -226.106186) (xy 93.23908 -226.075061) (xy 93.206445 -226.038224)
			(xy 93.180142 -225.996628) (xy 93.160851 -225.951352) (xy 93.149074 -225.903568) (xy 93.145114 -225.854514)
			(xy 92.82684 -225.854514) (xy 92.826328 -225.87996) (xy 92.818164 -225.930194) (xy 92.802048 -225.978468)
			(xy 92.778397 -226.023531) (xy 92.747824 -226.064217) (xy 92.71112 -226.099472) (xy 92.669236 -226.128382)
			(xy 92.623257 -226.150199) (xy 92.574373 -226.164359) (xy 92.523852 -226.170493) (xy 92.473 -226.168444)
			(xy 92.423136 -226.158264) (xy 92.37555 -226.140217) (xy 92.331476 -226.114771) (xy 92.292054 -226.082584)
			(xy 92.258306 -226.04449) (xy 92.231105 -226.001476) (xy 92.211157 -225.954656) (xy 92.198978 -225.905242)
			(xy 92.194883 -225.854514) (xy 91.876372 -225.854514) (xy 91.875877 -225.879121) (xy 91.867982 -225.927698)
			(xy 91.852398 -225.974379) (xy 91.829527 -226.017956) (xy 91.799962 -226.0573) (xy 91.764469 -226.091392)
			(xy 91.723966 -226.119348) (xy 91.679504 -226.140446) (xy 91.632233 -226.154138) (xy 91.583378 -226.16007)
			(xy 91.534203 -226.158089) (xy 91.485984 -226.148245) (xy 91.439968 -226.130793) (xy 91.397347 -226.106186)
			(xy 91.359226 -226.075061) (xy 91.326591 -226.038224) (xy 91.300288 -225.996628) (xy 91.280997 -225.951352)
			(xy 91.26922 -225.903568) (xy 91.26526 -225.854514) (xy 90.946732 -225.854514) (xy 90.94622 -225.87996)
			(xy 90.938056 -225.930194) (xy 90.92194 -225.978468) (xy 90.898289 -226.023531) (xy 90.867716 -226.064217)
			(xy 90.831012 -226.099472) (xy 90.789128 -226.128382) (xy 90.743149 -226.150199) (xy 90.694265 -226.164359)
			(xy 90.643744 -226.170493) (xy 90.592892 -226.168444) (xy 90.543028 -226.158264) (xy 90.495442 -226.140217)
			(xy 90.451368 -226.114771) (xy 90.411946 -226.082584) (xy 90.378198 -226.04449) (xy 90.350997 -226.001476)
			(xy 90.331049 -225.954656) (xy 90.31887 -225.905242) (xy 90.314775 -225.854514) (xy 89.996264 -225.854514)
			(xy 89.995769 -225.879121) (xy 89.987874 -225.927698) (xy 89.97229 -225.974379) (xy 89.949419 -226.017956)
			(xy 89.919854 -226.0573) (xy 89.884361 -226.091392) (xy 89.843858 -226.119348) (xy 89.799396 -226.140446)
			(xy 89.752125 -226.154138) (xy 89.70327 -226.16007) (xy 89.654095 -226.158089) (xy 89.605876 -226.148245)
			(xy 89.55986 -226.130793) (xy 89.517239 -226.106186) (xy 89.479118 -226.075061) (xy 89.446483 -226.038224)
			(xy 89.42018 -225.996628) (xy 89.400889 -225.951352) (xy 89.389112 -225.903568) (xy 89.385152 -225.854514)
			(xy 89.056464 -225.854514) (xy 89.055969 -225.879121) (xy 89.048074 -225.927698) (xy 89.03249 -225.974379)
			(xy 89.009619 -226.017956) (xy 88.980054 -226.0573) (xy 88.944561 -226.091392) (xy 88.904058 -226.119348)
			(xy 88.859596 -226.140446) (xy 88.812325 -226.154138) (xy 88.76347 -226.16007) (xy 88.714295 -226.158089)
			(xy 88.666076 -226.148245) (xy 88.62006 -226.130793) (xy 88.577439 -226.106186) (xy 88.539318 -226.075061)
			(xy 88.506683 -226.038224) (xy 88.48038 -225.996628) (xy 88.461089 -225.951352) (xy 88.449312 -225.903568)
			(xy 88.445352 -225.854514) (xy 88.11641 -225.854514) (xy 88.115915 -225.879121) (xy 88.10802 -225.927698)
			(xy 88.092436 -225.974379) (xy 88.069565 -226.017956) (xy 88.04 -226.0573) (xy 88.004507 -226.091392)
			(xy 87.964004 -226.119348) (xy 87.919542 -226.140446) (xy 87.872271 -226.154138) (xy 87.823416 -226.16007)
			(xy 87.774241 -226.158089) (xy 87.726022 -226.148245) (xy 87.680006 -226.130793) (xy 87.637385 -226.106186)
			(xy 87.599264 -226.075061) (xy 87.566629 -226.038224) (xy 87.540326 -225.996628) (xy 87.521035 -225.951352)
			(xy 87.509258 -225.903568) (xy 87.505298 -225.854514) (xy 87.176356 -225.854514) (xy 87.176356 -225.855784)
			(xy 87.175706 -225.882392) (xy 87.166256 -225.934768) (xy 87.15756 -225.959924) (xy 87.157306 -225.960686)
			(xy 87.157052 -225.961448) (xy 87.154004 -225.969576) (xy 87.15121 -225.976688) (xy 87.149432 -225.981006)
			(xy 87.145368 -226.000056) (xy 87.145114 -226.00412) (xy 87.144104 -226.013105) (xy 87.136557 -226.02952)
			(xy 87.130382 -226.036124) (xy 86.728046 -226.43846) (xy 86.72133 -226.445697) (xy 86.713723 -226.463902)
			(xy 86.713314 -226.473766) (xy 86.713314 -226.66452) (xy 87.035144 -226.66452) (xy 87.039104 -226.615466)
			(xy 87.050881 -226.567682) (xy 87.070172 -226.522406) (xy 87.096475 -226.48081) (xy 87.12911 -226.443973)
			(xy 87.167231 -226.412848) (xy 87.209852 -226.388241) (xy 87.255868 -226.370789) (xy 87.304087 -226.360945)
			(xy 87.353262 -226.358964) (xy 87.402117 -226.364896) (xy 87.449388 -226.378588) (xy 87.49385 -226.399686)
			(xy 87.534353 -226.427642) (xy 87.569846 -226.461734) (xy 87.599411 -226.501078) (xy 87.622282 -226.544655)
			(xy 87.637866 -226.591336) (xy 87.645761 -226.639913) (xy 87.646256 -226.66452) (xy 87.975198 -226.66452)
			(xy 87.979158 -226.615466) (xy 87.990935 -226.567682) (xy 88.010226 -226.522406) (xy 88.036529 -226.48081)
			(xy 88.069164 -226.443973) (xy 88.107285 -226.412848) (xy 88.149906 -226.388241) (xy 88.195922 -226.370789)
			(xy 88.244141 -226.360945) (xy 88.293316 -226.358964) (xy 88.342171 -226.364896) (xy 88.389442 -226.378588)
			(xy 88.433904 -226.399686) (xy 88.474407 -226.427642) (xy 88.5099 -226.461734) (xy 88.539465 -226.501078)
			(xy 88.562336 -226.544655) (xy 88.57792 -226.591336) (xy 88.585815 -226.639913) (xy 88.58631 -226.66452)
			(xy 88.915252 -226.66452) (xy 88.919212 -226.615466) (xy 88.930989 -226.567682) (xy 88.95028 -226.522406)
			(xy 88.976583 -226.48081) (xy 89.009218 -226.443973) (xy 89.047339 -226.412848) (xy 89.08996 -226.388241)
			(xy 89.135976 -226.370789) (xy 89.184195 -226.360945) (xy 89.23337 -226.358964) (xy 89.282225 -226.364896)
			(xy 89.329496 -226.378588) (xy 89.373958 -226.399686) (xy 89.414461 -226.427642) (xy 89.449954 -226.461734)
			(xy 89.479519 -226.501078) (xy 89.50239 -226.544655) (xy 89.517974 -226.591336) (xy 89.525869 -226.639913)
			(xy 89.526364 -226.66452) (xy 89.855306 -226.66452) (xy 89.859266 -226.615466) (xy 89.871043 -226.567682)
			(xy 89.890334 -226.522406) (xy 89.916637 -226.48081) (xy 89.949272 -226.443973) (xy 89.987393 -226.412848)
			(xy 90.030014 -226.388241) (xy 90.07603 -226.370789) (xy 90.124249 -226.360945) (xy 90.173424 -226.358964)
			(xy 90.222279 -226.364896) (xy 90.26955 -226.378588) (xy 90.314012 -226.399686) (xy 90.354515 -226.427642)
			(xy 90.390008 -226.461734) (xy 90.419573 -226.501078) (xy 90.442444 -226.544655) (xy 90.458028 -226.591336)
			(xy 90.465923 -226.639913) (xy 90.466418 -226.66452) (xy 90.784675 -226.66452) (xy 90.78877 -226.613792)
			(xy 90.800949 -226.564378) (xy 90.820897 -226.517558) (xy 90.848098 -226.474544) (xy 90.881846 -226.43645)
			(xy 90.921268 -226.404263) (xy 90.965342 -226.378817) (xy 91.012928 -226.36077) (xy 91.062792 -226.35059)
			(xy 91.113644 -226.348541) (xy 91.164165 -226.354675) (xy 91.213049 -226.368835) (xy 91.259028 -226.390652)
			(xy 91.300912 -226.419562) (xy 91.337616 -226.454817) (xy 91.368189 -226.495503) (xy 91.39184 -226.540566)
			(xy 91.407956 -226.58884) (xy 91.41612 -226.639074) (xy 91.416632 -226.66452) (xy 91.724729 -226.66452)
			(xy 91.728824 -226.613792) (xy 91.741003 -226.564378) (xy 91.760951 -226.517558) (xy 91.788152 -226.474544)
			(xy 91.8219 -226.43645) (xy 91.861322 -226.404263) (xy 91.905396 -226.378817) (xy 91.952982 -226.36077)
			(xy 92.002846 -226.35059) (xy 92.053698 -226.348541) (xy 92.104219 -226.354675) (xy 92.153103 -226.368835)
			(xy 92.199082 -226.390652) (xy 92.240966 -226.419562) (xy 92.27767 -226.454817) (xy 92.308243 -226.495503)
			(xy 92.331894 -226.540566) (xy 92.34801 -226.58884) (xy 92.356174 -226.639074) (xy 92.356686 -226.66452)
			(xy 92.675214 -226.66452) (xy 92.679174 -226.615466) (xy 92.690951 -226.567682) (xy 92.710242 -226.522406)
			(xy 92.736545 -226.48081) (xy 92.76918 -226.443973) (xy 92.807301 -226.412848) (xy 92.849922 -226.388241)
			(xy 92.895938 -226.370789) (xy 92.944157 -226.360945) (xy 92.993332 -226.358964) (xy 93.042187 -226.364896)
			(xy 93.089458 -226.378588) (xy 93.13392 -226.399686) (xy 93.174423 -226.427642) (xy 93.209916 -226.461734)
			(xy 93.239481 -226.501078) (xy 93.262352 -226.544655) (xy 93.277936 -226.591336) (xy 93.285831 -226.639913)
			(xy 93.286326 -226.66452) (xy 93.604837 -226.66452) (xy 93.608932 -226.613792) (xy 93.621111 -226.564378)
			(xy 93.641059 -226.517558) (xy 93.66826 -226.474544) (xy 93.702008 -226.43645) (xy 93.74143 -226.404263)
			(xy 93.785504 -226.378817) (xy 93.83309 -226.36077) (xy 93.882954 -226.35059) (xy 93.933806 -226.348541)
			(xy 93.984327 -226.354675) (xy 94.033211 -226.368835) (xy 94.07919 -226.390652) (xy 94.121074 -226.419562)
			(xy 94.157778 -226.454817) (xy 94.188351 -226.495503) (xy 94.212002 -226.540566) (xy 94.228118 -226.58884)
			(xy 94.236282 -226.639074) (xy 94.236794 -226.66452) (xy 94.555322 -226.66452) (xy 94.559282 -226.615466)
			(xy 94.571059 -226.567682) (xy 94.59035 -226.522406) (xy 94.616653 -226.48081) (xy 94.649288 -226.443973)
			(xy 94.687409 -226.412848) (xy 94.73003 -226.388241) (xy 94.776046 -226.370789) (xy 94.824265 -226.360945)
			(xy 94.87344 -226.358964) (xy 94.922295 -226.364896) (xy 94.969566 -226.378588) (xy 95.014028 -226.399686)
			(xy 95.054531 -226.427642) (xy 95.090024 -226.461734) (xy 95.119589 -226.501078) (xy 95.14246 -226.544655)
			(xy 95.158044 -226.591336) (xy 95.165939 -226.639913) (xy 95.166434 -226.66452) (xy 95.165939 -226.689127)
			(xy 95.158044 -226.737704) (xy 95.14246 -226.784385) (xy 95.119589 -226.827962) (xy 95.090024 -226.867306)
			(xy 95.054531 -226.901398) (xy 95.014028 -226.929354) (xy 94.969566 -226.950452) (xy 94.922295 -226.964144)
			(xy 94.87344 -226.970076) (xy 94.824265 -226.968095) (xy 94.776046 -226.958251) (xy 94.73003 -226.940799)
			(xy 94.687409 -226.916192) (xy 94.649288 -226.885067) (xy 94.616653 -226.84823) (xy 94.59035 -226.806634)
			(xy 94.571059 -226.761358) (xy 94.559282 -226.713574) (xy 94.555322 -226.66452) (xy 94.236794 -226.66452)
			(xy 94.236282 -226.689966) (xy 94.228118 -226.7402) (xy 94.212002 -226.788474) (xy 94.188351 -226.833537)
			(xy 94.157778 -226.874223) (xy 94.121074 -226.909478) (xy 94.07919 -226.938388) (xy 94.033211 -226.960205)
			(xy 93.984327 -226.974365) (xy 93.933806 -226.980499) (xy 93.882954 -226.97845) (xy 93.83309 -226.96827)
			(xy 93.785504 -226.950223) (xy 93.74143 -226.924777) (xy 93.702008 -226.89259) (xy 93.66826 -226.854496)
			(xy 93.641059 -226.811482) (xy 93.621111 -226.764662) (xy 93.608932 -226.715248) (xy 93.604837 -226.66452)
			(xy 93.286326 -226.66452) (xy 93.285831 -226.689127) (xy 93.277936 -226.737704) (xy 93.262352 -226.784385)
			(xy 93.239481 -226.827962) (xy 93.209916 -226.867306) (xy 93.174423 -226.901398) (xy 93.13392 -226.929354)
			(xy 93.089458 -226.950452) (xy 93.042187 -226.964144) (xy 92.993332 -226.970076) (xy 92.944157 -226.968095)
			(xy 92.895938 -226.958251) (xy 92.849922 -226.940799) (xy 92.807301 -226.916192) (xy 92.76918 -226.885067)
			(xy 92.736545 -226.84823) (xy 92.710242 -226.806634) (xy 92.690951 -226.761358) (xy 92.679174 -226.713574)
			(xy 92.675214 -226.66452) (xy 92.356686 -226.66452) (xy 92.356174 -226.689966) (xy 92.34801 -226.7402)
			(xy 92.331894 -226.788474) (xy 92.308243 -226.833537) (xy 92.27767 -226.874223) (xy 92.240966 -226.909478)
			(xy 92.199082 -226.938388) (xy 92.153103 -226.960205) (xy 92.104219 -226.974365) (xy 92.053698 -226.980499)
			(xy 92.002846 -226.97845) (xy 91.952982 -226.96827) (xy 91.905396 -226.950223) (xy 91.861322 -226.924777)
			(xy 91.8219 -226.89259) (xy 91.788152 -226.854496) (xy 91.760951 -226.811482) (xy 91.741003 -226.764662)
			(xy 91.728824 -226.715248) (xy 91.724729 -226.66452) (xy 91.416632 -226.66452) (xy 91.41612 -226.689966)
			(xy 91.407956 -226.7402) (xy 91.39184 -226.788474) (xy 91.368189 -226.833537) (xy 91.337616 -226.874223)
			(xy 91.300912 -226.909478) (xy 91.259028 -226.938388) (xy 91.213049 -226.960205) (xy 91.164165 -226.974365)
			(xy 91.113644 -226.980499) (xy 91.062792 -226.97845) (xy 91.012928 -226.96827) (xy 90.965342 -226.950223)
			(xy 90.921268 -226.924777) (xy 90.881846 -226.89259) (xy 90.848098 -226.854496) (xy 90.820897 -226.811482)
			(xy 90.800949 -226.764662) (xy 90.78877 -226.715248) (xy 90.784675 -226.66452) (xy 90.466418 -226.66452)
			(xy 90.465923 -226.689127) (xy 90.458028 -226.737704) (xy 90.442444 -226.784385) (xy 90.419573 -226.827962)
			(xy 90.390008 -226.867306) (xy 90.354515 -226.901398) (xy 90.314012 -226.929354) (xy 90.26955 -226.950452)
			(xy 90.222279 -226.964144) (xy 90.173424 -226.970076) (xy 90.124249 -226.968095) (xy 90.07603 -226.958251)
			(xy 90.030014 -226.940799) (xy 89.987393 -226.916192) (xy 89.949272 -226.885067) (xy 89.916637 -226.84823)
			(xy 89.890334 -226.806634) (xy 89.871043 -226.761358) (xy 89.859266 -226.713574) (xy 89.855306 -226.66452)
			(xy 89.526364 -226.66452) (xy 89.525869 -226.689127) (xy 89.517974 -226.737704) (xy 89.50239 -226.784385)
			(xy 89.479519 -226.827962) (xy 89.449954 -226.867306) (xy 89.414461 -226.901398) (xy 89.373958 -226.929354)
			(xy 89.329496 -226.950452) (xy 89.282225 -226.964144) (xy 89.23337 -226.970076) (xy 89.184195 -226.968095)
			(xy 89.135976 -226.958251) (xy 89.08996 -226.940799) (xy 89.047339 -226.916192) (xy 89.009218 -226.885067)
			(xy 88.976583 -226.84823) (xy 88.95028 -226.806634) (xy 88.930989 -226.761358) (xy 88.919212 -226.713574)
			(xy 88.915252 -226.66452) (xy 88.58631 -226.66452) (xy 88.585815 -226.689127) (xy 88.57792 -226.737704)
			(xy 88.562336 -226.784385) (xy 88.539465 -226.827962) (xy 88.5099 -226.867306) (xy 88.474407 -226.901398)
			(xy 88.433904 -226.929354) (xy 88.389442 -226.950452) (xy 88.342171 -226.964144) (xy 88.293316 -226.970076)
			(xy 88.244141 -226.968095) (xy 88.195922 -226.958251) (xy 88.149906 -226.940799) (xy 88.107285 -226.916192)
			(xy 88.069164 -226.885067) (xy 88.036529 -226.84823) (xy 88.010226 -226.806634) (xy 87.990935 -226.761358)
			(xy 87.979158 -226.713574) (xy 87.975198 -226.66452) (xy 87.646256 -226.66452) (xy 87.645761 -226.689127)
			(xy 87.637866 -226.737704) (xy 87.622282 -226.784385) (xy 87.599411 -226.827962) (xy 87.569846 -226.867306)
			(xy 87.534353 -226.901398) (xy 87.49385 -226.929354) (xy 87.449388 -226.950452) (xy 87.402117 -226.964144)
			(xy 87.353262 -226.970076) (xy 87.304087 -226.968095) (xy 87.255868 -226.958251) (xy 87.209852 -226.940799)
			(xy 87.167231 -226.916192) (xy 87.12911 -226.885067) (xy 87.096475 -226.84823) (xy 87.070172 -226.806634)
			(xy 87.050881 -226.761358) (xy 87.039104 -226.713574) (xy 87.035144 -226.66452) (xy 86.713314 -226.66452)
			(xy 86.713314 -226.67849) (xy 86.713787 -226.688361) (xy 86.72125 -226.70664) (xy 86.727792 -226.71405)
			(xy 86.728046 -226.714304) (xy 87.292942 -227.2792) (xy 87.299654 -227.286439) (xy 87.307248 -227.304643)
			(xy 87.307674 -227.314506) (xy 87.307674 -227.474526) (xy 87.505298 -227.474526) (xy 87.509258 -227.425472)
			(xy 87.521035 -227.377688) (xy 87.540326 -227.332412) (xy 87.566629 -227.290816) (xy 87.599264 -227.253979)
			(xy 87.637385 -227.222854) (xy 87.680006 -227.198247) (xy 87.726022 -227.180795) (xy 87.774241 -227.170951)
			(xy 87.823416 -227.16897) (xy 87.872271 -227.174902) (xy 87.919542 -227.188594) (xy 87.964004 -227.209692)
			(xy 88.004507 -227.237648) (xy 88.04 -227.27174) (xy 88.069565 -227.311084) (xy 88.092436 -227.354661)
			(xy 88.10802 -227.401342) (xy 88.115915 -227.449919) (xy 88.11641 -227.474526) (xy 88.445352 -227.474526)
			(xy 88.449312 -227.425472) (xy 88.461089 -227.377688) (xy 88.48038 -227.332412) (xy 88.506683 -227.290816)
			(xy 88.539318 -227.253979) (xy 88.577439 -227.222854) (xy 88.62006 -227.198247) (xy 88.666076 -227.180795)
			(xy 88.714295 -227.170951) (xy 88.76347 -227.16897) (xy 88.812325 -227.174902) (xy 88.859596 -227.188594)
			(xy 88.904058 -227.209692) (xy 88.944561 -227.237648) (xy 88.980054 -227.27174) (xy 89.009619 -227.311084)
			(xy 89.03249 -227.354661) (xy 89.048074 -227.401342) (xy 89.055969 -227.449919) (xy 89.056464 -227.474526)
			(xy 89.385152 -227.474526) (xy 89.389112 -227.425472) (xy 89.400889 -227.377688) (xy 89.42018 -227.332412)
			(xy 89.446483 -227.290816) (xy 89.479118 -227.253979) (xy 89.517239 -227.222854) (xy 89.55986 -227.198247)
			(xy 89.605876 -227.180795) (xy 89.654095 -227.170951) (xy 89.70327 -227.16897) (xy 89.752125 -227.174902)
			(xy 89.799396 -227.188594) (xy 89.843858 -227.209692) (xy 89.884361 -227.237648) (xy 89.919854 -227.27174)
			(xy 89.949419 -227.311084) (xy 89.97229 -227.354661) (xy 89.987874 -227.401342) (xy 89.995769 -227.449919)
			(xy 89.996264 -227.474526) (xy 90.314775 -227.474526) (xy 90.31887 -227.423798) (xy 90.331049 -227.374384)
			(xy 90.350997 -227.327564) (xy 90.378198 -227.28455) (xy 90.411946 -227.246456) (xy 90.451368 -227.214269)
			(xy 90.495442 -227.188823) (xy 90.543028 -227.170776) (xy 90.592892 -227.160596) (xy 90.643744 -227.158547)
			(xy 90.694265 -227.164681) (xy 90.743149 -227.178841) (xy 90.789128 -227.200658) (xy 90.831012 -227.229568)
			(xy 90.867716 -227.264823) (xy 90.898289 -227.305509) (xy 90.92194 -227.350572) (xy 90.938056 -227.398846)
			(xy 90.94622 -227.44908) (xy 90.946732 -227.474526) (xy 91.26526 -227.474526) (xy 91.26922 -227.425472)
			(xy 91.280997 -227.377688) (xy 91.300288 -227.332412) (xy 91.326591 -227.290816) (xy 91.359226 -227.253979)
			(xy 91.397347 -227.222854) (xy 91.439968 -227.198247) (xy 91.485984 -227.180795) (xy 91.534203 -227.170951)
			(xy 91.583378 -227.16897) (xy 91.632233 -227.174902) (xy 91.679504 -227.188594) (xy 91.723966 -227.209692)
			(xy 91.764469 -227.237648) (xy 91.799962 -227.27174) (xy 91.829527 -227.311084) (xy 91.852398 -227.354661)
			(xy 91.867982 -227.401342) (xy 91.875877 -227.449919) (xy 91.876372 -227.474526) (xy 92.194883 -227.474526)
			(xy 92.198978 -227.423798) (xy 92.211157 -227.374384) (xy 92.231105 -227.327564) (xy 92.258306 -227.28455)
			(xy 92.292054 -227.246456) (xy 92.331476 -227.214269) (xy 92.37555 -227.188823) (xy 92.423136 -227.170776)
			(xy 92.473 -227.160596) (xy 92.523852 -227.158547) (xy 92.574373 -227.164681) (xy 92.623257 -227.178841)
			(xy 92.669236 -227.200658) (xy 92.71112 -227.229568) (xy 92.747824 -227.264823) (xy 92.778397 -227.305509)
			(xy 92.802048 -227.350572) (xy 92.818164 -227.398846) (xy 92.826328 -227.44908) (xy 92.82684 -227.474526)
			(xy 93.145114 -227.474526) (xy 93.149074 -227.425472) (xy 93.160851 -227.377688) (xy 93.180142 -227.332412)
			(xy 93.206445 -227.290816) (xy 93.23908 -227.253979) (xy 93.277201 -227.222854) (xy 93.319822 -227.198247)
			(xy 93.365838 -227.180795) (xy 93.414057 -227.170951) (xy 93.463232 -227.16897) (xy 93.512087 -227.174902)
			(xy 93.559358 -227.188594) (xy 93.60382 -227.209692) (xy 93.644323 -227.237648) (xy 93.679816 -227.27174)
			(xy 93.709381 -227.311084) (xy 93.732252 -227.354661) (xy 93.747836 -227.401342) (xy 93.755731 -227.449919)
			(xy 93.756226 -227.474526) (xy 94.074737 -227.474526) (xy 94.078832 -227.423798) (xy 94.091011 -227.374384)
			(xy 94.110959 -227.327564) (xy 94.13816 -227.28455) (xy 94.171908 -227.246456) (xy 94.21133 -227.214269)
			(xy 94.255404 -227.188823) (xy 94.30299 -227.170776) (xy 94.352854 -227.160596) (xy 94.403706 -227.158547)
			(xy 94.454227 -227.164681) (xy 94.503111 -227.178841) (xy 94.54909 -227.200658) (xy 94.590974 -227.229568)
			(xy 94.627678 -227.264823) (xy 94.658251 -227.305509) (xy 94.681902 -227.350572) (xy 94.698018 -227.398846)
			(xy 94.706182 -227.44908) (xy 94.706694 -227.474526) (xy 94.706182 -227.499972) (xy 94.698018 -227.550206)
			(xy 94.681902 -227.59848) (xy 94.658251 -227.643543) (xy 94.627678 -227.684229) (xy 94.590974 -227.719484)
			(xy 94.54909 -227.748394) (xy 94.503111 -227.770211) (xy 94.454227 -227.784371) (xy 94.403706 -227.790505)
			(xy 94.352854 -227.788456) (xy 94.30299 -227.778276) (xy 94.255404 -227.760229) (xy 94.21133 -227.734783)
			(xy 94.171908 -227.702596) (xy 94.13816 -227.664502) (xy 94.110959 -227.621488) (xy 94.091011 -227.574668)
			(xy 94.078832 -227.525254) (xy 94.074737 -227.474526) (xy 93.756226 -227.474526) (xy 93.755731 -227.499133)
			(xy 93.747836 -227.54771) (xy 93.732252 -227.594391) (xy 93.709381 -227.637968) (xy 93.679816 -227.677312)
			(xy 93.644323 -227.711404) (xy 93.60382 -227.73936) (xy 93.559358 -227.760458) (xy 93.512087 -227.77415)
			(xy 93.463232 -227.780082) (xy 93.414057 -227.778101) (xy 93.365838 -227.768257) (xy 93.319822 -227.750805)
			(xy 93.277201 -227.726198) (xy 93.23908 -227.695073) (xy 93.206445 -227.658236) (xy 93.180142 -227.61664)
			(xy 93.160851 -227.571364) (xy 93.149074 -227.52358) (xy 93.145114 -227.474526) (xy 92.82684 -227.474526)
			(xy 92.826328 -227.499972) (xy 92.818164 -227.550206) (xy 92.802048 -227.59848) (xy 92.778397 -227.643543)
			(xy 92.747824 -227.684229) (xy 92.71112 -227.719484) (xy 92.669236 -227.748394) (xy 92.623257 -227.770211)
			(xy 92.574373 -227.784371) (xy 92.523852 -227.790505) (xy 92.473 -227.788456) (xy 92.423136 -227.778276)
			(xy 92.37555 -227.760229) (xy 92.331476 -227.734783) (xy 92.292054 -227.702596) (xy 92.258306 -227.664502)
			(xy 92.231105 -227.621488) (xy 92.211157 -227.574668) (xy 92.198978 -227.525254) (xy 92.194883 -227.474526)
			(xy 91.876372 -227.474526) (xy 91.875877 -227.499133) (xy 91.867982 -227.54771) (xy 91.852398 -227.594391)
			(xy 91.829527 -227.637968) (xy 91.799962 -227.677312) (xy 91.764469 -227.711404) (xy 91.723966 -227.73936)
			(xy 91.679504 -227.760458) (xy 91.632233 -227.77415) (xy 91.583378 -227.780082) (xy 91.534203 -227.778101)
			(xy 91.485984 -227.768257) (xy 91.439968 -227.750805) (xy 91.397347 -227.726198) (xy 91.359226 -227.695073)
			(xy 91.326591 -227.658236) (xy 91.300288 -227.61664) (xy 91.280997 -227.571364) (xy 91.26922 -227.52358)
			(xy 91.26526 -227.474526) (xy 90.946732 -227.474526) (xy 90.94622 -227.499972) (xy 90.938056 -227.550206)
			(xy 90.92194 -227.59848) (xy 90.898289 -227.643543) (xy 90.867716 -227.684229) (xy 90.831012 -227.719484)
			(xy 90.789128 -227.748394) (xy 90.743149 -227.770211) (xy 90.694265 -227.784371) (xy 90.643744 -227.790505)
			(xy 90.592892 -227.788456) (xy 90.543028 -227.778276) (xy 90.495442 -227.760229) (xy 90.451368 -227.734783)
			(xy 90.411946 -227.702596) (xy 90.378198 -227.664502) (xy 90.350997 -227.621488) (xy 90.331049 -227.574668)
			(xy 90.31887 -227.525254) (xy 90.314775 -227.474526) (xy 89.996264 -227.474526) (xy 89.995769 -227.499133)
			(xy 89.987874 -227.54771) (xy 89.97229 -227.594391) (xy 89.949419 -227.637968) (xy 89.919854 -227.677312)
			(xy 89.884361 -227.711404) (xy 89.843858 -227.73936) (xy 89.799396 -227.760458) (xy 89.752125 -227.77415)
			(xy 89.70327 -227.780082) (xy 89.654095 -227.778101) (xy 89.605876 -227.768257) (xy 89.55986 -227.750805)
			(xy 89.517239 -227.726198) (xy 89.479118 -227.695073) (xy 89.446483 -227.658236) (xy 89.42018 -227.61664)
			(xy 89.400889 -227.571364) (xy 89.389112 -227.52358) (xy 89.385152 -227.474526) (xy 89.056464 -227.474526)
			(xy 89.055969 -227.499133) (xy 89.048074 -227.54771) (xy 89.03249 -227.594391) (xy 89.009619 -227.637968)
			(xy 88.980054 -227.677312) (xy 88.944561 -227.711404) (xy 88.904058 -227.73936) (xy 88.859596 -227.760458)
			(xy 88.812325 -227.77415) (xy 88.76347 -227.780082) (xy 88.714295 -227.778101) (xy 88.666076 -227.768257)
			(xy 88.62006 -227.750805) (xy 88.577439 -227.726198) (xy 88.539318 -227.695073) (xy 88.506683 -227.658236)
			(xy 88.48038 -227.61664) (xy 88.461089 -227.571364) (xy 88.449312 -227.52358) (xy 88.445352 -227.474526)
			(xy 88.11641 -227.474526) (xy 88.115915 -227.499133) (xy 88.10802 -227.54771) (xy 88.092436 -227.594391)
			(xy 88.069565 -227.637968) (xy 88.04 -227.677312) (xy 88.004507 -227.711404) (xy 87.964004 -227.73936)
			(xy 87.919542 -227.760458) (xy 87.872271 -227.77415) (xy 87.823416 -227.780082) (xy 87.774241 -227.778101)
			(xy 87.726022 -227.768257) (xy 87.680006 -227.750805) (xy 87.637385 -227.726198) (xy 87.599264 -227.695073)
			(xy 87.566629 -227.658236) (xy 87.540326 -227.61664) (xy 87.521035 -227.571364) (xy 87.509258 -227.52358)
			(xy 87.505298 -227.474526) (xy 87.307674 -227.474526) (xy 87.307674 -227.570538) (xy 87.307143 -227.580377)
			(xy 87.299561 -227.598545) (xy 87.292942 -227.605844) (xy 86.716616 -228.18217) (xy 86.709779 -228.189572)
			(xy 86.702068 -228.20817) (xy 86.70163 -228.218238) (xy 86.70163 -228.228144) (xy 86.702392 -228.232462)
			(xy 86.704933 -228.24897) (xy 86.706837 -228.282319) (xy 86.706753 -228.284532) (xy 87.035144 -228.284532)
			(xy 87.039104 -228.235478) (xy 87.050881 -228.187694) (xy 87.070172 -228.142418) (xy 87.096475 -228.100822)
			(xy 87.12911 -228.063985) (xy 87.167231 -228.03286) (xy 87.209852 -228.008253) (xy 87.255868 -227.990801)
			(xy 87.304087 -227.980957) (xy 87.353262 -227.978976) (xy 87.402117 -227.984908) (xy 87.449388 -227.9986)
			(xy 87.49385 -228.019698) (xy 87.534353 -228.047654) (xy 87.569846 -228.081746) (xy 87.599411 -228.12109)
			(xy 87.622282 -228.164667) (xy 87.637866 -228.211348) (xy 87.645761 -228.259925) (xy 87.646256 -228.284532)
			(xy 87.975198 -228.284532) (xy 87.979158 -228.235478) (xy 87.990935 -228.187694) (xy 88.010226 -228.142418)
			(xy 88.036529 -228.100822) (xy 88.069164 -228.063985) (xy 88.107285 -228.03286) (xy 88.149906 -228.008253)
			(xy 88.195922 -227.990801) (xy 88.244141 -227.980957) (xy 88.293316 -227.978976) (xy 88.342171 -227.984908)
			(xy 88.389442 -227.9986) (xy 88.433904 -228.019698) (xy 88.474407 -228.047654) (xy 88.5099 -228.081746)
			(xy 88.539465 -228.12109) (xy 88.562336 -228.164667) (xy 88.57792 -228.211348) (xy 88.585815 -228.259925)
			(xy 88.58631 -228.284532) (xy 88.915252 -228.284532) (xy 88.919212 -228.235478) (xy 88.930989 -228.187694)
			(xy 88.95028 -228.142418) (xy 88.976583 -228.100822) (xy 89.009218 -228.063985) (xy 89.047339 -228.03286)
			(xy 89.08996 -228.008253) (xy 89.135976 -227.990801) (xy 89.184195 -227.980957) (xy 89.23337 -227.978976)
			(xy 89.282225 -227.984908) (xy 89.329496 -227.9986) (xy 89.373958 -228.019698) (xy 89.414461 -228.047654)
			(xy 89.449954 -228.081746) (xy 89.479519 -228.12109) (xy 89.50239 -228.164667) (xy 89.517974 -228.211348)
			(xy 89.525869 -228.259925) (xy 89.526364 -228.284532) (xy 89.855306 -228.284532) (xy 89.859266 -228.235478)
			(xy 89.871043 -228.187694) (xy 89.890334 -228.142418) (xy 89.916637 -228.100822) (xy 89.949272 -228.063985)
			(xy 89.987393 -228.03286) (xy 90.030014 -228.008253) (xy 90.07603 -227.990801) (xy 90.124249 -227.980957)
			(xy 90.173424 -227.978976) (xy 90.222279 -227.984908) (xy 90.26955 -227.9986) (xy 90.314012 -228.019698)
			(xy 90.354515 -228.047654) (xy 90.390008 -228.081746) (xy 90.419573 -228.12109) (xy 90.442444 -228.164667)
			(xy 90.458028 -228.211348) (xy 90.465923 -228.259925) (xy 90.466418 -228.284532) (xy 90.784675 -228.284532)
			(xy 90.78877 -228.233804) (xy 90.800949 -228.18439) (xy 90.820897 -228.13757) (xy 90.848098 -228.094556)
			(xy 90.881846 -228.056462) (xy 90.921268 -228.024275) (xy 90.965342 -227.998829) (xy 91.012928 -227.980782)
			(xy 91.062792 -227.970602) (xy 91.113644 -227.968553) (xy 91.164165 -227.974687) (xy 91.213049 -227.988847)
			(xy 91.259028 -228.010664) (xy 91.300912 -228.039574) (xy 91.337616 -228.074829) (xy 91.368189 -228.115515)
			(xy 91.39184 -228.160578) (xy 91.407956 -228.208852) (xy 91.41612 -228.259086) (xy 91.416632 -228.284532)
			(xy 91.724729 -228.284532) (xy 91.728824 -228.233804) (xy 91.741003 -228.18439) (xy 91.760951 -228.13757)
			(xy 91.788152 -228.094556) (xy 91.8219 -228.056462) (xy 91.861322 -228.024275) (xy 91.905396 -227.998829)
			(xy 91.952982 -227.980782) (xy 92.002846 -227.970602) (xy 92.053698 -227.968553) (xy 92.104219 -227.974687)
			(xy 92.153103 -227.988847) (xy 92.199082 -228.010664) (xy 92.240966 -228.039574) (xy 92.27767 -228.074829)
			(xy 92.308243 -228.115515) (xy 92.331894 -228.160578) (xy 92.34801 -228.208852) (xy 92.356174 -228.259086)
			(xy 92.356686 -228.284532) (xy 92.675214 -228.284532) (xy 92.679174 -228.235478) (xy 92.690951 -228.187694)
			(xy 92.710242 -228.142418) (xy 92.736545 -228.100822) (xy 92.76918 -228.063985) (xy 92.807301 -228.03286)
			(xy 92.849922 -228.008253) (xy 92.895938 -227.990801) (xy 92.944157 -227.980957) (xy 92.993332 -227.978976)
			(xy 93.042187 -227.984908) (xy 93.089458 -227.9986) (xy 93.13392 -228.019698) (xy 93.174423 -228.047654)
			(xy 93.209916 -228.081746) (xy 93.239481 -228.12109) (xy 93.262352 -228.164667) (xy 93.277936 -228.211348)
			(xy 93.285831 -228.259925) (xy 93.286326 -228.284532) (xy 93.604837 -228.284532) (xy 93.608932 -228.233804)
			(xy 93.621111 -228.18439) (xy 93.641059 -228.13757) (xy 93.66826 -228.094556) (xy 93.702008 -228.056462)
			(xy 93.74143 -228.024275) (xy 93.785504 -227.998829) (xy 93.83309 -227.980782) (xy 93.882954 -227.970602)
			(xy 93.933806 -227.968553) (xy 93.984327 -227.974687) (xy 94.033211 -227.988847) (xy 94.07919 -228.010664)
			(xy 94.121074 -228.039574) (xy 94.157778 -228.074829) (xy 94.188351 -228.115515) (xy 94.212002 -228.160578)
			(xy 94.228118 -228.208852) (xy 94.236282 -228.259086) (xy 94.236794 -228.284532) (xy 94.555322 -228.284532)
			(xy 94.559282 -228.235478) (xy 94.571059 -228.187694) (xy 94.59035 -228.142418) (xy 94.616653 -228.100822)
			(xy 94.649288 -228.063985) (xy 94.687409 -228.03286) (xy 94.73003 -228.008253) (xy 94.776046 -227.990801)
			(xy 94.824265 -227.980957) (xy 94.87344 -227.978976) (xy 94.922295 -227.984908) (xy 94.969566 -227.9986)
			(xy 95.014028 -228.019698) (xy 95.054531 -228.047654) (xy 95.090024 -228.081746) (xy 95.119589 -228.12109)
			(xy 95.14246 -228.164667) (xy 95.158044 -228.211348) (xy 95.165939 -228.259925) (xy 95.166434 -228.284532)
			(xy 95.165939 -228.309139) (xy 95.158044 -228.357716) (xy 95.14246 -228.404397) (xy 95.119589 -228.447974)
			(xy 95.090024 -228.487318) (xy 95.054531 -228.52141) (xy 95.014028 -228.549366) (xy 94.969566 -228.570464)
			(xy 94.922295 -228.584156) (xy 94.87344 -228.590088) (xy 94.824265 -228.588107) (xy 94.776046 -228.578263)
			(xy 94.73003 -228.560811) (xy 94.687409 -228.536204) (xy 94.649288 -228.505079) (xy 94.616653 -228.468242)
			(xy 94.59035 -228.426646) (xy 94.571059 -228.38137) (xy 94.559282 -228.333586) (xy 94.555322 -228.284532)
			(xy 94.236794 -228.284532) (xy 94.236282 -228.309978) (xy 94.228118 -228.360212) (xy 94.212002 -228.408486)
			(xy 94.188351 -228.453549) (xy 94.157778 -228.494235) (xy 94.121074 -228.52949) (xy 94.07919 -228.5584)
			(xy 94.033211 -228.580217) (xy 93.984327 -228.594377) (xy 93.933806 -228.600511) (xy 93.882954 -228.598462)
			(xy 93.83309 -228.588282) (xy 93.785504 -228.570235) (xy 93.74143 -228.544789) (xy 93.702008 -228.512602)
			(xy 93.66826 -228.474508) (xy 93.641059 -228.431494) (xy 93.621111 -228.384674) (xy 93.608932 -228.33526)
			(xy 93.604837 -228.284532) (xy 93.286326 -228.284532) (xy 93.285831 -228.309139) (xy 93.277936 -228.357716)
			(xy 93.262352 -228.404397) (xy 93.239481 -228.447974) (xy 93.209916 -228.487318) (xy 93.174423 -228.52141)
			(xy 93.13392 -228.549366) (xy 93.089458 -228.570464) (xy 93.042187 -228.584156) (xy 92.993332 -228.590088)
			(xy 92.944157 -228.588107) (xy 92.895938 -228.578263) (xy 92.849922 -228.560811) (xy 92.807301 -228.536204)
			(xy 92.76918 -228.505079) (xy 92.736545 -228.468242) (xy 92.710242 -228.426646) (xy 92.690951 -228.38137)
			(xy 92.679174 -228.333586) (xy 92.675214 -228.284532) (xy 92.356686 -228.284532) (xy 92.356174 -228.309978)
			(xy 92.34801 -228.360212) (xy 92.331894 -228.408486) (xy 92.308243 -228.453549) (xy 92.27767 -228.494235)
			(xy 92.240966 -228.52949) (xy 92.199082 -228.5584) (xy 92.153103 -228.580217) (xy 92.104219 -228.594377)
			(xy 92.053698 -228.600511) (xy 92.002846 -228.598462) (xy 91.952982 -228.588282) (xy 91.905396 -228.570235)
			(xy 91.861322 -228.544789) (xy 91.8219 -228.512602) (xy 91.788152 -228.474508) (xy 91.760951 -228.431494)
			(xy 91.741003 -228.384674) (xy 91.728824 -228.33526) (xy 91.724729 -228.284532) (xy 91.416632 -228.284532)
			(xy 91.41612 -228.309978) (xy 91.407956 -228.360212) (xy 91.39184 -228.408486) (xy 91.368189 -228.453549)
			(xy 91.337616 -228.494235) (xy 91.300912 -228.52949) (xy 91.259028 -228.5584) (xy 91.213049 -228.580217)
			(xy 91.164165 -228.594377) (xy 91.113644 -228.600511) (xy 91.062792 -228.598462) (xy 91.012928 -228.588282)
			(xy 90.965342 -228.570235) (xy 90.921268 -228.544789) (xy 90.881846 -228.512602) (xy 90.848098 -228.474508)
			(xy 90.820897 -228.431494) (xy 90.800949 -228.384674) (xy 90.78877 -228.33526) (xy 90.784675 -228.284532)
			(xy 90.466418 -228.284532) (xy 90.465923 -228.309139) (xy 90.458028 -228.357716) (xy 90.442444 -228.404397)
			(xy 90.419573 -228.447974) (xy 90.390008 -228.487318) (xy 90.354515 -228.52141) (xy 90.314012 -228.549366)
			(xy 90.26955 -228.570464) (xy 90.222279 -228.584156) (xy 90.173424 -228.590088) (xy 90.124249 -228.588107)
			(xy 90.07603 -228.578263) (xy 90.030014 -228.560811) (xy 89.987393 -228.536204) (xy 89.949272 -228.505079)
			(xy 89.916637 -228.468242) (xy 89.890334 -228.426646) (xy 89.871043 -228.38137) (xy 89.859266 -228.333586)
			(xy 89.855306 -228.284532) (xy 89.526364 -228.284532) (xy 89.525869 -228.309139) (xy 89.517974 -228.357716)
			(xy 89.50239 -228.404397) (xy 89.479519 -228.447974) (xy 89.449954 -228.487318) (xy 89.414461 -228.52141)
			(xy 89.373958 -228.549366) (xy 89.329496 -228.570464) (xy 89.282225 -228.584156) (xy 89.23337 -228.590088)
			(xy 89.184195 -228.588107) (xy 89.135976 -228.578263) (xy 89.08996 -228.560811) (xy 89.047339 -228.536204)
			(xy 89.009218 -228.505079) (xy 88.976583 -228.468242) (xy 88.95028 -228.426646) (xy 88.930989 -228.38137)
			(xy 88.919212 -228.333586) (xy 88.915252 -228.284532) (xy 88.58631 -228.284532) (xy 88.585815 -228.309139)
			(xy 88.57792 -228.357716) (xy 88.562336 -228.404397) (xy 88.539465 -228.447974) (xy 88.5099 -228.487318)
			(xy 88.474407 -228.52141) (xy 88.433904 -228.549366) (xy 88.389442 -228.570464) (xy 88.342171 -228.584156)
			(xy 88.293316 -228.590088) (xy 88.244141 -228.588107) (xy 88.195922 -228.578263) (xy 88.149906 -228.560811)
			(xy 88.107285 -228.536204) (xy 88.069164 -228.505079) (xy 88.036529 -228.468242) (xy 88.010226 -228.426646)
			(xy 87.990935 -228.38137) (xy 87.979158 -228.333586) (xy 87.975198 -228.284532) (xy 87.646256 -228.284532)
			(xy 87.645761 -228.309139) (xy 87.637866 -228.357716) (xy 87.622282 -228.404397) (xy 87.599411 -228.447974)
			(xy 87.569846 -228.487318) (xy 87.534353 -228.52141) (xy 87.49385 -228.549366) (xy 87.449388 -228.570464)
			(xy 87.402117 -228.584156) (xy 87.353262 -228.590088) (xy 87.304087 -228.588107) (xy 87.255868 -228.578263)
			(xy 87.209852 -228.560811) (xy 87.167231 -228.536204) (xy 87.12911 -228.505079) (xy 87.096475 -228.468242)
			(xy 87.070172 -228.426646) (xy 87.050881 -228.38137) (xy 87.039104 -228.333586) (xy 87.035144 -228.284532)
			(xy 86.706753 -228.284532) (xy 86.706202 -228.29901) (xy 86.706202 -228.299264) (xy 86.705584 -228.309422)
			(xy 86.70317 -228.329632) (xy 86.701376 -228.33965) (xy 86.700614 -228.344222) (xy 86.700614 -228.47427)
			(xy 86.701084 -228.484143) (xy 86.708542 -228.502427) (xy 86.715092 -228.50983) (xy 86.715346 -228.510084)
			(xy 87.057992 -228.85273) (xy 87.060786 -228.855016) (xy 87.06104 -228.85527) (xy 87.073944 -228.865796)
			(xy 87.097623 -228.889213) (xy 87.108284 -228.902006) (xy 87.112856 -228.907594) (xy 87.130382 -228.92512)
			(xy 87.134314 -228.929184) (xy 87.140471 -228.938667) (xy 87.142574 -228.943916) (xy 87.143082 -228.94544)
			(xy 87.146384 -228.953314) (xy 87.149178 -228.968046) (xy 87.151464 -228.97338) (xy 87.161461 -228.998083)
			(xy 87.173727 -229.049939) (xy 87.175848 -229.076504) (xy 87.176356 -229.094538) (xy 87.505298 -229.094538)
			(xy 87.509258 -229.045484) (xy 87.521035 -228.9977) (xy 87.540326 -228.952424) (xy 87.566629 -228.910828)
			(xy 87.599264 -228.873991) (xy 87.637385 -228.842866) (xy 87.680006 -228.818259) (xy 87.726022 -228.800807)
			(xy 87.774241 -228.790963) (xy 87.823416 -228.788982) (xy 87.872271 -228.794914) (xy 87.919542 -228.808606)
			(xy 87.964004 -228.829704) (xy 88.004507 -228.85766) (xy 88.04 -228.891752) (xy 88.069565 -228.931096)
			(xy 88.092436 -228.974673) (xy 88.10802 -229.021354) (xy 88.115915 -229.069931) (xy 88.11641 -229.094538)
			(xy 88.445352 -229.094538) (xy 88.449312 -229.045484) (xy 88.461089 -228.9977) (xy 88.48038 -228.952424)
			(xy 88.506683 -228.910828) (xy 88.539318 -228.873991) (xy 88.577439 -228.842866) (xy 88.62006 -228.818259)
			(xy 88.666076 -228.800807) (xy 88.714295 -228.790963) (xy 88.76347 -228.788982) (xy 88.812325 -228.794914)
			(xy 88.859596 -228.808606) (xy 88.904058 -228.829704) (xy 88.944561 -228.85766) (xy 88.980054 -228.891752)
			(xy 89.009619 -228.931096) (xy 89.03249 -228.974673) (xy 89.048074 -229.021354) (xy 89.055969 -229.069931)
			(xy 89.056464 -229.094538) (xy 89.385152 -229.094538) (xy 89.389112 -229.045484) (xy 89.400889 -228.9977)
			(xy 89.42018 -228.952424) (xy 89.446483 -228.910828) (xy 89.479118 -228.873991) (xy 89.517239 -228.842866)
			(xy 89.55986 -228.818259) (xy 89.605876 -228.800807) (xy 89.654095 -228.790963) (xy 89.70327 -228.788982)
			(xy 89.752125 -228.794914) (xy 89.799396 -228.808606) (xy 89.843858 -228.829704) (xy 89.884361 -228.85766)
			(xy 89.919854 -228.891752) (xy 89.949419 -228.931096) (xy 89.97229 -228.974673) (xy 89.987874 -229.021354)
			(xy 89.995769 -229.069931) (xy 89.996264 -229.094538) (xy 90.314775 -229.094538) (xy 90.31887 -229.04381)
			(xy 90.331049 -228.994396) (xy 90.350997 -228.947576) (xy 90.378198 -228.904562) (xy 90.411946 -228.866468)
			(xy 90.451368 -228.834281) (xy 90.495442 -228.808835) (xy 90.543028 -228.790788) (xy 90.592892 -228.780608)
			(xy 90.643744 -228.778559) (xy 90.694265 -228.784693) (xy 90.743149 -228.798853) (xy 90.789128 -228.82067)
			(xy 90.831012 -228.84958) (xy 90.867716 -228.884835) (xy 90.898289 -228.925521) (xy 90.92194 -228.970584)
			(xy 90.938056 -229.018858) (xy 90.94622 -229.069092) (xy 90.946732 -229.094538) (xy 91.26526 -229.094538)
			(xy 91.26922 -229.045484) (xy 91.280997 -228.9977) (xy 91.300288 -228.952424) (xy 91.326591 -228.910828)
			(xy 91.359226 -228.873991) (xy 91.397347 -228.842866) (xy 91.439968 -228.818259) (xy 91.485984 -228.800807)
			(xy 91.534203 -228.790963) (xy 91.583378 -228.788982) (xy 91.632233 -228.794914) (xy 91.679504 -228.808606)
			(xy 91.723966 -228.829704) (xy 91.764469 -228.85766) (xy 91.799962 -228.891752) (xy 91.829527 -228.931096)
			(xy 91.852398 -228.974673) (xy 91.867982 -229.021354) (xy 91.875877 -229.069931) (xy 91.876372 -229.094538)
			(xy 92.194883 -229.094538) (xy 92.198978 -229.04381) (xy 92.211157 -228.994396) (xy 92.231105 -228.947576)
			(xy 92.258306 -228.904562) (xy 92.292054 -228.866468) (xy 92.331476 -228.834281) (xy 92.37555 -228.808835)
			(xy 92.423136 -228.790788) (xy 92.473 -228.780608) (xy 92.523852 -228.778559) (xy 92.574373 -228.784693)
			(xy 92.623257 -228.798853) (xy 92.669236 -228.82067) (xy 92.71112 -228.84958) (xy 92.747824 -228.884835)
			(xy 92.778397 -228.925521) (xy 92.802048 -228.970584) (xy 92.818164 -229.018858) (xy 92.826328 -229.069092)
			(xy 92.82684 -229.094538) (xy 93.145114 -229.094538) (xy 93.149074 -229.045484) (xy 93.160851 -228.9977)
			(xy 93.180142 -228.952424) (xy 93.206445 -228.910828) (xy 93.23908 -228.873991) (xy 93.277201 -228.842866)
			(xy 93.319822 -228.818259) (xy 93.365838 -228.800807) (xy 93.414057 -228.790963) (xy 93.463232 -228.788982)
			(xy 93.512087 -228.794914) (xy 93.559358 -228.808606) (xy 93.60382 -228.829704) (xy 93.644323 -228.85766)
			(xy 93.679816 -228.891752) (xy 93.709381 -228.931096) (xy 93.732252 -228.974673) (xy 93.747836 -229.021354)
			(xy 93.755731 -229.069931) (xy 93.756226 -229.094538) (xy 94.074737 -229.094538) (xy 94.078832 -229.04381)
			(xy 94.091011 -228.994396) (xy 94.110959 -228.947576) (xy 94.13816 -228.904562) (xy 94.171908 -228.866468)
			(xy 94.21133 -228.834281) (xy 94.255404 -228.808835) (xy 94.30299 -228.790788) (xy 94.352854 -228.780608)
			(xy 94.403706 -228.778559) (xy 94.454227 -228.784693) (xy 94.503111 -228.798853) (xy 94.54909 -228.82067)
			(xy 94.590974 -228.84958) (xy 94.627678 -228.884835) (xy 94.658251 -228.925521) (xy 94.681902 -228.970584)
			(xy 94.698018 -229.018858) (xy 94.706182 -229.069092) (xy 94.706694 -229.094538) (xy 94.706182 -229.119984)
			(xy 94.698018 -229.170218) (xy 94.681902 -229.218492) (xy 94.658251 -229.263555) (xy 94.627678 -229.304241)
			(xy 94.590974 -229.339496) (xy 94.54909 -229.368406) (xy 94.503111 -229.390223) (xy 94.454227 -229.404383)
			(xy 94.403706 -229.410517) (xy 94.352854 -229.408468) (xy 94.30299 -229.398288) (xy 94.255404 -229.380241)
			(xy 94.21133 -229.354795) (xy 94.171908 -229.322608) (xy 94.13816 -229.284514) (xy 94.110959 -229.2415)
			(xy 94.091011 -229.19468) (xy 94.078832 -229.145266) (xy 94.074737 -229.094538) (xy 93.756226 -229.094538)
			(xy 93.755731 -229.119145) (xy 93.747836 -229.167722) (xy 93.732252 -229.214403) (xy 93.709381 -229.25798)
			(xy 93.679816 -229.297324) (xy 93.644323 -229.331416) (xy 93.60382 -229.359372) (xy 93.559358 -229.38047)
			(xy 93.512087 -229.394162) (xy 93.463232 -229.400094) (xy 93.414057 -229.398113) (xy 93.365838 -229.388269)
			(xy 93.319822 -229.370817) (xy 93.277201 -229.34621) (xy 93.23908 -229.315085) (xy 93.206445 -229.278248)
			(xy 93.180142 -229.236652) (xy 93.160851 -229.191376) (xy 93.149074 -229.143592) (xy 93.145114 -229.094538)
			(xy 92.82684 -229.094538) (xy 92.826328 -229.119984) (xy 92.818164 -229.170218) (xy 92.802048 -229.218492)
			(xy 92.778397 -229.263555) (xy 92.747824 -229.304241) (xy 92.71112 -229.339496) (xy 92.669236 -229.368406)
			(xy 92.623257 -229.390223) (xy 92.574373 -229.404383) (xy 92.523852 -229.410517) (xy 92.473 -229.408468)
			(xy 92.423136 -229.398288) (xy 92.37555 -229.380241) (xy 92.331476 -229.354795) (xy 92.292054 -229.322608)
			(xy 92.258306 -229.284514) (xy 92.231105 -229.2415) (xy 92.211157 -229.19468) (xy 92.198978 -229.145266)
			(xy 92.194883 -229.094538) (xy 91.876372 -229.094538) (xy 91.875877 -229.119145) (xy 91.867982 -229.167722)
			(xy 91.852398 -229.214403) (xy 91.829527 -229.25798) (xy 91.799962 -229.297324) (xy 91.764469 -229.331416)
			(xy 91.723966 -229.359372) (xy 91.679504 -229.38047) (xy 91.632233 -229.394162) (xy 91.583378 -229.400094)
			(xy 91.534203 -229.398113) (xy 91.485984 -229.388269) (xy 91.439968 -229.370817) (xy 91.397347 -229.34621)
			(xy 91.359226 -229.315085) (xy 91.326591 -229.278248) (xy 91.300288 -229.236652) (xy 91.280997 -229.191376)
			(xy 91.26922 -229.143592) (xy 91.26526 -229.094538) (xy 90.946732 -229.094538) (xy 90.94622 -229.119984)
			(xy 90.938056 -229.170218) (xy 90.92194 -229.218492) (xy 90.898289 -229.263555) (xy 90.867716 -229.304241)
			(xy 90.831012 -229.339496) (xy 90.789128 -229.368406) (xy 90.743149 -229.390223) (xy 90.694265 -229.404383)
			(xy 90.643744 -229.410517) (xy 90.592892 -229.408468) (xy 90.543028 -229.398288) (xy 90.495442 -229.380241)
			(xy 90.451368 -229.354795) (xy 90.411946 -229.322608) (xy 90.378198 -229.284514) (xy 90.350997 -229.2415)
			(xy 90.331049 -229.19468) (xy 90.31887 -229.145266) (xy 90.314775 -229.094538) (xy 89.996264 -229.094538)
			(xy 89.995769 -229.119145) (xy 89.987874 -229.167722) (xy 89.97229 -229.214403) (xy 89.949419 -229.25798)
			(xy 89.919854 -229.297324) (xy 89.884361 -229.331416) (xy 89.843858 -229.359372) (xy 89.799396 -229.38047)
			(xy 89.752125 -229.394162) (xy 89.70327 -229.400094) (xy 89.654095 -229.398113) (xy 89.605876 -229.388269)
			(xy 89.55986 -229.370817) (xy 89.517239 -229.34621) (xy 89.479118 -229.315085) (xy 89.446483 -229.278248)
			(xy 89.42018 -229.236652) (xy 89.400889 -229.191376) (xy 89.389112 -229.143592) (xy 89.385152 -229.094538)
			(xy 89.056464 -229.094538) (xy 89.055969 -229.119145) (xy 89.048074 -229.167722) (xy 89.03249 -229.214403)
			(xy 89.009619 -229.25798) (xy 88.980054 -229.297324) (xy 88.944561 -229.331416) (xy 88.904058 -229.359372)
			(xy 88.859596 -229.38047) (xy 88.812325 -229.394162) (xy 88.76347 -229.400094) (xy 88.714295 -229.398113)
			(xy 88.666076 -229.388269) (xy 88.62006 -229.370817) (xy 88.577439 -229.34621) (xy 88.539318 -229.315085)
			(xy 88.506683 -229.278248) (xy 88.48038 -229.236652) (xy 88.461089 -229.191376) (xy 88.449312 -229.143592)
			(xy 88.445352 -229.094538) (xy 88.11641 -229.094538) (xy 88.115915 -229.119145) (xy 88.10802 -229.167722)
			(xy 88.092436 -229.214403) (xy 88.069565 -229.25798) (xy 88.04 -229.297324) (xy 88.004507 -229.331416)
			(xy 87.964004 -229.359372) (xy 87.919542 -229.38047) (xy 87.872271 -229.394162) (xy 87.823416 -229.400094)
			(xy 87.774241 -229.398113) (xy 87.726022 -229.388269) (xy 87.680006 -229.370817) (xy 87.637385 -229.34621)
			(xy 87.599264 -229.315085) (xy 87.566629 -229.278248) (xy 87.540326 -229.236652) (xy 87.521035 -229.191376)
			(xy 87.509258 -229.143592) (xy 87.505298 -229.094538) (xy 87.176356 -229.094538) (xy 87.175968 -229.116054)
			(xy 87.169899 -229.158656) (xy 87.157928 -229.199989) (xy 87.149432 -229.21976) (xy 87.149432 -229.220014)
			(xy 87.147146 -229.225094) (xy 87.144098 -229.239572) (xy 87.143844 -229.240842) (xy 87.143082 -229.243636)
			(xy 87.139018 -229.25405) (xy 87.137494 -229.257352) (xy 87.110062 -229.284784) (xy 87.108284 -229.286816)
			(xy 87.098147 -229.298985) (xy 87.075748 -229.321381) (xy 87.06358 -229.33152) (xy 87.061548 -229.333298)
			(xy 86.862666 -229.53218) (xy 86.85595 -229.539417) (xy 86.848348 -229.557622) (xy 86.847934 -229.567486)
			(xy 86.847934 -229.90429) (xy 87.035144 -229.90429) (xy 87.039104 -229.855236) (xy 87.050881 -229.807452)
			(xy 87.070172 -229.762176) (xy 87.096475 -229.72058) (xy 87.12911 -229.683743) (xy 87.167231 -229.652618)
			(xy 87.209852 -229.628011) (xy 87.255868 -229.610559) (xy 87.304087 -229.600715) (xy 87.353262 -229.598734)
			(xy 87.402117 -229.604666) (xy 87.449388 -229.618358) (xy 87.49385 -229.639456) (xy 87.534353 -229.667412)
			(xy 87.569846 -229.701504) (xy 87.599411 -229.740848) (xy 87.622282 -229.784425) (xy 87.637866 -229.831106)
			(xy 87.645761 -229.879683) (xy 87.646256 -229.90429) (xy 87.975198 -229.90429) (xy 87.979158 -229.855236)
			(xy 87.990935 -229.807452) (xy 88.010226 -229.762176) (xy 88.036529 -229.72058) (xy 88.069164 -229.683743)
			(xy 88.107285 -229.652618) (xy 88.149906 -229.628011) (xy 88.195922 -229.610559) (xy 88.244141 -229.600715)
			(xy 88.293316 -229.598734) (xy 88.342171 -229.604666) (xy 88.389442 -229.618358) (xy 88.433904 -229.639456)
			(xy 88.474407 -229.667412) (xy 88.5099 -229.701504) (xy 88.539465 -229.740848) (xy 88.562336 -229.784425)
			(xy 88.57792 -229.831106) (xy 88.585815 -229.879683) (xy 88.58631 -229.90429) (xy 88.915252 -229.90429)
			(xy 88.919212 -229.855236) (xy 88.930989 -229.807452) (xy 88.95028 -229.762176) (xy 88.976583 -229.72058)
			(xy 89.009218 -229.683743) (xy 89.047339 -229.652618) (xy 89.08996 -229.628011) (xy 89.135976 -229.610559)
			(xy 89.184195 -229.600715) (xy 89.23337 -229.598734) (xy 89.282225 -229.604666) (xy 89.329496 -229.618358)
			(xy 89.373958 -229.639456) (xy 89.414461 -229.667412) (xy 89.449954 -229.701504) (xy 89.479519 -229.740848)
			(xy 89.50239 -229.784425) (xy 89.517974 -229.831106) (xy 89.525869 -229.879683) (xy 89.526364 -229.90429)
			(xy 89.855306 -229.90429) (xy 89.859266 -229.855236) (xy 89.871043 -229.807452) (xy 89.890334 -229.762176)
			(xy 89.916637 -229.72058) (xy 89.949272 -229.683743) (xy 89.987393 -229.652618) (xy 90.030014 -229.628011)
			(xy 90.07603 -229.610559) (xy 90.124249 -229.600715) (xy 90.173424 -229.598734) (xy 90.222279 -229.604666)
			(xy 90.26955 -229.618358) (xy 90.314012 -229.639456) (xy 90.354515 -229.667412) (xy 90.390008 -229.701504)
			(xy 90.419573 -229.740848) (xy 90.442444 -229.784425) (xy 90.458028 -229.831106) (xy 90.465923 -229.879683)
			(xy 90.466418 -229.90429) (xy 90.784675 -229.90429) (xy 90.78877 -229.853562) (xy 90.800949 -229.804148)
			(xy 90.820897 -229.757328) (xy 90.848098 -229.714314) (xy 90.881846 -229.67622) (xy 90.921268 -229.644033)
			(xy 90.965342 -229.618587) (xy 91.012928 -229.60054) (xy 91.062792 -229.59036) (xy 91.113644 -229.588311)
			(xy 91.164165 -229.594445) (xy 91.213049 -229.608605) (xy 91.259028 -229.630422) (xy 91.300912 -229.659332)
			(xy 91.337616 -229.694587) (xy 91.368189 -229.735273) (xy 91.39184 -229.780336) (xy 91.407956 -229.82861)
			(xy 91.41612 -229.878844) (xy 91.416632 -229.90429) (xy 91.724729 -229.90429) (xy 91.728824 -229.853562)
			(xy 91.741003 -229.804148) (xy 91.760951 -229.757328) (xy 91.788152 -229.714314) (xy 91.8219 -229.67622)
			(xy 91.861322 -229.644033) (xy 91.905396 -229.618587) (xy 91.952982 -229.60054) (xy 92.002846 -229.59036)
			(xy 92.053698 -229.588311) (xy 92.104219 -229.594445) (xy 92.153103 -229.608605) (xy 92.199082 -229.630422)
			(xy 92.240966 -229.659332) (xy 92.27767 -229.694587) (xy 92.308243 -229.735273) (xy 92.331894 -229.780336)
			(xy 92.34801 -229.82861) (xy 92.356174 -229.878844) (xy 92.356686 -229.90429) (xy 92.675214 -229.90429)
			(xy 92.679174 -229.855236) (xy 92.690951 -229.807452) (xy 92.710242 -229.762176) (xy 92.736545 -229.72058)
			(xy 92.76918 -229.683743) (xy 92.807301 -229.652618) (xy 92.849922 -229.628011) (xy 92.895938 -229.610559)
			(xy 92.944157 -229.600715) (xy 92.993332 -229.598734) (xy 93.042187 -229.604666) (xy 93.089458 -229.618358)
			(xy 93.13392 -229.639456) (xy 93.174423 -229.667412) (xy 93.209916 -229.701504) (xy 93.239481 -229.740848)
			(xy 93.262352 -229.784425) (xy 93.277936 -229.831106) (xy 93.285831 -229.879683) (xy 93.286326 -229.90429)
			(xy 93.604837 -229.90429) (xy 93.608932 -229.853562) (xy 93.621111 -229.804148) (xy 93.641059 -229.757328)
			(xy 93.66826 -229.714314) (xy 93.702008 -229.67622) (xy 93.74143 -229.644033) (xy 93.785504 -229.618587)
			(xy 93.83309 -229.60054) (xy 93.882954 -229.59036) (xy 93.933806 -229.588311) (xy 93.984327 -229.594445)
			(xy 94.033211 -229.608605) (xy 94.07919 -229.630422) (xy 94.121074 -229.659332) (xy 94.157778 -229.694587)
			(xy 94.188351 -229.735273) (xy 94.212002 -229.780336) (xy 94.228118 -229.82861) (xy 94.236282 -229.878844)
			(xy 94.236794 -229.90429) (xy 94.555322 -229.90429) (xy 94.559282 -229.855236) (xy 94.571059 -229.807452)
			(xy 94.59035 -229.762176) (xy 94.616653 -229.72058) (xy 94.649288 -229.683743) (xy 94.687409 -229.652618)
			(xy 94.73003 -229.628011) (xy 94.776046 -229.610559) (xy 94.824265 -229.600715) (xy 94.87344 -229.598734)
			(xy 94.922295 -229.604666) (xy 94.969566 -229.618358) (xy 95.014028 -229.639456) (xy 95.054531 -229.667412)
			(xy 95.090024 -229.701504) (xy 95.119589 -229.740848) (xy 95.14246 -229.784425) (xy 95.158044 -229.831106)
			(xy 95.165939 -229.879683) (xy 95.166434 -229.90429) (xy 95.165939 -229.928897) (xy 95.158044 -229.977474)
			(xy 95.14246 -230.024155) (xy 95.119589 -230.067732) (xy 95.090024 -230.107076) (xy 95.054531 -230.141168)
			(xy 95.014028 -230.169124) (xy 94.969566 -230.190222) (xy 94.922295 -230.203914) (xy 94.87344 -230.209846)
			(xy 94.824265 -230.207865) (xy 94.776046 -230.198021) (xy 94.73003 -230.180569) (xy 94.687409 -230.155962)
			(xy 94.649288 -230.124837) (xy 94.616653 -230.088) (xy 94.59035 -230.046404) (xy 94.571059 -230.001128)
			(xy 94.559282 -229.953344) (xy 94.555322 -229.90429) (xy 94.236794 -229.90429) (xy 94.236282 -229.929736)
			(xy 94.228118 -229.97997) (xy 94.212002 -230.028244) (xy 94.188351 -230.073307) (xy 94.157778 -230.113993)
			(xy 94.121074 -230.149248) (xy 94.07919 -230.178158) (xy 94.033211 -230.199975) (xy 93.984327 -230.214135)
			(xy 93.933806 -230.220269) (xy 93.882954 -230.21822) (xy 93.83309 -230.20804) (xy 93.785504 -230.189993)
			(xy 93.74143 -230.164547) (xy 93.702008 -230.13236) (xy 93.66826 -230.094266) (xy 93.641059 -230.051252)
			(xy 93.621111 -230.004432) (xy 93.608932 -229.955018) (xy 93.604837 -229.90429) (xy 93.286326 -229.90429)
			(xy 93.285831 -229.928897) (xy 93.277936 -229.977474) (xy 93.262352 -230.024155) (xy 93.239481 -230.067732)
			(xy 93.209916 -230.107076) (xy 93.174423 -230.141168) (xy 93.13392 -230.169124) (xy 93.089458 -230.190222)
			(xy 93.042187 -230.203914) (xy 92.993332 -230.209846) (xy 92.944157 -230.207865) (xy 92.895938 -230.198021)
			(xy 92.849922 -230.180569) (xy 92.807301 -230.155962) (xy 92.76918 -230.124837) (xy 92.736545 -230.088)
			(xy 92.710242 -230.046404) (xy 92.690951 -230.001128) (xy 92.679174 -229.953344) (xy 92.675214 -229.90429)
			(xy 92.356686 -229.90429) (xy 92.356174 -229.929736) (xy 92.34801 -229.97997) (xy 92.331894 -230.028244)
			(xy 92.308243 -230.073307) (xy 92.27767 -230.113993) (xy 92.240966 -230.149248) (xy 92.199082 -230.178158)
			(xy 92.153103 -230.199975) (xy 92.104219 -230.214135) (xy 92.053698 -230.220269) (xy 92.002846 -230.21822)
			(xy 91.952982 -230.20804) (xy 91.905396 -230.189993) (xy 91.861322 -230.164547) (xy 91.8219 -230.13236)
			(xy 91.788152 -230.094266) (xy 91.760951 -230.051252) (xy 91.741003 -230.004432) (xy 91.728824 -229.955018)
			(xy 91.724729 -229.90429) (xy 91.416632 -229.90429) (xy 91.41612 -229.929736) (xy 91.407956 -229.97997)
			(xy 91.39184 -230.028244) (xy 91.368189 -230.073307) (xy 91.337616 -230.113993) (xy 91.300912 -230.149248)
			(xy 91.259028 -230.178158) (xy 91.213049 -230.199975) (xy 91.164165 -230.214135) (xy 91.113644 -230.220269)
			(xy 91.062792 -230.21822) (xy 91.012928 -230.20804) (xy 90.965342 -230.189993) (xy 90.921268 -230.164547)
			(xy 90.881846 -230.13236) (xy 90.848098 -230.094266) (xy 90.820897 -230.051252) (xy 90.800949 -230.004432)
			(xy 90.78877 -229.955018) (xy 90.784675 -229.90429) (xy 90.466418 -229.90429) (xy 90.465923 -229.928897)
			(xy 90.458028 -229.977474) (xy 90.442444 -230.024155) (xy 90.419573 -230.067732) (xy 90.390008 -230.107076)
			(xy 90.354515 -230.141168) (xy 90.314012 -230.169124) (xy 90.26955 -230.190222) (xy 90.222279 -230.203914)
			(xy 90.173424 -230.209846) (xy 90.124249 -230.207865) (xy 90.07603 -230.198021) (xy 90.030014 -230.180569)
			(xy 89.987393 -230.155962) (xy 89.949272 -230.124837) (xy 89.916637 -230.088) (xy 89.890334 -230.046404)
			(xy 89.871043 -230.001128) (xy 89.859266 -229.953344) (xy 89.855306 -229.90429) (xy 89.526364 -229.90429)
			(xy 89.525869 -229.928897) (xy 89.517974 -229.977474) (xy 89.50239 -230.024155) (xy 89.479519 -230.067732)
			(xy 89.449954 -230.107076) (xy 89.414461 -230.141168) (xy 89.373958 -230.169124) (xy 89.329496 -230.190222)
			(xy 89.282225 -230.203914) (xy 89.23337 -230.209846) (xy 89.184195 -230.207865) (xy 89.135976 -230.198021)
			(xy 89.08996 -230.180569) (xy 89.047339 -230.155962) (xy 89.009218 -230.124837) (xy 88.976583 -230.088)
			(xy 88.95028 -230.046404) (xy 88.930989 -230.001128) (xy 88.919212 -229.953344) (xy 88.915252 -229.90429)
			(xy 88.58631 -229.90429) (xy 88.585815 -229.928897) (xy 88.57792 -229.977474) (xy 88.562336 -230.024155)
			(xy 88.539465 -230.067732) (xy 88.5099 -230.107076) (xy 88.474407 -230.141168) (xy 88.433904 -230.169124)
			(xy 88.389442 -230.190222) (xy 88.342171 -230.203914) (xy 88.293316 -230.209846) (xy 88.244141 -230.207865)
			(xy 88.195922 -230.198021) (xy 88.149906 -230.180569) (xy 88.107285 -230.155962) (xy 88.069164 -230.124837)
			(xy 88.036529 -230.088) (xy 88.010226 -230.046404) (xy 87.990935 -230.001128) (xy 87.979158 -229.953344)
			(xy 87.975198 -229.90429) (xy 87.646256 -229.90429) (xy 87.645761 -229.928897) (xy 87.637866 -229.977474)
			(xy 87.622282 -230.024155) (xy 87.599411 -230.067732) (xy 87.569846 -230.107076) (xy 87.534353 -230.141168)
			(xy 87.49385 -230.169124) (xy 87.449388 -230.190222) (xy 87.402117 -230.203914) (xy 87.353262 -230.209846)
			(xy 87.304087 -230.207865) (xy 87.255868 -230.198021) (xy 87.209852 -230.180569) (xy 87.167231 -230.155962)
			(xy 87.12911 -230.124837) (xy 87.096475 -230.088) (xy 87.070172 -230.046404) (xy 87.050881 -230.001128)
			(xy 87.039104 -229.953344) (xy 87.035144 -229.90429) (xy 86.847934 -229.90429) (xy 86.847934 -230.23195)
			(xy 86.848398 -230.241826) (xy 86.855843 -230.260122) (xy 86.862412 -230.26751) (xy 86.862666 -230.267764)
			(xy 87.138002 -230.5431) (xy 87.144718 -230.550337) (xy 87.152318 -230.568542) (xy 87.152734 -230.578406)
			(xy 87.152734 -230.587296) (xy 87.15629 -230.60533) (xy 87.15756 -230.609394) (xy 87.166289 -230.634738)
			(xy 87.175746 -230.687497) (xy 87.176356 -230.714296) (xy 87.176356 -230.71455) (xy 87.505298 -230.71455)
			(xy 87.509258 -230.665496) (xy 87.521035 -230.617712) (xy 87.540326 -230.572436) (xy 87.566629 -230.53084)
			(xy 87.599264 -230.494003) (xy 87.637385 -230.462878) (xy 87.680006 -230.438271) (xy 87.726022 -230.420819)
			(xy 87.774241 -230.410975) (xy 87.823416 -230.408994) (xy 87.872271 -230.414926) (xy 87.919542 -230.428618)
			(xy 87.964004 -230.449716) (xy 88.004507 -230.477672) (xy 88.04 -230.511764) (xy 88.069565 -230.551108)
			(xy 88.092436 -230.594685) (xy 88.10802 -230.641366) (xy 88.115915 -230.689943) (xy 88.11641 -230.71455)
			(xy 88.445352 -230.71455) (xy 88.449312 -230.665496) (xy 88.461089 -230.617712) (xy 88.48038 -230.572436)
			(xy 88.506683 -230.53084) (xy 88.539318 -230.494003) (xy 88.577439 -230.462878) (xy 88.62006 -230.438271)
			(xy 88.666076 -230.420819) (xy 88.714295 -230.410975) (xy 88.76347 -230.408994) (xy 88.812325 -230.414926)
			(xy 88.859596 -230.428618) (xy 88.904058 -230.449716) (xy 88.944561 -230.477672) (xy 88.980054 -230.511764)
			(xy 89.009619 -230.551108) (xy 89.03249 -230.594685) (xy 89.048074 -230.641366) (xy 89.055969 -230.689943)
			(xy 89.056459 -230.714296) (xy 89.385152 -230.714296) (xy 89.389112 -230.665242) (xy 89.400889 -230.617458)
			(xy 89.42018 -230.572182) (xy 89.446483 -230.530586) (xy 89.479118 -230.493749) (xy 89.517239 -230.462624)
			(xy 89.55986 -230.438017) (xy 89.605876 -230.420565) (xy 89.654095 -230.410721) (xy 89.70327 -230.40874)
			(xy 89.752125 -230.414672) (xy 89.799396 -230.428364) (xy 89.843858 -230.449462) (xy 89.884361 -230.477418)
			(xy 89.919854 -230.51151) (xy 89.949419 -230.550854) (xy 89.97229 -230.594431) (xy 89.987874 -230.641112)
			(xy 89.995769 -230.689689) (xy 89.996264 -230.714296) (xy 89.996259 -230.71455) (xy 90.314775 -230.71455)
			(xy 90.31887 -230.663822) (xy 90.331049 -230.614408) (xy 90.350997 -230.567588) (xy 90.378198 -230.524574)
			(xy 90.411946 -230.48648) (xy 90.451368 -230.454293) (xy 90.495442 -230.428847) (xy 90.543028 -230.4108)
			(xy 90.592892 -230.40062) (xy 90.643744 -230.398571) (xy 90.694265 -230.404705) (xy 90.743149 -230.418865)
			(xy 90.789128 -230.440682) (xy 90.831012 -230.469592) (xy 90.867716 -230.504847) (xy 90.898289 -230.545533)
			(xy 90.92194 -230.590596) (xy 90.938056 -230.63887) (xy 90.94622 -230.689104) (xy 90.946732 -230.71455)
			(xy 91.26526 -230.71455) (xy 91.26922 -230.665496) (xy 91.280997 -230.617712) (xy 91.300288 -230.572436)
			(xy 91.326591 -230.53084) (xy 91.359226 -230.494003) (xy 91.397347 -230.462878) (xy 91.439968 -230.438271)
			(xy 91.485984 -230.420819) (xy 91.534203 -230.410975) (xy 91.583378 -230.408994) (xy 91.632233 -230.414926)
			(xy 91.679504 -230.428618) (xy 91.723966 -230.449716) (xy 91.764469 -230.477672) (xy 91.799962 -230.511764)
			(xy 91.829527 -230.551108) (xy 91.852398 -230.594685) (xy 91.867982 -230.641366) (xy 91.875877 -230.689943)
			(xy 91.876372 -230.71455) (xy 92.194883 -230.71455) (xy 92.198978 -230.663822) (xy 92.211157 -230.614408)
			(xy 92.231105 -230.567588) (xy 92.258306 -230.524574) (xy 92.292054 -230.48648) (xy 92.331476 -230.454293)
			(xy 92.37555 -230.428847) (xy 92.423136 -230.4108) (xy 92.473 -230.40062) (xy 92.523852 -230.398571)
			(xy 92.574373 -230.404705) (xy 92.623257 -230.418865) (xy 92.669236 -230.440682) (xy 92.71112 -230.469592)
			(xy 92.747824 -230.504847) (xy 92.778397 -230.545533) (xy 92.802048 -230.590596) (xy 92.818164 -230.63887)
			(xy 92.826328 -230.689104) (xy 92.826835 -230.714296) (xy 93.145114 -230.714296) (xy 93.149074 -230.665242)
			(xy 93.160851 -230.617458) (xy 93.180142 -230.572182) (xy 93.206445 -230.530586) (xy 93.23908 -230.493749)
			(xy 93.277201 -230.462624) (xy 93.319822 -230.438017) (xy 93.365838 -230.420565) (xy 93.414057 -230.410721)
			(xy 93.463232 -230.40874) (xy 93.512087 -230.414672) (xy 93.559358 -230.428364) (xy 93.60382 -230.449462)
			(xy 93.644323 -230.477418) (xy 93.679816 -230.51151) (xy 93.709381 -230.550854) (xy 93.732252 -230.594431)
			(xy 93.747836 -230.641112) (xy 93.755731 -230.689689) (xy 93.756226 -230.714296) (xy 93.756221 -230.71455)
			(xy 94.074737 -230.71455) (xy 94.078832 -230.663822) (xy 94.091011 -230.614408) (xy 94.110959 -230.567588)
			(xy 94.13816 -230.524574) (xy 94.171908 -230.48648) (xy 94.21133 -230.454293) (xy 94.255404 -230.428847)
			(xy 94.30299 -230.4108) (xy 94.352854 -230.40062) (xy 94.403706 -230.398571) (xy 94.454227 -230.404705)
			(xy 94.503111 -230.418865) (xy 94.54909 -230.440682) (xy 94.590974 -230.469592) (xy 94.627678 -230.504847)
			(xy 94.658251 -230.545533) (xy 94.681902 -230.590596) (xy 94.698018 -230.63887) (xy 94.706182 -230.689104)
			(xy 94.706694 -230.71455) (xy 94.706182 -230.739996) (xy 94.698018 -230.79023) (xy 94.681902 -230.838504)
			(xy 94.658251 -230.883567) (xy 94.627678 -230.924253) (xy 94.590974 -230.959508) (xy 94.54909 -230.988418)
			(xy 94.503111 -231.010235) (xy 94.454227 -231.024395) (xy 94.403706 -231.030529) (xy 94.352854 -231.02848)
			(xy 94.30299 -231.0183) (xy 94.255404 -231.000253) (xy 94.21133 -230.974807) (xy 94.171908 -230.94262)
			(xy 94.13816 -230.904526) (xy 94.110959 -230.861512) (xy 94.091011 -230.814692) (xy 94.078832 -230.765278)
			(xy 94.074737 -230.71455) (xy 93.756221 -230.71455) (xy 93.755731 -230.738903) (xy 93.747836 -230.78748)
			(xy 93.732252 -230.834161) (xy 93.709381 -230.877738) (xy 93.679816 -230.917082) (xy 93.644323 -230.951174)
			(xy 93.60382 -230.97913) (xy 93.559358 -231.000228) (xy 93.512087 -231.01392) (xy 93.463232 -231.019852)
			(xy 93.414057 -231.017871) (xy 93.365838 -231.008027) (xy 93.319822 -230.990575) (xy 93.277201 -230.965968)
			(xy 93.23908 -230.934843) (xy 93.206445 -230.898006) (xy 93.180142 -230.85641) (xy 93.160851 -230.811134)
			(xy 93.149074 -230.76335) (xy 93.145114 -230.714296) (xy 92.826835 -230.714296) (xy 92.82684 -230.71455)
			(xy 92.826328 -230.739996) (xy 92.818164 -230.79023) (xy 92.802048 -230.838504) (xy 92.778397 -230.883567)
			(xy 92.747824 -230.924253) (xy 92.71112 -230.959508) (xy 92.669236 -230.988418) (xy 92.623257 -231.010235)
			(xy 92.574373 -231.024395) (xy 92.523852 -231.030529) (xy 92.473 -231.02848) (xy 92.423136 -231.0183)
			(xy 92.37555 -231.000253) (xy 92.331476 -230.974807) (xy 92.292054 -230.94262) (xy 92.258306 -230.904526)
			(xy 92.231105 -230.861512) (xy 92.211157 -230.814692) (xy 92.198978 -230.765278) (xy 92.194883 -230.71455)
			(xy 91.876372 -230.71455) (xy 91.875877 -230.739157) (xy 91.867982 -230.787734) (xy 91.852398 -230.834415)
			(xy 91.829527 -230.877992) (xy 91.799962 -230.917336) (xy 91.764469 -230.951428) (xy 91.723966 -230.979384)
			(xy 91.679504 -231.000482) (xy 91.632233 -231.014174) (xy 91.583378 -231.020106) (xy 91.534203 -231.018125)
			(xy 91.485984 -231.008281) (xy 91.439968 -230.990829) (xy 91.397347 -230.966222) (xy 91.359226 -230.935097)
			(xy 91.326591 -230.89826) (xy 91.300288 -230.856664) (xy 91.280997 -230.811388) (xy 91.26922 -230.763604)
			(xy 91.26526 -230.71455) (xy 90.946732 -230.71455) (xy 90.94622 -230.739996) (xy 90.938056 -230.79023)
			(xy 90.92194 -230.838504) (xy 90.898289 -230.883567) (xy 90.867716 -230.924253) (xy 90.831012 -230.959508)
			(xy 90.789128 -230.988418) (xy 90.743149 -231.010235) (xy 90.694265 -231.024395) (xy 90.643744 -231.030529)
			(xy 90.592892 -231.02848) (xy 90.543028 -231.0183) (xy 90.495442 -231.000253) (xy 90.451368 -230.974807)
			(xy 90.411946 -230.94262) (xy 90.378198 -230.904526) (xy 90.350997 -230.861512) (xy 90.331049 -230.814692)
			(xy 90.31887 -230.765278) (xy 90.314775 -230.71455) (xy 89.996259 -230.71455) (xy 89.995769 -230.738903)
			(xy 89.987874 -230.78748) (xy 89.97229 -230.834161) (xy 89.949419 -230.877738) (xy 89.919854 -230.917082)
			(xy 89.884361 -230.951174) (xy 89.843858 -230.97913) (xy 89.799396 -231.000228) (xy 89.752125 -231.01392)
			(xy 89.70327 -231.019852) (xy 89.654095 -231.017871) (xy 89.605876 -231.008027) (xy 89.55986 -230.990575)
			(xy 89.517239 -230.965968) (xy 89.479118 -230.934843) (xy 89.446483 -230.898006) (xy 89.42018 -230.85641)
			(xy 89.400889 -230.811134) (xy 89.389112 -230.76335) (xy 89.385152 -230.714296) (xy 89.056459 -230.714296)
			(xy 89.056464 -230.71455) (xy 89.055969 -230.739157) (xy 89.048074 -230.787734) (xy 89.03249 -230.834415)
			(xy 89.009619 -230.877992) (xy 88.980054 -230.917336) (xy 88.944561 -230.951428) (xy 88.904058 -230.979384)
			(xy 88.859596 -231.000482) (xy 88.812325 -231.014174) (xy 88.76347 -231.020106) (xy 88.714295 -231.018125)
			(xy 88.666076 -231.008281) (xy 88.62006 -230.990829) (xy 88.577439 -230.966222) (xy 88.539318 -230.935097)
			(xy 88.506683 -230.89826) (xy 88.48038 -230.856664) (xy 88.461089 -230.811388) (xy 88.449312 -230.763604)
			(xy 88.445352 -230.71455) (xy 88.11641 -230.71455) (xy 88.115915 -230.739157) (xy 88.10802 -230.787734)
			(xy 88.092436 -230.834415) (xy 88.069565 -230.877992) (xy 88.04 -230.917336) (xy 88.004507 -230.951428)
			(xy 87.964004 -230.979384) (xy 87.919542 -231.000482) (xy 87.872271 -231.014174) (xy 87.823416 -231.020106)
			(xy 87.774241 -231.018125) (xy 87.726022 -231.008281) (xy 87.680006 -230.990829) (xy 87.637385 -230.966222)
			(xy 87.599264 -230.935097) (xy 87.566629 -230.89826) (xy 87.540326 -230.856664) (xy 87.521035 -230.811388)
			(xy 87.509258 -230.763604) (xy 87.505298 -230.71455) (xy 87.176356 -230.71455) (xy 87.176356 -230.714804)
			(xy 87.175687 -230.742689) (xy 87.165454 -230.797515) (xy 87.156036 -230.82377) (xy 87.152734 -230.83266)
			(xy 87.152734 -230.862378) (xy 87.152197 -230.872216) (xy 87.144612 -230.890378) (xy 87.138002 -230.897684)
			(xy 86.743286 -231.2924) (xy 86.736571 -231.299638) (xy 86.728973 -231.317842) (xy 86.728554 -231.327706)
			(xy 86.728554 -231.524302) (xy 87.035144 -231.524302) (xy 87.039104 -231.475248) (xy 87.050881 -231.427464)
			(xy 87.070172 -231.382188) (xy 87.096475 -231.340592) (xy 87.12911 -231.303755) (xy 87.167231 -231.27263)
			(xy 87.209852 -231.248023) (xy 87.255868 -231.230571) (xy 87.304087 -231.220727) (xy 87.353262 -231.218746)
			(xy 87.402117 -231.224678) (xy 87.449388 -231.23837) (xy 87.49385 -231.259468) (xy 87.534353 -231.287424)
			(xy 87.569846 -231.321516) (xy 87.599411 -231.36086) (xy 87.622282 -231.404437) (xy 87.637866 -231.451118)
			(xy 87.645761 -231.499695) (xy 87.646256 -231.524302) (xy 87.975198 -231.524302) (xy 87.979158 -231.475248)
			(xy 87.990935 -231.427464) (xy 88.010226 -231.382188) (xy 88.036529 -231.340592) (xy 88.069164 -231.303755)
			(xy 88.107285 -231.27263) (xy 88.149906 -231.248023) (xy 88.195922 -231.230571) (xy 88.244141 -231.220727)
			(xy 88.293316 -231.218746) (xy 88.342171 -231.224678) (xy 88.389442 -231.23837) (xy 88.433904 -231.259468)
			(xy 88.474407 -231.287424) (xy 88.5099 -231.321516) (xy 88.539465 -231.36086) (xy 88.562336 -231.404437)
			(xy 88.57792 -231.451118) (xy 88.585815 -231.499695) (xy 88.58631 -231.524302) (xy 88.915252 -231.524302)
			(xy 88.919212 -231.475248) (xy 88.930989 -231.427464) (xy 88.95028 -231.382188) (xy 88.976583 -231.340592)
			(xy 89.009218 -231.303755) (xy 89.047339 -231.27263) (xy 89.08996 -231.248023) (xy 89.135976 -231.230571)
			(xy 89.184195 -231.220727) (xy 89.23337 -231.218746) (xy 89.282225 -231.224678) (xy 89.329496 -231.23837)
			(xy 89.373958 -231.259468) (xy 89.414461 -231.287424) (xy 89.449954 -231.321516) (xy 89.479519 -231.36086)
			(xy 89.50239 -231.404437) (xy 89.517974 -231.451118) (xy 89.525869 -231.499695) (xy 89.526364 -231.524302)
			(xy 89.855306 -231.524302) (xy 89.859266 -231.475248) (xy 89.871043 -231.427464) (xy 89.890334 -231.382188)
			(xy 89.916637 -231.340592) (xy 89.949272 -231.303755) (xy 89.987393 -231.27263) (xy 90.030014 -231.248023)
			(xy 90.07603 -231.230571) (xy 90.124249 -231.220727) (xy 90.173424 -231.218746) (xy 90.222279 -231.224678)
			(xy 90.26955 -231.23837) (xy 90.314012 -231.259468) (xy 90.354515 -231.287424) (xy 90.390008 -231.321516)
			(xy 90.419573 -231.36086) (xy 90.442444 -231.404437) (xy 90.458028 -231.451118) (xy 90.465923 -231.499695)
			(xy 90.466418 -231.524302) (xy 90.784675 -231.524302) (xy 90.78877 -231.473574) (xy 90.800949 -231.42416)
			(xy 90.820897 -231.37734) (xy 90.848098 -231.334326) (xy 90.881846 -231.296232) (xy 90.921268 -231.264045)
			(xy 90.965342 -231.238599) (xy 91.012928 -231.220552) (xy 91.062792 -231.210372) (xy 91.113644 -231.208323)
			(xy 91.164165 -231.214457) (xy 91.213049 -231.228617) (xy 91.259028 -231.250434) (xy 91.300912 -231.279344)
			(xy 91.337616 -231.314599) (xy 91.368189 -231.355285) (xy 91.39184 -231.400348) (xy 91.407956 -231.448622)
			(xy 91.41612 -231.498856) (xy 91.416632 -231.524302) (xy 91.724729 -231.524302) (xy 91.728824 -231.473574)
			(xy 91.741003 -231.42416) (xy 91.760951 -231.37734) (xy 91.788152 -231.334326) (xy 91.8219 -231.296232)
			(xy 91.861322 -231.264045) (xy 91.905396 -231.238599) (xy 91.952982 -231.220552) (xy 92.002846 -231.210372)
			(xy 92.053698 -231.208323) (xy 92.104219 -231.214457) (xy 92.153103 -231.228617) (xy 92.199082 -231.250434)
			(xy 92.240966 -231.279344) (xy 92.27767 -231.314599) (xy 92.308243 -231.355285) (xy 92.331894 -231.400348)
			(xy 92.34801 -231.448622) (xy 92.356174 -231.498856) (xy 92.356686 -231.524302) (xy 92.675214 -231.524302)
			(xy 92.679174 -231.475248) (xy 92.690951 -231.427464) (xy 92.710242 -231.382188) (xy 92.736545 -231.340592)
			(xy 92.76918 -231.303755) (xy 92.807301 -231.27263) (xy 92.849922 -231.248023) (xy 92.895938 -231.230571)
			(xy 92.944157 -231.220727) (xy 92.993332 -231.218746) (xy 93.042187 -231.224678) (xy 93.089458 -231.23837)
			(xy 93.13392 -231.259468) (xy 93.174423 -231.287424) (xy 93.209916 -231.321516) (xy 93.239481 -231.36086)
			(xy 93.262352 -231.404437) (xy 93.277936 -231.451118) (xy 93.285831 -231.499695) (xy 93.286326 -231.524302)
			(xy 93.604837 -231.524302) (xy 93.608932 -231.473574) (xy 93.621111 -231.42416) (xy 93.641059 -231.37734)
			(xy 93.66826 -231.334326) (xy 93.702008 -231.296232) (xy 93.74143 -231.264045) (xy 93.785504 -231.238599)
			(xy 93.83309 -231.220552) (xy 93.882954 -231.210372) (xy 93.933806 -231.208323) (xy 93.984327 -231.214457)
			(xy 94.033211 -231.228617) (xy 94.07919 -231.250434) (xy 94.121074 -231.279344) (xy 94.157778 -231.314599)
			(xy 94.188351 -231.355285) (xy 94.212002 -231.400348) (xy 94.228118 -231.448622) (xy 94.236282 -231.498856)
			(xy 94.236794 -231.524302) (xy 94.555322 -231.524302) (xy 94.559282 -231.475248) (xy 94.571059 -231.427464)
			(xy 94.59035 -231.382188) (xy 94.616653 -231.340592) (xy 94.649288 -231.303755) (xy 94.687409 -231.27263)
			(xy 94.73003 -231.248023) (xy 94.776046 -231.230571) (xy 94.824265 -231.220727) (xy 94.87344 -231.218746)
			(xy 94.922295 -231.224678) (xy 94.969566 -231.23837) (xy 95.014028 -231.259468) (xy 95.054531 -231.287424)
			(xy 95.090024 -231.321516) (xy 95.119589 -231.36086) (xy 95.14246 -231.404437) (xy 95.158044 -231.451118)
			(xy 95.165939 -231.499695) (xy 95.166434 -231.524302) (xy 95.165939 -231.548909) (xy 95.158044 -231.597486)
			(xy 95.14246 -231.644167) (xy 95.119589 -231.687744) (xy 95.090024 -231.727088) (xy 95.054531 -231.76118)
			(xy 95.014028 -231.789136) (xy 94.969566 -231.810234) (xy 94.922295 -231.823926) (xy 94.87344 -231.829858)
			(xy 94.824265 -231.827877) (xy 94.776046 -231.818033) (xy 94.73003 -231.800581) (xy 94.687409 -231.775974)
			(xy 94.649288 -231.744849) (xy 94.616653 -231.708012) (xy 94.59035 -231.666416) (xy 94.571059 -231.62114)
			(xy 94.559282 -231.573356) (xy 94.555322 -231.524302) (xy 94.236794 -231.524302) (xy 94.236282 -231.549748)
			(xy 94.228118 -231.599982) (xy 94.212002 -231.648256) (xy 94.188351 -231.693319) (xy 94.157778 -231.734005)
			(xy 94.121074 -231.76926) (xy 94.07919 -231.79817) (xy 94.033211 -231.819987) (xy 93.984327 -231.834147)
			(xy 93.933806 -231.840281) (xy 93.882954 -231.838232) (xy 93.83309 -231.828052) (xy 93.785504 -231.810005)
			(xy 93.74143 -231.784559) (xy 93.702008 -231.752372) (xy 93.66826 -231.714278) (xy 93.641059 -231.671264)
			(xy 93.621111 -231.624444) (xy 93.608932 -231.57503) (xy 93.604837 -231.524302) (xy 93.286326 -231.524302)
			(xy 93.285831 -231.548909) (xy 93.277936 -231.597486) (xy 93.262352 -231.644167) (xy 93.239481 -231.687744)
			(xy 93.209916 -231.727088) (xy 93.174423 -231.76118) (xy 93.13392 -231.789136) (xy 93.089458 -231.810234)
			(xy 93.042187 -231.823926) (xy 92.993332 -231.829858) (xy 92.944157 -231.827877) (xy 92.895938 -231.818033)
			(xy 92.849922 -231.800581) (xy 92.807301 -231.775974) (xy 92.76918 -231.744849) (xy 92.736545 -231.708012)
			(xy 92.710242 -231.666416) (xy 92.690951 -231.62114) (xy 92.679174 -231.573356) (xy 92.675214 -231.524302)
			(xy 92.356686 -231.524302) (xy 92.356174 -231.549748) (xy 92.34801 -231.599982) (xy 92.331894 -231.648256)
			(xy 92.308243 -231.693319) (xy 92.27767 -231.734005) (xy 92.240966 -231.76926) (xy 92.199082 -231.79817)
			(xy 92.153103 -231.819987) (xy 92.104219 -231.834147) (xy 92.053698 -231.840281) (xy 92.002846 -231.838232)
			(xy 91.952982 -231.828052) (xy 91.905396 -231.810005) (xy 91.861322 -231.784559) (xy 91.8219 -231.752372)
			(xy 91.788152 -231.714278) (xy 91.760951 -231.671264) (xy 91.741003 -231.624444) (xy 91.728824 -231.57503)
			(xy 91.724729 -231.524302) (xy 91.416632 -231.524302) (xy 91.41612 -231.549748) (xy 91.407956 -231.599982)
			(xy 91.39184 -231.648256) (xy 91.368189 -231.693319) (xy 91.337616 -231.734005) (xy 91.300912 -231.76926)
			(xy 91.259028 -231.79817) (xy 91.213049 -231.819987) (xy 91.164165 -231.834147) (xy 91.113644 -231.840281)
			(xy 91.062792 -231.838232) (xy 91.012928 -231.828052) (xy 90.965342 -231.810005) (xy 90.921268 -231.784559)
			(xy 90.881846 -231.752372) (xy 90.848098 -231.714278) (xy 90.820897 -231.671264) (xy 90.800949 -231.624444)
			(xy 90.78877 -231.57503) (xy 90.784675 -231.524302) (xy 90.466418 -231.524302) (xy 90.465923 -231.548909)
			(xy 90.458028 -231.597486) (xy 90.442444 -231.644167) (xy 90.419573 -231.687744) (xy 90.390008 -231.727088)
			(xy 90.354515 -231.76118) (xy 90.314012 -231.789136) (xy 90.26955 -231.810234) (xy 90.222279 -231.823926)
			(xy 90.173424 -231.829858) (xy 90.124249 -231.827877) (xy 90.07603 -231.818033) (xy 90.030014 -231.800581)
			(xy 89.987393 -231.775974) (xy 89.949272 -231.744849) (xy 89.916637 -231.708012) (xy 89.890334 -231.666416)
			(xy 89.871043 -231.62114) (xy 89.859266 -231.573356) (xy 89.855306 -231.524302) (xy 89.526364 -231.524302)
			(xy 89.525869 -231.548909) (xy 89.517974 -231.597486) (xy 89.50239 -231.644167) (xy 89.479519 -231.687744)
			(xy 89.449954 -231.727088) (xy 89.414461 -231.76118) (xy 89.373958 -231.789136) (xy 89.329496 -231.810234)
			(xy 89.282225 -231.823926) (xy 89.23337 -231.829858) (xy 89.184195 -231.827877) (xy 89.135976 -231.818033)
			(xy 89.08996 -231.800581) (xy 89.047339 -231.775974) (xy 89.009218 -231.744849) (xy 88.976583 -231.708012)
			(xy 88.95028 -231.666416) (xy 88.930989 -231.62114) (xy 88.919212 -231.573356) (xy 88.915252 -231.524302)
			(xy 88.58631 -231.524302) (xy 88.585815 -231.548909) (xy 88.57792 -231.597486) (xy 88.562336 -231.644167)
			(xy 88.539465 -231.687744) (xy 88.5099 -231.727088) (xy 88.474407 -231.76118) (xy 88.433904 -231.789136)
			(xy 88.389442 -231.810234) (xy 88.342171 -231.823926) (xy 88.293316 -231.829858) (xy 88.244141 -231.827877)
			(xy 88.195922 -231.818033) (xy 88.149906 -231.800581) (xy 88.107285 -231.775974) (xy 88.069164 -231.744849)
			(xy 88.036529 -231.708012) (xy 88.010226 -231.666416) (xy 87.990935 -231.62114) (xy 87.979158 -231.573356)
			(xy 87.975198 -231.524302) (xy 87.646256 -231.524302) (xy 87.645761 -231.548909) (xy 87.637866 -231.597486)
			(xy 87.622282 -231.644167) (xy 87.599411 -231.687744) (xy 87.569846 -231.727088) (xy 87.534353 -231.76118)
			(xy 87.49385 -231.789136) (xy 87.449388 -231.810234) (xy 87.402117 -231.823926) (xy 87.353262 -231.829858)
			(xy 87.304087 -231.827877) (xy 87.255868 -231.818033) (xy 87.209852 -231.800581) (xy 87.167231 -231.775974)
			(xy 87.12911 -231.744849) (xy 87.096475 -231.708012) (xy 87.070172 -231.666416) (xy 87.050881 -231.62114)
			(xy 87.039104 -231.573356) (xy 87.035144 -231.524302) (xy 86.728554 -231.524302) (xy 86.728554 -231.54767)
			(xy 86.729022 -231.557544) (xy 86.736474 -231.575833) (xy 86.743032 -231.58323) (xy 86.743286 -231.583484)
			(xy 87.292942 -232.13314) (xy 87.299647 -232.140381) (xy 87.307227 -232.158586) (xy 87.307674 -232.168446)
			(xy 87.307674 -232.334308) (xy 87.505298 -232.334308) (xy 87.509258 -232.285254) (xy 87.521035 -232.23747)
			(xy 87.540326 -232.192194) (xy 87.566629 -232.150598) (xy 87.599264 -232.113761) (xy 87.637385 -232.082636)
			(xy 87.680006 -232.058029) (xy 87.726022 -232.040577) (xy 87.774241 -232.030733) (xy 87.823416 -232.028752)
			(xy 87.872271 -232.034684) (xy 87.919542 -232.048376) (xy 87.964004 -232.069474) (xy 88.004507 -232.09743)
			(xy 88.04 -232.131522) (xy 88.069565 -232.170866) (xy 88.092436 -232.214443) (xy 88.10802 -232.261124)
			(xy 88.115915 -232.309701) (xy 88.11641 -232.334308) (xy 88.445352 -232.334308) (xy 88.449312 -232.285254)
			(xy 88.461089 -232.23747) (xy 88.48038 -232.192194) (xy 88.506683 -232.150598) (xy 88.539318 -232.113761)
			(xy 88.577439 -232.082636) (xy 88.62006 -232.058029) (xy 88.666076 -232.040577) (xy 88.714295 -232.030733)
			(xy 88.76347 -232.028752) (xy 88.812325 -232.034684) (xy 88.859596 -232.048376) (xy 88.904058 -232.069474)
			(xy 88.944561 -232.09743) (xy 88.980054 -232.131522) (xy 89.009619 -232.170866) (xy 89.03249 -232.214443)
			(xy 89.048074 -232.261124) (xy 89.055969 -232.309701) (xy 89.056464 -232.334308) (xy 89.385152 -232.334308)
			(xy 89.389112 -232.285254) (xy 89.400889 -232.23747) (xy 89.42018 -232.192194) (xy 89.446483 -232.150598)
			(xy 89.479118 -232.113761) (xy 89.517239 -232.082636) (xy 89.55986 -232.058029) (xy 89.605876 -232.040577)
			(xy 89.654095 -232.030733) (xy 89.70327 -232.028752) (xy 89.752125 -232.034684) (xy 89.799396 -232.048376)
			(xy 89.843858 -232.069474) (xy 89.884361 -232.09743) (xy 89.919854 -232.131522) (xy 89.949419 -232.170866)
			(xy 89.97229 -232.214443) (xy 89.987874 -232.261124) (xy 89.995769 -232.309701) (xy 89.996264 -232.334308)
			(xy 90.314775 -232.334308) (xy 90.31887 -232.28358) (xy 90.331049 -232.234166) (xy 90.350997 -232.187346)
			(xy 90.378198 -232.144332) (xy 90.411946 -232.106238) (xy 90.451368 -232.074051) (xy 90.495442 -232.048605)
			(xy 90.543028 -232.030558) (xy 90.592892 -232.020378) (xy 90.643744 -232.018329) (xy 90.694265 -232.024463)
			(xy 90.743149 -232.038623) (xy 90.789128 -232.06044) (xy 90.831012 -232.08935) (xy 90.867716 -232.124605)
			(xy 90.898289 -232.165291) (xy 90.92194 -232.210354) (xy 90.938056 -232.258628) (xy 90.94622 -232.308862)
			(xy 90.946732 -232.334308) (xy 91.26526 -232.334308) (xy 91.26922 -232.285254) (xy 91.280997 -232.23747)
			(xy 91.300288 -232.192194) (xy 91.326591 -232.150598) (xy 91.359226 -232.113761) (xy 91.397347 -232.082636)
			(xy 91.439968 -232.058029) (xy 91.485984 -232.040577) (xy 91.534203 -232.030733) (xy 91.583378 -232.028752)
			(xy 91.632233 -232.034684) (xy 91.679504 -232.048376) (xy 91.723966 -232.069474) (xy 91.764469 -232.09743)
			(xy 91.799962 -232.131522) (xy 91.829527 -232.170866) (xy 91.852398 -232.214443) (xy 91.867982 -232.261124)
			(xy 91.875877 -232.309701) (xy 91.876372 -232.334308) (xy 92.194883 -232.334308) (xy 92.198978 -232.28358)
			(xy 92.211157 -232.234166) (xy 92.231105 -232.187346) (xy 92.258306 -232.144332) (xy 92.292054 -232.106238)
			(xy 92.331476 -232.074051) (xy 92.37555 -232.048605) (xy 92.423136 -232.030558) (xy 92.473 -232.020378)
			(xy 92.523852 -232.018329) (xy 92.574373 -232.024463) (xy 92.623257 -232.038623) (xy 92.669236 -232.06044)
			(xy 92.71112 -232.08935) (xy 92.747824 -232.124605) (xy 92.778397 -232.165291) (xy 92.802048 -232.210354)
			(xy 92.818164 -232.258628) (xy 92.826328 -232.308862) (xy 92.82684 -232.334308) (xy 93.145114 -232.334308)
			(xy 93.149074 -232.285254) (xy 93.160851 -232.23747) (xy 93.180142 -232.192194) (xy 93.206445 -232.150598)
			(xy 93.23908 -232.113761) (xy 93.277201 -232.082636) (xy 93.319822 -232.058029) (xy 93.365838 -232.040577)
			(xy 93.414057 -232.030733) (xy 93.463232 -232.028752) (xy 93.512087 -232.034684) (xy 93.559358 -232.048376)
			(xy 93.60382 -232.069474) (xy 93.644323 -232.09743) (xy 93.679816 -232.131522) (xy 93.709381 -232.170866)
			(xy 93.732252 -232.214443) (xy 93.747836 -232.261124) (xy 93.755731 -232.309701) (xy 93.756226 -232.334308)
			(xy 94.074737 -232.334308) (xy 94.078832 -232.28358) (xy 94.091011 -232.234166) (xy 94.110959 -232.187346)
			(xy 94.13816 -232.144332) (xy 94.171908 -232.106238) (xy 94.21133 -232.074051) (xy 94.255404 -232.048605)
			(xy 94.30299 -232.030558) (xy 94.352854 -232.020378) (xy 94.403706 -232.018329) (xy 94.454227 -232.024463)
			(xy 94.503111 -232.038623) (xy 94.54909 -232.06044) (xy 94.590974 -232.08935) (xy 94.627678 -232.124605)
			(xy 94.658251 -232.165291) (xy 94.681902 -232.210354) (xy 94.698018 -232.258628) (xy 94.706182 -232.308862)
			(xy 94.706694 -232.334308) (xy 94.706182 -232.359754) (xy 94.698018 -232.409988) (xy 94.681902 -232.458262)
			(xy 94.658251 -232.503325) (xy 94.627678 -232.544011) (xy 94.590974 -232.579266) (xy 94.54909 -232.608176)
			(xy 94.503111 -232.629993) (xy 94.454227 -232.644153) (xy 94.403706 -232.650287) (xy 94.352854 -232.648238)
			(xy 94.30299 -232.638058) (xy 94.255404 -232.620011) (xy 94.21133 -232.594565) (xy 94.171908 -232.562378)
			(xy 94.13816 -232.524284) (xy 94.110959 -232.48127) (xy 94.091011 -232.43445) (xy 94.078832 -232.385036)
			(xy 94.074737 -232.334308) (xy 93.756226 -232.334308) (xy 93.755731 -232.358915) (xy 93.747836 -232.407492)
			(xy 93.732252 -232.454173) (xy 93.709381 -232.49775) (xy 93.679816 -232.537094) (xy 93.644323 -232.571186)
			(xy 93.60382 -232.599142) (xy 93.559358 -232.62024) (xy 93.512087 -232.633932) (xy 93.463232 -232.639864)
			(xy 93.414057 -232.637883) (xy 93.365838 -232.628039) (xy 93.319822 -232.610587) (xy 93.277201 -232.58598)
			(xy 93.23908 -232.554855) (xy 93.206445 -232.518018) (xy 93.180142 -232.476422) (xy 93.160851 -232.431146)
			(xy 93.149074 -232.383362) (xy 93.145114 -232.334308) (xy 92.82684 -232.334308) (xy 92.826328 -232.359754)
			(xy 92.818164 -232.409988) (xy 92.802048 -232.458262) (xy 92.778397 -232.503325) (xy 92.747824 -232.544011)
			(xy 92.71112 -232.579266) (xy 92.669236 -232.608176) (xy 92.623257 -232.629993) (xy 92.574373 -232.644153)
			(xy 92.523852 -232.650287) (xy 92.473 -232.648238) (xy 92.423136 -232.638058) (xy 92.37555 -232.620011)
			(xy 92.331476 -232.594565) (xy 92.292054 -232.562378) (xy 92.258306 -232.524284) (xy 92.231105 -232.48127)
			(xy 92.211157 -232.43445) (xy 92.198978 -232.385036) (xy 92.194883 -232.334308) (xy 91.876372 -232.334308)
			(xy 91.875877 -232.358915) (xy 91.867982 -232.407492) (xy 91.852398 -232.454173) (xy 91.829527 -232.49775)
			(xy 91.799962 -232.537094) (xy 91.764469 -232.571186) (xy 91.723966 -232.599142) (xy 91.679504 -232.62024)
			(xy 91.632233 -232.633932) (xy 91.583378 -232.639864) (xy 91.534203 -232.637883) (xy 91.485984 -232.628039)
			(xy 91.439968 -232.610587) (xy 91.397347 -232.58598) (xy 91.359226 -232.554855) (xy 91.326591 -232.518018)
			(xy 91.300288 -232.476422) (xy 91.280997 -232.431146) (xy 91.26922 -232.383362) (xy 91.26526 -232.334308)
			(xy 90.946732 -232.334308) (xy 90.94622 -232.359754) (xy 90.938056 -232.409988) (xy 90.92194 -232.458262)
			(xy 90.898289 -232.503325) (xy 90.867716 -232.544011) (xy 90.831012 -232.579266) (xy 90.789128 -232.608176)
			(xy 90.743149 -232.629993) (xy 90.694265 -232.644153) (xy 90.643744 -232.650287) (xy 90.592892 -232.648238)
			(xy 90.543028 -232.638058) (xy 90.495442 -232.620011) (xy 90.451368 -232.594565) (xy 90.411946 -232.562378)
			(xy 90.378198 -232.524284) (xy 90.350997 -232.48127) (xy 90.331049 -232.43445) (xy 90.31887 -232.385036)
			(xy 90.314775 -232.334308) (xy 89.996264 -232.334308) (xy 89.995769 -232.358915) (xy 89.987874 -232.407492)
			(xy 89.97229 -232.454173) (xy 89.949419 -232.49775) (xy 89.919854 -232.537094) (xy 89.884361 -232.571186)
			(xy 89.843858 -232.599142) (xy 89.799396 -232.62024) (xy 89.752125 -232.633932) (xy 89.70327 -232.639864)
			(xy 89.654095 -232.637883) (xy 89.605876 -232.628039) (xy 89.55986 -232.610587) (xy 89.517239 -232.58598)
			(xy 89.479118 -232.554855) (xy 89.446483 -232.518018) (xy 89.42018 -232.476422) (xy 89.400889 -232.431146)
			(xy 89.389112 -232.383362) (xy 89.385152 -232.334308) (xy 89.056464 -232.334308) (xy 89.055969 -232.358915)
			(xy 89.048074 -232.407492) (xy 89.03249 -232.454173) (xy 89.009619 -232.49775) (xy 88.980054 -232.537094)
			(xy 88.944561 -232.571186) (xy 88.904058 -232.599142) (xy 88.859596 -232.62024) (xy 88.812325 -232.633932)
			(xy 88.76347 -232.639864) (xy 88.714295 -232.637883) (xy 88.666076 -232.628039) (xy 88.62006 -232.610587)
			(xy 88.577439 -232.58598) (xy 88.539318 -232.554855) (xy 88.506683 -232.518018) (xy 88.48038 -232.476422)
			(xy 88.461089 -232.431146) (xy 88.449312 -232.383362) (xy 88.445352 -232.334308) (xy 88.11641 -232.334308)
			(xy 88.115915 -232.358915) (xy 88.10802 -232.407492) (xy 88.092436 -232.454173) (xy 88.069565 -232.49775)
			(xy 88.04 -232.537094) (xy 88.004507 -232.571186) (xy 87.964004 -232.599142) (xy 87.919542 -232.62024)
			(xy 87.872271 -232.633932) (xy 87.823416 -232.639864) (xy 87.774241 -232.637883) (xy 87.726022 -232.628039)
			(xy 87.680006 -232.610587) (xy 87.637385 -232.58598) (xy 87.599264 -232.554855) (xy 87.566629 -232.518018)
			(xy 87.540326 -232.476422) (xy 87.521035 -232.431146) (xy 87.509258 -232.383362) (xy 87.505298 -232.334308)
			(xy 87.307674 -232.334308) (xy 87.307674 -232.498138) (xy 87.307143 -232.507977) (xy 87.299561 -232.526145)
			(xy 87.292942 -232.533444) (xy 87.063326 -232.76306) (xy 87.056088 -232.769774) (xy 87.037883 -232.777374)
			(xy 87.02802 -232.777792) (xy 86.832948 -232.777792) (xy 86.823109 -232.778324) (xy 86.804942 -232.785906)
			(xy 86.797642 -232.792524) (xy 86.720426 -232.86974) (xy 86.713713 -232.876978) (xy 86.706123 -232.895183)
			(xy 86.705694 -232.905046) (xy 86.705694 -233.124248) (xy 86.706456 -233.144314) (xy 87.035144 -233.144314)
			(xy 87.039104 -233.09526) (xy 87.050881 -233.047476) (xy 87.070172 -233.0022) (xy 87.096475 -232.960604)
			(xy 87.12911 -232.923767) (xy 87.167231 -232.892642) (xy 87.209852 -232.868035) (xy 87.255868 -232.850583)
			(xy 87.304087 -232.840739) (xy 87.353262 -232.838758) (xy 87.402117 -232.84469) (xy 87.449388 -232.858382)
			(xy 87.49385 -232.87948) (xy 87.534353 -232.907436) (xy 87.569846 -232.941528) (xy 87.599411 -232.980872)
			(xy 87.622282 -233.024449) (xy 87.637866 -233.07113) (xy 87.645761 -233.119707) (xy 87.646256 -233.144314)
			(xy 87.975198 -233.144314) (xy 87.979158 -233.09526) (xy 87.990935 -233.047476) (xy 88.010226 -233.0022)
			(xy 88.036529 -232.960604) (xy 88.069164 -232.923767) (xy 88.107285 -232.892642) (xy 88.149906 -232.868035)
			(xy 88.195922 -232.850583) (xy 88.244141 -232.840739) (xy 88.293316 -232.838758) (xy 88.342171 -232.84469)
			(xy 88.389442 -232.858382) (xy 88.433904 -232.87948) (xy 88.474407 -232.907436) (xy 88.5099 -232.941528)
			(xy 88.539465 -232.980872) (xy 88.562336 -233.024449) (xy 88.57792 -233.07113) (xy 88.585815 -233.119707)
			(xy 88.58631 -233.144314) (xy 88.915252 -233.144314) (xy 88.919212 -233.09526) (xy 88.930989 -233.047476)
			(xy 88.95028 -233.0022) (xy 88.976583 -232.960604) (xy 89.009218 -232.923767) (xy 89.047339 -232.892642)
			(xy 89.08996 -232.868035) (xy 89.135976 -232.850583) (xy 89.184195 -232.840739) (xy 89.23337 -232.838758)
			(xy 89.282225 -232.84469) (xy 89.329496 -232.858382) (xy 89.373958 -232.87948) (xy 89.414461 -232.907436)
			(xy 89.449954 -232.941528) (xy 89.479519 -232.980872) (xy 89.50239 -233.024449) (xy 89.517974 -233.07113)
			(xy 89.525869 -233.119707) (xy 89.526364 -233.144314) (xy 89.855306 -233.144314) (xy 89.859266 -233.09526)
			(xy 89.871043 -233.047476) (xy 89.890334 -233.0022) (xy 89.916637 -232.960604) (xy 89.949272 -232.923767)
			(xy 89.987393 -232.892642) (xy 90.030014 -232.868035) (xy 90.07603 -232.850583) (xy 90.124249 -232.840739)
			(xy 90.173424 -232.838758) (xy 90.222279 -232.84469) (xy 90.26955 -232.858382) (xy 90.314012 -232.87948)
			(xy 90.354515 -232.907436) (xy 90.390008 -232.941528) (xy 90.419573 -232.980872) (xy 90.442444 -233.024449)
			(xy 90.458028 -233.07113) (xy 90.465923 -233.119707) (xy 90.466418 -233.144314) (xy 90.784675 -233.144314)
			(xy 90.78877 -233.093586) (xy 90.800949 -233.044172) (xy 90.820897 -232.997352) (xy 90.848098 -232.954338)
			(xy 90.881846 -232.916244) (xy 90.921268 -232.884057) (xy 90.965342 -232.858611) (xy 91.012928 -232.840564)
			(xy 91.062792 -232.830384) (xy 91.113644 -232.828335) (xy 91.164165 -232.834469) (xy 91.213049 -232.848629)
			(xy 91.259028 -232.870446) (xy 91.300912 -232.899356) (xy 91.337616 -232.934611) (xy 91.368189 -232.975297)
			(xy 91.39184 -233.02036) (xy 91.407956 -233.068634) (xy 91.41612 -233.118868) (xy 91.416632 -233.144314)
			(xy 91.724729 -233.144314) (xy 91.728824 -233.093586) (xy 91.741003 -233.044172) (xy 91.760951 -232.997352)
			(xy 91.788152 -232.954338) (xy 91.8219 -232.916244) (xy 91.861322 -232.884057) (xy 91.905396 -232.858611)
			(xy 91.952982 -232.840564) (xy 92.002846 -232.830384) (xy 92.053698 -232.828335) (xy 92.104219 -232.834469)
			(xy 92.153103 -232.848629) (xy 92.199082 -232.870446) (xy 92.240966 -232.899356) (xy 92.27767 -232.934611)
			(xy 92.308243 -232.975297) (xy 92.331894 -233.02036) (xy 92.34801 -233.068634) (xy 92.356174 -233.118868)
			(xy 92.356686 -233.144314) (xy 92.675214 -233.144314) (xy 92.679174 -233.09526) (xy 92.690951 -233.047476)
			(xy 92.710242 -233.0022) (xy 92.736545 -232.960604) (xy 92.76918 -232.923767) (xy 92.807301 -232.892642)
			(xy 92.849922 -232.868035) (xy 92.895938 -232.850583) (xy 92.944157 -232.840739) (xy 92.993332 -232.838758)
			(xy 93.042187 -232.84469) (xy 93.089458 -232.858382) (xy 93.13392 -232.87948) (xy 93.174423 -232.907436)
			(xy 93.209916 -232.941528) (xy 93.239481 -232.980872) (xy 93.262352 -233.024449) (xy 93.277936 -233.07113)
			(xy 93.285831 -233.119707) (xy 93.286326 -233.144314) (xy 93.604837 -233.144314) (xy 93.608932 -233.093586)
			(xy 93.621111 -233.044172) (xy 93.641059 -232.997352) (xy 93.66826 -232.954338) (xy 93.702008 -232.916244)
			(xy 93.74143 -232.884057) (xy 93.785504 -232.858611) (xy 93.83309 -232.840564) (xy 93.882954 -232.830384)
			(xy 93.933806 -232.828335) (xy 93.984327 -232.834469) (xy 94.033211 -232.848629) (xy 94.07919 -232.870446)
			(xy 94.121074 -232.899356) (xy 94.157778 -232.934611) (xy 94.188351 -232.975297) (xy 94.212002 -233.02036)
			(xy 94.228118 -233.068634) (xy 94.236282 -233.118868) (xy 94.236794 -233.144314) (xy 94.555322 -233.144314)
			(xy 94.559282 -233.09526) (xy 94.571059 -233.047476) (xy 94.59035 -233.0022) (xy 94.616653 -232.960604)
			(xy 94.649288 -232.923767) (xy 94.687409 -232.892642) (xy 94.73003 -232.868035) (xy 94.776046 -232.850583)
			(xy 94.824265 -232.840739) (xy 94.87344 -232.838758) (xy 94.922295 -232.84469) (xy 94.969566 -232.858382)
			(xy 95.014028 -232.87948) (xy 95.054531 -232.907436) (xy 95.090024 -232.941528) (xy 95.119589 -232.980872)
			(xy 95.14246 -233.024449) (xy 95.158044 -233.07113) (xy 95.165939 -233.119707) (xy 95.166434 -233.144314)
			(xy 95.165939 -233.168921) (xy 95.158044 -233.217498) (xy 95.14246 -233.264179) (xy 95.119589 -233.307756)
			(xy 95.090024 -233.3471) (xy 95.054531 -233.381192) (xy 95.014028 -233.409148) (xy 94.969566 -233.430246)
			(xy 94.922295 -233.443938) (xy 94.87344 -233.44987) (xy 94.824265 -233.447889) (xy 94.776046 -233.438045)
			(xy 94.73003 -233.420593) (xy 94.687409 -233.395986) (xy 94.649288 -233.364861) (xy 94.616653 -233.328024)
			(xy 94.59035 -233.286428) (xy 94.571059 -233.241152) (xy 94.559282 -233.193368) (xy 94.555322 -233.144314)
			(xy 94.236794 -233.144314) (xy 94.236282 -233.16976) (xy 94.228118 -233.219994) (xy 94.212002 -233.268268)
			(xy 94.188351 -233.313331) (xy 94.157778 -233.354017) (xy 94.121074 -233.389272) (xy 94.07919 -233.418182)
			(xy 94.033211 -233.439999) (xy 93.984327 -233.454159) (xy 93.933806 -233.460293) (xy 93.882954 -233.458244)
			(xy 93.83309 -233.448064) (xy 93.785504 -233.430017) (xy 93.74143 -233.404571) (xy 93.702008 -233.372384)
			(xy 93.66826 -233.33429) (xy 93.641059 -233.291276) (xy 93.621111 -233.244456) (xy 93.608932 -233.195042)
			(xy 93.604837 -233.144314) (xy 93.286326 -233.144314) (xy 93.285831 -233.168921) (xy 93.277936 -233.217498)
			(xy 93.262352 -233.264179) (xy 93.239481 -233.307756) (xy 93.209916 -233.3471) (xy 93.174423 -233.381192)
			(xy 93.13392 -233.409148) (xy 93.089458 -233.430246) (xy 93.042187 -233.443938) (xy 92.993332 -233.44987)
			(xy 92.944157 -233.447889) (xy 92.895938 -233.438045) (xy 92.849922 -233.420593) (xy 92.807301 -233.395986)
			(xy 92.76918 -233.364861) (xy 92.736545 -233.328024) (xy 92.710242 -233.286428) (xy 92.690951 -233.241152)
			(xy 92.679174 -233.193368) (xy 92.675214 -233.144314) (xy 92.356686 -233.144314) (xy 92.356174 -233.16976)
			(xy 92.34801 -233.219994) (xy 92.331894 -233.268268) (xy 92.308243 -233.313331) (xy 92.27767 -233.354017)
			(xy 92.240966 -233.389272) (xy 92.199082 -233.418182) (xy 92.153103 -233.439999) (xy 92.104219 -233.454159)
			(xy 92.053698 -233.460293) (xy 92.002846 -233.458244) (xy 91.952982 -233.448064) (xy 91.905396 -233.430017)
			(xy 91.861322 -233.404571) (xy 91.8219 -233.372384) (xy 91.788152 -233.33429) (xy 91.760951 -233.291276)
			(xy 91.741003 -233.244456) (xy 91.728824 -233.195042) (xy 91.724729 -233.144314) (xy 91.416632 -233.144314)
			(xy 91.41612 -233.16976) (xy 91.407956 -233.219994) (xy 91.39184 -233.268268) (xy 91.368189 -233.313331)
			(xy 91.337616 -233.354017) (xy 91.300912 -233.389272) (xy 91.259028 -233.418182) (xy 91.213049 -233.439999)
			(xy 91.164165 -233.454159) (xy 91.113644 -233.460293) (xy 91.062792 -233.458244) (xy 91.012928 -233.448064)
			(xy 90.965342 -233.430017) (xy 90.921268 -233.404571) (xy 90.881846 -233.372384) (xy 90.848098 -233.33429)
			(xy 90.820897 -233.291276) (xy 90.800949 -233.244456) (xy 90.78877 -233.195042) (xy 90.784675 -233.144314)
			(xy 90.466418 -233.144314) (xy 90.465923 -233.168921) (xy 90.458028 -233.217498) (xy 90.442444 -233.264179)
			(xy 90.419573 -233.307756) (xy 90.390008 -233.3471) (xy 90.354515 -233.381192) (xy 90.314012 -233.409148)
			(xy 90.26955 -233.430246) (xy 90.222279 -233.443938) (xy 90.173424 -233.44987) (xy 90.124249 -233.447889)
			(xy 90.07603 -233.438045) (xy 90.030014 -233.420593) (xy 89.987393 -233.395986) (xy 89.949272 -233.364861)
			(xy 89.916637 -233.328024) (xy 89.890334 -233.286428) (xy 89.871043 -233.241152) (xy 89.859266 -233.193368)
			(xy 89.855306 -233.144314) (xy 89.526364 -233.144314) (xy 89.525869 -233.168921) (xy 89.517974 -233.217498)
			(xy 89.50239 -233.264179) (xy 89.479519 -233.307756) (xy 89.449954 -233.3471) (xy 89.414461 -233.381192)
			(xy 89.373958 -233.409148) (xy 89.329496 -233.430246) (xy 89.282225 -233.443938) (xy 89.23337 -233.44987)
			(xy 89.184195 -233.447889) (xy 89.135976 -233.438045) (xy 89.08996 -233.420593) (xy 89.047339 -233.395986)
			(xy 89.009218 -233.364861) (xy 88.976583 -233.328024) (xy 88.95028 -233.286428) (xy 88.930989 -233.241152)
			(xy 88.919212 -233.193368) (xy 88.915252 -233.144314) (xy 88.58631 -233.144314) (xy 88.585815 -233.168921)
			(xy 88.57792 -233.217498) (xy 88.562336 -233.264179) (xy 88.539465 -233.307756) (xy 88.5099 -233.3471)
			(xy 88.474407 -233.381192) (xy 88.433904 -233.409148) (xy 88.389442 -233.430246) (xy 88.342171 -233.443938)
			(xy 88.293316 -233.44987) (xy 88.244141 -233.447889) (xy 88.195922 -233.438045) (xy 88.149906 -233.420593)
			(xy 88.107285 -233.395986) (xy 88.069164 -233.364861) (xy 88.036529 -233.328024) (xy 88.010226 -233.286428)
			(xy 87.990935 -233.241152) (xy 87.979158 -233.193368) (xy 87.975198 -233.144314) (xy 87.646256 -233.144314)
			(xy 87.645761 -233.168921) (xy 87.637866 -233.217498) (xy 87.622282 -233.264179) (xy 87.599411 -233.307756)
			(xy 87.569846 -233.3471) (xy 87.534353 -233.381192) (xy 87.49385 -233.409148) (xy 87.449388 -233.430246)
			(xy 87.402117 -233.443938) (xy 87.353262 -233.44987) (xy 87.304087 -233.447889) (xy 87.255868 -233.438045)
			(xy 87.209852 -233.420593) (xy 87.167231 -233.395986) (xy 87.12911 -233.364861) (xy 87.096475 -233.328024)
			(xy 87.070172 -233.286428) (xy 87.050881 -233.241152) (xy 87.039104 -233.193368) (xy 87.035144 -233.144314)
			(xy 86.706456 -233.144314) (xy 86.705694 -233.16438) (xy 86.705694 -233.49077) (xy 86.706163 -233.500643)
			(xy 86.713619 -233.518929) (xy 86.720172 -233.52633) (xy 86.720426 -233.526584) (xy 86.784688 -233.590846)
			(xy 86.785196 -233.591354) (xy 86.79258 -233.597929) (xy 86.810879 -233.605364) (xy 86.820756 -233.605832)
			(xy 86.97722 -233.605832) (xy 86.987061 -233.60636) (xy 87.005232 -233.613938) (xy 87.012526 -233.620564)
			(xy 87.165942 -233.77398) (xy 87.172657 -233.781218) (xy 87.180258 -233.799422) (xy 87.180674 -233.809286)
			(xy 87.180674 -233.95432) (xy 87.505298 -233.95432) (xy 87.509258 -233.905266) (xy 87.521035 -233.857482)
			(xy 87.540326 -233.812206) (xy 87.566629 -233.77061) (xy 87.599264 -233.733773) (xy 87.637385 -233.702648)
			(xy 87.680006 -233.678041) (xy 87.726022 -233.660589) (xy 87.774241 -233.650745) (xy 87.823416 -233.648764)
			(xy 87.872271 -233.654696) (xy 87.919542 -233.668388) (xy 87.964004 -233.689486) (xy 88.004507 -233.717442)
			(xy 88.04 -233.751534) (xy 88.069565 -233.790878) (xy 88.092436 -233.834455) (xy 88.10802 -233.881136)
			(xy 88.115915 -233.929713) (xy 88.11641 -233.95432) (xy 88.445352 -233.95432) (xy 88.449312 -233.905266)
			(xy 88.461089 -233.857482) (xy 88.48038 -233.812206) (xy 88.506683 -233.77061) (xy 88.539318 -233.733773)
			(xy 88.577439 -233.702648) (xy 88.62006 -233.678041) (xy 88.666076 -233.660589) (xy 88.714295 -233.650745)
			(xy 88.76347 -233.648764) (xy 88.812325 -233.654696) (xy 88.859596 -233.668388) (xy 88.904058 -233.689486)
			(xy 88.944561 -233.717442) (xy 88.980054 -233.751534) (xy 89.009619 -233.790878) (xy 89.03249 -233.834455)
			(xy 89.048074 -233.881136) (xy 89.055969 -233.929713) (xy 89.056464 -233.95432) (xy 89.385152 -233.95432)
			(xy 89.389112 -233.905266) (xy 89.400889 -233.857482) (xy 89.42018 -233.812206) (xy 89.446483 -233.77061)
			(xy 89.479118 -233.733773) (xy 89.517239 -233.702648) (xy 89.55986 -233.678041) (xy 89.605876 -233.660589)
			(xy 89.654095 -233.650745) (xy 89.70327 -233.648764) (xy 89.752125 -233.654696) (xy 89.799396 -233.668388)
			(xy 89.843858 -233.689486) (xy 89.884361 -233.717442) (xy 89.919854 -233.751534) (xy 89.949419 -233.790878)
			(xy 89.97229 -233.834455) (xy 89.987874 -233.881136) (xy 89.995769 -233.929713) (xy 89.996264 -233.95432)
			(xy 90.314775 -233.95432) (xy 90.31887 -233.903592) (xy 90.331049 -233.854178) (xy 90.350997 -233.807358)
			(xy 90.378198 -233.764344) (xy 90.411946 -233.72625) (xy 90.451368 -233.694063) (xy 90.495442 -233.668617)
			(xy 90.543028 -233.65057) (xy 90.592892 -233.64039) (xy 90.643744 -233.638341) (xy 90.694265 -233.644475)
			(xy 90.743149 -233.658635) (xy 90.789128 -233.680452) (xy 90.831012 -233.709362) (xy 90.867716 -233.744617)
			(xy 90.898289 -233.785303) (xy 90.92194 -233.830366) (xy 90.938056 -233.87864) (xy 90.94622 -233.928874)
			(xy 90.946732 -233.95432) (xy 91.26526 -233.95432) (xy 91.26922 -233.905266) (xy 91.280997 -233.857482)
			(xy 91.300288 -233.812206) (xy 91.326591 -233.77061) (xy 91.359226 -233.733773) (xy 91.397347 -233.702648)
			(xy 91.439968 -233.678041) (xy 91.485984 -233.660589) (xy 91.534203 -233.650745) (xy 91.583378 -233.648764)
			(xy 91.632233 -233.654696) (xy 91.679504 -233.668388) (xy 91.723966 -233.689486) (xy 91.764469 -233.717442)
			(xy 91.799962 -233.751534) (xy 91.829527 -233.790878) (xy 91.852398 -233.834455) (xy 91.867982 -233.881136)
			(xy 91.875877 -233.929713) (xy 91.876372 -233.95432) (xy 92.194883 -233.95432) (xy 92.198978 -233.903592)
			(xy 92.211157 -233.854178) (xy 92.231105 -233.807358) (xy 92.258306 -233.764344) (xy 92.292054 -233.72625)
			(xy 92.331476 -233.694063) (xy 92.37555 -233.668617) (xy 92.423136 -233.65057) (xy 92.473 -233.64039)
			(xy 92.523852 -233.638341) (xy 92.574373 -233.644475) (xy 92.623257 -233.658635) (xy 92.669236 -233.680452)
			(xy 92.71112 -233.709362) (xy 92.747824 -233.744617) (xy 92.778397 -233.785303) (xy 92.802048 -233.830366)
			(xy 92.818164 -233.87864) (xy 92.826328 -233.928874) (xy 92.82684 -233.95432) (xy 93.145114 -233.95432)
			(xy 93.149074 -233.905266) (xy 93.160851 -233.857482) (xy 93.180142 -233.812206) (xy 93.206445 -233.77061)
			(xy 93.23908 -233.733773) (xy 93.277201 -233.702648) (xy 93.319822 -233.678041) (xy 93.365838 -233.660589)
			(xy 93.414057 -233.650745) (xy 93.463232 -233.648764) (xy 93.512087 -233.654696) (xy 93.559358 -233.668388)
			(xy 93.60382 -233.689486) (xy 93.644323 -233.717442) (xy 93.679816 -233.751534) (xy 93.709381 -233.790878)
			(xy 93.732252 -233.834455) (xy 93.747836 -233.881136) (xy 93.755731 -233.929713) (xy 93.756226 -233.95432)
			(xy 94.074737 -233.95432) (xy 94.078832 -233.903592) (xy 94.091011 -233.854178) (xy 94.110959 -233.807358)
			(xy 94.13816 -233.764344) (xy 94.171908 -233.72625) (xy 94.21133 -233.694063) (xy 94.255404 -233.668617)
			(xy 94.30299 -233.65057) (xy 94.352854 -233.64039) (xy 94.403706 -233.638341) (xy 94.454227 -233.644475)
			(xy 94.503111 -233.658635) (xy 94.54909 -233.680452) (xy 94.590974 -233.709362) (xy 94.627678 -233.744617)
			(xy 94.658251 -233.785303) (xy 94.681902 -233.830366) (xy 94.698018 -233.87864) (xy 94.706182 -233.928874)
			(xy 94.706694 -233.95432) (xy 94.706182 -233.979766) (xy 94.698018 -234.03) (xy 94.681902 -234.078274)
			(xy 94.658251 -234.123337) (xy 94.627678 -234.164023) (xy 94.590974 -234.199278) (xy 94.54909 -234.228188)
			(xy 94.503111 -234.250005) (xy 94.454227 -234.264165) (xy 94.403706 -234.270299) (xy 94.352854 -234.26825)
			(xy 94.30299 -234.25807) (xy 94.255404 -234.240023) (xy 94.21133 -234.214577) (xy 94.171908 -234.18239)
			(xy 94.13816 -234.144296) (xy 94.110959 -234.101282) (xy 94.091011 -234.054462) (xy 94.078832 -234.005048)
			(xy 94.074737 -233.95432) (xy 93.756226 -233.95432) (xy 93.755731 -233.978927) (xy 93.747836 -234.027504)
			(xy 93.732252 -234.074185) (xy 93.709381 -234.117762) (xy 93.679816 -234.157106) (xy 93.644323 -234.191198)
			(xy 93.60382 -234.219154) (xy 93.559358 -234.240252) (xy 93.512087 -234.253944) (xy 93.463232 -234.259876)
			(xy 93.414057 -234.257895) (xy 93.365838 -234.248051) (xy 93.319822 -234.230599) (xy 93.277201 -234.205992)
			(xy 93.23908 -234.174867) (xy 93.206445 -234.13803) (xy 93.180142 -234.096434) (xy 93.160851 -234.051158)
			(xy 93.149074 -234.003374) (xy 93.145114 -233.95432) (xy 92.82684 -233.95432) (xy 92.826328 -233.979766)
			(xy 92.818164 -234.03) (xy 92.802048 -234.078274) (xy 92.778397 -234.123337) (xy 92.747824 -234.164023)
			(xy 92.71112 -234.199278) (xy 92.669236 -234.228188) (xy 92.623257 -234.250005) (xy 92.574373 -234.264165)
			(xy 92.523852 -234.270299) (xy 92.473 -234.26825) (xy 92.423136 -234.25807) (xy 92.37555 -234.240023)
			(xy 92.331476 -234.214577) (xy 92.292054 -234.18239) (xy 92.258306 -234.144296) (xy 92.231105 -234.101282)
			(xy 92.211157 -234.054462) (xy 92.198978 -234.005048) (xy 92.194883 -233.95432) (xy 91.876372 -233.95432)
			(xy 91.875877 -233.978927) (xy 91.867982 -234.027504) (xy 91.852398 -234.074185) (xy 91.829527 -234.117762)
			(xy 91.799962 -234.157106) (xy 91.764469 -234.191198) (xy 91.723966 -234.219154) (xy 91.679504 -234.240252)
			(xy 91.632233 -234.253944) (xy 91.583378 -234.259876) (xy 91.534203 -234.257895) (xy 91.485984 -234.248051)
			(xy 91.439968 -234.230599) (xy 91.397347 -234.205992) (xy 91.359226 -234.174867) (xy 91.326591 -234.13803)
			(xy 91.300288 -234.096434) (xy 91.280997 -234.051158) (xy 91.26922 -234.003374) (xy 91.26526 -233.95432)
			(xy 90.946732 -233.95432) (xy 90.94622 -233.979766) (xy 90.938056 -234.03) (xy 90.92194 -234.078274)
			(xy 90.898289 -234.123337) (xy 90.867716 -234.164023) (xy 90.831012 -234.199278) (xy 90.789128 -234.228188)
			(xy 90.743149 -234.250005) (xy 90.694265 -234.264165) (xy 90.643744 -234.270299) (xy 90.592892 -234.26825)
			(xy 90.543028 -234.25807) (xy 90.495442 -234.240023) (xy 90.451368 -234.214577) (xy 90.411946 -234.18239)
			(xy 90.378198 -234.144296) (xy 90.350997 -234.101282) (xy 90.331049 -234.054462) (xy 90.31887 -234.005048)
			(xy 90.314775 -233.95432) (xy 89.996264 -233.95432) (xy 89.995769 -233.978927) (xy 89.987874 -234.027504)
			(xy 89.97229 -234.074185) (xy 89.949419 -234.117762) (xy 89.919854 -234.157106) (xy 89.884361 -234.191198)
			(xy 89.843858 -234.219154) (xy 89.799396 -234.240252) (xy 89.752125 -234.253944) (xy 89.70327 -234.259876)
			(xy 89.654095 -234.257895) (xy 89.605876 -234.248051) (xy 89.55986 -234.230599) (xy 89.517239 -234.205992)
			(xy 89.479118 -234.174867) (xy 89.446483 -234.13803) (xy 89.42018 -234.096434) (xy 89.400889 -234.051158)
			(xy 89.389112 -234.003374) (xy 89.385152 -233.95432) (xy 89.056464 -233.95432) (xy 89.055969 -233.978927)
			(xy 89.048074 -234.027504) (xy 89.03249 -234.074185) (xy 89.009619 -234.117762) (xy 88.980054 -234.157106)
			(xy 88.944561 -234.191198) (xy 88.904058 -234.219154) (xy 88.859596 -234.240252) (xy 88.812325 -234.253944)
			(xy 88.76347 -234.259876) (xy 88.714295 -234.257895) (xy 88.666076 -234.248051) (xy 88.62006 -234.230599)
			(xy 88.577439 -234.205992) (xy 88.539318 -234.174867) (xy 88.506683 -234.13803) (xy 88.48038 -234.096434)
			(xy 88.461089 -234.051158) (xy 88.449312 -234.003374) (xy 88.445352 -233.95432) (xy 88.11641 -233.95432)
			(xy 88.115915 -233.978927) (xy 88.10802 -234.027504) (xy 88.092436 -234.074185) (xy 88.069565 -234.117762)
			(xy 88.04 -234.157106) (xy 88.004507 -234.191198) (xy 87.964004 -234.219154) (xy 87.919542 -234.240252)
			(xy 87.872271 -234.253944) (xy 87.823416 -234.259876) (xy 87.774241 -234.257895) (xy 87.726022 -234.248051)
			(xy 87.680006 -234.230599) (xy 87.637385 -234.205992) (xy 87.599264 -234.174867) (xy 87.566629 -234.13803)
			(xy 87.540326 -234.096434) (xy 87.521035 -234.051158) (xy 87.509258 -234.003374) (xy 87.505298 -233.95432)
			(xy 87.180674 -233.95432) (xy 87.180674 -234.057698) (xy 87.180132 -234.067533) (xy 87.172535 -234.085684)
			(xy 87.165942 -234.093004) (xy 86.870286 -234.38866) (xy 86.863565 -234.395895) (xy 86.855952 -234.4141)
			(xy 86.855554 -234.423966) (xy 86.855554 -234.764326) (xy 87.035144 -234.764326) (xy 87.039104 -234.715272)
			(xy 87.050881 -234.667488) (xy 87.070172 -234.622212) (xy 87.096475 -234.580616) (xy 87.12911 -234.543779)
			(xy 87.167231 -234.512654) (xy 87.209852 -234.488047) (xy 87.255868 -234.470595) (xy 87.304087 -234.460751)
			(xy 87.353262 -234.45877) (xy 87.402117 -234.464702) (xy 87.449388 -234.478394) (xy 87.49385 -234.499492)
			(xy 87.534353 -234.527448) (xy 87.569846 -234.56154) (xy 87.599411 -234.600884) (xy 87.622282 -234.644461)
			(xy 87.637866 -234.691142) (xy 87.645761 -234.739719) (xy 87.646256 -234.764326) (xy 87.975198 -234.764326)
			(xy 87.979158 -234.715272) (xy 87.990935 -234.667488) (xy 88.010226 -234.622212) (xy 88.036529 -234.580616)
			(xy 88.069164 -234.543779) (xy 88.107285 -234.512654) (xy 88.149906 -234.488047) (xy 88.195922 -234.470595)
			(xy 88.244141 -234.460751) (xy 88.293316 -234.45877) (xy 88.342171 -234.464702) (xy 88.389442 -234.478394)
			(xy 88.433904 -234.499492) (xy 88.474407 -234.527448) (xy 88.5099 -234.56154) (xy 88.539465 -234.600884)
			(xy 88.562336 -234.644461) (xy 88.57792 -234.691142) (xy 88.585815 -234.739719) (xy 88.58631 -234.764326)
			(xy 88.915252 -234.764326) (xy 88.919212 -234.715272) (xy 88.930989 -234.667488) (xy 88.95028 -234.622212)
			(xy 88.976583 -234.580616) (xy 89.009218 -234.543779) (xy 89.047339 -234.512654) (xy 89.08996 -234.488047)
			(xy 89.135976 -234.470595) (xy 89.184195 -234.460751) (xy 89.23337 -234.45877) (xy 89.282225 -234.464702)
			(xy 89.329496 -234.478394) (xy 89.373958 -234.499492) (xy 89.414461 -234.527448) (xy 89.449954 -234.56154)
			(xy 89.479519 -234.600884) (xy 89.50239 -234.644461) (xy 89.517974 -234.691142) (xy 89.525869 -234.739719)
			(xy 89.526364 -234.764326) (xy 89.855306 -234.764326) (xy 89.859266 -234.715272) (xy 89.871043 -234.667488)
			(xy 89.890334 -234.622212) (xy 89.916637 -234.580616) (xy 89.949272 -234.543779) (xy 89.987393 -234.512654)
			(xy 90.030014 -234.488047) (xy 90.07603 -234.470595) (xy 90.124249 -234.460751) (xy 90.173424 -234.45877)
			(xy 90.222279 -234.464702) (xy 90.26955 -234.478394) (xy 90.314012 -234.499492) (xy 90.354515 -234.527448)
			(xy 90.390008 -234.56154) (xy 90.419573 -234.600884) (xy 90.442444 -234.644461) (xy 90.458028 -234.691142)
			(xy 90.465923 -234.739719) (xy 90.466418 -234.764326) (xy 90.784675 -234.764326) (xy 90.78877 -234.713598)
			(xy 90.800949 -234.664184) (xy 90.820897 -234.617364) (xy 90.848098 -234.57435) (xy 90.881846 -234.536256)
			(xy 90.921268 -234.504069) (xy 90.965342 -234.478623) (xy 91.012928 -234.460576) (xy 91.062792 -234.450396)
			(xy 91.113644 -234.448347) (xy 91.164165 -234.454481) (xy 91.213049 -234.468641) (xy 91.259028 -234.490458)
			(xy 91.300912 -234.519368) (xy 91.337616 -234.554623) (xy 91.368189 -234.595309) (xy 91.39184 -234.640372)
			(xy 91.407956 -234.688646) (xy 91.41612 -234.73888) (xy 91.416632 -234.764326) (xy 91.724729 -234.764326)
			(xy 91.728824 -234.713598) (xy 91.741003 -234.664184) (xy 91.760951 -234.617364) (xy 91.788152 -234.57435)
			(xy 91.8219 -234.536256) (xy 91.861322 -234.504069) (xy 91.905396 -234.478623) (xy 91.952982 -234.460576)
			(xy 92.002846 -234.450396) (xy 92.053698 -234.448347) (xy 92.104219 -234.454481) (xy 92.153103 -234.468641)
			(xy 92.199082 -234.490458) (xy 92.240966 -234.519368) (xy 92.27767 -234.554623) (xy 92.308243 -234.595309)
			(xy 92.331894 -234.640372) (xy 92.34801 -234.688646) (xy 92.356174 -234.73888) (xy 92.356686 -234.764326)
			(xy 92.675214 -234.764326) (xy 92.679174 -234.715272) (xy 92.690951 -234.667488) (xy 92.710242 -234.622212)
			(xy 92.736545 -234.580616) (xy 92.76918 -234.543779) (xy 92.807301 -234.512654) (xy 92.849922 -234.488047)
			(xy 92.895938 -234.470595) (xy 92.944157 -234.460751) (xy 92.993332 -234.45877) (xy 93.042187 -234.464702)
			(xy 93.089458 -234.478394) (xy 93.13392 -234.499492) (xy 93.174423 -234.527448) (xy 93.209916 -234.56154)
			(xy 93.239481 -234.600884) (xy 93.262352 -234.644461) (xy 93.277936 -234.691142) (xy 93.285831 -234.739719)
			(xy 93.286326 -234.764326) (xy 93.604837 -234.764326) (xy 93.608932 -234.713598) (xy 93.621111 -234.664184)
			(xy 93.641059 -234.617364) (xy 93.66826 -234.57435) (xy 93.702008 -234.536256) (xy 93.74143 -234.504069)
			(xy 93.785504 -234.478623) (xy 93.83309 -234.460576) (xy 93.882954 -234.450396) (xy 93.933806 -234.448347)
			(xy 93.984327 -234.454481) (xy 94.033211 -234.468641) (xy 94.07919 -234.490458) (xy 94.121074 -234.519368)
			(xy 94.157778 -234.554623) (xy 94.188351 -234.595309) (xy 94.212002 -234.640372) (xy 94.228118 -234.688646)
			(xy 94.236282 -234.73888) (xy 94.236794 -234.764326) (xy 94.555322 -234.764326) (xy 94.559282 -234.715272)
			(xy 94.571059 -234.667488) (xy 94.59035 -234.622212) (xy 94.616653 -234.580616) (xy 94.649288 -234.543779)
			(xy 94.687409 -234.512654) (xy 94.73003 -234.488047) (xy 94.776046 -234.470595) (xy 94.824265 -234.460751)
			(xy 94.87344 -234.45877) (xy 94.922295 -234.464702) (xy 94.969566 -234.478394) (xy 95.014028 -234.499492)
			(xy 95.054531 -234.527448) (xy 95.090024 -234.56154) (xy 95.119589 -234.600884) (xy 95.14246 -234.644461)
			(xy 95.158044 -234.691142) (xy 95.165939 -234.739719) (xy 95.166434 -234.764326) (xy 95.165939 -234.788933)
			(xy 95.158044 -234.83751) (xy 95.14246 -234.884191) (xy 95.119589 -234.927768) (xy 95.090024 -234.967112)
			(xy 95.054531 -235.001204) (xy 95.014028 -235.02916) (xy 94.969566 -235.050258) (xy 94.922295 -235.06395)
			(xy 94.87344 -235.069882) (xy 94.824265 -235.067901) (xy 94.776046 -235.058057) (xy 94.73003 -235.040605)
			(xy 94.687409 -235.015998) (xy 94.649288 -234.984873) (xy 94.616653 -234.948036) (xy 94.59035 -234.90644)
			(xy 94.571059 -234.861164) (xy 94.559282 -234.81338) (xy 94.555322 -234.764326) (xy 94.236794 -234.764326)
			(xy 94.236282 -234.789772) (xy 94.228118 -234.840006) (xy 94.212002 -234.88828) (xy 94.188351 -234.933343)
			(xy 94.157778 -234.974029) (xy 94.121074 -235.009284) (xy 94.07919 -235.038194) (xy 94.033211 -235.060011)
			(xy 93.984327 -235.074171) (xy 93.933806 -235.080305) (xy 93.882954 -235.078256) (xy 93.83309 -235.068076)
			(xy 93.785504 -235.050029) (xy 93.74143 -235.024583) (xy 93.702008 -234.992396) (xy 93.66826 -234.954302)
			(xy 93.641059 -234.911288) (xy 93.621111 -234.864468) (xy 93.608932 -234.815054) (xy 93.604837 -234.764326)
			(xy 93.286326 -234.764326) (xy 93.285831 -234.788933) (xy 93.277936 -234.83751) (xy 93.262352 -234.884191)
			(xy 93.239481 -234.927768) (xy 93.209916 -234.967112) (xy 93.174423 -235.001204) (xy 93.13392 -235.02916)
			(xy 93.089458 -235.050258) (xy 93.042187 -235.06395) (xy 92.993332 -235.069882) (xy 92.944157 -235.067901)
			(xy 92.895938 -235.058057) (xy 92.849922 -235.040605) (xy 92.807301 -235.015998) (xy 92.76918 -234.984873)
			(xy 92.736545 -234.948036) (xy 92.710242 -234.90644) (xy 92.690951 -234.861164) (xy 92.679174 -234.81338)
			(xy 92.675214 -234.764326) (xy 92.356686 -234.764326) (xy 92.356174 -234.789772) (xy 92.34801 -234.840006)
			(xy 92.331894 -234.88828) (xy 92.308243 -234.933343) (xy 92.27767 -234.974029) (xy 92.240966 -235.009284)
			(xy 92.199082 -235.038194) (xy 92.153103 -235.060011) (xy 92.104219 -235.074171) (xy 92.053698 -235.080305)
			(xy 92.002846 -235.078256) (xy 91.952982 -235.068076) (xy 91.905396 -235.050029) (xy 91.861322 -235.024583)
			(xy 91.8219 -234.992396) (xy 91.788152 -234.954302) (xy 91.760951 -234.911288) (xy 91.741003 -234.864468)
			(xy 91.728824 -234.815054) (xy 91.724729 -234.764326) (xy 91.416632 -234.764326) (xy 91.41612 -234.789772)
			(xy 91.407956 -234.840006) (xy 91.39184 -234.88828) (xy 91.368189 -234.933343) (xy 91.337616 -234.974029)
			(xy 91.300912 -235.009284) (xy 91.259028 -235.038194) (xy 91.213049 -235.060011) (xy 91.164165 -235.074171)
			(xy 91.113644 -235.080305) (xy 91.062792 -235.078256) (xy 91.012928 -235.068076) (xy 90.965342 -235.050029)
			(xy 90.921268 -235.024583) (xy 90.881846 -234.992396) (xy 90.848098 -234.954302) (xy 90.820897 -234.911288)
			(xy 90.800949 -234.864468) (xy 90.78877 -234.815054) (xy 90.784675 -234.764326) (xy 90.466418 -234.764326)
			(xy 90.465923 -234.788933) (xy 90.458028 -234.83751) (xy 90.442444 -234.884191) (xy 90.419573 -234.927768)
			(xy 90.390008 -234.967112) (xy 90.354515 -235.001204) (xy 90.314012 -235.02916) (xy 90.26955 -235.050258)
			(xy 90.222279 -235.06395) (xy 90.173424 -235.069882) (xy 90.124249 -235.067901) (xy 90.07603 -235.058057)
			(xy 90.030014 -235.040605) (xy 89.987393 -235.015998) (xy 89.949272 -234.984873) (xy 89.916637 -234.948036)
			(xy 89.890334 -234.90644) (xy 89.871043 -234.861164) (xy 89.859266 -234.81338) (xy 89.855306 -234.764326)
			(xy 89.526364 -234.764326) (xy 89.525869 -234.788933) (xy 89.517974 -234.83751) (xy 89.50239 -234.884191)
			(xy 89.479519 -234.927768) (xy 89.449954 -234.967112) (xy 89.414461 -235.001204) (xy 89.373958 -235.02916)
			(xy 89.329496 -235.050258) (xy 89.282225 -235.06395) (xy 89.23337 -235.069882) (xy 89.184195 -235.067901)
			(xy 89.135976 -235.058057) (xy 89.08996 -235.040605) (xy 89.047339 -235.015998) (xy 89.009218 -234.984873)
			(xy 88.976583 -234.948036) (xy 88.95028 -234.90644) (xy 88.930989 -234.861164) (xy 88.919212 -234.81338)
			(xy 88.915252 -234.764326) (xy 88.58631 -234.764326) (xy 88.585815 -234.788933) (xy 88.57792 -234.83751)
			(xy 88.562336 -234.884191) (xy 88.539465 -234.927768) (xy 88.5099 -234.967112) (xy 88.474407 -235.001204)
			(xy 88.433904 -235.02916) (xy 88.389442 -235.050258) (xy 88.342171 -235.06395) (xy 88.293316 -235.069882)
			(xy 88.244141 -235.067901) (xy 88.195922 -235.058057) (xy 88.149906 -235.040605) (xy 88.107285 -235.015998)
			(xy 88.069164 -234.984873) (xy 88.036529 -234.948036) (xy 88.010226 -234.90644) (xy 87.990935 -234.861164)
			(xy 87.979158 -234.81338) (xy 87.975198 -234.764326) (xy 87.646256 -234.764326) (xy 87.645761 -234.788933)
			(xy 87.637866 -234.83751) (xy 87.622282 -234.884191) (xy 87.599411 -234.927768) (xy 87.569846 -234.967112)
			(xy 87.534353 -235.001204) (xy 87.49385 -235.02916) (xy 87.449388 -235.050258) (xy 87.402117 -235.06395)
			(xy 87.353262 -235.069882) (xy 87.304087 -235.067901) (xy 87.255868 -235.058057) (xy 87.209852 -235.040605)
			(xy 87.167231 -235.015998) (xy 87.12911 -234.984873) (xy 87.096475 -234.948036) (xy 87.070172 -234.90644)
			(xy 87.050881 -234.861164) (xy 87.039104 -234.81338) (xy 87.035144 -234.764326) (xy 86.855554 -234.764326)
			(xy 86.855554 -234.959398) (xy 86.85657 -234.970066) (xy 86.859872 -234.985052) (xy 86.864444 -234.995466)
			(xy 86.866221 -235.000093) (xy 86.868148 -235.009815) (xy 86.868254 -235.01477) (xy 86.868254 -235.07573)
			(xy 86.868715 -235.085607) (xy 86.876156 -235.103907) (xy 86.882732 -235.11129) (xy 86.882986 -235.111544)
			(xy 87.178642 -235.4072) (xy 87.185354 -235.414439) (xy 87.192948 -235.432643) (xy 87.193374 -235.442506)
			(xy 87.193374 -235.574332) (xy 87.505298 -235.574332) (xy 87.509258 -235.525278) (xy 87.521035 -235.477494)
			(xy 87.540326 -235.432218) (xy 87.566629 -235.390622) (xy 87.599264 -235.353785) (xy 87.637385 -235.32266)
			(xy 87.680006 -235.298053) (xy 87.726022 -235.280601) (xy 87.774241 -235.270757) (xy 87.823416 -235.268776)
			(xy 87.872271 -235.274708) (xy 87.919542 -235.2884) (xy 87.964004 -235.309498) (xy 88.004507 -235.337454)
			(xy 88.04 -235.371546) (xy 88.069565 -235.41089) (xy 88.092436 -235.454467) (xy 88.10802 -235.501148)
			(xy 88.115915 -235.549725) (xy 88.11641 -235.574332) (xy 88.445352 -235.574332) (xy 88.449312 -235.525278)
			(xy 88.461089 -235.477494) (xy 88.48038 -235.432218) (xy 88.506683 -235.390622) (xy 88.539318 -235.353785)
			(xy 88.577439 -235.32266) (xy 88.62006 -235.298053) (xy 88.666076 -235.280601) (xy 88.714295 -235.270757)
			(xy 88.76347 -235.268776) (xy 88.812325 -235.274708) (xy 88.859596 -235.2884) (xy 88.904058 -235.309498)
			(xy 88.944561 -235.337454) (xy 88.980054 -235.371546) (xy 89.009619 -235.41089) (xy 89.03249 -235.454467)
			(xy 89.048074 -235.501148) (xy 89.055969 -235.549725) (xy 89.056464 -235.574332) (xy 89.385152 -235.574332)
			(xy 89.389112 -235.525278) (xy 89.400889 -235.477494) (xy 89.42018 -235.432218) (xy 89.446483 -235.390622)
			(xy 89.479118 -235.353785) (xy 89.517239 -235.32266) (xy 89.55986 -235.298053) (xy 89.605876 -235.280601)
			(xy 89.654095 -235.270757) (xy 89.70327 -235.268776) (xy 89.752125 -235.274708) (xy 89.799396 -235.2884)
			(xy 89.843858 -235.309498) (xy 89.884361 -235.337454) (xy 89.919854 -235.371546) (xy 89.949419 -235.41089)
			(xy 89.97229 -235.454467) (xy 89.987874 -235.501148) (xy 89.995769 -235.549725) (xy 89.996264 -235.574332)
			(xy 90.314775 -235.574332) (xy 90.31887 -235.523604) (xy 90.331049 -235.47419) (xy 90.350997 -235.42737)
			(xy 90.378198 -235.384356) (xy 90.411946 -235.346262) (xy 90.451368 -235.314075) (xy 90.495442 -235.288629)
			(xy 90.543028 -235.270582) (xy 90.592892 -235.260402) (xy 90.643744 -235.258353) (xy 90.694265 -235.264487)
			(xy 90.743149 -235.278647) (xy 90.789128 -235.300464) (xy 90.831012 -235.329374) (xy 90.867716 -235.364629)
			(xy 90.898289 -235.405315) (xy 90.92194 -235.450378) (xy 90.938056 -235.498652) (xy 90.94622 -235.548886)
			(xy 90.946732 -235.574332) (xy 91.26526 -235.574332) (xy 91.26922 -235.525278) (xy 91.280997 -235.477494)
			(xy 91.300288 -235.432218) (xy 91.326591 -235.390622) (xy 91.359226 -235.353785) (xy 91.397347 -235.32266)
			(xy 91.439968 -235.298053) (xy 91.485984 -235.280601) (xy 91.534203 -235.270757) (xy 91.583378 -235.268776)
			(xy 91.632233 -235.274708) (xy 91.679504 -235.2884) (xy 91.723966 -235.309498) (xy 91.764469 -235.337454)
			(xy 91.799962 -235.371546) (xy 91.829527 -235.41089) (xy 91.852398 -235.454467) (xy 91.867982 -235.501148)
			(xy 91.875877 -235.549725) (xy 91.876372 -235.574332) (xy 92.194883 -235.574332) (xy 92.198978 -235.523604)
			(xy 92.211157 -235.47419) (xy 92.231105 -235.42737) (xy 92.258306 -235.384356) (xy 92.292054 -235.346262)
			(xy 92.331476 -235.314075) (xy 92.37555 -235.288629) (xy 92.423136 -235.270582) (xy 92.473 -235.260402)
			(xy 92.523852 -235.258353) (xy 92.574373 -235.264487) (xy 92.623257 -235.278647) (xy 92.669236 -235.300464)
			(xy 92.71112 -235.329374) (xy 92.747824 -235.364629) (xy 92.778397 -235.405315) (xy 92.802048 -235.450378)
			(xy 92.818164 -235.498652) (xy 92.826328 -235.548886) (xy 92.82684 -235.574332) (xy 93.145114 -235.574332)
			(xy 93.149074 -235.525278) (xy 93.160851 -235.477494) (xy 93.180142 -235.432218) (xy 93.206445 -235.390622)
			(xy 93.23908 -235.353785) (xy 93.277201 -235.32266) (xy 93.319822 -235.298053) (xy 93.365838 -235.280601)
			(xy 93.414057 -235.270757) (xy 93.463232 -235.268776) (xy 93.512087 -235.274708) (xy 93.559358 -235.2884)
			(xy 93.60382 -235.309498) (xy 93.644323 -235.337454) (xy 93.679816 -235.371546) (xy 93.709381 -235.41089)
			(xy 93.732252 -235.454467) (xy 93.747836 -235.501148) (xy 93.755731 -235.549725) (xy 93.756226 -235.574332)
			(xy 94.074737 -235.574332) (xy 94.078832 -235.523604) (xy 94.091011 -235.47419) (xy 94.110959 -235.42737)
			(xy 94.13816 -235.384356) (xy 94.171908 -235.346262) (xy 94.21133 -235.314075) (xy 94.255404 -235.288629)
			(xy 94.30299 -235.270582) (xy 94.352854 -235.260402) (xy 94.403706 -235.258353) (xy 94.454227 -235.264487)
			(xy 94.503111 -235.278647) (xy 94.54909 -235.300464) (xy 94.590974 -235.329374) (xy 94.627678 -235.364629)
			(xy 94.658251 -235.405315) (xy 94.681902 -235.450378) (xy 94.698018 -235.498652) (xy 94.706182 -235.548886)
			(xy 94.706694 -235.574332) (xy 94.706182 -235.599778) (xy 94.698018 -235.650012) (xy 94.681902 -235.698286)
			(xy 94.658251 -235.743349) (xy 94.627678 -235.784035) (xy 94.590974 -235.81929) (xy 94.54909 -235.8482)
			(xy 94.503111 -235.870017) (xy 94.454227 -235.884177) (xy 94.403706 -235.890311) (xy 94.352854 -235.888262)
			(xy 94.30299 -235.878082) (xy 94.255404 -235.860035) (xy 94.21133 -235.834589) (xy 94.171908 -235.802402)
			(xy 94.13816 -235.764308) (xy 94.110959 -235.721294) (xy 94.091011 -235.674474) (xy 94.078832 -235.62506)
			(xy 94.074737 -235.574332) (xy 93.756226 -235.574332) (xy 93.755731 -235.598939) (xy 93.747836 -235.647516)
			(xy 93.732252 -235.694197) (xy 93.709381 -235.737774) (xy 93.679816 -235.777118) (xy 93.644323 -235.81121)
			(xy 93.60382 -235.839166) (xy 93.559358 -235.860264) (xy 93.512087 -235.873956) (xy 93.463232 -235.879888)
			(xy 93.414057 -235.877907) (xy 93.365838 -235.868063) (xy 93.319822 -235.850611) (xy 93.277201 -235.826004)
			(xy 93.23908 -235.794879) (xy 93.206445 -235.758042) (xy 93.180142 -235.716446) (xy 93.160851 -235.67117)
			(xy 93.149074 -235.623386) (xy 93.145114 -235.574332) (xy 92.82684 -235.574332) (xy 92.826328 -235.599778)
			(xy 92.818164 -235.650012) (xy 92.802048 -235.698286) (xy 92.778397 -235.743349) (xy 92.747824 -235.784035)
			(xy 92.71112 -235.81929) (xy 92.669236 -235.8482) (xy 92.623257 -235.870017) (xy 92.574373 -235.884177)
			(xy 92.523852 -235.890311) (xy 92.473 -235.888262) (xy 92.423136 -235.878082) (xy 92.37555 -235.860035)
			(xy 92.331476 -235.834589) (xy 92.292054 -235.802402) (xy 92.258306 -235.764308) (xy 92.231105 -235.721294)
			(xy 92.211157 -235.674474) (xy 92.198978 -235.62506) (xy 92.194883 -235.574332) (xy 91.876372 -235.574332)
			(xy 91.875877 -235.598939) (xy 91.867982 -235.647516) (xy 91.852398 -235.694197) (xy 91.829527 -235.737774)
			(xy 91.799962 -235.777118) (xy 91.764469 -235.81121) (xy 91.723966 -235.839166) (xy 91.679504 -235.860264)
			(xy 91.632233 -235.873956) (xy 91.583378 -235.879888) (xy 91.534203 -235.877907) (xy 91.485984 -235.868063)
			(xy 91.439968 -235.850611) (xy 91.397347 -235.826004) (xy 91.359226 -235.794879) (xy 91.326591 -235.758042)
			(xy 91.300288 -235.716446) (xy 91.280997 -235.67117) (xy 91.26922 -235.623386) (xy 91.26526 -235.574332)
			(xy 90.946732 -235.574332) (xy 90.94622 -235.599778) (xy 90.938056 -235.650012) (xy 90.92194 -235.698286)
			(xy 90.898289 -235.743349) (xy 90.867716 -235.784035) (xy 90.831012 -235.81929) (xy 90.789128 -235.8482)
			(xy 90.743149 -235.870017) (xy 90.694265 -235.884177) (xy 90.643744 -235.890311) (xy 90.592892 -235.888262)
			(xy 90.543028 -235.878082) (xy 90.495442 -235.860035) (xy 90.451368 -235.834589) (xy 90.411946 -235.802402)
			(xy 90.378198 -235.764308) (xy 90.350997 -235.721294) (xy 90.331049 -235.674474) (xy 90.31887 -235.62506)
			(xy 90.314775 -235.574332) (xy 89.996264 -235.574332) (xy 89.995769 -235.598939) (xy 89.987874 -235.647516)
			(xy 89.97229 -235.694197) (xy 89.949419 -235.737774) (xy 89.919854 -235.777118) (xy 89.884361 -235.81121)
			(xy 89.843858 -235.839166) (xy 89.799396 -235.860264) (xy 89.752125 -235.873956) (xy 89.70327 -235.879888)
			(xy 89.654095 -235.877907) (xy 89.605876 -235.868063) (xy 89.55986 -235.850611) (xy 89.517239 -235.826004)
			(xy 89.479118 -235.794879) (xy 89.446483 -235.758042) (xy 89.42018 -235.716446) (xy 89.400889 -235.67117)
			(xy 89.389112 -235.623386) (xy 89.385152 -235.574332) (xy 89.056464 -235.574332) (xy 89.055969 -235.598939)
			(xy 89.048074 -235.647516) (xy 89.03249 -235.694197) (xy 89.009619 -235.737774) (xy 88.980054 -235.777118)
			(xy 88.944561 -235.81121) (xy 88.904058 -235.839166) (xy 88.859596 -235.860264) (xy 88.812325 -235.873956)
			(xy 88.76347 -235.879888) (xy 88.714295 -235.877907) (xy 88.666076 -235.868063) (xy 88.62006 -235.850611)
			(xy 88.577439 -235.826004) (xy 88.539318 -235.794879) (xy 88.506683 -235.758042) (xy 88.48038 -235.716446)
			(xy 88.461089 -235.67117) (xy 88.449312 -235.623386) (xy 88.445352 -235.574332) (xy 88.11641 -235.574332)
			(xy 88.115915 -235.598939) (xy 88.10802 -235.647516) (xy 88.092436 -235.694197) (xy 88.069565 -235.737774)
			(xy 88.04 -235.777118) (xy 88.004507 -235.81121) (xy 87.964004 -235.839166) (xy 87.919542 -235.860264)
			(xy 87.872271 -235.873956) (xy 87.823416 -235.879888) (xy 87.774241 -235.877907) (xy 87.726022 -235.868063)
			(xy 87.680006 -235.850611) (xy 87.637385 -235.826004) (xy 87.599264 -235.794879) (xy 87.566629 -235.758042)
			(xy 87.540326 -235.716446) (xy 87.521035 -235.67117) (xy 87.509258 -235.623386) (xy 87.505298 -235.574332)
			(xy 87.193374 -235.574332) (xy 87.193374 -235.657898) (xy 87.192832 -235.667733) (xy 87.185235 -235.685884)
			(xy 87.178642 -235.693204) (xy 87.12073 -235.751116) (xy 87.114126 -235.759244) (xy 87.113618 -235.759752)
			(xy 87.11184 -235.762292) (xy 87.099421 -235.777626) (xy 87.071266 -235.805274) (xy 87.055706 -235.81741)
			(xy 87.05342 -235.819188) (xy 87.037418 -235.834682) (xy 87.037164 -235.834936) (xy 87.012526 -235.85932)
			(xy 87.00529 -235.866038) (xy 86.987085 -235.873645) (xy 86.97722 -235.874052) (xy 86.929468 -235.874052)
			(xy 86.924896 -235.874814) (xy 86.911548 -235.877068) (xy 86.884584 -235.879484) (xy 86.871048 -235.87964)
			(xy 86.86419 -235.87964) (xy 86.85403 -235.879386) (xy 86.83498 -235.887006) (xy 86.735666 -235.98632)
			(xy 86.728957 -235.99356) (xy 86.721369 -236.011764) (xy 86.720934 -236.021626) (xy 86.720934 -236.384338)
			(xy 87.035144 -236.384338) (xy 87.039104 -236.335284) (xy 87.050881 -236.2875) (xy 87.070172 -236.242224)
			(xy 87.096475 -236.200628) (xy 87.12911 -236.163791) (xy 87.167231 -236.132666) (xy 87.209852 -236.108059)
			(xy 87.255868 -236.090607) (xy 87.304087 -236.080763) (xy 87.353262 -236.078782) (xy 87.402117 -236.084714)
			(xy 87.449388 -236.098406) (xy 87.49385 -236.119504) (xy 87.534353 -236.14746) (xy 87.569846 -236.181552)
			(xy 87.599411 -236.220896) (xy 87.622282 -236.264473) (xy 87.637866 -236.311154) (xy 87.645761 -236.359731)
			(xy 87.646256 -236.384338) (xy 87.975198 -236.384338) (xy 87.979158 -236.335284) (xy 87.990935 -236.2875)
			(xy 88.010226 -236.242224) (xy 88.036529 -236.200628) (xy 88.069164 -236.163791) (xy 88.107285 -236.132666)
			(xy 88.149906 -236.108059) (xy 88.195922 -236.090607) (xy 88.244141 -236.080763) (xy 88.293316 -236.078782)
			(xy 88.342171 -236.084714) (xy 88.389442 -236.098406) (xy 88.433904 -236.119504) (xy 88.474407 -236.14746)
			(xy 88.5099 -236.181552) (xy 88.539465 -236.220896) (xy 88.562336 -236.264473) (xy 88.57792 -236.311154)
			(xy 88.585815 -236.359731) (xy 88.58631 -236.384338) (xy 88.915252 -236.384338) (xy 88.919212 -236.335284)
			(xy 88.930989 -236.2875) (xy 88.95028 -236.242224) (xy 88.976583 -236.200628) (xy 89.009218 -236.163791)
			(xy 89.047339 -236.132666) (xy 89.08996 -236.108059) (xy 89.135976 -236.090607) (xy 89.184195 -236.080763)
			(xy 89.23337 -236.078782) (xy 89.282225 -236.084714) (xy 89.329496 -236.098406) (xy 89.373958 -236.119504)
			(xy 89.414461 -236.14746) (xy 89.449954 -236.181552) (xy 89.479519 -236.220896) (xy 89.50239 -236.264473)
			(xy 89.517974 -236.311154) (xy 89.525869 -236.359731) (xy 89.526364 -236.384338) (xy 89.855306 -236.384338)
			(xy 89.859266 -236.335284) (xy 89.871043 -236.2875) (xy 89.890334 -236.242224) (xy 89.916637 -236.200628)
			(xy 89.949272 -236.163791) (xy 89.987393 -236.132666) (xy 90.030014 -236.108059) (xy 90.07603 -236.090607)
			(xy 90.124249 -236.080763) (xy 90.173424 -236.078782) (xy 90.222279 -236.084714) (xy 90.26955 -236.098406)
			(xy 90.314012 -236.119504) (xy 90.354515 -236.14746) (xy 90.390008 -236.181552) (xy 90.419573 -236.220896)
			(xy 90.442444 -236.264473) (xy 90.458028 -236.311154) (xy 90.465923 -236.359731) (xy 90.466418 -236.384338)
			(xy 90.784675 -236.384338) (xy 90.78877 -236.33361) (xy 90.800949 -236.284196) (xy 90.820897 -236.237376)
			(xy 90.848098 -236.194362) (xy 90.881846 -236.156268) (xy 90.921268 -236.124081) (xy 90.965342 -236.098635)
			(xy 91.012928 -236.080588) (xy 91.062792 -236.070408) (xy 91.113644 -236.068359) (xy 91.164165 -236.074493)
			(xy 91.213049 -236.088653) (xy 91.259028 -236.11047) (xy 91.300912 -236.13938) (xy 91.337616 -236.174635)
			(xy 91.368189 -236.215321) (xy 91.39184 -236.260384) (xy 91.407956 -236.308658) (xy 91.41612 -236.358892)
			(xy 91.416632 -236.384338) (xy 91.724729 -236.384338) (xy 91.728824 -236.33361) (xy 91.741003 -236.284196)
			(xy 91.760951 -236.237376) (xy 91.788152 -236.194362) (xy 91.8219 -236.156268) (xy 91.861322 -236.124081)
			(xy 91.905396 -236.098635) (xy 91.952982 -236.080588) (xy 92.002846 -236.070408) (xy 92.053698 -236.068359)
			(xy 92.104219 -236.074493) (xy 92.153103 -236.088653) (xy 92.199082 -236.11047) (xy 92.240966 -236.13938)
			(xy 92.27767 -236.174635) (xy 92.308243 -236.215321) (xy 92.331894 -236.260384) (xy 92.34801 -236.308658)
			(xy 92.356174 -236.358892) (xy 92.356686 -236.384338) (xy 92.675214 -236.384338) (xy 92.679174 -236.335284)
			(xy 92.690951 -236.2875) (xy 92.710242 -236.242224) (xy 92.736545 -236.200628) (xy 92.76918 -236.163791)
			(xy 92.807301 -236.132666) (xy 92.849922 -236.108059) (xy 92.895938 -236.090607) (xy 92.944157 -236.080763)
			(xy 92.993332 -236.078782) (xy 93.042187 -236.084714) (xy 93.089458 -236.098406) (xy 93.13392 -236.119504)
			(xy 93.174423 -236.14746) (xy 93.209916 -236.181552) (xy 93.239481 -236.220896) (xy 93.262352 -236.264473)
			(xy 93.277936 -236.311154) (xy 93.285831 -236.359731) (xy 93.286326 -236.384338) (xy 93.604837 -236.384338)
			(xy 93.608932 -236.33361) (xy 93.621111 -236.284196) (xy 93.641059 -236.237376) (xy 93.66826 -236.194362)
			(xy 93.702008 -236.156268) (xy 93.74143 -236.124081) (xy 93.785504 -236.098635) (xy 93.83309 -236.080588)
			(xy 93.882954 -236.070408) (xy 93.933806 -236.068359) (xy 93.984327 -236.074493) (xy 94.033211 -236.088653)
			(xy 94.07919 -236.11047) (xy 94.121074 -236.13938) (xy 94.157778 -236.174635) (xy 94.188351 -236.215321)
			(xy 94.212002 -236.260384) (xy 94.228118 -236.308658) (xy 94.236282 -236.358892) (xy 94.236794 -236.384338)
			(xy 94.555322 -236.384338) (xy 94.559282 -236.335284) (xy 94.571059 -236.2875) (xy 94.59035 -236.242224)
			(xy 94.616653 -236.200628) (xy 94.649288 -236.163791) (xy 94.687409 -236.132666) (xy 94.73003 -236.108059)
			(xy 94.776046 -236.090607) (xy 94.824265 -236.080763) (xy 94.87344 -236.078782) (xy 94.922295 -236.084714)
			(xy 94.969566 -236.098406) (xy 95.014028 -236.119504) (xy 95.054531 -236.14746) (xy 95.090024 -236.181552)
			(xy 95.119589 -236.220896) (xy 95.14246 -236.264473) (xy 95.158044 -236.311154) (xy 95.165939 -236.359731)
			(xy 95.166434 -236.384338) (xy 95.165939 -236.408945) (xy 95.158044 -236.457522) (xy 95.14246 -236.504203)
			(xy 95.119589 -236.54778) (xy 95.090024 -236.587124) (xy 95.054531 -236.621216) (xy 95.014028 -236.649172)
			(xy 94.969566 -236.67027) (xy 94.922295 -236.683962) (xy 94.87344 -236.689894) (xy 94.824265 -236.687913)
			(xy 94.776046 -236.678069) (xy 94.73003 -236.660617) (xy 94.687409 -236.63601) (xy 94.649288 -236.604885)
			(xy 94.616653 -236.568048) (xy 94.59035 -236.526452) (xy 94.571059 -236.481176) (xy 94.559282 -236.433392)
			(xy 94.555322 -236.384338) (xy 94.236794 -236.384338) (xy 94.236282 -236.409784) (xy 94.228118 -236.460018)
			(xy 94.212002 -236.508292) (xy 94.188351 -236.553355) (xy 94.157778 -236.594041) (xy 94.121074 -236.629296)
			(xy 94.07919 -236.658206) (xy 94.033211 -236.680023) (xy 93.984327 -236.694183) (xy 93.933806 -236.700317)
			(xy 93.882954 -236.698268) (xy 93.83309 -236.688088) (xy 93.785504 -236.670041) (xy 93.74143 -236.644595)
			(xy 93.702008 -236.612408) (xy 93.66826 -236.574314) (xy 93.641059 -236.5313) (xy 93.621111 -236.48448)
			(xy 93.608932 -236.435066) (xy 93.604837 -236.384338) (xy 93.286326 -236.384338) (xy 93.285831 -236.408945)
			(xy 93.277936 -236.457522) (xy 93.262352 -236.504203) (xy 93.239481 -236.54778) (xy 93.209916 -236.587124)
			(xy 93.174423 -236.621216) (xy 93.13392 -236.649172) (xy 93.089458 -236.67027) (xy 93.042187 -236.683962)
			(xy 92.993332 -236.689894) (xy 92.944157 -236.687913) (xy 92.895938 -236.678069) (xy 92.849922 -236.660617)
			(xy 92.807301 -236.63601) (xy 92.76918 -236.604885) (xy 92.736545 -236.568048) (xy 92.710242 -236.526452)
			(xy 92.690951 -236.481176) (xy 92.679174 -236.433392) (xy 92.675214 -236.384338) (xy 92.356686 -236.384338)
			(xy 92.356174 -236.409784) (xy 92.34801 -236.460018) (xy 92.331894 -236.508292) (xy 92.308243 -236.553355)
			(xy 92.27767 -236.594041) (xy 92.240966 -236.629296) (xy 92.199082 -236.658206) (xy 92.153103 -236.680023)
			(xy 92.104219 -236.694183) (xy 92.053698 -236.700317) (xy 92.002846 -236.698268) (xy 91.952982 -236.688088)
			(xy 91.905396 -236.670041) (xy 91.861322 -236.644595) (xy 91.8219 -236.612408) (xy 91.788152 -236.574314)
			(xy 91.760951 -236.5313) (xy 91.741003 -236.48448) (xy 91.728824 -236.435066) (xy 91.724729 -236.384338)
			(xy 91.416632 -236.384338) (xy 91.41612 -236.409784) (xy 91.407956 -236.460018) (xy 91.39184 -236.508292)
			(xy 91.368189 -236.553355) (xy 91.337616 -236.594041) (xy 91.300912 -236.629296) (xy 91.259028 -236.658206)
			(xy 91.213049 -236.680023) (xy 91.164165 -236.694183) (xy 91.113644 -236.700317) (xy 91.062792 -236.698268)
			(xy 91.012928 -236.688088) (xy 90.965342 -236.670041) (xy 90.921268 -236.644595) (xy 90.881846 -236.612408)
			(xy 90.848098 -236.574314) (xy 90.820897 -236.5313) (xy 90.800949 -236.48448) (xy 90.78877 -236.435066)
			(xy 90.784675 -236.384338) (xy 90.466418 -236.384338) (xy 90.465923 -236.408945) (xy 90.458028 -236.457522)
			(xy 90.442444 -236.504203) (xy 90.419573 -236.54778) (xy 90.390008 -236.587124) (xy 90.354515 -236.621216)
			(xy 90.314012 -236.649172) (xy 90.26955 -236.67027) (xy 90.222279 -236.683962) (xy 90.173424 -236.689894)
			(xy 90.124249 -236.687913) (xy 90.07603 -236.678069) (xy 90.030014 -236.660617) (xy 89.987393 -236.63601)
			(xy 89.949272 -236.604885) (xy 89.916637 -236.568048) (xy 89.890334 -236.526452) (xy 89.871043 -236.481176)
			(xy 89.859266 -236.433392) (xy 89.855306 -236.384338) (xy 89.526364 -236.384338) (xy 89.525869 -236.408945)
			(xy 89.517974 -236.457522) (xy 89.50239 -236.504203) (xy 89.479519 -236.54778) (xy 89.449954 -236.587124)
			(xy 89.414461 -236.621216) (xy 89.373958 -236.649172) (xy 89.329496 -236.67027) (xy 89.282225 -236.683962)
			(xy 89.23337 -236.689894) (xy 89.184195 -236.687913) (xy 89.135976 -236.678069) (xy 89.08996 -236.660617)
			(xy 89.047339 -236.63601) (xy 89.009218 -236.604885) (xy 88.976583 -236.568048) (xy 88.95028 -236.526452)
			(xy 88.930989 -236.481176) (xy 88.919212 -236.433392) (xy 88.915252 -236.384338) (xy 88.58631 -236.384338)
			(xy 88.585815 -236.408945) (xy 88.57792 -236.457522) (xy 88.562336 -236.504203) (xy 88.539465 -236.54778)
			(xy 88.5099 -236.587124) (xy 88.474407 -236.621216) (xy 88.433904 -236.649172) (xy 88.389442 -236.67027)
			(xy 88.342171 -236.683962) (xy 88.293316 -236.689894) (xy 88.244141 -236.687913) (xy 88.195922 -236.678069)
			(xy 88.149906 -236.660617) (xy 88.107285 -236.63601) (xy 88.069164 -236.604885) (xy 88.036529 -236.568048)
			(xy 88.010226 -236.526452) (xy 87.990935 -236.481176) (xy 87.979158 -236.433392) (xy 87.975198 -236.384338)
			(xy 87.646256 -236.384338) (xy 87.645761 -236.408945) (xy 87.637866 -236.457522) (xy 87.622282 -236.504203)
			(xy 87.599411 -236.54778) (xy 87.569846 -236.587124) (xy 87.534353 -236.621216) (xy 87.49385 -236.649172)
			(xy 87.449388 -236.67027) (xy 87.402117 -236.683962) (xy 87.353262 -236.689894) (xy 87.304087 -236.687913)
			(xy 87.255868 -236.678069) (xy 87.209852 -236.660617) (xy 87.167231 -236.63601) (xy 87.12911 -236.604885)
			(xy 87.096475 -236.568048) (xy 87.070172 -236.526452) (xy 87.050881 -236.481176) (xy 87.039104 -236.433392)
			(xy 87.035144 -236.384338) (xy 86.720934 -236.384338) (xy 86.720934 -236.47019) (xy 86.721405 -236.480063)
			(xy 86.72886 -236.498349) (xy 86.735412 -236.50575) (xy 86.735666 -236.506004) (xy 87.265002 -237.03534)
			(xy 87.271712 -237.042579) (xy 87.279297 -237.060784) (xy 87.279734 -237.070646) (xy 87.279734 -237.194344)
			(xy 87.505298 -237.194344) (xy 87.509258 -237.14529) (xy 87.521035 -237.097506) (xy 87.540326 -237.05223)
			(xy 87.566629 -237.010634) (xy 87.599264 -236.973797) (xy 87.637385 -236.942672) (xy 87.680006 -236.918065)
			(xy 87.726022 -236.900613) (xy 87.774241 -236.890769) (xy 87.823416 -236.888788) (xy 87.872271 -236.89472)
			(xy 87.919542 -236.908412) (xy 87.964004 -236.92951) (xy 88.004507 -236.957466) (xy 88.04 -236.991558)
			(xy 88.069565 -237.030902) (xy 88.092436 -237.074479) (xy 88.10802 -237.12116) (xy 88.115915 -237.169737)
			(xy 88.11641 -237.194344) (xy 88.445352 -237.194344) (xy 88.449312 -237.14529) (xy 88.461089 -237.097506)
			(xy 88.48038 -237.05223) (xy 88.506683 -237.010634) (xy 88.539318 -236.973797) (xy 88.577439 -236.942672)
			(xy 88.62006 -236.918065) (xy 88.666076 -236.900613) (xy 88.714295 -236.890769) (xy 88.76347 -236.888788)
			(xy 88.812325 -236.89472) (xy 88.859596 -236.908412) (xy 88.904058 -236.92951) (xy 88.944561 -236.957466)
			(xy 88.980054 -236.991558) (xy 89.009619 -237.030902) (xy 89.03249 -237.074479) (xy 89.048074 -237.12116)
			(xy 89.055969 -237.169737) (xy 89.056464 -237.194344) (xy 89.385152 -237.194344) (xy 89.389112 -237.14529)
			(xy 89.400889 -237.097506) (xy 89.42018 -237.05223) (xy 89.446483 -237.010634) (xy 89.479118 -236.973797)
			(xy 89.517239 -236.942672) (xy 89.55986 -236.918065) (xy 89.605876 -236.900613) (xy 89.654095 -236.890769)
			(xy 89.70327 -236.888788) (xy 89.752125 -236.89472) (xy 89.799396 -236.908412) (xy 89.843858 -236.92951)
			(xy 89.884361 -236.957466) (xy 89.919854 -236.991558) (xy 89.949419 -237.030902) (xy 89.97229 -237.074479)
			(xy 89.987874 -237.12116) (xy 89.995769 -237.169737) (xy 89.996264 -237.194344) (xy 90.314775 -237.194344)
			(xy 90.31887 -237.143616) (xy 90.331049 -237.094202) (xy 90.350997 -237.047382) (xy 90.378198 -237.004368)
			(xy 90.411946 -236.966274) (xy 90.451368 -236.934087) (xy 90.495442 -236.908641) (xy 90.543028 -236.890594)
			(xy 90.592892 -236.880414) (xy 90.643744 -236.878365) (xy 90.694265 -236.884499) (xy 90.743149 -236.898659)
			(xy 90.789128 -236.920476) (xy 90.831012 -236.949386) (xy 90.867716 -236.984641) (xy 90.898289 -237.025327)
			(xy 90.92194 -237.07039) (xy 90.938056 -237.118664) (xy 90.94622 -237.168898) (xy 90.946732 -237.194344)
			(xy 91.26526 -237.194344) (xy 91.26922 -237.14529) (xy 91.280997 -237.097506) (xy 91.300288 -237.05223)
			(xy 91.326591 -237.010634) (xy 91.359226 -236.973797) (xy 91.397347 -236.942672) (xy 91.439968 -236.918065)
			(xy 91.485984 -236.900613) (xy 91.534203 -236.890769) (xy 91.583378 -236.888788) (xy 91.632233 -236.89472)
			(xy 91.679504 -236.908412) (xy 91.723966 -236.92951) (xy 91.764469 -236.957466) (xy 91.799962 -236.991558)
			(xy 91.829527 -237.030902) (xy 91.852398 -237.074479) (xy 91.867982 -237.12116) (xy 91.875877 -237.169737)
			(xy 91.876372 -237.194344) (xy 92.194883 -237.194344) (xy 92.198978 -237.143616) (xy 92.211157 -237.094202)
			(xy 92.231105 -237.047382) (xy 92.258306 -237.004368) (xy 92.292054 -236.966274) (xy 92.331476 -236.934087)
			(xy 92.37555 -236.908641) (xy 92.423136 -236.890594) (xy 92.473 -236.880414) (xy 92.523852 -236.878365)
			(xy 92.574373 -236.884499) (xy 92.623257 -236.898659) (xy 92.669236 -236.920476) (xy 92.71112 -236.949386)
			(xy 92.747824 -236.984641) (xy 92.778397 -237.025327) (xy 92.802048 -237.07039) (xy 92.818164 -237.118664)
			(xy 92.826328 -237.168898) (xy 92.82684 -237.194344) (xy 93.145114 -237.194344) (xy 93.149074 -237.14529)
			(xy 93.160851 -237.097506) (xy 93.180142 -237.05223) (xy 93.206445 -237.010634) (xy 93.23908 -236.973797)
			(xy 93.277201 -236.942672) (xy 93.319822 -236.918065) (xy 93.365838 -236.900613) (xy 93.414057 -236.890769)
			(xy 93.463232 -236.888788) (xy 93.512087 -236.89472) (xy 93.559358 -236.908412) (xy 93.60382 -236.92951)
			(xy 93.644323 -236.957466) (xy 93.679816 -236.991558) (xy 93.709381 -237.030902) (xy 93.732252 -237.074479)
			(xy 93.747836 -237.12116) (xy 93.755731 -237.169737) (xy 93.756226 -237.194344) (xy 94.074737 -237.194344)
			(xy 94.078832 -237.143616) (xy 94.091011 -237.094202) (xy 94.110959 -237.047382) (xy 94.13816 -237.004368)
			(xy 94.171908 -236.966274) (xy 94.21133 -236.934087) (xy 94.255404 -236.908641) (xy 94.30299 -236.890594)
			(xy 94.352854 -236.880414) (xy 94.403706 -236.878365) (xy 94.454227 -236.884499) (xy 94.503111 -236.898659)
			(xy 94.54909 -236.920476) (xy 94.590974 -236.949386) (xy 94.627678 -236.984641) (xy 94.658251 -237.025327)
			(xy 94.681902 -237.07039) (xy 94.698018 -237.118664) (xy 94.706182 -237.168898) (xy 94.706694 -237.194344)
			(xy 94.706182 -237.21979) (xy 94.698018 -237.270024) (xy 94.681902 -237.318298) (xy 94.658251 -237.363361)
			(xy 94.627678 -237.404047) (xy 94.590974 -237.439302) (xy 94.54909 -237.468212) (xy 94.503111 -237.490029)
			(xy 94.454227 -237.504189) (xy 94.403706 -237.510323) (xy 94.352854 -237.508274) (xy 94.30299 -237.498094)
			(xy 94.255404 -237.480047) (xy 94.21133 -237.454601) (xy 94.171908 -237.422414) (xy 94.13816 -237.38432)
			(xy 94.110959 -237.341306) (xy 94.091011 -237.294486) (xy 94.078832 -237.245072) (xy 94.074737 -237.194344)
			(xy 93.756226 -237.194344) (xy 93.755731 -237.218951) (xy 93.747836 -237.267528) (xy 93.732252 -237.314209)
			(xy 93.709381 -237.357786) (xy 93.679816 -237.39713) (xy 93.644323 -237.431222) (xy 93.60382 -237.459178)
			(xy 93.559358 -237.480276) (xy 93.512087 -237.493968) (xy 93.463232 -237.4999) (xy 93.414057 -237.497919)
			(xy 93.365838 -237.488075) (xy 93.319822 -237.470623) (xy 93.277201 -237.446016) (xy 93.23908 -237.414891)
			(xy 93.206445 -237.378054) (xy 93.180142 -237.336458) (xy 93.160851 -237.291182) (xy 93.149074 -237.243398)
			(xy 93.145114 -237.194344) (xy 92.82684 -237.194344) (xy 92.826328 -237.21979) (xy 92.818164 -237.270024)
			(xy 92.802048 -237.318298) (xy 92.778397 -237.363361) (xy 92.747824 -237.404047) (xy 92.71112 -237.439302)
			(xy 92.669236 -237.468212) (xy 92.623257 -237.490029) (xy 92.574373 -237.504189) (xy 92.523852 -237.510323)
			(xy 92.473 -237.508274) (xy 92.423136 -237.498094) (xy 92.37555 -237.480047) (xy 92.331476 -237.454601)
			(xy 92.292054 -237.422414) (xy 92.258306 -237.38432) (xy 92.231105 -237.341306) (xy 92.211157 -237.294486)
			(xy 92.198978 -237.245072) (xy 92.194883 -237.194344) (xy 91.876372 -237.194344) (xy 91.875877 -237.218951)
			(xy 91.867982 -237.267528) (xy 91.852398 -237.314209) (xy 91.829527 -237.357786) (xy 91.799962 -237.39713)
			(xy 91.764469 -237.431222) (xy 91.723966 -237.459178) (xy 91.679504 -237.480276) (xy 91.632233 -237.493968)
			(xy 91.583378 -237.4999) (xy 91.534203 -237.497919) (xy 91.485984 -237.488075) (xy 91.439968 -237.470623)
			(xy 91.397347 -237.446016) (xy 91.359226 -237.414891) (xy 91.326591 -237.378054) (xy 91.300288 -237.336458)
			(xy 91.280997 -237.291182) (xy 91.26922 -237.243398) (xy 91.26526 -237.194344) (xy 90.946732 -237.194344)
			(xy 90.94622 -237.21979) (xy 90.938056 -237.270024) (xy 90.92194 -237.318298) (xy 90.898289 -237.363361)
			(xy 90.867716 -237.404047) (xy 90.831012 -237.439302) (xy 90.789128 -237.468212) (xy 90.743149 -237.490029)
			(xy 90.694265 -237.504189) (xy 90.643744 -237.510323) (xy 90.592892 -237.508274) (xy 90.543028 -237.498094)
			(xy 90.495442 -237.480047) (xy 90.451368 -237.454601) (xy 90.411946 -237.422414) (xy 90.378198 -237.38432)
			(xy 90.350997 -237.341306) (xy 90.331049 -237.294486) (xy 90.31887 -237.245072) (xy 90.314775 -237.194344)
			(xy 89.996264 -237.194344) (xy 89.995769 -237.218951) (xy 89.987874 -237.267528) (xy 89.97229 -237.314209)
			(xy 89.949419 -237.357786) (xy 89.919854 -237.39713) (xy 89.884361 -237.431222) (xy 89.843858 -237.459178)
			(xy 89.799396 -237.480276) (xy 89.752125 -237.493968) (xy 89.70327 -237.4999) (xy 89.654095 -237.497919)
			(xy 89.605876 -237.488075) (xy 89.55986 -237.470623) (xy 89.517239 -237.446016) (xy 89.479118 -237.414891)
			(xy 89.446483 -237.378054) (xy 89.42018 -237.336458) (xy 89.400889 -237.291182) (xy 89.389112 -237.243398)
			(xy 89.385152 -237.194344) (xy 89.056464 -237.194344) (xy 89.055969 -237.218951) (xy 89.048074 -237.267528)
			(xy 89.03249 -237.314209) (xy 89.009619 -237.357786) (xy 88.980054 -237.39713) (xy 88.944561 -237.431222)
			(xy 88.904058 -237.459178) (xy 88.859596 -237.480276) (xy 88.812325 -237.493968) (xy 88.76347 -237.4999)
			(xy 88.714295 -237.497919) (xy 88.666076 -237.488075) (xy 88.62006 -237.470623) (xy 88.577439 -237.446016)
			(xy 88.539318 -237.414891) (xy 88.506683 -237.378054) (xy 88.48038 -237.336458) (xy 88.461089 -237.291182)
			(xy 88.449312 -237.243398) (xy 88.445352 -237.194344) (xy 88.11641 -237.194344) (xy 88.115915 -237.218951)
			(xy 88.10802 -237.267528) (xy 88.092436 -237.314209) (xy 88.069565 -237.357786) (xy 88.04 -237.39713)
			(xy 88.004507 -237.431222) (xy 87.964004 -237.459178) (xy 87.919542 -237.480276) (xy 87.872271 -237.493968)
			(xy 87.823416 -237.4999) (xy 87.774241 -237.497919) (xy 87.726022 -237.488075) (xy 87.680006 -237.470623)
			(xy 87.637385 -237.446016) (xy 87.599264 -237.414891) (xy 87.566629 -237.378054) (xy 87.540326 -237.336458)
			(xy 87.521035 -237.291182) (xy 87.509258 -237.243398) (xy 87.505298 -237.194344) (xy 87.279734 -237.194344)
			(xy 87.279734 -237.326678) (xy 87.279197 -237.336516) (xy 87.271612 -237.354678) (xy 87.265002 -237.361984)
			(xy 87.012526 -237.61446) (xy 87.005288 -237.621174) (xy 86.987083 -237.628774) (xy 86.97722 -237.629192)
			(xy 86.840568 -237.629192) (xy 86.830727 -237.629721) (xy 86.812555 -237.637297) (xy 86.805262 -237.643924)
			(xy 86.715346 -237.73384) (xy 86.708642 -237.741082) (xy 86.701065 -237.759286) (xy 86.700614 -237.769146)
			(xy 86.700614 -237.94339) (xy 86.701376 -237.948216) (xy 86.701376 -237.949486) (xy 86.70372 -237.963082)
			(xy 86.70626 -237.990555) (xy 86.706456 -238.00435) (xy 87.035144 -238.00435) (xy 87.039104 -237.955296)
			(xy 87.050881 -237.907512) (xy 87.070172 -237.862236) (xy 87.096475 -237.82064) (xy 87.12911 -237.783803)
			(xy 87.167231 -237.752678) (xy 87.209852 -237.728071) (xy 87.255868 -237.710619) (xy 87.304087 -237.700775)
			(xy 87.353262 -237.698794) (xy 87.402117 -237.704726) (xy 87.449388 -237.718418) (xy 87.49385 -237.739516)
			(xy 87.534353 -237.767472) (xy 87.569846 -237.801564) (xy 87.599411 -237.840908) (xy 87.622282 -237.884485)
			(xy 87.637866 -237.931166) (xy 87.645761 -237.979743) (xy 87.646256 -238.00435) (xy 87.975198 -238.00435)
			(xy 87.979158 -237.955296) (xy 87.990935 -237.907512) (xy 88.010226 -237.862236) (xy 88.036529 -237.82064)
			(xy 88.069164 -237.783803) (xy 88.107285 -237.752678) (xy 88.149906 -237.728071) (xy 88.195922 -237.710619)
			(xy 88.244141 -237.700775) (xy 88.293316 -237.698794) (xy 88.342171 -237.704726) (xy 88.389442 -237.718418)
			(xy 88.433904 -237.739516) (xy 88.474407 -237.767472) (xy 88.5099 -237.801564) (xy 88.539465 -237.840908)
			(xy 88.562336 -237.884485) (xy 88.57792 -237.931166) (xy 88.585815 -237.979743) (xy 88.58631 -238.00435)
			(xy 88.915252 -238.00435) (xy 88.919212 -237.955296) (xy 88.930989 -237.907512) (xy 88.95028 -237.862236)
			(xy 88.976583 -237.82064) (xy 89.009218 -237.783803) (xy 89.047339 -237.752678) (xy 89.08996 -237.728071)
			(xy 89.135976 -237.710619) (xy 89.184195 -237.700775) (xy 89.23337 -237.698794) (xy 89.282225 -237.704726)
			(xy 89.329496 -237.718418) (xy 89.373958 -237.739516) (xy 89.414461 -237.767472) (xy 89.449954 -237.801564)
			(xy 89.479519 -237.840908) (xy 89.50239 -237.884485) (xy 89.517974 -237.931166) (xy 89.525869 -237.979743)
			(xy 89.526364 -238.00435) (xy 89.855306 -238.00435) (xy 89.859266 -237.955296) (xy 89.871043 -237.907512)
			(xy 89.890334 -237.862236) (xy 89.916637 -237.82064) (xy 89.949272 -237.783803) (xy 89.987393 -237.752678)
			(xy 90.030014 -237.728071) (xy 90.07603 -237.710619) (xy 90.124249 -237.700775) (xy 90.173424 -237.698794)
			(xy 90.222279 -237.704726) (xy 90.26955 -237.718418) (xy 90.314012 -237.739516) (xy 90.354515 -237.767472)
			(xy 90.390008 -237.801564) (xy 90.419573 -237.840908) (xy 90.442444 -237.884485) (xy 90.458028 -237.931166)
			(xy 90.465923 -237.979743) (xy 90.466418 -238.00435) (xy 90.784675 -238.00435) (xy 90.78877 -237.953622)
			(xy 90.800949 -237.904208) (xy 90.820897 -237.857388) (xy 90.848098 -237.814374) (xy 90.881846 -237.77628)
			(xy 90.921268 -237.744093) (xy 90.965342 -237.718647) (xy 91.012928 -237.7006) (xy 91.062792 -237.69042)
			(xy 91.113644 -237.688371) (xy 91.164165 -237.694505) (xy 91.213049 -237.708665) (xy 91.259028 -237.730482)
			(xy 91.300912 -237.759392) (xy 91.337616 -237.794647) (xy 91.368189 -237.835333) (xy 91.39184 -237.880396)
			(xy 91.407956 -237.92867) (xy 91.41612 -237.978904) (xy 91.416632 -238.00435) (xy 91.724729 -238.00435)
			(xy 91.728824 -237.953622) (xy 91.741003 -237.904208) (xy 91.760951 -237.857388) (xy 91.788152 -237.814374)
			(xy 91.8219 -237.77628) (xy 91.861322 -237.744093) (xy 91.905396 -237.718647) (xy 91.952982 -237.7006)
			(xy 92.002846 -237.69042) (xy 92.053698 -237.688371) (xy 92.104219 -237.694505) (xy 92.153103 -237.708665)
			(xy 92.199082 -237.730482) (xy 92.240966 -237.759392) (xy 92.27767 -237.794647) (xy 92.308243 -237.835333)
			(xy 92.331894 -237.880396) (xy 92.34801 -237.92867) (xy 92.356174 -237.978904) (xy 92.356686 -238.00435)
			(xy 92.675214 -238.00435) (xy 92.679174 -237.955296) (xy 92.690951 -237.907512) (xy 92.710242 -237.862236)
			(xy 92.736545 -237.82064) (xy 92.76918 -237.783803) (xy 92.807301 -237.752678) (xy 92.849922 -237.728071)
			(xy 92.895938 -237.710619) (xy 92.944157 -237.700775) (xy 92.993332 -237.698794) (xy 93.042187 -237.704726)
			(xy 93.089458 -237.718418) (xy 93.13392 -237.739516) (xy 93.174423 -237.767472) (xy 93.209916 -237.801564)
			(xy 93.239481 -237.840908) (xy 93.262352 -237.884485) (xy 93.277936 -237.931166) (xy 93.285831 -237.979743)
			(xy 93.286326 -238.00435) (xy 93.604837 -238.00435) (xy 93.608932 -237.953622) (xy 93.621111 -237.904208)
			(xy 93.641059 -237.857388) (xy 93.66826 -237.814374) (xy 93.702008 -237.77628) (xy 93.74143 -237.744093)
			(xy 93.785504 -237.718647) (xy 93.83309 -237.7006) (xy 93.882954 -237.69042) (xy 93.933806 -237.688371)
			(xy 93.984327 -237.694505) (xy 94.033211 -237.708665) (xy 94.07919 -237.730482) (xy 94.121074 -237.759392)
			(xy 94.157778 -237.794647) (xy 94.188351 -237.835333) (xy 94.212002 -237.880396) (xy 94.228118 -237.92867)
			(xy 94.236282 -237.978904) (xy 94.236794 -238.00435) (xy 94.555322 -238.00435) (xy 94.559282 -237.955296)
			(xy 94.571059 -237.907512) (xy 94.59035 -237.862236) (xy 94.616653 -237.82064) (xy 94.649288 -237.783803)
			(xy 94.687409 -237.752678) (xy 94.73003 -237.728071) (xy 94.776046 -237.710619) (xy 94.824265 -237.700775)
			(xy 94.87344 -237.698794) (xy 94.922295 -237.704726) (xy 94.969566 -237.718418) (xy 95.014028 -237.739516)
			(xy 95.054531 -237.767472) (xy 95.090024 -237.801564) (xy 95.119589 -237.840908) (xy 95.14246 -237.884485)
			(xy 95.158044 -237.931166) (xy 95.165939 -237.979743) (xy 95.166434 -238.00435) (xy 95.165939 -238.028957)
			(xy 95.158044 -238.077534) (xy 95.14246 -238.124215) (xy 95.119589 -238.167792) (xy 95.090024 -238.207136)
			(xy 95.054531 -238.241228) (xy 95.014028 -238.269184) (xy 94.969566 -238.290282) (xy 94.922295 -238.303974)
			(xy 94.87344 -238.309906) (xy 94.824265 -238.307925) (xy 94.776046 -238.298081) (xy 94.73003 -238.280629)
			(xy 94.687409 -238.256022) (xy 94.649288 -238.224897) (xy 94.616653 -238.18806) (xy 94.59035 -238.146464)
			(xy 94.571059 -238.101188) (xy 94.559282 -238.053404) (xy 94.555322 -238.00435) (xy 94.236794 -238.00435)
			(xy 94.236282 -238.029796) (xy 94.228118 -238.08003) (xy 94.212002 -238.128304) (xy 94.188351 -238.173367)
			(xy 94.157778 -238.214053) (xy 94.121074 -238.249308) (xy 94.07919 -238.278218) (xy 94.033211 -238.300035)
			(xy 93.984327 -238.314195) (xy 93.933806 -238.320329) (xy 93.882954 -238.31828) (xy 93.83309 -238.3081)
			(xy 93.785504 -238.290053) (xy 93.74143 -238.264607) (xy 93.702008 -238.23242) (xy 93.66826 -238.194326)
			(xy 93.641059 -238.151312) (xy 93.621111 -238.104492) (xy 93.608932 -238.055078) (xy 93.604837 -238.00435)
			(xy 93.286326 -238.00435) (xy 93.285831 -238.028957) (xy 93.277936 -238.077534) (xy 93.262352 -238.124215)
			(xy 93.239481 -238.167792) (xy 93.209916 -238.207136) (xy 93.174423 -238.241228) (xy 93.13392 -238.269184)
			(xy 93.089458 -238.290282) (xy 93.042187 -238.303974) (xy 92.993332 -238.309906) (xy 92.944157 -238.307925)
			(xy 92.895938 -238.298081) (xy 92.849922 -238.280629) (xy 92.807301 -238.256022) (xy 92.76918 -238.224897)
			(xy 92.736545 -238.18806) (xy 92.710242 -238.146464) (xy 92.690951 -238.101188) (xy 92.679174 -238.053404)
			(xy 92.675214 -238.00435) (xy 92.356686 -238.00435) (xy 92.356174 -238.029796) (xy 92.34801 -238.08003)
			(xy 92.331894 -238.128304) (xy 92.308243 -238.173367) (xy 92.27767 -238.214053) (xy 92.240966 -238.249308)
			(xy 92.199082 -238.278218) (xy 92.153103 -238.300035) (xy 92.104219 -238.314195) (xy 92.053698 -238.320329)
			(xy 92.002846 -238.31828) (xy 91.952982 -238.3081) (xy 91.905396 -238.290053) (xy 91.861322 -238.264607)
			(xy 91.8219 -238.23242) (xy 91.788152 -238.194326) (xy 91.760951 -238.151312) (xy 91.741003 -238.104492)
			(xy 91.728824 -238.055078) (xy 91.724729 -238.00435) (xy 91.416632 -238.00435) (xy 91.41612 -238.029796)
			(xy 91.407956 -238.08003) (xy 91.39184 -238.128304) (xy 91.368189 -238.173367) (xy 91.337616 -238.214053)
			(xy 91.300912 -238.249308) (xy 91.259028 -238.278218) (xy 91.213049 -238.300035) (xy 91.164165 -238.314195)
			(xy 91.113644 -238.320329) (xy 91.062792 -238.31828) (xy 91.012928 -238.3081) (xy 90.965342 -238.290053)
			(xy 90.921268 -238.264607) (xy 90.881846 -238.23242) (xy 90.848098 -238.194326) (xy 90.820897 -238.151312)
			(xy 90.800949 -238.104492) (xy 90.78877 -238.055078) (xy 90.784675 -238.00435) (xy 90.466418 -238.00435)
			(xy 90.465923 -238.028957) (xy 90.458028 -238.077534) (xy 90.442444 -238.124215) (xy 90.419573 -238.167792)
			(xy 90.390008 -238.207136) (xy 90.354515 -238.241228) (xy 90.314012 -238.269184) (xy 90.26955 -238.290282)
			(xy 90.222279 -238.303974) (xy 90.173424 -238.309906) (xy 90.124249 -238.307925) (xy 90.07603 -238.298081)
			(xy 90.030014 -238.280629) (xy 89.987393 -238.256022) (xy 89.949272 -238.224897) (xy 89.916637 -238.18806)
			(xy 89.890334 -238.146464) (xy 89.871043 -238.101188) (xy 89.859266 -238.053404) (xy 89.855306 -238.00435)
			(xy 89.526364 -238.00435) (xy 89.525869 -238.028957) (xy 89.517974 -238.077534) (xy 89.50239 -238.124215)
			(xy 89.479519 -238.167792) (xy 89.449954 -238.207136) (xy 89.414461 -238.241228) (xy 89.373958 -238.269184)
			(xy 89.329496 -238.290282) (xy 89.282225 -238.303974) (xy 89.23337 -238.309906) (xy 89.184195 -238.307925)
			(xy 89.135976 -238.298081) (xy 89.08996 -238.280629) (xy 89.047339 -238.256022) (xy 89.009218 -238.224897)
			(xy 88.976583 -238.18806) (xy 88.95028 -238.146464) (xy 88.930989 -238.101188) (xy 88.919212 -238.053404)
			(xy 88.915252 -238.00435) (xy 88.58631 -238.00435) (xy 88.585815 -238.028957) (xy 88.57792 -238.077534)
			(xy 88.562336 -238.124215) (xy 88.539465 -238.167792) (xy 88.5099 -238.207136) (xy 88.474407 -238.241228)
			(xy 88.433904 -238.269184) (xy 88.389442 -238.290282) (xy 88.342171 -238.303974) (xy 88.293316 -238.309906)
			(xy 88.244141 -238.307925) (xy 88.195922 -238.298081) (xy 88.149906 -238.280629) (xy 88.107285 -238.256022)
			(xy 88.069164 -238.224897) (xy 88.036529 -238.18806) (xy 88.010226 -238.146464) (xy 87.990935 -238.101188)
			(xy 87.979158 -238.053404) (xy 87.975198 -238.00435) (xy 87.646256 -238.00435) (xy 87.645761 -238.028957)
			(xy 87.637866 -238.077534) (xy 87.622282 -238.124215) (xy 87.599411 -238.167792) (xy 87.569846 -238.207136)
			(xy 87.534353 -238.241228) (xy 87.49385 -238.269184) (xy 87.449388 -238.290282) (xy 87.402117 -238.303974)
			(xy 87.353262 -238.309906) (xy 87.304087 -238.307925) (xy 87.255868 -238.298081) (xy 87.209852 -238.280629)
			(xy 87.167231 -238.256022) (xy 87.12911 -238.224897) (xy 87.096475 -238.18806) (xy 87.070172 -238.146464)
			(xy 87.050881 -238.101188) (xy 87.039104 -238.053404) (xy 87.035144 -238.00435) (xy 86.706456 -238.00435)
			(xy 86.706456 -238.009938) (xy 86.706202 -238.021114) (xy 86.704932 -238.03483) (xy 86.704932 -238.035592)
			(xy 86.701376 -238.059468) (xy 86.700614 -238.06404) (xy 86.700614 -238.33709) (xy 86.701087 -238.346961)
			(xy 86.70855 -238.36524) (xy 86.715092 -238.37265) (xy 86.715346 -238.372904) (xy 86.805008 -238.462566)
			(xy 86.805516 -238.463074) (xy 86.812896 -238.46966) (xy 86.831195 -238.47712) (xy 86.841076 -238.477552)
			(xy 87.00516 -238.477552) (xy 87.014999 -238.478085) (xy 87.033167 -238.485664) (xy 87.040466 -238.492284)
			(xy 87.158322 -238.61014) (xy 87.16503 -238.61738) (xy 87.172612 -238.635585) (xy 87.173054 -238.645446)
			(xy 87.173054 -238.769398) (xy 87.173562 -238.772954) (xy 87.174874 -238.783254) (xy 87.176273 -238.803973)
			(xy 87.176356 -238.814356) (xy 87.505298 -238.814356) (xy 87.509258 -238.765302) (xy 87.521035 -238.717518)
			(xy 87.540326 -238.672242) (xy 87.566629 -238.630646) (xy 87.599264 -238.593809) (xy 87.637385 -238.562684)
			(xy 87.680006 -238.538077) (xy 87.726022 -238.520625) (xy 87.774241 -238.510781) (xy 87.823416 -238.5088)
			(xy 87.872271 -238.514732) (xy 87.919542 -238.528424) (xy 87.964004 -238.549522) (xy 88.004507 -238.577478)
			(xy 88.04 -238.61157) (xy 88.069565 -238.650914) (xy 88.092436 -238.694491) (xy 88.10802 -238.741172)
			(xy 88.115915 -238.789749) (xy 88.11641 -238.814356) (xy 88.445352 -238.814356) (xy 88.449312 -238.765302)
			(xy 88.461089 -238.717518) (xy 88.48038 -238.672242) (xy 88.506683 -238.630646) (xy 88.539318 -238.593809)
			(xy 88.577439 -238.562684) (xy 88.62006 -238.538077) (xy 88.666076 -238.520625) (xy 88.714295 -238.510781)
			(xy 88.76347 -238.5088) (xy 88.812325 -238.514732) (xy 88.859596 -238.528424) (xy 88.904058 -238.549522)
			(xy 88.944561 -238.577478) (xy 88.980054 -238.61157) (xy 89.009619 -238.650914) (xy 89.03249 -238.694491)
			(xy 89.048074 -238.741172) (xy 89.055969 -238.789749) (xy 89.056464 -238.814356) (xy 89.385152 -238.814356)
			(xy 89.389112 -238.765302) (xy 89.400889 -238.717518) (xy 89.42018 -238.672242) (xy 89.446483 -238.630646)
			(xy 89.479118 -238.593809) (xy 89.517239 -238.562684) (xy 89.55986 -238.538077) (xy 89.605876 -238.520625)
			(xy 89.654095 -238.510781) (xy 89.70327 -238.5088) (xy 89.752125 -238.514732) (xy 89.799396 -238.528424)
			(xy 89.843858 -238.549522) (xy 89.884361 -238.577478) (xy 89.919854 -238.61157) (xy 89.949419 -238.650914)
			(xy 89.97229 -238.694491) (xy 89.987874 -238.741172) (xy 89.995769 -238.789749) (xy 89.996264 -238.814356)
			(xy 90.314775 -238.814356) (xy 90.31887 -238.763628) (xy 90.331049 -238.714214) (xy 90.350997 -238.667394)
			(xy 90.378198 -238.62438) (xy 90.411946 -238.586286) (xy 90.451368 -238.554099) (xy 90.495442 -238.528653)
			(xy 90.543028 -238.510606) (xy 90.592892 -238.500426) (xy 90.643744 -238.498377) (xy 90.694265 -238.504511)
			(xy 90.743149 -238.518671) (xy 90.789128 -238.540488) (xy 90.831012 -238.569398) (xy 90.867716 -238.604653)
			(xy 90.898289 -238.645339) (xy 90.92194 -238.690402) (xy 90.938056 -238.738676) (xy 90.94622 -238.78891)
			(xy 90.946732 -238.814356) (xy 91.26526 -238.814356) (xy 91.26922 -238.765302) (xy 91.280997 -238.717518)
			(xy 91.300288 -238.672242) (xy 91.326591 -238.630646) (xy 91.359226 -238.593809) (xy 91.397347 -238.562684)
			(xy 91.439968 -238.538077) (xy 91.485984 -238.520625) (xy 91.534203 -238.510781) (xy 91.583378 -238.5088)
			(xy 91.632233 -238.514732) (xy 91.679504 -238.528424) (xy 91.723966 -238.549522) (xy 91.764469 -238.577478)
			(xy 91.799962 -238.61157) (xy 91.829527 -238.650914) (xy 91.852398 -238.694491) (xy 91.867982 -238.741172)
			(xy 91.875877 -238.789749) (xy 91.876372 -238.814356) (xy 92.194883 -238.814356) (xy 92.198978 -238.763628)
			(xy 92.211157 -238.714214) (xy 92.231105 -238.667394) (xy 92.258306 -238.62438) (xy 92.292054 -238.586286)
			(xy 92.331476 -238.554099) (xy 92.37555 -238.528653) (xy 92.423136 -238.510606) (xy 92.473 -238.500426)
			(xy 92.523852 -238.498377) (xy 92.574373 -238.504511) (xy 92.623257 -238.518671) (xy 92.669236 -238.540488)
			(xy 92.71112 -238.569398) (xy 92.747824 -238.604653) (xy 92.778397 -238.645339) (xy 92.802048 -238.690402)
			(xy 92.818164 -238.738676) (xy 92.826328 -238.78891) (xy 92.82684 -238.814356) (xy 93.145114 -238.814356)
			(xy 93.149074 -238.765302) (xy 93.160851 -238.717518) (xy 93.180142 -238.672242) (xy 93.206445 -238.630646)
			(xy 93.23908 -238.593809) (xy 93.277201 -238.562684) (xy 93.319822 -238.538077) (xy 93.365838 -238.520625)
			(xy 93.414057 -238.510781) (xy 93.463232 -238.5088) (xy 93.512087 -238.514732) (xy 93.559358 -238.528424)
			(xy 93.60382 -238.549522) (xy 93.644323 -238.577478) (xy 93.679816 -238.61157) (xy 93.709381 -238.650914)
			(xy 93.732252 -238.694491) (xy 93.747836 -238.741172) (xy 93.755731 -238.789749) (xy 93.756226 -238.814356)
			(xy 94.074737 -238.814356) (xy 94.078832 -238.763628) (xy 94.091011 -238.714214) (xy 94.110959 -238.667394)
			(xy 94.13816 -238.62438) (xy 94.171908 -238.586286) (xy 94.21133 -238.554099) (xy 94.255404 -238.528653)
			(xy 94.30299 -238.510606) (xy 94.352854 -238.500426) (xy 94.403706 -238.498377) (xy 94.454227 -238.504511)
			(xy 94.503111 -238.518671) (xy 94.54909 -238.540488) (xy 94.590974 -238.569398) (xy 94.627678 -238.604653)
			(xy 94.658251 -238.645339) (xy 94.681902 -238.690402) (xy 94.698018 -238.738676) (xy 94.706182 -238.78891)
			(xy 94.706694 -238.814356) (xy 94.706182 -238.839802) (xy 94.698018 -238.890036) (xy 94.681902 -238.93831)
			(xy 94.658251 -238.983373) (xy 94.627678 -239.024059) (xy 94.590974 -239.059314) (xy 94.54909 -239.088224)
			(xy 94.503111 -239.110041) (xy 94.454227 -239.124201) (xy 94.403706 -239.130335) (xy 94.352854 -239.128286)
			(xy 94.30299 -239.118106) (xy 94.255404 -239.100059) (xy 94.21133 -239.074613) (xy 94.171908 -239.042426)
			(xy 94.13816 -239.004332) (xy 94.110959 -238.961318) (xy 94.091011 -238.914498) (xy 94.078832 -238.865084)
			(xy 94.074737 -238.814356) (xy 93.756226 -238.814356) (xy 93.755731 -238.838963) (xy 93.747836 -238.88754)
			(xy 93.732252 -238.934221) (xy 93.709381 -238.977798) (xy 93.679816 -239.017142) (xy 93.644323 -239.051234)
			(xy 93.60382 -239.07919) (xy 93.559358 -239.100288) (xy 93.512087 -239.11398) (xy 93.463232 -239.119912)
			(xy 93.414057 -239.117931) (xy 93.365838 -239.108087) (xy 93.319822 -239.090635) (xy 93.277201 -239.066028)
			(xy 93.23908 -239.034903) (xy 93.206445 -238.998066) (xy 93.180142 -238.95647) (xy 93.160851 -238.911194)
			(xy 93.149074 -238.86341) (xy 93.145114 -238.814356) (xy 92.82684 -238.814356) (xy 92.826328 -238.839802)
			(xy 92.818164 -238.890036) (xy 92.802048 -238.93831) (xy 92.778397 -238.983373) (xy 92.747824 -239.024059)
			(xy 92.71112 -239.059314) (xy 92.669236 -239.088224) (xy 92.623257 -239.110041) (xy 92.574373 -239.124201)
			(xy 92.523852 -239.130335) (xy 92.473 -239.128286) (xy 92.423136 -239.118106) (xy 92.37555 -239.100059)
			(xy 92.331476 -239.074613) (xy 92.292054 -239.042426) (xy 92.258306 -239.004332) (xy 92.231105 -238.961318)
			(xy 92.211157 -238.914498) (xy 92.198978 -238.865084) (xy 92.194883 -238.814356) (xy 91.876372 -238.814356)
			(xy 91.875877 -238.838963) (xy 91.867982 -238.88754) (xy 91.852398 -238.934221) (xy 91.829527 -238.977798)
			(xy 91.799962 -239.017142) (xy 91.764469 -239.051234) (xy 91.723966 -239.07919) (xy 91.679504 -239.100288)
			(xy 91.632233 -239.11398) (xy 91.583378 -239.119912) (xy 91.534203 -239.117931) (xy 91.485984 -239.108087)
			(xy 91.439968 -239.090635) (xy 91.397347 -239.066028) (xy 91.359226 -239.034903) (xy 91.326591 -238.998066)
			(xy 91.300288 -238.95647) (xy 91.280997 -238.911194) (xy 91.26922 -238.86341) (xy 91.26526 -238.814356)
			(xy 90.946732 -238.814356) (xy 90.94622 -238.839802) (xy 90.938056 -238.890036) (xy 90.92194 -238.93831)
			(xy 90.898289 -238.983373) (xy 90.867716 -239.024059) (xy 90.831012 -239.059314) (xy 90.789128 -239.088224)
			(xy 90.743149 -239.110041) (xy 90.694265 -239.124201) (xy 90.643744 -239.130335) (xy 90.592892 -239.128286)
			(xy 90.543028 -239.118106) (xy 90.495442 -239.100059) (xy 90.451368 -239.074613) (xy 90.411946 -239.042426)
			(xy 90.378198 -239.004332) (xy 90.350997 -238.961318) (xy 90.331049 -238.914498) (xy 90.31887 -238.865084)
			(xy 90.314775 -238.814356) (xy 89.996264 -238.814356) (xy 89.995769 -238.838963) (xy 89.987874 -238.88754)
			(xy 89.97229 -238.934221) (xy 89.949419 -238.977798) (xy 89.919854 -239.017142) (xy 89.884361 -239.051234)
			(xy 89.843858 -239.07919) (xy 89.799396 -239.100288) (xy 89.752125 -239.11398) (xy 89.70327 -239.119912)
			(xy 89.654095 -239.117931) (xy 89.605876 -239.108087) (xy 89.55986 -239.090635) (xy 89.517239 -239.066028)
			(xy 89.479118 -239.034903) (xy 89.446483 -238.998066) (xy 89.42018 -238.95647) (xy 89.400889 -238.911194)
			(xy 89.389112 -238.86341) (xy 89.385152 -238.814356) (xy 89.056464 -238.814356) (xy 89.055969 -238.838963)
			(xy 89.048074 -238.88754) (xy 89.03249 -238.934221) (xy 89.009619 -238.977798) (xy 88.980054 -239.017142)
			(xy 88.944561 -239.051234) (xy 88.904058 -239.07919) (xy 88.859596 -239.100288) (xy 88.812325 -239.11398)
			(xy 88.76347 -239.119912) (xy 88.714295 -239.117931) (xy 88.666076 -239.108087) (xy 88.62006 -239.090635)
			(xy 88.577439 -239.066028) (xy 88.539318 -239.034903) (xy 88.506683 -238.998066) (xy 88.48038 -238.95647)
			(xy 88.461089 -238.911194) (xy 88.449312 -238.86341) (xy 88.445352 -238.814356) (xy 88.11641 -238.814356)
			(xy 88.115915 -238.838963) (xy 88.10802 -238.88754) (xy 88.092436 -238.934221) (xy 88.069565 -238.977798)
			(xy 88.04 -239.017142) (xy 88.004507 -239.051234) (xy 87.964004 -239.07919) (xy 87.919542 -239.100288)
			(xy 87.872271 -239.11398) (xy 87.823416 -239.119912) (xy 87.774241 -239.117931) (xy 87.726022 -239.108087)
			(xy 87.680006 -239.090635) (xy 87.637385 -239.066028) (xy 87.599264 -239.034903) (xy 87.566629 -238.998066)
			(xy 87.540326 -238.95647) (xy 87.521035 -238.911194) (xy 87.509258 -238.86341) (xy 87.505298 -238.814356)
			(xy 87.176356 -238.814356) (xy 87.176281 -238.824739) (xy 87.174885 -238.845459) (xy 87.173562 -238.855758)
			(xy 87.173054 -238.859314) (xy 87.173054 -238.901478) (xy 87.172518 -238.911316) (xy 87.164935 -238.92948)
			(xy 87.158322 -238.936784) (xy 87.144352 -238.950754) (xy 87.140796 -238.957612) (xy 87.129783 -238.977472)
			(xy 87.102788 -239.013989) (xy 87.070683 -239.046106) (xy 87.034178 -239.073116) (xy 87.014304 -239.084104)
			(xy 87.007446 -239.08766) (xy 86.997286 -239.09782) (xy 86.990047 -239.104532) (xy 86.971842 -239.112124)
			(xy 86.96198 -239.112552) (xy 86.936072 -239.112552) (xy 86.930738 -239.113822) (xy 86.92134 -239.1156)
			(xy 86.913974 -239.11687) (xy 86.88578 -239.130332) (xy 86.879684 -239.136682) (xy 86.799166 -239.2172)
			(xy 86.792453 -239.224438) (xy 86.784858 -239.242643) (xy 86.784434 -239.252506) (xy 86.784434 -239.624362)
			(xy 87.035144 -239.624362) (xy 87.039104 -239.575308) (xy 87.050881 -239.527524) (xy 87.070172 -239.482248)
			(xy 87.096475 -239.440652) (xy 87.12911 -239.403815) (xy 87.167231 -239.37269) (xy 87.209852 -239.348083)
			(xy 87.255868 -239.330631) (xy 87.304087 -239.320787) (xy 87.353262 -239.318806) (xy 87.402117 -239.324738)
			(xy 87.449388 -239.33843) (xy 87.49385 -239.359528) (xy 87.534353 -239.387484) (xy 87.569846 -239.421576)
			(xy 87.599411 -239.46092) (xy 87.622282 -239.504497) (xy 87.637866 -239.551178) (xy 87.645761 -239.599755)
			(xy 87.646256 -239.624362) (xy 87.975198 -239.624362) (xy 87.979158 -239.575308) (xy 87.990935 -239.527524)
			(xy 88.010226 -239.482248) (xy 88.036529 -239.440652) (xy 88.069164 -239.403815) (xy 88.107285 -239.37269)
			(xy 88.149906 -239.348083) (xy 88.195922 -239.330631) (xy 88.244141 -239.320787) (xy 88.293316 -239.318806)
			(xy 88.342171 -239.324738) (xy 88.389442 -239.33843) (xy 88.433904 -239.359528) (xy 88.474407 -239.387484)
			(xy 88.5099 -239.421576) (xy 88.539465 -239.46092) (xy 88.562336 -239.504497) (xy 88.57792 -239.551178)
			(xy 88.585815 -239.599755) (xy 88.58631 -239.624362) (xy 88.915252 -239.624362) (xy 88.919212 -239.575308)
			(xy 88.930989 -239.527524) (xy 88.95028 -239.482248) (xy 88.976583 -239.440652) (xy 89.009218 -239.403815)
			(xy 89.047339 -239.37269) (xy 89.08996 -239.348083) (xy 89.135976 -239.330631) (xy 89.184195 -239.320787)
			(xy 89.23337 -239.318806) (xy 89.282225 -239.324738) (xy 89.329496 -239.33843) (xy 89.373958 -239.359528)
			(xy 89.414461 -239.387484) (xy 89.449954 -239.421576) (xy 89.479519 -239.46092) (xy 89.50239 -239.504497)
			(xy 89.517974 -239.551178) (xy 89.525869 -239.599755) (xy 89.526364 -239.624362) (xy 89.855306 -239.624362)
			(xy 89.859266 -239.575308) (xy 89.871043 -239.527524) (xy 89.890334 -239.482248) (xy 89.916637 -239.440652)
			(xy 89.949272 -239.403815) (xy 89.987393 -239.37269) (xy 90.030014 -239.348083) (xy 90.07603 -239.330631)
			(xy 90.124249 -239.320787) (xy 90.173424 -239.318806) (xy 90.222279 -239.324738) (xy 90.26955 -239.33843)
			(xy 90.314012 -239.359528) (xy 90.354515 -239.387484) (xy 90.390008 -239.421576) (xy 90.419573 -239.46092)
			(xy 90.442444 -239.504497) (xy 90.458028 -239.551178) (xy 90.465923 -239.599755) (xy 90.466418 -239.624362)
			(xy 90.784675 -239.624362) (xy 90.78877 -239.573634) (xy 90.800949 -239.52422) (xy 90.820897 -239.4774)
			(xy 90.848098 -239.434386) (xy 90.881846 -239.396292) (xy 90.921268 -239.364105) (xy 90.965342 -239.338659)
			(xy 91.012928 -239.320612) (xy 91.062792 -239.310432) (xy 91.113644 -239.308383) (xy 91.164165 -239.314517)
			(xy 91.213049 -239.328677) (xy 91.259028 -239.350494) (xy 91.300912 -239.379404) (xy 91.337616 -239.414659)
			(xy 91.368189 -239.455345) (xy 91.39184 -239.500408) (xy 91.407956 -239.548682) (xy 91.41612 -239.598916)
			(xy 91.416632 -239.624362) (xy 91.724729 -239.624362) (xy 91.728824 -239.573634) (xy 91.741003 -239.52422)
			(xy 91.760951 -239.4774) (xy 91.788152 -239.434386) (xy 91.8219 -239.396292) (xy 91.861322 -239.364105)
			(xy 91.905396 -239.338659) (xy 91.952982 -239.320612) (xy 92.002846 -239.310432) (xy 92.053698 -239.308383)
			(xy 92.104219 -239.314517) (xy 92.153103 -239.328677) (xy 92.199082 -239.350494) (xy 92.240966 -239.379404)
			(xy 92.27767 -239.414659) (xy 92.308243 -239.455345) (xy 92.331894 -239.500408) (xy 92.34801 -239.548682)
			(xy 92.356174 -239.598916) (xy 92.356686 -239.624362) (xy 92.675214 -239.624362) (xy 92.679174 -239.575308)
			(xy 92.690951 -239.527524) (xy 92.710242 -239.482248) (xy 92.736545 -239.440652) (xy 92.76918 -239.403815)
			(xy 92.807301 -239.37269) (xy 92.849922 -239.348083) (xy 92.895938 -239.330631) (xy 92.944157 -239.320787)
			(xy 92.993332 -239.318806) (xy 93.042187 -239.324738) (xy 93.089458 -239.33843) (xy 93.13392 -239.359528)
			(xy 93.174423 -239.387484) (xy 93.209916 -239.421576) (xy 93.239481 -239.46092) (xy 93.262352 -239.504497)
			(xy 93.277936 -239.551178) (xy 93.285831 -239.599755) (xy 93.286326 -239.624362) (xy 93.604837 -239.624362)
			(xy 93.608932 -239.573634) (xy 93.621111 -239.52422) (xy 93.641059 -239.4774) (xy 93.66826 -239.434386)
			(xy 93.702008 -239.396292) (xy 93.74143 -239.364105) (xy 93.785504 -239.338659) (xy 93.83309 -239.320612)
			(xy 93.882954 -239.310432) (xy 93.933806 -239.308383) (xy 93.984327 -239.314517) (xy 94.033211 -239.328677)
			(xy 94.07919 -239.350494) (xy 94.121074 -239.379404) (xy 94.157778 -239.414659) (xy 94.188351 -239.455345)
			(xy 94.212002 -239.500408) (xy 94.228118 -239.548682) (xy 94.236282 -239.598916) (xy 94.236794 -239.624362)
			(xy 94.555322 -239.624362) (xy 94.559282 -239.575308) (xy 94.571059 -239.527524) (xy 94.59035 -239.482248)
			(xy 94.616653 -239.440652) (xy 94.649288 -239.403815) (xy 94.687409 -239.37269) (xy 94.73003 -239.348083)
			(xy 94.776046 -239.330631) (xy 94.824265 -239.320787) (xy 94.87344 -239.318806) (xy 94.922295 -239.324738)
			(xy 94.969566 -239.33843) (xy 95.014028 -239.359528) (xy 95.054531 -239.387484) (xy 95.090024 -239.421576)
			(xy 95.119589 -239.46092) (xy 95.14246 -239.504497) (xy 95.158044 -239.551178) (xy 95.165939 -239.599755)
			(xy 95.166434 -239.624362) (xy 95.165939 -239.648969) (xy 95.158044 -239.697546) (xy 95.14246 -239.744227)
			(xy 95.119589 -239.787804) (xy 95.090024 -239.827148) (xy 95.054531 -239.86124) (xy 95.014028 -239.889196)
			(xy 94.969566 -239.910294) (xy 94.922295 -239.923986) (xy 94.87344 -239.929918) (xy 94.824265 -239.927937)
			(xy 94.776046 -239.918093) (xy 94.73003 -239.900641) (xy 94.687409 -239.876034) (xy 94.649288 -239.844909)
			(xy 94.616653 -239.808072) (xy 94.59035 -239.766476) (xy 94.571059 -239.7212) (xy 94.559282 -239.673416)
			(xy 94.555322 -239.624362) (xy 94.236794 -239.624362) (xy 94.236282 -239.649808) (xy 94.228118 -239.700042)
			(xy 94.212002 -239.748316) (xy 94.188351 -239.793379) (xy 94.157778 -239.834065) (xy 94.121074 -239.86932)
			(xy 94.07919 -239.89823) (xy 94.033211 -239.920047) (xy 93.984327 -239.934207) (xy 93.933806 -239.940341)
			(xy 93.882954 -239.938292) (xy 93.83309 -239.928112) (xy 93.785504 -239.910065) (xy 93.74143 -239.884619)
			(xy 93.702008 -239.852432) (xy 93.66826 -239.814338) (xy 93.641059 -239.771324) (xy 93.621111 -239.724504)
			(xy 93.608932 -239.67509) (xy 93.604837 -239.624362) (xy 93.286326 -239.624362) (xy 93.285831 -239.648969)
			(xy 93.277936 -239.697546) (xy 93.262352 -239.744227) (xy 93.239481 -239.787804) (xy 93.209916 -239.827148)
			(xy 93.174423 -239.86124) (xy 93.13392 -239.889196) (xy 93.089458 -239.910294) (xy 93.042187 -239.923986)
			(xy 92.993332 -239.929918) (xy 92.944157 -239.927937) (xy 92.895938 -239.918093) (xy 92.849922 -239.900641)
			(xy 92.807301 -239.876034) (xy 92.76918 -239.844909) (xy 92.736545 -239.808072) (xy 92.710242 -239.766476)
			(xy 92.690951 -239.7212) (xy 92.679174 -239.673416) (xy 92.675214 -239.624362) (xy 92.356686 -239.624362)
			(xy 92.356174 -239.649808) (xy 92.34801 -239.700042) (xy 92.331894 -239.748316) (xy 92.308243 -239.793379)
			(xy 92.27767 -239.834065) (xy 92.240966 -239.86932) (xy 92.199082 -239.89823) (xy 92.153103 -239.920047)
			(xy 92.104219 -239.934207) (xy 92.053698 -239.940341) (xy 92.002846 -239.938292) (xy 91.952982 -239.928112)
			(xy 91.905396 -239.910065) (xy 91.861322 -239.884619) (xy 91.8219 -239.852432) (xy 91.788152 -239.814338)
			(xy 91.760951 -239.771324) (xy 91.741003 -239.724504) (xy 91.728824 -239.67509) (xy 91.724729 -239.624362)
			(xy 91.416632 -239.624362) (xy 91.41612 -239.649808) (xy 91.407956 -239.700042) (xy 91.39184 -239.748316)
			(xy 91.368189 -239.793379) (xy 91.337616 -239.834065) (xy 91.300912 -239.86932) (xy 91.259028 -239.89823)
			(xy 91.213049 -239.920047) (xy 91.164165 -239.934207) (xy 91.113644 -239.940341) (xy 91.062792 -239.938292)
			(xy 91.012928 -239.928112) (xy 90.965342 -239.910065) (xy 90.921268 -239.884619) (xy 90.881846 -239.852432)
			(xy 90.848098 -239.814338) (xy 90.820897 -239.771324) (xy 90.800949 -239.724504) (xy 90.78877 -239.67509)
			(xy 90.784675 -239.624362) (xy 90.466418 -239.624362) (xy 90.465923 -239.648969) (xy 90.458028 -239.697546)
			(xy 90.442444 -239.744227) (xy 90.419573 -239.787804) (xy 90.390008 -239.827148) (xy 90.354515 -239.86124)
			(xy 90.314012 -239.889196) (xy 90.26955 -239.910294) (xy 90.222279 -239.923986) (xy 90.173424 -239.929918)
			(xy 90.124249 -239.927937) (xy 90.07603 -239.918093) (xy 90.030014 -239.900641) (xy 89.987393 -239.876034)
			(xy 89.949272 -239.844909) (xy 89.916637 -239.808072) (xy 89.890334 -239.766476) (xy 89.871043 -239.7212)
			(xy 89.859266 -239.673416) (xy 89.855306 -239.624362) (xy 89.526364 -239.624362) (xy 89.525869 -239.648969)
			(xy 89.517974 -239.697546) (xy 89.50239 -239.744227) (xy 89.479519 -239.787804) (xy 89.449954 -239.827148)
			(xy 89.414461 -239.86124) (xy 89.373958 -239.889196) (xy 89.329496 -239.910294) (xy 89.282225 -239.923986)
			(xy 89.23337 -239.929918) (xy 89.184195 -239.927937) (xy 89.135976 -239.918093) (xy 89.08996 -239.900641)
			(xy 89.047339 -239.876034) (xy 89.009218 -239.844909) (xy 88.976583 -239.808072) (xy 88.95028 -239.766476)
			(xy 88.930989 -239.7212) (xy 88.919212 -239.673416) (xy 88.915252 -239.624362) (xy 88.58631 -239.624362)
			(xy 88.585815 -239.648969) (xy 88.57792 -239.697546) (xy 88.562336 -239.744227) (xy 88.539465 -239.787804)
			(xy 88.5099 -239.827148) (xy 88.474407 -239.86124) (xy 88.433904 -239.889196) (xy 88.389442 -239.910294)
			(xy 88.342171 -239.923986) (xy 88.293316 -239.929918) (xy 88.244141 -239.927937) (xy 88.195922 -239.918093)
			(xy 88.149906 -239.900641) (xy 88.107285 -239.876034) (xy 88.069164 -239.844909) (xy 88.036529 -239.808072)
			(xy 88.010226 -239.766476) (xy 87.990935 -239.7212) (xy 87.979158 -239.673416) (xy 87.975198 -239.624362)
			(xy 87.646256 -239.624362) (xy 87.645761 -239.648969) (xy 87.637866 -239.697546) (xy 87.622282 -239.744227)
			(xy 87.599411 -239.787804) (xy 87.569846 -239.827148) (xy 87.534353 -239.86124) (xy 87.49385 -239.889196)
			(xy 87.449388 -239.910294) (xy 87.402117 -239.923986) (xy 87.353262 -239.929918) (xy 87.304087 -239.927937)
			(xy 87.255868 -239.918093) (xy 87.209852 -239.900641) (xy 87.167231 -239.876034) (xy 87.12911 -239.844909)
			(xy 87.096475 -239.808072) (xy 87.070172 -239.766476) (xy 87.050881 -239.7212) (xy 87.039104 -239.673416)
			(xy 87.035144 -239.624362) (xy 86.784434 -239.624362) (xy 86.784434 -239.86871) (xy 86.784891 -239.878589)
			(xy 86.792325 -239.896895) (xy 86.798912 -239.90427) (xy 86.799166 -239.904524) (xy 87.145622 -240.25098)
			(xy 87.152339 -240.258217) (xy 87.159943 -240.276422) (xy 87.160354 -240.286286) (xy 87.160354 -240.336578)
			(xy 87.16264 -240.343944) (xy 87.169042 -240.366) (xy 87.175923 -240.411406) (xy 87.176356 -240.434368)
			(xy 87.505298 -240.434368) (xy 87.509258 -240.385314) (xy 87.521035 -240.33753) (xy 87.540326 -240.292254)
			(xy 87.566629 -240.250658) (xy 87.599264 -240.213821) (xy 87.637385 -240.182696) (xy 87.680006 -240.158089)
			(xy 87.726022 -240.140637) (xy 87.774241 -240.130793) (xy 87.823416 -240.128812) (xy 87.872271 -240.134744)
			(xy 87.919542 -240.148436) (xy 87.964004 -240.169534) (xy 88.004507 -240.19749) (xy 88.04 -240.231582)
			(xy 88.069565 -240.270926) (xy 88.092436 -240.314503) (xy 88.10802 -240.361184) (xy 88.115915 -240.409761)
			(xy 88.11641 -240.434368) (xy 88.445352 -240.434368) (xy 88.449312 -240.385314) (xy 88.461089 -240.33753)
			(xy 88.48038 -240.292254) (xy 88.506683 -240.250658) (xy 88.539318 -240.213821) (xy 88.577439 -240.182696)
			(xy 88.62006 -240.158089) (xy 88.666076 -240.140637) (xy 88.714295 -240.130793) (xy 88.76347 -240.128812)
			(xy 88.812325 -240.134744) (xy 88.859596 -240.148436) (xy 88.904058 -240.169534) (xy 88.944561 -240.19749)
			(xy 88.980054 -240.231582) (xy 89.009619 -240.270926) (xy 89.03249 -240.314503) (xy 89.048074 -240.361184)
			(xy 89.055969 -240.409761) (xy 89.056464 -240.434368) (xy 89.385152 -240.434368) (xy 89.389112 -240.385314)
			(xy 89.400889 -240.33753) (xy 89.42018 -240.292254) (xy 89.446483 -240.250658) (xy 89.479118 -240.213821)
			(xy 89.517239 -240.182696) (xy 89.55986 -240.158089) (xy 89.605876 -240.140637) (xy 89.654095 -240.130793)
			(xy 89.70327 -240.128812) (xy 89.752125 -240.134744) (xy 89.799396 -240.148436) (xy 89.843858 -240.169534)
			(xy 89.884361 -240.19749) (xy 89.919854 -240.231582) (xy 89.949419 -240.270926) (xy 89.97229 -240.314503)
			(xy 89.987874 -240.361184) (xy 89.995769 -240.409761) (xy 89.996264 -240.434368) (xy 90.314775 -240.434368)
			(xy 90.31887 -240.38364) (xy 90.331049 -240.334226) (xy 90.350997 -240.287406) (xy 90.378198 -240.244392)
			(xy 90.411946 -240.206298) (xy 90.451368 -240.174111) (xy 90.495442 -240.148665) (xy 90.543028 -240.130618)
			(xy 90.592892 -240.120438) (xy 90.643744 -240.118389) (xy 90.694265 -240.124523) (xy 90.743149 -240.138683)
			(xy 90.789128 -240.1605) (xy 90.831012 -240.18941) (xy 90.867716 -240.224665) (xy 90.898289 -240.265351)
			(xy 90.92194 -240.310414) (xy 90.938056 -240.358688) (xy 90.94622 -240.408922) (xy 90.946732 -240.434368)
			(xy 91.26526 -240.434368) (xy 91.26922 -240.385314) (xy 91.280997 -240.33753) (xy 91.300288 -240.292254)
			(xy 91.326591 -240.250658) (xy 91.359226 -240.213821) (xy 91.397347 -240.182696) (xy 91.439968 -240.158089)
			(xy 91.485984 -240.140637) (xy 91.534203 -240.130793) (xy 91.583378 -240.128812) (xy 91.632233 -240.134744)
			(xy 91.679504 -240.148436) (xy 91.723966 -240.169534) (xy 91.764469 -240.19749) (xy 91.799962 -240.231582)
			(xy 91.829527 -240.270926) (xy 91.852398 -240.314503) (xy 91.867982 -240.361184) (xy 91.875877 -240.409761)
			(xy 91.876372 -240.434368) (xy 92.194883 -240.434368) (xy 92.198978 -240.38364) (xy 92.211157 -240.334226)
			(xy 92.231105 -240.287406) (xy 92.258306 -240.244392) (xy 92.292054 -240.206298) (xy 92.331476 -240.174111)
			(xy 92.37555 -240.148665) (xy 92.423136 -240.130618) (xy 92.473 -240.120438) (xy 92.523852 -240.118389)
			(xy 92.574373 -240.124523) (xy 92.623257 -240.138683) (xy 92.669236 -240.1605) (xy 92.71112 -240.18941)
			(xy 92.747824 -240.224665) (xy 92.778397 -240.265351) (xy 92.802048 -240.310414) (xy 92.818164 -240.358688)
			(xy 92.826328 -240.408922) (xy 92.82684 -240.434368) (xy 93.145114 -240.434368) (xy 93.149074 -240.385314)
			(xy 93.160851 -240.33753) (xy 93.180142 -240.292254) (xy 93.206445 -240.250658) (xy 93.23908 -240.213821)
			(xy 93.277201 -240.182696) (xy 93.319822 -240.158089) (xy 93.365838 -240.140637) (xy 93.414057 -240.130793)
			(xy 93.463232 -240.128812) (xy 93.512087 -240.134744) (xy 93.559358 -240.148436) (xy 93.60382 -240.169534)
			(xy 93.644323 -240.19749) (xy 93.679816 -240.231582) (xy 93.709381 -240.270926) (xy 93.732252 -240.314503)
			(xy 93.747836 -240.361184) (xy 93.755731 -240.409761) (xy 93.756226 -240.434368) (xy 94.074737 -240.434368)
			(xy 94.078832 -240.38364) (xy 94.091011 -240.334226) (xy 94.110959 -240.287406) (xy 94.13816 -240.244392)
			(xy 94.171908 -240.206298) (xy 94.21133 -240.174111) (xy 94.255404 -240.148665) (xy 94.30299 -240.130618)
			(xy 94.352854 -240.120438) (xy 94.403706 -240.118389) (xy 94.454227 -240.124523) (xy 94.503111 -240.138683)
			(xy 94.54909 -240.1605) (xy 94.590974 -240.18941) (xy 94.627678 -240.224665) (xy 94.658251 -240.265351)
			(xy 94.681902 -240.310414) (xy 94.698018 -240.358688) (xy 94.706182 -240.408922) (xy 94.706694 -240.434368)
			(xy 94.706182 -240.459814) (xy 94.698018 -240.510048) (xy 94.681902 -240.558322) (xy 94.658251 -240.603385)
			(xy 94.627678 -240.644071) (xy 94.590974 -240.679326) (xy 94.54909 -240.708236) (xy 94.503111 -240.730053)
			(xy 94.454227 -240.744213) (xy 94.403706 -240.750347) (xy 94.352854 -240.748298) (xy 94.30299 -240.738118)
			(xy 94.255404 -240.720071) (xy 94.21133 -240.694625) (xy 94.171908 -240.662438) (xy 94.13816 -240.624344)
			(xy 94.110959 -240.58133) (xy 94.091011 -240.53451) (xy 94.078832 -240.485096) (xy 94.074737 -240.434368)
			(xy 93.756226 -240.434368) (xy 93.755731 -240.458975) (xy 93.747836 -240.507552) (xy 93.732252 -240.554233)
			(xy 93.709381 -240.59781) (xy 93.679816 -240.637154) (xy 93.644323 -240.671246) (xy 93.60382 -240.699202)
			(xy 93.559358 -240.7203) (xy 93.512087 -240.733992) (xy 93.463232 -240.739924) (xy 93.414057 -240.737943)
			(xy 93.365838 -240.728099) (xy 93.319822 -240.710647) (xy 93.277201 -240.68604) (xy 93.23908 -240.654915)
			(xy 93.206445 -240.618078) (xy 93.180142 -240.576482) (xy 93.160851 -240.531206) (xy 93.149074 -240.483422)
			(xy 93.145114 -240.434368) (xy 92.82684 -240.434368) (xy 92.826328 -240.459814) (xy 92.818164 -240.510048)
			(xy 92.802048 -240.558322) (xy 92.778397 -240.603385) (xy 92.747824 -240.644071) (xy 92.71112 -240.679326)
			(xy 92.669236 -240.708236) (xy 92.623257 -240.730053) (xy 92.574373 -240.744213) (xy 92.523852 -240.750347)
			(xy 92.473 -240.748298) (xy 92.423136 -240.738118) (xy 92.37555 -240.720071) (xy 92.331476 -240.694625)
			(xy 92.292054 -240.662438) (xy 92.258306 -240.624344) (xy 92.231105 -240.58133) (xy 92.211157 -240.53451)
			(xy 92.198978 -240.485096) (xy 92.194883 -240.434368) (xy 91.876372 -240.434368) (xy 91.875877 -240.458975)
			(xy 91.867982 -240.507552) (xy 91.852398 -240.554233) (xy 91.829527 -240.59781) (xy 91.799962 -240.637154)
			(xy 91.764469 -240.671246) (xy 91.723966 -240.699202) (xy 91.679504 -240.7203) (xy 91.632233 -240.733992)
			(xy 91.583378 -240.739924) (xy 91.534203 -240.737943) (xy 91.485984 -240.728099) (xy 91.439968 -240.710647)
			(xy 91.397347 -240.68604) (xy 91.359226 -240.654915) (xy 91.326591 -240.618078) (xy 91.300288 -240.576482)
			(xy 91.280997 -240.531206) (xy 91.26922 -240.483422) (xy 91.26526 -240.434368) (xy 90.946732 -240.434368)
			(xy 90.94622 -240.459814) (xy 90.938056 -240.510048) (xy 90.92194 -240.558322) (xy 90.898289 -240.603385)
			(xy 90.867716 -240.644071) (xy 90.831012 -240.679326) (xy 90.789128 -240.708236) (xy 90.743149 -240.730053)
			(xy 90.694265 -240.744213) (xy 90.643744 -240.750347) (xy 90.592892 -240.748298) (xy 90.543028 -240.738118)
			(xy 90.495442 -240.720071) (xy 90.451368 -240.694625) (xy 90.411946 -240.662438) (xy 90.378198 -240.624344)
			(xy 90.350997 -240.58133) (xy 90.331049 -240.53451) (xy 90.31887 -240.485096) (xy 90.314775 -240.434368)
			(xy 89.996264 -240.434368) (xy 89.995769 -240.458975) (xy 89.987874 -240.507552) (xy 89.97229 -240.554233)
			(xy 89.949419 -240.59781) (xy 89.919854 -240.637154) (xy 89.884361 -240.671246) (xy 89.843858 -240.699202)
			(xy 89.799396 -240.7203) (xy 89.752125 -240.733992) (xy 89.70327 -240.739924) (xy 89.654095 -240.737943)
			(xy 89.605876 -240.728099) (xy 89.55986 -240.710647) (xy 89.517239 -240.68604) (xy 89.479118 -240.654915)
			(xy 89.446483 -240.618078) (xy 89.42018 -240.576482) (xy 89.400889 -240.531206) (xy 89.389112 -240.483422)
			(xy 89.385152 -240.434368) (xy 89.056464 -240.434368) (xy 89.055969 -240.458975) (xy 89.048074 -240.507552)
			(xy 89.03249 -240.554233) (xy 89.009619 -240.59781) (xy 88.980054 -240.637154) (xy 88.944561 -240.671246)
			(xy 88.904058 -240.699202) (xy 88.859596 -240.7203) (xy 88.812325 -240.733992) (xy 88.76347 -240.739924)
			(xy 88.714295 -240.737943) (xy 88.666076 -240.728099) (xy 88.62006 -240.710647) (xy 88.577439 -240.68604)
			(xy 88.539318 -240.654915) (xy 88.506683 -240.618078) (xy 88.48038 -240.576482) (xy 88.461089 -240.531206)
			(xy 88.449312 -240.483422) (xy 88.445352 -240.434368) (xy 88.11641 -240.434368) (xy 88.115915 -240.458975)
			(xy 88.10802 -240.507552) (xy 88.092436 -240.554233) (xy 88.069565 -240.59781) (xy 88.04 -240.637154)
			(xy 88.004507 -240.671246) (xy 87.964004 -240.699202) (xy 87.919542 -240.7203) (xy 87.872271 -240.733992)
			(xy 87.823416 -240.739924) (xy 87.774241 -240.737943) (xy 87.726022 -240.728099) (xy 87.680006 -240.710647)
			(xy 87.637385 -240.68604) (xy 87.599264 -240.654915) (xy 87.566629 -240.618078) (xy 87.540326 -240.576482)
			(xy 87.521035 -240.531206) (xy 87.509258 -240.483422) (xy 87.505298 -240.434368) (xy 87.176356 -240.434368)
			(xy 87.175922 -240.456802) (xy 87.169293 -240.50118) (xy 87.163148 -240.52276) (xy 87.162894 -240.523522)
			(xy 87.16264 -240.525046) (xy 87.160354 -240.532412) (xy 87.160354 -240.610898) (xy 87.159814 -240.620734)
			(xy 87.152226 -240.638893) (xy 87.145622 -240.646204) (xy 87.017606 -240.77422) (xy 87.010368 -240.780935)
			(xy 86.992164 -240.788534) (xy 86.9823 -240.788952) (xy 86.817708 -240.788952) (xy 86.807871 -240.789491)
			(xy 86.789711 -240.797078) (xy 86.782402 -240.803684) (xy 86.763606 -240.82248) (xy 86.756886 -240.829715)
			(xy 86.749277 -240.847921) (xy 86.748874 -240.857786) (xy 86.748874 -241.244374) (xy 87.035144 -241.244374)
			(xy 87.039104 -241.19532) (xy 87.050881 -241.147536) (xy 87.070172 -241.10226) (xy 87.096475 -241.060664)
			(xy 87.12911 -241.023827) (xy 87.167231 -240.992702) (xy 87.209852 -240.968095) (xy 87.255868 -240.950643)
			(xy 87.304087 -240.940799) (xy 87.353262 -240.938818) (xy 87.402117 -240.94475) (xy 87.449388 -240.958442)
			(xy 87.49385 -240.97954) (xy 87.534353 -241.007496) (xy 87.569846 -241.041588) (xy 87.599411 -241.080932)
			(xy 87.622282 -241.124509) (xy 87.637866 -241.17119) (xy 87.645761 -241.219767) (xy 87.646256 -241.244374)
			(xy 87.975198 -241.244374) (xy 87.979158 -241.19532) (xy 87.990935 -241.147536) (xy 88.010226 -241.10226)
			(xy 88.036529 -241.060664) (xy 88.069164 -241.023827) (xy 88.107285 -240.992702) (xy 88.149906 -240.968095)
			(xy 88.195922 -240.950643) (xy 88.244141 -240.940799) (xy 88.293316 -240.938818) (xy 88.342171 -240.94475)
			(xy 88.389442 -240.958442) (xy 88.433904 -240.97954) (xy 88.474407 -241.007496) (xy 88.5099 -241.041588)
			(xy 88.539465 -241.080932) (xy 88.562336 -241.124509) (xy 88.57792 -241.17119) (xy 88.585815 -241.219767)
			(xy 88.58631 -241.244374) (xy 88.915252 -241.244374) (xy 88.919212 -241.19532) (xy 88.930989 -241.147536)
			(xy 88.95028 -241.10226) (xy 88.976583 -241.060664) (xy 89.009218 -241.023827) (xy 89.047339 -240.992702)
			(xy 89.08996 -240.968095) (xy 89.135976 -240.950643) (xy 89.184195 -240.940799) (xy 89.23337 -240.938818)
			(xy 89.282225 -240.94475) (xy 89.329496 -240.958442) (xy 89.373958 -240.97954) (xy 89.414461 -241.007496)
			(xy 89.449954 -241.041588) (xy 89.479519 -241.080932) (xy 89.50239 -241.124509) (xy 89.517974 -241.17119)
			(xy 89.525869 -241.219767) (xy 89.526364 -241.244374) (xy 89.855306 -241.244374) (xy 89.859266 -241.19532)
			(xy 89.871043 -241.147536) (xy 89.890334 -241.10226) (xy 89.916637 -241.060664) (xy 89.949272 -241.023827)
			(xy 89.987393 -240.992702) (xy 90.030014 -240.968095) (xy 90.07603 -240.950643) (xy 90.124249 -240.940799)
			(xy 90.173424 -240.938818) (xy 90.222279 -240.94475) (xy 90.26955 -240.958442) (xy 90.314012 -240.97954)
			(xy 90.354515 -241.007496) (xy 90.390008 -241.041588) (xy 90.419573 -241.080932) (xy 90.442444 -241.124509)
			(xy 90.458028 -241.17119) (xy 90.465923 -241.219767) (xy 90.466418 -241.244374) (xy 90.784675 -241.244374)
			(xy 90.78877 -241.193646) (xy 90.800949 -241.144232) (xy 90.820897 -241.097412) (xy 90.848098 -241.054398)
			(xy 90.881846 -241.016304) (xy 90.921268 -240.984117) (xy 90.965342 -240.958671) (xy 91.012928 -240.940624)
			(xy 91.062792 -240.930444) (xy 91.113644 -240.928395) (xy 91.164165 -240.934529) (xy 91.213049 -240.948689)
			(xy 91.259028 -240.970506) (xy 91.300912 -240.999416) (xy 91.337616 -241.034671) (xy 91.368189 -241.075357)
			(xy 91.39184 -241.12042) (xy 91.407956 -241.168694) (xy 91.41612 -241.218928) (xy 91.416632 -241.244374)
			(xy 91.724729 -241.244374) (xy 91.728824 -241.193646) (xy 91.741003 -241.144232) (xy 91.760951 -241.097412)
			(xy 91.788152 -241.054398) (xy 91.8219 -241.016304) (xy 91.861322 -240.984117) (xy 91.905396 -240.958671)
			(xy 91.952982 -240.940624) (xy 92.002846 -240.930444) (xy 92.053698 -240.928395) (xy 92.104219 -240.934529)
			(xy 92.153103 -240.948689) (xy 92.199082 -240.970506) (xy 92.240966 -240.999416) (xy 92.27767 -241.034671)
			(xy 92.308243 -241.075357) (xy 92.331894 -241.12042) (xy 92.34801 -241.168694) (xy 92.356174 -241.218928)
			(xy 92.356686 -241.244374) (xy 92.675214 -241.244374) (xy 92.679174 -241.19532) (xy 92.690951 -241.147536)
			(xy 92.710242 -241.10226) (xy 92.736545 -241.060664) (xy 92.76918 -241.023827) (xy 92.807301 -240.992702)
			(xy 92.849922 -240.968095) (xy 92.895938 -240.950643) (xy 92.944157 -240.940799) (xy 92.993332 -240.938818)
			(xy 93.042187 -240.94475) (xy 93.089458 -240.958442) (xy 93.13392 -240.97954) (xy 93.174423 -241.007496)
			(xy 93.209916 -241.041588) (xy 93.239481 -241.080932) (xy 93.262352 -241.124509) (xy 93.277936 -241.17119)
			(xy 93.285831 -241.219767) (xy 93.286326 -241.244374) (xy 93.604837 -241.244374) (xy 93.608932 -241.193646)
			(xy 93.621111 -241.144232) (xy 93.641059 -241.097412) (xy 93.66826 -241.054398) (xy 93.702008 -241.016304)
			(xy 93.74143 -240.984117) (xy 93.785504 -240.958671) (xy 93.83309 -240.940624) (xy 93.882954 -240.930444)
			(xy 93.933806 -240.928395) (xy 93.984327 -240.934529) (xy 94.033211 -240.948689) (xy 94.07919 -240.970506)
			(xy 94.121074 -240.999416) (xy 94.157778 -241.034671) (xy 94.188351 -241.075357) (xy 94.212002 -241.12042)
			(xy 94.228118 -241.168694) (xy 94.236282 -241.218928) (xy 94.236794 -241.244374) (xy 94.555322 -241.244374)
			(xy 94.559282 -241.19532) (xy 94.571059 -241.147536) (xy 94.59035 -241.10226) (xy 94.616653 -241.060664)
			(xy 94.649288 -241.023827) (xy 94.687409 -240.992702) (xy 94.73003 -240.968095) (xy 94.776046 -240.950643)
			(xy 94.824265 -240.940799) (xy 94.87344 -240.938818) (xy 94.922295 -240.94475) (xy 94.969566 -240.958442)
			(xy 95.014028 -240.97954) (xy 95.054531 -241.007496) (xy 95.090024 -241.041588) (xy 95.119589 -241.080932)
			(xy 95.14246 -241.124509) (xy 95.158044 -241.17119) (xy 95.165939 -241.219767) (xy 95.166434 -241.244374)
			(xy 95.165939 -241.268981) (xy 95.158044 -241.317558) (xy 95.14246 -241.364239) (xy 95.119589 -241.407816)
			(xy 95.090024 -241.44716) (xy 95.054531 -241.481252) (xy 95.014028 -241.509208) (xy 94.969566 -241.530306)
			(xy 94.922295 -241.543998) (xy 94.87344 -241.54993) (xy 94.824265 -241.547949) (xy 94.776046 -241.538105)
			(xy 94.73003 -241.520653) (xy 94.687409 -241.496046) (xy 94.649288 -241.464921) (xy 94.616653 -241.428084)
			(xy 94.59035 -241.386488) (xy 94.571059 -241.341212) (xy 94.559282 -241.293428) (xy 94.555322 -241.244374)
			(xy 94.236794 -241.244374) (xy 94.236282 -241.26982) (xy 94.228118 -241.320054) (xy 94.212002 -241.368328)
			(xy 94.188351 -241.413391) (xy 94.157778 -241.454077) (xy 94.121074 -241.489332) (xy 94.07919 -241.518242)
			(xy 94.033211 -241.540059) (xy 93.984327 -241.554219) (xy 93.933806 -241.560353) (xy 93.882954 -241.558304)
			(xy 93.83309 -241.548124) (xy 93.785504 -241.530077) (xy 93.74143 -241.504631) (xy 93.702008 -241.472444)
			(xy 93.66826 -241.43435) (xy 93.641059 -241.391336) (xy 93.621111 -241.344516) (xy 93.608932 -241.295102)
			(xy 93.604837 -241.244374) (xy 93.286326 -241.244374) (xy 93.285831 -241.268981) (xy 93.277936 -241.317558)
			(xy 93.262352 -241.364239) (xy 93.239481 -241.407816) (xy 93.209916 -241.44716) (xy 93.174423 -241.481252)
			(xy 93.13392 -241.509208) (xy 93.089458 -241.530306) (xy 93.042187 -241.543998) (xy 92.993332 -241.54993)
			(xy 92.944157 -241.547949) (xy 92.895938 -241.538105) (xy 92.849922 -241.520653) (xy 92.807301 -241.496046)
			(xy 92.76918 -241.464921) (xy 92.736545 -241.428084) (xy 92.710242 -241.386488) (xy 92.690951 -241.341212)
			(xy 92.679174 -241.293428) (xy 92.675214 -241.244374) (xy 92.356686 -241.244374) (xy 92.356174 -241.26982)
			(xy 92.34801 -241.320054) (xy 92.331894 -241.368328) (xy 92.308243 -241.413391) (xy 92.27767 -241.454077)
			(xy 92.240966 -241.489332) (xy 92.199082 -241.518242) (xy 92.153103 -241.540059) (xy 92.104219 -241.554219)
			(xy 92.053698 -241.560353) (xy 92.002846 -241.558304) (xy 91.952982 -241.548124) (xy 91.905396 -241.530077)
			(xy 91.861322 -241.504631) (xy 91.8219 -241.472444) (xy 91.788152 -241.43435) (xy 91.760951 -241.391336)
			(xy 91.741003 -241.344516) (xy 91.728824 -241.295102) (xy 91.724729 -241.244374) (xy 91.416632 -241.244374)
			(xy 91.41612 -241.26982) (xy 91.407956 -241.320054) (xy 91.39184 -241.368328) (xy 91.368189 -241.413391)
			(xy 91.337616 -241.454077) (xy 91.300912 -241.489332) (xy 91.259028 -241.518242) (xy 91.213049 -241.540059)
			(xy 91.164165 -241.554219) (xy 91.113644 -241.560353) (xy 91.062792 -241.558304) (xy 91.012928 -241.548124)
			(xy 90.965342 -241.530077) (xy 90.921268 -241.504631) (xy 90.881846 -241.472444) (xy 90.848098 -241.43435)
			(xy 90.820897 -241.391336) (xy 90.800949 -241.344516) (xy 90.78877 -241.295102) (xy 90.784675 -241.244374)
			(xy 90.466418 -241.244374) (xy 90.465923 -241.268981) (xy 90.458028 -241.317558) (xy 90.442444 -241.364239)
			(xy 90.419573 -241.407816) (xy 90.390008 -241.44716) (xy 90.354515 -241.481252) (xy 90.314012 -241.509208)
			(xy 90.26955 -241.530306) (xy 90.222279 -241.543998) (xy 90.173424 -241.54993) (xy 90.124249 -241.547949)
			(xy 90.07603 -241.538105) (xy 90.030014 -241.520653) (xy 89.987393 -241.496046) (xy 89.949272 -241.464921)
			(xy 89.916637 -241.428084) (xy 89.890334 -241.386488) (xy 89.871043 -241.341212) (xy 89.859266 -241.293428)
			(xy 89.855306 -241.244374) (xy 89.526364 -241.244374) (xy 89.525869 -241.268981) (xy 89.517974 -241.317558)
			(xy 89.50239 -241.364239) (xy 89.479519 -241.407816) (xy 89.449954 -241.44716) (xy 89.414461 -241.481252)
			(xy 89.373958 -241.509208) (xy 89.329496 -241.530306) (xy 89.282225 -241.543998) (xy 89.23337 -241.54993)
			(xy 89.184195 -241.547949) (xy 89.135976 -241.538105) (xy 89.08996 -241.520653) (xy 89.047339 -241.496046)
			(xy 89.009218 -241.464921) (xy 88.976583 -241.428084) (xy 88.95028 -241.386488) (xy 88.930989 -241.341212)
			(xy 88.919212 -241.293428) (xy 88.915252 -241.244374) (xy 88.58631 -241.244374) (xy 88.585815 -241.268981)
			(xy 88.57792 -241.317558) (xy 88.562336 -241.364239) (xy 88.539465 -241.407816) (xy 88.5099 -241.44716)
			(xy 88.474407 -241.481252) (xy 88.433904 -241.509208) (xy 88.389442 -241.530306) (xy 88.342171 -241.543998)
			(xy 88.293316 -241.54993) (xy 88.244141 -241.547949) (xy 88.195922 -241.538105) (xy 88.149906 -241.520653)
			(xy 88.107285 -241.496046) (xy 88.069164 -241.464921) (xy 88.036529 -241.428084) (xy 88.010226 -241.386488)
			(xy 87.990935 -241.341212) (xy 87.979158 -241.293428) (xy 87.975198 -241.244374) (xy 87.646256 -241.244374)
			(xy 87.645761 -241.268981) (xy 87.637866 -241.317558) (xy 87.622282 -241.364239) (xy 87.599411 -241.407816)
			(xy 87.569846 -241.44716) (xy 87.534353 -241.481252) (xy 87.49385 -241.509208) (xy 87.449388 -241.530306)
			(xy 87.402117 -241.543998) (xy 87.353262 -241.54993) (xy 87.304087 -241.547949) (xy 87.255868 -241.538105)
			(xy 87.209852 -241.520653) (xy 87.167231 -241.496046) (xy 87.12911 -241.464921) (xy 87.096475 -241.428084)
			(xy 87.070172 -241.386488) (xy 87.050881 -241.341212) (xy 87.039104 -241.293428) (xy 87.035144 -241.244374)
			(xy 86.748874 -241.244374) (xy 86.748874 -241.45113) (xy 86.749335 -241.461007) (xy 86.756779 -241.479305)
			(xy 86.763352 -241.48669) (xy 86.763606 -241.486944) (xy 86.832948 -241.556286) (xy 86.833456 -241.556794)
			(xy 86.840839 -241.563371) (xy 86.859138 -241.570814) (xy 86.869016 -241.571272) (xy 86.98738 -241.571272)
			(xy 86.997217 -241.571809) (xy 87.015378 -241.579395) (xy 87.022686 -241.586004) (xy 87.285322 -241.84864)
			(xy 87.29203 -241.85588) (xy 87.299612 -241.874085) (xy 87.300054 -241.883946) (xy 87.300054 -242.05438)
			(xy 87.505298 -242.05438) (xy 87.509258 -242.005326) (xy 87.521035 -241.957542) (xy 87.540326 -241.912266)
			(xy 87.566629 -241.87067) (xy 87.599264 -241.833833) (xy 87.637385 -241.802708) (xy 87.680006 -241.778101)
			(xy 87.726022 -241.760649) (xy 87.774241 -241.750805) (xy 87.823416 -241.748824) (xy 87.872271 -241.754756)
			(xy 87.919542 -241.768448) (xy 87.964004 -241.789546) (xy 88.004507 -241.817502) (xy 88.04 -241.851594)
			(xy 88.069565 -241.890938) (xy 88.092436 -241.934515) (xy 88.10802 -241.981196) (xy 88.115915 -242.029773)
			(xy 88.11641 -242.05438) (xy 88.445352 -242.05438) (xy 88.449312 -242.005326) (xy 88.461089 -241.957542)
			(xy 88.48038 -241.912266) (xy 88.506683 -241.87067) (xy 88.539318 -241.833833) (xy 88.577439 -241.802708)
			(xy 88.62006 -241.778101) (xy 88.666076 -241.760649) (xy 88.714295 -241.750805) (xy 88.76347 -241.748824)
			(xy 88.812325 -241.754756) (xy 88.859596 -241.768448) (xy 88.904058 -241.789546) (xy 88.944561 -241.817502)
			(xy 88.980054 -241.851594) (xy 89.009619 -241.890938) (xy 89.03249 -241.934515) (xy 89.048074 -241.981196)
			(xy 89.055969 -242.029773) (xy 89.056464 -242.05438) (xy 89.385152 -242.05438) (xy 89.389112 -242.005326)
			(xy 89.400889 -241.957542) (xy 89.42018 -241.912266) (xy 89.446483 -241.87067) (xy 89.479118 -241.833833)
			(xy 89.517239 -241.802708) (xy 89.55986 -241.778101) (xy 89.605876 -241.760649) (xy 89.654095 -241.750805)
			(xy 89.70327 -241.748824) (xy 89.752125 -241.754756) (xy 89.799396 -241.768448) (xy 89.843858 -241.789546)
			(xy 89.884361 -241.817502) (xy 89.919854 -241.851594) (xy 89.949419 -241.890938) (xy 89.97229 -241.934515)
			(xy 89.987874 -241.981196) (xy 89.995769 -242.029773) (xy 89.996264 -242.05438) (xy 90.314775 -242.05438)
			(xy 90.31887 -242.003652) (xy 90.331049 -241.954238) (xy 90.350997 -241.907418) (xy 90.378198 -241.864404)
			(xy 90.411946 -241.82631) (xy 90.451368 -241.794123) (xy 90.495442 -241.768677) (xy 90.543028 -241.75063)
			(xy 90.592892 -241.74045) (xy 90.643744 -241.738401) (xy 90.694265 -241.744535) (xy 90.743149 -241.758695)
			(xy 90.789128 -241.780512) (xy 90.831012 -241.809422) (xy 90.867716 -241.844677) (xy 90.898289 -241.885363)
			(xy 90.92194 -241.930426) (xy 90.938056 -241.9787) (xy 90.94622 -242.028934) (xy 90.946732 -242.05438)
			(xy 91.26526 -242.05438) (xy 91.26922 -242.005326) (xy 91.280997 -241.957542) (xy 91.300288 -241.912266)
			(xy 91.326591 -241.87067) (xy 91.359226 -241.833833) (xy 91.397347 -241.802708) (xy 91.439968 -241.778101)
			(xy 91.485984 -241.760649) (xy 91.534203 -241.750805) (xy 91.583378 -241.748824) (xy 91.632233 -241.754756)
			(xy 91.679504 -241.768448) (xy 91.723966 -241.789546) (xy 91.764469 -241.817502) (xy 91.799962 -241.851594)
			(xy 91.829527 -241.890938) (xy 91.852398 -241.934515) (xy 91.867982 -241.981196) (xy 91.875877 -242.029773)
			(xy 91.876372 -242.05438) (xy 92.194883 -242.05438) (xy 92.198978 -242.003652) (xy 92.211157 -241.954238)
			(xy 92.231105 -241.907418) (xy 92.258306 -241.864404) (xy 92.292054 -241.82631) (xy 92.331476 -241.794123)
			(xy 92.37555 -241.768677) (xy 92.423136 -241.75063) (xy 92.473 -241.74045) (xy 92.523852 -241.738401)
			(xy 92.574373 -241.744535) (xy 92.623257 -241.758695) (xy 92.669236 -241.780512) (xy 92.71112 -241.809422)
			(xy 92.747824 -241.844677) (xy 92.778397 -241.885363) (xy 92.802048 -241.930426) (xy 92.818164 -241.9787)
			(xy 92.826328 -242.028934) (xy 92.82684 -242.05438) (xy 93.145114 -242.05438) (xy 93.149074 -242.005326)
			(xy 93.160851 -241.957542) (xy 93.180142 -241.912266) (xy 93.206445 -241.87067) (xy 93.23908 -241.833833)
			(xy 93.277201 -241.802708) (xy 93.319822 -241.778101) (xy 93.365838 -241.760649) (xy 93.414057 -241.750805)
			(xy 93.463232 -241.748824) (xy 93.512087 -241.754756) (xy 93.559358 -241.768448) (xy 93.60382 -241.789546)
			(xy 93.644323 -241.817502) (xy 93.679816 -241.851594) (xy 93.709381 -241.890938) (xy 93.732252 -241.934515)
			(xy 93.747836 -241.981196) (xy 93.755731 -242.029773) (xy 93.756226 -242.05438) (xy 94.074737 -242.05438)
			(xy 94.078832 -242.003652) (xy 94.091011 -241.954238) (xy 94.110959 -241.907418) (xy 94.13816 -241.864404)
			(xy 94.171908 -241.82631) (xy 94.21133 -241.794123) (xy 94.255404 -241.768677) (xy 94.30299 -241.75063)
			(xy 94.352854 -241.74045) (xy 94.403706 -241.738401) (xy 94.454227 -241.744535) (xy 94.503111 -241.758695)
			(xy 94.54909 -241.780512) (xy 94.590974 -241.809422) (xy 94.627678 -241.844677) (xy 94.658251 -241.885363)
			(xy 94.681902 -241.930426) (xy 94.698018 -241.9787) (xy 94.706182 -242.028934) (xy 94.706694 -242.05438)
			(xy 94.706182 -242.079826) (xy 94.698018 -242.13006) (xy 94.681902 -242.178334) (xy 94.658251 -242.223397)
			(xy 94.627678 -242.264083) (xy 94.590974 -242.299338) (xy 94.54909 -242.328248) (xy 94.503111 -242.350065)
			(xy 94.454227 -242.364225) (xy 94.403706 -242.370359) (xy 94.352854 -242.36831) (xy 94.30299 -242.35813)
			(xy 94.255404 -242.340083) (xy 94.21133 -242.314637) (xy 94.171908 -242.28245) (xy 94.13816 -242.244356)
			(xy 94.110959 -242.201342) (xy 94.091011 -242.154522) (xy 94.078832 -242.105108) (xy 94.074737 -242.05438)
			(xy 93.756226 -242.05438) (xy 93.755731 -242.078987) (xy 93.747836 -242.127564) (xy 93.732252 -242.174245)
			(xy 93.709381 -242.217822) (xy 93.679816 -242.257166) (xy 93.644323 -242.291258) (xy 93.60382 -242.319214)
			(xy 93.559358 -242.340312) (xy 93.512087 -242.354004) (xy 93.463232 -242.359936) (xy 93.414057 -242.357955)
			(xy 93.365838 -242.348111) (xy 93.319822 -242.330659) (xy 93.277201 -242.306052) (xy 93.23908 -242.274927)
			(xy 93.206445 -242.23809) (xy 93.180142 -242.196494) (xy 93.160851 -242.151218) (xy 93.149074 -242.103434)
			(xy 93.145114 -242.05438) (xy 92.82684 -242.05438) (xy 92.826328 -242.079826) (xy 92.818164 -242.13006)
			(xy 92.802048 -242.178334) (xy 92.778397 -242.223397) (xy 92.747824 -242.264083) (xy 92.71112 -242.299338)
			(xy 92.669236 -242.328248) (xy 92.623257 -242.350065) (xy 92.574373 -242.364225) (xy 92.523852 -242.370359)
			(xy 92.473 -242.36831) (xy 92.423136 -242.35813) (xy 92.37555 -242.340083) (xy 92.331476 -242.314637)
			(xy 92.292054 -242.28245) (xy 92.258306 -242.244356) (xy 92.231105 -242.201342) (xy 92.211157 -242.154522)
			(xy 92.198978 -242.105108) (xy 92.194883 -242.05438) (xy 91.876372 -242.05438) (xy 91.875877 -242.078987)
			(xy 91.867982 -242.127564) (xy 91.852398 -242.174245) (xy 91.829527 -242.217822) (xy 91.799962 -242.257166)
			(xy 91.764469 -242.291258) (xy 91.723966 -242.319214) (xy 91.679504 -242.340312) (xy 91.632233 -242.354004)
			(xy 91.583378 -242.359936) (xy 91.534203 -242.357955) (xy 91.485984 -242.348111) (xy 91.439968 -242.330659)
			(xy 91.397347 -242.306052) (xy 91.359226 -242.274927) (xy 91.326591 -242.23809) (xy 91.300288 -242.196494)
			(xy 91.280997 -242.151218) (xy 91.26922 -242.103434) (xy 91.26526 -242.05438) (xy 90.946732 -242.05438)
			(xy 90.94622 -242.079826) (xy 90.938056 -242.13006) (xy 90.92194 -242.178334) (xy 90.898289 -242.223397)
			(xy 90.867716 -242.264083) (xy 90.831012 -242.299338) (xy 90.789128 -242.328248) (xy 90.743149 -242.350065)
			(xy 90.694265 -242.364225) (xy 90.643744 -242.370359) (xy 90.592892 -242.36831) (xy 90.543028 -242.35813)
			(xy 90.495442 -242.340083) (xy 90.451368 -242.314637) (xy 90.411946 -242.28245) (xy 90.378198 -242.244356)
			(xy 90.350997 -242.201342) (xy 90.331049 -242.154522) (xy 90.31887 -242.105108) (xy 90.314775 -242.05438)
			(xy 89.996264 -242.05438) (xy 89.995769 -242.078987) (xy 89.987874 -242.127564) (xy 89.97229 -242.174245)
			(xy 89.949419 -242.217822) (xy 89.919854 -242.257166) (xy 89.884361 -242.291258) (xy 89.843858 -242.319214)
			(xy 89.799396 -242.340312) (xy 89.752125 -242.354004) (xy 89.70327 -242.359936) (xy 89.654095 -242.357955)
			(xy 89.605876 -242.348111) (xy 89.55986 -242.330659) (xy 89.517239 -242.306052) (xy 89.479118 -242.274927)
			(xy 89.446483 -242.23809) (xy 89.42018 -242.196494) (xy 89.400889 -242.151218) (xy 89.389112 -242.103434)
			(xy 89.385152 -242.05438) (xy 89.056464 -242.05438) (xy 89.055969 -242.078987) (xy 89.048074 -242.127564)
			(xy 89.03249 -242.174245) (xy 89.009619 -242.217822) (xy 88.980054 -242.257166) (xy 88.944561 -242.291258)
			(xy 88.904058 -242.319214) (xy 88.859596 -242.340312) (xy 88.812325 -242.354004) (xy 88.76347 -242.359936)
			(xy 88.714295 -242.357955) (xy 88.666076 -242.348111) (xy 88.62006 -242.330659) (xy 88.577439 -242.306052)
			(xy 88.539318 -242.274927) (xy 88.506683 -242.23809) (xy 88.48038 -242.196494) (xy 88.461089 -242.151218)
			(xy 88.449312 -242.103434) (xy 88.445352 -242.05438) (xy 88.11641 -242.05438) (xy 88.115915 -242.078987)
			(xy 88.10802 -242.127564) (xy 88.092436 -242.174245) (xy 88.069565 -242.217822) (xy 88.04 -242.257166)
			(xy 88.004507 -242.291258) (xy 87.964004 -242.319214) (xy 87.919542 -242.340312) (xy 87.872271 -242.354004)
			(xy 87.823416 -242.359936) (xy 87.774241 -242.357955) (xy 87.726022 -242.348111) (xy 87.680006 -242.330659)
			(xy 87.637385 -242.306052) (xy 87.599264 -242.274927) (xy 87.566629 -242.23809) (xy 87.540326 -242.196494)
			(xy 87.521035 -242.151218) (xy 87.509258 -242.103434) (xy 87.505298 -242.05438) (xy 87.300054 -242.05438)
			(xy 87.300054 -242.274598) (xy 87.299514 -242.284434) (xy 87.291926 -242.302593) (xy 87.285322 -242.309904)
			(xy 87.111586 -242.48364) (xy 87.104346 -242.49035) (xy 87.086142 -242.497938) (xy 87.07628 -242.498372)
			(xy 86.820248 -242.498372) (xy 86.810408 -242.498904) (xy 86.79224 -242.506483) (xy 86.784942 -242.513104)
			(xy 86.728046 -242.57) (xy 86.721336 -242.577239) (xy 86.713744 -242.595444) (xy 86.713314 -242.605306)
			(xy 86.713314 -242.864386) (xy 87.035144 -242.864386) (xy 87.039104 -242.815332) (xy 87.050881 -242.767548)
			(xy 87.070172 -242.722272) (xy 87.096475 -242.680676) (xy 87.12911 -242.643839) (xy 87.167231 -242.612714)
			(xy 87.209852 -242.588107) (xy 87.255868 -242.570655) (xy 87.304087 -242.560811) (xy 87.353262 -242.55883)
			(xy 87.402117 -242.564762) (xy 87.449388 -242.578454) (xy 87.49385 -242.599552) (xy 87.534353 -242.627508)
			(xy 87.569846 -242.6616) (xy 87.599411 -242.700944) (xy 87.622282 -242.744521) (xy 87.637866 -242.791202)
			(xy 87.645761 -242.839779) (xy 87.646256 -242.864386) (xy 87.975198 -242.864386) (xy 87.979158 -242.815332)
			(xy 87.990935 -242.767548) (xy 88.010226 -242.722272) (xy 88.036529 -242.680676) (xy 88.069164 -242.643839)
			(xy 88.107285 -242.612714) (xy 88.149906 -242.588107) (xy 88.195922 -242.570655) (xy 88.244141 -242.560811)
			(xy 88.293316 -242.55883) (xy 88.342171 -242.564762) (xy 88.389442 -242.578454) (xy 88.433904 -242.599552)
			(xy 88.474407 -242.627508) (xy 88.5099 -242.6616) (xy 88.539465 -242.700944) (xy 88.562336 -242.744521)
			(xy 88.57792 -242.791202) (xy 88.585815 -242.839779) (xy 88.58631 -242.864386) (xy 88.915252 -242.864386)
			(xy 88.919212 -242.815332) (xy 88.930989 -242.767548) (xy 88.95028 -242.722272) (xy 88.976583 -242.680676)
			(xy 89.009218 -242.643839) (xy 89.047339 -242.612714) (xy 89.08996 -242.588107) (xy 89.135976 -242.570655)
			(xy 89.184195 -242.560811) (xy 89.23337 -242.55883) (xy 89.282225 -242.564762) (xy 89.329496 -242.578454)
			(xy 89.373958 -242.599552) (xy 89.414461 -242.627508) (xy 89.449954 -242.6616) (xy 89.479519 -242.700944)
			(xy 89.50239 -242.744521) (xy 89.517974 -242.791202) (xy 89.525869 -242.839779) (xy 89.526364 -242.864386)
			(xy 89.855306 -242.864386) (xy 89.859266 -242.815332) (xy 89.871043 -242.767548) (xy 89.890334 -242.722272)
			(xy 89.916637 -242.680676) (xy 89.949272 -242.643839) (xy 89.987393 -242.612714) (xy 90.030014 -242.588107)
			(xy 90.07603 -242.570655) (xy 90.124249 -242.560811) (xy 90.173424 -242.55883) (xy 90.222279 -242.564762)
			(xy 90.26955 -242.578454) (xy 90.314012 -242.599552) (xy 90.354515 -242.627508) (xy 90.390008 -242.6616)
			(xy 90.419573 -242.700944) (xy 90.442444 -242.744521) (xy 90.458028 -242.791202) (xy 90.465923 -242.839779)
			(xy 90.466418 -242.864386) (xy 90.784675 -242.864386) (xy 90.78877 -242.813658) (xy 90.800949 -242.764244)
			(xy 90.820897 -242.717424) (xy 90.848098 -242.67441) (xy 90.881846 -242.636316) (xy 90.921268 -242.604129)
			(xy 90.965342 -242.578683) (xy 91.012928 -242.560636) (xy 91.062792 -242.550456) (xy 91.113644 -242.548407)
			(xy 91.164165 -242.554541) (xy 91.213049 -242.568701) (xy 91.259028 -242.590518) (xy 91.300912 -242.619428)
			(xy 91.337616 -242.654683) (xy 91.368189 -242.695369) (xy 91.39184 -242.740432) (xy 91.407956 -242.788706)
			(xy 91.41612 -242.83894) (xy 91.416632 -242.864386) (xy 91.724729 -242.864386) (xy 91.728824 -242.813658)
			(xy 91.741003 -242.764244) (xy 91.760951 -242.717424) (xy 91.788152 -242.67441) (xy 91.8219 -242.636316)
			(xy 91.861322 -242.604129) (xy 91.905396 -242.578683) (xy 91.952982 -242.560636) (xy 92.002846 -242.550456)
			(xy 92.053698 -242.548407) (xy 92.104219 -242.554541) (xy 92.153103 -242.568701) (xy 92.199082 -242.590518)
			(xy 92.240966 -242.619428) (xy 92.27767 -242.654683) (xy 92.308243 -242.695369) (xy 92.331894 -242.740432)
			(xy 92.34801 -242.788706) (xy 92.356174 -242.83894) (xy 92.356686 -242.864386) (xy 92.675214 -242.864386)
			(xy 92.679174 -242.815332) (xy 92.690951 -242.767548) (xy 92.710242 -242.722272) (xy 92.736545 -242.680676)
			(xy 92.76918 -242.643839) (xy 92.807301 -242.612714) (xy 92.849922 -242.588107) (xy 92.895938 -242.570655)
			(xy 92.944157 -242.560811) (xy 92.993332 -242.55883) (xy 93.042187 -242.564762) (xy 93.089458 -242.578454)
			(xy 93.13392 -242.599552) (xy 93.174423 -242.627508) (xy 93.209916 -242.6616) (xy 93.239481 -242.700944)
			(xy 93.262352 -242.744521) (xy 93.277936 -242.791202) (xy 93.285831 -242.839779) (xy 93.286326 -242.864386)
			(xy 93.604837 -242.864386) (xy 93.608932 -242.813658) (xy 93.621111 -242.764244) (xy 93.641059 -242.717424)
			(xy 93.66826 -242.67441) (xy 93.702008 -242.636316) (xy 93.74143 -242.604129) (xy 93.785504 -242.578683)
			(xy 93.83309 -242.560636) (xy 93.882954 -242.550456) (xy 93.933806 -242.548407) (xy 93.984327 -242.554541)
			(xy 94.033211 -242.568701) (xy 94.07919 -242.590518) (xy 94.121074 -242.619428) (xy 94.157778 -242.654683)
			(xy 94.188351 -242.695369) (xy 94.212002 -242.740432) (xy 94.228118 -242.788706) (xy 94.236282 -242.83894)
			(xy 94.236794 -242.864386) (xy 94.555322 -242.864386) (xy 94.559282 -242.815332) (xy 94.571059 -242.767548)
			(xy 94.59035 -242.722272) (xy 94.616653 -242.680676) (xy 94.649288 -242.643839) (xy 94.687409 -242.612714)
			(xy 94.73003 -242.588107) (xy 94.776046 -242.570655) (xy 94.824265 -242.560811) (xy 94.87344 -242.55883)
			(xy 94.922295 -242.564762) (xy 94.969566 -242.578454) (xy 95.014028 -242.599552) (xy 95.054531 -242.627508)
			(xy 95.090024 -242.6616) (xy 95.119589 -242.700944) (xy 95.14246 -242.744521) (xy 95.158044 -242.791202)
			(xy 95.165939 -242.839779) (xy 95.166434 -242.864386) (xy 95.165939 -242.888993) (xy 95.158044 -242.93757)
			(xy 95.14246 -242.984251) (xy 95.119589 -243.027828) (xy 95.090024 -243.067172) (xy 95.054531 -243.101264)
			(xy 95.014028 -243.12922) (xy 94.969566 -243.150318) (xy 94.922295 -243.16401) (xy 94.87344 -243.169942)
			(xy 94.824265 -243.167961) (xy 94.776046 -243.158117) (xy 94.73003 -243.140665) (xy 94.687409 -243.116058)
			(xy 94.649288 -243.084933) (xy 94.616653 -243.048096) (xy 94.59035 -243.0065) (xy 94.571059 -242.961224)
			(xy 94.559282 -242.91344) (xy 94.555322 -242.864386) (xy 94.236794 -242.864386) (xy 94.236282 -242.889832)
			(xy 94.228118 -242.940066) (xy 94.212002 -242.98834) (xy 94.188351 -243.033403) (xy 94.157778 -243.074089)
			(xy 94.121074 -243.109344) (xy 94.07919 -243.138254) (xy 94.033211 -243.160071) (xy 93.984327 -243.174231)
			(xy 93.933806 -243.180365) (xy 93.882954 -243.178316) (xy 93.83309 -243.168136) (xy 93.785504 -243.150089)
			(xy 93.74143 -243.124643) (xy 93.702008 -243.092456) (xy 93.66826 -243.054362) (xy 93.641059 -243.011348)
			(xy 93.621111 -242.964528) (xy 93.608932 -242.915114) (xy 93.604837 -242.864386) (xy 93.286326 -242.864386)
			(xy 93.285831 -242.888993) (xy 93.277936 -242.93757) (xy 93.262352 -242.984251) (xy 93.239481 -243.027828)
			(xy 93.209916 -243.067172) (xy 93.174423 -243.101264) (xy 93.13392 -243.12922) (xy 93.089458 -243.150318)
			(xy 93.042187 -243.16401) (xy 92.993332 -243.169942) (xy 92.944157 -243.167961) (xy 92.895938 -243.158117)
			(xy 92.849922 -243.140665) (xy 92.807301 -243.116058) (xy 92.76918 -243.084933) (xy 92.736545 -243.048096)
			(xy 92.710242 -243.0065) (xy 92.690951 -242.961224) (xy 92.679174 -242.91344) (xy 92.675214 -242.864386)
			(xy 92.356686 -242.864386) (xy 92.356174 -242.889832) (xy 92.34801 -242.940066) (xy 92.331894 -242.98834)
			(xy 92.308243 -243.033403) (xy 92.27767 -243.074089) (xy 92.240966 -243.109344) (xy 92.199082 -243.138254)
			(xy 92.153103 -243.160071) (xy 92.104219 -243.174231) (xy 92.053698 -243.180365) (xy 92.002846 -243.178316)
			(xy 91.952982 -243.168136) (xy 91.905396 -243.150089) (xy 91.861322 -243.124643) (xy 91.8219 -243.092456)
			(xy 91.788152 -243.054362) (xy 91.760951 -243.011348) (xy 91.741003 -242.964528) (xy 91.728824 -242.915114)
			(xy 91.724729 -242.864386) (xy 91.416632 -242.864386) (xy 91.41612 -242.889832) (xy 91.407956 -242.940066)
			(xy 91.39184 -242.98834) (xy 91.368189 -243.033403) (xy 91.337616 -243.074089) (xy 91.300912 -243.109344)
			(xy 91.259028 -243.138254) (xy 91.213049 -243.160071) (xy 91.164165 -243.174231) (xy 91.113644 -243.180365)
			(xy 91.062792 -243.178316) (xy 91.012928 -243.168136) (xy 90.965342 -243.150089) (xy 90.921268 -243.124643)
			(xy 90.881846 -243.092456) (xy 90.848098 -243.054362) (xy 90.820897 -243.011348) (xy 90.800949 -242.964528)
			(xy 90.78877 -242.915114) (xy 90.784675 -242.864386) (xy 90.466418 -242.864386) (xy 90.465923 -242.888993)
			(xy 90.458028 -242.93757) (xy 90.442444 -242.984251) (xy 90.419573 -243.027828) (xy 90.390008 -243.067172)
			(xy 90.354515 -243.101264) (xy 90.314012 -243.12922) (xy 90.26955 -243.150318) (xy 90.222279 -243.16401)
			(xy 90.173424 -243.169942) (xy 90.124249 -243.167961) (xy 90.07603 -243.158117) (xy 90.030014 -243.140665)
			(xy 89.987393 -243.116058) (xy 89.949272 -243.084933) (xy 89.916637 -243.048096) (xy 89.890334 -243.0065)
			(xy 89.871043 -242.961224) (xy 89.859266 -242.91344) (xy 89.855306 -242.864386) (xy 89.526364 -242.864386)
			(xy 89.525869 -242.888993) (xy 89.517974 -242.93757) (xy 89.50239 -242.984251) (xy 89.479519 -243.027828)
			(xy 89.449954 -243.067172) (xy 89.414461 -243.101264) (xy 89.373958 -243.12922) (xy 89.329496 -243.150318)
			(xy 89.282225 -243.16401) (xy 89.23337 -243.169942) (xy 89.184195 -243.167961) (xy 89.135976 -243.158117)
			(xy 89.08996 -243.140665) (xy 89.047339 -243.116058) (xy 89.009218 -243.084933) (xy 88.976583 -243.048096)
			(xy 88.95028 -243.0065) (xy 88.930989 -242.961224) (xy 88.919212 -242.91344) (xy 88.915252 -242.864386)
			(xy 88.58631 -242.864386) (xy 88.585815 -242.888993) (xy 88.57792 -242.93757) (xy 88.562336 -242.984251)
			(xy 88.539465 -243.027828) (xy 88.5099 -243.067172) (xy 88.474407 -243.101264) (xy 88.433904 -243.12922)
			(xy 88.389442 -243.150318) (xy 88.342171 -243.16401) (xy 88.293316 -243.169942) (xy 88.244141 -243.167961)
			(xy 88.195922 -243.158117) (xy 88.149906 -243.140665) (xy 88.107285 -243.116058) (xy 88.069164 -243.084933)
			(xy 88.036529 -243.048096) (xy 88.010226 -243.0065) (xy 87.990935 -242.961224) (xy 87.979158 -242.91344)
			(xy 87.975198 -242.864386) (xy 87.646256 -242.864386) (xy 87.645761 -242.888993) (xy 87.637866 -242.93757)
			(xy 87.622282 -242.984251) (xy 87.599411 -243.027828) (xy 87.569846 -243.067172) (xy 87.534353 -243.101264)
			(xy 87.49385 -243.12922) (xy 87.449388 -243.150318) (xy 87.402117 -243.16401) (xy 87.353262 -243.169942)
			(xy 87.304087 -243.167961) (xy 87.255868 -243.158117) (xy 87.209852 -243.140665) (xy 87.167231 -243.116058)
			(xy 87.12911 -243.084933) (xy 87.096475 -243.048096) (xy 87.070172 -243.0065) (xy 87.050881 -242.961224)
			(xy 87.039104 -242.91344) (xy 87.035144 -242.864386) (xy 86.713314 -242.864386) (xy 86.713314 -243.21897)
			(xy 86.713784 -243.228843) (xy 86.721242 -243.247127) (xy 86.727792 -243.25453) (xy 86.728046 -243.254784)
			(xy 86.784688 -243.311426) (xy 86.785196 -243.311934) (xy 86.792579 -243.318512) (xy 86.810878 -243.325949)
			(xy 86.820756 -243.326412) (xy 87.01786 -243.326412) (xy 87.027698 -243.326947) (xy 87.045861 -243.334532)
			(xy 87.053166 -243.341144) (xy 87.193882 -243.48186) (xy 87.200606 -243.489094) (xy 87.208224 -243.507299)
			(xy 87.208614 -243.517166) (xy 87.208614 -243.674392) (xy 87.505298 -243.674392) (xy 87.509258 -243.625338)
			(xy 87.521035 -243.577554) (xy 87.540326 -243.532278) (xy 87.566629 -243.490682) (xy 87.599264 -243.453845)
			(xy 87.637385 -243.42272) (xy 87.680006 -243.398113) (xy 87.726022 -243.380661) (xy 87.774241 -243.370817)
			(xy 87.823416 -243.368836) (xy 87.872271 -243.374768) (xy 87.919542 -243.38846) (xy 87.964004 -243.409558)
			(xy 88.004507 -243.437514) (xy 88.04 -243.471606) (xy 88.069565 -243.51095) (xy 88.092436 -243.554527)
			(xy 88.10802 -243.601208) (xy 88.115915 -243.649785) (xy 88.11641 -243.674392) (xy 88.445352 -243.674392)
			(xy 88.449312 -243.625338) (xy 88.461089 -243.577554) (xy 88.48038 -243.532278) (xy 88.506683 -243.490682)
			(xy 88.539318 -243.453845) (xy 88.577439 -243.42272) (xy 88.62006 -243.398113) (xy 88.666076 -243.380661)
			(xy 88.714295 -243.370817) (xy 88.76347 -243.368836) (xy 88.812325 -243.374768) (xy 88.859596 -243.38846)
			(xy 88.904058 -243.409558) (xy 88.944561 -243.437514) (xy 88.980054 -243.471606) (xy 89.009619 -243.51095)
			(xy 89.03249 -243.554527) (xy 89.048074 -243.601208) (xy 89.055969 -243.649785) (xy 89.056464 -243.674392)
			(xy 89.385152 -243.674392) (xy 89.389112 -243.625338) (xy 89.400889 -243.577554) (xy 89.42018 -243.532278)
			(xy 89.446483 -243.490682) (xy 89.479118 -243.453845) (xy 89.517239 -243.42272) (xy 89.55986 -243.398113)
			(xy 89.605876 -243.380661) (xy 89.654095 -243.370817) (xy 89.70327 -243.368836) (xy 89.752125 -243.374768)
			(xy 89.799396 -243.38846) (xy 89.843858 -243.409558) (xy 89.884361 -243.437514) (xy 89.919854 -243.471606)
			(xy 89.949419 -243.51095) (xy 89.97229 -243.554527) (xy 89.987874 -243.601208) (xy 89.995769 -243.649785)
			(xy 89.996264 -243.674392) (xy 90.314775 -243.674392) (xy 90.31887 -243.623664) (xy 90.331049 -243.57425)
			(xy 90.350997 -243.52743) (xy 90.378198 -243.484416) (xy 90.411946 -243.446322) (xy 90.451368 -243.414135)
			(xy 90.495442 -243.388689) (xy 90.543028 -243.370642) (xy 90.592892 -243.360462) (xy 90.643744 -243.358413)
			(xy 90.694265 -243.364547) (xy 90.743149 -243.378707) (xy 90.789128 -243.400524) (xy 90.831012 -243.429434)
			(xy 90.867716 -243.464689) (xy 90.898289 -243.505375) (xy 90.92194 -243.550438) (xy 90.938056 -243.598712)
			(xy 90.94622 -243.648946) (xy 90.946732 -243.674392) (xy 91.26526 -243.674392) (xy 91.26922 -243.625338)
			(xy 91.280997 -243.577554) (xy 91.300288 -243.532278) (xy 91.326591 -243.490682) (xy 91.359226 -243.453845)
			(xy 91.397347 -243.42272) (xy 91.439968 -243.398113) (xy 91.485984 -243.380661) (xy 91.534203 -243.370817)
			(xy 91.583378 -243.368836) (xy 91.632233 -243.374768) (xy 91.679504 -243.38846) (xy 91.723966 -243.409558)
			(xy 91.764469 -243.437514) (xy 91.799962 -243.471606) (xy 91.829527 -243.51095) (xy 91.852398 -243.554527)
			(xy 91.867982 -243.601208) (xy 91.875877 -243.649785) (xy 91.876372 -243.674392) (xy 92.194883 -243.674392)
			(xy 92.198978 -243.623664) (xy 92.211157 -243.57425) (xy 92.231105 -243.52743) (xy 92.258306 -243.484416)
			(xy 92.292054 -243.446322) (xy 92.331476 -243.414135) (xy 92.37555 -243.388689) (xy 92.423136 -243.370642)
			(xy 92.473 -243.360462) (xy 92.523852 -243.358413) (xy 92.574373 -243.364547) (xy 92.623257 -243.378707)
			(xy 92.669236 -243.400524) (xy 92.71112 -243.429434) (xy 92.747824 -243.464689) (xy 92.778397 -243.505375)
			(xy 92.802048 -243.550438) (xy 92.818164 -243.598712) (xy 92.826328 -243.648946) (xy 92.82684 -243.674392)
			(xy 93.145114 -243.674392) (xy 93.149074 -243.625338) (xy 93.160851 -243.577554) (xy 93.180142 -243.532278)
			(xy 93.206445 -243.490682) (xy 93.23908 -243.453845) (xy 93.277201 -243.42272) (xy 93.319822 -243.398113)
			(xy 93.365838 -243.380661) (xy 93.414057 -243.370817) (xy 93.463232 -243.368836) (xy 93.512087 -243.374768)
			(xy 93.559358 -243.38846) (xy 93.60382 -243.409558) (xy 93.644323 -243.437514) (xy 93.679816 -243.471606)
			(xy 93.709381 -243.51095) (xy 93.732252 -243.554527) (xy 93.747836 -243.601208) (xy 93.755731 -243.649785)
			(xy 93.756226 -243.674392) (xy 94.074737 -243.674392) (xy 94.078832 -243.623664) (xy 94.091011 -243.57425)
			(xy 94.110959 -243.52743) (xy 94.13816 -243.484416) (xy 94.171908 -243.446322) (xy 94.21133 -243.414135)
			(xy 94.255404 -243.388689) (xy 94.30299 -243.370642) (xy 94.352854 -243.360462) (xy 94.403706 -243.358413)
			(xy 94.454227 -243.364547) (xy 94.503111 -243.378707) (xy 94.54909 -243.400524) (xy 94.590974 -243.429434)
			(xy 94.627678 -243.464689) (xy 94.658251 -243.505375) (xy 94.681902 -243.550438) (xy 94.698018 -243.598712)
			(xy 94.706182 -243.648946) (xy 94.706694 -243.674392) (xy 94.706182 -243.699838) (xy 94.698018 -243.750072)
			(xy 94.681902 -243.798346) (xy 94.658251 -243.843409) (xy 94.627678 -243.884095) (xy 94.590974 -243.91935)
			(xy 94.54909 -243.94826) (xy 94.503111 -243.970077) (xy 94.454227 -243.984237) (xy 94.403706 -243.990371)
			(xy 94.352854 -243.988322) (xy 94.30299 -243.978142) (xy 94.255404 -243.960095) (xy 94.21133 -243.934649)
			(xy 94.171908 -243.902462) (xy 94.13816 -243.864368) (xy 94.110959 -243.821354) (xy 94.091011 -243.774534)
			(xy 94.078832 -243.72512) (xy 94.074737 -243.674392) (xy 93.756226 -243.674392) (xy 93.755731 -243.698999)
			(xy 93.747836 -243.747576) (xy 93.732252 -243.794257) (xy 93.709381 -243.837834) (xy 93.679816 -243.877178)
			(xy 93.644323 -243.91127) (xy 93.60382 -243.939226) (xy 93.559358 -243.960324) (xy 93.512087 -243.974016)
			(xy 93.463232 -243.979948) (xy 93.414057 -243.977967) (xy 93.365838 -243.968123) (xy 93.319822 -243.950671)
			(xy 93.277201 -243.926064) (xy 93.23908 -243.894939) (xy 93.206445 -243.858102) (xy 93.180142 -243.816506)
			(xy 93.160851 -243.77123) (xy 93.149074 -243.723446) (xy 93.145114 -243.674392) (xy 92.82684 -243.674392)
			(xy 92.826328 -243.699838) (xy 92.818164 -243.750072) (xy 92.802048 -243.798346) (xy 92.778397 -243.843409)
			(xy 92.747824 -243.884095) (xy 92.71112 -243.91935) (xy 92.669236 -243.94826) (xy 92.623257 -243.970077)
			(xy 92.574373 -243.984237) (xy 92.523852 -243.990371) (xy 92.473 -243.988322) (xy 92.423136 -243.978142)
			(xy 92.37555 -243.960095) (xy 92.331476 -243.934649) (xy 92.292054 -243.902462) (xy 92.258306 -243.864368)
			(xy 92.231105 -243.821354) (xy 92.211157 -243.774534) (xy 92.198978 -243.72512) (xy 92.194883 -243.674392)
			(xy 91.876372 -243.674392) (xy 91.875877 -243.698999) (xy 91.867982 -243.747576) (xy 91.852398 -243.794257)
			(xy 91.829527 -243.837834) (xy 91.799962 -243.877178) (xy 91.764469 -243.91127) (xy 91.723966 -243.939226)
			(xy 91.679504 -243.960324) (xy 91.632233 -243.974016) (xy 91.583378 -243.979948) (xy 91.534203 -243.977967)
			(xy 91.485984 -243.968123) (xy 91.439968 -243.950671) (xy 91.397347 -243.926064) (xy 91.359226 -243.894939)
			(xy 91.326591 -243.858102) (xy 91.300288 -243.816506) (xy 91.280997 -243.77123) (xy 91.26922 -243.723446)
			(xy 91.26526 -243.674392) (xy 90.946732 -243.674392) (xy 90.94622 -243.699838) (xy 90.938056 -243.750072)
			(xy 90.92194 -243.798346) (xy 90.898289 -243.843409) (xy 90.867716 -243.884095) (xy 90.831012 -243.91935)
			(xy 90.789128 -243.94826) (xy 90.743149 -243.970077) (xy 90.694265 -243.984237) (xy 90.643744 -243.990371)
			(xy 90.592892 -243.988322) (xy 90.543028 -243.978142) (xy 90.495442 -243.960095) (xy 90.451368 -243.934649)
			(xy 90.411946 -243.902462) (xy 90.378198 -243.864368) (xy 90.350997 -243.821354) (xy 90.331049 -243.774534)
			(xy 90.31887 -243.72512) (xy 90.314775 -243.674392) (xy 89.996264 -243.674392) (xy 89.995769 -243.698999)
			(xy 89.987874 -243.747576) (xy 89.97229 -243.794257) (xy 89.949419 -243.837834) (xy 89.919854 -243.877178)
			(xy 89.884361 -243.91127) (xy 89.843858 -243.939226) (xy 89.799396 -243.960324) (xy 89.752125 -243.974016)
			(xy 89.70327 -243.979948) (xy 89.654095 -243.977967) (xy 89.605876 -243.968123) (xy 89.55986 -243.950671)
			(xy 89.517239 -243.926064) (xy 89.479118 -243.894939) (xy 89.446483 -243.858102) (xy 89.42018 -243.816506)
			(xy 89.400889 -243.77123) (xy 89.389112 -243.723446) (xy 89.385152 -243.674392) (xy 89.056464 -243.674392)
			(xy 89.055969 -243.698999) (xy 89.048074 -243.747576) (xy 89.03249 -243.794257) (xy 89.009619 -243.837834)
			(xy 88.980054 -243.877178) (xy 88.944561 -243.91127) (xy 88.904058 -243.939226) (xy 88.859596 -243.960324)
			(xy 88.812325 -243.974016) (xy 88.76347 -243.979948) (xy 88.714295 -243.977967) (xy 88.666076 -243.968123)
			(xy 88.62006 -243.950671) (xy 88.577439 -243.926064) (xy 88.539318 -243.894939) (xy 88.506683 -243.858102)
			(xy 88.48038 -243.816506) (xy 88.461089 -243.77123) (xy 88.449312 -243.723446) (xy 88.445352 -243.674392)
			(xy 88.11641 -243.674392) (xy 88.115915 -243.698999) (xy 88.10802 -243.747576) (xy 88.092436 -243.794257)
			(xy 88.069565 -243.837834) (xy 88.04 -243.877178) (xy 88.004507 -243.91127) (xy 87.964004 -243.939226)
			(xy 87.919542 -243.960324) (xy 87.872271 -243.974016) (xy 87.823416 -243.979948) (xy 87.774241 -243.977967)
			(xy 87.726022 -243.968123) (xy 87.680006 -243.950671) (xy 87.637385 -243.926064) (xy 87.599264 -243.894939)
			(xy 87.566629 -243.858102) (xy 87.540326 -243.816506) (xy 87.521035 -243.77123) (xy 87.509258 -243.723446)
			(xy 87.505298 -243.674392) (xy 87.208614 -243.674392) (xy 87.208614 -243.742718) (xy 87.208088 -243.75256)
			(xy 87.200516 -243.770736) (xy 87.193882 -243.778024) (xy 87.122508 -243.849398) (xy 87.118698 -243.852954)
			(xy 87.116158 -243.856764) (xy 87.115396 -243.85778) (xy 87.101998 -243.874943) (xy 87.071144 -243.905664)
			(xy 87.053928 -243.918994) (xy 87.052404 -243.92001) (xy 87.047324 -243.924582) (xy 86.855046 -244.11686)
			(xy 86.84833 -244.124097) (xy 86.840723 -244.142302) (xy 86.840314 -244.152166) (xy 86.840314 -244.484398)
			(xy 87.035144 -244.484398) (xy 87.039104 -244.435344) (xy 87.050881 -244.38756) (xy 87.070172 -244.342284)
			(xy 87.096475 -244.300688) (xy 87.12911 -244.263851) (xy 87.167231 -244.232726) (xy 87.209852 -244.208119)
			(xy 87.255868 -244.190667) (xy 87.304087 -244.180823) (xy 87.353262 -244.178842) (xy 87.402117 -244.184774)
			(xy 87.449388 -244.198466) (xy 87.49385 -244.219564) (xy 87.534353 -244.24752) (xy 87.569846 -244.281612)
			(xy 87.599411 -244.320956) (xy 87.622282 -244.364533) (xy 87.637866 -244.411214) (xy 87.645761 -244.459791)
			(xy 87.646256 -244.484398) (xy 87.975198 -244.484398) (xy 87.979158 -244.435344) (xy 87.990935 -244.38756)
			(xy 88.010226 -244.342284) (xy 88.036529 -244.300688) (xy 88.069164 -244.263851) (xy 88.107285 -244.232726)
			(xy 88.149906 -244.208119) (xy 88.195922 -244.190667) (xy 88.244141 -244.180823) (xy 88.293316 -244.178842)
			(xy 88.342171 -244.184774) (xy 88.389442 -244.198466) (xy 88.433904 -244.219564) (xy 88.474407 -244.24752)
			(xy 88.5099 -244.281612) (xy 88.539465 -244.320956) (xy 88.562336 -244.364533) (xy 88.57792 -244.411214)
			(xy 88.585815 -244.459791) (xy 88.58631 -244.484398) (xy 88.915252 -244.484398) (xy 88.919212 -244.435344)
			(xy 88.930989 -244.38756) (xy 88.95028 -244.342284) (xy 88.976583 -244.300688) (xy 89.009218 -244.263851)
			(xy 89.047339 -244.232726) (xy 89.08996 -244.208119) (xy 89.135976 -244.190667) (xy 89.184195 -244.180823)
			(xy 89.23337 -244.178842) (xy 89.282225 -244.184774) (xy 89.329496 -244.198466) (xy 89.373958 -244.219564)
			(xy 89.414461 -244.24752) (xy 89.449954 -244.281612) (xy 89.479519 -244.320956) (xy 89.50239 -244.364533)
			(xy 89.517974 -244.411214) (xy 89.525869 -244.459791) (xy 89.526364 -244.484398) (xy 89.855306 -244.484398)
			(xy 89.859266 -244.435344) (xy 89.871043 -244.38756) (xy 89.890334 -244.342284) (xy 89.916637 -244.300688)
			(xy 89.949272 -244.263851) (xy 89.987393 -244.232726) (xy 90.030014 -244.208119) (xy 90.07603 -244.190667)
			(xy 90.124249 -244.180823) (xy 90.173424 -244.178842) (xy 90.222279 -244.184774) (xy 90.26955 -244.198466)
			(xy 90.314012 -244.219564) (xy 90.354515 -244.24752) (xy 90.390008 -244.281612) (xy 90.419573 -244.320956)
			(xy 90.442444 -244.364533) (xy 90.458028 -244.411214) (xy 90.465923 -244.459791) (xy 90.466418 -244.484398)
			(xy 90.784675 -244.484398) (xy 90.78877 -244.43367) (xy 90.800949 -244.384256) (xy 90.820897 -244.337436)
			(xy 90.848098 -244.294422) (xy 90.881846 -244.256328) (xy 90.921268 -244.224141) (xy 90.965342 -244.198695)
			(xy 91.012928 -244.180648) (xy 91.062792 -244.170468) (xy 91.113644 -244.168419) (xy 91.164165 -244.174553)
			(xy 91.213049 -244.188713) (xy 91.259028 -244.21053) (xy 91.300912 -244.23944) (xy 91.337616 -244.274695)
			(xy 91.368189 -244.315381) (xy 91.39184 -244.360444) (xy 91.407956 -244.408718) (xy 91.41612 -244.458952)
			(xy 91.416632 -244.484398) (xy 91.724729 -244.484398) (xy 91.728824 -244.43367) (xy 91.741003 -244.384256)
			(xy 91.760951 -244.337436) (xy 91.788152 -244.294422) (xy 91.8219 -244.256328) (xy 91.861322 -244.224141)
			(xy 91.905396 -244.198695) (xy 91.952982 -244.180648) (xy 92.002846 -244.170468) (xy 92.053698 -244.168419)
			(xy 92.104219 -244.174553) (xy 92.153103 -244.188713) (xy 92.199082 -244.21053) (xy 92.240966 -244.23944)
			(xy 92.27767 -244.274695) (xy 92.308243 -244.315381) (xy 92.331894 -244.360444) (xy 92.34801 -244.408718)
			(xy 92.356174 -244.458952) (xy 92.356686 -244.484398) (xy 92.675214 -244.484398) (xy 92.679174 -244.435344)
			(xy 92.690951 -244.38756) (xy 92.710242 -244.342284) (xy 92.736545 -244.300688) (xy 92.76918 -244.263851)
			(xy 92.807301 -244.232726) (xy 92.849922 -244.208119) (xy 92.895938 -244.190667) (xy 92.944157 -244.180823)
			(xy 92.993332 -244.178842) (xy 93.042187 -244.184774) (xy 93.089458 -244.198466) (xy 93.13392 -244.219564)
			(xy 93.174423 -244.24752) (xy 93.209916 -244.281612) (xy 93.239481 -244.320956) (xy 93.262352 -244.364533)
			(xy 93.277936 -244.411214) (xy 93.285831 -244.459791) (xy 93.286326 -244.484398) (xy 93.604837 -244.484398)
			(xy 93.608932 -244.43367) (xy 93.621111 -244.384256) (xy 93.641059 -244.337436) (xy 93.66826 -244.294422)
			(xy 93.702008 -244.256328) (xy 93.74143 -244.224141) (xy 93.785504 -244.198695) (xy 93.83309 -244.180648)
			(xy 93.882954 -244.170468) (xy 93.933806 -244.168419) (xy 93.984327 -244.174553) (xy 94.033211 -244.188713)
			(xy 94.07919 -244.21053) (xy 94.121074 -244.23944) (xy 94.157778 -244.274695) (xy 94.188351 -244.315381)
			(xy 94.212002 -244.360444) (xy 94.228118 -244.408718) (xy 94.236282 -244.458952) (xy 94.236794 -244.484398)
			(xy 94.555322 -244.484398) (xy 94.559282 -244.435344) (xy 94.571059 -244.38756) (xy 94.59035 -244.342284)
			(xy 94.616653 -244.300688) (xy 94.649288 -244.263851) (xy 94.687409 -244.232726) (xy 94.73003 -244.208119)
			(xy 94.776046 -244.190667) (xy 94.824265 -244.180823) (xy 94.87344 -244.178842) (xy 94.922295 -244.184774)
			(xy 94.969566 -244.198466) (xy 95.014028 -244.219564) (xy 95.054531 -244.24752) (xy 95.090024 -244.281612)
			(xy 95.119589 -244.320956) (xy 95.14246 -244.364533) (xy 95.158044 -244.411214) (xy 95.165939 -244.459791)
			(xy 95.166434 -244.484398) (xy 95.165939 -244.509005) (xy 95.158044 -244.557582) (xy 95.14246 -244.604263)
			(xy 95.119589 -244.64784) (xy 95.090024 -244.687184) (xy 95.054531 -244.721276) (xy 95.014028 -244.749232)
			(xy 94.969566 -244.77033) (xy 94.922295 -244.784022) (xy 94.87344 -244.789954) (xy 94.824265 -244.787973)
			(xy 94.776046 -244.778129) (xy 94.73003 -244.760677) (xy 94.687409 -244.73607) (xy 94.649288 -244.704945)
			(xy 94.616653 -244.668108) (xy 94.59035 -244.626512) (xy 94.571059 -244.581236) (xy 94.559282 -244.533452)
			(xy 94.555322 -244.484398) (xy 94.236794 -244.484398) (xy 94.236282 -244.509844) (xy 94.228118 -244.560078)
			(xy 94.212002 -244.608352) (xy 94.188351 -244.653415) (xy 94.157778 -244.694101) (xy 94.121074 -244.729356)
			(xy 94.07919 -244.758266) (xy 94.033211 -244.780083) (xy 93.984327 -244.794243) (xy 93.933806 -244.800377)
			(xy 93.882954 -244.798328) (xy 93.83309 -244.788148) (xy 93.785504 -244.770101) (xy 93.74143 -244.744655)
			(xy 93.702008 -244.712468) (xy 93.66826 -244.674374) (xy 93.641059 -244.63136) (xy 93.621111 -244.58454)
			(xy 93.608932 -244.535126) (xy 93.604837 -244.484398) (xy 93.286326 -244.484398) (xy 93.285831 -244.509005)
			(xy 93.277936 -244.557582) (xy 93.262352 -244.604263) (xy 93.239481 -244.64784) (xy 93.209916 -244.687184)
			(xy 93.174423 -244.721276) (xy 93.13392 -244.749232) (xy 93.089458 -244.77033) (xy 93.042187 -244.784022)
			(xy 92.993332 -244.789954) (xy 92.944157 -244.787973) (xy 92.895938 -244.778129) (xy 92.849922 -244.760677)
			(xy 92.807301 -244.73607) (xy 92.76918 -244.704945) (xy 92.736545 -244.668108) (xy 92.710242 -244.626512)
			(xy 92.690951 -244.581236) (xy 92.679174 -244.533452) (xy 92.675214 -244.484398) (xy 92.356686 -244.484398)
			(xy 92.356174 -244.509844) (xy 92.34801 -244.560078) (xy 92.331894 -244.608352) (xy 92.308243 -244.653415)
			(xy 92.27767 -244.694101) (xy 92.240966 -244.729356) (xy 92.199082 -244.758266) (xy 92.153103 -244.780083)
			(xy 92.104219 -244.794243) (xy 92.053698 -244.800377) (xy 92.002846 -244.798328) (xy 91.952982 -244.788148)
			(xy 91.905396 -244.770101) (xy 91.861322 -244.744655) (xy 91.8219 -244.712468) (xy 91.788152 -244.674374)
			(xy 91.760951 -244.63136) (xy 91.741003 -244.58454) (xy 91.728824 -244.535126) (xy 91.724729 -244.484398)
			(xy 91.416632 -244.484398) (xy 91.41612 -244.509844) (xy 91.407956 -244.560078) (xy 91.39184 -244.608352)
			(xy 91.368189 -244.653415) (xy 91.337616 -244.694101) (xy 91.300912 -244.729356) (xy 91.259028 -244.758266)
			(xy 91.213049 -244.780083) (xy 91.164165 -244.794243) (xy 91.113644 -244.800377) (xy 91.062792 -244.798328)
			(xy 91.012928 -244.788148) (xy 90.965342 -244.770101) (xy 90.921268 -244.744655) (xy 90.881846 -244.712468)
			(xy 90.848098 -244.674374) (xy 90.820897 -244.63136) (xy 90.800949 -244.58454) (xy 90.78877 -244.535126)
			(xy 90.784675 -244.484398) (xy 90.466418 -244.484398) (xy 90.465923 -244.509005) (xy 90.458028 -244.557582)
			(xy 90.442444 -244.604263) (xy 90.419573 -244.64784) (xy 90.390008 -244.687184) (xy 90.354515 -244.721276)
			(xy 90.314012 -244.749232) (xy 90.26955 -244.77033) (xy 90.222279 -244.784022) (xy 90.173424 -244.789954)
			(xy 90.124249 -244.787973) (xy 90.07603 -244.778129) (xy 90.030014 -244.760677) (xy 89.987393 -244.73607)
			(xy 89.949272 -244.704945) (xy 89.916637 -244.668108) (xy 89.890334 -244.626512) (xy 89.871043 -244.581236)
			(xy 89.859266 -244.533452) (xy 89.855306 -244.484398) (xy 89.526364 -244.484398) (xy 89.525869 -244.509005)
			(xy 89.517974 -244.557582) (xy 89.50239 -244.604263) (xy 89.479519 -244.64784) (xy 89.449954 -244.687184)
			(xy 89.414461 -244.721276) (xy 89.373958 -244.749232) (xy 89.329496 -244.77033) (xy 89.282225 -244.784022)
			(xy 89.23337 -244.789954) (xy 89.184195 -244.787973) (xy 89.135976 -244.778129) (xy 89.08996 -244.760677)
			(xy 89.047339 -244.73607) (xy 89.009218 -244.704945) (xy 88.976583 -244.668108) (xy 88.95028 -244.626512)
			(xy 88.930989 -244.581236) (xy 88.919212 -244.533452) (xy 88.915252 -244.484398) (xy 88.58631 -244.484398)
			(xy 88.585815 -244.509005) (xy 88.57792 -244.557582) (xy 88.562336 -244.604263) (xy 88.539465 -244.64784)
			(xy 88.5099 -244.687184) (xy 88.474407 -244.721276) (xy 88.433904 -244.749232) (xy 88.389442 -244.77033)
			(xy 88.342171 -244.784022) (xy 88.293316 -244.789954) (xy 88.244141 -244.787973) (xy 88.195922 -244.778129)
			(xy 88.149906 -244.760677) (xy 88.107285 -244.73607) (xy 88.069164 -244.704945) (xy 88.036529 -244.668108)
			(xy 88.010226 -244.626512) (xy 87.990935 -244.581236) (xy 87.979158 -244.533452) (xy 87.975198 -244.484398)
			(xy 87.646256 -244.484398) (xy 87.645761 -244.509005) (xy 87.637866 -244.557582) (xy 87.622282 -244.604263)
			(xy 87.599411 -244.64784) (xy 87.569846 -244.687184) (xy 87.534353 -244.721276) (xy 87.49385 -244.749232)
			(xy 87.449388 -244.77033) (xy 87.402117 -244.784022) (xy 87.353262 -244.789954) (xy 87.304087 -244.787973)
			(xy 87.255868 -244.778129) (xy 87.209852 -244.760677) (xy 87.167231 -244.73607) (xy 87.12911 -244.704945)
			(xy 87.096475 -244.668108) (xy 87.070172 -244.626512) (xy 87.050881 -244.581236) (xy 87.039104 -244.533452)
			(xy 87.035144 -244.484398) (xy 86.840314 -244.484398) (xy 86.840314 -244.72265) (xy 86.84078 -244.732524)
			(xy 86.848233 -244.750813) (xy 86.854792 -244.75821) (xy 86.855046 -244.758464) (xy 87.193882 -245.0973)
			(xy 87.2006 -245.104536) (xy 87.208204 -245.122741) (xy 87.208614 -245.132606) (xy 87.208614 -245.294404)
			(xy 87.505298 -245.294404) (xy 87.509258 -245.24535) (xy 87.521035 -245.197566) (xy 87.540326 -245.15229)
			(xy 87.566629 -245.110694) (xy 87.599264 -245.073857) (xy 87.637385 -245.042732) (xy 87.680006 -245.018125)
			(xy 87.726022 -245.000673) (xy 87.774241 -244.990829) (xy 87.823416 -244.988848) (xy 87.872271 -244.99478)
			(xy 87.919542 -245.008472) (xy 87.964004 -245.02957) (xy 88.004507 -245.057526) (xy 88.04 -245.091618)
			(xy 88.069565 -245.130962) (xy 88.092436 -245.174539) (xy 88.10802 -245.22122) (xy 88.115915 -245.269797)
			(xy 88.11641 -245.294404) (xy 88.445352 -245.294404) (xy 88.449312 -245.24535) (xy 88.461089 -245.197566)
			(xy 88.48038 -245.15229) (xy 88.506683 -245.110694) (xy 88.539318 -245.073857) (xy 88.577439 -245.042732)
			(xy 88.62006 -245.018125) (xy 88.666076 -245.000673) (xy 88.714295 -244.990829) (xy 88.76347 -244.988848)
			(xy 88.812325 -244.99478) (xy 88.859596 -245.008472) (xy 88.904058 -245.02957) (xy 88.944561 -245.057526)
			(xy 88.980054 -245.091618) (xy 89.009619 -245.130962) (xy 89.03249 -245.174539) (xy 89.048074 -245.22122)
			(xy 89.055969 -245.269797) (xy 89.056464 -245.294404) (xy 89.385152 -245.294404) (xy 89.389112 -245.24535)
			(xy 89.400889 -245.197566) (xy 89.42018 -245.15229) (xy 89.446483 -245.110694) (xy 89.479118 -245.073857)
			(xy 89.517239 -245.042732) (xy 89.55986 -245.018125) (xy 89.605876 -245.000673) (xy 89.654095 -244.990829)
			(xy 89.70327 -244.988848) (xy 89.752125 -244.99478) (xy 89.799396 -245.008472) (xy 89.843858 -245.02957)
			(xy 89.884361 -245.057526) (xy 89.919854 -245.091618) (xy 89.949419 -245.130962) (xy 89.97229 -245.174539)
			(xy 89.987874 -245.22122) (xy 89.995769 -245.269797) (xy 89.996264 -245.294404) (xy 90.314775 -245.294404)
			(xy 90.31887 -245.243676) (xy 90.331049 -245.194262) (xy 90.350997 -245.147442) (xy 90.378198 -245.104428)
			(xy 90.411946 -245.066334) (xy 90.451368 -245.034147) (xy 90.495442 -245.008701) (xy 90.543028 -244.990654)
			(xy 90.592892 -244.980474) (xy 90.643744 -244.978425) (xy 90.694265 -244.984559) (xy 90.743149 -244.998719)
			(xy 90.789128 -245.020536) (xy 90.831012 -245.049446) (xy 90.867716 -245.084701) (xy 90.898289 -245.125387)
			(xy 90.92194 -245.17045) (xy 90.938056 -245.218724) (xy 90.94622 -245.268958) (xy 90.946732 -245.294404)
			(xy 91.26526 -245.294404) (xy 91.26922 -245.24535) (xy 91.280997 -245.197566) (xy 91.300288 -245.15229)
			(xy 91.326591 -245.110694) (xy 91.359226 -245.073857) (xy 91.397347 -245.042732) (xy 91.439968 -245.018125)
			(xy 91.485984 -245.000673) (xy 91.534203 -244.990829) (xy 91.583378 -244.988848) (xy 91.632233 -244.99478)
			(xy 91.679504 -245.008472) (xy 91.723966 -245.02957) (xy 91.764469 -245.057526) (xy 91.799962 -245.091618)
			(xy 91.829527 -245.130962) (xy 91.852398 -245.174539) (xy 91.867982 -245.22122) (xy 91.875877 -245.269797)
			(xy 91.876372 -245.294404) (xy 92.194883 -245.294404) (xy 92.198978 -245.243676) (xy 92.211157 -245.194262)
			(xy 92.231105 -245.147442) (xy 92.258306 -245.104428) (xy 92.292054 -245.066334) (xy 92.331476 -245.034147)
			(xy 92.37555 -245.008701) (xy 92.423136 -244.990654) (xy 92.473 -244.980474) (xy 92.523852 -244.978425)
			(xy 92.574373 -244.984559) (xy 92.623257 -244.998719) (xy 92.669236 -245.020536) (xy 92.71112 -245.049446)
			(xy 92.747824 -245.084701) (xy 92.778397 -245.125387) (xy 92.802048 -245.17045) (xy 92.818164 -245.218724)
			(xy 92.826328 -245.268958) (xy 92.82684 -245.294404) (xy 93.145114 -245.294404) (xy 93.149074 -245.24535)
			(xy 93.160851 -245.197566) (xy 93.180142 -245.15229) (xy 93.206445 -245.110694) (xy 93.23908 -245.073857)
			(xy 93.277201 -245.042732) (xy 93.319822 -245.018125) (xy 93.365838 -245.000673) (xy 93.414057 -244.990829)
			(xy 93.463232 -244.988848) (xy 93.512087 -244.99478) (xy 93.559358 -245.008472) (xy 93.60382 -245.02957)
			(xy 93.644323 -245.057526) (xy 93.679816 -245.091618) (xy 93.709381 -245.130962) (xy 93.732252 -245.174539)
			(xy 93.747836 -245.22122) (xy 93.755731 -245.269797) (xy 93.756226 -245.294404) (xy 94.074737 -245.294404)
			(xy 94.078832 -245.243676) (xy 94.091011 -245.194262) (xy 94.110959 -245.147442) (xy 94.13816 -245.104428)
			(xy 94.171908 -245.066334) (xy 94.21133 -245.034147) (xy 94.255404 -245.008701) (xy 94.30299 -244.990654)
			(xy 94.352854 -244.980474) (xy 94.403706 -244.978425) (xy 94.454227 -244.984559) (xy 94.503111 -244.998719)
			(xy 94.54909 -245.020536) (xy 94.590974 -245.049446) (xy 94.627678 -245.084701) (xy 94.658251 -245.125387)
			(xy 94.681902 -245.17045) (xy 94.698018 -245.218724) (xy 94.706182 -245.268958) (xy 94.706694 -245.294404)
			(xy 95.014791 -245.294404) (xy 95.018886 -245.243676) (xy 95.031065 -245.194262) (xy 95.051013 -245.147442)
			(xy 95.078214 -245.104428) (xy 95.111962 -245.066334) (xy 95.151384 -245.034147) (xy 95.195458 -245.008701)
			(xy 95.243044 -244.990654) (xy 95.292908 -244.980474) (xy 95.34376 -244.978425) (xy 95.394281 -244.984559)
			(xy 95.443165 -244.998719) (xy 95.489144 -245.020536) (xy 95.531028 -245.049446) (xy 95.567732 -245.084701)
			(xy 95.598305 -245.125387) (xy 95.621956 -245.17045) (xy 95.638072 -245.218724) (xy 95.646236 -245.268958)
			(xy 95.646748 -245.294404) (xy 95.646236 -245.31985) (xy 95.638072 -245.370084) (xy 95.621956 -245.418358)
			(xy 95.598305 -245.463421) (xy 95.567732 -245.504107) (xy 95.531028 -245.539362) (xy 95.489144 -245.568272)
			(xy 95.443165 -245.590089) (xy 95.394281 -245.604249) (xy 95.34376 -245.610383) (xy 95.292908 -245.608334)
			(xy 95.243044 -245.598154) (xy 95.195458 -245.580107) (xy 95.151384 -245.554661) (xy 95.111962 -245.522474)
			(xy 95.078214 -245.48438) (xy 95.051013 -245.441366) (xy 95.031065 -245.394546) (xy 95.018886 -245.345132)
			(xy 95.014791 -245.294404) (xy 94.706694 -245.294404) (xy 94.706182 -245.31985) (xy 94.698018 -245.370084)
			(xy 94.681902 -245.418358) (xy 94.658251 -245.463421) (xy 94.627678 -245.504107) (xy 94.590974 -245.539362)
			(xy 94.54909 -245.568272) (xy 94.503111 -245.590089) (xy 94.454227 -245.604249) (xy 94.403706 -245.610383)
			(xy 94.352854 -245.608334) (xy 94.30299 -245.598154) (xy 94.255404 -245.580107) (xy 94.21133 -245.554661)
			(xy 94.171908 -245.522474) (xy 94.13816 -245.48438) (xy 94.110959 -245.441366) (xy 94.091011 -245.394546)
			(xy 94.078832 -245.345132) (xy 94.074737 -245.294404) (xy 93.756226 -245.294404) (xy 93.755731 -245.319011)
			(xy 93.747836 -245.367588) (xy 93.732252 -245.414269) (xy 93.709381 -245.457846) (xy 93.679816 -245.49719)
			(xy 93.644323 -245.531282) (xy 93.60382 -245.559238) (xy 93.559358 -245.580336) (xy 93.512087 -245.594028)
			(xy 93.463232 -245.59996) (xy 93.414057 -245.597979) (xy 93.365838 -245.588135) (xy 93.319822 -245.570683)
			(xy 93.277201 -245.546076) (xy 93.23908 -245.514951) (xy 93.206445 -245.478114) (xy 93.180142 -245.436518)
			(xy 93.160851 -245.391242) (xy 93.149074 -245.343458) (xy 93.145114 -245.294404) (xy 92.82684 -245.294404)
			(xy 92.826328 -245.31985) (xy 92.818164 -245.370084) (xy 92.802048 -245.418358) (xy 92.778397 -245.463421)
			(xy 92.747824 -245.504107) (xy 92.71112 -245.539362) (xy 92.669236 -245.568272) (xy 92.623257 -245.590089)
			(xy 92.574373 -245.604249) (xy 92.523852 -245.610383) (xy 92.473 -245.608334) (xy 92.423136 -245.598154)
			(xy 92.37555 -245.580107) (xy 92.331476 -245.554661) (xy 92.292054 -245.522474) (xy 92.258306 -245.48438)
			(xy 92.231105 -245.441366) (xy 92.211157 -245.394546) (xy 92.198978 -245.345132) (xy 92.194883 -245.294404)
			(xy 91.876372 -245.294404) (xy 91.875877 -245.319011) (xy 91.867982 -245.367588) (xy 91.852398 -245.414269)
			(xy 91.829527 -245.457846) (xy 91.799962 -245.49719) (xy 91.764469 -245.531282) (xy 91.723966 -245.559238)
			(xy 91.679504 -245.580336) (xy 91.632233 -245.594028) (xy 91.583378 -245.59996) (xy 91.534203 -245.597979)
			(xy 91.485984 -245.588135) (xy 91.439968 -245.570683) (xy 91.397347 -245.546076) (xy 91.359226 -245.514951)
			(xy 91.326591 -245.478114) (xy 91.300288 -245.436518) (xy 91.280997 -245.391242) (xy 91.26922 -245.343458)
			(xy 91.26526 -245.294404) (xy 90.946732 -245.294404) (xy 90.94622 -245.31985) (xy 90.938056 -245.370084)
			(xy 90.92194 -245.418358) (xy 90.898289 -245.463421) (xy 90.867716 -245.504107) (xy 90.831012 -245.539362)
			(xy 90.789128 -245.568272) (xy 90.743149 -245.590089) (xy 90.694265 -245.604249) (xy 90.643744 -245.610383)
			(xy 90.592892 -245.608334) (xy 90.543028 -245.598154) (xy 90.495442 -245.580107) (xy 90.451368 -245.554661)
			(xy 90.411946 -245.522474) (xy 90.378198 -245.48438) (xy 90.350997 -245.441366) (xy 90.331049 -245.394546)
			(xy 90.31887 -245.345132) (xy 90.314775 -245.294404) (xy 89.996264 -245.294404) (xy 89.995769 -245.319011)
			(xy 89.987874 -245.367588) (xy 89.97229 -245.414269) (xy 89.949419 -245.457846) (xy 89.919854 -245.49719)
			(xy 89.884361 -245.531282) (xy 89.843858 -245.559238) (xy 89.799396 -245.580336) (xy 89.752125 -245.594028)
			(xy 89.70327 -245.59996) (xy 89.654095 -245.597979) (xy 89.605876 -245.588135) (xy 89.55986 -245.570683)
			(xy 89.517239 -245.546076) (xy 89.479118 -245.514951) (xy 89.446483 -245.478114) (xy 89.42018 -245.436518)
			(xy 89.400889 -245.391242) (xy 89.389112 -245.343458) (xy 89.385152 -245.294404) (xy 89.056464 -245.294404)
			(xy 89.055969 -245.319011) (xy 89.048074 -245.367588) (xy 89.03249 -245.414269) (xy 89.009619 -245.457846)
			(xy 88.980054 -245.49719) (xy 88.944561 -245.531282) (xy 88.904058 -245.559238) (xy 88.859596 -245.580336)
			(xy 88.812325 -245.594028) (xy 88.76347 -245.59996) (xy 88.714295 -245.597979) (xy 88.666076 -245.588135)
			(xy 88.62006 -245.570683) (xy 88.577439 -245.546076) (xy 88.539318 -245.514951) (xy 88.506683 -245.478114)
			(xy 88.48038 -245.436518) (xy 88.461089 -245.391242) (xy 88.449312 -245.343458) (xy 88.445352 -245.294404)
			(xy 88.11641 -245.294404) (xy 88.115915 -245.319011) (xy 88.10802 -245.367588) (xy 88.092436 -245.414269)
			(xy 88.069565 -245.457846) (xy 88.04 -245.49719) (xy 88.004507 -245.531282) (xy 87.964004 -245.559238)
			(xy 87.919542 -245.580336) (xy 87.872271 -245.594028) (xy 87.823416 -245.59996) (xy 87.774241 -245.597979)
			(xy 87.726022 -245.588135) (xy 87.680006 -245.570683) (xy 87.637385 -245.546076) (xy 87.599264 -245.514951)
			(xy 87.566629 -245.478114) (xy 87.540326 -245.436518) (xy 87.521035 -245.391242) (xy 87.509258 -245.343458)
			(xy 87.505298 -245.294404) (xy 87.208614 -245.294404) (xy 87.208614 -245.388638) (xy 87.208084 -245.398478)
			(xy 87.200507 -245.416649) (xy 87.193882 -245.423944) (xy 87.017606 -245.60022) (xy 87.010368 -245.606935)
			(xy 86.992164 -245.614534) (xy 86.9823 -245.614952) (xy 86.761828 -245.614952) (xy 86.755224 -245.614444)
			(xy 86.752938 -245.613936) (xy 86.741 -245.611396) (xy 86.729824 -245.613682) (xy 86.722204 -245.614952)
			(xy 86.708488 -245.622318) (xy 86.684866 -245.64594) (xy 86.67816 -245.653181) (xy 86.670579 -245.671386)
			(xy 86.670134 -245.681246) (xy 86.670134 -245.947946) (xy 86.671404 -245.953534) (xy 86.674198 -245.96725)
			(xy 86.676992 -245.973092) (xy 86.686349 -245.993707) (xy 86.699572 -246.037004) (xy 86.706286 -246.081775)
			(xy 86.70671 -246.10441) (xy 87.035144 -246.10441) (xy 87.039104 -246.055356) (xy 87.050881 -246.007572)
			(xy 87.070172 -245.962296) (xy 87.096475 -245.9207) (xy 87.12911 -245.883863) (xy 87.167231 -245.852738)
			(xy 87.209852 -245.828131) (xy 87.255868 -245.810679) (xy 87.304087 -245.800835) (xy 87.353262 -245.798854)
			(xy 87.402117 -245.804786) (xy 87.449388 -245.818478) (xy 87.49385 -245.839576) (xy 87.534353 -245.867532)
			(xy 87.569846 -245.901624) (xy 87.599411 -245.940968) (xy 87.622282 -245.984545) (xy 87.637866 -246.031226)
			(xy 87.645761 -246.079803) (xy 87.646256 -246.10441) (xy 87.975198 -246.10441) (xy 87.979158 -246.055356)
			(xy 87.990935 -246.007572) (xy 88.010226 -245.962296) (xy 88.036529 -245.9207) (xy 88.069164 -245.883863)
			(xy 88.107285 -245.852738) (xy 88.149906 -245.828131) (xy 88.195922 -245.810679) (xy 88.244141 -245.800835)
			(xy 88.293316 -245.798854) (xy 88.342171 -245.804786) (xy 88.389442 -245.818478) (xy 88.433904 -245.839576)
			(xy 88.474407 -245.867532) (xy 88.5099 -245.901624) (xy 88.539465 -245.940968) (xy 88.562336 -245.984545)
			(xy 88.57792 -246.031226) (xy 88.585815 -246.079803) (xy 88.58631 -246.10441) (xy 88.915252 -246.10441)
			(xy 88.919212 -246.055356) (xy 88.930989 -246.007572) (xy 88.95028 -245.962296) (xy 88.976583 -245.9207)
			(xy 89.009218 -245.883863) (xy 89.047339 -245.852738) (xy 89.08996 -245.828131) (xy 89.135976 -245.810679)
			(xy 89.184195 -245.800835) (xy 89.23337 -245.798854) (xy 89.282225 -245.804786) (xy 89.329496 -245.818478)
			(xy 89.373958 -245.839576) (xy 89.414461 -245.867532) (xy 89.449954 -245.901624) (xy 89.479519 -245.940968)
			(xy 89.50239 -245.984545) (xy 89.517974 -246.031226) (xy 89.525869 -246.079803) (xy 89.526364 -246.10441)
			(xy 89.855306 -246.10441) (xy 89.859266 -246.055356) (xy 89.871043 -246.007572) (xy 89.890334 -245.962296)
			(xy 89.916637 -245.9207) (xy 89.949272 -245.883863) (xy 89.987393 -245.852738) (xy 90.030014 -245.828131)
			(xy 90.07603 -245.810679) (xy 90.124249 -245.800835) (xy 90.173424 -245.798854) (xy 90.222279 -245.804786)
			(xy 90.26955 -245.818478) (xy 90.314012 -245.839576) (xy 90.354515 -245.867532) (xy 90.390008 -245.901624)
			(xy 90.419573 -245.940968) (xy 90.442444 -245.984545) (xy 90.458028 -246.031226) (xy 90.465923 -246.079803)
			(xy 90.466418 -246.10441) (xy 90.784675 -246.10441) (xy 90.78877 -246.053682) (xy 90.800949 -246.004268)
			(xy 90.820897 -245.957448) (xy 90.848098 -245.914434) (xy 90.881846 -245.87634) (xy 90.921268 -245.844153)
			(xy 90.965342 -245.818707) (xy 91.012928 -245.80066) (xy 91.062792 -245.79048) (xy 91.113644 -245.788431)
			(xy 91.164165 -245.794565) (xy 91.213049 -245.808725) (xy 91.259028 -245.830542) (xy 91.300912 -245.859452)
			(xy 91.337616 -245.894707) (xy 91.368189 -245.935393) (xy 91.39184 -245.980456) (xy 91.407956 -246.02873)
			(xy 91.41612 -246.078964) (xy 91.416632 -246.10441) (xy 91.724729 -246.10441) (xy 91.728824 -246.053682)
			(xy 91.741003 -246.004268) (xy 91.760951 -245.957448) (xy 91.788152 -245.914434) (xy 91.8219 -245.87634)
			(xy 91.861322 -245.844153) (xy 91.905396 -245.818707) (xy 91.952982 -245.80066) (xy 92.002846 -245.79048)
			(xy 92.053698 -245.788431) (xy 92.104219 -245.794565) (xy 92.153103 -245.808725) (xy 92.199082 -245.830542)
			(xy 92.240966 -245.859452) (xy 92.27767 -245.894707) (xy 92.308243 -245.935393) (xy 92.331894 -245.980456)
			(xy 92.34801 -246.02873) (xy 92.356174 -246.078964) (xy 92.356686 -246.10441) (xy 92.675214 -246.10441)
			(xy 92.679174 -246.055356) (xy 92.690951 -246.007572) (xy 92.710242 -245.962296) (xy 92.736545 -245.9207)
			(xy 92.76918 -245.883863) (xy 92.807301 -245.852738) (xy 92.849922 -245.828131) (xy 92.895938 -245.810679)
			(xy 92.944157 -245.800835) (xy 92.993332 -245.798854) (xy 93.042187 -245.804786) (xy 93.089458 -245.818478)
			(xy 93.13392 -245.839576) (xy 93.174423 -245.867532) (xy 93.209916 -245.901624) (xy 93.239481 -245.940968)
			(xy 93.262352 -245.984545) (xy 93.277936 -246.031226) (xy 93.285831 -246.079803) (xy 93.286326 -246.10441)
			(xy 93.604837 -246.10441) (xy 93.608932 -246.053682) (xy 93.621111 -246.004268) (xy 93.641059 -245.957448)
			(xy 93.66826 -245.914434) (xy 93.702008 -245.87634) (xy 93.74143 -245.844153) (xy 93.785504 -245.818707)
			(xy 93.83309 -245.80066) (xy 93.882954 -245.79048) (xy 93.933806 -245.788431) (xy 93.984327 -245.794565)
			(xy 94.033211 -245.808725) (xy 94.07919 -245.830542) (xy 94.121074 -245.859452) (xy 94.157778 -245.894707)
			(xy 94.188351 -245.935393) (xy 94.212002 -245.980456) (xy 94.228118 -246.02873) (xy 94.236282 -246.078964)
			(xy 94.236794 -246.10441) (xy 94.555322 -246.10441) (xy 94.559282 -246.055356) (xy 94.571059 -246.007572)
			(xy 94.59035 -245.962296) (xy 94.616653 -245.9207) (xy 94.649288 -245.883863) (xy 94.687409 -245.852738)
			(xy 94.73003 -245.828131) (xy 94.776046 -245.810679) (xy 94.824265 -245.800835) (xy 94.87344 -245.798854)
			(xy 94.922295 -245.804786) (xy 94.969566 -245.818478) (xy 95.014028 -245.839576) (xy 95.054531 -245.867532)
			(xy 95.090024 -245.901624) (xy 95.119589 -245.940968) (xy 95.14246 -245.984545) (xy 95.158044 -246.031226)
			(xy 95.165939 -246.079803) (xy 95.166434 -246.10441) (xy 95.484691 -246.10441) (xy 95.488786 -246.053682)
			(xy 95.500965 -246.004268) (xy 95.520913 -245.957448) (xy 95.548114 -245.914434) (xy 95.581862 -245.87634)
			(xy 95.621284 -245.844153) (xy 95.665358 -245.818707) (xy 95.712944 -245.80066) (xy 95.762808 -245.79048)
			(xy 95.81366 -245.788431) (xy 95.864181 -245.794565) (xy 95.913065 -245.808725) (xy 95.959044 -245.830542)
			(xy 96.000928 -245.859452) (xy 96.037632 -245.894707) (xy 96.068205 -245.935393) (xy 96.091856 -245.980456)
			(xy 96.107972 -246.02873) (xy 96.116136 -246.078964) (xy 96.116648 -246.10441) (xy 96.116136 -246.129856)
			(xy 96.107972 -246.18009) (xy 96.091856 -246.228364) (xy 96.068205 -246.273427) (xy 96.037632 -246.314113)
			(xy 96.000928 -246.349368) (xy 95.959044 -246.378278) (xy 95.913065 -246.400095) (xy 95.864181 -246.414255)
			(xy 95.81366 -246.420389) (xy 95.762808 -246.41834) (xy 95.712944 -246.40816) (xy 95.665358 -246.390113)
			(xy 95.621284 -246.364667) (xy 95.581862 -246.33248) (xy 95.548114 -246.294386) (xy 95.520913 -246.251372)
			(xy 95.500965 -246.204552) (xy 95.488786 -246.155138) (xy 95.484691 -246.10441) (xy 95.166434 -246.10441)
			(xy 95.165939 -246.129017) (xy 95.158044 -246.177594) (xy 95.14246 -246.224275) (xy 95.119589 -246.267852)
			(xy 95.090024 -246.307196) (xy 95.054531 -246.341288) (xy 95.014028 -246.369244) (xy 94.969566 -246.390342)
			(xy 94.922295 -246.404034) (xy 94.87344 -246.409966) (xy 94.824265 -246.407985) (xy 94.776046 -246.398141)
			(xy 94.73003 -246.380689) (xy 94.687409 -246.356082) (xy 94.649288 -246.324957) (xy 94.616653 -246.28812)
			(xy 94.59035 -246.246524) (xy 94.571059 -246.201248) (xy 94.559282 -246.153464) (xy 94.555322 -246.10441)
			(xy 94.236794 -246.10441) (xy 94.236282 -246.129856) (xy 94.228118 -246.18009) (xy 94.212002 -246.228364)
			(xy 94.188351 -246.273427) (xy 94.157778 -246.314113) (xy 94.121074 -246.349368) (xy 94.07919 -246.378278)
			(xy 94.033211 -246.400095) (xy 93.984327 -246.414255) (xy 93.933806 -246.420389) (xy 93.882954 -246.41834)
			(xy 93.83309 -246.40816) (xy 93.785504 -246.390113) (xy 93.74143 -246.364667) (xy 93.702008 -246.33248)
			(xy 93.66826 -246.294386) (xy 93.641059 -246.251372) (xy 93.621111 -246.204552) (xy 93.608932 -246.155138)
			(xy 93.604837 -246.10441) (xy 93.286326 -246.10441) (xy 93.285831 -246.129017) (xy 93.277936 -246.177594)
			(xy 93.262352 -246.224275) (xy 93.239481 -246.267852) (xy 93.209916 -246.307196) (xy 93.174423 -246.341288)
			(xy 93.13392 -246.369244) (xy 93.089458 -246.390342) (xy 93.042187 -246.404034) (xy 92.993332 -246.409966)
			(xy 92.944157 -246.407985) (xy 92.895938 -246.398141) (xy 92.849922 -246.380689) (xy 92.807301 -246.356082)
			(xy 92.76918 -246.324957) (xy 92.736545 -246.28812) (xy 92.710242 -246.246524) (xy 92.690951 -246.201248)
			(xy 92.679174 -246.153464) (xy 92.675214 -246.10441) (xy 92.356686 -246.10441) (xy 92.356174 -246.129856)
			(xy 92.34801 -246.18009) (xy 92.331894 -246.228364) (xy 92.308243 -246.273427) (xy 92.27767 -246.314113)
			(xy 92.240966 -246.349368) (xy 92.199082 -246.378278) (xy 92.153103 -246.400095) (xy 92.104219 -246.414255)
			(xy 92.053698 -246.420389) (xy 92.002846 -246.41834) (xy 91.952982 -246.40816) (xy 91.905396 -246.390113)
			(xy 91.861322 -246.364667) (xy 91.8219 -246.33248) (xy 91.788152 -246.294386) (xy 91.760951 -246.251372)
			(xy 91.741003 -246.204552) (xy 91.728824 -246.155138) (xy 91.724729 -246.10441) (xy 91.416632 -246.10441)
			(xy 91.41612 -246.129856) (xy 91.407956 -246.18009) (xy 91.39184 -246.228364) (xy 91.368189 -246.273427)
			(xy 91.337616 -246.314113) (xy 91.300912 -246.349368) (xy 91.259028 -246.378278) (xy 91.213049 -246.400095)
			(xy 91.164165 -246.414255) (xy 91.113644 -246.420389) (xy 91.062792 -246.41834) (xy 91.012928 -246.40816)
			(xy 90.965342 -246.390113) (xy 90.921268 -246.364667) (xy 90.881846 -246.33248) (xy 90.848098 -246.294386)
			(xy 90.820897 -246.251372) (xy 90.800949 -246.204552) (xy 90.78877 -246.155138) (xy 90.784675 -246.10441)
			(xy 90.466418 -246.10441) (xy 90.465923 -246.129017) (xy 90.458028 -246.177594) (xy 90.442444 -246.224275)
			(xy 90.419573 -246.267852) (xy 90.390008 -246.307196) (xy 90.354515 -246.341288) (xy 90.314012 -246.369244)
			(xy 90.26955 -246.390342) (xy 90.222279 -246.404034) (xy 90.173424 -246.409966) (xy 90.124249 -246.407985)
			(xy 90.07603 -246.398141) (xy 90.030014 -246.380689) (xy 89.987393 -246.356082) (xy 89.949272 -246.324957)
			(xy 89.916637 -246.28812) (xy 89.890334 -246.246524) (xy 89.871043 -246.201248) (xy 89.859266 -246.153464)
			(xy 89.855306 -246.10441) (xy 89.526364 -246.10441) (xy 89.525869 -246.129017) (xy 89.517974 -246.177594)
			(xy 89.50239 -246.224275) (xy 89.479519 -246.267852) (xy 89.449954 -246.307196) (xy 89.414461 -246.341288)
			(xy 89.373958 -246.369244) (xy 89.329496 -246.390342) (xy 89.282225 -246.404034) (xy 89.23337 -246.409966)
			(xy 89.184195 -246.407985) (xy 89.135976 -246.398141) (xy 89.08996 -246.380689) (xy 89.047339 -246.356082)
			(xy 89.009218 -246.324957) (xy 88.976583 -246.28812) (xy 88.95028 -246.246524) (xy 88.930989 -246.201248)
			(xy 88.919212 -246.153464) (xy 88.915252 -246.10441) (xy 88.58631 -246.10441) (xy 88.585815 -246.129017)
			(xy 88.57792 -246.177594) (xy 88.562336 -246.224275) (xy 88.539465 -246.267852) (xy 88.5099 -246.307196)
			(xy 88.474407 -246.341288) (xy 88.433904 -246.369244) (xy 88.389442 -246.390342) (xy 88.342171 -246.404034)
			(xy 88.293316 -246.409966) (xy 88.244141 -246.407985) (xy 88.195922 -246.398141) (xy 88.149906 -246.380689)
			(xy 88.107285 -246.356082) (xy 88.069164 -246.324957) (xy 88.036529 -246.28812) (xy 88.010226 -246.246524)
			(xy 87.990935 -246.201248) (xy 87.979158 -246.153464) (xy 87.975198 -246.10441) (xy 87.646256 -246.10441)
			(xy 87.645761 -246.129017) (xy 87.637866 -246.177594) (xy 87.622282 -246.224275) (xy 87.599411 -246.267852)
			(xy 87.569846 -246.307196) (xy 87.534353 -246.341288) (xy 87.49385 -246.369244) (xy 87.449388 -246.390342)
			(xy 87.402117 -246.404034) (xy 87.353262 -246.409966) (xy 87.304087 -246.407985) (xy 87.255868 -246.398141)
			(xy 87.209852 -246.380689) (xy 87.167231 -246.356082) (xy 87.12911 -246.324957) (xy 87.096475 -246.28812)
			(xy 87.070172 -246.246524) (xy 87.050881 -246.201248) (xy 87.039104 -246.153464) (xy 87.035144 -246.10441)
			(xy 86.70671 -246.10441) (xy 86.70671 -246.10568) (xy 86.706256 -246.128978) (xy 86.699146 -246.175028)
			(xy 86.68512 -246.219462) (xy 86.675214 -246.240554) (xy 86.672674 -246.245888) (xy 86.670134 -246.257064)
			(xy 86.670134 -246.32031) (xy 86.670591 -246.330189) (xy 86.678025 -246.348495) (xy 86.684612 -246.35587)
			(xy 86.684866 -246.356124) (xy 86.784688 -246.455946) (xy 86.785196 -246.456454) (xy 86.79258 -246.463029)
			(xy 86.810879 -246.470464) (xy 86.820756 -246.470932) (xy 87.05342 -246.470932) (xy 87.063261 -246.47146)
			(xy 87.081432 -246.479038) (xy 87.088726 -246.485664) (xy 87.313262 -246.7102) (xy 87.319972 -246.71744)
			(xy 87.327562 -246.735644) (xy 87.327994 -246.745506) (xy 87.327994 -246.914416) (xy 87.505298 -246.914416)
			(xy 87.509258 -246.865362) (xy 87.521035 -246.817578) (xy 87.540326 -246.772302) (xy 87.566629 -246.730706)
			(xy 87.599264 -246.693869) (xy 87.637385 -246.662744) (xy 87.680006 -246.638137) (xy 87.726022 -246.620685)
			(xy 87.774241 -246.610841) (xy 87.823416 -246.60886) (xy 87.872271 -246.614792) (xy 87.919542 -246.628484)
			(xy 87.964004 -246.649582) (xy 88.004507 -246.677538) (xy 88.04 -246.71163) (xy 88.069565 -246.750974)
			(xy 88.092436 -246.794551) (xy 88.10802 -246.841232) (xy 88.115915 -246.889809) (xy 88.11641 -246.914416)
			(xy 88.445352 -246.914416) (xy 88.449312 -246.865362) (xy 88.461089 -246.817578) (xy 88.48038 -246.772302)
			(xy 88.506683 -246.730706) (xy 88.539318 -246.693869) (xy 88.577439 -246.662744) (xy 88.62006 -246.638137)
			(xy 88.666076 -246.620685) (xy 88.714295 -246.610841) (xy 88.76347 -246.60886) (xy 88.812325 -246.614792)
			(xy 88.859596 -246.628484) (xy 88.904058 -246.649582) (xy 88.944561 -246.677538) (xy 88.980054 -246.71163)
			(xy 89.009619 -246.750974) (xy 89.03249 -246.794551) (xy 89.048074 -246.841232) (xy 89.055969 -246.889809)
			(xy 89.056464 -246.914416) (xy 89.385152 -246.914416) (xy 89.389112 -246.865362) (xy 89.400889 -246.817578)
			(xy 89.42018 -246.772302) (xy 89.446483 -246.730706) (xy 89.479118 -246.693869) (xy 89.517239 -246.662744)
			(xy 89.55986 -246.638137) (xy 89.605876 -246.620685) (xy 89.654095 -246.610841) (xy 89.70327 -246.60886)
			(xy 89.752125 -246.614792) (xy 89.799396 -246.628484) (xy 89.843858 -246.649582) (xy 89.884361 -246.677538)
			(xy 89.919854 -246.71163) (xy 89.949419 -246.750974) (xy 89.97229 -246.794551) (xy 89.987874 -246.841232)
			(xy 89.995769 -246.889809) (xy 89.996264 -246.914416) (xy 90.314775 -246.914416) (xy 90.31887 -246.863688)
			(xy 90.331049 -246.814274) (xy 90.350997 -246.767454) (xy 90.378198 -246.72444) (xy 90.411946 -246.686346)
			(xy 90.451368 -246.654159) (xy 90.495442 -246.628713) (xy 90.543028 -246.610666) (xy 90.592892 -246.600486)
			(xy 90.643744 -246.598437) (xy 90.694265 -246.604571) (xy 90.743149 -246.618731) (xy 90.789128 -246.640548)
			(xy 90.831012 -246.669458) (xy 90.867716 -246.704713) (xy 90.898289 -246.745399) (xy 90.92194 -246.790462)
			(xy 90.938056 -246.838736) (xy 90.94622 -246.88897) (xy 90.946732 -246.914416) (xy 91.26526 -246.914416)
			(xy 91.26922 -246.865362) (xy 91.280997 -246.817578) (xy 91.300288 -246.772302) (xy 91.326591 -246.730706)
			(xy 91.359226 -246.693869) (xy 91.397347 -246.662744) (xy 91.439968 -246.638137) (xy 91.485984 -246.620685)
			(xy 91.534203 -246.610841) (xy 91.583378 -246.60886) (xy 91.632233 -246.614792) (xy 91.679504 -246.628484)
			(xy 91.723966 -246.649582) (xy 91.764469 -246.677538) (xy 91.799962 -246.71163) (xy 91.829527 -246.750974)
			(xy 91.852398 -246.794551) (xy 91.867982 -246.841232) (xy 91.875877 -246.889809) (xy 91.876372 -246.914416)
			(xy 92.194883 -246.914416) (xy 92.198978 -246.863688) (xy 92.211157 -246.814274) (xy 92.231105 -246.767454)
			(xy 92.258306 -246.72444) (xy 92.292054 -246.686346) (xy 92.331476 -246.654159) (xy 92.37555 -246.628713)
			(xy 92.423136 -246.610666) (xy 92.473 -246.600486) (xy 92.523852 -246.598437) (xy 92.574373 -246.604571)
			(xy 92.623257 -246.618731) (xy 92.669236 -246.640548) (xy 92.71112 -246.669458) (xy 92.747824 -246.704713)
			(xy 92.778397 -246.745399) (xy 92.802048 -246.790462) (xy 92.818164 -246.838736) (xy 92.826328 -246.88897)
			(xy 92.82684 -246.914416) (xy 93.145114 -246.914416) (xy 93.149074 -246.865362) (xy 93.160851 -246.817578)
			(xy 93.180142 -246.772302) (xy 93.206445 -246.730706) (xy 93.23908 -246.693869) (xy 93.277201 -246.662744)
			(xy 93.319822 -246.638137) (xy 93.365838 -246.620685) (xy 93.414057 -246.610841) (xy 93.463232 -246.60886)
			(xy 93.512087 -246.614792) (xy 93.559358 -246.628484) (xy 93.60382 -246.649582) (xy 93.644323 -246.677538)
			(xy 93.679816 -246.71163) (xy 93.709381 -246.750974) (xy 93.732252 -246.794551) (xy 93.747836 -246.841232)
			(xy 93.755731 -246.889809) (xy 93.756226 -246.914416) (xy 94.074737 -246.914416) (xy 94.078832 -246.863688)
			(xy 94.091011 -246.814274) (xy 94.110959 -246.767454) (xy 94.13816 -246.72444) (xy 94.171908 -246.686346)
			(xy 94.21133 -246.654159) (xy 94.255404 -246.628713) (xy 94.30299 -246.610666) (xy 94.352854 -246.600486)
			(xy 94.403706 -246.598437) (xy 94.454227 -246.604571) (xy 94.503111 -246.618731) (xy 94.54909 -246.640548)
			(xy 94.590974 -246.669458) (xy 94.627678 -246.704713) (xy 94.658251 -246.745399) (xy 94.681902 -246.790462)
			(xy 94.698018 -246.838736) (xy 94.706182 -246.88897) (xy 94.706694 -246.914416) (xy 95.014791 -246.914416)
			(xy 95.018886 -246.863688) (xy 95.031065 -246.814274) (xy 95.051013 -246.767454) (xy 95.078214 -246.72444)
			(xy 95.111962 -246.686346) (xy 95.151384 -246.654159) (xy 95.195458 -246.628713) (xy 95.243044 -246.610666)
			(xy 95.292908 -246.600486) (xy 95.34376 -246.598437) (xy 95.394281 -246.604571) (xy 95.443165 -246.618731)
			(xy 95.489144 -246.640548) (xy 95.531028 -246.669458) (xy 95.567732 -246.704713) (xy 95.598305 -246.745399)
			(xy 95.621956 -246.790462) (xy 95.638072 -246.838736) (xy 95.646236 -246.88897) (xy 95.646748 -246.914416)
			(xy 95.646236 -246.939862) (xy 95.638072 -246.990096) (xy 95.621956 -247.03837) (xy 95.598305 -247.083433)
			(xy 95.567732 -247.124119) (xy 95.531028 -247.159374) (xy 95.489144 -247.188284) (xy 95.443165 -247.210101)
			(xy 95.394281 -247.224261) (xy 95.34376 -247.230395) (xy 95.292908 -247.228346) (xy 95.243044 -247.218166)
			(xy 95.195458 -247.200119) (xy 95.151384 -247.174673) (xy 95.111962 -247.142486) (xy 95.078214 -247.104392)
			(xy 95.051013 -247.061378) (xy 95.031065 -247.014558) (xy 95.018886 -246.965144) (xy 95.014791 -246.914416)
			(xy 94.706694 -246.914416) (xy 94.706182 -246.939862) (xy 94.698018 -246.990096) (xy 94.681902 -247.03837)
			(xy 94.658251 -247.083433) (xy 94.627678 -247.124119) (xy 94.590974 -247.159374) (xy 94.54909 -247.188284)
			(xy 94.503111 -247.210101) (xy 94.454227 -247.224261) (xy 94.403706 -247.230395) (xy 94.352854 -247.228346)
			(xy 94.30299 -247.218166) (xy 94.255404 -247.200119) (xy 94.21133 -247.174673) (xy 94.171908 -247.142486)
			(xy 94.13816 -247.104392) (xy 94.110959 -247.061378) (xy 94.091011 -247.014558) (xy 94.078832 -246.965144)
			(xy 94.074737 -246.914416) (xy 93.756226 -246.914416) (xy 93.755731 -246.939023) (xy 93.747836 -246.9876)
			(xy 93.732252 -247.034281) (xy 93.709381 -247.077858) (xy 93.679816 -247.117202) (xy 93.644323 -247.151294)
			(xy 93.60382 -247.17925) (xy 93.559358 -247.200348) (xy 93.512087 -247.21404) (xy 93.463232 -247.219972)
			(xy 93.414057 -247.217991) (xy 93.365838 -247.208147) (xy 93.319822 -247.190695) (xy 93.277201 -247.166088)
			(xy 93.23908 -247.134963) (xy 93.206445 -247.098126) (xy 93.180142 -247.05653) (xy 93.160851 -247.011254)
			(xy 93.149074 -246.96347) (xy 93.145114 -246.914416) (xy 92.82684 -246.914416) (xy 92.826328 -246.939862)
			(xy 92.818164 -246.990096) (xy 92.802048 -247.03837) (xy 92.778397 -247.083433) (xy 92.747824 -247.124119)
			(xy 92.71112 -247.159374) (xy 92.669236 -247.188284) (xy 92.623257 -247.210101) (xy 92.574373 -247.224261)
			(xy 92.523852 -247.230395) (xy 92.473 -247.228346) (xy 92.423136 -247.218166) (xy 92.37555 -247.200119)
			(xy 92.331476 -247.174673) (xy 92.292054 -247.142486) (xy 92.258306 -247.104392) (xy 92.231105 -247.061378)
			(xy 92.211157 -247.014558) (xy 92.198978 -246.965144) (xy 92.194883 -246.914416) (xy 91.876372 -246.914416)
			(xy 91.875877 -246.939023) (xy 91.867982 -246.9876) (xy 91.852398 -247.034281) (xy 91.829527 -247.077858)
			(xy 91.799962 -247.117202) (xy 91.764469 -247.151294) (xy 91.723966 -247.17925) (xy 91.679504 -247.200348)
			(xy 91.632233 -247.21404) (xy 91.583378 -247.219972) (xy 91.534203 -247.217991) (xy 91.485984 -247.208147)
			(xy 91.439968 -247.190695) (xy 91.397347 -247.166088) (xy 91.359226 -247.134963) (xy 91.326591 -247.098126)
			(xy 91.300288 -247.05653) (xy 91.280997 -247.011254) (xy 91.26922 -246.96347) (xy 91.26526 -246.914416)
			(xy 90.946732 -246.914416) (xy 90.94622 -246.939862) (xy 90.938056 -246.990096) (xy 90.92194 -247.03837)
			(xy 90.898289 -247.083433) (xy 90.867716 -247.124119) (xy 90.831012 -247.159374) (xy 90.789128 -247.188284)
			(xy 90.743149 -247.210101) (xy 90.694265 -247.224261) (xy 90.643744 -247.230395) (xy 90.592892 -247.228346)
			(xy 90.543028 -247.218166) (xy 90.495442 -247.200119) (xy 90.451368 -247.174673) (xy 90.411946 -247.142486)
			(xy 90.378198 -247.104392) (xy 90.350997 -247.061378) (xy 90.331049 -247.014558) (xy 90.31887 -246.965144)
			(xy 90.314775 -246.914416) (xy 89.996264 -246.914416) (xy 89.995769 -246.939023) (xy 89.987874 -246.9876)
			(xy 89.97229 -247.034281) (xy 89.949419 -247.077858) (xy 89.919854 -247.117202) (xy 89.884361 -247.151294)
			(xy 89.843858 -247.17925) (xy 89.799396 -247.200348) (xy 89.752125 -247.21404) (xy 89.70327 -247.219972)
			(xy 89.654095 -247.217991) (xy 89.605876 -247.208147) (xy 89.55986 -247.190695) (xy 89.517239 -247.166088)
			(xy 89.479118 -247.134963) (xy 89.446483 -247.098126) (xy 89.42018 -247.05653) (xy 89.400889 -247.011254)
			(xy 89.389112 -246.96347) (xy 89.385152 -246.914416) (xy 89.056464 -246.914416) (xy 89.055969 -246.939023)
			(xy 89.048074 -246.9876) (xy 89.03249 -247.034281) (xy 89.009619 -247.077858) (xy 88.980054 -247.117202)
			(xy 88.944561 -247.151294) (xy 88.904058 -247.17925) (xy 88.859596 -247.200348) (xy 88.812325 -247.21404)
			(xy 88.76347 -247.219972) (xy 88.714295 -247.217991) (xy 88.666076 -247.208147) (xy 88.62006 -247.190695)
			(xy 88.577439 -247.166088) (xy 88.539318 -247.134963) (xy 88.506683 -247.098126) (xy 88.48038 -247.05653)
			(xy 88.461089 -247.011254) (xy 88.449312 -246.96347) (xy 88.445352 -246.914416) (xy 88.11641 -246.914416)
			(xy 88.115915 -246.939023) (xy 88.10802 -246.9876) (xy 88.092436 -247.034281) (xy 88.069565 -247.077858)
			(xy 88.04 -247.117202) (xy 88.004507 -247.151294) (xy 87.964004 -247.17925) (xy 87.919542 -247.200348)
			(xy 87.872271 -247.21404) (xy 87.823416 -247.219972) (xy 87.774241 -247.217991) (xy 87.726022 -247.208147)
			(xy 87.680006 -247.190695) (xy 87.637385 -247.166088) (xy 87.599264 -247.134963) (xy 87.566629 -247.098126)
			(xy 87.540326 -247.05653) (xy 87.521035 -247.011254) (xy 87.509258 -246.96347) (xy 87.505298 -246.914416)
			(xy 87.327994 -246.914416) (xy 87.327994 -247.080278) (xy 87.327456 -247.090115) (xy 87.319867 -247.108273)
			(xy 87.313262 -247.115584) (xy 87.060786 -247.36806) (xy 87.053546 -247.374768) (xy 87.035341 -247.382353)
			(xy 87.02548 -247.382792) (xy 86.904068 -247.382792) (xy 86.894227 -247.383321) (xy 86.876055 -247.390897)
			(xy 86.868762 -247.397524) (xy 86.728046 -247.53824) (xy 86.721342 -247.545482) (xy 86.713765 -247.563686)
			(xy 86.713314 -247.573546) (xy 86.713314 -247.724422) (xy 87.035144 -247.724422) (xy 87.039104 -247.675368)
			(xy 87.050881 -247.627584) (xy 87.070172 -247.582308) (xy 87.096475 -247.540712) (xy 87.12911 -247.503875)
			(xy 87.167231 -247.47275) (xy 87.209852 -247.448143) (xy 87.255868 -247.430691) (xy 87.304087 -247.420847)
			(xy 87.353262 -247.418866) (xy 87.402117 -247.424798) (xy 87.449388 -247.43849) (xy 87.49385 -247.459588)
			(xy 87.534353 -247.487544) (xy 87.569846 -247.521636) (xy 87.599411 -247.56098) (xy 87.622282 -247.604557)
			(xy 87.637866 -247.651238) (xy 87.645761 -247.699815) (xy 87.646256 -247.724422) (xy 87.975198 -247.724422)
			(xy 87.979158 -247.675368) (xy 87.990935 -247.627584) (xy 88.010226 -247.582308) (xy 88.036529 -247.540712)
			(xy 88.069164 -247.503875) (xy 88.107285 -247.47275) (xy 88.149906 -247.448143) (xy 88.195922 -247.430691)
			(xy 88.244141 -247.420847) (xy 88.293316 -247.418866) (xy 88.342171 -247.424798) (xy 88.389442 -247.43849)
			(xy 88.433904 -247.459588) (xy 88.474407 -247.487544) (xy 88.5099 -247.521636) (xy 88.539465 -247.56098)
			(xy 88.562336 -247.604557) (xy 88.57792 -247.651238) (xy 88.585815 -247.699815) (xy 88.58631 -247.724422)
			(xy 88.915252 -247.724422) (xy 88.919212 -247.675368) (xy 88.930989 -247.627584) (xy 88.95028 -247.582308)
			(xy 88.976583 -247.540712) (xy 89.009218 -247.503875) (xy 89.047339 -247.47275) (xy 89.08996 -247.448143)
			(xy 89.135976 -247.430691) (xy 89.184195 -247.420847) (xy 89.23337 -247.418866) (xy 89.282225 -247.424798)
			(xy 89.329496 -247.43849) (xy 89.373958 -247.459588) (xy 89.414461 -247.487544) (xy 89.449954 -247.521636)
			(xy 89.479519 -247.56098) (xy 89.50239 -247.604557) (xy 89.517974 -247.651238) (xy 89.525869 -247.699815)
			(xy 89.526364 -247.724422) (xy 89.855306 -247.724422) (xy 89.859266 -247.675368) (xy 89.871043 -247.627584)
			(xy 89.890334 -247.582308) (xy 89.916637 -247.540712) (xy 89.949272 -247.503875) (xy 89.987393 -247.47275)
			(xy 90.030014 -247.448143) (xy 90.07603 -247.430691) (xy 90.124249 -247.420847) (xy 90.173424 -247.418866)
			(xy 90.222279 -247.424798) (xy 90.26955 -247.43849) (xy 90.314012 -247.459588) (xy 90.354515 -247.487544)
			(xy 90.390008 -247.521636) (xy 90.419573 -247.56098) (xy 90.442444 -247.604557) (xy 90.458028 -247.651238)
			(xy 90.465923 -247.699815) (xy 90.466418 -247.724422) (xy 90.784675 -247.724422) (xy 90.78877 -247.673694)
			(xy 90.800949 -247.62428) (xy 90.820897 -247.57746) (xy 90.848098 -247.534446) (xy 90.881846 -247.496352)
			(xy 90.921268 -247.464165) (xy 90.965342 -247.438719) (xy 91.012928 -247.420672) (xy 91.062792 -247.410492)
			(xy 91.113644 -247.408443) (xy 91.164165 -247.414577) (xy 91.213049 -247.428737) (xy 91.259028 -247.450554)
			(xy 91.300912 -247.479464) (xy 91.337616 -247.514719) (xy 91.368189 -247.555405) (xy 91.39184 -247.600468)
			(xy 91.407956 -247.648742) (xy 91.41612 -247.698976) (xy 91.416632 -247.724422) (xy 91.724729 -247.724422)
			(xy 91.728824 -247.673694) (xy 91.741003 -247.62428) (xy 91.760951 -247.57746) (xy 91.788152 -247.534446)
			(xy 91.8219 -247.496352) (xy 91.861322 -247.464165) (xy 91.905396 -247.438719) (xy 91.952982 -247.420672)
			(xy 92.002846 -247.410492) (xy 92.053698 -247.408443) (xy 92.104219 -247.414577) (xy 92.153103 -247.428737)
			(xy 92.199082 -247.450554) (xy 92.240966 -247.479464) (xy 92.27767 -247.514719) (xy 92.308243 -247.555405)
			(xy 92.331894 -247.600468) (xy 92.34801 -247.648742) (xy 92.356174 -247.698976) (xy 92.356686 -247.724422)
			(xy 92.675214 -247.724422) (xy 92.679174 -247.675368) (xy 92.690951 -247.627584) (xy 92.710242 -247.582308)
			(xy 92.736545 -247.540712) (xy 92.76918 -247.503875) (xy 92.807301 -247.47275) (xy 92.849922 -247.448143)
			(xy 92.895938 -247.430691) (xy 92.944157 -247.420847) (xy 92.993332 -247.418866) (xy 93.042187 -247.424798)
			(xy 93.089458 -247.43849) (xy 93.13392 -247.459588) (xy 93.174423 -247.487544) (xy 93.209916 -247.521636)
			(xy 93.239481 -247.56098) (xy 93.262352 -247.604557) (xy 93.277936 -247.651238) (xy 93.285831 -247.699815)
			(xy 93.286326 -247.724422) (xy 93.604837 -247.724422) (xy 93.608932 -247.673694) (xy 93.621111 -247.62428)
			(xy 93.641059 -247.57746) (xy 93.66826 -247.534446) (xy 93.702008 -247.496352) (xy 93.74143 -247.464165)
			(xy 93.785504 -247.438719) (xy 93.83309 -247.420672) (xy 93.882954 -247.410492) (xy 93.933806 -247.408443)
			(xy 93.984327 -247.414577) (xy 94.033211 -247.428737) (xy 94.07919 -247.450554) (xy 94.121074 -247.479464)
			(xy 94.157778 -247.514719) (xy 94.188351 -247.555405) (xy 94.212002 -247.600468) (xy 94.228118 -247.648742)
			(xy 94.236282 -247.698976) (xy 94.236794 -247.724422) (xy 94.555322 -247.724422) (xy 94.559282 -247.675368)
			(xy 94.571059 -247.627584) (xy 94.59035 -247.582308) (xy 94.616653 -247.540712) (xy 94.649288 -247.503875)
			(xy 94.687409 -247.47275) (xy 94.73003 -247.448143) (xy 94.776046 -247.430691) (xy 94.824265 -247.420847)
			(xy 94.87344 -247.418866) (xy 94.922295 -247.424798) (xy 94.969566 -247.43849) (xy 95.014028 -247.459588)
			(xy 95.054531 -247.487544) (xy 95.090024 -247.521636) (xy 95.119589 -247.56098) (xy 95.14246 -247.604557)
			(xy 95.158044 -247.651238) (xy 95.165939 -247.699815) (xy 95.166434 -247.724422) (xy 95.484691 -247.724422)
			(xy 95.488786 -247.673694) (xy 95.500965 -247.62428) (xy 95.520913 -247.57746) (xy 95.548114 -247.534446)
			(xy 95.581862 -247.496352) (xy 95.621284 -247.464165) (xy 95.665358 -247.438719) (xy 95.712944 -247.420672)
			(xy 95.762808 -247.410492) (xy 95.81366 -247.408443) (xy 95.864181 -247.414577) (xy 95.913065 -247.428737)
			(xy 95.959044 -247.450554) (xy 96.000928 -247.479464) (xy 96.037632 -247.514719) (xy 96.068205 -247.555405)
			(xy 96.091856 -247.600468) (xy 96.107972 -247.648742) (xy 96.116136 -247.698976) (xy 96.116648 -247.724422)
			(xy 96.116136 -247.749868) (xy 96.107972 -247.800102) (xy 96.091856 -247.848376) (xy 96.068205 -247.893439)
			(xy 96.037632 -247.934125) (xy 96.000928 -247.96938) (xy 95.959044 -247.99829) (xy 95.913065 -248.020107)
			(xy 95.864181 -248.034267) (xy 95.81366 -248.040401) (xy 95.762808 -248.038352) (xy 95.712944 -248.028172)
			(xy 95.665358 -248.010125) (xy 95.621284 -247.984679) (xy 95.581862 -247.952492) (xy 95.548114 -247.914398)
			(xy 95.520913 -247.871384) (xy 95.500965 -247.824564) (xy 95.488786 -247.77515) (xy 95.484691 -247.724422)
			(xy 95.166434 -247.724422) (xy 95.165939 -247.749029) (xy 95.158044 -247.797606) (xy 95.14246 -247.844287)
			(xy 95.119589 -247.887864) (xy 95.090024 -247.927208) (xy 95.054531 -247.9613) (xy 95.014028 -247.989256)
			(xy 94.969566 -248.010354) (xy 94.922295 -248.024046) (xy 94.87344 -248.029978) (xy 94.824265 -248.027997)
			(xy 94.776046 -248.018153) (xy 94.73003 -248.000701) (xy 94.687409 -247.976094) (xy 94.649288 -247.944969)
			(xy 94.616653 -247.908132) (xy 94.59035 -247.866536) (xy 94.571059 -247.82126) (xy 94.559282 -247.773476)
			(xy 94.555322 -247.724422) (xy 94.236794 -247.724422) (xy 94.236282 -247.749868) (xy 94.228118 -247.800102)
			(xy 94.212002 -247.848376) (xy 94.188351 -247.893439) (xy 94.157778 -247.934125) (xy 94.121074 -247.96938)
			(xy 94.07919 -247.99829) (xy 94.033211 -248.020107) (xy 93.984327 -248.034267) (xy 93.933806 -248.040401)
			(xy 93.882954 -248.038352) (xy 93.83309 -248.028172) (xy 93.785504 -248.010125) (xy 93.74143 -247.984679)
			(xy 93.702008 -247.952492) (xy 93.66826 -247.914398) (xy 93.641059 -247.871384) (xy 93.621111 -247.824564)
			(xy 93.608932 -247.77515) (xy 93.604837 -247.724422) (xy 93.286326 -247.724422) (xy 93.285831 -247.749029)
			(xy 93.277936 -247.797606) (xy 93.262352 -247.844287) (xy 93.239481 -247.887864) (xy 93.209916 -247.927208)
			(xy 93.174423 -247.9613) (xy 93.13392 -247.989256) (xy 93.089458 -248.010354) (xy 93.042187 -248.024046)
			(xy 92.993332 -248.029978) (xy 92.944157 -248.027997) (xy 92.895938 -248.018153) (xy 92.849922 -248.000701)
			(xy 92.807301 -247.976094) (xy 92.76918 -247.944969) (xy 92.736545 -247.908132) (xy 92.710242 -247.866536)
			(xy 92.690951 -247.82126) (xy 92.679174 -247.773476) (xy 92.675214 -247.724422) (xy 92.356686 -247.724422)
			(xy 92.356174 -247.749868) (xy 92.34801 -247.800102) (xy 92.331894 -247.848376) (xy 92.308243 -247.893439)
			(xy 92.27767 -247.934125) (xy 92.240966 -247.96938) (xy 92.199082 -247.99829) (xy 92.153103 -248.020107)
			(xy 92.104219 -248.034267) (xy 92.053698 -248.040401) (xy 92.002846 -248.038352) (xy 91.952982 -248.028172)
			(xy 91.905396 -248.010125) (xy 91.861322 -247.984679) (xy 91.8219 -247.952492) (xy 91.788152 -247.914398)
			(xy 91.760951 -247.871384) (xy 91.741003 -247.824564) (xy 91.728824 -247.77515) (xy 91.724729 -247.724422)
			(xy 91.416632 -247.724422) (xy 91.41612 -247.749868) (xy 91.407956 -247.800102) (xy 91.39184 -247.848376)
			(xy 91.368189 -247.893439) (xy 91.337616 -247.934125) (xy 91.300912 -247.96938) (xy 91.259028 -247.99829)
			(xy 91.213049 -248.020107) (xy 91.164165 -248.034267) (xy 91.113644 -248.040401) (xy 91.062792 -248.038352)
			(xy 91.012928 -248.028172) (xy 90.965342 -248.010125) (xy 90.921268 -247.984679) (xy 90.881846 -247.952492)
			(xy 90.848098 -247.914398) (xy 90.820897 -247.871384) (xy 90.800949 -247.824564) (xy 90.78877 -247.77515)
			(xy 90.784675 -247.724422) (xy 90.466418 -247.724422) (xy 90.465923 -247.749029) (xy 90.458028 -247.797606)
			(xy 90.442444 -247.844287) (xy 90.419573 -247.887864) (xy 90.390008 -247.927208) (xy 90.354515 -247.9613)
			(xy 90.314012 -247.989256) (xy 90.26955 -248.010354) (xy 90.222279 -248.024046) (xy 90.173424 -248.029978)
			(xy 90.124249 -248.027997) (xy 90.07603 -248.018153) (xy 90.030014 -248.000701) (xy 89.987393 -247.976094)
			(xy 89.949272 -247.944969) (xy 89.916637 -247.908132) (xy 89.890334 -247.866536) (xy 89.871043 -247.82126)
			(xy 89.859266 -247.773476) (xy 89.855306 -247.724422) (xy 89.526364 -247.724422) (xy 89.525869 -247.749029)
			(xy 89.517974 -247.797606) (xy 89.50239 -247.844287) (xy 89.479519 -247.887864) (xy 89.449954 -247.927208)
			(xy 89.414461 -247.9613) (xy 89.373958 -247.989256) (xy 89.329496 -248.010354) (xy 89.282225 -248.024046)
			(xy 89.23337 -248.029978) (xy 89.184195 -248.027997) (xy 89.135976 -248.018153) (xy 89.08996 -248.000701)
			(xy 89.047339 -247.976094) (xy 89.009218 -247.944969) (xy 88.976583 -247.908132) (xy 88.95028 -247.866536)
			(xy 88.930989 -247.82126) (xy 88.919212 -247.773476) (xy 88.915252 -247.724422) (xy 88.58631 -247.724422)
			(xy 88.585815 -247.749029) (xy 88.57792 -247.797606) (xy 88.562336 -247.844287) (xy 88.539465 -247.887864)
			(xy 88.5099 -247.927208) (xy 88.474407 -247.9613) (xy 88.433904 -247.989256) (xy 88.389442 -248.010354)
			(xy 88.342171 -248.024046) (xy 88.293316 -248.029978) (xy 88.244141 -248.027997) (xy 88.195922 -248.018153)
			(xy 88.149906 -248.000701) (xy 88.107285 -247.976094) (xy 88.069164 -247.944969) (xy 88.036529 -247.908132)
			(xy 88.010226 -247.866536) (xy 87.990935 -247.82126) (xy 87.979158 -247.773476) (xy 87.975198 -247.724422)
			(xy 87.646256 -247.724422) (xy 87.645761 -247.749029) (xy 87.637866 -247.797606) (xy 87.622282 -247.844287)
			(xy 87.599411 -247.887864) (xy 87.569846 -247.927208) (xy 87.534353 -247.9613) (xy 87.49385 -247.989256)
			(xy 87.449388 -248.010354) (xy 87.402117 -248.024046) (xy 87.353262 -248.029978) (xy 87.304087 -248.027997)
			(xy 87.255868 -248.018153) (xy 87.209852 -248.000701) (xy 87.167231 -247.976094) (xy 87.12911 -247.944969)
			(xy 87.096475 -247.908132) (xy 87.070172 -247.866536) (xy 87.050881 -247.82126) (xy 87.039104 -247.773476)
			(xy 87.035144 -247.724422) (xy 86.713314 -247.724422) (xy 86.713314 -248.02719) (xy 86.713787 -248.037061)
			(xy 86.72125 -248.05534) (xy 86.727792 -248.06275) (xy 86.728046 -248.063004) (xy 86.805008 -248.139966)
			(xy 86.805516 -248.140474) (xy 86.812896 -248.14706) (xy 86.831195 -248.15452) (xy 86.841076 -248.154952)
			(xy 87.01278 -248.154952) (xy 87.022618 -248.155489) (xy 87.040781 -248.163073) (xy 87.048086 -248.169684)
			(xy 87.201502 -248.3231) (xy 87.208218 -248.330337) (xy 87.215818 -248.348542) (xy 87.216234 -248.358406)
			(xy 87.216234 -248.534428) (xy 87.505298 -248.534428) (xy 87.509258 -248.485374) (xy 87.521035 -248.43759)
			(xy 87.540326 -248.392314) (xy 87.566629 -248.350718) (xy 87.599264 -248.313881) (xy 87.637385 -248.282756)
			(xy 87.680006 -248.258149) (xy 87.726022 -248.240697) (xy 87.774241 -248.230853) (xy 87.823416 -248.228872)
			(xy 87.872271 -248.234804) (xy 87.919542 -248.248496) (xy 87.964004 -248.269594) (xy 88.004507 -248.29755)
			(xy 88.04 -248.331642) (xy 88.069565 -248.370986) (xy 88.092436 -248.414563) (xy 88.10802 -248.461244)
			(xy 88.115915 -248.509821) (xy 88.11641 -248.534428) (xy 88.445352 -248.534428) (xy 88.449312 -248.485374)
			(xy 88.461089 -248.43759) (xy 88.48038 -248.392314) (xy 88.506683 -248.350718) (xy 88.539318 -248.313881)
			(xy 88.577439 -248.282756) (xy 88.62006 -248.258149) (xy 88.666076 -248.240697) (xy 88.714295 -248.230853)
			(xy 88.76347 -248.228872) (xy 88.812325 -248.234804) (xy 88.859596 -248.248496) (xy 88.904058 -248.269594)
			(xy 88.944561 -248.29755) (xy 88.980054 -248.331642) (xy 89.009619 -248.370986) (xy 89.03249 -248.414563)
			(xy 89.048074 -248.461244) (xy 89.055969 -248.509821) (xy 89.056464 -248.534428) (xy 89.385152 -248.534428)
			(xy 89.389112 -248.485374) (xy 89.400889 -248.43759) (xy 89.42018 -248.392314) (xy 89.446483 -248.350718)
			(xy 89.479118 -248.313881) (xy 89.517239 -248.282756) (xy 89.55986 -248.258149) (xy 89.605876 -248.240697)
			(xy 89.654095 -248.230853) (xy 89.70327 -248.228872) (xy 89.752125 -248.234804) (xy 89.799396 -248.248496)
			(xy 89.843858 -248.269594) (xy 89.884361 -248.29755) (xy 89.919854 -248.331642) (xy 89.949419 -248.370986)
			(xy 89.97229 -248.414563) (xy 89.987874 -248.461244) (xy 89.995769 -248.509821) (xy 89.996264 -248.534428)
			(xy 90.314775 -248.534428) (xy 90.31887 -248.4837) (xy 90.331049 -248.434286) (xy 90.350997 -248.387466)
			(xy 90.378198 -248.344452) (xy 90.411946 -248.306358) (xy 90.451368 -248.274171) (xy 90.495442 -248.248725)
			(xy 90.543028 -248.230678) (xy 90.592892 -248.220498) (xy 90.643744 -248.218449) (xy 90.694265 -248.224583)
			(xy 90.743149 -248.238743) (xy 90.789128 -248.26056) (xy 90.831012 -248.28947) (xy 90.867716 -248.324725)
			(xy 90.898289 -248.365411) (xy 90.92194 -248.410474) (xy 90.938056 -248.458748) (xy 90.94622 -248.508982)
			(xy 90.946732 -248.534428) (xy 91.26526 -248.534428) (xy 91.26922 -248.485374) (xy 91.280997 -248.43759)
			(xy 91.300288 -248.392314) (xy 91.326591 -248.350718) (xy 91.359226 -248.313881) (xy 91.397347 -248.282756)
			(xy 91.439968 -248.258149) (xy 91.485984 -248.240697) (xy 91.534203 -248.230853) (xy 91.583378 -248.228872)
			(xy 91.632233 -248.234804) (xy 91.679504 -248.248496) (xy 91.723966 -248.269594) (xy 91.764469 -248.29755)
			(xy 91.799962 -248.331642) (xy 91.829527 -248.370986) (xy 91.852398 -248.414563) (xy 91.867982 -248.461244)
			(xy 91.875877 -248.509821) (xy 91.876372 -248.534428) (xy 92.194883 -248.534428) (xy 92.198978 -248.4837)
			(xy 92.211157 -248.434286) (xy 92.231105 -248.387466) (xy 92.258306 -248.344452) (xy 92.292054 -248.306358)
			(xy 92.331476 -248.274171) (xy 92.37555 -248.248725) (xy 92.423136 -248.230678) (xy 92.473 -248.220498)
			(xy 92.523852 -248.218449) (xy 92.574373 -248.224583) (xy 92.623257 -248.238743) (xy 92.669236 -248.26056)
			(xy 92.71112 -248.28947) (xy 92.747824 -248.324725) (xy 92.778397 -248.365411) (xy 92.802048 -248.410474)
			(xy 92.818164 -248.458748) (xy 92.826328 -248.508982) (xy 92.82684 -248.534428) (xy 93.145114 -248.534428)
			(xy 93.149074 -248.485374) (xy 93.160851 -248.43759) (xy 93.180142 -248.392314) (xy 93.206445 -248.350718)
			(xy 93.23908 -248.313881) (xy 93.277201 -248.282756) (xy 93.319822 -248.258149) (xy 93.365838 -248.240697)
			(xy 93.414057 -248.230853) (xy 93.463232 -248.228872) (xy 93.512087 -248.234804) (xy 93.559358 -248.248496)
			(xy 93.60382 -248.269594) (xy 93.644323 -248.29755) (xy 93.679816 -248.331642) (xy 93.709381 -248.370986)
			(xy 93.732252 -248.414563) (xy 93.747836 -248.461244) (xy 93.755731 -248.509821) (xy 93.756226 -248.534428)
			(xy 94.074737 -248.534428) (xy 94.078832 -248.4837) (xy 94.091011 -248.434286) (xy 94.110959 -248.387466)
			(xy 94.13816 -248.344452) (xy 94.171908 -248.306358) (xy 94.21133 -248.274171) (xy 94.255404 -248.248725)
			(xy 94.30299 -248.230678) (xy 94.352854 -248.220498) (xy 94.403706 -248.218449) (xy 94.454227 -248.224583)
			(xy 94.503111 -248.238743) (xy 94.54909 -248.26056) (xy 94.590974 -248.28947) (xy 94.627678 -248.324725)
			(xy 94.658251 -248.365411) (xy 94.681902 -248.410474) (xy 94.698018 -248.458748) (xy 94.706182 -248.508982)
			(xy 94.706694 -248.534428) (xy 95.014791 -248.534428) (xy 95.018886 -248.4837) (xy 95.031065 -248.434286)
			(xy 95.051013 -248.387466) (xy 95.078214 -248.344452) (xy 95.111962 -248.306358) (xy 95.151384 -248.274171)
			(xy 95.195458 -248.248725) (xy 95.243044 -248.230678) (xy 95.292908 -248.220498) (xy 95.34376 -248.218449)
			(xy 95.394281 -248.224583) (xy 95.443165 -248.238743) (xy 95.489144 -248.26056) (xy 95.531028 -248.28947)
			(xy 95.567732 -248.324725) (xy 95.598305 -248.365411) (xy 95.621956 -248.410474) (xy 95.638072 -248.458748)
			(xy 95.646236 -248.508982) (xy 95.646748 -248.534428) (xy 95.646236 -248.559874) (xy 95.638072 -248.610108)
			(xy 95.621956 -248.658382) (xy 95.598305 -248.703445) (xy 95.567732 -248.744131) (xy 95.531028 -248.779386)
			(xy 95.489144 -248.808296) (xy 95.443165 -248.830113) (xy 95.394281 -248.844273) (xy 95.34376 -248.850407)
			(xy 95.292908 -248.848358) (xy 95.243044 -248.838178) (xy 95.195458 -248.820131) (xy 95.151384 -248.794685)
			(xy 95.111962 -248.762498) (xy 95.078214 -248.724404) (xy 95.051013 -248.68139) (xy 95.031065 -248.63457)
			(xy 95.018886 -248.585156) (xy 95.014791 -248.534428) (xy 94.706694 -248.534428) (xy 94.706182 -248.559874)
			(xy 94.698018 -248.610108) (xy 94.681902 -248.658382) (xy 94.658251 -248.703445) (xy 94.627678 -248.744131)
			(xy 94.590974 -248.779386) (xy 94.54909 -248.808296) (xy 94.503111 -248.830113) (xy 94.454227 -248.844273)
			(xy 94.403706 -248.850407) (xy 94.352854 -248.848358) (xy 94.30299 -248.838178) (xy 94.255404 -248.820131)
			(xy 94.21133 -248.794685) (xy 94.171908 -248.762498) (xy 94.13816 -248.724404) (xy 94.110959 -248.68139)
			(xy 94.091011 -248.63457) (xy 94.078832 -248.585156) (xy 94.074737 -248.534428) (xy 93.756226 -248.534428)
			(xy 93.755731 -248.559035) (xy 93.747836 -248.607612) (xy 93.732252 -248.654293) (xy 93.709381 -248.69787)
			(xy 93.679816 -248.737214) (xy 93.644323 -248.771306) (xy 93.60382 -248.799262) (xy 93.559358 -248.82036)
			(xy 93.512087 -248.834052) (xy 93.463232 -248.839984) (xy 93.414057 -248.838003) (xy 93.365838 -248.828159)
			(xy 93.319822 -248.810707) (xy 93.277201 -248.7861) (xy 93.23908 -248.754975) (xy 93.206445 -248.718138)
			(xy 93.180142 -248.676542) (xy 93.160851 -248.631266) (xy 93.149074 -248.583482) (xy 93.145114 -248.534428)
			(xy 92.82684 -248.534428) (xy 92.826328 -248.559874) (xy 92.818164 -248.610108) (xy 92.802048 -248.658382)
			(xy 92.778397 -248.703445) (xy 92.747824 -248.744131) (xy 92.71112 -248.779386) (xy 92.669236 -248.808296)
			(xy 92.623257 -248.830113) (xy 92.574373 -248.844273) (xy 92.523852 -248.850407) (xy 92.473 -248.848358)
			(xy 92.423136 -248.838178) (xy 92.37555 -248.820131) (xy 92.331476 -248.794685) (xy 92.292054 -248.762498)
			(xy 92.258306 -248.724404) (xy 92.231105 -248.68139) (xy 92.211157 -248.63457) (xy 92.198978 -248.585156)
			(xy 92.194883 -248.534428) (xy 91.876372 -248.534428) (xy 91.875877 -248.559035) (xy 91.867982 -248.607612)
			(xy 91.852398 -248.654293) (xy 91.829527 -248.69787) (xy 91.799962 -248.737214) (xy 91.764469 -248.771306)
			(xy 91.723966 -248.799262) (xy 91.679504 -248.82036) (xy 91.632233 -248.834052) (xy 91.583378 -248.839984)
			(xy 91.534203 -248.838003) (xy 91.485984 -248.828159) (xy 91.439968 -248.810707) (xy 91.397347 -248.7861)
			(xy 91.359226 -248.754975) (xy 91.326591 -248.718138) (xy 91.300288 -248.676542) (xy 91.280997 -248.631266)
			(xy 91.26922 -248.583482) (xy 91.26526 -248.534428) (xy 90.946732 -248.534428) (xy 90.94622 -248.559874)
			(xy 90.938056 -248.610108) (xy 90.92194 -248.658382) (xy 90.898289 -248.703445) (xy 90.867716 -248.744131)
			(xy 90.831012 -248.779386) (xy 90.789128 -248.808296) (xy 90.743149 -248.830113) (xy 90.694265 -248.844273)
			(xy 90.643744 -248.850407) (xy 90.592892 -248.848358) (xy 90.543028 -248.838178) (xy 90.495442 -248.820131)
			(xy 90.451368 -248.794685) (xy 90.411946 -248.762498) (xy 90.378198 -248.724404) (xy 90.350997 -248.68139)
			(xy 90.331049 -248.63457) (xy 90.31887 -248.585156) (xy 90.314775 -248.534428) (xy 89.996264 -248.534428)
			(xy 89.995769 -248.559035) (xy 89.987874 -248.607612) (xy 89.97229 -248.654293) (xy 89.949419 -248.69787)
			(xy 89.919854 -248.737214) (xy 89.884361 -248.771306) (xy 89.843858 -248.799262) (xy 89.799396 -248.82036)
			(xy 89.752125 -248.834052) (xy 89.70327 -248.839984) (xy 89.654095 -248.838003) (xy 89.605876 -248.828159)
			(xy 89.55986 -248.810707) (xy 89.517239 -248.7861) (xy 89.479118 -248.754975) (xy 89.446483 -248.718138)
			(xy 89.42018 -248.676542) (xy 89.400889 -248.631266) (xy 89.389112 -248.583482) (xy 89.385152 -248.534428)
			(xy 89.056464 -248.534428) (xy 89.055969 -248.559035) (xy 89.048074 -248.607612) (xy 89.03249 -248.654293)
			(xy 89.009619 -248.69787) (xy 88.980054 -248.737214) (xy 88.944561 -248.771306) (xy 88.904058 -248.799262)
			(xy 88.859596 -248.82036) (xy 88.812325 -248.834052) (xy 88.76347 -248.839984) (xy 88.714295 -248.838003)
			(xy 88.666076 -248.828159) (xy 88.62006 -248.810707) (xy 88.577439 -248.7861) (xy 88.539318 -248.754975)
			(xy 88.506683 -248.718138) (xy 88.48038 -248.676542) (xy 88.461089 -248.631266) (xy 88.449312 -248.583482)
			(xy 88.445352 -248.534428) (xy 88.11641 -248.534428) (xy 88.115915 -248.559035) (xy 88.10802 -248.607612)
			(xy 88.092436 -248.654293) (xy 88.069565 -248.69787) (xy 88.04 -248.737214) (xy 88.004507 -248.771306)
			(xy 87.964004 -248.799262) (xy 87.919542 -248.82036) (xy 87.872271 -248.834052) (xy 87.823416 -248.839984)
			(xy 87.774241 -248.838003) (xy 87.726022 -248.828159) (xy 87.680006 -248.810707) (xy 87.637385 -248.7861)
			(xy 87.599264 -248.754975) (xy 87.566629 -248.718138) (xy 87.540326 -248.676542) (xy 87.521035 -248.631266)
			(xy 87.509258 -248.583482) (xy 87.505298 -248.534428) (xy 87.216234 -248.534428) (xy 87.216234 -248.606818)
			(xy 87.215708 -248.61666) (xy 87.208138 -248.634838) (xy 87.201502 -248.642124) (xy 86.855046 -248.98858)
			(xy 86.848333 -248.995818) (xy 86.840733 -249.014023) (xy 86.840314 -249.023886) (xy 86.840314 -249.344434)
			(xy 87.035144 -249.344434) (xy 87.039104 -249.29538) (xy 87.050881 -249.247596) (xy 87.070172 -249.20232)
			(xy 87.096475 -249.160724) (xy 87.12911 -249.123887) (xy 87.167231 -249.092762) (xy 87.209852 -249.068155)
			(xy 87.255868 -249.050703) (xy 87.304087 -249.040859) (xy 87.353262 -249.038878) (xy 87.402117 -249.04481)
			(xy 87.449388 -249.058502) (xy 87.49385 -249.0796) (xy 87.534353 -249.107556) (xy 87.569846 -249.141648)
			(xy 87.599411 -249.180992) (xy 87.622282 -249.224569) (xy 87.637866 -249.27125) (xy 87.645761 -249.319827)
			(xy 87.646256 -249.344434) (xy 87.975198 -249.344434) (xy 87.979158 -249.29538) (xy 87.990935 -249.247596)
			(xy 88.010226 -249.20232) (xy 88.036529 -249.160724) (xy 88.069164 -249.123887) (xy 88.107285 -249.092762)
			(xy 88.149906 -249.068155) (xy 88.195922 -249.050703) (xy 88.244141 -249.040859) (xy 88.293316 -249.038878)
			(xy 88.342171 -249.04481) (xy 88.389442 -249.058502) (xy 88.433904 -249.0796) (xy 88.474407 -249.107556)
			(xy 88.5099 -249.141648) (xy 88.539465 -249.180992) (xy 88.562336 -249.224569) (xy 88.57792 -249.27125)
			(xy 88.585815 -249.319827) (xy 88.58631 -249.344434) (xy 88.915252 -249.344434) (xy 88.919212 -249.29538)
			(xy 88.930989 -249.247596) (xy 88.95028 -249.20232) (xy 88.976583 -249.160724) (xy 89.009218 -249.123887)
			(xy 89.047339 -249.092762) (xy 89.08996 -249.068155) (xy 89.135976 -249.050703) (xy 89.184195 -249.040859)
			(xy 89.23337 -249.038878) (xy 89.282225 -249.04481) (xy 89.329496 -249.058502) (xy 89.373958 -249.0796)
			(xy 89.414461 -249.107556) (xy 89.449954 -249.141648) (xy 89.479519 -249.180992) (xy 89.50239 -249.224569)
			(xy 89.517974 -249.27125) (xy 89.525869 -249.319827) (xy 89.526364 -249.344434) (xy 89.855306 -249.344434)
			(xy 89.859266 -249.29538) (xy 89.871043 -249.247596) (xy 89.890334 -249.20232) (xy 89.916637 -249.160724)
			(xy 89.949272 -249.123887) (xy 89.987393 -249.092762) (xy 90.030014 -249.068155) (xy 90.07603 -249.050703)
			(xy 90.124249 -249.040859) (xy 90.173424 -249.038878) (xy 90.222279 -249.04481) (xy 90.26955 -249.058502)
			(xy 90.314012 -249.0796) (xy 90.354515 -249.107556) (xy 90.390008 -249.141648) (xy 90.419573 -249.180992)
			(xy 90.442444 -249.224569) (xy 90.458028 -249.27125) (xy 90.465923 -249.319827) (xy 90.466418 -249.344434)
			(xy 90.795106 -249.344434) (xy 90.799066 -249.29538) (xy 90.810843 -249.247596) (xy 90.830134 -249.20232)
			(xy 90.856437 -249.160724) (xy 90.889072 -249.123887) (xy 90.927193 -249.092762) (xy 90.969814 -249.068155)
			(xy 91.01583 -249.050703) (xy 91.064049 -249.040859) (xy 91.113224 -249.038878) (xy 91.162079 -249.04481)
			(xy 91.20935 -249.058502) (xy 91.253812 -249.0796) (xy 91.294315 -249.107556) (xy 91.329808 -249.141648)
			(xy 91.359373 -249.180992) (xy 91.382244 -249.224569) (xy 91.397828 -249.27125) (xy 91.405723 -249.319827)
			(xy 91.406218 -249.344434) (xy 91.724729 -249.344434) (xy 91.728824 -249.293706) (xy 91.741003 -249.244292)
			(xy 91.760951 -249.197472) (xy 91.788152 -249.154458) (xy 91.8219 -249.116364) (xy 91.861322 -249.084177)
			(xy 91.905396 -249.058731) (xy 91.952982 -249.040684) (xy 92.002846 -249.030504) (xy 92.053698 -249.028455)
			(xy 92.104219 -249.034589) (xy 92.153103 -249.048749) (xy 92.199082 -249.070566) (xy 92.240966 -249.099476)
			(xy 92.27767 -249.134731) (xy 92.308243 -249.175417) (xy 92.331894 -249.22048) (xy 92.34801 -249.268754)
			(xy 92.356174 -249.318988) (xy 92.356686 -249.344434) (xy 92.675214 -249.344434) (xy 92.679174 -249.29538)
			(xy 92.690951 -249.247596) (xy 92.710242 -249.20232) (xy 92.736545 -249.160724) (xy 92.76918 -249.123887)
			(xy 92.807301 -249.092762) (xy 92.849922 -249.068155) (xy 92.895938 -249.050703) (xy 92.944157 -249.040859)
			(xy 92.993332 -249.038878) (xy 93.042187 -249.04481) (xy 93.089458 -249.058502) (xy 93.13392 -249.0796)
			(xy 93.174423 -249.107556) (xy 93.209916 -249.141648) (xy 93.239481 -249.180992) (xy 93.262352 -249.224569)
			(xy 93.277936 -249.27125) (xy 93.285831 -249.319827) (xy 93.286326 -249.344434) (xy 93.615268 -249.344434)
			(xy 93.619228 -249.29538) (xy 93.631005 -249.247596) (xy 93.650296 -249.20232) (xy 93.676599 -249.160724)
			(xy 93.709234 -249.123887) (xy 93.747355 -249.092762) (xy 93.789976 -249.068155) (xy 93.835992 -249.050703)
			(xy 93.884211 -249.040859) (xy 93.933386 -249.038878) (xy 93.982241 -249.04481) (xy 94.029512 -249.058502)
			(xy 94.073974 -249.0796) (xy 94.114477 -249.107556) (xy 94.14997 -249.141648) (xy 94.179535 -249.180992)
			(xy 94.202406 -249.224569) (xy 94.21799 -249.27125) (xy 94.225885 -249.319827) (xy 94.22638 -249.344434)
			(xy 94.555322 -249.344434) (xy 94.559282 -249.29538) (xy 94.571059 -249.247596) (xy 94.59035 -249.20232)
			(xy 94.616653 -249.160724) (xy 94.649288 -249.123887) (xy 94.687409 -249.092762) (xy 94.73003 -249.068155)
			(xy 94.776046 -249.050703) (xy 94.824265 -249.040859) (xy 94.87344 -249.038878) (xy 94.922295 -249.04481)
			(xy 94.969566 -249.058502) (xy 95.014028 -249.0796) (xy 95.054531 -249.107556) (xy 95.090024 -249.141648)
			(xy 95.119589 -249.180992) (xy 95.14246 -249.224569) (xy 95.158044 -249.27125) (xy 95.165939 -249.319827)
			(xy 95.166434 -249.344434) (xy 95.484691 -249.344434) (xy 95.488786 -249.293706) (xy 95.500965 -249.244292)
			(xy 95.520913 -249.197472) (xy 95.548114 -249.154458) (xy 95.581862 -249.116364) (xy 95.621284 -249.084177)
			(xy 95.665358 -249.058731) (xy 95.712944 -249.040684) (xy 95.762808 -249.030504) (xy 95.81366 -249.028455)
			(xy 95.864181 -249.034589) (xy 95.913065 -249.048749) (xy 95.959044 -249.070566) (xy 96.000928 -249.099476)
			(xy 96.037632 -249.134731) (xy 96.068205 -249.175417) (xy 96.091856 -249.22048) (xy 96.107972 -249.268754)
			(xy 96.116136 -249.318988) (xy 96.116648 -249.344434) (xy 96.116136 -249.36988) (xy 96.107972 -249.420114)
			(xy 96.091856 -249.468388) (xy 96.068205 -249.513451) (xy 96.037632 -249.554137) (xy 96.000928 -249.589392)
			(xy 95.959044 -249.618302) (xy 95.913065 -249.640119) (xy 95.864181 -249.654279) (xy 95.81366 -249.660413)
			(xy 95.762808 -249.658364) (xy 95.712944 -249.648184) (xy 95.665358 -249.630137) (xy 95.621284 -249.604691)
			(xy 95.581862 -249.572504) (xy 95.548114 -249.53441) (xy 95.520913 -249.491396) (xy 95.500965 -249.444576)
			(xy 95.488786 -249.395162) (xy 95.484691 -249.344434) (xy 95.166434 -249.344434) (xy 95.165939 -249.369041)
			(xy 95.158044 -249.417618) (xy 95.14246 -249.464299) (xy 95.119589 -249.507876) (xy 95.090024 -249.54722)
			(xy 95.054531 -249.581312) (xy 95.014028 -249.609268) (xy 94.969566 -249.630366) (xy 94.922295 -249.644058)
			(xy 94.87344 -249.64999) (xy 94.824265 -249.648009) (xy 94.776046 -249.638165) (xy 94.73003 -249.620713)
			(xy 94.687409 -249.596106) (xy 94.649288 -249.564981) (xy 94.616653 -249.528144) (xy 94.59035 -249.486548)
			(xy 94.571059 -249.441272) (xy 94.559282 -249.393488) (xy 94.555322 -249.344434) (xy 94.22638 -249.344434)
			(xy 94.225885 -249.369041) (xy 94.21799 -249.417618) (xy 94.202406 -249.464299) (xy 94.179535 -249.507876)
			(xy 94.14997 -249.54722) (xy 94.114477 -249.581312) (xy 94.073974 -249.609268) (xy 94.029512 -249.630366)
			(xy 93.982241 -249.644058) (xy 93.933386 -249.64999) (xy 93.884211 -249.648009) (xy 93.835992 -249.638165)
			(xy 93.789976 -249.620713) (xy 93.747355 -249.596106) (xy 93.709234 -249.564981) (xy 93.676599 -249.528144)
			(xy 93.650296 -249.486548) (xy 93.631005 -249.441272) (xy 93.619228 -249.393488) (xy 93.615268 -249.344434)
			(xy 93.286326 -249.344434) (xy 93.285831 -249.369041) (xy 93.277936 -249.417618) (xy 93.262352 -249.464299)
			(xy 93.239481 -249.507876) (xy 93.209916 -249.54722) (xy 93.174423 -249.581312) (xy 93.13392 -249.609268)
			(xy 93.089458 -249.630366) (xy 93.042187 -249.644058) (xy 92.993332 -249.64999) (xy 92.944157 -249.648009)
			(xy 92.895938 -249.638165) (xy 92.849922 -249.620713) (xy 92.807301 -249.596106) (xy 92.76918 -249.564981)
			(xy 92.736545 -249.528144) (xy 92.710242 -249.486548) (xy 92.690951 -249.441272) (xy 92.679174 -249.393488)
			(xy 92.675214 -249.344434) (xy 92.356686 -249.344434) (xy 92.356174 -249.36988) (xy 92.34801 -249.420114)
			(xy 92.331894 -249.468388) (xy 92.308243 -249.513451) (xy 92.27767 -249.554137) (xy 92.240966 -249.589392)
			(xy 92.199082 -249.618302) (xy 92.153103 -249.640119) (xy 92.104219 -249.654279) (xy 92.053698 -249.660413)
			(xy 92.002846 -249.658364) (xy 91.952982 -249.648184) (xy 91.905396 -249.630137) (xy 91.861322 -249.604691)
			(xy 91.8219 -249.572504) (xy 91.788152 -249.53441) (xy 91.760951 -249.491396) (xy 91.741003 -249.444576)
			(xy 91.728824 -249.395162) (xy 91.724729 -249.344434) (xy 91.406218 -249.344434) (xy 91.405723 -249.369041)
			(xy 91.397828 -249.417618) (xy 91.382244 -249.464299) (xy 91.359373 -249.507876) (xy 91.329808 -249.54722)
			(xy 91.294315 -249.581312) (xy 91.253812 -249.609268) (xy 91.20935 -249.630366) (xy 91.162079 -249.644058)
			(xy 91.113224 -249.64999) (xy 91.064049 -249.648009) (xy 91.01583 -249.638165) (xy 90.969814 -249.620713)
			(xy 90.927193 -249.596106) (xy 90.889072 -249.564981) (xy 90.856437 -249.528144) (xy 90.830134 -249.486548)
			(xy 90.810843 -249.441272) (xy 90.799066 -249.393488) (xy 90.795106 -249.344434) (xy 90.466418 -249.344434)
			(xy 90.465923 -249.369041) (xy 90.458028 -249.417618) (xy 90.442444 -249.464299) (xy 90.419573 -249.507876)
			(xy 90.390008 -249.54722) (xy 90.354515 -249.581312) (xy 90.314012 -249.609268) (xy 90.26955 -249.630366)
			(xy 90.222279 -249.644058) (xy 90.173424 -249.64999) (xy 90.124249 -249.648009) (xy 90.07603 -249.638165)
			(xy 90.030014 -249.620713) (xy 89.987393 -249.596106) (xy 89.949272 -249.564981) (xy 89.916637 -249.528144)
			(xy 89.890334 -249.486548) (xy 89.871043 -249.441272) (xy 89.859266 -249.393488) (xy 89.855306 -249.344434)
			(xy 89.526364 -249.344434) (xy 89.525869 -249.369041) (xy 89.517974 -249.417618) (xy 89.50239 -249.464299)
			(xy 89.479519 -249.507876) (xy 89.449954 -249.54722) (xy 89.414461 -249.581312) (xy 89.373958 -249.609268)
			(xy 89.329496 -249.630366) (xy 89.282225 -249.644058) (xy 89.23337 -249.64999) (xy 89.184195 -249.648009)
			(xy 89.135976 -249.638165) (xy 89.08996 -249.620713) (xy 89.047339 -249.596106) (xy 89.009218 -249.564981)
			(xy 88.976583 -249.528144) (xy 88.95028 -249.486548) (xy 88.930989 -249.441272) (xy 88.919212 -249.393488)
			(xy 88.915252 -249.344434) (xy 88.58631 -249.344434) (xy 88.585815 -249.369041) (xy 88.57792 -249.417618)
			(xy 88.562336 -249.464299) (xy 88.539465 -249.507876) (xy 88.5099 -249.54722) (xy 88.474407 -249.581312)
			(xy 88.433904 -249.609268) (xy 88.389442 -249.630366) (xy 88.342171 -249.644058) (xy 88.293316 -249.64999)
			(xy 88.244141 -249.648009) (xy 88.195922 -249.638165) (xy 88.149906 -249.620713) (xy 88.107285 -249.596106)
			(xy 88.069164 -249.564981) (xy 88.036529 -249.528144) (xy 88.010226 -249.486548) (xy 87.990935 -249.441272)
			(xy 87.979158 -249.393488) (xy 87.975198 -249.344434) (xy 87.646256 -249.344434) (xy 87.645761 -249.369041)
			(xy 87.637866 -249.417618) (xy 87.622282 -249.464299) (xy 87.599411 -249.507876) (xy 87.569846 -249.54722)
			(xy 87.534353 -249.581312) (xy 87.49385 -249.609268) (xy 87.449388 -249.630366) (xy 87.402117 -249.644058)
			(xy 87.353262 -249.64999) (xy 87.304087 -249.648009) (xy 87.255868 -249.638165) (xy 87.209852 -249.620713)
			(xy 87.167231 -249.596106) (xy 87.12911 -249.564981) (xy 87.096475 -249.528144) (xy 87.070172 -249.486548)
			(xy 87.050881 -249.441272) (xy 87.039104 -249.393488) (xy 87.035144 -249.344434) (xy 86.840314 -249.344434)
			(xy 86.840314 -249.68581) (xy 86.840773 -249.695687) (xy 86.848216 -249.713987) (xy 86.854792 -249.72137)
			(xy 86.855046 -249.721624) (xy 87.02294 -249.889518) (xy 87.028274 -249.89282) (xy 87.04899 -249.90579)
			(xy 87.086368 -249.937277) (xy 87.118228 -249.974338) (xy 87.131398 -249.994928) (xy 87.132922 -249.997468)
			(xy 87.141812 -250.008644) (xy 87.144098 -250.010676) (xy 87.158322 -250.0249) (xy 87.165036 -250.032138)
			(xy 87.172633 -250.050343) (xy 87.173054 -250.060206) (xy 87.173054 -250.109482) (xy 87.173562 -250.113038)
			(xy 87.174875 -250.123338) (xy 87.176275 -250.144057) (xy 87.176356 -250.15444) (xy 87.505298 -250.15444)
			(xy 87.509258 -250.105386) (xy 87.521035 -250.057602) (xy 87.540326 -250.012326) (xy 87.566629 -249.97073)
			(xy 87.599264 -249.933893) (xy 87.637385 -249.902768) (xy 87.680006 -249.878161) (xy 87.726022 -249.860709)
			(xy 87.774241 -249.850865) (xy 87.823416 -249.848884) (xy 87.872271 -249.854816) (xy 87.919542 -249.868508)
			(xy 87.964004 -249.889606) (xy 88.004507 -249.917562) (xy 88.04 -249.951654) (xy 88.069565 -249.990998)
			(xy 88.092436 -250.034575) (xy 88.10802 -250.081256) (xy 88.115915 -250.129833) (xy 88.11641 -250.15444)
			(xy 88.445352 -250.15444) (xy 88.449312 -250.105386) (xy 88.461089 -250.057602) (xy 88.48038 -250.012326)
			(xy 88.506683 -249.97073) (xy 88.539318 -249.933893) (xy 88.577439 -249.902768) (xy 88.62006 -249.878161)
			(xy 88.666076 -249.860709) (xy 88.714295 -249.850865) (xy 88.76347 -249.848884) (xy 88.812325 -249.854816)
			(xy 88.859596 -249.868508) (xy 88.904058 -249.889606) (xy 88.944561 -249.917562) (xy 88.980054 -249.951654)
			(xy 89.009619 -249.990998) (xy 89.03249 -250.034575) (xy 89.048074 -250.081256) (xy 89.055969 -250.129833)
			(xy 89.056464 -250.15444) (xy 89.385152 -250.15444) (xy 89.389112 -250.105386) (xy 89.400889 -250.057602)
			(xy 89.42018 -250.012326) (xy 89.446483 -249.97073) (xy 89.479118 -249.933893) (xy 89.517239 -249.902768)
			(xy 89.55986 -249.878161) (xy 89.605876 -249.860709) (xy 89.654095 -249.850865) (xy 89.70327 -249.848884)
			(xy 89.752125 -249.854816) (xy 89.799396 -249.868508) (xy 89.843858 -249.889606) (xy 89.884361 -249.917562)
			(xy 89.919854 -249.951654) (xy 89.949419 -249.990998) (xy 89.97229 -250.034575) (xy 89.987874 -250.081256)
			(xy 89.995769 -250.129833) (xy 89.996264 -250.15444) (xy 90.325206 -250.15444) (xy 90.329166 -250.105386)
			(xy 90.340943 -250.057602) (xy 90.360234 -250.012326) (xy 90.386537 -249.97073) (xy 90.419172 -249.933893)
			(xy 90.457293 -249.902768) (xy 90.499914 -249.878161) (xy 90.54593 -249.860709) (xy 90.594149 -249.850865)
			(xy 90.643324 -249.848884) (xy 90.692179 -249.854816) (xy 90.73945 -249.868508) (xy 90.783912 -249.889606)
			(xy 90.824415 -249.917562) (xy 90.859908 -249.951654) (xy 90.889473 -249.990998) (xy 90.912344 -250.034575)
			(xy 90.927928 -250.081256) (xy 90.935823 -250.129833) (xy 90.936318 -250.15444) (xy 91.26526 -250.15444)
			(xy 91.26922 -250.105386) (xy 91.280997 -250.057602) (xy 91.300288 -250.012326) (xy 91.326591 -249.97073)
			(xy 91.359226 -249.933893) (xy 91.397347 -249.902768) (xy 91.439968 -249.878161) (xy 91.485984 -249.860709)
			(xy 91.534203 -249.850865) (xy 91.583378 -249.848884) (xy 91.632233 -249.854816) (xy 91.679504 -249.868508)
			(xy 91.723966 -249.889606) (xy 91.764469 -249.917562) (xy 91.799962 -249.951654) (xy 91.829527 -249.990998)
			(xy 91.852398 -250.034575) (xy 91.867982 -250.081256) (xy 91.875877 -250.129833) (xy 91.876372 -250.15444)
			(xy 92.194883 -250.15444) (xy 92.198978 -250.103712) (xy 92.211157 -250.054298) (xy 92.231105 -250.007478)
			(xy 92.258306 -249.964464) (xy 92.292054 -249.92637) (xy 92.331476 -249.894183) (xy 92.37555 -249.868737)
			(xy 92.423136 -249.85069) (xy 92.473 -249.84051) (xy 92.523852 -249.838461) (xy 92.574373 -249.844595)
			(xy 92.623257 -249.858755) (xy 92.669236 -249.880572) (xy 92.71112 -249.909482) (xy 92.747824 -249.944737)
			(xy 92.778397 -249.985423) (xy 92.802048 -250.030486) (xy 92.818164 -250.07876) (xy 92.826328 -250.128994)
			(xy 92.82684 -250.15444) (xy 93.145114 -250.15444) (xy 93.149074 -250.105386) (xy 93.160851 -250.057602)
			(xy 93.180142 -250.012326) (xy 93.206445 -249.97073) (xy 93.23908 -249.933893) (xy 93.277201 -249.902768)
			(xy 93.319822 -249.878161) (xy 93.365838 -249.860709) (xy 93.414057 -249.850865) (xy 93.463232 -249.848884)
			(xy 93.512087 -249.854816) (xy 93.559358 -249.868508) (xy 93.60382 -249.889606) (xy 93.644323 -249.917562)
			(xy 93.679816 -249.951654) (xy 93.709381 -249.990998) (xy 93.732252 -250.034575) (xy 93.747836 -250.081256)
			(xy 93.755731 -250.129833) (xy 93.756226 -250.15444) (xy 94.085168 -250.15444) (xy 94.089128 -250.105386)
			(xy 94.100905 -250.057602) (xy 94.120196 -250.012326) (xy 94.146499 -249.97073) (xy 94.179134 -249.933893)
			(xy 94.217255 -249.902768) (xy 94.259876 -249.878161) (xy 94.305892 -249.860709) (xy 94.354111 -249.850865)
			(xy 94.403286 -249.848884) (xy 94.452141 -249.854816) (xy 94.499412 -249.868508) (xy 94.543874 -249.889606)
			(xy 94.584377 -249.917562) (xy 94.61987 -249.951654) (xy 94.649435 -249.990998) (xy 94.672306 -250.034575)
			(xy 94.68789 -250.081256) (xy 94.695785 -250.129833) (xy 94.69628 -250.15444) (xy 95.014791 -250.15444)
			(xy 95.018886 -250.103712) (xy 95.031065 -250.054298) (xy 95.051013 -250.007478) (xy 95.078214 -249.964464)
			(xy 95.111962 -249.92637) (xy 95.151384 -249.894183) (xy 95.195458 -249.868737) (xy 95.243044 -249.85069)
			(xy 95.292908 -249.84051) (xy 95.34376 -249.838461) (xy 95.394281 -249.844595) (xy 95.443165 -249.858755)
			(xy 95.489144 -249.880572) (xy 95.531028 -249.909482) (xy 95.567732 -249.944737) (xy 95.598305 -249.985423)
			(xy 95.621956 -250.030486) (xy 95.638072 -250.07876) (xy 95.646236 -250.128994) (xy 95.646748 -250.15444)
			(xy 95.965276 -250.15444) (xy 95.969236 -250.105386) (xy 95.981013 -250.057602) (xy 96.000304 -250.012326)
			(xy 96.026607 -249.97073) (xy 96.059242 -249.933893) (xy 96.097363 -249.902768) (xy 96.139984 -249.878161)
			(xy 96.186 -249.860709) (xy 96.234219 -249.850865) (xy 96.283394 -249.848884) (xy 96.332249 -249.854816)
			(xy 96.37952 -249.868508) (xy 96.423982 -249.889606) (xy 96.464485 -249.917562) (xy 96.499978 -249.951654)
			(xy 96.529543 -249.990998) (xy 96.552414 -250.034575) (xy 96.567998 -250.081256) (xy 96.575893 -250.129833)
			(xy 96.576388 -250.15444) (xy 97.84513 -250.15444) (xy 97.84909 -250.105386) (xy 97.860867 -250.057602)
			(xy 97.880158 -250.012326) (xy 97.906461 -249.97073) (xy 97.939096 -249.933893) (xy 97.977217 -249.902768)
			(xy 98.019838 -249.878161) (xy 98.065854 -249.860709) (xy 98.114073 -249.850865) (xy 98.163248 -249.848884)
			(xy 98.212103 -249.854816) (xy 98.259374 -249.868508) (xy 98.303836 -249.889606) (xy 98.344339 -249.917562)
			(xy 98.379832 -249.951654) (xy 98.409397 -249.990998) (xy 98.432268 -250.034575) (xy 98.447852 -250.081256)
			(xy 98.455747 -250.129833) (xy 98.456242 -250.15444) (xy 98.455747 -250.179047) (xy 98.447852 -250.227624)
			(xy 98.432268 -250.274305) (xy 98.409397 -250.317882) (xy 98.379832 -250.357226) (xy 98.344339 -250.391318)
			(xy 98.303836 -250.419274) (xy 98.259374 -250.440372) (xy 98.212103 -250.454064) (xy 98.163248 -250.459996)
			(xy 98.114073 -250.458015) (xy 98.065854 -250.448171) (xy 98.019838 -250.430719) (xy 97.977217 -250.406112)
			(xy 97.939096 -250.374987) (xy 97.906461 -250.33815) (xy 97.880158 -250.296554) (xy 97.860867 -250.251278)
			(xy 97.84909 -250.203494) (xy 97.84513 -250.15444) (xy 96.576388 -250.15444) (xy 96.575893 -250.179047)
			(xy 96.567998 -250.227624) (xy 96.552414 -250.274305) (xy 96.529543 -250.317882) (xy 96.499978 -250.357226)
			(xy 96.464485 -250.391318) (xy 96.423982 -250.419274) (xy 96.37952 -250.440372) (xy 96.332249 -250.454064)
			(xy 96.283394 -250.459996) (xy 96.234219 -250.458015) (xy 96.186 -250.448171) (xy 96.139984 -250.430719)
			(xy 96.097363 -250.406112) (xy 96.059242 -250.374987) (xy 96.026607 -250.33815) (xy 96.000304 -250.296554)
			(xy 95.981013 -250.251278) (xy 95.969236 -250.203494) (xy 95.965276 -250.15444) (xy 95.646748 -250.15444)
			(xy 95.646236 -250.179886) (xy 95.638072 -250.23012) (xy 95.621956 -250.278394) (xy 95.598305 -250.323457)
			(xy 95.567732 -250.364143) (xy 95.531028 -250.399398) (xy 95.489144 -250.428308) (xy 95.443165 -250.450125)
			(xy 95.394281 -250.464285) (xy 95.34376 -250.470419) (xy 95.292908 -250.46837) (xy 95.243044 -250.45819)
			(xy 95.195458 -250.440143) (xy 95.151384 -250.414697) (xy 95.111962 -250.38251) (xy 95.078214 -250.344416)
			(xy 95.051013 -250.301402) (xy 95.031065 -250.254582) (xy 95.018886 -250.205168) (xy 95.014791 -250.15444)
			(xy 94.69628 -250.15444) (xy 94.695785 -250.179047) (xy 94.68789 -250.227624) (xy 94.672306 -250.274305)
			(xy 94.649435 -250.317882) (xy 94.61987 -250.357226) (xy 94.584377 -250.391318) (xy 94.543874 -250.419274)
			(xy 94.499412 -250.440372) (xy 94.452141 -250.454064) (xy 94.403286 -250.459996) (xy 94.354111 -250.458015)
			(xy 94.305892 -250.448171) (xy 94.259876 -250.430719) (xy 94.217255 -250.406112) (xy 94.179134 -250.374987)
			(xy 94.146499 -250.33815) (xy 94.120196 -250.296554) (xy 94.100905 -250.251278) (xy 94.089128 -250.203494)
			(xy 94.085168 -250.15444) (xy 93.756226 -250.15444) (xy 93.755731 -250.179047) (xy 93.747836 -250.227624)
			(xy 93.732252 -250.274305) (xy 93.709381 -250.317882) (xy 93.679816 -250.357226) (xy 93.644323 -250.391318)
			(xy 93.60382 -250.419274) (xy 93.559358 -250.440372) (xy 93.512087 -250.454064) (xy 93.463232 -250.459996)
			(xy 93.414057 -250.458015) (xy 93.365838 -250.448171) (xy 93.319822 -250.430719) (xy 93.277201 -250.406112)
			(xy 93.23908 -250.374987) (xy 93.206445 -250.33815) (xy 93.180142 -250.296554) (xy 93.160851 -250.251278)
			(xy 93.149074 -250.203494) (xy 93.145114 -250.15444) (xy 92.82684 -250.15444) (xy 92.826328 -250.179886)
			(xy 92.818164 -250.23012) (xy 92.802048 -250.278394) (xy 92.778397 -250.323457) (xy 92.747824 -250.364143)
			(xy 92.71112 -250.399398) (xy 92.669236 -250.428308) (xy 92.623257 -250.450125) (xy 92.574373 -250.464285)
			(xy 92.523852 -250.470419) (xy 92.473 -250.46837) (xy 92.423136 -250.45819) (xy 92.37555 -250.440143)
			(xy 92.331476 -250.414697) (xy 92.292054 -250.38251) (xy 92.258306 -250.344416) (xy 92.231105 -250.301402)
			(xy 92.211157 -250.254582) (xy 92.198978 -250.205168) (xy 92.194883 -250.15444) (xy 91.876372 -250.15444)
			(xy 91.875877 -250.179047) (xy 91.867982 -250.227624) (xy 91.852398 -250.274305) (xy 91.829527 -250.317882)
			(xy 91.799962 -250.357226) (xy 91.764469 -250.391318) (xy 91.723966 -250.419274) (xy 91.679504 -250.440372)
			(xy 91.632233 -250.454064) (xy 91.583378 -250.459996) (xy 91.534203 -250.458015) (xy 91.485984 -250.448171)
			(xy 91.439968 -250.430719) (xy 91.397347 -250.406112) (xy 91.359226 -250.374987) (xy 91.326591 -250.33815)
			(xy 91.300288 -250.296554) (xy 91.280997 -250.251278) (xy 91.26922 -250.203494) (xy 91.26526 -250.15444)
			(xy 90.936318 -250.15444) (xy 90.935823 -250.179047) (xy 90.927928 -250.227624) (xy 90.912344 -250.274305)
			(xy 90.889473 -250.317882) (xy 90.859908 -250.357226) (xy 90.824415 -250.391318) (xy 90.783912 -250.419274)
			(xy 90.73945 -250.440372) (xy 90.692179 -250.454064) (xy 90.643324 -250.459996) (xy 90.594149 -250.458015)
			(xy 90.54593 -250.448171) (xy 90.499914 -250.430719) (xy 90.457293 -250.406112) (xy 90.419172 -250.374987)
			(xy 90.386537 -250.33815) (xy 90.360234 -250.296554) (xy 90.340943 -250.251278) (xy 90.329166 -250.203494)
			(xy 90.325206 -250.15444) (xy 89.996264 -250.15444) (xy 89.995769 -250.179047) (xy 89.987874 -250.227624)
			(xy 89.97229 -250.274305) (xy 89.949419 -250.317882) (xy 89.919854 -250.357226) (xy 89.884361 -250.391318)
			(xy 89.843858 -250.419274) (xy 89.799396 -250.440372) (xy 89.752125 -250.454064) (xy 89.70327 -250.459996)
			(xy 89.654095 -250.458015) (xy 89.605876 -250.448171) (xy 89.55986 -250.430719) (xy 89.517239 -250.406112)
			(xy 89.479118 -250.374987) (xy 89.446483 -250.33815) (xy 89.42018 -250.296554) (xy 89.400889 -250.251278)
			(xy 89.389112 -250.203494) (xy 89.385152 -250.15444) (xy 89.056464 -250.15444) (xy 89.055969 -250.179047)
			(xy 89.048074 -250.227624) (xy 89.03249 -250.274305) (xy 89.009619 -250.317882) (xy 88.980054 -250.357226)
			(xy 88.944561 -250.391318) (xy 88.904058 -250.419274) (xy 88.859596 -250.440372) (xy 88.812325 -250.454064)
			(xy 88.76347 -250.459996) (xy 88.714295 -250.458015) (xy 88.666076 -250.448171) (xy 88.62006 -250.430719)
			(xy 88.577439 -250.406112) (xy 88.539318 -250.374987) (xy 88.506683 -250.33815) (xy 88.48038 -250.296554)
			(xy 88.461089 -250.251278) (xy 88.449312 -250.203494) (xy 88.445352 -250.15444) (xy 88.11641 -250.15444)
			(xy 88.115915 -250.179047) (xy 88.10802 -250.227624) (xy 88.092436 -250.274305) (xy 88.069565 -250.317882)
			(xy 88.04 -250.357226) (xy 88.004507 -250.391318) (xy 87.964004 -250.419274) (xy 87.919542 -250.440372)
			(xy 87.872271 -250.454064) (xy 87.823416 -250.459996) (xy 87.774241 -250.458015) (xy 87.726022 -250.448171)
			(xy 87.680006 -250.430719) (xy 87.637385 -250.406112) (xy 87.599264 -250.374987) (xy 87.566629 -250.33815)
			(xy 87.540326 -250.296554) (xy 87.521035 -250.251278) (xy 87.509258 -250.203494) (xy 87.505298 -250.15444)
			(xy 87.176356 -250.15444) (xy 87.176278 -250.164823) (xy 87.174877 -250.185542) (xy 87.173562 -250.195842)
			(xy 87.173054 -250.199398) (xy 87.173054 -250.23191) (xy 87.173511 -250.241789) (xy 87.180948 -250.260093)
			(xy 87.187532 -250.26747) (xy 87.187786 -250.267724) (xy 87.760302 -250.84024) (xy 87.767012 -250.847479)
			(xy 87.774597 -250.865684) (xy 87.775034 -250.875546) (xy 87.775034 -250.964446) (xy 87.975198 -250.964446)
			(xy 87.979158 -250.915392) (xy 87.990935 -250.867608) (xy 88.010226 -250.822332) (xy 88.036529 -250.780736)
			(xy 88.069164 -250.743899) (xy 88.107285 -250.712774) (xy 88.149906 -250.688167) (xy 88.195922 -250.670715)
			(xy 88.244141 -250.660871) (xy 88.293316 -250.65889) (xy 88.342171 -250.664822) (xy 88.389442 -250.678514)
			(xy 88.433904 -250.699612) (xy 88.474407 -250.727568) (xy 88.5099 -250.76166) (xy 88.539465 -250.801004)
			(xy 88.562336 -250.844581) (xy 88.57792 -250.891262) (xy 88.585815 -250.939839) (xy 88.58631 -250.964446)
			(xy 88.915252 -250.964446) (xy 88.919212 -250.915392) (xy 88.930989 -250.867608) (xy 88.95028 -250.822332)
			(xy 88.976583 -250.780736) (xy 89.009218 -250.743899) (xy 89.047339 -250.712774) (xy 89.08996 -250.688167)
			(xy 89.135976 -250.670715) (xy 89.184195 -250.660871) (xy 89.23337 -250.65889) (xy 89.282225 -250.664822)
			(xy 89.329496 -250.678514) (xy 89.373958 -250.699612) (xy 89.414461 -250.727568) (xy 89.449954 -250.76166)
			(xy 89.479519 -250.801004) (xy 89.50239 -250.844581) (xy 89.517974 -250.891262) (xy 89.525869 -250.939839)
			(xy 89.526364 -250.964446) (xy 89.855306 -250.964446) (xy 89.859266 -250.915392) (xy 89.871043 -250.867608)
			(xy 89.890334 -250.822332) (xy 89.916637 -250.780736) (xy 89.949272 -250.743899) (xy 89.987393 -250.712774)
			(xy 90.030014 -250.688167) (xy 90.07603 -250.670715) (xy 90.124249 -250.660871) (xy 90.173424 -250.65889)
			(xy 90.222279 -250.664822) (xy 90.26955 -250.678514) (xy 90.314012 -250.699612) (xy 90.354515 -250.727568)
			(xy 90.390008 -250.76166) (xy 90.419573 -250.801004) (xy 90.442444 -250.844581) (xy 90.458028 -250.891262)
			(xy 90.465923 -250.939839) (xy 90.466418 -250.964446) (xy 90.79536 -250.964446) (xy 90.79932 -250.915392)
			(xy 90.811097 -250.867608) (xy 90.830388 -250.822332) (xy 90.856691 -250.780736) (xy 90.889326 -250.743899)
			(xy 90.927447 -250.712774) (xy 90.970068 -250.688167) (xy 91.016084 -250.670715) (xy 91.064303 -250.660871)
			(xy 91.113478 -250.65889) (xy 91.162333 -250.664822) (xy 91.209604 -250.678514) (xy 91.254066 -250.699612)
			(xy 91.294569 -250.727568) (xy 91.330062 -250.76166) (xy 91.359627 -250.801004) (xy 91.382498 -250.844581)
			(xy 91.398082 -250.891262) (xy 91.405977 -250.939839) (xy 91.406472 -250.964446) (xy 91.724729 -250.964446)
			(xy 91.728824 -250.913718) (xy 91.741003 -250.864304) (xy 91.760951 -250.817484) (xy 91.788152 -250.77447)
			(xy 91.8219 -250.736376) (xy 91.861322 -250.704189) (xy 91.905396 -250.678743) (xy 91.952982 -250.660696)
			(xy 92.002846 -250.650516) (xy 92.053698 -250.648467) (xy 92.104219 -250.654601) (xy 92.153103 -250.668761)
			(xy 92.199082 -250.690578) (xy 92.240966 -250.719488) (xy 92.27767 -250.754743) (xy 92.308243 -250.795429)
			(xy 92.331894 -250.840492) (xy 92.34801 -250.888766) (xy 92.356174 -250.939) (xy 92.356686 -250.964446)
			(xy 92.675214 -250.964446) (xy 92.679174 -250.915392) (xy 92.690951 -250.867608) (xy 92.710242 -250.822332)
			(xy 92.736545 -250.780736) (xy 92.76918 -250.743899) (xy 92.807301 -250.712774) (xy 92.849922 -250.688167)
			(xy 92.895938 -250.670715) (xy 92.944157 -250.660871) (xy 92.993332 -250.65889) (xy 93.042187 -250.664822)
			(xy 93.089458 -250.678514) (xy 93.13392 -250.699612) (xy 93.174423 -250.727568) (xy 93.209916 -250.76166)
			(xy 93.239481 -250.801004) (xy 93.262352 -250.844581) (xy 93.277936 -250.891262) (xy 93.285831 -250.939839)
			(xy 93.286326 -250.964446) (xy 93.615268 -250.964446) (xy 93.619228 -250.915392) (xy 93.631005 -250.867608)
			(xy 93.650296 -250.822332) (xy 93.676599 -250.780736) (xy 93.709234 -250.743899) (xy 93.747355 -250.712774)
			(xy 93.789976 -250.688167) (xy 93.835992 -250.670715) (xy 93.884211 -250.660871) (xy 93.933386 -250.65889)
			(xy 93.982241 -250.664822) (xy 94.029512 -250.678514) (xy 94.073974 -250.699612) (xy 94.114477 -250.727568)
			(xy 94.14997 -250.76166) (xy 94.179535 -250.801004) (xy 94.202406 -250.844581) (xy 94.21799 -250.891262)
			(xy 94.225885 -250.939839) (xy 94.22638 -250.964446) (xy 94.555322 -250.964446) (xy 94.559282 -250.915392)
			(xy 94.571059 -250.867608) (xy 94.59035 -250.822332) (xy 94.616653 -250.780736) (xy 94.649288 -250.743899)
			(xy 94.687409 -250.712774) (xy 94.73003 -250.688167) (xy 94.776046 -250.670715) (xy 94.824265 -250.660871)
			(xy 94.87344 -250.65889) (xy 94.922295 -250.664822) (xy 94.969566 -250.678514) (xy 95.014028 -250.699612)
			(xy 95.054531 -250.727568) (xy 95.090024 -250.76166) (xy 95.119589 -250.801004) (xy 95.14246 -250.844581)
			(xy 95.158044 -250.891262) (xy 95.165939 -250.939839) (xy 95.166434 -250.964446) (xy 95.484691 -250.964446)
			(xy 95.488786 -250.913718) (xy 95.500965 -250.864304) (xy 95.520913 -250.817484) (xy 95.548114 -250.77447)
			(xy 95.581862 -250.736376) (xy 95.621284 -250.704189) (xy 95.665358 -250.678743) (xy 95.712944 -250.660696)
			(xy 95.762808 -250.650516) (xy 95.81366 -250.648467) (xy 95.864181 -250.654601) (xy 95.913065 -250.668761)
			(xy 95.959044 -250.690578) (xy 96.000928 -250.719488) (xy 96.037632 -250.754743) (xy 96.068205 -250.795429)
			(xy 96.091856 -250.840492) (xy 96.107972 -250.888766) (xy 96.116136 -250.939) (xy 96.116648 -250.964446)
			(xy 97.37523 -250.964446) (xy 97.37919 -250.915392) (xy 97.390967 -250.867608) (xy 97.410258 -250.822332)
			(xy 97.436561 -250.780736) (xy 97.469196 -250.743899) (xy 97.507317 -250.712774) (xy 97.549938 -250.688167)
			(xy 97.595954 -250.670715) (xy 97.644173 -250.660871) (xy 97.693348 -250.65889) (xy 97.742203 -250.664822)
			(xy 97.789474 -250.678514) (xy 97.833936 -250.699612) (xy 97.874439 -250.727568) (xy 97.909932 -250.76166)
			(xy 97.939497 -250.801004) (xy 97.962368 -250.844581) (xy 97.977952 -250.891262) (xy 97.985847 -250.939839)
			(xy 97.986342 -250.964446) (xy 99.255338 -250.964446) (xy 99.259298 -250.915392) (xy 99.271075 -250.867608)
			(xy 99.290366 -250.822332) (xy 99.316669 -250.780736) (xy 99.349304 -250.743899) (xy 99.387425 -250.712774)
			(xy 99.430046 -250.688167) (xy 99.476062 -250.670715) (xy 99.524281 -250.660871) (xy 99.573456 -250.65889)
			(xy 99.622311 -250.664822) (xy 99.669582 -250.678514) (xy 99.714044 -250.699612) (xy 99.754547 -250.727568)
			(xy 99.79004 -250.76166) (xy 99.819605 -250.801004) (xy 99.842476 -250.844581) (xy 99.85806 -250.891262)
			(xy 99.865955 -250.939839) (xy 99.86645 -250.964446) (xy 99.865955 -250.989053) (xy 99.85806 -251.03763)
			(xy 99.842476 -251.084311) (xy 99.819605 -251.127888) (xy 99.79004 -251.167232) (xy 99.754547 -251.201324)
			(xy 99.714044 -251.22928) (xy 99.669582 -251.250378) (xy 99.622311 -251.26407) (xy 99.573456 -251.270002)
			(xy 99.524281 -251.268021) (xy 99.476062 -251.258177) (xy 99.430046 -251.240725) (xy 99.387425 -251.216118)
			(xy 99.349304 -251.184993) (xy 99.316669 -251.148156) (xy 99.290366 -251.10656) (xy 99.271075 -251.061284)
			(xy 99.259298 -251.0135) (xy 99.255338 -250.964446) (xy 97.986342 -250.964446) (xy 97.985847 -250.989053)
			(xy 97.977952 -251.03763) (xy 97.962368 -251.084311) (xy 97.939497 -251.127888) (xy 97.909932 -251.167232)
			(xy 97.874439 -251.201324) (xy 97.833936 -251.22928) (xy 97.789474 -251.250378) (xy 97.742203 -251.26407)
			(xy 97.693348 -251.270002) (xy 97.644173 -251.268021) (xy 97.595954 -251.258177) (xy 97.549938 -251.240725)
			(xy 97.507317 -251.216118) (xy 97.469196 -251.184993) (xy 97.436561 -251.148156) (xy 97.410258 -251.10656)
			(xy 97.390967 -251.061284) (xy 97.37919 -251.0135) (xy 97.37523 -250.964446) (xy 96.116648 -250.964446)
			(xy 96.116136 -250.989892) (xy 96.107972 -251.040126) (xy 96.091856 -251.0884) (xy 96.068205 -251.133463)
			(xy 96.037632 -251.174149) (xy 96.000928 -251.209404) (xy 95.959044 -251.238314) (xy 95.913065 -251.260131)
			(xy 95.864181 -251.274291) (xy 95.81366 -251.280425) (xy 95.762808 -251.278376) (xy 95.712944 -251.268196)
			(xy 95.665358 -251.250149) (xy 95.621284 -251.224703) (xy 95.581862 -251.192516) (xy 95.548114 -251.154422)
			(xy 95.520913 -251.111408) (xy 95.500965 -251.064588) (xy 95.488786 -251.015174) (xy 95.484691 -250.964446)
			(xy 95.166434 -250.964446) (xy 95.165939 -250.989053) (xy 95.158044 -251.03763) (xy 95.14246 -251.084311)
			(xy 95.119589 -251.127888) (xy 95.090024 -251.167232) (xy 95.054531 -251.201324) (xy 95.014028 -251.22928)
			(xy 94.969566 -251.250378) (xy 94.922295 -251.26407) (xy 94.87344 -251.270002) (xy 94.824265 -251.268021)
			(xy 94.776046 -251.258177) (xy 94.73003 -251.240725) (xy 94.687409 -251.216118) (xy 94.649288 -251.184993)
			(xy 94.616653 -251.148156) (xy 94.59035 -251.10656) (xy 94.571059 -251.061284) (xy 94.559282 -251.0135)
			(xy 94.555322 -250.964446) (xy 94.22638 -250.964446) (xy 94.225885 -250.989053) (xy 94.21799 -251.03763)
			(xy 94.202406 -251.084311) (xy 94.179535 -251.127888) (xy 94.14997 -251.167232) (xy 94.114477 -251.201324)
			(xy 94.073974 -251.22928) (xy 94.029512 -251.250378) (xy 93.982241 -251.26407) (xy 93.933386 -251.270002)
			(xy 93.884211 -251.268021) (xy 93.835992 -251.258177) (xy 93.789976 -251.240725) (xy 93.747355 -251.216118)
			(xy 93.709234 -251.184993) (xy 93.676599 -251.148156) (xy 93.650296 -251.10656) (xy 93.631005 -251.061284)
			(xy 93.619228 -251.0135) (xy 93.615268 -250.964446) (xy 93.286326 -250.964446) (xy 93.285831 -250.989053)
			(xy 93.277936 -251.03763) (xy 93.262352 -251.084311) (xy 93.239481 -251.127888) (xy 93.209916 -251.167232)
			(xy 93.174423 -251.201324) (xy 93.13392 -251.22928) (xy 93.089458 -251.250378) (xy 93.042187 -251.26407)
			(xy 92.993332 -251.270002) (xy 92.944157 -251.268021) (xy 92.895938 -251.258177) (xy 92.849922 -251.240725)
			(xy 92.807301 -251.216118) (xy 92.76918 -251.184993) (xy 92.736545 -251.148156) (xy 92.710242 -251.10656)
			(xy 92.690951 -251.061284) (xy 92.679174 -251.0135) (xy 92.675214 -250.964446) (xy 92.356686 -250.964446)
			(xy 92.356174 -250.989892) (xy 92.34801 -251.040126) (xy 92.331894 -251.0884) (xy 92.308243 -251.133463)
			(xy 92.27767 -251.174149) (xy 92.240966 -251.209404) (xy 92.199082 -251.238314) (xy 92.153103 -251.260131)
			(xy 92.104219 -251.274291) (xy 92.053698 -251.280425) (xy 92.002846 -251.278376) (xy 91.952982 -251.268196)
			(xy 91.905396 -251.250149) (xy 91.861322 -251.224703) (xy 91.8219 -251.192516) (xy 91.788152 -251.154422)
			(xy 91.760951 -251.111408) (xy 91.741003 -251.064588) (xy 91.728824 -251.015174) (xy 91.724729 -250.964446)
			(xy 91.406472 -250.964446) (xy 91.405977 -250.989053) (xy 91.398082 -251.03763) (xy 91.382498 -251.084311)
			(xy 91.359627 -251.127888) (xy 91.330062 -251.167232) (xy 91.294569 -251.201324) (xy 91.254066 -251.22928)
			(xy 91.209604 -251.250378) (xy 91.162333 -251.26407) (xy 91.113478 -251.270002) (xy 91.064303 -251.268021)
			(xy 91.016084 -251.258177) (xy 90.970068 -251.240725) (xy 90.927447 -251.216118) (xy 90.889326 -251.184993)
			(xy 90.856691 -251.148156) (xy 90.830388 -251.10656) (xy 90.811097 -251.061284) (xy 90.79932 -251.0135)
			(xy 90.79536 -250.964446) (xy 90.466418 -250.964446) (xy 90.465923 -250.989053) (xy 90.458028 -251.03763)
			(xy 90.442444 -251.084311) (xy 90.419573 -251.127888) (xy 90.390008 -251.167232) (xy 90.354515 -251.201324)
			(xy 90.314012 -251.22928) (xy 90.26955 -251.250378) (xy 90.222279 -251.26407) (xy 90.173424 -251.270002)
			(xy 90.124249 -251.268021) (xy 90.07603 -251.258177) (xy 90.030014 -251.240725) (xy 89.987393 -251.216118)
			(xy 89.949272 -251.184993) (xy 89.916637 -251.148156) (xy 89.890334 -251.10656) (xy 89.871043 -251.061284)
			(xy 89.859266 -251.0135) (xy 89.855306 -250.964446) (xy 89.526364 -250.964446) (xy 89.525869 -250.989053)
			(xy 89.517974 -251.03763) (xy 89.50239 -251.084311) (xy 89.479519 -251.127888) (xy 89.449954 -251.167232)
			(xy 89.414461 -251.201324) (xy 89.373958 -251.22928) (xy 89.329496 -251.250378) (xy 89.282225 -251.26407)
			(xy 89.23337 -251.270002) (xy 89.184195 -251.268021) (xy 89.135976 -251.258177) (xy 89.08996 -251.240725)
			(xy 89.047339 -251.216118) (xy 89.009218 -251.184993) (xy 88.976583 -251.148156) (xy 88.95028 -251.10656)
			(xy 88.930989 -251.061284) (xy 88.919212 -251.0135) (xy 88.915252 -250.964446) (xy 88.58631 -250.964446)
			(xy 88.585815 -250.989053) (xy 88.57792 -251.03763) (xy 88.562336 -251.084311) (xy 88.539465 -251.127888)
			(xy 88.5099 -251.167232) (xy 88.474407 -251.201324) (xy 88.433904 -251.22928) (xy 88.389442 -251.250378)
			(xy 88.342171 -251.26407) (xy 88.293316 -251.270002) (xy 88.244141 -251.268021) (xy 88.195922 -251.258177)
			(xy 88.149906 -251.240725) (xy 88.107285 -251.216118) (xy 88.069164 -251.184993) (xy 88.036529 -251.148156)
			(xy 88.010226 -251.10656) (xy 87.990935 -251.061284) (xy 87.979158 -251.0135) (xy 87.975198 -250.964446)
			(xy 87.775034 -250.964446) (xy 87.775034 -251.101098) (xy 87.774494 -251.110934) (xy 87.766904 -251.129091)
			(xy 87.760302 -251.136404) (xy 87.314786 -251.58192) (xy 87.308074 -251.589158) (xy 87.300483 -251.607364)
			(xy 87.300054 -251.617226) (xy 87.300054 -251.774452) (xy 87.505298 -251.774452) (xy 87.509258 -251.725398)
			(xy 87.521035 -251.677614) (xy 87.540326 -251.632338) (xy 87.566629 -251.590742) (xy 87.599264 -251.553905)
			(xy 87.637385 -251.52278) (xy 87.680006 -251.498173) (xy 87.726022 -251.480721) (xy 87.774241 -251.470877)
			(xy 87.823416 -251.468896) (xy 87.872271 -251.474828) (xy 87.919542 -251.48852) (xy 87.964004 -251.509618)
			(xy 88.004507 -251.537574) (xy 88.04 -251.571666) (xy 88.069565 -251.61101) (xy 88.092436 -251.654587)
			(xy 88.10802 -251.701268) (xy 88.115915 -251.749845) (xy 88.11641 -251.774452) (xy 88.445352 -251.774452)
			(xy 88.449312 -251.725398) (xy 88.461089 -251.677614) (xy 88.48038 -251.632338) (xy 88.506683 -251.590742)
			(xy 88.539318 -251.553905) (xy 88.577439 -251.52278) (xy 88.62006 -251.498173) (xy 88.666076 -251.480721)
			(xy 88.714295 -251.470877) (xy 88.76347 -251.468896) (xy 88.812325 -251.474828) (xy 88.859596 -251.48852)
			(xy 88.904058 -251.509618) (xy 88.944561 -251.537574) (xy 88.980054 -251.571666) (xy 89.009619 -251.61101)
			(xy 89.03249 -251.654587) (xy 89.048074 -251.701268) (xy 89.055969 -251.749845) (xy 89.056464 -251.774452)
			(xy 89.385152 -251.774452) (xy 89.389112 -251.725398) (xy 89.400889 -251.677614) (xy 89.42018 -251.632338)
			(xy 89.446483 -251.590742) (xy 89.479118 -251.553905) (xy 89.517239 -251.52278) (xy 89.55986 -251.498173)
			(xy 89.605876 -251.480721) (xy 89.654095 -251.470877) (xy 89.70327 -251.468896) (xy 89.752125 -251.474828)
			(xy 89.799396 -251.48852) (xy 89.843858 -251.509618) (xy 89.884361 -251.537574) (xy 89.919854 -251.571666)
			(xy 89.949419 -251.61101) (xy 89.97229 -251.654587) (xy 89.987874 -251.701268) (xy 89.995769 -251.749845)
			(xy 89.996264 -251.774452) (xy 90.314775 -251.774452) (xy 90.31887 -251.723724) (xy 90.331049 -251.67431)
			(xy 90.350997 -251.62749) (xy 90.378198 -251.584476) (xy 90.411946 -251.546382) (xy 90.451368 -251.514195)
			(xy 90.495442 -251.488749) (xy 90.543028 -251.470702) (xy 90.592892 -251.460522) (xy 90.643744 -251.458473)
			(xy 90.694265 -251.464607) (xy 90.743149 -251.478767) (xy 90.789128 -251.500584) (xy 90.831012 -251.529494)
			(xy 90.867716 -251.564749) (xy 90.898289 -251.605435) (xy 90.92194 -251.650498) (xy 90.938056 -251.698772)
			(xy 90.94622 -251.749006) (xy 90.946732 -251.774452) (xy 91.26526 -251.774452) (xy 91.26922 -251.725398)
			(xy 91.280997 -251.677614) (xy 91.300288 -251.632338) (xy 91.326591 -251.590742) (xy 91.359226 -251.553905)
			(xy 91.397347 -251.52278) (xy 91.439968 -251.498173) (xy 91.485984 -251.480721) (xy 91.534203 -251.470877)
			(xy 91.583378 -251.468896) (xy 91.632233 -251.474828) (xy 91.679504 -251.48852) (xy 91.723966 -251.509618)
			(xy 91.764469 -251.537574) (xy 91.799962 -251.571666) (xy 91.829527 -251.61101) (xy 91.852398 -251.654587)
			(xy 91.867982 -251.701268) (xy 91.875877 -251.749845) (xy 91.876372 -251.774452) (xy 92.205314 -251.774452)
			(xy 92.209274 -251.725398) (xy 92.221051 -251.677614) (xy 92.240342 -251.632338) (xy 92.266645 -251.590742)
			(xy 92.29928 -251.553905) (xy 92.337401 -251.52278) (xy 92.380022 -251.498173) (xy 92.426038 -251.480721)
			(xy 92.474257 -251.470877) (xy 92.523432 -251.468896) (xy 92.572287 -251.474828) (xy 92.619558 -251.48852)
			(xy 92.66402 -251.509618) (xy 92.704523 -251.537574) (xy 92.740016 -251.571666) (xy 92.769581 -251.61101)
			(xy 92.792452 -251.654587) (xy 92.808036 -251.701268) (xy 92.815931 -251.749845) (xy 92.816426 -251.774452)
			(xy 93.145114 -251.774452) (xy 93.149074 -251.725398) (xy 93.160851 -251.677614) (xy 93.180142 -251.632338)
			(xy 93.206445 -251.590742) (xy 93.23908 -251.553905) (xy 93.277201 -251.52278) (xy 93.319822 -251.498173)
			(xy 93.365838 -251.480721) (xy 93.414057 -251.470877) (xy 93.463232 -251.468896) (xy 93.512087 -251.474828)
			(xy 93.559358 -251.48852) (xy 93.60382 -251.509618) (xy 93.644323 -251.537574) (xy 93.679816 -251.571666)
			(xy 93.709381 -251.61101) (xy 93.732252 -251.654587) (xy 93.747836 -251.701268) (xy 93.755731 -251.749845)
			(xy 93.756226 -251.774452) (xy 94.074737 -251.774452) (xy 94.078832 -251.723724) (xy 94.091011 -251.67431)
			(xy 94.110959 -251.62749) (xy 94.13816 -251.584476) (xy 94.171908 -251.546382) (xy 94.21133 -251.514195)
			(xy 94.255404 -251.488749) (xy 94.30299 -251.470702) (xy 94.352854 -251.460522) (xy 94.403706 -251.458473)
			(xy 94.454227 -251.464607) (xy 94.503111 -251.478767) (xy 94.54909 -251.500584) (xy 94.590974 -251.529494)
			(xy 94.627678 -251.564749) (xy 94.658251 -251.605435) (xy 94.681902 -251.650498) (xy 94.698018 -251.698772)
			(xy 94.706182 -251.749006) (xy 94.706694 -251.774452) (xy 95.025222 -251.774452) (xy 95.029182 -251.725398)
			(xy 95.040959 -251.677614) (xy 95.06025 -251.632338) (xy 95.086553 -251.590742) (xy 95.119188 -251.553905)
			(xy 95.157309 -251.52278) (xy 95.19993 -251.498173) (xy 95.245946 -251.480721) (xy 95.294165 -251.470877)
			(xy 95.34334 -251.468896) (xy 95.392195 -251.474828) (xy 95.439466 -251.48852) (xy 95.483928 -251.509618)
			(xy 95.524431 -251.537574) (xy 95.559924 -251.571666) (xy 95.589489 -251.61101) (xy 95.61236 -251.654587)
			(xy 95.627944 -251.701268) (xy 95.635839 -251.749845) (xy 95.636334 -251.774452) (xy 95.965276 -251.774452)
			(xy 95.969236 -251.725398) (xy 95.981013 -251.677614) (xy 96.000304 -251.632338) (xy 96.026607 -251.590742)
			(xy 96.059242 -251.553905) (xy 96.097363 -251.52278) (xy 96.139984 -251.498173) (xy 96.186 -251.480721)
			(xy 96.234219 -251.470877) (xy 96.283394 -251.468896) (xy 96.332249 -251.474828) (xy 96.37952 -251.48852)
			(xy 96.423982 -251.509618) (xy 96.464485 -251.537574) (xy 96.499978 -251.571666) (xy 96.529543 -251.61101)
			(xy 96.552414 -251.654587) (xy 96.567998 -251.701268) (xy 96.575893 -251.749845) (xy 96.576388 -251.774452)
			(xy 97.84513 -251.774452) (xy 97.84909 -251.725398) (xy 97.860867 -251.677614) (xy 97.880158 -251.632338)
			(xy 97.906461 -251.590742) (xy 97.939096 -251.553905) (xy 97.977217 -251.52278) (xy 98.019838 -251.498173)
			(xy 98.065854 -251.480721) (xy 98.114073 -251.470877) (xy 98.163248 -251.468896) (xy 98.212103 -251.474828)
			(xy 98.259374 -251.48852) (xy 98.303836 -251.509618) (xy 98.344339 -251.537574) (xy 98.379832 -251.571666)
			(xy 98.409397 -251.61101) (xy 98.432268 -251.654587) (xy 98.447852 -251.701268) (xy 98.455747 -251.749845)
			(xy 98.456242 -251.774452) (xy 99.725238 -251.774452) (xy 99.729198 -251.725398) (xy 99.740975 -251.677614)
			(xy 99.760266 -251.632338) (xy 99.786569 -251.590742) (xy 99.819204 -251.553905) (xy 99.857325 -251.52278)
			(xy 99.899946 -251.498173) (xy 99.945962 -251.480721) (xy 99.994181 -251.470877) (xy 100.043356 -251.468896)
			(xy 100.092211 -251.474828) (xy 100.139482 -251.48852) (xy 100.183944 -251.509618) (xy 100.224447 -251.537574)
			(xy 100.25994 -251.571666) (xy 100.289505 -251.61101) (xy 100.312376 -251.654587) (xy 100.32796 -251.701268)
			(xy 100.335855 -251.749845) (xy 100.33635 -251.774452) (xy 100.335855 -251.799059) (xy 100.32796 -251.847636)
			(xy 100.312376 -251.894317) (xy 100.289505 -251.937894) (xy 100.25994 -251.977238) (xy 100.224447 -252.01133)
			(xy 100.183944 -252.039286) (xy 100.139482 -252.060384) (xy 100.092211 -252.074076) (xy 100.043356 -252.080008)
			(xy 99.994181 -252.078027) (xy 99.945962 -252.068183) (xy 99.899946 -252.050731) (xy 99.857325 -252.026124)
			(xy 99.819204 -251.994999) (xy 99.786569 -251.958162) (xy 99.760266 -251.916566) (xy 99.740975 -251.87129)
			(xy 99.729198 -251.823506) (xy 99.725238 -251.774452) (xy 98.456242 -251.774452) (xy 98.455747 -251.799059)
			(xy 98.447852 -251.847636) (xy 98.432268 -251.894317) (xy 98.409397 -251.937894) (xy 98.379832 -251.977238)
			(xy 98.344339 -252.01133) (xy 98.303836 -252.039286) (xy 98.259374 -252.060384) (xy 98.212103 -252.074076)
			(xy 98.163248 -252.080008) (xy 98.114073 -252.078027) (xy 98.065854 -252.068183) (xy 98.019838 -252.050731)
			(xy 97.977217 -252.026124) (xy 97.939096 -251.994999) (xy 97.906461 -251.958162) (xy 97.880158 -251.916566)
			(xy 97.860867 -251.87129) (xy 97.84909 -251.823506) (xy 97.84513 -251.774452) (xy 96.576388 -251.774452)
			(xy 96.575893 -251.799059) (xy 96.567998 -251.847636) (xy 96.552414 -251.894317) (xy 96.529543 -251.937894)
			(xy 96.499978 -251.977238) (xy 96.464485 -252.01133) (xy 96.423982 -252.039286) (xy 96.37952 -252.060384)
			(xy 96.332249 -252.074076) (xy 96.283394 -252.080008) (xy 96.234219 -252.078027) (xy 96.186 -252.068183)
			(xy 96.139984 -252.050731) (xy 96.097363 -252.026124) (xy 96.059242 -251.994999) (xy 96.026607 -251.958162)
			(xy 96.000304 -251.916566) (xy 95.981013 -251.87129) (xy 95.969236 -251.823506) (xy 95.965276 -251.774452)
			(xy 95.636334 -251.774452) (xy 95.635839 -251.799059) (xy 95.627944 -251.847636) (xy 95.61236 -251.894317)
			(xy 95.589489 -251.937894) (xy 95.559924 -251.977238) (xy 95.524431 -252.01133) (xy 95.483928 -252.039286)
			(xy 95.439466 -252.060384) (xy 95.392195 -252.074076) (xy 95.34334 -252.080008) (xy 95.294165 -252.078027)
			(xy 95.245946 -252.068183) (xy 95.19993 -252.050731) (xy 95.157309 -252.026124) (xy 95.119188 -251.994999)
			(xy 95.086553 -251.958162) (xy 95.06025 -251.916566) (xy 95.040959 -251.87129) (xy 95.029182 -251.823506)
			(xy 95.025222 -251.774452) (xy 94.706694 -251.774452) (xy 94.706182 -251.799898) (xy 94.698018 -251.850132)
			(xy 94.681902 -251.898406) (xy 94.658251 -251.943469) (xy 94.627678 -251.984155) (xy 94.590974 -252.01941)
			(xy 94.54909 -252.04832) (xy 94.503111 -252.070137) (xy 94.454227 -252.084297) (xy 94.403706 -252.090431)
			(xy 94.352854 -252.088382) (xy 94.30299 -252.078202) (xy 94.255404 -252.060155) (xy 94.21133 -252.034709)
			(xy 94.171908 -252.002522) (xy 94.13816 -251.964428) (xy 94.110959 -251.921414) (xy 94.091011 -251.874594)
			(xy 94.078832 -251.82518) (xy 94.074737 -251.774452) (xy 93.756226 -251.774452) (xy 93.755731 -251.799059)
			(xy 93.747836 -251.847636) (xy 93.732252 -251.894317) (xy 93.709381 -251.937894) (xy 93.679816 -251.977238)
			(xy 93.644323 -252.01133) (xy 93.60382 -252.039286) (xy 93.559358 -252.060384) (xy 93.512087 -252.074076)
			(xy 93.463232 -252.080008) (xy 93.414057 -252.078027) (xy 93.365838 -252.068183) (xy 93.319822 -252.050731)
			(xy 93.277201 -252.026124) (xy 93.23908 -251.994999) (xy 93.206445 -251.958162) (xy 93.180142 -251.916566)
			(xy 93.160851 -251.87129) (xy 93.149074 -251.823506) (xy 93.145114 -251.774452) (xy 92.816426 -251.774452)
			(xy 92.815931 -251.799059) (xy 92.808036 -251.847636) (xy 92.792452 -251.894317) (xy 92.769581 -251.937894)
			(xy 92.740016 -251.977238) (xy 92.704523 -252.01133) (xy 92.66402 -252.039286) (xy 92.619558 -252.060384)
			(xy 92.572287 -252.074076) (xy 92.523432 -252.080008) (xy 92.474257 -252.078027) (xy 92.426038 -252.068183)
			(xy 92.380022 -252.050731) (xy 92.337401 -252.026124) (xy 92.29928 -251.994999) (xy 92.266645 -251.958162)
			(xy 92.240342 -251.916566) (xy 92.221051 -251.87129) (xy 92.209274 -251.823506) (xy 92.205314 -251.774452)
			(xy 91.876372 -251.774452) (xy 91.875877 -251.799059) (xy 91.867982 -251.847636) (xy 91.852398 -251.894317)
			(xy 91.829527 -251.937894) (xy 91.799962 -251.977238) (xy 91.764469 -252.01133) (xy 91.723966 -252.039286)
			(xy 91.679504 -252.060384) (xy 91.632233 -252.074076) (xy 91.583378 -252.080008) (xy 91.534203 -252.078027)
			(xy 91.485984 -252.068183) (xy 91.439968 -252.050731) (xy 91.397347 -252.026124) (xy 91.359226 -251.994999)
			(xy 91.326591 -251.958162) (xy 91.300288 -251.916566) (xy 91.280997 -251.87129) (xy 91.26922 -251.823506)
			(xy 91.26526 -251.774452) (xy 90.946732 -251.774452) (xy 90.94622 -251.799898) (xy 90.938056 -251.850132)
			(xy 90.92194 -251.898406) (xy 90.898289 -251.943469) (xy 90.867716 -251.984155) (xy 90.831012 -252.01941)
			(xy 90.789128 -252.04832) (xy 90.743149 -252.070137) (xy 90.694265 -252.084297) (xy 90.643744 -252.090431)
			(xy 90.592892 -252.088382) (xy 90.543028 -252.078202) (xy 90.495442 -252.060155) (xy 90.451368 -252.034709)
			(xy 90.411946 -252.002522) (xy 90.378198 -251.964428) (xy 90.350997 -251.921414) (xy 90.331049 -251.874594)
			(xy 90.31887 -251.82518) (xy 90.314775 -251.774452) (xy 89.996264 -251.774452) (xy 89.995769 -251.799059)
			(xy 89.987874 -251.847636) (xy 89.97229 -251.894317) (xy 89.949419 -251.937894) (xy 89.919854 -251.977238)
			(xy 89.884361 -252.01133) (xy 89.843858 -252.039286) (xy 89.799396 -252.060384) (xy 89.752125 -252.074076)
			(xy 89.70327 -252.080008) (xy 89.654095 -252.078027) (xy 89.605876 -252.068183) (xy 89.55986 -252.050731)
			(xy 89.517239 -252.026124) (xy 89.479118 -251.994999) (xy 89.446483 -251.958162) (xy 89.42018 -251.916566)
			(xy 89.400889 -251.87129) (xy 89.389112 -251.823506) (xy 89.385152 -251.774452) (xy 89.056464 -251.774452)
			(xy 89.055969 -251.799059) (xy 89.048074 -251.847636) (xy 89.03249 -251.894317) (xy 89.009619 -251.937894)
			(xy 88.980054 -251.977238) (xy 88.944561 -252.01133) (xy 88.904058 -252.039286) (xy 88.859596 -252.060384)
			(xy 88.812325 -252.074076) (xy 88.76347 -252.080008) (xy 88.714295 -252.078027) (xy 88.666076 -252.068183)
			(xy 88.62006 -252.050731) (xy 88.577439 -252.026124) (xy 88.539318 -251.994999) (xy 88.506683 -251.958162)
			(xy 88.48038 -251.916566) (xy 88.461089 -251.87129) (xy 88.449312 -251.823506) (xy 88.445352 -251.774452)
			(xy 88.11641 -251.774452) (xy 88.115915 -251.799059) (xy 88.10802 -251.847636) (xy 88.092436 -251.894317)
			(xy 88.069565 -251.937894) (xy 88.04 -251.977238) (xy 88.004507 -252.01133) (xy 87.964004 -252.039286)
			(xy 87.919542 -252.060384) (xy 87.872271 -252.074076) (xy 87.823416 -252.080008) (xy 87.774241 -252.078027)
			(xy 87.726022 -252.068183) (xy 87.680006 -252.050731) (xy 87.637385 -252.026124) (xy 87.599264 -251.994999)
			(xy 87.566629 -251.958162) (xy 87.540326 -251.916566) (xy 87.521035 -251.87129) (xy 87.509258 -251.823506)
			(xy 87.505298 -251.774452) (xy 87.300054 -251.774452) (xy 87.300054 -251.913898) (xy 87.299514 -251.923734)
			(xy 87.291926 -251.941893) (xy 87.285322 -251.949204) (xy 87.053166 -252.18136) (xy 87.045924 -252.188064)
			(xy 87.02772 -252.195643) (xy 87.01786 -252.196092) (xy 86.820248 -252.196092) (xy 86.810409 -252.196624)
			(xy 86.792242 -252.204206) (xy 86.784942 -252.210824) (xy 86.707726 -252.28804) (xy 86.701013 -252.295278)
			(xy 86.693423 -252.313483) (xy 86.692994 -252.323346) (xy 86.692994 -252.494796) (xy 86.695026 -252.501654)
			(xy 86.700193 -252.521195) (xy 86.705928 -252.561205) (xy 86.706456 -252.58141) (xy 86.706456 -252.583188)
			(xy 86.706456 -252.584458) (xy 87.035144 -252.584458) (xy 87.039104 -252.535404) (xy 87.050881 -252.48762)
			(xy 87.070172 -252.442344) (xy 87.096475 -252.400748) (xy 87.12911 -252.363911) (xy 87.167231 -252.332786)
			(xy 87.209852 -252.308179) (xy 87.255868 -252.290727) (xy 87.304087 -252.280883) (xy 87.353262 -252.278902)
			(xy 87.402117 -252.284834) (xy 87.449388 -252.298526) (xy 87.49385 -252.319624) (xy 87.534353 -252.34758)
			(xy 87.569846 -252.381672) (xy 87.599411 -252.421016) (xy 87.622282 -252.464593) (xy 87.637866 -252.511274)
			(xy 87.645761 -252.559851) (xy 87.646256 -252.584458) (xy 87.975198 -252.584458) (xy 87.979158 -252.535404)
			(xy 87.990935 -252.48762) (xy 88.010226 -252.442344) (xy 88.036529 -252.400748) (xy 88.069164 -252.363911)
			(xy 88.107285 -252.332786) (xy 88.149906 -252.308179) (xy 88.195922 -252.290727) (xy 88.244141 -252.280883)
			(xy 88.293316 -252.278902) (xy 88.342171 -252.284834) (xy 88.389442 -252.298526) (xy 88.433904 -252.319624)
			(xy 88.474407 -252.34758) (xy 88.5099 -252.381672) (xy 88.539465 -252.421016) (xy 88.562336 -252.464593)
			(xy 88.57792 -252.511274) (xy 88.585815 -252.559851) (xy 88.58631 -252.584458) (xy 88.915252 -252.584458)
			(xy 88.919212 -252.535404) (xy 88.930989 -252.48762) (xy 88.95028 -252.442344) (xy 88.976583 -252.400748)
			(xy 89.009218 -252.363911) (xy 89.047339 -252.332786) (xy 89.08996 -252.308179) (xy 89.135976 -252.290727)
			(xy 89.184195 -252.280883) (xy 89.23337 -252.278902) (xy 89.282225 -252.284834) (xy 89.329496 -252.298526)
			(xy 89.373958 -252.319624) (xy 89.414461 -252.34758) (xy 89.449954 -252.381672) (xy 89.479519 -252.421016)
			(xy 89.50239 -252.464593) (xy 89.517974 -252.511274) (xy 89.525869 -252.559851) (xy 89.526364 -252.584458)
			(xy 89.855306 -252.584458) (xy 89.859266 -252.535404) (xy 89.871043 -252.48762) (xy 89.890334 -252.442344)
			(xy 89.916637 -252.400748) (xy 89.949272 -252.363911) (xy 89.987393 -252.332786) (xy 90.030014 -252.308179)
			(xy 90.07603 -252.290727) (xy 90.124249 -252.280883) (xy 90.173424 -252.278902) (xy 90.222279 -252.284834)
			(xy 90.26955 -252.298526) (xy 90.314012 -252.319624) (xy 90.354515 -252.34758) (xy 90.390008 -252.381672)
			(xy 90.419573 -252.421016) (xy 90.442444 -252.464593) (xy 90.458028 -252.511274) (xy 90.465923 -252.559851)
			(xy 90.466418 -252.584458) (xy 90.784675 -252.584458) (xy 90.78877 -252.53373) (xy 90.800949 -252.484316)
			(xy 90.820897 -252.437496) (xy 90.848098 -252.394482) (xy 90.881846 -252.356388) (xy 90.921268 -252.324201)
			(xy 90.965342 -252.298755) (xy 91.012928 -252.280708) (xy 91.062792 -252.270528) (xy 91.113644 -252.268479)
			(xy 91.164165 -252.274613) (xy 91.213049 -252.288773) (xy 91.259028 -252.31059) (xy 91.300912 -252.3395)
			(xy 91.337616 -252.374755) (xy 91.368189 -252.415441) (xy 91.39184 -252.460504) (xy 91.407956 -252.508778)
			(xy 91.41612 -252.559012) (xy 91.416632 -252.584458) (xy 91.724729 -252.584458) (xy 91.728824 -252.53373)
			(xy 91.741003 -252.484316) (xy 91.760951 -252.437496) (xy 91.788152 -252.394482) (xy 91.8219 -252.356388)
			(xy 91.861322 -252.324201) (xy 91.905396 -252.298755) (xy 91.952982 -252.280708) (xy 92.002846 -252.270528)
			(xy 92.053698 -252.268479) (xy 92.104219 -252.274613) (xy 92.153103 -252.288773) (xy 92.199082 -252.31059)
			(xy 92.240966 -252.3395) (xy 92.27767 -252.374755) (xy 92.308243 -252.415441) (xy 92.331894 -252.460504)
			(xy 92.34801 -252.508778) (xy 92.356174 -252.559012) (xy 92.356686 -252.584458) (xy 92.675214 -252.584458)
			(xy 92.679174 -252.535404) (xy 92.690951 -252.48762) (xy 92.710242 -252.442344) (xy 92.736545 -252.400748)
			(xy 92.76918 -252.363911) (xy 92.807301 -252.332786) (xy 92.849922 -252.308179) (xy 92.895938 -252.290727)
			(xy 92.944157 -252.280883) (xy 92.993332 -252.278902) (xy 93.042187 -252.284834) (xy 93.089458 -252.298526)
			(xy 93.13392 -252.319624) (xy 93.174423 -252.34758) (xy 93.209916 -252.381672) (xy 93.239481 -252.421016)
			(xy 93.262352 -252.464593) (xy 93.277936 -252.511274) (xy 93.285831 -252.559851) (xy 93.286326 -252.584458)
			(xy 93.604837 -252.584458) (xy 93.608932 -252.53373) (xy 93.621111 -252.484316) (xy 93.641059 -252.437496)
			(xy 93.66826 -252.394482) (xy 93.702008 -252.356388) (xy 93.74143 -252.324201) (xy 93.785504 -252.298755)
			(xy 93.83309 -252.280708) (xy 93.882954 -252.270528) (xy 93.933806 -252.268479) (xy 93.984327 -252.274613)
			(xy 94.033211 -252.288773) (xy 94.07919 -252.31059) (xy 94.121074 -252.3395) (xy 94.157778 -252.374755)
			(xy 94.188351 -252.415441) (xy 94.212002 -252.460504) (xy 94.228118 -252.508778) (xy 94.236282 -252.559012)
			(xy 94.236794 -252.584458) (xy 94.555322 -252.584458) (xy 94.559282 -252.535404) (xy 94.571059 -252.48762)
			(xy 94.59035 -252.442344) (xy 94.616653 -252.400748) (xy 94.649288 -252.363911) (xy 94.687409 -252.332786)
			(xy 94.73003 -252.308179) (xy 94.776046 -252.290727) (xy 94.824265 -252.280883) (xy 94.87344 -252.278902)
			(xy 94.922295 -252.284834) (xy 94.969566 -252.298526) (xy 95.014028 -252.319624) (xy 95.054531 -252.34758)
			(xy 95.090024 -252.381672) (xy 95.119589 -252.421016) (xy 95.14246 -252.464593) (xy 95.158044 -252.511274)
			(xy 95.165939 -252.559851) (xy 95.166434 -252.584458) (xy 95.484691 -252.584458) (xy 95.488786 -252.53373)
			(xy 95.500965 -252.484316) (xy 95.520913 -252.437496) (xy 95.548114 -252.394482) (xy 95.581862 -252.356388)
			(xy 95.621284 -252.324201) (xy 95.665358 -252.298755) (xy 95.712944 -252.280708) (xy 95.762808 -252.270528)
			(xy 95.81366 -252.268479) (xy 95.864181 -252.274613) (xy 95.913065 -252.288773) (xy 95.959044 -252.31059)
			(xy 96.000928 -252.3395) (xy 96.037632 -252.374755) (xy 96.068205 -252.415441) (xy 96.091856 -252.460504)
			(xy 96.107972 -252.508778) (xy 96.116136 -252.559012) (xy 96.116648 -252.584458) (xy 97.37523 -252.584458)
			(xy 97.37919 -252.535404) (xy 97.390967 -252.48762) (xy 97.410258 -252.442344) (xy 97.436561 -252.400748)
			(xy 97.469196 -252.363911) (xy 97.507317 -252.332786) (xy 97.549938 -252.308179) (xy 97.595954 -252.290727)
			(xy 97.644173 -252.280883) (xy 97.693348 -252.278902) (xy 97.742203 -252.284834) (xy 97.789474 -252.298526)
			(xy 97.833936 -252.319624) (xy 97.874439 -252.34758) (xy 97.909932 -252.381672) (xy 97.939497 -252.421016)
			(xy 97.962368 -252.464593) (xy 97.977952 -252.511274) (xy 97.985847 -252.559851) (xy 97.986342 -252.584458)
			(xy 99.255338 -252.584458) (xy 99.259298 -252.535404) (xy 99.271075 -252.48762) (xy 99.290366 -252.442344)
			(xy 99.316669 -252.400748) (xy 99.349304 -252.363911) (xy 99.387425 -252.332786) (xy 99.430046 -252.308179)
			(xy 99.476062 -252.290727) (xy 99.524281 -252.280883) (xy 99.573456 -252.278902) (xy 99.622311 -252.284834)
			(xy 99.669582 -252.298526) (xy 99.714044 -252.319624) (xy 99.754547 -252.34758) (xy 99.79004 -252.381672)
			(xy 99.819605 -252.421016) (xy 99.842476 -252.464593) (xy 99.85806 -252.511274) (xy 99.865955 -252.559851)
			(xy 99.86645 -252.584458) (xy 101.135192 -252.584458) (xy 101.139152 -252.535404) (xy 101.150929 -252.48762)
			(xy 101.17022 -252.442344) (xy 101.196523 -252.400748) (xy 101.229158 -252.363911) (xy 101.267279 -252.332786)
			(xy 101.3099 -252.308179) (xy 101.355916 -252.290727) (xy 101.404135 -252.280883) (xy 101.45331 -252.278902)
			(xy 101.502165 -252.284834) (xy 101.549436 -252.298526) (xy 101.593898 -252.319624) (xy 101.634401 -252.34758)
			(xy 101.669894 -252.381672) (xy 101.699459 -252.421016) (xy 101.72233 -252.464593) (xy 101.737914 -252.511274)
			(xy 101.745809 -252.559851) (xy 101.746304 -252.584458) (xy 101.745809 -252.609065) (xy 101.737914 -252.657642)
			(xy 101.72233 -252.704323) (xy 101.699459 -252.7479) (xy 101.669894 -252.787244) (xy 101.634401 -252.821336)
			(xy 101.593898 -252.849292) (xy 101.549436 -252.87039) (xy 101.502165 -252.884082) (xy 101.45331 -252.890014)
			(xy 101.404135 -252.888033) (xy 101.355916 -252.878189) (xy 101.3099 -252.860737) (xy 101.267279 -252.83613)
			(xy 101.229158 -252.805005) (xy 101.196523 -252.768168) (xy 101.17022 -252.726572) (xy 101.150929 -252.681296)
			(xy 101.139152 -252.633512) (xy 101.135192 -252.584458) (xy 99.86645 -252.584458) (xy 99.865955 -252.609065)
			(xy 99.85806 -252.657642) (xy 99.842476 -252.704323) (xy 99.819605 -252.7479) (xy 99.79004 -252.787244)
			(xy 99.754547 -252.821336) (xy 99.714044 -252.849292) (xy 99.669582 -252.87039) (xy 99.622311 -252.884082)
			(xy 99.573456 -252.890014) (xy 99.524281 -252.888033) (xy 99.476062 -252.878189) (xy 99.430046 -252.860737)
			(xy 99.387425 -252.83613) (xy 99.349304 -252.805005) (xy 99.316669 -252.768168) (xy 99.290366 -252.726572)
			(xy 99.271075 -252.681296) (xy 99.259298 -252.633512) (xy 99.255338 -252.584458) (xy 97.986342 -252.584458)
			(xy 97.985847 -252.609065) (xy 97.977952 -252.657642) (xy 97.962368 -252.704323) (xy 97.939497 -252.7479)
			(xy 97.909932 -252.787244) (xy 97.874439 -252.821336) (xy 97.833936 -252.849292) (xy 97.789474 -252.87039)
			(xy 97.742203 -252.884082) (xy 97.693348 -252.890014) (xy 97.644173 -252.888033) (xy 97.595954 -252.878189)
			(xy 97.549938 -252.860737) (xy 97.507317 -252.83613) (xy 97.469196 -252.805005) (xy 97.436561 -252.768168)
			(xy 97.410258 -252.726572) (xy 97.390967 -252.681296) (xy 97.37919 -252.633512) (xy 97.37523 -252.584458)
			(xy 96.116648 -252.584458) (xy 96.116136 -252.609904) (xy 96.107972 -252.660138) (xy 96.091856 -252.708412)
			(xy 96.068205 -252.753475) (xy 96.037632 -252.794161) (xy 96.000928 -252.829416) (xy 95.959044 -252.858326)
			(xy 95.913065 -252.880143) (xy 95.864181 -252.894303) (xy 95.81366 -252.900437) (xy 95.762808 -252.898388)
			(xy 95.712944 -252.888208) (xy 95.665358 -252.870161) (xy 95.621284 -252.844715) (xy 95.581862 -252.812528)
			(xy 95.548114 -252.774434) (xy 95.520913 -252.73142) (xy 95.500965 -252.6846) (xy 95.488786 -252.635186)
			(xy 95.484691 -252.584458) (xy 95.166434 -252.584458) (xy 95.165939 -252.609065) (xy 95.158044 -252.657642)
			(xy 95.14246 -252.704323) (xy 95.119589 -252.7479) (xy 95.090024 -252.787244) (xy 95.054531 -252.821336)
			(xy 95.014028 -252.849292) (xy 94.969566 -252.87039) (xy 94.922295 -252.884082) (xy 94.87344 -252.890014)
			(xy 94.824265 -252.888033) (xy 94.776046 -252.878189) (xy 94.73003 -252.860737) (xy 94.687409 -252.83613)
			(xy 94.649288 -252.805005) (xy 94.616653 -252.768168) (xy 94.59035 -252.726572) (xy 94.571059 -252.681296)
			(xy 94.559282 -252.633512) (xy 94.555322 -252.584458) (xy 94.236794 -252.584458) (xy 94.236282 -252.609904)
			(xy 94.228118 -252.660138) (xy 94.212002 -252.708412) (xy 94.188351 -252.753475) (xy 94.157778 -252.794161)
			(xy 94.121074 -252.829416) (xy 94.07919 -252.858326) (xy 94.033211 -252.880143) (xy 93.984327 -252.894303)
			(xy 93.933806 -252.900437) (xy 93.882954 -252.898388) (xy 93.83309 -252.888208) (xy 93.785504 -252.870161)
			(xy 93.74143 -252.844715) (xy 93.702008 -252.812528) (xy 93.66826 -252.774434) (xy 93.641059 -252.73142)
			(xy 93.621111 -252.6846) (xy 93.608932 -252.635186) (xy 93.604837 -252.584458) (xy 93.286326 -252.584458)
			(xy 93.285831 -252.609065) (xy 93.277936 -252.657642) (xy 93.262352 -252.704323) (xy 93.239481 -252.7479)
			(xy 93.209916 -252.787244) (xy 93.174423 -252.821336) (xy 93.13392 -252.849292) (xy 93.089458 -252.87039)
			(xy 93.042187 -252.884082) (xy 92.993332 -252.890014) (xy 92.944157 -252.888033) (xy 92.895938 -252.878189)
			(xy 92.849922 -252.860737) (xy 92.807301 -252.83613) (xy 92.76918 -252.805005) (xy 92.736545 -252.768168)
			(xy 92.710242 -252.726572) (xy 92.690951 -252.681296) (xy 92.679174 -252.633512) (xy 92.675214 -252.584458)
			(xy 92.356686 -252.584458) (xy 92.356174 -252.609904) (xy 92.34801 -252.660138) (xy 92.331894 -252.708412)
			(xy 92.308243 -252.753475) (xy 92.27767 -252.794161) (xy 92.240966 -252.829416) (xy 92.199082 -252.858326)
			(xy 92.153103 -252.880143) (xy 92.104219 -252.894303) (xy 92.053698 -252.900437) (xy 92.002846 -252.898388)
			(xy 91.952982 -252.888208) (xy 91.905396 -252.870161) (xy 91.861322 -252.844715) (xy 91.8219 -252.812528)
			(xy 91.788152 -252.774434) (xy 91.760951 -252.73142) (xy 91.741003 -252.6846) (xy 91.728824 -252.635186)
			(xy 91.724729 -252.584458) (xy 91.416632 -252.584458) (xy 91.41612 -252.609904) (xy 91.407956 -252.660138)
			(xy 91.39184 -252.708412) (xy 91.368189 -252.753475) (xy 91.337616 -252.794161) (xy 91.300912 -252.829416)
			(xy 91.259028 -252.858326) (xy 91.213049 -252.880143) (xy 91.164165 -252.894303) (xy 91.113644 -252.900437)
			(xy 91.062792 -252.898388) (xy 91.012928 -252.888208) (xy 90.965342 -252.870161) (xy 90.921268 -252.844715)
			(xy 90.881846 -252.812528) (xy 90.848098 -252.774434) (xy 90.820897 -252.73142) (xy 90.800949 -252.6846)
			(xy 90.78877 -252.635186) (xy 90.784675 -252.584458) (xy 90.466418 -252.584458) (xy 90.465923 -252.609065)
			(xy 90.458028 -252.657642) (xy 90.442444 -252.704323) (xy 90.419573 -252.7479) (xy 90.390008 -252.787244)
			(xy 90.354515 -252.821336) (xy 90.314012 -252.849292) (xy 90.26955 -252.87039) (xy 90.222279 -252.884082)
			(xy 90.173424 -252.890014) (xy 90.124249 -252.888033) (xy 90.07603 -252.878189) (xy 90.030014 -252.860737)
			(xy 89.987393 -252.83613) (xy 89.949272 -252.805005) (xy 89.916637 -252.768168) (xy 89.890334 -252.726572)
			(xy 89.871043 -252.681296) (xy 89.859266 -252.633512) (xy 89.855306 -252.584458) (xy 89.526364 -252.584458)
			(xy 89.525869 -252.609065) (xy 89.517974 -252.657642) (xy 89.50239 -252.704323) (xy 89.479519 -252.7479)
			(xy 89.449954 -252.787244) (xy 89.414461 -252.821336) (xy 89.373958 -252.849292) (xy 89.329496 -252.87039)
			(xy 89.282225 -252.884082) (xy 89.23337 -252.890014) (xy 89.184195 -252.888033) (xy 89.135976 -252.878189)
			(xy 89.08996 -252.860737) (xy 89.047339 -252.83613) (xy 89.009218 -252.805005) (xy 88.976583 -252.768168)
			(xy 88.95028 -252.726572) (xy 88.930989 -252.681296) (xy 88.919212 -252.633512) (xy 88.915252 -252.584458)
			(xy 88.58631 -252.584458) (xy 88.585815 -252.609065) (xy 88.57792 -252.657642) (xy 88.562336 -252.704323)
			(xy 88.539465 -252.7479) (xy 88.5099 -252.787244) (xy 88.474407 -252.821336) (xy 88.433904 -252.849292)
			(xy 88.389442 -252.87039) (xy 88.342171 -252.884082) (xy 88.293316 -252.890014) (xy 88.244141 -252.888033)
			(xy 88.195922 -252.878189) (xy 88.149906 -252.860737) (xy 88.107285 -252.83613) (xy 88.069164 -252.805005)
			(xy 88.036529 -252.768168) (xy 88.010226 -252.726572) (xy 87.990935 -252.681296) (xy 87.979158 -252.633512)
			(xy 87.975198 -252.584458) (xy 87.646256 -252.584458) (xy 87.645761 -252.609065) (xy 87.637866 -252.657642)
			(xy 87.622282 -252.704323) (xy 87.599411 -252.7479) (xy 87.569846 -252.787244) (xy 87.534353 -252.821336)
			(xy 87.49385 -252.849292) (xy 87.449388 -252.87039) (xy 87.402117 -252.884082) (xy 87.353262 -252.890014)
			(xy 87.304087 -252.888033) (xy 87.255868 -252.878189) (xy 87.209852 -252.860737) (xy 87.167231 -252.83613)
			(xy 87.12911 -252.805005) (xy 87.096475 -252.768168) (xy 87.070172 -252.726572) (xy 87.050881 -252.681296)
			(xy 87.039104 -252.633512) (xy 87.035144 -252.584458) (xy 86.706456 -252.584458) (xy 86.706106 -252.60543)
			(xy 86.700365 -252.646978) (xy 86.695026 -252.667262) (xy 86.692994 -252.674374) (xy 86.692994 -252.91923)
			(xy 86.693456 -252.929106) (xy 86.700902 -252.947402) (xy 86.707472 -252.95479) (xy 86.707726 -252.955044)
			(xy 86.777068 -253.024386) (xy 86.777576 -253.024894) (xy 86.78496 -253.031468) (xy 86.803259 -253.038904)
			(xy 86.813136 -253.039372) (xy 86.94166 -253.039372) (xy 86.951499 -253.039905) (xy 86.969665 -253.047487)
			(xy 86.976966 -253.054104) (xy 87.158322 -253.23546) (xy 87.165042 -253.242696) (xy 87.172654 -253.2609)
			(xy 87.173054 -253.270766) (xy 87.173054 -253.349506) (xy 87.173562 -253.353062) (xy 87.174874 -253.363362)
			(xy 87.176273 -253.384081) (xy 87.176356 -253.394464) (xy 87.505298 -253.394464) (xy 87.509258 -253.34541)
			(xy 87.521035 -253.297626) (xy 87.540326 -253.25235) (xy 87.566629 -253.210754) (xy 87.599264 -253.173917)
			(xy 87.637385 -253.142792) (xy 87.680006 -253.118185) (xy 87.726022 -253.100733) (xy 87.774241 -253.090889)
			(xy 87.823416 -253.088908) (xy 87.872271 -253.09484) (xy 87.919542 -253.108532) (xy 87.964004 -253.12963)
			(xy 88.004507 -253.157586) (xy 88.04 -253.191678) (xy 88.069565 -253.231022) (xy 88.092436 -253.274599)
			(xy 88.10802 -253.32128) (xy 88.115915 -253.369857) (xy 88.11641 -253.394464) (xy 88.445352 -253.394464)
			(xy 88.449312 -253.34541) (xy 88.461089 -253.297626) (xy 88.48038 -253.25235) (xy 88.506683 -253.210754)
			(xy 88.539318 -253.173917) (xy 88.577439 -253.142792) (xy 88.62006 -253.118185) (xy 88.666076 -253.100733)
			(xy 88.714295 -253.090889) (xy 88.76347 -253.088908) (xy 88.812325 -253.09484) (xy 88.859596 -253.108532)
			(xy 88.904058 -253.12963) (xy 88.944561 -253.157586) (xy 88.980054 -253.191678) (xy 89.009619 -253.231022)
			(xy 89.03249 -253.274599) (xy 89.048074 -253.32128) (xy 89.055969 -253.369857) (xy 89.056464 -253.394464)
			(xy 89.385152 -253.394464) (xy 89.389112 -253.34541) (xy 89.400889 -253.297626) (xy 89.42018 -253.25235)
			(xy 89.446483 -253.210754) (xy 89.479118 -253.173917) (xy 89.517239 -253.142792) (xy 89.55986 -253.118185)
			(xy 89.605876 -253.100733) (xy 89.654095 -253.090889) (xy 89.70327 -253.088908) (xy 89.752125 -253.09484)
			(xy 89.799396 -253.108532) (xy 89.843858 -253.12963) (xy 89.884361 -253.157586) (xy 89.919854 -253.191678)
			(xy 89.949419 -253.231022) (xy 89.97229 -253.274599) (xy 89.987874 -253.32128) (xy 89.995769 -253.369857)
			(xy 89.996264 -253.394464) (xy 90.314775 -253.394464) (xy 90.31887 -253.343736) (xy 90.331049 -253.294322)
			(xy 90.350997 -253.247502) (xy 90.378198 -253.204488) (xy 90.411946 -253.166394) (xy 90.451368 -253.134207)
			(xy 90.495442 -253.108761) (xy 90.543028 -253.090714) (xy 90.592892 -253.080534) (xy 90.643744 -253.078485)
			(xy 90.694265 -253.084619) (xy 90.743149 -253.098779) (xy 90.789128 -253.120596) (xy 90.831012 -253.149506)
			(xy 90.867716 -253.184761) (xy 90.898289 -253.225447) (xy 90.92194 -253.27051) (xy 90.938056 -253.318784)
			(xy 90.94622 -253.369018) (xy 90.946732 -253.394464) (xy 91.26526 -253.394464) (xy 91.26922 -253.34541)
			(xy 91.280997 -253.297626) (xy 91.300288 -253.25235) (xy 91.326591 -253.210754) (xy 91.359226 -253.173917)
			(xy 91.397347 -253.142792) (xy 91.439968 -253.118185) (xy 91.485984 -253.100733) (xy 91.534203 -253.090889)
			(xy 91.583378 -253.088908) (xy 91.632233 -253.09484) (xy 91.679504 -253.108532) (xy 91.723966 -253.12963)
			(xy 91.764469 -253.157586) (xy 91.799962 -253.191678) (xy 91.829527 -253.231022) (xy 91.852398 -253.274599)
			(xy 91.867982 -253.32128) (xy 91.875877 -253.369857) (xy 91.876372 -253.394464) (xy 92.194883 -253.394464)
			(xy 92.198978 -253.343736) (xy 92.211157 -253.294322) (xy 92.231105 -253.247502) (xy 92.258306 -253.204488)
			(xy 92.292054 -253.166394) (xy 92.331476 -253.134207) (xy 92.37555 -253.108761) (xy 92.423136 -253.090714)
			(xy 92.473 -253.080534) (xy 92.523852 -253.078485) (xy 92.574373 -253.084619) (xy 92.623257 -253.098779)
			(xy 92.669236 -253.120596) (xy 92.71112 -253.149506) (xy 92.747824 -253.184761) (xy 92.778397 -253.225447)
			(xy 92.802048 -253.27051) (xy 92.818164 -253.318784) (xy 92.826328 -253.369018) (xy 92.82684 -253.394464)
			(xy 93.145114 -253.394464) (xy 93.149074 -253.34541) (xy 93.160851 -253.297626) (xy 93.180142 -253.25235)
			(xy 93.206445 -253.210754) (xy 93.23908 -253.173917) (xy 93.277201 -253.142792) (xy 93.319822 -253.118185)
			(xy 93.365838 -253.100733) (xy 93.414057 -253.090889) (xy 93.463232 -253.088908) (xy 93.512087 -253.09484)
			(xy 93.559358 -253.108532) (xy 93.60382 -253.12963) (xy 93.644323 -253.157586) (xy 93.679816 -253.191678)
			(xy 93.709381 -253.231022) (xy 93.732252 -253.274599) (xy 93.747836 -253.32128) (xy 93.755731 -253.369857)
			(xy 93.756226 -253.394464) (xy 94.074737 -253.394464) (xy 94.078832 -253.343736) (xy 94.091011 -253.294322)
			(xy 94.110959 -253.247502) (xy 94.13816 -253.204488) (xy 94.171908 -253.166394) (xy 94.21133 -253.134207)
			(xy 94.255404 -253.108761) (xy 94.30299 -253.090714) (xy 94.352854 -253.080534) (xy 94.403706 -253.078485)
			(xy 94.454227 -253.084619) (xy 94.503111 -253.098779) (xy 94.54909 -253.120596) (xy 94.590974 -253.149506)
			(xy 94.627678 -253.184761) (xy 94.658251 -253.225447) (xy 94.681902 -253.27051) (xy 94.698018 -253.318784)
			(xy 94.706182 -253.369018) (xy 94.706694 -253.394464) (xy 95.014791 -253.394464) (xy 95.018886 -253.343736)
			(xy 95.031065 -253.294322) (xy 95.051013 -253.247502) (xy 95.078214 -253.204488) (xy 95.111962 -253.166394)
			(xy 95.151384 -253.134207) (xy 95.195458 -253.108761) (xy 95.243044 -253.090714) (xy 95.292908 -253.080534)
			(xy 95.34376 -253.078485) (xy 95.394281 -253.084619) (xy 95.443165 -253.098779) (xy 95.489144 -253.120596)
			(xy 95.531028 -253.149506) (xy 95.567732 -253.184761) (xy 95.598305 -253.225447) (xy 95.621956 -253.27051)
			(xy 95.638072 -253.318784) (xy 95.646236 -253.369018) (xy 95.646748 -253.394464) (xy 95.965276 -253.394464)
			(xy 95.969236 -253.34541) (xy 95.981013 -253.297626) (xy 96.000304 -253.25235) (xy 96.026607 -253.210754)
			(xy 96.059242 -253.173917) (xy 96.097363 -253.142792) (xy 96.139984 -253.118185) (xy 96.186 -253.100733)
			(xy 96.234219 -253.090889) (xy 96.283394 -253.088908) (xy 96.332249 -253.09484) (xy 96.37952 -253.108532)
			(xy 96.423982 -253.12963) (xy 96.464485 -253.157586) (xy 96.499978 -253.191678) (xy 96.529543 -253.231022)
			(xy 96.552414 -253.274599) (xy 96.567998 -253.32128) (xy 96.575893 -253.369857) (xy 96.576388 -253.394464)
			(xy 97.84513 -253.394464) (xy 97.84909 -253.34541) (xy 97.860867 -253.297626) (xy 97.880158 -253.25235)
			(xy 97.906461 -253.210754) (xy 97.939096 -253.173917) (xy 97.977217 -253.142792) (xy 98.019838 -253.118185)
			(xy 98.065854 -253.100733) (xy 98.114073 -253.090889) (xy 98.163248 -253.088908) (xy 98.212103 -253.09484)
			(xy 98.259374 -253.108532) (xy 98.303836 -253.12963) (xy 98.344339 -253.157586) (xy 98.379832 -253.191678)
			(xy 98.409397 -253.231022) (xy 98.432268 -253.274599) (xy 98.447852 -253.32128) (xy 98.455747 -253.369857)
			(xy 98.456242 -253.394464) (xy 99.725238 -253.394464) (xy 99.729198 -253.34541) (xy 99.740975 -253.297626)
			(xy 99.760266 -253.25235) (xy 99.786569 -253.210754) (xy 99.819204 -253.173917) (xy 99.857325 -253.142792)
			(xy 99.899946 -253.118185) (xy 99.945962 -253.100733) (xy 99.994181 -253.090889) (xy 100.043356 -253.088908)
			(xy 100.092211 -253.09484) (xy 100.139482 -253.108532) (xy 100.183944 -253.12963) (xy 100.224447 -253.157586)
			(xy 100.25994 -253.191678) (xy 100.289505 -253.231022) (xy 100.312376 -253.274599) (xy 100.32796 -253.32128)
			(xy 100.335855 -253.369857) (xy 100.33635 -253.394464) (xy 100.665292 -253.394464) (xy 100.669252 -253.34541)
			(xy 100.681029 -253.297626) (xy 100.70032 -253.25235) (xy 100.726623 -253.210754) (xy 100.759258 -253.173917)
			(xy 100.797379 -253.142792) (xy 100.84 -253.118185) (xy 100.886016 -253.100733) (xy 100.934235 -253.090889)
			(xy 100.98341 -253.088908) (xy 101.032265 -253.09484) (xy 101.079536 -253.108532) (xy 101.123998 -253.12963)
			(xy 101.164501 -253.157586) (xy 101.199994 -253.191678) (xy 101.229559 -253.231022) (xy 101.25243 -253.274599)
			(xy 101.268014 -253.32128) (xy 101.275909 -253.369857) (xy 101.276404 -253.394464) (xy 101.605346 -253.394464)
			(xy 101.609306 -253.34541) (xy 101.621083 -253.297626) (xy 101.640374 -253.25235) (xy 101.666677 -253.210754)
			(xy 101.699312 -253.173917) (xy 101.737433 -253.142792) (xy 101.780054 -253.118185) (xy 101.82607 -253.100733)
			(xy 101.874289 -253.090889) (xy 101.923464 -253.088908) (xy 101.972319 -253.09484) (xy 102.01959 -253.108532)
			(xy 102.064052 -253.12963) (xy 102.104555 -253.157586) (xy 102.140048 -253.191678) (xy 102.169613 -253.231022)
			(xy 102.192484 -253.274599) (xy 102.208068 -253.32128) (xy 102.215963 -253.369857) (xy 102.216458 -253.394464)
			(xy 102.215963 -253.419071) (xy 102.208068 -253.467648) (xy 102.192484 -253.514329) (xy 102.169613 -253.557906)
			(xy 102.140048 -253.59725) (xy 102.104555 -253.631342) (xy 102.064052 -253.659298) (xy 102.01959 -253.680396)
			(xy 101.972319 -253.694088) (xy 101.923464 -253.70002) (xy 101.874289 -253.698039) (xy 101.82607 -253.688195)
			(xy 101.780054 -253.670743) (xy 101.737433 -253.646136) (xy 101.699312 -253.615011) (xy 101.666677 -253.578174)
			(xy 101.640374 -253.536578) (xy 101.621083 -253.491302) (xy 101.609306 -253.443518) (xy 101.605346 -253.394464)
			(xy 101.276404 -253.394464) (xy 101.275909 -253.419071) (xy 101.268014 -253.467648) (xy 101.25243 -253.514329)
			(xy 101.229559 -253.557906) (xy 101.199994 -253.59725) (xy 101.164501 -253.631342) (xy 101.123998 -253.659298)
			(xy 101.079536 -253.680396) (xy 101.032265 -253.694088) (xy 100.98341 -253.70002) (xy 100.934235 -253.698039)
			(xy 100.886016 -253.688195) (xy 100.84 -253.670743) (xy 100.797379 -253.646136) (xy 100.759258 -253.615011)
			(xy 100.726623 -253.578174) (xy 100.70032 -253.536578) (xy 100.681029 -253.491302) (xy 100.669252 -253.443518)
			(xy 100.665292 -253.394464) (xy 100.33635 -253.394464) (xy 100.335855 -253.419071) (xy 100.32796 -253.467648)
			(xy 100.312376 -253.514329) (xy 100.289505 -253.557906) (xy 100.25994 -253.59725) (xy 100.224447 -253.631342)
			(xy 100.183944 -253.659298) (xy 100.139482 -253.680396) (xy 100.092211 -253.694088) (xy 100.043356 -253.70002)
			(xy 99.994181 -253.698039) (xy 99.945962 -253.688195) (xy 99.899946 -253.670743) (xy 99.857325 -253.646136)
			(xy 99.819204 -253.615011) (xy 99.786569 -253.578174) (xy 99.760266 -253.536578) (xy 99.740975 -253.491302)
			(xy 99.729198 -253.443518) (xy 99.725238 -253.394464) (xy 98.456242 -253.394464) (xy 98.455747 -253.419071)
			(xy 98.447852 -253.467648) (xy 98.432268 -253.514329) (xy 98.409397 -253.557906) (xy 98.379832 -253.59725)
			(xy 98.344339 -253.631342) (xy 98.303836 -253.659298) (xy 98.259374 -253.680396) (xy 98.212103 -253.694088)
			(xy 98.163248 -253.70002) (xy 98.114073 -253.698039) (xy 98.065854 -253.688195) (xy 98.019838 -253.670743)
			(xy 97.977217 -253.646136) (xy 97.939096 -253.615011) (xy 97.906461 -253.578174) (xy 97.880158 -253.536578)
			(xy 97.860867 -253.491302) (xy 97.84909 -253.443518) (xy 97.84513 -253.394464) (xy 96.576388 -253.394464)
			(xy 96.575893 -253.419071) (xy 96.567998 -253.467648) (xy 96.552414 -253.514329) (xy 96.529543 -253.557906)
			(xy 96.499978 -253.59725) (xy 96.464485 -253.631342) (xy 96.423982 -253.659298) (xy 96.37952 -253.680396)
			(xy 96.332249 -253.694088) (xy 96.283394 -253.70002) (xy 96.234219 -253.698039) (xy 96.186 -253.688195)
			(xy 96.139984 -253.670743) (xy 96.097363 -253.646136) (xy 96.059242 -253.615011) (xy 96.026607 -253.578174)
			(xy 96.000304 -253.536578) (xy 95.981013 -253.491302) (xy 95.969236 -253.443518) (xy 95.965276 -253.394464)
			(xy 95.646748 -253.394464) (xy 95.646236 -253.41991) (xy 95.638072 -253.470144) (xy 95.621956 -253.518418)
			(xy 95.598305 -253.563481) (xy 95.567732 -253.604167) (xy 95.531028 -253.639422) (xy 95.489144 -253.668332)
			(xy 95.443165 -253.690149) (xy 95.394281 -253.704309) (xy 95.34376 -253.710443) (xy 95.292908 -253.708394)
			(xy 95.243044 -253.698214) (xy 95.195458 -253.680167) (xy 95.151384 -253.654721) (xy 95.111962 -253.622534)
			(xy 95.078214 -253.58444) (xy 95.051013 -253.541426) (xy 95.031065 -253.494606) (xy 95.018886 -253.445192)
			(xy 95.014791 -253.394464) (xy 94.706694 -253.394464) (xy 94.706182 -253.41991) (xy 94.698018 -253.470144)
			(xy 94.681902 -253.518418) (xy 94.658251 -253.563481) (xy 94.627678 -253.604167) (xy 94.590974 -253.639422)
			(xy 94.54909 -253.668332) (xy 94.503111 -253.690149) (xy 94.454227 -253.704309) (xy 94.403706 -253.710443)
			(xy 94.352854 -253.708394) (xy 94.30299 -253.698214) (xy 94.255404 -253.680167) (xy 94.21133 -253.654721)
			(xy 94.171908 -253.622534) (xy 94.13816 -253.58444) (xy 94.110959 -253.541426) (xy 94.091011 -253.494606)
			(xy 94.078832 -253.445192) (xy 94.074737 -253.394464) (xy 93.756226 -253.394464) (xy 93.755731 -253.419071)
			(xy 93.747836 -253.467648) (xy 93.732252 -253.514329) (xy 93.709381 -253.557906) (xy 93.679816 -253.59725)
			(xy 93.644323 -253.631342) (xy 93.60382 -253.659298) (xy 93.559358 -253.680396) (xy 93.512087 -253.694088)
			(xy 93.463232 -253.70002) (xy 93.414057 -253.698039) (xy 93.365838 -253.688195) (xy 93.319822 -253.670743)
			(xy 93.277201 -253.646136) (xy 93.23908 -253.615011) (xy 93.206445 -253.578174) (xy 93.180142 -253.536578)
			(xy 93.160851 -253.491302) (xy 93.149074 -253.443518) (xy 93.145114 -253.394464) (xy 92.82684 -253.394464)
			(xy 92.826328 -253.41991) (xy 92.818164 -253.470144) (xy 92.802048 -253.518418) (xy 92.778397 -253.563481)
			(xy 92.747824 -253.604167) (xy 92.71112 -253.639422) (xy 92.669236 -253.668332) (xy 92.623257 -253.690149)
			(xy 92.574373 -253.704309) (xy 92.523852 -253.710443) (xy 92.473 -253.708394) (xy 92.423136 -253.698214)
			(xy 92.37555 -253.680167) (xy 92.331476 -253.654721) (xy 92.292054 -253.622534) (xy 92.258306 -253.58444)
			(xy 92.231105 -253.541426) (xy 92.211157 -253.494606) (xy 92.198978 -253.445192) (xy 92.194883 -253.394464)
			(xy 91.876372 -253.394464) (xy 91.875877 -253.419071) (xy 91.867982 -253.467648) (xy 91.852398 -253.514329)
			(xy 91.829527 -253.557906) (xy 91.799962 -253.59725) (xy 91.764469 -253.631342) (xy 91.723966 -253.659298)
			(xy 91.679504 -253.680396) (xy 91.632233 -253.694088) (xy 91.583378 -253.70002) (xy 91.534203 -253.698039)
			(xy 91.485984 -253.688195) (xy 91.439968 -253.670743) (xy 91.397347 -253.646136) (xy 91.359226 -253.615011)
			(xy 91.326591 -253.578174) (xy 91.300288 -253.536578) (xy 91.280997 -253.491302) (xy 91.26922 -253.443518)
			(xy 91.26526 -253.394464) (xy 90.946732 -253.394464) (xy 90.94622 -253.41991) (xy 90.938056 -253.470144)
			(xy 90.92194 -253.518418) (xy 90.898289 -253.563481) (xy 90.867716 -253.604167) (xy 90.831012 -253.639422)
			(xy 90.789128 -253.668332) (xy 90.743149 -253.690149) (xy 90.694265 -253.704309) (xy 90.643744 -253.710443)
			(xy 90.592892 -253.708394) (xy 90.543028 -253.698214) (xy 90.495442 -253.680167) (xy 90.451368 -253.654721)
			(xy 90.411946 -253.622534) (xy 90.378198 -253.58444) (xy 90.350997 -253.541426) (xy 90.331049 -253.494606)
			(xy 90.31887 -253.445192) (xy 90.314775 -253.394464) (xy 89.996264 -253.394464) (xy 89.995769 -253.419071)
			(xy 89.987874 -253.467648) (xy 89.97229 -253.514329) (xy 89.949419 -253.557906) (xy 89.919854 -253.59725)
			(xy 89.884361 -253.631342) (xy 89.843858 -253.659298) (xy 89.799396 -253.680396) (xy 89.752125 -253.694088)
			(xy 89.70327 -253.70002) (xy 89.654095 -253.698039) (xy 89.605876 -253.688195) (xy 89.55986 -253.670743)
			(xy 89.517239 -253.646136) (xy 89.479118 -253.615011) (xy 89.446483 -253.578174) (xy 89.42018 -253.536578)
			(xy 89.400889 -253.491302) (xy 89.389112 -253.443518) (xy 89.385152 -253.394464) (xy 89.056464 -253.394464)
			(xy 89.055969 -253.419071) (xy 89.048074 -253.467648) (xy 89.03249 -253.514329) (xy 89.009619 -253.557906)
			(xy 88.980054 -253.59725) (xy 88.944561 -253.631342) (xy 88.904058 -253.659298) (xy 88.859596 -253.680396)
			(xy 88.812325 -253.694088) (xy 88.76347 -253.70002) (xy 88.714295 -253.698039) (xy 88.666076 -253.688195)
			(xy 88.62006 -253.670743) (xy 88.577439 -253.646136) (xy 88.539318 -253.615011) (xy 88.506683 -253.578174)
			(xy 88.48038 -253.536578) (xy 88.461089 -253.491302) (xy 88.449312 -253.443518) (xy 88.445352 -253.394464)
			(xy 88.11641 -253.394464) (xy 88.115915 -253.419071) (xy 88.10802 -253.467648) (xy 88.092436 -253.514329)
			(xy 88.069565 -253.557906) (xy 88.04 -253.59725) (xy 88.004507 -253.631342) (xy 87.964004 -253.659298)
			(xy 87.919542 -253.680396) (xy 87.872271 -253.694088) (xy 87.823416 -253.70002) (xy 87.774241 -253.698039)
			(xy 87.726022 -253.688195) (xy 87.680006 -253.670743) (xy 87.637385 -253.646136) (xy 87.599264 -253.615011)
			(xy 87.566629 -253.578174) (xy 87.540326 -253.536578) (xy 87.521035 -253.491302) (xy 87.509258 -253.443518)
			(xy 87.505298 -253.394464) (xy 87.176356 -253.394464) (xy 87.17628 -253.404847) (xy 87.174884 -253.425567)
			(xy 87.173562 -253.435866) (xy 87.173054 -253.439422) (xy 87.173054 -253.534418) (xy 87.172529 -253.544261)
			(xy 87.164961 -253.56244) (xy 87.158322 -253.569724) (xy 86.819486 -253.90856) (xy 86.812765 -253.915795)
			(xy 86.805152 -253.934) (xy 86.804754 -253.943866) (xy 86.804754 -254.20447) (xy 87.035144 -254.20447)
			(xy 87.039104 -254.155416) (xy 87.050881 -254.107632) (xy 87.070172 -254.062356) (xy 87.096475 -254.02076)
			(xy 87.12911 -253.983923) (xy 87.167231 -253.952798) (xy 87.209852 -253.928191) (xy 87.255868 -253.910739)
			(xy 87.304087 -253.900895) (xy 87.353262 -253.898914) (xy 87.402117 -253.904846) (xy 87.449388 -253.918538)
			(xy 87.49385 -253.939636) (xy 87.534353 -253.967592) (xy 87.569846 -254.001684) (xy 87.599411 -254.041028)
			(xy 87.622282 -254.084605) (xy 87.637866 -254.131286) (xy 87.645761 -254.179863) (xy 87.646256 -254.20447)
			(xy 87.975198 -254.20447) (xy 87.979158 -254.155416) (xy 87.990935 -254.107632) (xy 88.010226 -254.062356)
			(xy 88.036529 -254.02076) (xy 88.069164 -253.983923) (xy 88.107285 -253.952798) (xy 88.149906 -253.928191)
			(xy 88.195922 -253.910739) (xy 88.244141 -253.900895) (xy 88.293316 -253.898914) (xy 88.342171 -253.904846)
			(xy 88.389442 -253.918538) (xy 88.433904 -253.939636) (xy 88.474407 -253.967592) (xy 88.5099 -254.001684)
			(xy 88.539465 -254.041028) (xy 88.562336 -254.084605) (xy 88.57792 -254.131286) (xy 88.585815 -254.179863)
			(xy 88.58631 -254.20447) (xy 88.915252 -254.20447) (xy 88.919212 -254.155416) (xy 88.930989 -254.107632)
			(xy 88.95028 -254.062356) (xy 88.976583 -254.02076) (xy 89.009218 -253.983923) (xy 89.047339 -253.952798)
			(xy 89.08996 -253.928191) (xy 89.135976 -253.910739) (xy 89.184195 -253.900895) (xy 89.23337 -253.898914)
			(xy 89.282225 -253.904846) (xy 89.329496 -253.918538) (xy 89.373958 -253.939636) (xy 89.414461 -253.967592)
			(xy 89.449954 -254.001684) (xy 89.479519 -254.041028) (xy 89.50239 -254.084605) (xy 89.517974 -254.131286)
			(xy 89.525869 -254.179863) (xy 89.526364 -254.20447) (xy 89.855306 -254.20447) (xy 89.859266 -254.155416)
			(xy 89.871043 -254.107632) (xy 89.890334 -254.062356) (xy 89.916637 -254.02076) (xy 89.949272 -253.983923)
			(xy 89.987393 -253.952798) (xy 90.030014 -253.928191) (xy 90.07603 -253.910739) (xy 90.124249 -253.900895)
			(xy 90.173424 -253.898914) (xy 90.222279 -253.904846) (xy 90.26955 -253.918538) (xy 90.314012 -253.939636)
			(xy 90.354515 -253.967592) (xy 90.390008 -254.001684) (xy 90.419573 -254.041028) (xy 90.442444 -254.084605)
			(xy 90.458028 -254.131286) (xy 90.465923 -254.179863) (xy 90.466418 -254.20447) (xy 90.784675 -254.20447)
			(xy 90.78877 -254.153742) (xy 90.800949 -254.104328) (xy 90.820897 -254.057508) (xy 90.848098 -254.014494)
			(xy 90.881846 -253.9764) (xy 90.921268 -253.944213) (xy 90.965342 -253.918767) (xy 91.012928 -253.90072)
			(xy 91.062792 -253.89054) (xy 91.113644 -253.888491) (xy 91.164165 -253.894625) (xy 91.213049 -253.908785)
			(xy 91.259028 -253.930602) (xy 91.300912 -253.959512) (xy 91.337616 -253.994767) (xy 91.368189 -254.035453)
			(xy 91.39184 -254.080516) (xy 91.407956 -254.12879) (xy 91.41612 -254.179024) (xy 91.416632 -254.20447)
			(xy 91.724729 -254.20447) (xy 91.728824 -254.153742) (xy 91.741003 -254.104328) (xy 91.760951 -254.057508)
			(xy 91.788152 -254.014494) (xy 91.8219 -253.9764) (xy 91.861322 -253.944213) (xy 91.905396 -253.918767)
			(xy 91.952982 -253.90072) (xy 92.002846 -253.89054) (xy 92.053698 -253.888491) (xy 92.104219 -253.894625)
			(xy 92.153103 -253.908785) (xy 92.199082 -253.930602) (xy 92.240966 -253.959512) (xy 92.27767 -253.994767)
			(xy 92.308243 -254.035453) (xy 92.331894 -254.080516) (xy 92.34801 -254.12879) (xy 92.356174 -254.179024)
			(xy 92.356686 -254.20447) (xy 92.675214 -254.20447) (xy 92.679174 -254.155416) (xy 92.690951 -254.107632)
			(xy 92.710242 -254.062356) (xy 92.736545 -254.02076) (xy 92.76918 -253.983923) (xy 92.807301 -253.952798)
			(xy 92.849922 -253.928191) (xy 92.895938 -253.910739) (xy 92.944157 -253.900895) (xy 92.993332 -253.898914)
			(xy 93.042187 -253.904846) (xy 93.089458 -253.918538) (xy 93.13392 -253.939636) (xy 93.174423 -253.967592)
			(xy 93.209916 -254.001684) (xy 93.239481 -254.041028) (xy 93.262352 -254.084605) (xy 93.277936 -254.131286)
			(xy 93.285831 -254.179863) (xy 93.286326 -254.20447) (xy 93.604837 -254.20447) (xy 93.608932 -254.153742)
			(xy 93.621111 -254.104328) (xy 93.641059 -254.057508) (xy 93.66826 -254.014494) (xy 93.702008 -253.9764)
			(xy 93.74143 -253.944213) (xy 93.785504 -253.918767) (xy 93.83309 -253.90072) (xy 93.882954 -253.89054)
			(xy 93.933806 -253.888491) (xy 93.984327 -253.894625) (xy 94.033211 -253.908785) (xy 94.07919 -253.930602)
			(xy 94.121074 -253.959512) (xy 94.157778 -253.994767) (xy 94.188351 -254.035453) (xy 94.212002 -254.080516)
			(xy 94.228118 -254.12879) (xy 94.236282 -254.179024) (xy 94.236794 -254.20447) (xy 94.555322 -254.20447)
			(xy 94.559282 -254.155416) (xy 94.571059 -254.107632) (xy 94.59035 -254.062356) (xy 94.616653 -254.02076)
			(xy 94.649288 -253.983923) (xy 94.687409 -253.952798) (xy 94.73003 -253.928191) (xy 94.776046 -253.910739)
			(xy 94.824265 -253.900895) (xy 94.87344 -253.898914) (xy 94.922295 -253.904846) (xy 94.969566 -253.918538)
			(xy 95.014028 -253.939636) (xy 95.054531 -253.967592) (xy 95.090024 -254.001684) (xy 95.119589 -254.041028)
			(xy 95.14246 -254.084605) (xy 95.158044 -254.131286) (xy 95.165939 -254.179863) (xy 95.166434 -254.20447)
			(xy 95.484691 -254.20447) (xy 95.488786 -254.153742) (xy 95.500965 -254.104328) (xy 95.520913 -254.057508)
			(xy 95.548114 -254.014494) (xy 95.581862 -253.9764) (xy 95.621284 -253.944213) (xy 95.665358 -253.918767)
			(xy 95.712944 -253.90072) (xy 95.762808 -253.89054) (xy 95.81366 -253.888491) (xy 95.864181 -253.894625)
			(xy 95.913065 -253.908785) (xy 95.959044 -253.930602) (xy 96.000928 -253.959512) (xy 96.037632 -253.994767)
			(xy 96.068205 -254.035453) (xy 96.091856 -254.080516) (xy 96.107972 -254.12879) (xy 96.116136 -254.179024)
			(xy 96.116648 -254.20447) (xy 97.37523 -254.20447) (xy 97.37919 -254.155416) (xy 97.390967 -254.107632)
			(xy 97.410258 -254.062356) (xy 97.436561 -254.02076) (xy 97.469196 -253.983923) (xy 97.507317 -253.952798)
			(xy 97.549938 -253.928191) (xy 97.595954 -253.910739) (xy 97.644173 -253.900895) (xy 97.693348 -253.898914)
			(xy 97.742203 -253.904846) (xy 97.789474 -253.918538) (xy 97.833936 -253.939636) (xy 97.874439 -253.967592)
			(xy 97.909932 -254.001684) (xy 97.939497 -254.041028) (xy 97.962368 -254.084605) (xy 97.977952 -254.131286)
			(xy 97.985847 -254.179863) (xy 97.986342 -254.20447) (xy 99.255338 -254.20447) (xy 99.259298 -254.155416)
			(xy 99.271075 -254.107632) (xy 99.290366 -254.062356) (xy 99.316669 -254.02076) (xy 99.349304 -253.983923)
			(xy 99.387425 -253.952798) (xy 99.430046 -253.928191) (xy 99.476062 -253.910739) (xy 99.524281 -253.900895)
			(xy 99.573456 -253.898914) (xy 99.622311 -253.904846) (xy 99.669582 -253.918538) (xy 99.714044 -253.939636)
			(xy 99.754547 -253.967592) (xy 99.79004 -254.001684) (xy 99.819605 -254.041028) (xy 99.842476 -254.084605)
			(xy 99.85806 -254.131286) (xy 99.865955 -254.179863) (xy 99.86645 -254.20447) (xy 101.135192 -254.20447)
			(xy 101.139152 -254.155416) (xy 101.150929 -254.107632) (xy 101.17022 -254.062356) (xy 101.196523 -254.02076)
			(xy 101.229158 -253.983923) (xy 101.267279 -253.952798) (xy 101.3099 -253.928191) (xy 101.355916 -253.910739)
			(xy 101.404135 -253.900895) (xy 101.45331 -253.898914) (xy 101.502165 -253.904846) (xy 101.549436 -253.918538)
			(xy 101.593898 -253.939636) (xy 101.634401 -253.967592) (xy 101.669894 -254.001684) (xy 101.699459 -254.041028)
			(xy 101.72233 -254.084605) (xy 101.737914 -254.131286) (xy 101.745809 -254.179863) (xy 101.746304 -254.20447)
			(xy 102.075246 -254.20447) (xy 102.079206 -254.155416) (xy 102.090983 -254.107632) (xy 102.110274 -254.062356)
			(xy 102.136577 -254.02076) (xy 102.169212 -253.983923) (xy 102.207333 -253.952798) (xy 102.249954 -253.928191)
			(xy 102.29597 -253.910739) (xy 102.344189 -253.900895) (xy 102.393364 -253.898914) (xy 102.442219 -253.904846)
			(xy 102.48949 -253.918538) (xy 102.533952 -253.939636) (xy 102.574455 -253.967592) (xy 102.609948 -254.001684)
			(xy 102.639513 -254.041028) (xy 102.662384 -254.084605) (xy 102.677968 -254.131286) (xy 102.685863 -254.179863)
			(xy 102.686358 -254.20447) (xy 102.685863 -254.229077) (xy 102.677968 -254.277654) (xy 102.662384 -254.324335)
			(xy 102.639513 -254.367912) (xy 102.609948 -254.407256) (xy 102.574455 -254.441348) (xy 102.533952 -254.469304)
			(xy 102.48949 -254.490402) (xy 102.442219 -254.504094) (xy 102.393364 -254.510026) (xy 102.344189 -254.508045)
			(xy 102.29597 -254.498201) (xy 102.249954 -254.480749) (xy 102.207333 -254.456142) (xy 102.169212 -254.425017)
			(xy 102.136577 -254.38818) (xy 102.110274 -254.346584) (xy 102.090983 -254.301308) (xy 102.079206 -254.253524)
			(xy 102.075246 -254.20447) (xy 101.746304 -254.20447) (xy 101.745809 -254.229077) (xy 101.737914 -254.277654)
			(xy 101.72233 -254.324335) (xy 101.699459 -254.367912) (xy 101.669894 -254.407256) (xy 101.634401 -254.441348)
			(xy 101.593898 -254.469304) (xy 101.549436 -254.490402) (xy 101.502165 -254.504094) (xy 101.45331 -254.510026)
			(xy 101.404135 -254.508045) (xy 101.355916 -254.498201) (xy 101.3099 -254.480749) (xy 101.267279 -254.456142)
			(xy 101.229158 -254.425017) (xy 101.196523 -254.38818) (xy 101.17022 -254.346584) (xy 101.150929 -254.301308)
			(xy 101.139152 -254.253524) (xy 101.135192 -254.20447) (xy 99.86645 -254.20447) (xy 99.865955 -254.229077)
			(xy 99.85806 -254.277654) (xy 99.842476 -254.324335) (xy 99.819605 -254.367912) (xy 99.79004 -254.407256)
			(xy 99.754547 -254.441348) (xy 99.714044 -254.469304) (xy 99.669582 -254.490402) (xy 99.622311 -254.504094)
			(xy 99.573456 -254.510026) (xy 99.524281 -254.508045) (xy 99.476062 -254.498201) (xy 99.430046 -254.480749)
			(xy 99.387425 -254.456142) (xy 99.349304 -254.425017) (xy 99.316669 -254.38818) (xy 99.290366 -254.346584)
			(xy 99.271075 -254.301308) (xy 99.259298 -254.253524) (xy 99.255338 -254.20447) (xy 97.986342 -254.20447)
			(xy 97.985847 -254.229077) (xy 97.977952 -254.277654) (xy 97.962368 -254.324335) (xy 97.939497 -254.367912)
			(xy 97.909932 -254.407256) (xy 97.874439 -254.441348) (xy 97.833936 -254.469304) (xy 97.789474 -254.490402)
			(xy 97.742203 -254.504094) (xy 97.693348 -254.510026) (xy 97.644173 -254.508045) (xy 97.595954 -254.498201)
			(xy 97.549938 -254.480749) (xy 97.507317 -254.456142) (xy 97.469196 -254.425017) (xy 97.436561 -254.38818)
			(xy 97.410258 -254.346584) (xy 97.390967 -254.301308) (xy 97.37919 -254.253524) (xy 97.37523 -254.20447)
			(xy 96.116648 -254.20447) (xy 96.116136 -254.229916) (xy 96.107972 -254.28015) (xy 96.091856 -254.328424)
			(xy 96.068205 -254.373487) (xy 96.037632 -254.414173) (xy 96.000928 -254.449428) (xy 95.959044 -254.478338)
			(xy 95.913065 -254.500155) (xy 95.864181 -254.514315) (xy 95.81366 -254.520449) (xy 95.762808 -254.5184)
			(xy 95.712944 -254.50822) (xy 95.665358 -254.490173) (xy 95.621284 -254.464727) (xy 95.581862 -254.43254)
			(xy 95.548114 -254.394446) (xy 95.520913 -254.351432) (xy 95.500965 -254.304612) (xy 95.488786 -254.255198)
			(xy 95.484691 -254.20447) (xy 95.166434 -254.20447) (xy 95.165939 -254.229077) (xy 95.158044 -254.277654)
			(xy 95.14246 -254.324335) (xy 95.119589 -254.367912) (xy 95.090024 -254.407256) (xy 95.054531 -254.441348)
			(xy 95.014028 -254.469304) (xy 94.969566 -254.490402) (xy 94.922295 -254.504094) (xy 94.87344 -254.510026)
			(xy 94.824265 -254.508045) (xy 94.776046 -254.498201) (xy 94.73003 -254.480749) (xy 94.687409 -254.456142)
			(xy 94.649288 -254.425017) (xy 94.616653 -254.38818) (xy 94.59035 -254.346584) (xy 94.571059 -254.301308)
			(xy 94.559282 -254.253524) (xy 94.555322 -254.20447) (xy 94.236794 -254.20447) (xy 94.236282 -254.229916)
			(xy 94.228118 -254.28015) (xy 94.212002 -254.328424) (xy 94.188351 -254.373487) (xy 94.157778 -254.414173)
			(xy 94.121074 -254.449428) (xy 94.07919 -254.478338) (xy 94.033211 -254.500155) (xy 93.984327 -254.514315)
			(xy 93.933806 -254.520449) (xy 93.882954 -254.5184) (xy 93.83309 -254.50822) (xy 93.785504 -254.490173)
			(xy 93.74143 -254.464727) (xy 93.702008 -254.43254) (xy 93.66826 -254.394446) (xy 93.641059 -254.351432)
			(xy 93.621111 -254.304612) (xy 93.608932 -254.255198) (xy 93.604837 -254.20447) (xy 93.286326 -254.20447)
			(xy 93.285831 -254.229077) (xy 93.277936 -254.277654) (xy 93.262352 -254.324335) (xy 93.239481 -254.367912)
			(xy 93.209916 -254.407256) (xy 93.174423 -254.441348) (xy 93.13392 -254.469304) (xy 93.089458 -254.490402)
			(xy 93.042187 -254.504094) (xy 92.993332 -254.510026) (xy 92.944157 -254.508045) (xy 92.895938 -254.498201)
			(xy 92.849922 -254.480749) (xy 92.807301 -254.456142) (xy 92.76918 -254.425017) (xy 92.736545 -254.38818)
			(xy 92.710242 -254.346584) (xy 92.690951 -254.301308) (xy 92.679174 -254.253524) (xy 92.675214 -254.20447)
			(xy 92.356686 -254.20447) (xy 92.356174 -254.229916) (xy 92.34801 -254.28015) (xy 92.331894 -254.328424)
			(xy 92.308243 -254.373487) (xy 92.27767 -254.414173) (xy 92.240966 -254.449428) (xy 92.199082 -254.478338)
			(xy 92.153103 -254.500155) (xy 92.104219 -254.514315) (xy 92.053698 -254.520449) (xy 92.002846 -254.5184)
			(xy 91.952982 -254.50822) (xy 91.905396 -254.490173) (xy 91.861322 -254.464727) (xy 91.8219 -254.43254)
			(xy 91.788152 -254.394446) (xy 91.760951 -254.351432) (xy 91.741003 -254.304612) (xy 91.728824 -254.255198)
			(xy 91.724729 -254.20447) (xy 91.416632 -254.20447) (xy 91.41612 -254.229916) (xy 91.407956 -254.28015)
			(xy 91.39184 -254.328424) (xy 91.368189 -254.373487) (xy 91.337616 -254.414173) (xy 91.300912 -254.449428)
			(xy 91.259028 -254.478338) (xy 91.213049 -254.500155) (xy 91.164165 -254.514315) (xy 91.113644 -254.520449)
			(xy 91.062792 -254.5184) (xy 91.012928 -254.50822) (xy 90.965342 -254.490173) (xy 90.921268 -254.464727)
			(xy 90.881846 -254.43254) (xy 90.848098 -254.394446) (xy 90.820897 -254.351432) (xy 90.800949 -254.304612)
			(xy 90.78877 -254.255198) (xy 90.784675 -254.20447) (xy 90.466418 -254.20447) (xy 90.465923 -254.229077)
			(xy 90.458028 -254.277654) (xy 90.442444 -254.324335) (xy 90.419573 -254.367912) (xy 90.390008 -254.407256)
			(xy 90.354515 -254.441348) (xy 90.314012 -254.469304) (xy 90.26955 -254.490402) (xy 90.222279 -254.504094)
			(xy 90.173424 -254.510026) (xy 90.124249 -254.508045) (xy 90.07603 -254.498201) (xy 90.030014 -254.480749)
			(xy 89.987393 -254.456142) (xy 89.949272 -254.425017) (xy 89.916637 -254.38818) (xy 89.890334 -254.346584)
			(xy 89.871043 -254.301308) (xy 89.859266 -254.253524) (xy 89.855306 -254.20447) (xy 89.526364 -254.20447)
			(xy 89.525869 -254.229077) (xy 89.517974 -254.277654) (xy 89.50239 -254.324335) (xy 89.479519 -254.367912)
			(xy 89.449954 -254.407256) (xy 89.414461 -254.441348) (xy 89.373958 -254.469304) (xy 89.329496 -254.490402)
			(xy 89.282225 -254.504094) (xy 89.23337 -254.510026) (xy 89.184195 -254.508045) (xy 89.135976 -254.498201)
			(xy 89.08996 -254.480749) (xy 89.047339 -254.456142) (xy 89.009218 -254.425017) (xy 88.976583 -254.38818)
			(xy 88.95028 -254.346584) (xy 88.930989 -254.301308) (xy 88.919212 -254.253524) (xy 88.915252 -254.20447)
			(xy 88.58631 -254.20447) (xy 88.585815 -254.229077) (xy 88.57792 -254.277654) (xy 88.562336 -254.324335)
			(xy 88.539465 -254.367912) (xy 88.5099 -254.407256) (xy 88.474407 -254.441348) (xy 88.433904 -254.469304)
			(xy 88.389442 -254.490402) (xy 88.342171 -254.504094) (xy 88.293316 -254.510026) (xy 88.244141 -254.508045)
			(xy 88.195922 -254.498201) (xy 88.149906 -254.480749) (xy 88.107285 -254.456142) (xy 88.069164 -254.425017)
			(xy 88.036529 -254.38818) (xy 88.010226 -254.346584) (xy 87.990935 -254.301308) (xy 87.979158 -254.253524)
			(xy 87.975198 -254.20447) (xy 87.646256 -254.20447) (xy 87.645761 -254.229077) (xy 87.637866 -254.277654)
			(xy 87.622282 -254.324335) (xy 87.599411 -254.367912) (xy 87.569846 -254.407256) (xy 87.534353 -254.441348)
			(xy 87.49385 -254.469304) (xy 87.449388 -254.490402) (xy 87.402117 -254.504094) (xy 87.353262 -254.510026)
			(xy 87.304087 -254.508045) (xy 87.255868 -254.498201) (xy 87.209852 -254.480749) (xy 87.167231 -254.456142)
			(xy 87.12911 -254.425017) (xy 87.096475 -254.38818) (xy 87.070172 -254.346584) (xy 87.050881 -254.301308)
			(xy 87.039104 -254.253524) (xy 87.035144 -254.20447) (xy 86.804754 -254.20447) (xy 86.804754 -254.49911)
			(xy 86.805211 -254.508989) (xy 86.812648 -254.527293) (xy 86.819232 -254.53467) (xy 86.819486 -254.534924)
			(xy 87.05342 -254.768858) (xy 87.05596 -254.771144) (xy 87.071697 -254.783494) (xy 87.100109 -254.811654)
			(xy 87.112602 -254.827278) (xy 87.114634 -254.830072) (xy 87.165942 -254.88138) (xy 87.172657 -254.888618)
			(xy 87.180258 -254.906822) (xy 87.180674 -254.916686) (xy 87.180674 -255.014476) (xy 87.505298 -255.014476)
			(xy 87.509258 -254.965422) (xy 87.521035 -254.917638) (xy 87.540326 -254.872362) (xy 87.566629 -254.830766)
			(xy 87.599264 -254.793929) (xy 87.637385 -254.762804) (xy 87.680006 -254.738197) (xy 87.726022 -254.720745)
			(xy 87.774241 -254.710901) (xy 87.823416 -254.70892) (xy 87.872271 -254.714852) (xy 87.919542 -254.728544)
			(xy 87.964004 -254.749642) (xy 88.004507 -254.777598) (xy 88.04 -254.81169) (xy 88.069565 -254.851034)
			(xy 88.092436 -254.894611) (xy 88.10802 -254.941292) (xy 88.115915 -254.989869) (xy 88.11641 -255.014476)
			(xy 88.445352 -255.014476) (xy 88.449312 -254.965422) (xy 88.461089 -254.917638) (xy 88.48038 -254.872362)
			(xy 88.506683 -254.830766) (xy 88.539318 -254.793929) (xy 88.577439 -254.762804) (xy 88.62006 -254.738197)
			(xy 88.666076 -254.720745) (xy 88.714295 -254.710901) (xy 88.76347 -254.70892) (xy 88.812325 -254.714852)
			(xy 88.859596 -254.728544) (xy 88.904058 -254.749642) (xy 88.944561 -254.777598) (xy 88.980054 -254.81169)
			(xy 89.009619 -254.851034) (xy 89.03249 -254.894611) (xy 89.048074 -254.941292) (xy 89.055969 -254.989869)
			(xy 89.056464 -255.014476) (xy 89.385152 -255.014476) (xy 89.389112 -254.965422) (xy 89.400889 -254.917638)
			(xy 89.42018 -254.872362) (xy 89.446483 -254.830766) (xy 89.479118 -254.793929) (xy 89.517239 -254.762804)
			(xy 89.55986 -254.738197) (xy 89.605876 -254.720745) (xy 89.654095 -254.710901) (xy 89.70327 -254.70892)
			(xy 89.752125 -254.714852) (xy 89.799396 -254.728544) (xy 89.843858 -254.749642) (xy 89.884361 -254.777598)
			(xy 89.919854 -254.81169) (xy 89.949419 -254.851034) (xy 89.97229 -254.894611) (xy 89.987874 -254.941292)
			(xy 89.995769 -254.989869) (xy 89.996264 -255.014476) (xy 90.314775 -255.014476) (xy 90.31887 -254.963748)
			(xy 90.331049 -254.914334) (xy 90.350997 -254.867514) (xy 90.378198 -254.8245) (xy 90.411946 -254.786406)
			(xy 90.451368 -254.754219) (xy 90.495442 -254.728773) (xy 90.543028 -254.710726) (xy 90.592892 -254.700546)
			(xy 90.643744 -254.698497) (xy 90.694265 -254.704631) (xy 90.743149 -254.718791) (xy 90.789128 -254.740608)
			(xy 90.831012 -254.769518) (xy 90.867716 -254.804773) (xy 90.898289 -254.845459) (xy 90.92194 -254.890522)
			(xy 90.938056 -254.938796) (xy 90.94622 -254.98903) (xy 90.946732 -255.014476) (xy 91.26526 -255.014476)
			(xy 91.26922 -254.965422) (xy 91.280997 -254.917638) (xy 91.300288 -254.872362) (xy 91.326591 -254.830766)
			(xy 91.359226 -254.793929) (xy 91.397347 -254.762804) (xy 91.439968 -254.738197) (xy 91.485984 -254.720745)
			(xy 91.534203 -254.710901) (xy 91.583378 -254.70892) (xy 91.632233 -254.714852) (xy 91.679504 -254.728544)
			(xy 91.723966 -254.749642) (xy 91.764469 -254.777598) (xy 91.799962 -254.81169) (xy 91.829527 -254.851034)
			(xy 91.852398 -254.894611) (xy 91.867982 -254.941292) (xy 91.875877 -254.989869) (xy 91.876372 -255.014476)
			(xy 92.194883 -255.014476) (xy 92.198978 -254.963748) (xy 92.211157 -254.914334) (xy 92.231105 -254.867514)
			(xy 92.258306 -254.8245) (xy 92.292054 -254.786406) (xy 92.331476 -254.754219) (xy 92.37555 -254.728773)
			(xy 92.423136 -254.710726) (xy 92.473 -254.700546) (xy 92.523852 -254.698497) (xy 92.574373 -254.704631)
			(xy 92.623257 -254.718791) (xy 92.669236 -254.740608) (xy 92.71112 -254.769518) (xy 92.747824 -254.804773)
			(xy 92.778397 -254.845459) (xy 92.802048 -254.890522) (xy 92.818164 -254.938796) (xy 92.826328 -254.98903)
			(xy 92.82684 -255.014476) (xy 93.145114 -255.014476) (xy 93.149074 -254.965422) (xy 93.160851 -254.917638)
			(xy 93.180142 -254.872362) (xy 93.206445 -254.830766) (xy 93.23908 -254.793929) (xy 93.277201 -254.762804)
			(xy 93.319822 -254.738197) (xy 93.365838 -254.720745) (xy 93.414057 -254.710901) (xy 93.463232 -254.70892)
			(xy 93.512087 -254.714852) (xy 93.559358 -254.728544) (xy 93.60382 -254.749642) (xy 93.644323 -254.777598)
			(xy 93.679816 -254.81169) (xy 93.709381 -254.851034) (xy 93.732252 -254.894611) (xy 93.747836 -254.941292)
			(xy 93.755731 -254.989869) (xy 93.756226 -255.014476) (xy 94.074737 -255.014476) (xy 94.078832 -254.963748)
			(xy 94.091011 -254.914334) (xy 94.110959 -254.867514) (xy 94.13816 -254.8245) (xy 94.171908 -254.786406)
			(xy 94.21133 -254.754219) (xy 94.255404 -254.728773) (xy 94.30299 -254.710726) (xy 94.352854 -254.700546)
			(xy 94.403706 -254.698497) (xy 94.454227 -254.704631) (xy 94.503111 -254.718791) (xy 94.54909 -254.740608)
			(xy 94.590974 -254.769518) (xy 94.627678 -254.804773) (xy 94.658251 -254.845459) (xy 94.681902 -254.890522)
			(xy 94.698018 -254.938796) (xy 94.706182 -254.98903) (xy 94.706694 -255.014476) (xy 95.014791 -255.014476)
			(xy 95.018886 -254.963748) (xy 95.031065 -254.914334) (xy 95.051013 -254.867514) (xy 95.078214 -254.8245)
			(xy 95.111962 -254.786406) (xy 95.151384 -254.754219) (xy 95.195458 -254.728773) (xy 95.243044 -254.710726)
			(xy 95.292908 -254.700546) (xy 95.34376 -254.698497) (xy 95.394281 -254.704631) (xy 95.443165 -254.718791)
			(xy 95.489144 -254.740608) (xy 95.531028 -254.769518) (xy 95.567732 -254.804773) (xy 95.598305 -254.845459)
			(xy 95.621956 -254.890522) (xy 95.638072 -254.938796) (xy 95.646236 -254.98903) (xy 95.646748 -255.014476)
			(xy 95.965276 -255.014476) (xy 95.969236 -254.965422) (xy 95.981013 -254.917638) (xy 96.000304 -254.872362)
			(xy 96.026607 -254.830766) (xy 96.059242 -254.793929) (xy 96.097363 -254.762804) (xy 96.139984 -254.738197)
			(xy 96.186 -254.720745) (xy 96.234219 -254.710901) (xy 96.283394 -254.70892) (xy 96.332249 -254.714852)
			(xy 96.37952 -254.728544) (xy 96.423982 -254.749642) (xy 96.464485 -254.777598) (xy 96.499978 -254.81169)
			(xy 96.529543 -254.851034) (xy 96.552414 -254.894611) (xy 96.567998 -254.941292) (xy 96.575893 -254.989869)
			(xy 96.576388 -255.014476) (xy 97.84513 -255.014476) (xy 97.84909 -254.965422) (xy 97.860867 -254.917638)
			(xy 97.880158 -254.872362) (xy 97.906461 -254.830766) (xy 97.939096 -254.793929) (xy 97.977217 -254.762804)
			(xy 98.019838 -254.738197) (xy 98.065854 -254.720745) (xy 98.114073 -254.710901) (xy 98.163248 -254.70892)
			(xy 98.212103 -254.714852) (xy 98.259374 -254.728544) (xy 98.303836 -254.749642) (xy 98.344339 -254.777598)
			(xy 98.379832 -254.81169) (xy 98.409397 -254.851034) (xy 98.432268 -254.894611) (xy 98.447852 -254.941292)
			(xy 98.455747 -254.989869) (xy 98.456242 -255.014476) (xy 99.725238 -255.014476) (xy 99.729198 -254.965422)
			(xy 99.740975 -254.917638) (xy 99.760266 -254.872362) (xy 99.786569 -254.830766) (xy 99.819204 -254.793929)
			(xy 99.857325 -254.762804) (xy 99.899946 -254.738197) (xy 99.945962 -254.720745) (xy 99.994181 -254.710901)
			(xy 100.043356 -254.70892) (xy 100.092211 -254.714852) (xy 100.139482 -254.728544) (xy 100.183944 -254.749642)
			(xy 100.224447 -254.777598) (xy 100.25994 -254.81169) (xy 100.289505 -254.851034) (xy 100.312376 -254.894611)
			(xy 100.32796 -254.941292) (xy 100.335855 -254.989869) (xy 100.33635 -255.014476) (xy 100.665292 -255.014476)
			(xy 100.669252 -254.965422) (xy 100.681029 -254.917638) (xy 100.70032 -254.872362) (xy 100.726623 -254.830766)
			(xy 100.759258 -254.793929) (xy 100.797379 -254.762804) (xy 100.84 -254.738197) (xy 100.886016 -254.720745)
			(xy 100.934235 -254.710901) (xy 100.98341 -254.70892) (xy 101.032265 -254.714852) (xy 101.079536 -254.728544)
			(xy 101.123998 -254.749642) (xy 101.164501 -254.777598) (xy 101.199994 -254.81169) (xy 101.229559 -254.851034)
			(xy 101.25243 -254.894611) (xy 101.268014 -254.941292) (xy 101.275909 -254.989869) (xy 101.276404 -255.014476)
			(xy 101.605346 -255.014476) (xy 101.609306 -254.965422) (xy 101.621083 -254.917638) (xy 101.640374 -254.872362)
			(xy 101.666677 -254.830766) (xy 101.699312 -254.793929) (xy 101.737433 -254.762804) (xy 101.780054 -254.738197)
			(xy 101.82607 -254.720745) (xy 101.874289 -254.710901) (xy 101.923464 -254.70892) (xy 101.972319 -254.714852)
			(xy 102.01959 -254.728544) (xy 102.064052 -254.749642) (xy 102.104555 -254.777598) (xy 102.140048 -254.81169)
			(xy 102.169613 -254.851034) (xy 102.192484 -254.894611) (xy 102.208068 -254.941292) (xy 102.215963 -254.989869)
			(xy 102.216458 -255.014476) (xy 102.215963 -255.039083) (xy 102.208068 -255.08766) (xy 102.192484 -255.134341)
			(xy 102.169613 -255.177918) (xy 102.140048 -255.217262) (xy 102.104555 -255.251354) (xy 102.064052 -255.27931)
			(xy 102.01959 -255.300408) (xy 101.972319 -255.3141) (xy 101.923464 -255.320032) (xy 101.874289 -255.318051)
			(xy 101.82607 -255.308207) (xy 101.780054 -255.290755) (xy 101.737433 -255.266148) (xy 101.699312 -255.235023)
			(xy 101.666677 -255.198186) (xy 101.640374 -255.15659) (xy 101.621083 -255.111314) (xy 101.609306 -255.06353)
			(xy 101.605346 -255.014476) (xy 101.276404 -255.014476) (xy 101.275909 -255.039083) (xy 101.268014 -255.08766)
			(xy 101.25243 -255.134341) (xy 101.229559 -255.177918) (xy 101.199994 -255.217262) (xy 101.164501 -255.251354)
			(xy 101.123998 -255.27931) (xy 101.079536 -255.300408) (xy 101.032265 -255.3141) (xy 100.98341 -255.320032)
			(xy 100.934235 -255.318051) (xy 100.886016 -255.308207) (xy 100.84 -255.290755) (xy 100.797379 -255.266148)
			(xy 100.759258 -255.235023) (xy 100.726623 -255.198186) (xy 100.70032 -255.15659) (xy 100.681029 -255.111314)
			(xy 100.669252 -255.06353) (xy 100.665292 -255.014476) (xy 100.33635 -255.014476) (xy 100.335855 -255.039083)
			(xy 100.32796 -255.08766) (xy 100.312376 -255.134341) (xy 100.289505 -255.177918) (xy 100.25994 -255.217262)
			(xy 100.224447 -255.251354) (xy 100.183944 -255.27931) (xy 100.139482 -255.300408) (xy 100.092211 -255.3141)
			(xy 100.043356 -255.320032) (xy 99.994181 -255.318051) (xy 99.945962 -255.308207) (xy 99.899946 -255.290755)
			(xy 99.857325 -255.266148) (xy 99.819204 -255.235023) (xy 99.786569 -255.198186) (xy 99.760266 -255.15659)
			(xy 99.740975 -255.111314) (xy 99.729198 -255.06353) (xy 99.725238 -255.014476) (xy 98.456242 -255.014476)
			(xy 98.455747 -255.039083) (xy 98.447852 -255.08766) (xy 98.432268 -255.134341) (xy 98.409397 -255.177918)
			(xy 98.379832 -255.217262) (xy 98.344339 -255.251354) (xy 98.303836 -255.27931) (xy 98.259374 -255.300408)
			(xy 98.212103 -255.3141) (xy 98.163248 -255.320032) (xy 98.114073 -255.318051) (xy 98.065854 -255.308207)
			(xy 98.019838 -255.290755) (xy 97.977217 -255.266148) (xy 97.939096 -255.235023) (xy 97.906461 -255.198186)
			(xy 97.880158 -255.15659) (xy 97.860867 -255.111314) (xy 97.84909 -255.06353) (xy 97.84513 -255.014476)
			(xy 96.576388 -255.014476) (xy 96.575893 -255.039083) (xy 96.567998 -255.08766) (xy 96.552414 -255.134341)
			(xy 96.529543 -255.177918) (xy 96.499978 -255.217262) (xy 96.464485 -255.251354) (xy 96.423982 -255.27931)
			(xy 96.37952 -255.300408) (xy 96.332249 -255.3141) (xy 96.283394 -255.320032) (xy 96.234219 -255.318051)
			(xy 96.186 -255.308207) (xy 96.139984 -255.290755) (xy 96.097363 -255.266148) (xy 96.059242 -255.235023)
			(xy 96.026607 -255.198186) (xy 96.000304 -255.15659) (xy 95.981013 -255.111314) (xy 95.969236 -255.06353)
			(xy 95.965276 -255.014476) (xy 95.646748 -255.014476) (xy 95.646236 -255.039922) (xy 95.638072 -255.090156)
			(xy 95.621956 -255.13843) (xy 95.598305 -255.183493) (xy 95.567732 -255.224179) (xy 95.531028 -255.259434)
			(xy 95.489144 -255.288344) (xy 95.443165 -255.310161) (xy 95.394281 -255.324321) (xy 95.34376 -255.330455)
			(xy 95.292908 -255.328406) (xy 95.243044 -255.318226) (xy 95.195458 -255.300179) (xy 95.151384 -255.274733)
			(xy 95.111962 -255.242546) (xy 95.078214 -255.204452) (xy 95.051013 -255.161438) (xy 95.031065 -255.114618)
			(xy 95.018886 -255.065204) (xy 95.014791 -255.014476) (xy 94.706694 -255.014476) (xy 94.706182 -255.039922)
			(xy 94.698018 -255.090156) (xy 94.681902 -255.13843) (xy 94.658251 -255.183493) (xy 94.627678 -255.224179)
			(xy 94.590974 -255.259434) (xy 94.54909 -255.288344) (xy 94.503111 -255.310161) (xy 94.454227 -255.324321)
			(xy 94.403706 -255.330455) (xy 94.352854 -255.328406) (xy 94.30299 -255.318226) (xy 94.255404 -255.300179)
			(xy 94.21133 -255.274733) (xy 94.171908 -255.242546) (xy 94.13816 -255.204452) (xy 94.110959 -255.161438)
			(xy 94.091011 -255.114618) (xy 94.078832 -255.065204) (xy 94.074737 -255.014476) (xy 93.756226 -255.014476)
			(xy 93.755731 -255.039083) (xy 93.747836 -255.08766) (xy 93.732252 -255.134341) (xy 93.709381 -255.177918)
			(xy 93.679816 -255.217262) (xy 93.644323 -255.251354) (xy 93.60382 -255.27931) (xy 93.559358 -255.300408)
			(xy 93.512087 -255.3141) (xy 93.463232 -255.320032) (xy 93.414057 -255.318051) (xy 93.365838 -255.308207)
			(xy 93.319822 -255.290755) (xy 93.277201 -255.266148) (xy 93.23908 -255.235023) (xy 93.206445 -255.198186)
			(xy 93.180142 -255.15659) (xy 93.160851 -255.111314) (xy 93.149074 -255.06353) (xy 93.145114 -255.014476)
			(xy 92.82684 -255.014476) (xy 92.826328 -255.039922) (xy 92.818164 -255.090156) (xy 92.802048 -255.13843)
			(xy 92.778397 -255.183493) (xy 92.747824 -255.224179) (xy 92.71112 -255.259434) (xy 92.669236 -255.288344)
			(xy 92.623257 -255.310161) (xy 92.574373 -255.324321) (xy 92.523852 -255.330455) (xy 92.473 -255.328406)
			(xy 92.423136 -255.318226) (xy 92.37555 -255.300179) (xy 92.331476 -255.274733) (xy 92.292054 -255.242546)
			(xy 92.258306 -255.204452) (xy 92.231105 -255.161438) (xy 92.211157 -255.114618) (xy 92.198978 -255.065204)
			(xy 92.194883 -255.014476) (xy 91.876372 -255.014476) (xy 91.875877 -255.039083) (xy 91.867982 -255.08766)
			(xy 91.852398 -255.134341) (xy 91.829527 -255.177918) (xy 91.799962 -255.217262) (xy 91.764469 -255.251354)
			(xy 91.723966 -255.27931) (xy 91.679504 -255.300408) (xy 91.632233 -255.3141) (xy 91.583378 -255.320032)
			(xy 91.534203 -255.318051) (xy 91.485984 -255.308207) (xy 91.439968 -255.290755) (xy 91.397347 -255.266148)
			(xy 91.359226 -255.235023) (xy 91.326591 -255.198186) (xy 91.300288 -255.15659) (xy 91.280997 -255.111314)
			(xy 91.26922 -255.06353) (xy 91.26526 -255.014476) (xy 90.946732 -255.014476) (xy 90.94622 -255.039922)
			(xy 90.938056 -255.090156) (xy 90.92194 -255.13843) (xy 90.898289 -255.183493) (xy 90.867716 -255.224179)
			(xy 90.831012 -255.259434) (xy 90.789128 -255.288344) (xy 90.743149 -255.310161) (xy 90.694265 -255.324321)
			(xy 90.643744 -255.330455) (xy 90.592892 -255.328406) (xy 90.543028 -255.318226) (xy 90.495442 -255.300179)
			(xy 90.451368 -255.274733) (xy 90.411946 -255.242546) (xy 90.378198 -255.204452) (xy 90.350997 -255.161438)
			(xy 90.331049 -255.114618) (xy 90.31887 -255.065204) (xy 90.314775 -255.014476) (xy 89.996264 -255.014476)
			(xy 89.995769 -255.039083) (xy 89.987874 -255.08766) (xy 89.97229 -255.134341) (xy 89.949419 -255.177918)
			(xy 89.919854 -255.217262) (xy 89.884361 -255.251354) (xy 89.843858 -255.27931) (xy 89.799396 -255.300408)
			(xy 89.752125 -255.3141) (xy 89.70327 -255.320032) (xy 89.654095 -255.318051) (xy 89.605876 -255.308207)
			(xy 89.55986 -255.290755) (xy 89.517239 -255.266148) (xy 89.479118 -255.235023) (xy 89.446483 -255.198186)
			(xy 89.42018 -255.15659) (xy 89.400889 -255.111314) (xy 89.389112 -255.06353) (xy 89.385152 -255.014476)
			(xy 89.056464 -255.014476) (xy 89.055969 -255.039083) (xy 89.048074 -255.08766) (xy 89.03249 -255.134341)
			(xy 89.009619 -255.177918) (xy 88.980054 -255.217262) (xy 88.944561 -255.251354) (xy 88.904058 -255.27931)
			(xy 88.859596 -255.300408) (xy 88.812325 -255.3141) (xy 88.76347 -255.320032) (xy 88.714295 -255.318051)
			(xy 88.666076 -255.308207) (xy 88.62006 -255.290755) (xy 88.577439 -255.266148) (xy 88.539318 -255.235023)
			(xy 88.506683 -255.198186) (xy 88.48038 -255.15659) (xy 88.461089 -255.111314) (xy 88.449312 -255.06353)
			(xy 88.445352 -255.014476) (xy 88.11641 -255.014476) (xy 88.115915 -255.039083) (xy 88.10802 -255.08766)
			(xy 88.092436 -255.134341) (xy 88.069565 -255.177918) (xy 88.04 -255.217262) (xy 88.004507 -255.251354)
			(xy 87.964004 -255.27931) (xy 87.919542 -255.300408) (xy 87.872271 -255.3141) (xy 87.823416 -255.320032)
			(xy 87.774241 -255.318051) (xy 87.726022 -255.308207) (xy 87.680006 -255.290755) (xy 87.637385 -255.266148)
			(xy 87.599264 -255.235023) (xy 87.566629 -255.198186) (xy 87.540326 -255.15659) (xy 87.521035 -255.111314)
			(xy 87.509258 -255.06353) (xy 87.505298 -255.014476) (xy 87.180674 -255.014476) (xy 87.180674 -255.23063)
			(xy 87.181135 -255.240507) (xy 87.188579 -255.258805) (xy 87.195152 -255.26619) (xy 87.195406 -255.266444)
			(xy 87.483188 -255.554226) (xy 87.489538 -255.557782) (xy 87.511636 -255.571498) (xy 87.517732 -255.575562)
			(xy 87.54618 -255.584452) (xy 88.067896 -255.584452) (xy 88.079326 -255.582674) (xy 88.083136 -255.582166)
			(xy 88.103202 -255.57607) (xy 88.109806 -255.571752) (xy 88.128614 -255.559497) (xy 88.169065 -255.540036)
			(xy 88.211926 -255.526695) (xy 88.256276 -255.519761) (xy 88.278716 -255.519174) (xy 88.28405 -255.519174)
			(xy 88.30631 -255.519803) (xy 88.350303 -255.526708) (xy 88.392831 -255.539914) (xy 88.432997 -255.559141)
			(xy 88.45169 -255.571244) (xy 88.457532 -255.575308) (xy 88.48598 -255.584452) (xy 89.00795 -255.584452)
			(xy 89.01938 -255.582674) (xy 89.02319 -255.582166) (xy 89.043256 -255.57607) (xy 89.04986 -255.571752)
			(xy 89.068909 -255.559342) (xy 89.109907 -255.539693) (xy 89.153366 -255.526345) (xy 89.198325 -255.519593)
			(xy 89.221056 -255.519174) (xy 89.229692 -255.519174) (xy 89.253242 -255.520268) (xy 89.299604 -255.528809)
			(xy 89.344102 -255.544376) (xy 89.385678 -255.5666) (xy 89.423342 -255.594951) (xy 89.4562 -255.628756)
			(xy 89.48347 -255.667211) (xy 89.504503 -255.709402) (xy 89.5188 -255.754324) (xy 89.52602 -255.800911)
			(xy 89.526364 -255.824482) (xy 89.526364 -255.824736) (xy 89.525947 -255.847237) (xy 89.519317 -255.891748)
			(xy 89.506233 -255.934807) (xy 89.48698 -255.975483) (xy 89.474802 -255.994408) (xy 89.470484 -256.001012)
			(xy 89.468198 -256.008632) (xy 89.46723 -256.012172) (xy 89.466205 -256.01944) (xy 89.466166 -256.02311)
			(xy 89.466166 -256.033524) (xy 89.466626 -256.043401) (xy 89.474067 -256.061701) (xy 89.480644 -256.069084)
			(xy 89.480898 -256.069338) (xy 89.492328 -256.080768) (xy 89.492836 -256.081276) (xy 89.500218 -256.087858)
			(xy 89.518516 -256.095311) (xy 89.528396 -256.095754) (xy 89.793064 -256.095754) (xy 89.801615 -256.095434)
			(xy 89.817767 -256.089819) (xy 89.831173 -256.079202) (xy 89.83599 -256.072132) (xy 89.887806 -255.990852)
			(xy 89.889584 -255.965198) (xy 89.883996 -255.95326) (xy 89.875091 -255.933107) (xy 89.862532 -255.890875)
			(xy 89.856198 -255.847274) (xy 89.855802 -255.825244) (xy 89.855802 -255.824482) (xy 89.856324 -255.799227)
			(xy 89.864637 -255.749405) (xy 89.881038 -255.701631) (xy 89.905079 -255.657208) (xy 89.936103 -255.617348)
			(xy 89.973265 -255.583138) (xy 90.015551 -255.555512) (xy 90.061807 -255.535222) (xy 90.110772 -255.522822)
			(xy 90.16111 -255.518651) (xy 90.211448 -255.522822) (xy 90.260413 -255.535222) (xy 90.306669 -255.555512)
			(xy 90.348955 -255.583138) (xy 90.386117 -255.617348) (xy 90.417141 -255.657208) (xy 90.441182 -255.701631)
			(xy 90.457583 -255.749405) (xy 90.465896 -255.799227) (xy 90.466418 -255.824482) (xy 90.466418 -255.825244)
			(xy 90.466011 -255.847272) (xy 90.459653 -255.890867) (xy 90.447116 -255.933103) (xy 90.438224 -255.95326)
			(xy 90.432636 -255.965198) (xy 90.434414 -255.990852) (xy 90.48623 -256.072132) (xy 90.491056 -256.078736)
			(xy 90.497685 -256.085568) (xy 90.514648 -256.09418) (xy 90.524076 -256.0955) (xy 90.528902 -256.095754)
			(xy 90.73134 -256.095754) (xy 90.741216 -256.095291) (xy 90.759514 -256.087848) (xy 90.7669 -256.081276)
			(xy 90.767154 -256.081022) (xy 90.771472 -256.076704) (xy 90.778584 -256.068068) (xy 90.82151 -256.000504)
			(xy 90.82278 -255.974342) (xy 90.816938 -255.962404) (xy 90.806924 -255.940806) (xy 90.792785 -255.895349)
			(xy 90.785635 -255.848284) (xy 90.785188 -255.824482) (xy 90.785675 -255.799672) (xy 90.793437 -255.750664)
			(xy 90.80877 -255.703474) (xy 90.831297 -255.659263) (xy 90.860462 -255.61912) (xy 90.895548 -255.584034)
			(xy 90.935691 -255.554869) (xy 90.979902 -255.532342) (xy 91.027092 -255.517009) (xy 91.0761 -255.509247)
			(xy 91.12572 -255.509247) (xy 91.174728 -255.517009) (xy 91.221918 -255.532342) (xy 91.266129 -255.554869)
			(xy 91.306272 -255.584034) (xy 91.341358 -255.61912) (xy 91.370523 -255.659263) (xy 91.39305 -255.703474)
			(xy 91.408383 -255.750664) (xy 91.416145 -255.799672) (xy 91.416632 -255.824482) (xy 91.4162 -255.848001)
			(xy 91.409222 -255.894518) (xy 91.395418 -255.939484) (xy 91.385644 -255.96088) (xy 91.383104 -255.966214)
			(xy 91.380564 -255.976882) (xy 91.380564 -255.986026) (xy 91.380812 -255.993207) (xy 91.384808 -256.007003)
			(xy 91.388438 -256.013204) (xy 91.425776 -256.072132) (xy 91.43111 -256.07899) (xy 91.437748 -256.085675)
			(xy 91.454553 -256.09415) (xy 91.463876 -256.0955) (xy 91.468702 -256.095754) (xy 91.671394 -256.095754)
			(xy 91.681266 -256.095282) (xy 91.69955 -256.087825) (xy 91.706954 -256.081276) (xy 91.707208 -256.081022)
			(xy 91.711526 -256.076704) (xy 91.718384 -256.068068) (xy 91.753436 -256.013458) (xy 91.757099 -256.007201)
			(xy 91.761101 -255.993273) (xy 91.76131 -255.986026) (xy 91.76131 -255.971294) (xy 91.75623 -255.96088)
			(xy 91.746494 -255.939477) (xy 91.732769 -255.894505) (xy 91.725884 -255.847993) (xy 91.725496 -255.824482)
			(xy 91.725982 -255.799692) (xy 91.733738 -255.750724) (xy 91.749059 -255.703571) (xy 91.771568 -255.659396)
			(xy 91.80071 -255.619285) (xy 91.835767 -255.584228) (xy 91.875878 -255.555086) (xy 91.920053 -255.532577)
			(xy 91.967206 -255.517256) (xy 92.016174 -255.5095) (xy 92.065754 -255.5095) (xy 92.114722 -255.517256)
			(xy 92.161875 -255.532577) (xy 92.20605 -255.555086) (xy 92.246161 -255.584228) (xy 92.281218 -255.619285)
			(xy 92.31036 -255.659396) (xy 92.332869 -255.703571) (xy 92.34819 -255.750724) (xy 92.355946 -255.799692)
			(xy 92.356432 -255.824482) (xy 92.356038 -255.848276) (xy 92.34897 -255.895336) (xy 92.334914 -255.9408)
			(xy 92.324936 -255.962404) (xy 92.319094 -255.974342) (xy 92.320364 -256.000504) (xy 92.36583 -256.072132)
			(xy 92.371164 -256.07899) (xy 92.377799 -256.085681) (xy 92.394603 -256.094171) (xy 92.40393 -256.0955)
			(xy 92.408756 -256.095754) (xy 92.612972 -256.095754) (xy 92.621522 -256.095433) (xy 92.637673 -256.089816)
			(xy 92.651077 -256.079198) (xy 92.655898 -256.072132) (xy 92.707714 -255.990852) (xy 92.709492 -255.965198)
			(xy 92.703904 -255.95326) (xy 92.695001 -255.933106) (xy 92.682446 -255.890874) (xy 92.676114 -255.847273)
			(xy 92.67571 -255.825244) (xy 92.67571 -255.824482) (xy 92.676232 -255.799227) (xy 92.684545 -255.749405)
			(xy 92.700946 -255.701631) (xy 92.724987 -255.657208) (xy 92.756011 -255.617348) (xy 92.793173 -255.583138)
			(xy 92.835459 -255.555512) (xy 92.881715 -255.535222) (xy 92.93068 -255.522822) (xy 92.981018 -255.518651)
			(xy 93.031356 -255.522822) (xy 93.080321 -255.535222) (xy 93.126577 -255.555512) (xy 93.168863 -255.583138)
			(xy 93.206025 -255.617348) (xy 93.237049 -255.657208) (xy 93.26109 -255.701631) (xy 93.277491 -255.749405)
			(xy 93.285804 -255.799227) (xy 93.286326 -255.824482) (xy 93.286326 -255.825244) (xy 93.28592 -255.847272)
			(xy 93.279561 -255.890867) (xy 93.267025 -255.933103) (xy 93.258132 -255.95326) (xy 93.252544 -255.965198)
			(xy 93.254322 -255.990852) (xy 93.306138 -256.072132) (xy 93.310964 -256.078736) (xy 93.317594 -256.085567)
			(xy 93.334557 -256.094176) (xy 93.343984 -256.0955) (xy 93.34881 -256.095754) (xy 93.551502 -256.095754)
			(xy 93.561381 -256.095298) (xy 93.579689 -256.087865) (xy 93.587062 -256.081276) (xy 93.587316 -256.081022)
			(xy 93.591634 -256.076704) (xy 93.598492 -256.068068) (xy 93.633544 -256.013458) (xy 93.637207 -256.007201)
			(xy 93.641208 -255.993273) (xy 93.641418 -255.986026) (xy 93.641418 -255.971294) (xy 93.636338 -255.96088)
			(xy 93.626602 -255.939477) (xy 93.612877 -255.894505) (xy 93.605991 -255.847993) (xy 93.605604 -255.824482)
			(xy 93.60609 -255.799692) (xy 93.613846 -255.750724) (xy 93.629167 -255.703571) (xy 93.651676 -255.659396)
			(xy 93.680818 -255.619285) (xy 93.715875 -255.584228) (xy 93.755986 -255.555086) (xy 93.800161 -255.532577)
			(xy 93.847314 -255.517256) (xy 93.896282 -255.5095) (xy 93.945862 -255.5095) (xy 93.99483 -255.517256)
			(xy 94.041983 -255.532577) (xy 94.086158 -255.555086) (xy 94.126269 -255.584228) (xy 94.161326 -255.619285)
			(xy 94.190468 -255.659396) (xy 94.212977 -255.703571) (xy 94.228298 -255.750724) (xy 94.236054 -255.799692)
			(xy 94.23654 -255.824482) (xy 94.236147 -255.848276) (xy 94.229078 -255.895336) (xy 94.215023 -255.9408)
			(xy 94.205044 -255.962404) (xy 94.199202 -255.974342) (xy 94.200472 -256.000504) (xy 94.245938 -256.072132)
			(xy 94.251272 -256.07899) (xy 94.257907 -256.08568) (xy 94.274712 -256.094167) (xy 94.284038 -256.0955)
			(xy 94.288864 -256.095754) (xy 94.49308 -256.095754) (xy 94.501629 -256.095432) (xy 94.517778 -256.089813)
			(xy 94.53118 -256.079195) (xy 94.536006 -256.072132) (xy 94.587822 -255.990852) (xy 94.5896 -255.965198)
			(xy 94.584012 -255.95326) (xy 94.575109 -255.933106) (xy 94.562554 -255.890874) (xy 94.556221 -255.847273)
			(xy 94.555818 -255.825244) (xy 94.555818 -255.824482) (xy 94.55634 -255.799227) (xy 94.564653 -255.749405)
			(xy 94.581054 -255.701631) (xy 94.605095 -255.657208) (xy 94.636119 -255.617348) (xy 94.673281 -255.583138)
			(xy 94.715567 -255.555512) (xy 94.761823 -255.535222) (xy 94.810788 -255.522822) (xy 94.861126 -255.518651)
			(xy 94.911464 -255.522822) (xy 94.960429 -255.535222) (xy 95.006685 -255.555512) (xy 95.048971 -255.583138)
			(xy 95.086133 -255.617348) (xy 95.117157 -255.657208) (xy 95.141198 -255.701631) (xy 95.157599 -255.749405)
			(xy 95.165912 -255.799227) (xy 95.166434 -255.824482) (xy 95.166434 -255.825244) (xy 95.166028 -255.847272)
			(xy 95.159669 -255.890868) (xy 95.147133 -255.933103) (xy 95.13824 -255.95326) (xy 95.132652 -255.965198)
			(xy 95.13443 -255.990852) (xy 95.186246 -256.072132) (xy 95.191072 -256.078736) (xy 95.197702 -256.085566)
			(xy 95.214666 -256.094172) (xy 95.224092 -256.0955) (xy 95.228918 -256.095754) (xy 95.431356 -256.095754)
			(xy 95.441231 -256.095288) (xy 95.459525 -256.087841) (xy 95.466916 -256.081276) (xy 95.46717 -256.081022)
			(xy 95.471488 -256.076704) (xy 95.4786 -256.068068) (xy 95.521526 -256.000504) (xy 95.522796 -255.974342)
			(xy 95.516954 -255.962404) (xy 95.50694 -255.940806) (xy 95.4928 -255.89535) (xy 95.48565 -255.848285)
			(xy 95.485204 -255.824482) (xy 95.485691 -255.799672) (xy 95.493453 -255.750664) (xy 95.508786 -255.703474)
			(xy 95.531313 -255.659263) (xy 95.560478 -255.61912) (xy 95.595564 -255.584034) (xy 95.635707 -255.554869)
			(xy 95.679918 -255.532342) (xy 95.727108 -255.517009) (xy 95.776116 -255.509247) (xy 95.825736 -255.509247)
			(xy 95.874744 -255.517009) (xy 95.921934 -255.532342) (xy 95.966145 -255.554869) (xy 96.006288 -255.584034)
			(xy 96.041374 -255.61912) (xy 96.070539 -255.659263) (xy 96.093066 -255.703474) (xy 96.108399 -255.750664)
			(xy 96.116161 -255.799672) (xy 96.116648 -255.824482) (xy 96.116216 -255.848001) (xy 96.109238 -255.894518)
			(xy 96.095435 -255.939484) (xy 96.08566 -255.96088) (xy 96.08312 -255.966214) (xy 96.08058 -255.976882)
			(xy 96.08058 -255.986026) (xy 96.080828 -255.993207) (xy 96.084825 -256.007002) (xy 96.088454 -256.013204)
			(xy 96.125792 -256.072132) (xy 96.131126 -256.07899) (xy 96.137764 -256.085673) (xy 96.154571 -256.094142)
			(xy 96.163892 -256.0955) (xy 96.168718 -256.095754) (xy 96.502474 -256.095754) (xy 96.506284 -256.099564)
			(xy 97.314766 -256.099564) (xy 97.323317 -256.099244) (xy 97.33947 -256.093629) (xy 97.352877 -256.083013)
			(xy 97.357692 -256.075942) (xy 97.39757 -256.012696) (xy 97.397824 -256.012188) (xy 97.401323 -256.006082)
			(xy 97.405182 -255.992552) (xy 97.405444 -255.985518) (xy 97.405444 -255.956562) (xy 97.401126 -255.946656)
			(xy 97.393037 -255.927313) (xy 97.381631 -255.886969) (xy 97.37584 -255.845444) (xy 97.375472 -255.824482)
			(xy 97.375994 -255.799206) (xy 97.384315 -255.749342) (xy 97.400729 -255.701529) (xy 97.424789 -255.657069)
			(xy 97.45584 -255.617176) (xy 97.493032 -255.582938) (xy 97.535353 -255.555288) (xy 97.581648 -255.534981)
			(xy 97.630654 -255.522571) (xy 97.681034 -255.518397) (xy 97.731414 -255.522571) (xy 97.78042 -255.534981)
			(xy 97.826715 -255.555288) (xy 97.869036 -255.582938) (xy 97.906228 -255.617176) (xy 97.937279 -255.657069)
			(xy 97.961339 -255.701529) (xy 97.977753 -255.749342) (xy 97.986074 -255.799206) (xy 97.986596 -255.824482)
			(xy 97.986234 -255.845446) (xy 97.980459 -255.886974) (xy 97.969042 -255.927317) (xy 97.960942 -255.946656)
			(xy 97.956624 -255.956562) (xy 97.956624 -255.986026) (xy 97.956873 -255.993207) (xy 97.960873 -256.007)
			(xy 97.964498 -256.013204) (xy 98.004376 -256.075942) (xy 98.005392 -256.07772) (xy 98.013053 -256.087435)
			(xy 98.034952 -256.098862) (xy 98.047302 -256.099564) (xy 99.194874 -256.099564) (xy 99.203424 -256.099243)
			(xy 99.219575 -256.093626) (xy 99.23298 -256.083009) (xy 99.2378 -256.075942) (xy 99.277678 -256.012696)
			(xy 99.277932 -256.012188) (xy 99.281431 -256.006081) (xy 99.285289 -255.992552) (xy 99.285552 -255.985518)
			(xy 99.285552 -255.956562) (xy 99.281234 -255.946656) (xy 99.273145 -255.927313) (xy 99.261738 -255.886969)
			(xy 99.255948 -255.845445) (xy 99.25558 -255.824482) (xy 99.256102 -255.799206) (xy 99.264423 -255.749342)
			(xy 99.280837 -255.701529) (xy 99.304897 -255.657069) (xy 99.335948 -255.617176) (xy 99.37314 -255.582938)
			(xy 99.415461 -255.555288) (xy 99.461756 -255.534981) (xy 99.510762 -255.522571) (xy 99.561142 -255.518397)
			(xy 99.611522 -255.522571) (xy 99.660528 -255.534981) (xy 99.706823 -255.555288) (xy 99.749144 -255.582938)
			(xy 99.786336 -255.617176) (xy 99.817387 -255.657069) (xy 99.841447 -255.701529) (xy 99.857861 -255.749342)
			(xy 99.866182 -255.799206) (xy 99.866704 -255.824482) (xy 100.195138 -255.824482) (xy 100.199098 -255.775428)
			(xy 100.210875 -255.727644) (xy 100.230166 -255.682368) (xy 100.256469 -255.640772) (xy 100.289104 -255.603935)
			(xy 100.327225 -255.57281) (xy 100.369846 -255.548203) (xy 100.415862 -255.530751) (xy 100.464081 -255.520907)
			(xy 100.513256 -255.518926) (xy 100.562111 -255.524858) (xy 100.609382 -255.53855) (xy 100.653844 -255.559648)
			(xy 100.694347 -255.587604) (xy 100.72984 -255.621696) (xy 100.759405 -255.66104) (xy 100.782276 -255.704617)
			(xy 100.79786 -255.751298) (xy 100.805755 -255.799875) (xy 100.80625 -255.824482) (xy 101.135192 -255.824482)
			(xy 101.139152 -255.775428) (xy 101.150929 -255.727644) (xy 101.17022 -255.682368) (xy 101.196523 -255.640772)
			(xy 101.229158 -255.603935) (xy 101.267279 -255.57281) (xy 101.3099 -255.548203) (xy 101.355916 -255.530751)
			(xy 101.404135 -255.520907) (xy 101.45331 -255.518926) (xy 101.502165 -255.524858) (xy 101.549436 -255.53855)
			(xy 101.593898 -255.559648) (xy 101.634401 -255.587604) (xy 101.669894 -255.621696) (xy 101.699459 -255.66104)
			(xy 101.72233 -255.704617) (xy 101.737914 -255.751298) (xy 101.745809 -255.799875) (xy 101.746304 -255.824482)
			(xy 102.075246 -255.824482) (xy 102.079206 -255.775428) (xy 102.090983 -255.727644) (xy 102.110274 -255.682368)
			(xy 102.136577 -255.640772) (xy 102.169212 -255.603935) (xy 102.207333 -255.57281) (xy 102.249954 -255.548203)
			(xy 102.29597 -255.530751) (xy 102.344189 -255.520907) (xy 102.393364 -255.518926) (xy 102.442219 -255.524858)
			(xy 102.48949 -255.53855) (xy 102.533952 -255.559648) (xy 102.574455 -255.587604) (xy 102.609948 -255.621696)
			(xy 102.639513 -255.66104) (xy 102.662384 -255.704617) (xy 102.677968 -255.751298) (xy 102.685863 -255.799875)
			(xy 102.686317 -255.82245) (xy 103.011998 -255.82245) (xy 103.015958 -255.773396) (xy 103.027735 -255.725612)
			(xy 103.047026 -255.680336) (xy 103.073329 -255.63874) (xy 103.105964 -255.601903) (xy 103.144085 -255.570778)
			(xy 103.186706 -255.546171) (xy 103.232722 -255.528719) (xy 103.280941 -255.518875) (xy 103.330116 -255.516894)
			(xy 103.378971 -255.522826) (xy 103.426242 -255.536518) (xy 103.470704 -255.557616) (xy 103.511207 -255.585572)
			(xy 103.5467 -255.619664) (xy 103.576265 -255.659008) (xy 103.599136 -255.702585) (xy 103.61472 -255.749266)
			(xy 103.622615 -255.797843) (xy 103.62311 -255.82245) (xy 103.952052 -255.82245) (xy 103.956012 -255.773396)
			(xy 103.967789 -255.725612) (xy 103.98708 -255.680336) (xy 104.013383 -255.63874) (xy 104.046018 -255.601903)
			(xy 104.084139 -255.570778) (xy 104.12676 -255.546171) (xy 104.172776 -255.528719) (xy 104.220995 -255.518875)
			(xy 104.27017 -255.516894) (xy 104.319025 -255.522826) (xy 104.345001 -255.53035) (xy 106.061259 -255.53035)
			(xy 106.065289 -255.477852) (xy 106.077286 -255.426584) (xy 106.096969 -255.377749) (xy 106.123875 -255.33249)
			(xy 106.157375 -255.291869) (xy 106.196683 -255.256838) (xy 106.240878 -255.228218) (xy 106.288923 -255.206679)
			(xy 106.339694 -255.192727) (xy 106.391999 -255.186689) (xy 106.444613 -255.188706) (xy 106.496303 -255.19873)
			(xy 106.545856 -255.216528) (xy 106.592112 -255.241681) (xy 106.633986 -255.2736) (xy 106.670498 -255.311538)
			(xy 106.70079 -255.354604) (xy 106.724153 -255.401789) (xy 106.740039 -255.451988) (xy 106.748076 -255.504024)
			(xy 106.74858 -255.53035) (xy 106.748076 -255.556676) (xy 106.740039 -255.608712) (xy 106.724153 -255.658911)
			(xy 106.70079 -255.706096) (xy 106.670498 -255.749162) (xy 106.633986 -255.7871) (xy 106.592112 -255.819019)
			(xy 106.545856 -255.844172) (xy 106.496303 -255.86197) (xy 106.444613 -255.871994) (xy 106.391999 -255.874011)
			(xy 106.339694 -255.867973) (xy 106.288923 -255.854021) (xy 106.240878 -255.832482) (xy 106.196683 -255.803862)
			(xy 106.157375 -255.768831) (xy 106.123875 -255.72821) (xy 106.096969 -255.682951) (xy 106.077286 -255.634116)
			(xy 106.065289 -255.582848) (xy 106.061259 -255.53035) (xy 104.345001 -255.53035) (xy 104.366296 -255.536518)
			(xy 104.410758 -255.557616) (xy 104.451261 -255.585572) (xy 104.486754 -255.619664) (xy 104.516319 -255.659008)
			(xy 104.53919 -255.702585) (xy 104.554774 -255.749266) (xy 104.562669 -255.797843) (xy 104.563164 -255.82245)
			(xy 104.562669 -255.847057) (xy 104.554774 -255.895634) (xy 104.53919 -255.942315) (xy 104.516319 -255.985892)
			(xy 104.486754 -256.025236) (xy 104.451261 -256.059328) (xy 104.410758 -256.087284) (xy 104.366296 -256.108382)
			(xy 104.319025 -256.122074) (xy 104.27017 -256.128006) (xy 104.220995 -256.126025) (xy 104.172776 -256.116181)
			(xy 104.12676 -256.098729) (xy 104.084139 -256.074122) (xy 104.046018 -256.042997) (xy 104.013383 -256.00616)
			(xy 103.98708 -255.964564) (xy 103.967789 -255.919288) (xy 103.956012 -255.871504) (xy 103.952052 -255.82245)
			(xy 103.62311 -255.82245) (xy 103.622615 -255.847057) (xy 103.61472 -255.895634) (xy 103.599136 -255.942315)
			(xy 103.576265 -255.985892) (xy 103.5467 -256.025236) (xy 103.511207 -256.059328) (xy 103.470704 -256.087284)
			(xy 103.426242 -256.108382) (xy 103.378971 -256.122074) (xy 103.330116 -256.128006) (xy 103.280941 -256.126025)
			(xy 103.232722 -256.116181) (xy 103.186706 -256.098729) (xy 103.144085 -256.074122) (xy 103.105964 -256.042997)
			(xy 103.073329 -256.00616) (xy 103.047026 -255.964564) (xy 103.027735 -255.919288) (xy 103.015958 -255.871504)
			(xy 103.011998 -255.82245) (xy 102.686317 -255.82245) (xy 102.686358 -255.824482) (xy 102.685863 -255.849089)
			(xy 102.677968 -255.897666) (xy 102.662384 -255.944347) (xy 102.639513 -255.987924) (xy 102.609948 -256.027268)
			(xy 102.574455 -256.06136) (xy 102.533952 -256.089316) (xy 102.48949 -256.110414) (xy 102.442219 -256.124106)
			(xy 102.393364 -256.130038) (xy 102.344189 -256.128057) (xy 102.29597 -256.118213) (xy 102.249954 -256.100761)
			(xy 102.207333 -256.076154) (xy 102.169212 -256.045029) (xy 102.136577 -256.008192) (xy 102.110274 -255.966596)
			(xy 102.090983 -255.92132) (xy 102.079206 -255.873536) (xy 102.075246 -255.824482) (xy 101.746304 -255.824482)
			(xy 101.745809 -255.849089) (xy 101.737914 -255.897666) (xy 101.72233 -255.944347) (xy 101.699459 -255.987924)
			(xy 101.669894 -256.027268) (xy 101.634401 -256.06136) (xy 101.593898 -256.089316) (xy 101.549436 -256.110414)
			(xy 101.502165 -256.124106) (xy 101.45331 -256.130038) (xy 101.404135 -256.128057) (xy 101.355916 -256.118213)
			(xy 101.3099 -256.100761) (xy 101.267279 -256.076154) (xy 101.229158 -256.045029) (xy 101.196523 -256.008192)
			(xy 101.17022 -255.966596) (xy 101.150929 -255.92132) (xy 101.139152 -255.873536) (xy 101.135192 -255.824482)
			(xy 100.80625 -255.824482) (xy 100.805755 -255.849089) (xy 100.79786 -255.897666) (xy 100.782276 -255.944347)
			(xy 100.759405 -255.987924) (xy 100.72984 -256.027268) (xy 100.694347 -256.06136) (xy 100.653844 -256.089316)
			(xy 100.609382 -256.110414) (xy 100.562111 -256.124106) (xy 100.513256 -256.130038) (xy 100.464081 -256.128057)
			(xy 100.415862 -256.118213) (xy 100.369846 -256.100761) (xy 100.327225 -256.076154) (xy 100.289104 -256.045029)
			(xy 100.256469 -256.008192) (xy 100.230166 -255.966596) (xy 100.210875 -255.92132) (xy 100.199098 -255.873536)
			(xy 100.195138 -255.824482) (xy 99.866704 -255.824482) (xy 99.866342 -255.845446) (xy 99.860567 -255.886974)
			(xy 99.84915 -255.927317) (xy 99.84105 -255.946656) (xy 99.836732 -255.956562) (xy 99.836732 -255.986026)
			(xy 99.836981 -255.993207) (xy 99.840982 -256.007) (xy 99.844606 -256.013204) (xy 99.884484 -256.075942)
			(xy 99.8855 -256.07772) (xy 99.893161 -256.087433) (xy 99.91506 -256.098857) (xy 99.92741 -256.099564)
			(xy 100.045012 -256.099564) (xy 100.054855 -256.100089) (xy 100.073034 -256.107657) (xy 100.080318 -256.114296)
			(xy 100.522786 -256.556764) (xy 100.532235 -256.565206) (xy 100.556493 -256.572419) (xy 100.569014 -256.57048)
			(xy 100.649786 -256.553462) (xy 100.660891 -256.550483) (xy 100.679105 -256.536503) (xy 100.684838 -256.526538)
			(xy 100.686362 -256.52349) (xy 100.687124 -256.521458) (xy 100.697271 -256.497489) (xy 100.724494 -256.453129)
			(xy 100.758831 -256.414016) (xy 100.799293 -256.381279) (xy 100.844712 -256.355863) (xy 100.893777 -256.338499)
			(xy 100.945073 -256.32969) (xy 100.971096 -256.32918) (xy 100.997052 -256.3297) (xy 101.048217 -256.338477)
			(xy 101.097162 -256.35578) (xy 101.142475 -256.381109) (xy 101.182854 -256.413735) (xy 101.217134 -256.45272)
			(xy 101.244328 -256.496939) (xy 101.263654 -256.545121) (xy 101.274555 -256.595876) (xy 101.27615 -256.621788)
			(xy 101.276404 -256.627884) (xy 101.276404 -256.634488) (xy 101.275997 -256.65766) (xy 101.269033 -256.703476)
			(xy 101.255218 -256.747711) (xy 101.234871 -256.789347) (xy 101.208459 -256.827426) (xy 101.192838 -256.844546)
			(xy 101.187504 -256.84988) (xy 101.183948 -256.857246) (xy 101.179442 -256.867451) (xy 101.17877 -256.889724)
			(xy 101.182678 -256.900172) (xy 101.218492 -256.98323) (xy 101.22027 -256.986786) (xy 101.224918 -256.994771)
			(xy 101.238739 -257.007012) (xy 101.255997 -257.01357) (xy 101.265228 -257.013964) (xy 101.617018 -257.013964)
			(xy 101.626247 -257.013562) (xy 101.643505 -257.00701) (xy 101.657317 -256.994765) (xy 101.661976 -256.986786)
			(xy 101.662992 -256.985008) (xy 101.699568 -256.900172) (xy 101.703437 -256.889717) (xy 101.70277 -256.867459)
			(xy 101.698298 -256.857246) (xy 101.694742 -256.84988) (xy 101.689408 -256.844546) (xy 101.6738 -256.827418)
			(xy 101.647409 -256.789331) (xy 101.627072 -256.747695) (xy 101.613255 -256.703465) (xy 101.606275 -256.657657)
			(xy 101.605842 -256.634488) (xy 101.605842 -256.627884) (xy 101.606096 -256.621788) (xy 101.607612 -256.597243)
			(xy 101.617505 -256.549076) (xy 101.63499 -256.503117) (xy 101.659616 -256.460554) (xy 101.690744 -256.422488)
			(xy 101.727571 -256.389904) (xy 101.769145 -256.363643) (xy 101.81439 -256.344384) (xy 101.862136 -256.332627)
			(xy 101.91115 -256.328673) (xy 101.960164 -256.332627) (xy 102.00791 -256.344384) (xy 102.053155 -256.363643)
			(xy 102.094729 -256.389904) (xy 102.131556 -256.422488) (xy 102.162684 -256.460554) (xy 102.18731 -256.503117)
			(xy 102.204795 -256.549076) (xy 102.214688 -256.597243) (xy 102.216204 -256.621788) (xy 102.216458 -256.627884)
			(xy 102.216458 -256.634488) (xy 102.216051 -256.65766) (xy 102.209088 -256.703477) (xy 102.195275 -256.747714)
			(xy 102.17493 -256.789352) (xy 102.148522 -256.827434) (xy 102.132892 -256.844546) (xy 102.127558 -256.84988)
			(xy 102.124002 -256.857246) (xy 102.119492 -256.867451) (xy 102.11882 -256.889725) (xy 102.122732 -256.900172)
			(xy 102.158546 -256.98323) (xy 102.160324 -256.986786) (xy 102.164975 -256.994765) (xy 102.178798 -257.006991)
			(xy 102.196055 -257.013531) (xy 102.205282 -257.013964) (xy 102.557326 -257.013964) (xy 102.566222 -257.013636)
			(xy 102.582943 -257.007561) (xy 102.596569 -256.996123) (xy 102.601268 -256.988564) (xy 102.604062 -256.983992)
			(xy 102.64013 -256.899664) (xy 102.643618 -256.890366) (xy 102.643952 -256.870529) (xy 102.636729 -256.852051)
			(xy 102.630224 -256.844546) (xy 102.62997 -256.844292) (xy 102.614141 -256.827123) (xy 102.587352 -256.788877)
			(xy 102.566697 -256.746998) (xy 102.552655 -256.702464) (xy 102.545554 -256.656312) (xy 102.545134 -256.632964)
			(xy 102.545656 -256.607709) (xy 102.553969 -256.557887) (xy 102.57037 -256.510113) (xy 102.594411 -256.46569)
			(xy 102.625435 -256.42583) (xy 102.662597 -256.39162) (xy 102.704883 -256.363994) (xy 102.751139 -256.343704)
			(xy 102.800104 -256.331304) (xy 102.850442 -256.327133) (xy 102.90078 -256.331304) (xy 102.949745 -256.343704)
			(xy 102.996001 -256.363994) (xy 103.038287 -256.39162) (xy 103.075449 -256.42583) (xy 103.106473 -256.46569)
			(xy 103.114385 -256.48031) (xy 106.061259 -256.48031) (xy 106.065289 -256.427812) (xy 106.077286 -256.376544)
			(xy 106.096969 -256.327709) (xy 106.123875 -256.28245) (xy 106.157375 -256.241829) (xy 106.196683 -256.206798)
			(xy 106.240878 -256.178178) (xy 106.288923 -256.156639) (xy 106.339694 -256.142687) (xy 106.391999 -256.136649)
			(xy 106.444613 -256.138666) (xy 106.496303 -256.14869) (xy 106.545856 -256.166488) (xy 106.592112 -256.191641)
			(xy 106.633986 -256.22356) (xy 106.670498 -256.261498) (xy 106.70079 -256.304564) (xy 106.724153 -256.351749)
			(xy 106.735498 -256.3876) (xy 107.304081 -256.3876) (xy 107.308111 -256.335102) (xy 107.320108 -256.283834)
			(xy 107.339791 -256.234999) (xy 107.366697 -256.18974) (xy 107.400197 -256.149119) (xy 107.439505 -256.114088)
			(xy 107.4837 -256.085468) (xy 107.531745 -256.063929) (xy 107.582516 -256.049977) (xy 107.634821 -256.043939)
			(xy 107.687435 -256.045956) (xy 107.739125 -256.05598) (xy 107.788678 -256.073778) (xy 107.834934 -256.098931)
			(xy 107.876808 -256.13085) (xy 107.91332 -256.168788) (xy 107.943612 -256.211854) (xy 107.966975 -256.259039)
			(xy 107.982861 -256.309238) (xy 107.990898 -256.361274) (xy 107.991402 -256.3876) (xy 108.254041 -256.3876)
			(xy 108.258071 -256.335102) (xy 108.270068 -256.283834) (xy 108.289751 -256.234999) (xy 108.316657 -256.18974)
			(xy 108.350157 -256.149119) (xy 108.389465 -256.114088) (xy 108.43366 -256.085468) (xy 108.481705 -256.063929)
			(xy 108.532476 -256.049977) (xy 108.584781 -256.043939) (xy 108.637395 -256.045956) (xy 108.689085 -256.05598)
			(xy 108.738638 -256.073778) (xy 108.784894 -256.098931) (xy 108.826768 -256.13085) (xy 108.86328 -256.168788)
			(xy 108.893572 -256.211854) (xy 108.916935 -256.259039) (xy 108.932821 -256.309238) (xy 108.940858 -256.361274)
			(xy 108.941362 -256.3876) (xy 109.204001 -256.3876) (xy 109.208031 -256.335102) (xy 109.220028 -256.283834)
			(xy 109.239711 -256.234999) (xy 109.266617 -256.18974) (xy 109.300117 -256.149119) (xy 109.339425 -256.114088)
			(xy 109.38362 -256.085468) (xy 109.431665 -256.063929) (xy 109.482436 -256.049977) (xy 109.534741 -256.043939)
			(xy 109.587355 -256.045956) (xy 109.639045 -256.05598) (xy 109.688598 -256.073778) (xy 109.734854 -256.098931)
			(xy 109.776728 -256.13085) (xy 109.81324 -256.168788) (xy 109.843532 -256.211854) (xy 109.866895 -256.259039)
			(xy 109.882781 -256.309238) (xy 109.890818 -256.361274) (xy 109.891322 -256.3876) (xy 110.153961 -256.3876)
			(xy 110.157991 -256.335102) (xy 110.169988 -256.283834) (xy 110.189671 -256.234999) (xy 110.216577 -256.18974)
			(xy 110.250077 -256.149119) (xy 110.289385 -256.114088) (xy 110.33358 -256.085468) (xy 110.381625 -256.063929)
			(xy 110.432396 -256.049977) (xy 110.484701 -256.043939) (xy 110.537315 -256.045956) (xy 110.589005 -256.05598)
			(xy 110.638558 -256.073778) (xy 110.684814 -256.098931) (xy 110.726688 -256.13085) (xy 110.7632 -256.168788)
			(xy 110.793492 -256.211854) (xy 110.816855 -256.259039) (xy 110.832741 -256.309238) (xy 110.840778 -256.361274)
			(xy 110.841282 -256.3876) (xy 111.103921 -256.3876) (xy 111.107951 -256.335102) (xy 111.119948 -256.283834)
			(xy 111.139631 -256.234999) (xy 111.166537 -256.18974) (xy 111.200037 -256.149119) (xy 111.239345 -256.114088)
			(xy 111.28354 -256.085468) (xy 111.331585 -256.063929) (xy 111.382356 -256.049977) (xy 111.434661 -256.043939)
			(xy 111.487275 -256.045956) (xy 111.538965 -256.05598) (xy 111.588518 -256.073778) (xy 111.634774 -256.098931)
			(xy 111.676648 -256.13085) (xy 111.71316 -256.168788) (xy 111.743452 -256.211854) (xy 111.766815 -256.259039)
			(xy 111.782701 -256.309238) (xy 111.790738 -256.361274) (xy 111.791242 -256.3876) (xy 111.790738 -256.413926)
			(xy 111.782701 -256.465962) (xy 111.766815 -256.516161) (xy 111.743452 -256.563346) (xy 111.71316 -256.606412)
			(xy 111.676648 -256.64435) (xy 111.634774 -256.676269) (xy 111.588518 -256.701422) (xy 111.538965 -256.71922)
			(xy 111.487275 -256.729244) (xy 111.434661 -256.731261) (xy 111.382356 -256.725223) (xy 111.331585 -256.711271)
			(xy 111.28354 -256.689732) (xy 111.239345 -256.661112) (xy 111.200037 -256.626081) (xy 111.166537 -256.58546)
			(xy 111.139631 -256.540201) (xy 111.119948 -256.491366) (xy 111.107951 -256.440098) (xy 111.103921 -256.3876)
			(xy 110.841282 -256.3876) (xy 110.840778 -256.413926) (xy 110.832741 -256.465962) (xy 110.816855 -256.516161)
			(xy 110.793492 -256.563346) (xy 110.7632 -256.606412) (xy 110.726688 -256.64435) (xy 110.684814 -256.676269)
			(xy 110.638558 -256.701422) (xy 110.589005 -256.71922) (xy 110.537315 -256.729244) (xy 110.484701 -256.731261)
			(xy 110.432396 -256.725223) (xy 110.381625 -256.711271) (xy 110.33358 -256.689732) (xy 110.289385 -256.661112)
			(xy 110.250077 -256.626081) (xy 110.216577 -256.58546) (xy 110.189671 -256.540201) (xy 110.169988 -256.491366)
			(xy 110.157991 -256.440098) (xy 110.153961 -256.3876) (xy 109.891322 -256.3876) (xy 109.890818 -256.413926)
			(xy 109.882781 -256.465962) (xy 109.866895 -256.516161) (xy 109.843532 -256.563346) (xy 109.81324 -256.606412)
			(xy 109.776728 -256.64435) (xy 109.734854 -256.676269) (xy 109.688598 -256.701422) (xy 109.639045 -256.71922)
			(xy 109.587355 -256.729244) (xy 109.534741 -256.731261) (xy 109.482436 -256.725223) (xy 109.431665 -256.711271)
			(xy 109.38362 -256.689732) (xy 109.339425 -256.661112) (xy 109.300117 -256.626081) (xy 109.266617 -256.58546)
			(xy 109.239711 -256.540201) (xy 109.220028 -256.491366) (xy 109.208031 -256.440098) (xy 109.204001 -256.3876)
			(xy 108.941362 -256.3876) (xy 108.940858 -256.413926) (xy 108.932821 -256.465962) (xy 108.916935 -256.516161)
			(xy 108.893572 -256.563346) (xy 108.86328 -256.606412) (xy 108.826768 -256.64435) (xy 108.784894 -256.676269)
			(xy 108.738638 -256.701422) (xy 108.689085 -256.71922) (xy 108.637395 -256.729244) (xy 108.584781 -256.731261)
			(xy 108.532476 -256.725223) (xy 108.481705 -256.711271) (xy 108.43366 -256.689732) (xy 108.389465 -256.661112)
			(xy 108.350157 -256.626081) (xy 108.316657 -256.58546) (xy 108.289751 -256.540201) (xy 108.270068 -256.491366)
			(xy 108.258071 -256.440098) (xy 108.254041 -256.3876) (xy 107.991402 -256.3876) (xy 107.990898 -256.413926)
			(xy 107.982861 -256.465962) (xy 107.966975 -256.516161) (xy 107.943612 -256.563346) (xy 107.91332 -256.606412)
			(xy 107.876808 -256.64435) (xy 107.834934 -256.676269) (xy 107.788678 -256.701422) (xy 107.739125 -256.71922)
			(xy 107.687435 -256.729244) (xy 107.634821 -256.731261) (xy 107.582516 -256.725223) (xy 107.531745 -256.711271)
			(xy 107.4837 -256.689732) (xy 107.439505 -256.661112) (xy 107.400197 -256.626081) (xy 107.366697 -256.58546)
			(xy 107.339791 -256.540201) (xy 107.320108 -256.491366) (xy 107.308111 -256.440098) (xy 107.304081 -256.3876)
			(xy 106.735498 -256.3876) (xy 106.740039 -256.401948) (xy 106.748076 -256.453984) (xy 106.74858 -256.48031)
			(xy 106.748076 -256.506636) (xy 106.740039 -256.558672) (xy 106.724153 -256.608871) (xy 106.70079 -256.656056)
			(xy 106.670498 -256.699122) (xy 106.633986 -256.73706) (xy 106.592112 -256.768979) (xy 106.545856 -256.794132)
			(xy 106.496303 -256.81193) (xy 106.444613 -256.821954) (xy 106.391999 -256.823971) (xy 106.339694 -256.817933)
			(xy 106.288923 -256.803981) (xy 106.240878 -256.782442) (xy 106.196683 -256.753822) (xy 106.157375 -256.718791)
			(xy 106.123875 -256.67817) (xy 106.096969 -256.632911) (xy 106.077286 -256.584076) (xy 106.065289 -256.532808)
			(xy 106.061259 -256.48031) (xy 103.114385 -256.48031) (xy 103.130514 -256.510113) (xy 103.146915 -256.557887)
			(xy 103.155228 -256.607709) (xy 103.15575 -256.632964) (xy 103.155303 -256.656309) (xy 103.148193 -256.702453)
			(xy 103.134147 -256.74698) (xy 103.113493 -256.788853) (xy 103.086711 -256.827097) (xy 103.070914 -256.844292)
			(xy 103.059992 -256.855468) (xy 103.054658 -256.885186) (xy 103.096314 -256.982976) (xy 103.09733 -256.985262)
			(xy 103.101832 -256.99366) (xy 103.115804 -257.006596) (xy 103.13353 -257.013552) (xy 103.14305 -257.013964)
			(xy 105.912412 -257.013964) (xy 105.922255 -257.014489) (xy 105.940434 -257.022057) (xy 105.947718 -257.028696)
			(xy 106.095546 -257.176524) (xy 106.096308 -257.177286) (xy 106.101917 -257.182328) (xy 106.115347 -257.189176)
			(xy 106.122724 -257.190748) (xy 106.139488 -257.193796) (xy 106.162094 -257.187192) (xy 106.170984 -257.17881)
			(xy 106.190191 -257.161612) (xy 106.232758 -257.13253) (xy 106.279182 -257.110113) (xy 106.328428 -257.094862)
			(xy 106.379396 -257.087119) (xy 106.405172 -257.086608) (xy 106.430895 -257.087063) (xy 106.481768 -257.094727)
			(xy 106.53093 -257.109888) (xy 106.577283 -257.132207) (xy 106.619791 -257.161186) (xy 106.657506 -257.196176)
			(xy 106.689583 -257.236398) (xy 106.715308 -257.280951) (xy 106.734104 -257.328841) (xy 106.745553 -257.378997)
			(xy 106.749398 -257.4303) (xy 106.745553 -257.481603) (xy 106.734104 -257.531759) (xy 106.715308 -257.579649)
			(xy 106.689583 -257.624202) (xy 106.657506 -257.664424) (xy 106.619791 -257.699414) (xy 106.577283 -257.728393)
			(xy 106.542315 -257.74523) (xy 108.488229 -257.74523) (xy 108.492259 -257.692732) (xy 108.504256 -257.641464)
			(xy 108.523939 -257.592629) (xy 108.550845 -257.54737) (xy 108.584345 -257.506749) (xy 108.623653 -257.471718)
			(xy 108.667848 -257.443098) (xy 108.715893 -257.421559) (xy 108.766664 -257.407607) (xy 108.818969 -257.401569)
			(xy 108.871583 -257.403586) (xy 108.923273 -257.41361) (xy 108.972826 -257.431408) (xy 109.019082 -257.456561)
			(xy 109.060956 -257.48848) (xy 109.097468 -257.526418) (xy 109.12776 -257.569484) (xy 109.151123 -257.616669)
			(xy 109.167009 -257.666868) (xy 109.175046 -257.718904) (xy 109.17555 -257.74523) (xy 110.073951 -257.74523)
			(xy 110.077981 -257.692732) (xy 110.089978 -257.641464) (xy 110.109661 -257.592629) (xy 110.136567 -257.54737)
			(xy 110.170067 -257.506749) (xy 110.209375 -257.471718) (xy 110.25357 -257.443098) (xy 110.301615 -257.421559)
			(xy 110.352386 -257.407607) (xy 110.404691 -257.401569) (xy 110.457305 -257.403586) (xy 110.508995 -257.41361)
			(xy 110.558548 -257.431408) (xy 110.604804 -257.456561) (xy 110.646678 -257.48848) (xy 110.68319 -257.526418)
			(xy 110.713482 -257.569484) (xy 110.736845 -257.616669) (xy 110.752731 -257.666868) (xy 110.760768 -257.718904)
			(xy 110.761272 -257.74523) (xy 110.988351 -257.74523) (xy 110.992381 -257.692732) (xy 111.004378 -257.641464)
			(xy 111.024061 -257.592629) (xy 111.050967 -257.54737) (xy 111.084467 -257.506749) (xy 111.123775 -257.471718)
			(xy 111.16797 -257.443098) (xy 111.216015 -257.421559) (xy 111.266786 -257.407607) (xy 111.319091 -257.401569)
			(xy 111.371705 -257.403586) (xy 111.423395 -257.41361) (xy 111.472948 -257.431408) (xy 111.519204 -257.456561)
			(xy 111.561078 -257.48848) (xy 111.59759 -257.526418) (xy 111.627882 -257.569484) (xy 111.651245 -257.616669)
			(xy 111.667131 -257.666868) (xy 111.675168 -257.718904) (xy 111.675672 -257.74523) (xy 111.675168 -257.771556)
			(xy 111.667131 -257.823592) (xy 111.651245 -257.873791) (xy 111.627882 -257.920976) (xy 111.59759 -257.964042)
			(xy 111.561078 -258.00198) (xy 111.519204 -258.033899) (xy 111.472948 -258.059052) (xy 111.423395 -258.07685)
			(xy 111.371705 -258.086874) (xy 111.319091 -258.088891) (xy 111.266786 -258.082853) (xy 111.216015 -258.068901)
			(xy 111.16797 -258.047362) (xy 111.123775 -258.018742) (xy 111.084467 -257.983711) (xy 111.050967 -257.94309)
			(xy 111.024061 -257.897831) (xy 111.004378 -257.848996) (xy 110.992381 -257.797728) (xy 110.988351 -257.74523)
			(xy 110.761272 -257.74523) (xy 110.760768 -257.771556) (xy 110.752731 -257.823592) (xy 110.736845 -257.873791)
			(xy 110.713482 -257.920976) (xy 110.68319 -257.964042) (xy 110.646678 -258.00198) (xy 110.604804 -258.033899)
			(xy 110.558548 -258.059052) (xy 110.508995 -258.07685) (xy 110.457305 -258.086874) (xy 110.404691 -258.088891)
			(xy 110.352386 -258.082853) (xy 110.301615 -258.068901) (xy 110.25357 -258.047362) (xy 110.209375 -258.018742)
			(xy 110.170067 -257.983711) (xy 110.136567 -257.94309) (xy 110.109661 -257.897831) (xy 110.089978 -257.848996)
			(xy 110.077981 -257.797728) (xy 110.073951 -257.74523) (xy 109.17555 -257.74523) (xy 109.175046 -257.771556)
			(xy 109.167009 -257.823592) (xy 109.151123 -257.873791) (xy 109.12776 -257.920976) (xy 109.097468 -257.964042)
			(xy 109.060956 -258.00198) (xy 109.019082 -258.033899) (xy 108.972826 -258.059052) (xy 108.923273 -258.07685)
			(xy 108.871583 -258.086874) (xy 108.818969 -258.088891) (xy 108.766664 -258.082853) (xy 108.715893 -258.068901)
			(xy 108.667848 -258.047362) (xy 108.623653 -258.018742) (xy 108.584345 -257.983711) (xy 108.550845 -257.94309)
			(xy 108.523939 -257.897831) (xy 108.504256 -257.848996) (xy 108.492259 -257.797728) (xy 108.488229 -257.74523)
			(xy 106.542315 -257.74523) (xy 106.53093 -257.750712) (xy 106.481768 -257.765873) (xy 106.430895 -257.773537)
			(xy 106.405172 -257.773932) (xy 106.404156 -257.773932) (xy 106.382845 -257.773564) (xy 106.340558 -257.76822)
			(xy 106.319828 -257.763264) (xy 106.319574 -257.763264) (xy 106.3117 -257.761486) (xy 106.300565 -257.759427)
			(xy 106.278428 -257.764057) (xy 106.269028 -257.770376) (xy 106.207052 -257.81762) (xy 106.1974 -257.824986)
			(xy 106.186986 -257.846068) (xy 106.186986 -257.881882) (xy 106.187457 -257.891754) (xy 106.194915 -257.910038)
			(xy 106.201464 -257.917442) (xy 106.201718 -257.917696) (xy 106.309668 -258.025646) (xy 106.317067 -258.032488)
			(xy 106.335666 -258.040206) (xy 106.345736 -258.040632) (xy 106.354118 -258.040632) (xy 106.366176 -258.038929)
			(xy 106.390456 -258.037024) (xy 106.402632 -258.036822) (xy 106.403902 -258.036822) (xy 106.405172 -258.036822)
			(xy 106.432173 -258.037323) (xy 106.485509 -258.045771) (xy 106.536866 -258.062464) (xy 106.584977 -258.086989)
			(xy 106.628656 -258.118743) (xy 106.666826 -258.156942) (xy 106.698547 -258.200645) (xy 106.723036 -258.248774)
			(xy 106.731816 -258.274312) (xy 106.736896 -258.29006) (xy 106.763566 -258.309364) (xy 108.071412 -258.309364)
			(xy 108.081255 -258.309889) (xy 108.099434 -258.317457) (xy 108.106718 -258.324096) (xy 108.407454 -258.624832)
			(xy 108.41209 -258.629741) (xy 108.418788 -258.641459) (xy 108.420662 -258.647946) (xy 108.42498 -258.665218)
			(xy 108.452158 -258.6863) (xy 108.471716 -258.6863) (xy 108.481427 -258.685867) (xy 108.499455 -258.678641)
			(xy 108.513504 -258.66523) (xy 108.517944 -258.656582) (xy 108.518198 -258.656074) (xy 108.518198 -258.65582)
			(xy 108.52866 -258.633381) (xy 108.555076 -258.591507) (xy 108.587226 -258.553857) (xy 108.624446 -258.52121)
			(xy 108.665964 -258.494241) (xy 108.710923 -258.473507) (xy 108.758392 -258.459439) (xy 108.807387 -258.452327)
			(xy 108.832142 -258.451858) (xy 108.857841 -258.452341) (xy 108.908665 -258.460007) (xy 108.957779 -258.475162)
			(xy 109.004086 -258.497468) (xy 109.046552 -258.526425) (xy 109.084227 -258.561387) (xy 109.116272 -258.601574)
			(xy 109.14197 -258.646088) (xy 109.160746 -258.693934) (xy 109.172183 -258.744045) (xy 109.176021 -258.795266)
			(xy 110.073951 -258.795266) (xy 110.077981 -258.742768) (xy 110.089978 -258.6915) (xy 110.109661 -258.642665)
			(xy 110.136567 -258.597406) (xy 110.170067 -258.556785) (xy 110.209375 -258.521754) (xy 110.25357 -258.493134)
			(xy 110.301615 -258.471595) (xy 110.352386 -258.457643) (xy 110.404691 -258.451605) (xy 110.457305 -258.453622)
			(xy 110.508995 -258.463646) (xy 110.558548 -258.481444) (xy 110.604804 -258.506597) (xy 110.646678 -258.538516)
			(xy 110.68319 -258.576454) (xy 110.713482 -258.61952) (xy 110.736845 -258.666705) (xy 110.752731 -258.716904)
			(xy 110.760768 -258.76894) (xy 110.761272 -258.795266) (xy 110.988351 -258.795266) (xy 110.992381 -258.742768)
			(xy 111.004378 -258.6915) (xy 111.024061 -258.642665) (xy 111.050967 -258.597406) (xy 111.084467 -258.556785)
			(xy 111.123775 -258.521754) (xy 111.16797 -258.493134) (xy 111.216015 -258.471595) (xy 111.266786 -258.457643)
			(xy 111.319091 -258.451605) (xy 111.371705 -258.453622) (xy 111.423395 -258.463646) (xy 111.472948 -258.481444)
			(xy 111.519204 -258.506597) (xy 111.561078 -258.538516) (xy 111.59759 -258.576454) (xy 111.627882 -258.61952)
			(xy 111.651245 -258.666705) (xy 111.667131 -258.716904) (xy 111.675168 -258.76894) (xy 111.675672 -258.795266)
			(xy 111.675168 -258.821592) (xy 111.667131 -258.873628) (xy 111.651245 -258.923827) (xy 111.627882 -258.971012)
			(xy 111.59759 -259.014078) (xy 111.561078 -259.052016) (xy 111.519204 -259.083935) (xy 111.472948 -259.109088)
			(xy 111.423395 -259.126886) (xy 111.371705 -259.13691) (xy 111.319091 -259.138927) (xy 111.266786 -259.132889)
			(xy 111.216015 -259.118937) (xy 111.16797 -259.097398) (xy 111.123775 -259.068778) (xy 111.084467 -259.033747)
			(xy 111.050967 -258.993126) (xy 111.024061 -258.947867) (xy 111.004378 -258.899032) (xy 110.992381 -258.847764)
			(xy 110.988351 -258.795266) (xy 110.761272 -258.795266) (xy 110.760768 -258.821592) (xy 110.752731 -258.873628)
			(xy 110.736845 -258.923827) (xy 110.713482 -258.971012) (xy 110.68319 -259.014078) (xy 110.646678 -259.052016)
			(xy 110.604804 -259.083935) (xy 110.558548 -259.109088) (xy 110.508995 -259.126886) (xy 110.457305 -259.13691)
			(xy 110.404691 -259.138927) (xy 110.352386 -259.132889) (xy 110.301615 -259.118937) (xy 110.25357 -259.097398)
			(xy 110.209375 -259.068778) (xy 110.170067 -259.033747) (xy 110.136567 -258.993126) (xy 110.109661 -258.947867)
			(xy 110.089978 -258.899032) (xy 110.077981 -258.847764) (xy 110.073951 -258.795266) (xy 109.176021 -258.795266)
			(xy 109.176024 -258.7953) (xy 109.172183 -258.846555) (xy 109.160746 -258.896666) (xy 109.14197 -258.944512)
			(xy 109.116272 -258.989026) (xy 109.084227 -259.029213) (xy 109.046552 -259.064175) (xy 109.004086 -259.093132)
			(xy 108.957779 -259.115438) (xy 108.908665 -259.130593) (xy 108.857841 -259.138259) (xy 108.832142 -259.138674)
			(xy 108.805588 -259.138174) (xy 108.753113 -259.129993) (xy 108.702522 -259.113835) (xy 108.65502 -259.090084)
			(xy 108.611739 -259.059306) (xy 108.592366 -259.041138) (xy 108.581444 -259.03047) (xy 108.551472 -259.024882)
			(xy 108.453428 -259.06603) (xy 108.453174 -259.06603) (xy 108.444181 -259.070372) (xy 108.430173 -259.084577)
			(xy 108.422624 -259.103044) (xy 108.422186 -259.11302) (xy 108.422186 -259.543296) (xy 108.43895 -259.568442)
			(xy 108.453428 -259.574538) (xy 108.551472 -259.615686) (xy 108.581444 -259.610098) (xy 108.592366 -259.59943)
			(xy 108.611723 -259.581241) (xy 108.655002 -259.550452) (xy 108.702507 -259.526694) (xy 108.753104 -259.510536)
			(xy 108.805585 -259.502363) (xy 108.832142 -259.501894) (xy 108.857839 -259.502377) (xy 108.908657 -259.510042)
			(xy 108.957766 -259.525196) (xy 109.004068 -259.547499) (xy 109.046529 -259.576453) (xy 109.084201 -259.611412)
			(xy 109.116242 -259.651595) (xy 109.141937 -259.696104) (xy 109.160712 -259.743945) (xy 109.172147 -259.79405)
			(xy 109.175988 -259.8453) (xy 109.175988 -259.845302) (xy 110.073951 -259.845302) (xy 110.077981 -259.792804)
			(xy 110.089978 -259.741536) (xy 110.109661 -259.692701) (xy 110.136567 -259.647442) (xy 110.170067 -259.606821)
			(xy 110.209375 -259.57179) (xy 110.25357 -259.54317) (xy 110.301615 -259.521631) (xy 110.352386 -259.507679)
			(xy 110.404691 -259.501641) (xy 110.457305 -259.503658) (xy 110.508995 -259.513682) (xy 110.558548 -259.53148)
			(xy 110.604804 -259.556633) (xy 110.646678 -259.588552) (xy 110.68319 -259.62649) (xy 110.713482 -259.669556)
			(xy 110.736845 -259.716741) (xy 110.752731 -259.76694) (xy 110.760768 -259.818976) (xy 110.761272 -259.845302)
			(xy 110.988351 -259.845302) (xy 110.992381 -259.792804) (xy 111.004378 -259.741536) (xy 111.024061 -259.692701)
			(xy 111.050967 -259.647442) (xy 111.084467 -259.606821) (xy 111.123775 -259.57179) (xy 111.16797 -259.54317)
			(xy 111.216015 -259.521631) (xy 111.266786 -259.507679) (xy 111.319091 -259.501641) (xy 111.371705 -259.503658)
			(xy 111.423395 -259.513682) (xy 111.472948 -259.53148) (xy 111.519204 -259.556633) (xy 111.561078 -259.588552)
			(xy 111.59759 -259.62649) (xy 111.627882 -259.669556) (xy 111.651245 -259.716741) (xy 111.667131 -259.76694)
			(xy 111.675168 -259.818976) (xy 111.675672 -259.845302) (xy 112.323883 -259.845302) (xy 112.327913 -259.792804)
			(xy 112.33991 -259.741536) (xy 112.359593 -259.692701) (xy 112.386499 -259.647442) (xy 112.419999 -259.606821)
			(xy 112.459307 -259.57179) (xy 112.503502 -259.54317) (xy 112.551547 -259.521631) (xy 112.602318 -259.507679)
			(xy 112.654623 -259.501641) (xy 112.707237 -259.503658) (xy 112.758927 -259.513682) (xy 112.80848 -259.53148)
			(xy 112.854736 -259.556633) (xy 112.89661 -259.588552) (xy 112.933122 -259.62649) (xy 112.963414 -259.669556)
			(xy 112.986777 -259.716741) (xy 113.002663 -259.76694) (xy 113.0107 -259.818976) (xy 113.011204 -259.845302)
			(xy 113.238283 -259.845302) (xy 113.242313 -259.792804) (xy 113.25431 -259.741536) (xy 113.273993 -259.692701)
			(xy 113.300899 -259.647442) (xy 113.334399 -259.606821) (xy 113.373707 -259.57179) (xy 113.417902 -259.54317)
			(xy 113.465947 -259.521631) (xy 113.516718 -259.507679) (xy 113.569023 -259.501641) (xy 113.621637 -259.503658)
			(xy 113.673327 -259.513682) (xy 113.72288 -259.53148) (xy 113.769136 -259.556633) (xy 113.81101 -259.588552)
			(xy 113.847522 -259.62649) (xy 113.877814 -259.669556) (xy 113.901177 -259.716741) (xy 113.917063 -259.76694)
			(xy 113.9251 -259.818976) (xy 113.925604 -259.845302) (xy 114.923827 -259.845302) (xy 114.927857 -259.792804)
			(xy 114.939854 -259.741536) (xy 114.959537 -259.692701) (xy 114.986443 -259.647442) (xy 115.019943 -259.606821)
			(xy 115.059251 -259.57179) (xy 115.103446 -259.54317) (xy 115.151491 -259.521631) (xy 115.202262 -259.507679)
			(xy 115.254567 -259.501641) (xy 115.307181 -259.503658) (xy 115.358871 -259.513682) (xy 115.408424 -259.53148)
			(xy 115.45468 -259.556633) (xy 115.496554 -259.588552) (xy 115.533066 -259.62649) (xy 115.563358 -259.669556)
			(xy 115.586721 -259.716741) (xy 115.602607 -259.76694) (xy 115.610644 -259.818976) (xy 115.611148 -259.845302)
			(xy 115.838227 -259.845302) (xy 115.842257 -259.792804) (xy 115.854254 -259.741536) (xy 115.873937 -259.692701)
			(xy 115.900843 -259.647442) (xy 115.934343 -259.606821) (xy 115.973651 -259.57179) (xy 116.017846 -259.54317)
			(xy 116.065891 -259.521631) (xy 116.116662 -259.507679) (xy 116.168967 -259.501641) (xy 116.221581 -259.503658)
			(xy 116.273271 -259.513682) (xy 116.322824 -259.53148) (xy 116.36908 -259.556633) (xy 116.410954 -259.588552)
			(xy 116.447466 -259.62649) (xy 116.477758 -259.669556) (xy 116.501121 -259.716741) (xy 116.517007 -259.76694)
			(xy 116.525044 -259.818976) (xy 116.525548 -259.845302) (xy 116.525044 -259.871628) (xy 116.517007 -259.923664)
			(xy 116.501121 -259.973863) (xy 116.477758 -260.021048) (xy 116.447466 -260.064114) (xy 116.410954 -260.102052)
			(xy 116.36908 -260.133971) (xy 116.322824 -260.159124) (xy 116.273271 -260.176922) (xy 116.221581 -260.186946)
			(xy 116.168967 -260.188963) (xy 116.116662 -260.182925) (xy 116.065891 -260.168973) (xy 116.017846 -260.147434)
			(xy 115.973651 -260.118814) (xy 115.934343 -260.083783) (xy 115.900843 -260.043162) (xy 115.873937 -259.997903)
			(xy 115.854254 -259.949068) (xy 115.842257 -259.8978) (xy 115.838227 -259.845302) (xy 115.611148 -259.845302)
			(xy 115.610644 -259.871628) (xy 115.602607 -259.923664) (xy 115.586721 -259.973863) (xy 115.563358 -260.021048)
			(xy 115.533066 -260.064114) (xy 115.496554 -260.102052) (xy 115.45468 -260.133971) (xy 115.408424 -260.159124)
			(xy 115.358871 -260.176922) (xy 115.307181 -260.186946) (xy 115.254567 -260.188963) (xy 115.202262 -260.182925)
			(xy 115.151491 -260.168973) (xy 115.103446 -260.147434) (xy 115.059251 -260.118814) (xy 115.019943 -260.083783)
			(xy 114.986443 -260.043162) (xy 114.959537 -259.997903) (xy 114.939854 -259.949068) (xy 114.927857 -259.8978)
			(xy 114.923827 -259.845302) (xy 113.925604 -259.845302) (xy 113.9251 -259.871628) (xy 113.917063 -259.923664)
			(xy 113.901177 -259.973863) (xy 113.877814 -260.021048) (xy 113.847522 -260.064114) (xy 113.81101 -260.102052)
			(xy 113.769136 -260.133971) (xy 113.72288 -260.159124) (xy 113.673327 -260.176922) (xy 113.621637 -260.186946)
			(xy 113.569023 -260.188963) (xy 113.516718 -260.182925) (xy 113.465947 -260.168973) (xy 113.417902 -260.147434)
			(xy 113.373707 -260.118814) (xy 113.334399 -260.083783) (xy 113.300899 -260.043162) (xy 113.273993 -259.997903)
			(xy 113.25431 -259.949068) (xy 113.242313 -259.8978) (xy 113.238283 -259.845302) (xy 113.011204 -259.845302)
			(xy 113.0107 -259.871628) (xy 113.002663 -259.923664) (xy 112.986777 -259.973863) (xy 112.963414 -260.021048)
			(xy 112.933122 -260.064114) (xy 112.89661 -260.102052) (xy 112.854736 -260.133971) (xy 112.80848 -260.159124)
			(xy 112.758927 -260.176922) (xy 112.707237 -260.186946) (xy 112.654623 -260.188963) (xy 112.602318 -260.182925)
			(xy 112.551547 -260.168973) (xy 112.503502 -260.147434) (xy 112.459307 -260.118814) (xy 112.419999 -260.083783)
			(xy 112.386499 -260.043162) (xy 112.359593 -259.997903) (xy 112.33991 -259.949068) (xy 112.327913 -259.8978)
			(xy 112.323883 -259.845302) (xy 111.675672 -259.845302) (xy 111.675168 -259.871628) (xy 111.667131 -259.923664)
			(xy 111.651245 -259.973863) (xy 111.627882 -260.021048) (xy 111.59759 -260.064114) (xy 111.561078 -260.102052)
			(xy 111.519204 -260.133971) (xy 111.472948 -260.159124) (xy 111.423395 -260.176922) (xy 111.371705 -260.186946)
			(xy 111.319091 -260.188963) (xy 111.266786 -260.182925) (xy 111.216015 -260.168973) (xy 111.16797 -260.147434)
			(xy 111.123775 -260.118814) (xy 111.084467 -260.083783) (xy 111.050967 -260.043162) (xy 111.024061 -259.997903)
			(xy 111.004378 -259.949068) (xy 110.992381 -259.8978) (xy 110.988351 -259.845302) (xy 110.761272 -259.845302)
			(xy 110.760768 -259.871628) (xy 110.752731 -259.923664) (xy 110.736845 -259.973863) (xy 110.713482 -260.021048)
			(xy 110.68319 -260.064114) (xy 110.646678 -260.102052) (xy 110.604804 -260.133971) (xy 110.558548 -260.159124)
			(xy 110.508995 -260.176922) (xy 110.457305 -260.186946) (xy 110.404691 -260.188963) (xy 110.352386 -260.182925)
			(xy 110.301615 -260.168973) (xy 110.25357 -260.147434) (xy 110.209375 -260.118814) (xy 110.170067 -260.083783)
			(xy 110.136567 -260.043162) (xy 110.109661 -259.997903) (xy 110.089978 -259.949068) (xy 110.077981 -259.8978)
			(xy 110.073951 -259.845302) (xy 109.175988 -259.845302) (xy 109.172147 -259.89655) (xy 109.160712 -259.946655)
			(xy 109.141937 -259.994496) (xy 109.116242 -260.039005) (xy 109.084201 -260.079188) (xy 109.046529 -260.114147)
			(xy 109.004068 -260.143101) (xy 108.957766 -260.165404) (xy 108.908657 -260.180558) (xy 108.857839 -260.188223)
			(xy 108.832142 -260.18871) (xy 108.805587 -260.188211) (xy 108.753112 -260.180031) (xy 108.70252 -260.163873)
			(xy 108.655016 -260.140124) (xy 108.611733 -260.109349) (xy 108.592366 -260.091174) (xy 108.581444 -260.080506)
			(xy 108.551472 -260.074918) (xy 108.453428 -260.116066) (xy 108.453174 -260.116066) (xy 108.444185 -260.12041)
			(xy 108.430187 -260.134617) (xy 108.422651 -260.153082) (xy 108.422186 -260.163056) (xy 108.422186 -260.882384)
			(xy 108.422452 -260.889709) (xy 108.426571 -260.903769) (xy 108.430314 -260.91007) (xy 108.434886 -260.916928)
			(xy 108.436976 -260.920099) (xy 108.441952 -260.925836) (xy 108.444792 -260.928358) (xy 108.497878 -260.973316)
			(xy 108.50557 -260.979249) (xy 108.52398 -260.985405) (xy 108.533692 -260.985254) (xy 108.536994 -260.985)
			(xy 108.539788 -260.984746) (xy 108.554214 -260.982386) (xy 108.583337 -260.979841) (xy 108.597954 -260.979666)
			(xy 108.624944 -260.980164) (xy 108.678262 -260.988602) (xy 108.729602 -261.005277) (xy 108.777702 -261.029778)
			(xy 108.821377 -261.061502) (xy 108.859551 -261.099668) (xy 108.891285 -261.143336) (xy 108.915796 -261.191431)
			(xy 108.932481 -261.242768) (xy 108.94093 -261.296084) (xy 108.941362 -261.323074) (xy 109.204001 -261.323074)
			(xy 109.208031 -261.270576) (xy 109.220028 -261.219308) (xy 109.239711 -261.170473) (xy 109.266617 -261.125214)
			(xy 109.300117 -261.084593) (xy 109.339425 -261.049562) (xy 109.38362 -261.020942) (xy 109.431665 -260.999403)
			(xy 109.482436 -260.985451) (xy 109.534741 -260.979413) (xy 109.587355 -260.98143) (xy 109.639045 -260.991454)
			(xy 109.688598 -261.009252) (xy 109.734854 -261.034405) (xy 109.776728 -261.066324) (xy 109.81324 -261.104262)
			(xy 109.843532 -261.147328) (xy 109.866895 -261.194513) (xy 109.882781 -261.244712) (xy 109.890818 -261.296748)
			(xy 109.891322 -261.323074) (xy 110.153961 -261.323074) (xy 110.157991 -261.270576) (xy 110.169988 -261.219308)
			(xy 110.189671 -261.170473) (xy 110.216577 -261.125214) (xy 110.250077 -261.084593) (xy 110.289385 -261.049562)
			(xy 110.33358 -261.020942) (xy 110.381625 -260.999403) (xy 110.432396 -260.985451) (xy 110.484701 -260.979413)
			(xy 110.537315 -260.98143) (xy 110.589005 -260.991454) (xy 110.638558 -261.009252) (xy 110.684814 -261.034405)
			(xy 110.726688 -261.066324) (xy 110.7632 -261.104262) (xy 110.793492 -261.147328) (xy 110.816855 -261.194513)
			(xy 110.832741 -261.244712) (xy 110.840778 -261.296748) (xy 110.841282 -261.323074) (xy 111.103921 -261.323074)
			(xy 111.107951 -261.270576) (xy 111.119948 -261.219308) (xy 111.139631 -261.170473) (xy 111.166537 -261.125214)
			(xy 111.200037 -261.084593) (xy 111.239345 -261.049562) (xy 111.28354 -261.020942) (xy 111.331585 -260.999403)
			(xy 111.382356 -260.985451) (xy 111.434661 -260.979413) (xy 111.487275 -260.98143) (xy 111.538965 -260.991454)
			(xy 111.588518 -261.009252) (xy 111.634774 -261.034405) (xy 111.676648 -261.066324) (xy 111.71316 -261.104262)
			(xy 111.743452 -261.147328) (xy 111.766815 -261.194513) (xy 111.782701 -261.244712) (xy 111.790738 -261.296748)
			(xy 111.791242 -261.323074) (xy 112.053881 -261.323074) (xy 112.057911 -261.270576) (xy 112.069908 -261.219308)
			(xy 112.089591 -261.170473) (xy 112.116497 -261.125214) (xy 112.149997 -261.084593) (xy 112.189305 -261.049562)
			(xy 112.2335 -261.020942) (xy 112.281545 -260.999403) (xy 112.332316 -260.985451) (xy 112.384621 -260.979413)
			(xy 112.437235 -260.98143) (xy 112.488925 -260.991454) (xy 112.538478 -261.009252) (xy 112.584734 -261.034405)
			(xy 112.626608 -261.066324) (xy 112.66312 -261.104262) (xy 112.693412 -261.147328) (xy 112.716775 -261.194513)
			(xy 112.732661 -261.244712) (xy 112.740698 -261.296748) (xy 112.741202 -261.323074) (xy 113.004095 -261.323074)
			(xy 113.008125 -261.270576) (xy 113.020122 -261.219308) (xy 113.039805 -261.170473) (xy 113.066711 -261.125214)
			(xy 113.100211 -261.084593) (xy 113.139519 -261.049562) (xy 113.183714 -261.020942) (xy 113.231759 -260.999403)
			(xy 113.28253 -260.985451) (xy 113.334835 -260.979413) (xy 113.387449 -260.98143) (xy 113.439139 -260.991454)
			(xy 113.488692 -261.009252) (xy 113.534948 -261.034405) (xy 113.576822 -261.066324) (xy 113.613334 -261.104262)
			(xy 113.643626 -261.147328) (xy 113.666989 -261.194513) (xy 113.682875 -261.244712) (xy 113.690912 -261.296748)
			(xy 113.691416 -261.323074) (xy 113.954055 -261.323074) (xy 113.958085 -261.270576) (xy 113.970082 -261.219308)
			(xy 113.989765 -261.170473) (xy 114.016671 -261.125214) (xy 114.050171 -261.084593) (xy 114.089479 -261.049562)
			(xy 114.133674 -261.020942) (xy 114.181719 -260.999403) (xy 114.23249 -260.985451) (xy 114.284795 -260.979413)
			(xy 114.337409 -260.98143) (xy 114.389099 -260.991454) (xy 114.438652 -261.009252) (xy 114.484908 -261.034405)
			(xy 114.526782 -261.066324) (xy 114.563294 -261.104262) (xy 114.593586 -261.147328) (xy 114.616949 -261.194513)
			(xy 114.632835 -261.244712) (xy 114.640872 -261.296748) (xy 114.641376 -261.323074) (xy 114.904015 -261.323074)
			(xy 114.908045 -261.270576) (xy 114.920042 -261.219308) (xy 114.939725 -261.170473) (xy 114.966631 -261.125214)
			(xy 115.000131 -261.084593) (xy 115.039439 -261.049562) (xy 115.083634 -261.020942) (xy 115.131679 -260.999403)
			(xy 115.18245 -260.985451) (xy 115.234755 -260.979413) (xy 115.287369 -260.98143) (xy 115.339059 -260.991454)
			(xy 115.388612 -261.009252) (xy 115.434868 -261.034405) (xy 115.476742 -261.066324) (xy 115.513254 -261.104262)
			(xy 115.543546 -261.147328) (xy 115.566909 -261.194513) (xy 115.582795 -261.244712) (xy 115.590832 -261.296748)
			(xy 115.591336 -261.323074) (xy 115.853975 -261.323074) (xy 115.858005 -261.270576) (xy 115.870002 -261.219308)
			(xy 115.889685 -261.170473) (xy 115.916591 -261.125214) (xy 115.950091 -261.084593) (xy 115.989399 -261.049562)
			(xy 116.033594 -261.020942) (xy 116.081639 -260.999403) (xy 116.13241 -260.985451) (xy 116.184715 -260.979413)
			(xy 116.237329 -260.98143) (xy 116.289019 -260.991454) (xy 116.338572 -261.009252) (xy 116.384828 -261.034405)
			(xy 116.426702 -261.066324) (xy 116.463214 -261.104262) (xy 116.493506 -261.147328) (xy 116.516869 -261.194513)
			(xy 116.528214 -261.230364) (xy 117.096797 -261.230364) (xy 117.100827 -261.177866) (xy 117.112824 -261.126598)
			(xy 117.132507 -261.077763) (xy 117.159413 -261.032504) (xy 117.192913 -260.991883) (xy 117.232221 -260.956852)
			(xy 117.276416 -260.928232) (xy 117.324461 -260.906693) (xy 117.375232 -260.892741) (xy 117.427537 -260.886703)
			(xy 117.480151 -260.88872) (xy 117.531841 -260.898744) (xy 117.581394 -260.916542) (xy 117.62765 -260.941695)
			(xy 117.669524 -260.973614) (xy 117.706036 -261.011552) (xy 117.736328 -261.054618) (xy 117.759691 -261.101803)
			(xy 117.775577 -261.152002) (xy 117.783614 -261.204038) (xy 117.784118 -261.230364) (xy 118.011197 -261.230364)
			(xy 118.015227 -261.177866) (xy 118.027224 -261.126598) (xy 118.046907 -261.077763) (xy 118.073813 -261.032504)
			(xy 118.107313 -260.991883) (xy 118.146621 -260.956852) (xy 118.190816 -260.928232) (xy 118.238861 -260.906693)
			(xy 118.289632 -260.892741) (xy 118.341937 -260.886703) (xy 118.394551 -260.88872) (xy 118.446241 -260.898744)
			(xy 118.495794 -260.916542) (xy 118.54205 -260.941695) (xy 118.583924 -260.973614) (xy 118.620436 -261.011552)
			(xy 118.650728 -261.054618) (xy 118.674091 -261.101803) (xy 118.689977 -261.152002) (xy 118.698014 -261.204038)
			(xy 118.698518 -261.230364) (xy 118.698014 -261.25669) (xy 118.689977 -261.308726) (xy 118.674091 -261.358925)
			(xy 118.650728 -261.40611) (xy 118.620436 -261.449176) (xy 118.583924 -261.487114) (xy 118.54205 -261.519033)
			(xy 118.495794 -261.544186) (xy 118.446241 -261.561984) (xy 118.394551 -261.572008) (xy 118.341937 -261.574025)
			(xy 118.289632 -261.567987) (xy 118.238861 -261.554035) (xy 118.190816 -261.532496) (xy 118.146621 -261.503876)
			(xy 118.107313 -261.468845) (xy 118.073813 -261.428224) (xy 118.046907 -261.382965) (xy 118.027224 -261.33413)
			(xy 118.015227 -261.282862) (xy 118.011197 -261.230364) (xy 117.784118 -261.230364) (xy 117.783614 -261.25669)
			(xy 117.775577 -261.308726) (xy 117.759691 -261.358925) (xy 117.736328 -261.40611) (xy 117.706036 -261.449176)
			(xy 117.669524 -261.487114) (xy 117.62765 -261.519033) (xy 117.581394 -261.544186) (xy 117.531841 -261.561984)
			(xy 117.480151 -261.572008) (xy 117.427537 -261.574025) (xy 117.375232 -261.567987) (xy 117.324461 -261.554035)
			(xy 117.276416 -261.532496) (xy 117.232221 -261.503876) (xy 117.192913 -261.468845) (xy 117.159413 -261.428224)
			(xy 117.132507 -261.382965) (xy 117.112824 -261.33413) (xy 117.100827 -261.282862) (xy 117.096797 -261.230364)
			(xy 116.528214 -261.230364) (xy 116.532755 -261.244712) (xy 116.540792 -261.296748) (xy 116.541296 -261.323074)
			(xy 116.540792 -261.3494) (xy 116.532755 -261.401436) (xy 116.516869 -261.451635) (xy 116.493506 -261.49882)
			(xy 116.463214 -261.541886) (xy 116.426702 -261.579824) (xy 116.384828 -261.611743) (xy 116.338572 -261.636896)
			(xy 116.289019 -261.654694) (xy 116.237329 -261.664718) (xy 116.184715 -261.666735) (xy 116.13241 -261.660697)
			(xy 116.081639 -261.646745) (xy 116.033594 -261.625206) (xy 115.989399 -261.596586) (xy 115.950091 -261.561555)
			(xy 115.916591 -261.520934) (xy 115.889685 -261.475675) (xy 115.870002 -261.42684) (xy 115.858005 -261.375572)
			(xy 115.853975 -261.323074) (xy 115.591336 -261.323074) (xy 115.590832 -261.3494) (xy 115.582795 -261.401436)
			(xy 115.566909 -261.451635) (xy 115.543546 -261.49882) (xy 115.513254 -261.541886) (xy 115.476742 -261.579824)
			(xy 115.434868 -261.611743) (xy 115.388612 -261.636896) (xy 115.339059 -261.654694) (xy 115.287369 -261.664718)
			(xy 115.234755 -261.666735) (xy 115.18245 -261.660697) (xy 115.131679 -261.646745) (xy 115.083634 -261.625206)
			(xy 115.039439 -261.596586) (xy 115.000131 -261.561555) (xy 114.966631 -261.520934) (xy 114.939725 -261.475675)
			(xy 114.920042 -261.42684) (xy 114.908045 -261.375572) (xy 114.904015 -261.323074) (xy 114.641376 -261.323074)
			(xy 114.640872 -261.3494) (xy 114.632835 -261.401436) (xy 114.616949 -261.451635) (xy 114.593586 -261.49882)
			(xy 114.563294 -261.541886) (xy 114.526782 -261.579824) (xy 114.484908 -261.611743) (xy 114.438652 -261.636896)
			(xy 114.389099 -261.654694) (xy 114.337409 -261.664718) (xy 114.284795 -261.666735) (xy 114.23249 -261.660697)
			(xy 114.181719 -261.646745) (xy 114.133674 -261.625206) (xy 114.089479 -261.596586) (xy 114.050171 -261.561555)
			(xy 114.016671 -261.520934) (xy 113.989765 -261.475675) (xy 113.970082 -261.42684) (xy 113.958085 -261.375572)
			(xy 113.954055 -261.323074) (xy 113.691416 -261.323074) (xy 113.690912 -261.3494) (xy 113.682875 -261.401436)
			(xy 113.666989 -261.451635) (xy 113.643626 -261.49882) (xy 113.613334 -261.541886) (xy 113.576822 -261.579824)
			(xy 113.534948 -261.611743) (xy 113.488692 -261.636896) (xy 113.439139 -261.654694) (xy 113.387449 -261.664718)
			(xy 113.334835 -261.666735) (xy 113.28253 -261.660697) (xy 113.231759 -261.646745) (xy 113.183714 -261.625206)
			(xy 113.139519 -261.596586) (xy 113.100211 -261.561555) (xy 113.066711 -261.520934) (xy 113.039805 -261.475675)
			(xy 113.020122 -261.42684) (xy 113.008125 -261.375572) (xy 113.004095 -261.323074) (xy 112.741202 -261.323074)
			(xy 112.740698 -261.3494) (xy 112.732661 -261.401436) (xy 112.716775 -261.451635) (xy 112.693412 -261.49882)
			(xy 112.66312 -261.541886) (xy 112.626608 -261.579824) (xy 112.584734 -261.611743) (xy 112.538478 -261.636896)
			(xy 112.488925 -261.654694) (xy 112.437235 -261.664718) (xy 112.384621 -261.666735) (xy 112.332316 -261.660697)
			(xy 112.281545 -261.646745) (xy 112.2335 -261.625206) (xy 112.189305 -261.596586) (xy 112.149997 -261.561555)
			(xy 112.116497 -261.520934) (xy 112.089591 -261.475675) (xy 112.069908 -261.42684) (xy 112.057911 -261.375572)
			(xy 112.053881 -261.323074) (xy 111.791242 -261.323074) (xy 111.790738 -261.3494) (xy 111.782701 -261.401436)
			(xy 111.766815 -261.451635) (xy 111.743452 -261.49882) (xy 111.71316 -261.541886) (xy 111.676648 -261.579824)
			(xy 111.634774 -261.611743) (xy 111.588518 -261.636896) (xy 111.538965 -261.654694) (xy 111.487275 -261.664718)
			(xy 111.434661 -261.666735) (xy 111.382356 -261.660697) (xy 111.331585 -261.646745) (xy 111.28354 -261.625206)
			(xy 111.239345 -261.596586) (xy 111.200037 -261.561555) (xy 111.166537 -261.520934) (xy 111.139631 -261.475675)
			(xy 111.119948 -261.42684) (xy 111.107951 -261.375572) (xy 111.103921 -261.323074) (xy 110.841282 -261.323074)
			(xy 110.840778 -261.3494) (xy 110.832741 -261.401436) (xy 110.816855 -261.451635) (xy 110.793492 -261.49882)
			(xy 110.7632 -261.541886) (xy 110.726688 -261.579824) (xy 110.684814 -261.611743) (xy 110.638558 -261.636896)
			(xy 110.589005 -261.654694) (xy 110.537315 -261.664718) (xy 110.484701 -261.666735) (xy 110.432396 -261.660697)
			(xy 110.381625 -261.646745) (xy 110.33358 -261.625206) (xy 110.289385 -261.596586) (xy 110.250077 -261.561555)
			(xy 110.216577 -261.520934) (xy 110.189671 -261.475675) (xy 110.169988 -261.42684) (xy 110.157991 -261.375572)
			(xy 110.153961 -261.323074) (xy 109.891322 -261.323074) (xy 109.890818 -261.3494) (xy 109.882781 -261.401436)
			(xy 109.866895 -261.451635) (xy 109.843532 -261.49882) (xy 109.81324 -261.541886) (xy 109.776728 -261.579824)
			(xy 109.734854 -261.611743) (xy 109.688598 -261.636896) (xy 109.639045 -261.654694) (xy 109.587355 -261.664718)
			(xy 109.534741 -261.666735) (xy 109.482436 -261.660697) (xy 109.431665 -261.646745) (xy 109.38362 -261.625206)
			(xy 109.339425 -261.596586) (xy 109.300117 -261.561555) (xy 109.266617 -261.520934) (xy 109.239711 -261.475675)
			(xy 109.220028 -261.42684) (xy 109.208031 -261.375572) (xy 109.204001 -261.323074) (xy 108.941362 -261.323074)
			(xy 108.940902 -261.348525) (xy 108.933392 -261.398869) (xy 108.918531 -261.447552) (xy 108.896646 -261.493508)
			(xy 108.868216 -261.53573) (xy 108.833865 -261.573292) (xy 108.794345 -261.605371) (xy 108.750522 -261.631265)
			(xy 108.703356 -261.650405) (xy 108.678726 -261.65683) (xy 108.671614 -261.658608) (xy 108.659676 -261.665212)
			(xy 108.654596 -261.670292) (xy 108.647762 -261.677657) (xy 108.640031 -261.696185) (xy 108.64004 -261.716261)
			(xy 108.647788 -261.734782) (xy 108.654596 -261.742174) (xy 108.6866 -261.774178) (xy 108.687108 -261.774686)
			(xy 108.694488 -261.781272) (xy 108.712787 -261.788733) (xy 108.722668 -261.789164) (xy 116.580412 -261.789164)
			(xy 116.590255 -261.789689) (xy 116.608434 -261.797257) (xy 116.615718 -261.803896) (xy 116.789454 -261.977632)
			(xy 116.796159 -261.984873) (xy 116.803739 -262.003078) (xy 116.804186 -262.012938) (xy 116.804186 -262.180324)
			(xy 117.096797 -262.180324) (xy 117.100827 -262.127826) (xy 117.112824 -262.076558) (xy 117.132507 -262.027723)
			(xy 117.159413 -261.982464) (xy 117.192913 -261.941843) (xy 117.232221 -261.906812) (xy 117.276416 -261.878192)
			(xy 117.324461 -261.856653) (xy 117.375232 -261.842701) (xy 117.427537 -261.836663) (xy 117.480151 -261.83868)
			(xy 117.531841 -261.848704) (xy 117.581394 -261.866502) (xy 117.62765 -261.891655) (xy 117.669524 -261.923574)
			(xy 117.706036 -261.961512) (xy 117.736328 -262.004578) (xy 117.759691 -262.051763) (xy 117.775577 -262.101962)
			(xy 117.783614 -262.153998) (xy 117.784118 -262.180324) (xy 118.011197 -262.180324) (xy 118.015227 -262.127826)
			(xy 118.027224 -262.076558) (xy 118.046907 -262.027723) (xy 118.073813 -261.982464) (xy 118.107313 -261.941843)
			(xy 118.146621 -261.906812) (xy 118.190816 -261.878192) (xy 118.238861 -261.856653) (xy 118.289632 -261.842701)
			(xy 118.341937 -261.836663) (xy 118.394551 -261.83868) (xy 118.446241 -261.848704) (xy 118.495794 -261.866502)
			(xy 118.54205 -261.891655) (xy 118.583924 -261.923574) (xy 118.596104 -261.93623) (xy 121.168934 -261.93623)
			(xy 121.172894 -261.887176) (xy 121.184671 -261.839392) (xy 121.203962 -261.794116) (xy 121.230265 -261.75252)
			(xy 121.2629 -261.715683) (xy 121.301021 -261.684558) (xy 121.343642 -261.659951) (xy 121.389658 -261.642499)
			(xy 121.437877 -261.632655) (xy 121.487052 -261.630674) (xy 121.535907 -261.636606) (xy 121.583178 -261.650298)
			(xy 121.62764 -261.671396) (xy 121.668143 -261.699352) (xy 121.703636 -261.733444) (xy 121.733201 -261.772788)
			(xy 121.756072 -261.816365) (xy 121.771656 -261.863046) (xy 121.779551 -261.911623) (xy 121.780046 -261.93623)
			(xy 121.779551 -261.960837) (xy 121.771656 -262.009414) (xy 121.756072 -262.056095) (xy 121.733201 -262.099672)
			(xy 121.703636 -262.139016) (xy 121.668143 -262.173108) (xy 121.62764 -262.201064) (xy 121.583178 -262.222162)
			(xy 121.535907 -262.235854) (xy 121.487052 -262.241786) (xy 121.437877 -262.239805) (xy 121.389658 -262.229961)
			(xy 121.343642 -262.212509) (xy 121.301021 -262.187902) (xy 121.2629 -262.156777) (xy 121.230265 -262.11994)
			(xy 121.203962 -262.078344) (xy 121.184671 -262.033068) (xy 121.172894 -261.985284) (xy 121.168934 -261.93623)
			(xy 118.596104 -261.93623) (xy 118.620436 -261.961512) (xy 118.650728 -262.004578) (xy 118.674091 -262.051763)
			(xy 118.689977 -262.101962) (xy 118.698014 -262.153998) (xy 118.698518 -262.180324) (xy 118.698014 -262.20665)
			(xy 118.689977 -262.258686) (xy 118.674091 -262.308885) (xy 118.650728 -262.35607) (xy 118.620436 -262.399136)
			(xy 118.583924 -262.437074) (xy 118.54205 -262.468993) (xy 118.495794 -262.494146) (xy 118.446241 -262.511944)
			(xy 118.394551 -262.521968) (xy 118.341937 -262.523985) (xy 118.289632 -262.517947) (xy 118.238861 -262.503995)
			(xy 118.190816 -262.482456) (xy 118.146621 -262.453836) (xy 118.107313 -262.418805) (xy 118.073813 -262.378184)
			(xy 118.046907 -262.332925) (xy 118.027224 -262.28409) (xy 118.015227 -262.232822) (xy 118.011197 -262.180324)
			(xy 117.784118 -262.180324) (xy 117.783614 -262.20665) (xy 117.775577 -262.258686) (xy 117.759691 -262.308885)
			(xy 117.736328 -262.35607) (xy 117.706036 -262.399136) (xy 117.669524 -262.437074) (xy 117.62765 -262.468993)
			(xy 117.581394 -262.494146) (xy 117.531841 -262.511944) (xy 117.480151 -262.521968) (xy 117.427537 -262.523985)
			(xy 117.375232 -262.517947) (xy 117.324461 -262.503995) (xy 117.276416 -262.482456) (xy 117.232221 -262.453836)
			(xy 117.192913 -262.418805) (xy 117.159413 -262.378184) (xy 117.132507 -262.332925) (xy 117.112824 -262.28409)
			(xy 117.100827 -262.232822) (xy 117.096797 -262.180324) (xy 116.804186 -262.180324) (xy 116.804186 -262.746236)
			(xy 121.638834 -262.746236) (xy 121.642794 -262.697182) (xy 121.654571 -262.649398) (xy 121.673862 -262.604122)
			(xy 121.700165 -262.562526) (xy 121.7328 -262.525689) (xy 121.770921 -262.494564) (xy 121.813542 -262.469957)
			(xy 121.859558 -262.452505) (xy 121.907777 -262.442661) (xy 121.956952 -262.44068) (xy 122.005807 -262.446612)
			(xy 122.053078 -262.460304) (xy 122.09754 -262.481402) (xy 122.138043 -262.509358) (xy 122.173536 -262.54345)
			(xy 122.203101 -262.582794) (xy 122.225972 -262.626371) (xy 122.241556 -262.673052) (xy 122.249451 -262.721629)
			(xy 122.249946 -262.746236) (xy 122.249451 -262.770843) (xy 122.241556 -262.81942) (xy 122.225972 -262.866101)
			(xy 122.203101 -262.909678) (xy 122.173536 -262.949022) (xy 122.138043 -262.983114) (xy 122.09754 -263.01107)
			(xy 122.053078 -263.032168) (xy 122.005807 -263.04586) (xy 121.956952 -263.051792) (xy 121.907777 -263.049811)
			(xy 121.859558 -263.039967) (xy 121.813542 -263.022515) (xy 121.770921 -262.997908) (xy 121.7328 -262.966783)
			(xy 121.700165 -262.929946) (xy 121.673862 -262.88835) (xy 121.654571 -262.843074) (xy 121.642794 -262.79529)
			(xy 121.638834 -262.746236) (xy 116.804186 -262.746236) (xy 116.804186 -263.165082) (xy 116.804657 -263.174954)
			(xy 116.812115 -263.193238) (xy 116.818664 -263.200642) (xy 116.818918 -263.200896) (xy 117.221 -263.602978)
			(xy 117.221508 -263.603486) (xy 117.228888 -263.610072) (xy 117.247187 -263.617533) (xy 117.257068 -263.617964)
			(xy 121.081038 -263.617964)
		)
		(stroke
			(width 0)
			(type solid)
		)
		(fill yes)
		(layer "In11.Cu")
		(net "PVDD18_S5_P1")
	)
	(gr_poly
		(pts
			(xy 310.824372 -336.703162) (xy 310.834436 -336.702725) (xy 310.853018 -336.694988) (xy 310.86044 -336.688176)
			(xy 316.558168 -330.990448) (xy 316.558168 -330.981304) (xy 316.724284 -330.815188) (xy 316.731683 -330.808345)
			(xy 316.750282 -330.800627) (xy 316.760352 -330.800202) (xy 318.36487 -330.800202) (xy 318.374935 -330.799766)
			(xy 318.393521 -330.792034) (xy 318.400938 -330.785216) (xy 321.854576 -327.331578) (xy 321.861975 -327.324735)
			(xy 321.880574 -327.317016) (xy 321.890644 -327.316592) (xy 342.707976 -327.316592) (xy 342.70823 -327.316338)
			(xy 348.531942 -327.316338) (xy 348.542007 -327.315906) (xy 348.560595 -327.308173) (xy 348.56801 -327.301352)
			(xy 348.638114 -327.231248) (xy 348.642725 -327.226394) (xy 348.649423 -327.214808) (xy 348.651322 -327.208388)
			(xy 348.662015 -327.171433) (xy 348.693015 -327.101026) (xy 348.713044 -327.06818) (xy 348.713552 -327.067672)
			(xy 348.713552 -327.067418) (xy 348.717053 -327.061312) (xy 348.720917 -327.047782) (xy 348.721172 -327.040748)
			(xy 348.721172 -327.005696) (xy 348.72095 -326.998656) (xy 348.717084 -326.985119) (xy 348.713552 -326.979026)
			(xy 348.713298 -326.978518) (xy 348.698167 -326.954002) (xy 348.672922 -326.902215) (xy 348.653696 -326.847905)
			(xy 348.640735 -326.79177) (xy 348.634206 -326.734528) (xy 348.633796 -326.705722) (xy 348.634194 -326.676949)
			(xy 348.640694 -326.61977) (xy 348.653612 -326.563692) (xy 348.672783 -326.509433) (xy 348.697962 -326.457687)
			(xy 348.713044 -326.43318) (xy 348.713552 -326.432672) (xy 348.713552 -326.432418) (xy 348.717053 -326.426312)
			(xy 348.720917 -326.412782) (xy 348.721172 -326.405748) (xy 348.721172 -326.370696) (xy 348.72095 -326.363656)
			(xy 348.717084 -326.350119) (xy 348.713552 -326.344026) (xy 348.713298 -326.343518) (xy 348.698167 -326.319002)
			(xy 348.672922 -326.267215) (xy 348.653696 -326.212905) (xy 348.640735 -326.15677) (xy 348.634206 -326.099528)
			(xy 348.633796 -326.070722) (xy 348.634194 -326.041949) (xy 348.640694 -325.98477) (xy 348.653612 -325.928692)
			(xy 348.672783 -325.874433) (xy 348.697962 -325.822687) (xy 348.713044 -325.79818) (xy 348.713552 -325.797672)
			(xy 348.713552 -325.797418) (xy 348.717053 -325.791312) (xy 348.720917 -325.777782) (xy 348.721172 -325.770748)
			(xy 348.721172 -325.735696) (xy 348.72095 -325.728656) (xy 348.717084 -325.715119) (xy 348.713552 -325.709026)
			(xy 348.713298 -325.708518) (xy 348.698167 -325.684002) (xy 348.672922 -325.632215) (xy 348.653696 -325.577905)
			(xy 348.640735 -325.52177) (xy 348.634206 -325.464528) (xy 348.633796 -325.435722) (xy 348.634194 -325.406949)
			(xy 348.640694 -325.34977) (xy 348.653612 -325.293692) (xy 348.672783 -325.239433) (xy 348.697962 -325.187687)
			(xy 348.713044 -325.16318) (xy 348.713552 -325.162672) (xy 348.713552 -325.162418) (xy 348.717053 -325.156312)
			(xy 348.720917 -325.142782) (xy 348.721172 -325.135748) (xy 348.721172 -325.103744) (xy 348.716092 -325.08825)
			(xy 348.711012 -325.081646) (xy 348.691613 -325.055084) (xy 348.659088 -324.997912) (xy 348.634206 -324.937024)
			(xy 348.617383 -324.873436) (xy 348.608899 -324.80821) (xy 348.608396 -324.775322) (xy 348.608857 -324.744601)
			(xy 348.616255 -324.683606) (xy 348.630947 -324.623946) (xy 348.652717 -324.56649) (xy 348.681249 -324.512075)
			(xy 348.698312 -324.486524) (xy 348.703709 -324.477839) (xy 348.707778 -324.457818) (xy 348.703723 -324.437795)
			(xy 348.698312 -324.42912) (xy 348.681254 -324.403566) (xy 348.652722 -324.34915) (xy 348.630952 -324.291694)
			(xy 348.616258 -324.232034) (xy 348.608857 -324.171039) (xy 348.608855 -324.109597) (xy 348.616252 -324.048602)
			(xy 348.630941 -323.988941) (xy 348.652708 -323.931483) (xy 348.681235 -323.877066) (xy 348.698312 -323.851524)
			(xy 348.703709 -323.842839) (xy 348.707778 -323.822818) (xy 348.703723 -323.802795) (xy 348.698312 -323.79412)
			(xy 348.681254 -323.768566) (xy 348.652722 -323.71415) (xy 348.630952 -323.656694) (xy 348.616258 -323.597034)
			(xy 348.608857 -323.536039) (xy 348.608855 -323.474597) (xy 348.616252 -323.413602) (xy 348.630941 -323.353941)
			(xy 348.652708 -323.296483) (xy 348.681235 -323.242066) (xy 348.698312 -323.216524) (xy 348.703709 -323.207839)
			(xy 348.707778 -323.187818) (xy 348.703723 -323.167795) (xy 348.698312 -323.15912) (xy 348.681254 -323.133566)
			(xy 348.652722 -323.07915) (xy 348.630952 -323.021694) (xy 348.616258 -322.962034) (xy 348.608857 -322.901039)
			(xy 348.608855 -322.839597) (xy 348.616252 -322.778602) (xy 348.630941 -322.718941) (xy 348.652708 -322.661483)
			(xy 348.681235 -322.607066) (xy 348.698312 -322.581524) (xy 348.703709 -322.572839) (xy 348.707778 -322.552818)
			(xy 348.703723 -322.532795) (xy 348.698312 -322.52412) (xy 348.681254 -322.498566) (xy 348.652722 -322.44415)
			(xy 348.630952 -322.386694) (xy 348.616258 -322.327034) (xy 348.608857 -322.266039) (xy 348.608855 -322.204597)
			(xy 348.616252 -322.143602) (xy 348.630941 -322.083941) (xy 348.652708 -322.026483) (xy 348.681235 -321.972066)
			(xy 348.698312 -321.946524) (xy 348.703709 -321.937839) (xy 348.707778 -321.917818) (xy 348.703723 -321.897795)
			(xy 348.698312 -321.88912) (xy 348.681254 -321.863566) (xy 348.652723 -321.809151) (xy 348.630952 -321.751696)
			(xy 348.616259 -321.692037) (xy 348.608857 -321.631043) (xy 348.608396 -321.600322) (xy 348.608936 -321.567462)
			(xy 348.617446 -321.502293) (xy 348.634277 -321.438764) (xy 348.659149 -321.37793) (xy 348.691646 -321.320805)
			(xy 348.711012 -321.294252) (xy 348.715709 -321.287455) (xy 348.720886 -321.271776) (xy 348.721172 -321.263518)
			(xy 348.721172 -311.90819) (xy 348.720685 -311.897818) (xy 348.712503 -311.878755) (xy 348.697468 -311.864462)
			(xy 348.687898 -311.860438) (xy 348.58325 -311.822084) (xy 348.552262 -311.830212) (xy 348.542102 -311.842404)
			(xy 348.521344 -311.866162) (xy 348.474917 -311.908881) (xy 348.423564 -311.945532) (xy 348.368075 -311.975553)
			(xy 348.309299 -311.998485) (xy 348.24814 -312.013975) (xy 348.185535 -312.021786) (xy 348.15399 -312.022236)
			(xy 348.122937 -312.02175) (xy 348.061297 -312.014156) (xy 348.001036 -311.999131) (xy 347.971872 -311.988454)
			(xy 347.962982 -311.985152) (xy 347.944694 -311.985152) (xy 347.863414 -312.015886) (xy 347.849698 -312.028332)
			(xy 347.84538 -312.03646) (xy 347.832984 -312.059372) (xy 347.802913 -312.101908) (xy 347.767335 -312.139958)
			(xy 347.726912 -312.172815) (xy 347.682395 -312.199868) (xy 347.634611 -312.220614) (xy 347.58445 -312.234667)
			(xy 347.532844 -312.241767) (xy 347.506798 -312.2422) (xy 347.479547 -312.241714) (xy 347.425601 -312.233958)
			(xy 347.373308 -312.218603) (xy 347.323732 -312.195962) (xy 347.277882 -312.166496) (xy 347.236693 -312.130805)
			(xy 347.201003 -312.089616) (xy 347.171537 -312.043767) (xy 347.148897 -311.994191) (xy 347.133542 -311.941897)
			(xy 347.125786 -311.887951) (xy 347.125786 -311.833449) (xy 347.133542 -311.779503) (xy 347.148897 -311.727209)
			(xy 347.171537 -311.677633) (xy 347.201003 -311.631784) (xy 347.236693 -311.590595) (xy 347.277882 -311.554904)
			(xy 347.323732 -311.525438) (xy 347.373308 -311.502797) (xy 347.425601 -311.487442) (xy 347.479547 -311.479686)
			(xy 347.506798 -311.479184) (xy 347.517043 -311.479272) (xy 347.537501 -311.480415) (xy 347.547692 -311.48147)
			(xy 347.556971 -311.482088) (xy 347.57495 -311.477399) (xy 347.582744 -311.472326) (xy 347.645228 -311.427368)
			(xy 347.655642 -311.41162) (xy 347.657674 -311.402476) (xy 347.664567 -311.373613) (xy 347.684196 -311.317609)
			(xy 347.710221 -311.264276) (xy 347.742286 -311.214341) (xy 347.760798 -311.191148) (xy 347.765992 -311.184182)
			(xy 347.77182 -311.167825) (xy 347.772228 -311.159144) (xy 347.772228 -311.004712) (xy 347.771883 -310.99602)
			(xy 347.766039 -310.97965) (xy 347.760798 -310.972708) (xy 347.741909 -310.948955) (xy 347.70931 -310.897763)
			(xy 347.695774 -310.8706) (xy 347.691508 -310.862713) (xy 347.678638 -310.850248) (xy 347.670628 -310.846216)
			(xy 347.642942 -310.83377) (xy 347.634755 -310.830552) (xy 347.617223 -310.82925) (xy 347.608652 -310.83123)
			(xy 347.583692 -310.837739) (xy 347.532589 -310.844745) (xy 347.506798 -310.8452) (xy 347.479547 -310.844714)
			(xy 347.425601 -310.836958) (xy 347.373308 -310.821603) (xy 347.323732 -310.798962) (xy 347.277882 -310.769496)
			(xy 347.236693 -310.733805) (xy 347.201003 -310.692616) (xy 347.171537 -310.646767) (xy 347.148897 -310.597191)
			(xy 347.133542 -310.544897) (xy 347.125786 -310.490951) (xy 347.125786 -310.436449) (xy 347.133542 -310.382503)
			(xy 347.148897 -310.330209) (xy 347.171537 -310.280633) (xy 347.201003 -310.234784) (xy 347.236693 -310.193595)
			(xy 347.277882 -310.157904) (xy 347.323732 -310.128438) (xy 347.373308 -310.105797) (xy 347.425601 -310.090442)
			(xy 347.479547 -310.082686) (xy 347.506798 -310.082184) (xy 347.533247 -310.082634) (xy 347.585638 -310.08994)
			(xy 347.636517 -310.104412) (xy 347.684911 -310.125772) (xy 347.72989 -310.153611) (xy 347.770594 -310.187395)
			(xy 347.788738 -310.206644) (xy 347.794894 -310.213006) (xy 347.810505 -310.221331) (xy 347.819218 -310.2229)
			(xy 347.848936 -310.226964) (xy 347.857857 -310.227867) (xy 347.875402 -310.224232) (xy 347.883226 -310.219852)
			(xy 347.905446 -310.206224) (xy 347.952146 -310.183061) (xy 347.976444 -310.173624) (xy 347.976698 -310.173624)
			(xy 347.98635 -310.169814) (xy 348.000828 -310.156098) (xy 348.034356 -310.07939) (xy 348.038038 -310.069768)
			(xy 348.038153 -310.049188) (xy 348.03461 -310.039512) (xy 346.856812 -307.195728) (xy 346.852126 -307.18582)
			(xy 346.83606 -307.170946) (xy 346.825824 -307.167026) (xy 346.742512 -307.13934) (xy 346.720922 -307.141626)
			(xy 346.71127 -307.147214) (xy 346.692807 -307.157856) (xy 346.653982 -307.175424) (xy 346.6338 -307.182266)
			(xy 346.62237 -307.185822) (xy 346.605352 -307.202332) (xy 346.574364 -307.289708) (xy 346.570985 -307.300962)
			(xy 346.573768 -307.324267) (xy 346.579698 -307.334412) (xy 346.595386 -307.359254) (xy 346.62158 -307.411848)
			(xy 346.641547 -307.467107) (xy 346.655022 -307.524296) (xy 346.661826 -307.582656) (xy 346.662248 -307.612034)
			(xy 346.661746 -307.643995) (xy 346.653735 -307.707413) (xy 346.637838 -307.769327) (xy 346.614306 -307.82876)
			(xy 346.583512 -307.884775) (xy 346.545939 -307.93649) (xy 346.502182 -307.983087) (xy 346.452929 -308.023832)
			(xy 346.398958 -308.058083) (xy 346.341119 -308.0853) (xy 346.280326 -308.105053) (xy 346.217536 -308.117031)
			(xy 346.15374 -308.121045) (xy 346.089944 -308.117031) (xy 346.027154 -308.105053) (xy 345.966361 -308.0853)
			(xy 345.908522 -308.058083) (xy 345.854551 -308.023832) (xy 345.805298 -307.983087) (xy 345.761541 -307.93649)
			(xy 345.723968 -307.884775) (xy 345.693174 -307.82876) (xy 345.669642 -307.769327) (xy 345.653745 -307.707413)
			(xy 345.645734 -307.643995) (xy 345.645232 -307.612034) (xy 345.645775 -307.578831) (xy 345.654426 -307.512991)
			(xy 345.671574 -307.448837) (xy 345.696926 -307.38746) (xy 345.730051 -307.329906) (xy 345.770386 -307.277152)
			(xy 345.817243 -307.230097) (xy 345.869826 -307.189542) (xy 345.927241 -307.156175) (xy 345.98851 -307.130565)
			(xy 346.052592 -307.113148) (xy 346.085414 -307.108098) (xy 346.097098 -307.106574) (xy 346.11691 -307.093366)
			(xy 346.16263 -307.012594) (xy 346.167914 -307.002176) (xy 346.169368 -306.978886) (xy 346.165424 -306.96789)
			(xy 346.16136 -306.958238) (xy 346.156613 -306.947882) (xy 346.139998 -306.932337) (xy 346.129356 -306.928266)
			(xy 346.098876 -306.918614) (xy 346.087607 -306.915674) (xy 346.064596 -306.91911) (xy 346.05468 -306.925218)
			(xy 346.029166 -306.942233) (xy 345.974841 -306.970691) (xy 345.917486 -306.992404) (xy 345.857935 -307.007056)
			(xy 345.797054 -307.014436) (xy 345.76639 -307.01488) (xy 345.734431 -307.014378) (xy 345.671018 -307.006365)
			(xy 345.609108 -306.990469) (xy 345.549679 -306.966938) (xy 345.493668 -306.936145) (xy 345.441958 -306.898574)
			(xy 345.395364 -306.854819) (xy 345.354622 -306.805569) (xy 345.320374 -306.751601) (xy 345.293159 -306.693767)
			(xy 345.273408 -306.632977) (xy 345.261431 -306.570192) (xy 345.257417 -306.5064) (xy 345.261431 -306.442608)
			(xy 345.273408 -306.379823) (xy 345.293159 -306.319033) (xy 345.320374 -306.261199) (xy 345.354622 -306.207231)
			(xy 345.395364 -306.157981) (xy 345.441958 -306.114226) (xy 345.493668 -306.076655) (xy 345.549679 -306.045862)
			(xy 345.609108 -306.022331) (xy 345.671018 -306.006435) (xy 345.734431 -305.998422) (xy 345.76639 -305.997864)
			(xy 345.797195 -305.998308) (xy 345.858354 -306.005741) (xy 345.918167 -306.020511) (xy 345.975757 -306.042402)
			(xy 346.030278 -306.071093) (xy 346.080932 -306.106163) (xy 346.126976 -306.147098) (xy 346.167735 -306.193298)
			(xy 346.202611 -306.244086) (xy 346.231094 -306.298716) (xy 346.252765 -306.356389) (xy 346.26042 -306.38623)
			(xy 346.263431 -306.396386) (xy 346.276291 -306.41319) (xy 346.285312 -306.418742) (xy 346.361004 -306.460144)
			(xy 346.382086 -306.461922) (xy 346.392246 -306.458366) (xy 346.421964 -306.449476) (xy 346.422472 -306.449476)
			(xy 346.43314 -306.446682) (xy 346.449904 -306.432966) (xy 346.489274 -306.35448) (xy 346.493738 -306.344476)
			(xy 346.494546 -306.322608) (xy 346.490798 -306.312316) (xy 343.83472 -299.899324) (xy 343.820761 -299.864039)
			(xy 343.801092 -299.790751) (xy 343.791154 -299.715523) (xy 343.790524 -299.677582) (xy 343.790524 -296.46372)
			(xy 343.790982 -296.43193) (xy 343.798 -296.368738) (xy 343.811898 -296.306695) (xy 343.832509 -296.246548)
			(xy 343.845642 -296.217594) (xy 343.850468 -296.207434) (xy 343.850468 -295.899586) (xy 343.850042 -295.889518)
			(xy 343.84232 -295.87092) (xy 343.835482 -295.863518) (xy 343.357454 -295.38549) (xy 343.353898 -295.374822)
			(xy 343.344754 -295.351454) (xy 343.339166 -295.34485) (xy 343.323833 -295.326299) (xy 343.298598 -295.285318)
			(xy 343.280103 -295.240887) (xy 343.268804 -295.194106) (xy 343.264982 -295.146131) (xy 343.268732 -295.098151)
			(xy 343.27996 -295.051352) (xy 343.298388 -295.006893) (xy 343.323561 -294.965875) (xy 343.338912 -294.94734)
			(xy 343.344754 -294.940736) (xy 343.35466 -294.915082) (xy 343.355906 -294.911196) (xy 343.357312 -294.903158)
			(xy 343.357454 -294.89908) (xy 343.357454 -294.710612) (xy 343.356813 -294.698056) (xy 343.344956 -294.675923)
			(xy 343.334848 -294.668448) (xy 343.297256 -294.643302) (xy 343.265506 -294.62222) (xy 343.260283 -294.619002)
			(xy 343.248728 -294.614896) (xy 343.242646 -294.614092) (xy 343.230708 -294.612822) (xy 343.218516 -294.617902)
			(xy 343.190416 -294.628812) (xy 343.131304 -294.640579) (xy 343.101168 -294.64127) (xy 343.098882 -294.64127)
			(xy 343.075011 -294.640627) (xy 343.027901 -294.632835) (xy 342.982579 -294.617802) (xy 342.94015 -294.595897)
			(xy 342.901649 -294.567652) (xy 342.868015 -294.533758) (xy 342.840068 -294.49504) (xy 342.818491 -294.452443)
			(xy 342.803809 -294.407006) (xy 342.79638 -294.359837) (xy 342.79586 -294.335962) (xy 342.796333 -294.311972)
			(xy 342.803844 -294.264583) (xy 342.818674 -294.218952) (xy 342.840459 -294.176202) (xy 342.868663 -294.137386)
			(xy 342.902591 -294.103459) (xy 342.941407 -294.075256) (xy 342.984157 -294.053472) (xy 343.029789 -294.038643)
			(xy 343.077178 -294.031133) (xy 343.101168 -294.030654) (xy 343.102184 -294.030654) (xy 343.131998 -294.031469)
			(xy 343.190458 -294.043232) (xy 343.218262 -294.054022) (xy 343.218516 -294.054022) (xy 343.224458 -294.056324)
			(xy 343.23705 -294.058252) (xy 343.243408 -294.057832) (xy 343.255092 -294.056562) (xy 343.33561 -294.003222)
			(xy 343.343105 -293.997478) (xy 343.353666 -293.981843) (xy 343.356184 -293.972742) (xy 343.357454 -293.961566)
			(xy 343.357454 -293.765478) (xy 343.353898 -293.755064) (xy 343.335637 -293.737049) (xy 343.304627 -293.696191)
			(xy 343.28064 -293.650852) (xy 343.264308 -293.602229) (xy 343.256061 -293.551603) (xy 343.2556 -293.525956)
			(xy 343.256083 -293.500274) (xy 343.264357 -293.44958) (xy 343.280728 -293.400895) (xy 343.304765 -293.355502)
			(xy 343.335833 -293.314599) (xy 343.354152 -293.296594) (xy 343.355676 -293.292022) (xy 343.357454 -293.27856)
			(xy 343.357454 -293.0906) (xy 343.356811 -293.078045) (xy 343.34495 -293.055917) (xy 343.334848 -293.048436)
			(xy 343.297256 -293.02329) (xy 343.265506 -293.002208) (xy 343.260285 -292.998985) (xy 343.24873 -292.994872)
			(xy 343.242646 -292.99408) (xy 343.230708 -292.99281) (xy 343.218516 -292.99789) (xy 343.190415 -293.008797)
			(xy 343.131304 -293.02056) (xy 343.101168 -293.021258) (xy 343.098882 -293.021258) (xy 343.075011 -293.020615)
			(xy 343.027902 -293.012823) (xy 342.982581 -292.99779) (xy 342.940152 -292.975884) (xy 342.901652 -292.94764)
			(xy 342.868019 -292.913745) (xy 342.840074 -292.875027) (xy 342.818498 -292.83243) (xy 342.803818 -292.786993)
			(xy 342.796391 -292.739825) (xy 342.79586 -292.71595) (xy 342.796334 -292.69196) (xy 342.803846 -292.644573)
			(xy 342.818678 -292.598944) (xy 342.840464 -292.556195) (xy 342.868667 -292.517381) (xy 342.902595 -292.483456)
			(xy 342.941411 -292.455254) (xy 342.98416 -292.433471) (xy 343.02979 -292.418642) (xy 343.077178 -292.411133)
			(xy 343.101168 -292.410642) (xy 343.102184 -292.410642) (xy 343.131997 -292.411458) (xy 343.190457 -292.423223)
			(xy 343.218262 -292.43401) (xy 343.218516 -292.43401) (xy 343.224458 -292.436313) (xy 343.23705 -292.438241)
			(xy 343.243408 -292.43782) (xy 343.255092 -292.43655) (xy 343.33561 -292.38321) (xy 343.343104 -292.377465)
			(xy 343.353661 -292.361829) (xy 343.356184 -292.35273) (xy 343.357454 -292.341554) (xy 343.357454 -292.145466)
			(xy 343.353898 -292.135052) (xy 343.335638 -292.117037) (xy 343.30463 -292.076178) (xy 343.280644 -292.03084)
			(xy 343.264314 -291.982216) (xy 343.256069 -291.931591) (xy 343.2556 -291.905944) (xy 343.256084 -291.880262)
			(xy 343.264359 -291.82957) (xy 343.280732 -291.780886) (xy 343.30477 -291.735494) (xy 343.335838 -291.694593)
			(xy 343.354152 -291.676582) (xy 343.355676 -291.67201) (xy 343.357454 -291.658548) (xy 343.357454 -291.470588)
			(xy 343.356808 -291.458035) (xy 343.344945 -291.435911) (xy 343.334848 -291.428424) (xy 343.297256 -291.403278)
			(xy 343.265506 -291.382196) (xy 343.260285 -291.378974) (xy 343.24873 -291.374861) (xy 343.242646 -291.374068)
			(xy 343.230708 -291.372798) (xy 343.218516 -291.377878) (xy 343.190415 -291.388785) (xy 343.131304 -291.400549)
			(xy 343.101168 -291.401246) (xy 343.098882 -291.401246) (xy 343.075012 -291.400603) (xy 343.027903 -291.39281)
			(xy 342.982582 -291.377778) (xy 342.940155 -291.355872) (xy 342.901656 -291.327627) (xy 342.868024 -291.293732)
			(xy 342.84008 -291.255014) (xy 342.818506 -291.212417) (xy 342.803827 -291.166981) (xy 342.796402 -291.119813)
			(xy 342.79586 -291.095938) (xy 342.796303 -291.071942) (xy 342.803805 -291.02454) (xy 342.81863 -290.978895)
			(xy 342.840413 -290.936132) (xy 342.868617 -290.897302) (xy 342.902549 -290.863363) (xy 342.941372 -290.835149)
			(xy 342.98413 -290.813357) (xy 343.029772 -290.798521) (xy 343.077172 -290.791009) (xy 343.101168 -290.79063)
			(xy 343.102184 -290.79063) (xy 343.131997 -290.791446) (xy 343.190457 -290.803211) (xy 343.218262 -290.813998)
			(xy 343.218516 -290.813998) (xy 343.224458 -290.816301) (xy 343.23705 -290.81823) (xy 343.243408 -290.817808)
			(xy 343.255092 -290.816538) (xy 343.33561 -290.763198) (xy 343.343103 -290.757452) (xy 343.353656 -290.741816)
			(xy 343.356184 -290.732718) (xy 343.357454 -290.721542) (xy 343.357454 -290.525454) (xy 343.353898 -290.51504)
			(xy 343.335638 -290.497025) (xy 343.304632 -290.456166) (xy 343.280648 -290.410827) (xy 343.264319 -290.362204)
			(xy 343.256076 -290.311578) (xy 343.2556 -290.285932) (xy 343.256085 -290.26025) (xy 343.264362 -290.209559)
			(xy 343.280736 -290.160876) (xy 343.304775 -290.115486) (xy 343.335844 -290.074586) (xy 343.354152 -290.05657)
			(xy 343.355676 -290.051998) (xy 343.357454 -290.038536) (xy 343.357454 -289.850576) (xy 343.356805 -289.838024)
			(xy 343.344939 -289.815905) (xy 343.334848 -289.808412) (xy 343.297256 -289.783266) (xy 343.265506 -289.762184)
			(xy 343.260284 -289.758963) (xy 343.248729 -289.754851) (xy 343.242646 -289.754056) (xy 343.230708 -289.752786)
			(xy 343.218516 -289.757866) (xy 343.190415 -289.768774) (xy 343.131304 -289.780538) (xy 343.101168 -289.781234)
			(xy 343.098882 -289.781234) (xy 343.075009 -289.780591) (xy 343.027895 -289.772799) (xy 342.982569 -289.757768)
			(xy 342.940135 -289.735863) (xy 342.901629 -289.70762) (xy 342.867989 -289.673726) (xy 342.840035 -289.635009)
			(xy 342.81845 -289.592412) (xy 342.803759 -289.546974) (xy 342.796321 -289.499803) (xy 342.79586 -289.475926)
			(xy 342.796329 -289.451933) (xy 342.803831 -289.404536) (xy 342.818656 -289.358896) (xy 342.840438 -289.316138)
			(xy 342.86864 -289.277313) (xy 342.902569 -289.243378) (xy 342.941388 -289.215168) (xy 342.984143 -289.193378)
			(xy 343.029779 -289.178545) (xy 343.077175 -289.171033) (xy 343.101168 -289.170618) (xy 343.102184 -289.170618)
			(xy 343.131997 -289.171434) (xy 343.190457 -289.183198) (xy 343.218262 -289.193986) (xy 343.218516 -289.193986)
			(xy 343.224458 -289.196286) (xy 343.23705 -289.198212) (xy 343.243408 -289.197796) (xy 343.255092 -289.196526)
			(xy 343.33561 -289.143186) (xy 343.343101 -289.137439) (xy 343.353652 -289.121802) (xy 343.356184 -289.112706)
			(xy 343.357454 -289.10153) (xy 343.357454 -288.905442) (xy 343.353898 -288.895028) (xy 343.335639 -288.877013)
			(xy 343.304634 -288.836153) (xy 343.280652 -288.790814) (xy 343.264325 -288.742191) (xy 343.256084 -288.691566)
			(xy 343.2556 -288.66592) (xy 343.256086 -288.640239) (xy 343.264365 -288.589548) (xy 343.28074 -288.540867)
			(xy 343.30478 -288.495478) (xy 343.33585 -288.45458) (xy 343.354152 -288.436558) (xy 343.355676 -288.431986)
			(xy 343.357454 -288.418524) (xy 343.357454 -288.230818) (xy 343.356815 -288.218261) (xy 343.344959 -288.196126)
			(xy 343.334848 -288.188654) (xy 343.297256 -288.163508) (xy 343.265506 -288.142426) (xy 343.260283 -288.139208)
			(xy 343.248728 -288.135101) (xy 343.242646 -288.134298) (xy 343.230708 -288.133028) (xy 343.218516 -288.138108)
			(xy 343.190416 -288.149017) (xy 343.131304 -288.160784) (xy 343.101168 -288.161476) (xy 343.098882 -288.161476)
			(xy 343.075011 -288.160833) (xy 343.0279 -288.153041) (xy 342.982578 -288.138008) (xy 342.940148 -288.116103)
			(xy 342.901647 -288.087859) (xy 342.868012 -288.053964) (xy 342.840065 -288.015246) (xy 342.818487 -287.972649)
			(xy 342.803804 -287.927212) (xy 342.796374 -287.880043) (xy 342.79586 -287.856168) (xy 342.796333 -287.832178)
			(xy 342.803843 -287.784788) (xy 342.818673 -287.739156) (xy 342.840457 -287.696405) (xy 342.868661 -287.657589)
			(xy 342.902589 -287.623661) (xy 342.941405 -287.595457) (xy 342.984156 -287.573673) (xy 343.029788 -287.558843)
			(xy 343.077178 -287.551333) (xy 343.101168 -287.55086) (xy 343.101422 -287.55086) (xy 343.131149 -287.551568)
			(xy 343.189477 -287.563084) (xy 343.217246 -287.57372) (xy 343.218262 -287.574228) (xy 343.219786 -287.574736)
			(xy 343.225882 -287.576514) (xy 343.235444 -287.57847) (xy 343.254766 -287.575843) (xy 343.263474 -287.571434)
			(xy 343.32037 -287.533588) (xy 343.334848 -287.523936) (xy 343.339703 -287.520494) (xy 343.347791 -287.511769)
			(xy 343.35085 -287.506664) (xy 343.353903 -287.500899) (xy 343.357244 -287.488293) (xy 343.357454 -287.481772)
			(xy 343.357454 -287.28543) (xy 343.353898 -287.275016) (xy 343.33564 -287.257) (xy 343.304637 -287.216141)
			(xy 343.280656 -287.170801) (xy 343.264331 -287.122178) (xy 343.256092 -287.071554) (xy 343.2556 -287.045908)
			(xy 343.256087 -287.020227) (xy 343.264367 -286.969538) (xy 343.280744 -286.920858) (xy 343.304785 -286.87547)
			(xy 343.335856 -286.834573) (xy 343.354152 -286.816546) (xy 343.355676 -286.811974) (xy 343.357454 -286.798512)
			(xy 343.357454 -286.610806) (xy 343.356812 -286.598251) (xy 343.344953 -286.57612) (xy 343.334848 -286.568642)
			(xy 343.297256 -286.543496) (xy 343.265506 -286.522414) (xy 343.260285 -286.519191) (xy 343.24873 -286.515077)
			(xy 343.242646 -286.514286) (xy 343.230708 -286.513016) (xy 343.218516 -286.518096) (xy 343.190416 -286.529006)
			(xy 343.131304 -286.540773) (xy 343.101168 -286.541464) (xy 343.098882 -286.541464) (xy 343.075011 -286.540821)
			(xy 343.027902 -286.533029) (xy 342.98258 -286.517996) (xy 342.940151 -286.496091) (xy 342.90165 -286.467846)
			(xy 342.868017 -286.433951) (xy 342.840071 -286.395233) (xy 342.818494 -286.352636) (xy 342.803813 -286.3072)
			(xy 342.796385 -286.260031) (xy 342.79586 -286.236156) (xy 342.796334 -286.212166) (xy 342.803845 -286.164778)
			(xy 342.818676 -286.119148) (xy 342.840462 -286.076399) (xy 342.868665 -286.037584) (xy 342.902593 -286.003657)
			(xy 342.941409 -285.975455) (xy 342.984159 -285.953672) (xy 343.02979 -285.938842) (xy 343.077178 -285.931333)
			(xy 343.101168 -285.930848) (xy 343.101422 -285.930848) (xy 343.131149 -285.931556) (xy 343.189477 -285.943072)
			(xy 343.217246 -285.953708) (xy 343.218262 -285.954216) (xy 343.219786 -285.954724) (xy 343.225882 -285.956502)
			(xy 343.235444 -285.958457) (xy 343.254767 -285.955834) (xy 343.263474 -285.951422) (xy 343.32037 -285.913576)
			(xy 343.334848 -285.903924) (xy 343.339702 -285.900482) (xy 343.347789 -285.891755) (xy 343.35085 -285.886652)
			(xy 343.353901 -285.880886) (xy 343.35724 -285.86828) (xy 343.357454 -285.86176) (xy 343.357454 -285.665672)
			(xy 343.353898 -285.655258) (xy 343.335671 -285.637281) (xy 343.304711 -285.596513) (xy 343.280743 -285.55128)
			(xy 343.264397 -285.502768) (xy 343.256102 -285.452253) (xy 343.2556 -285.426658) (xy 343.2556 -285.42615)
			(xy 343.256159 -285.399011) (xy 343.265434 -285.345531) (xy 343.283717 -285.294426) (xy 343.310472 -285.2472)
			(xy 343.344909 -285.205245) (xy 343.386014 -285.169799) (xy 343.409016 -285.155386) (xy 343.418668 -285.147766)
			(xy 343.75471 -284.811724) (xy 343.760085 -284.805971) (xy 343.767318 -284.791998) (xy 343.768934 -284.784292)
			(xy 343.76995 -284.777434) (xy 343.756033 -284.752852) (xy 343.736218 -284.699959) (xy 343.726128 -284.644385)
			(xy 343.7255 -284.616144) (xy 343.725959 -284.591337) (xy 343.733718 -284.542332) (xy 343.749051 -284.495146)
			(xy 343.77158 -284.450942) (xy 343.800751 -284.410808) (xy 343.835844 -284.375735) (xy 343.875994 -284.346587)
			(xy 343.920211 -284.324082) (xy 343.967406 -284.308776) (xy 344.016414 -284.301045) (xy 344.041222 -284.300676)
			(xy 344.066679 -284.301173) (xy 344.116939 -284.309304) (xy 344.165246 -284.325386) (xy 344.188034 -284.336744)
			(xy 344.195503 -284.340305) (xy 344.211833 -284.342894) (xy 344.220038 -284.341824) (xy 344.225372 -284.341062)
			(xy 344.35288 -284.213554) (xy 344.357452 -284.208474) (xy 344.358722 -284.206696) (xy 344.363344 -284.199552)
			(xy 344.368015 -284.1832) (xy 344.367866 -284.174692) (xy 344.361516 -284.109414) (xy 344.3605 -284.105096)
			(xy 344.35161 -284.070806) (xy 344.3478 -284.064456) (xy 344.341704 -284.060138) (xy 344.321439 -284.04605)
			(xy 344.285323 -284.012413) (xy 344.255089 -283.973405) (xy 344.231525 -283.930041) (xy 344.215243 -283.883451)
			(xy 344.206669 -283.834849) (xy 344.206025 -283.7855) (xy 344.213329 -283.73669) (xy 344.22839 -283.689691)
			(xy 344.250816 -283.645728) (xy 344.280022 -283.605945) (xy 344.315249 -283.571378) (xy 344.3351 -283.55671)
			(xy 344.342213 -283.55121) (xy 344.352353 -283.536375) (xy 344.354912 -283.527754) (xy 344.367229 -283.481375)
			(xy 344.398673 -283.390704) (xy 344.437683 -283.303023) (xy 344.48398 -283.218961) (xy 344.537231 -283.139122)
			(xy 344.566748 -283.101288) (xy 344.571864 -283.094365) (xy 344.577582 -283.078139) (xy 344.577924 -283.069538)
			(xy 344.577924 -282.922726) (xy 344.577588 -282.914123) (xy 344.571876 -282.897892) (xy 344.566748 -282.890976)
			(xy 344.539457 -282.85605) (xy 344.489797 -282.782625) (xy 344.446038 -282.705536) (xy 344.40845 -282.625257)
			(xy 344.377263 -282.542281) (xy 344.364564 -282.499816) (xy 344.361505 -282.490673) (xy 344.349754 -282.475405)
			(xy 344.341704 -282.470098) (xy 344.319385 -282.456195) (xy 344.27906 -282.422454) (xy 344.244581 -282.382757)
			(xy 344.21682 -282.338103) (xy 344.196474 -282.28962) (xy 344.184057 -282.238527) (xy 344.179881 -282.186113)
			(xy 344.184052 -282.133699) (xy 344.196465 -282.082606) (xy 344.216807 -282.03412) (xy 344.244566 -281.989465)
			(xy 344.279041 -281.949765) (xy 344.319363 -281.91602) (xy 344.341704 -281.902154) (xy 344.349787 -281.896882)
			(xy 344.361544 -281.881601) (xy 344.364564 -281.872436) (xy 344.380092 -281.820928) (xy 344.419649 -281.720875)
			(xy 344.468539 -281.625037) (xy 344.496898 -281.57932) (xy 344.500708 -281.573224) (xy 344.504772 -281.559508)
			(xy 344.504772 -281.200098) (xy 344.504526 -281.192916) (xy 344.500531 -281.17912) (xy 344.496898 -281.17292)
			(xy 344.486059 -281.155724) (xy 344.46548 -281.120663) (xy 344.45575 -281.102816) (xy 344.452194 -281.096212)
			(xy 344.11412 -280.758138) (xy 344.107281 -280.750737) (xy 344.099566 -280.732139) (xy 344.099134 -280.72207)
			(xy 344.099134 -280.483564) (xy 344.098776 -280.475145) (xy 344.09332 -280.459212) (xy 344.088466 -280.452322)
			(xy 344.088212 -280.452068) (xy 344.062395 -280.418657) (xy 344.01527 -280.348586) (xy 343.973531 -280.27518)
			(xy 343.955116 -280.237184) (xy 343.951306 -280.22931) (xy 343.703148 -279.981152) (xy 343.696304 -279.973753)
			(xy 343.688579 -279.955154) (xy 343.688162 -279.945084) (xy 343.688162 -279.475184) (xy 343.68859 -279.465116)
			(xy 343.696315 -279.446522) (xy 343.703148 -279.439116) (xy 344.113104 -279.02916) (xy 344.115898 -279.026112)
			(xy 344.134064 -279.005042) (xy 344.172181 -278.96451) (xy 344.192098 -278.945086) (xy 344.198266 -278.938661)
			(xy 344.206065 -278.92266) (xy 344.207338 -278.913844) (xy 344.210632 -278.88806) (xy 344.224842 -278.838063)
			(xy 344.247302 -278.791188) (xy 344.277364 -278.748787) (xy 344.314162 -278.712078) (xy 344.3351 -278.696674)
			(xy 344.34222 -278.691178) (xy 344.352378 -278.676348) (xy 344.354912 -278.667718) (xy 344.366277 -278.624752)
			(xy 344.394876 -278.540596) (xy 344.429991 -278.458944) (xy 344.471406 -278.380299) (xy 344.518866 -278.305148)
			(xy 344.572077 -278.233953) (xy 344.630712 -278.167155) (xy 344.662252 -278.135842) (xy 344.668356 -278.129396)
			(xy 344.676022 -278.113395) (xy 344.677238 -278.1046) (xy 344.680293 -278.079894) (xy 344.693381 -278.031865)
			(xy 344.71407 -277.986589) (xy 344.741814 -277.945258) (xy 344.758518 -277.9268) (xy 344.765122 -277.920196)
			(xy 344.77579 -277.89378) (xy 344.777542 -277.889213) (xy 344.779456 -277.87962) (xy 344.7796 -277.87473)
			(xy 344.7796 -276.77745) (xy 344.779463 -276.772559) (xy 344.777546 -276.762967) (xy 344.77579 -276.7584)
			(xy 344.765122 -276.731984) (xy 344.758518 -276.72538) (xy 344.741335 -276.706349) (xy 344.712935 -276.663663)
			(xy 344.69206 -276.616835) (xy 344.679297 -276.567179) (xy 344.675003 -276.516088) (xy 344.679301 -276.464998)
			(xy 344.692068 -276.415343) (xy 344.712946 -276.368516) (xy 344.74135 -276.325833) (xy 344.758518 -276.306788)
			(xy 344.765122 -276.300184) (xy 344.77579 -276.273768) (xy 344.777541 -276.2692) (xy 344.779453 -276.259608)
			(xy 344.7796 -276.254718) (xy 344.7796 -276.077172) (xy 344.778838 -276.06879) (xy 344.777243 -276.060831)
			(xy 344.769725 -276.046454) (xy 344.764106 -276.040596) (xy 344.756232 -276.0345) (xy 344.68435 -275.988018)
			(xy 344.679005 -275.984802) (xy 344.667183 -275.980829) (xy 344.660982 -275.980144) (xy 344.648282 -275.979128)
			(xy 344.636344 -275.984462) (xy 344.616577 -275.992972) (xy 344.575247 -276.004968) (xy 344.53264 -276.01102)
			(xy 344.511122 -276.011386) (xy 344.485865 -276.010895) (xy 344.436039 -276.002584) (xy 344.388261 -275.986185)
			(xy 344.343834 -275.962145) (xy 344.30397 -275.93112) (xy 344.269757 -275.893957) (xy 344.242127 -275.851669)
			(xy 344.221835 -275.80541) (xy 344.209434 -275.756442) (xy 344.205262 -275.7061) (xy 344.209434 -275.655758)
			(xy 344.221835 -275.60679) (xy 344.242127 -275.560531) (xy 344.269757 -275.518243) (xy 344.30397 -275.48108)
			(xy 344.343834 -275.450055) (xy 344.388261 -275.426015) (xy 344.436039 -275.409616) (xy 344.485865 -275.401305)
			(xy 344.511122 -275.40077) (xy 344.532637 -275.401163) (xy 344.575235 -275.407242) (xy 344.616564 -275.41922)
			(xy 344.636344 -275.427694) (xy 344.642249 -275.430153) (xy 344.654848 -275.43234) (xy 344.661236 -275.432012)
			(xy 344.673682 -275.430996) (xy 344.756232 -275.377656) (xy 344.764106 -275.37156) (xy 344.769713 -275.365693)
			(xy 344.777226 -275.351319) (xy 344.778838 -275.343366) (xy 344.7796 -275.334984) (xy 344.7796 -275.157438)
			(xy 344.779462 -275.152548) (xy 344.777542 -275.142956) (xy 344.77579 -275.138388) (xy 344.765122 -275.111972)
			(xy 344.758518 -275.105368) (xy 344.741336 -275.086337) (xy 344.712938 -275.043652) (xy 344.692065 -274.996824)
			(xy 344.679303 -274.947169) (xy 344.675012 -274.89608) (xy 344.67931 -274.844991) (xy 344.692078 -274.795338)
			(xy 344.712957 -274.748513) (xy 344.741362 -274.705831) (xy 344.758518 -274.686776) (xy 344.765122 -274.680172)
			(xy 344.77579 -274.653756) (xy 344.77754 -274.649188) (xy 344.77945 -274.639596) (xy 344.7796 -274.634706)
			(xy 344.7796 -273.537426) (xy 344.779461 -273.532536) (xy 344.777539 -273.522945) (xy 344.77579 -273.518376)
			(xy 344.765122 -273.49196) (xy 344.758518 -273.485356) (xy 344.741337 -273.466325) (xy 344.712941 -273.42364)
			(xy 344.69207 -273.376813) (xy 344.67931 -273.327159) (xy 344.67502 -273.276071) (xy 344.67932 -273.224984)
			(xy 344.692089 -273.175332) (xy 344.712969 -273.128509) (xy 344.741373 -273.085829) (xy 344.758518 -273.066764)
			(xy 344.765122 -273.06016) (xy 344.77579 -273.033744) (xy 344.777548 -273.029178) (xy 344.779474 -273.019585)
			(xy 344.7796 -273.014694) (xy 344.7796 -272.837148) (xy 344.778838 -272.828766) (xy 344.77724 -272.820809)
			(xy 344.769717 -272.806437) (xy 344.764106 -272.800572) (xy 344.756232 -272.794476) (xy 344.68435 -272.747994)
			(xy 344.679004 -272.744779) (xy 344.667183 -272.740807) (xy 344.660982 -272.74012) (xy 344.648282 -272.739104)
			(xy 344.636344 -272.744438) (xy 344.616577 -272.752949) (xy 344.575248 -272.764945) (xy 344.53264 -272.770998)
			(xy 344.511122 -272.771362) (xy 344.485867 -272.770871) (xy 344.436045 -272.762561) (xy 344.388271 -272.746163)
			(xy 344.343847 -272.722125) (xy 344.303986 -272.691103) (xy 344.269775 -272.653942) (xy 344.242148 -272.611657)
			(xy 344.221857 -272.565402) (xy 344.209457 -272.516438) (xy 344.205286 -272.4661) (xy 344.209457 -272.415762)
			(xy 344.221857 -272.366798) (xy 344.242148 -272.320543) (xy 344.269775 -272.278258) (xy 344.303986 -272.241097)
			(xy 344.343847 -272.210075) (xy 344.388271 -272.186037) (xy 344.436045 -272.169639) (xy 344.485867 -272.161329)
			(xy 344.511122 -272.160746) (xy 344.532636 -272.16114) (xy 344.575234 -272.16722) (xy 344.616563 -272.179201)
			(xy 344.636344 -272.18767) (xy 344.642255 -272.190109) (xy 344.654849 -272.192292) (xy 344.661236 -272.191988)
			(xy 344.673682 -272.190972) (xy 344.756232 -272.137632) (xy 344.764106 -272.131536) (xy 344.76971 -272.125668)
			(xy 344.777217 -272.111293) (xy 344.778838 -272.103342) (xy 344.7796 -272.09496) (xy 344.7796 -271.917414)
			(xy 344.77946 -271.912524) (xy 344.777536 -271.902934) (xy 344.77579 -271.898364) (xy 344.765122 -271.871948)
			(xy 344.758518 -271.865344) (xy 344.741329 -271.846313) (xy 344.712918 -271.803625) (xy 344.692033 -271.756794)
			(xy 344.679261 -271.707132) (xy 344.674959 -271.656035) (xy 344.679249 -271.604937) (xy 344.69201 -271.555273)
			(xy 344.712885 -271.508436) (xy 344.741286 -271.465742) (xy 344.758518 -271.446752) (xy 344.765122 -271.440148)
			(xy 344.77579 -271.413732) (xy 344.777547 -271.409165) (xy 344.779471 -271.399573) (xy 344.7796 -271.394682)
			(xy 344.7796 -270.383) (xy 344.77452 -270.37792) (xy 344.77452 -270.281908) (xy 344.774266 -270.277844)
			(xy 344.77328 -270.269656) (xy 344.766795 -270.254504) (xy 344.761566 -270.248126) (xy 344.743815 -270.229015)
			(xy 344.714448 -270.185912) (xy 344.692838 -270.138443) (xy 344.679613 -270.087992) (xy 344.675159 -270.036026)
			(xy 344.679604 -269.98406) (xy 344.692821 -269.933606) (xy 344.714423 -269.886134) (xy 344.743782 -269.843025)
			(xy 344.761566 -269.823946) (xy 344.766816 -269.817583) (xy 344.773289 -269.80242) (xy 344.774266 -269.794228)
			(xy 344.77452 -269.790164) (xy 344.77452 -269.59941) (xy 344.773849 -269.586764) (xy 344.76186 -269.564495)
			(xy 344.75166 -269.556992) (xy 344.680794 -269.510256) (xy 344.675339 -269.506944) (xy 344.66326 -269.502843)
			(xy 344.656918 -269.502128) (xy 344.644472 -269.501112) (xy 344.632788 -269.506192) (xy 344.63228 -269.506192)
			(xy 344.613118 -269.514119) (xy 344.573188 -269.525301) (xy 344.532109 -269.530963) (xy 344.511376 -269.531338)
			(xy 344.50655 -269.531338) (xy 344.482795 -269.530531) (xy 344.435955 -269.522465) (xy 344.39093 -269.507238)
			(xy 344.34881 -269.485217) (xy 344.310612 -269.456933) (xy 344.277259 -269.423071) (xy 344.249557 -269.38445)
			(xy 344.228175 -269.342001) (xy 344.213631 -269.296752) (xy 344.206276 -269.249795) (xy 344.205814 -269.22603)
			(xy 344.206258 -269.202036) (xy 344.213761 -269.154638) (xy 344.228587 -269.108998) (xy 344.250371 -269.066239)
			(xy 344.278577 -269.027415) (xy 344.312509 -268.993482) (xy 344.351332 -268.965276) (xy 344.39409 -268.94349)
			(xy 344.43973 -268.928663) (xy 344.487128 -268.921159) (xy 344.511122 -268.920722) (xy 344.511376 -268.920722)
			(xy 344.532108 -268.921106) (xy 344.573183 -268.926781) (xy 344.613116 -268.93795) (xy 344.63228 -268.945868)
			(xy 344.632788 -268.945868) (xy 344.633042 -268.946122) (xy 344.638735 -268.948359) (xy 344.650811 -268.950287)
			(xy 344.656918 -268.949932) (xy 344.669872 -268.948916) (xy 344.75166 -268.895068) (xy 344.761852 -268.887553)
			(xy 344.773861 -268.865295) (xy 344.77452 -268.85265) (xy 344.77452 -268.661896) (xy 344.774266 -268.657832)
			(xy 344.773293 -268.649638) (xy 344.766827 -268.634469) (xy 344.761566 -268.628114) (xy 344.743816 -268.609003)
			(xy 344.714451 -268.5659) (xy 344.692843 -268.518432) (xy 344.67962 -268.467982) (xy 344.675167 -268.416017)
			(xy 344.679614 -268.364052) (xy 344.692831 -268.3136) (xy 344.714434 -268.26613) (xy 344.743794 -268.223024)
			(xy 344.761566 -268.203934) (xy 344.766815 -268.19757) (xy 344.773284 -268.182407) (xy 344.774266 -268.174216)
			(xy 344.77452 -268.170152) (xy 344.77452 -267.979398) (xy 344.773846 -267.966754) (xy 344.761855 -267.944489)
			(xy 344.75166 -267.93698) (xy 344.680794 -267.890244) (xy 344.675339 -267.886933) (xy 344.66326 -267.882833)
			(xy 344.656918 -267.882116) (xy 344.644472 -267.8811) (xy 344.632788 -267.88618) (xy 344.63228 -267.88618)
			(xy 344.613119 -267.894107) (xy 344.573188 -267.90529) (xy 344.532109 -267.910952) (xy 344.511376 -267.911326)
			(xy 344.50655 -267.911326) (xy 344.482795 -267.910519) (xy 344.435956 -267.902453) (xy 344.390932 -267.887226)
			(xy 344.348813 -267.865204) (xy 344.310616 -267.836921) (xy 344.277264 -267.803059) (xy 344.249563 -267.764437)
			(xy 344.228183 -267.721988) (xy 344.213641 -267.676739) (xy 344.206287 -267.629783) (xy 344.205814 -267.606018)
			(xy 344.206259 -267.582025) (xy 344.213763 -267.534628) (xy 344.228591 -267.48899) (xy 344.250375 -267.446232)
			(xy 344.278581 -267.40741) (xy 344.312513 -267.373479) (xy 344.351336 -267.345273) (xy 344.394093 -267.323489)
			(xy 344.439732 -267.308663) (xy 344.487129 -267.301159) (xy 344.511122 -267.30071) (xy 344.537438 -267.301262)
			(xy 344.589291 -267.310286) (xy 344.63883 -267.328062) (xy 344.68459 -267.354066) (xy 344.725216 -267.387527)
			(xy 344.759507 -267.427455) (xy 344.786447 -267.47267) (xy 344.796364 -267.497052) (xy 344.796618 -267.49756)
			(xy 344.799012 -267.503364) (xy 344.8062 -267.513653) (xy 344.810842 -267.51788) (xy 344.815414 -267.52169)
			(xy 344.826336 -267.527024) (xy 344.863166 -267.534898) (xy 344.916506 -267.546328) (xy 344.922856 -267.547344)
			(xy 344.931434 -267.547745) (xy 344.948051 -267.543457) (xy 344.955368 -267.538962) (xy 344.962988 -267.532612)
			(xy 345.605862 -266.889738) (xy 345.610026 -266.885382) (xy 345.616311 -266.875104) (xy 345.618308 -266.869418)
			(xy 345.621864 -266.857988) (xy 345.619832 -266.845796) (xy 345.617972 -266.833817) (xy 345.615941 -266.809658)
			(xy 345.615768 -266.797536) (xy 345.615768 -266.794234) (xy 345.61637 -266.770333) (xy 345.624094 -266.723153)
			(xy 345.639077 -266.677753) (xy 345.660953 -266.635243) (xy 345.689187 -266.596662) (xy 345.723089 -266.562953)
			(xy 345.76183 -266.53494) (xy 345.804464 -266.513307) (xy 345.849948 -266.498583) (xy 345.897172 -266.491128)
			(xy 345.921076 -266.490704) (xy 345.92133 -266.490704) (xy 345.93377 -266.490827) (xy 345.958566 -266.492865)
			(xy 345.97086 -266.494768) (xy 345.983052 -266.4968) (xy 345.994482 -266.493244) (xy 346.000142 -266.491196)
			(xy 346.010401 -266.484905) (xy 346.014802 -266.480798) (xy 346.163138 -266.332462) (xy 346.1639 -266.3317)
			(xy 346.16517 -266.330176) (xy 346.170424 -266.323814) (xy 346.176905 -266.308652) (xy 346.17787 -266.300458)
			(xy 346.179394 -266.230608) (xy 346.179648 -266.217654) (xy 346.17279 -266.19962) (xy 346.165932 -266.192254)
			(xy 346.150968 -266.175282) (xy 346.125695 -266.137751) (xy 346.106233 -266.096903) (xy 346.09301 -266.053632)
			(xy 346.086313 -266.008883) (xy 346.085922 -265.98626) (xy 346.085922 -265.977624) (xy 346.087 -265.954064)
			(xy 346.095516 -265.907679) (xy 346.111066 -265.863156) (xy 346.133279 -265.821555) (xy 346.161628 -265.783866)
			(xy 346.195437 -265.750986) (xy 346.233901 -265.723699) (xy 346.276106 -265.702653) (xy 346.321045 -265.688351)
			(xy 346.367649 -265.681131) (xy 346.39123 -265.680698) (xy 346.414994 -265.681153) (xy 346.461948 -265.68852)
			(xy 346.507193 -265.703073) (xy 346.549638 -265.724459) (xy 346.588258 -265.752162) (xy 346.62212 -265.785513)
			(xy 346.650406 -265.823708) (xy 346.672434 -265.865823) (xy 346.687671 -265.910843) (xy 346.695751 -265.957679)
			(xy 346.696538 -265.981434) (xy 346.696538 -265.986514) (xy 346.696183 -266.007384) (xy 346.690468 -266.048732)
			(xy 346.679174 -266.088916) (xy 346.671138 -266.10818) (xy 346.668598 -266.114022) (xy 346.666312 -266.126722)
			(xy 346.667074 -266.132818) (xy 346.667756 -266.139019) (xy 346.671738 -266.150837) (xy 346.674948 -266.156186)
			(xy 346.7227 -266.229084) (xy 346.730166 -266.238476) (xy 346.751371 -266.24963) (xy 346.76334 -266.25042)
			(xy 347.898212 -266.25042) (xy 347.898974 -266.25042) (xy 347.910935 -266.24959) (xy 347.932133 -266.238455)
			(xy 347.939614 -266.229084) (xy 347.987366 -266.156186) (xy 347.990587 -266.150842) (xy 347.99457 -266.139022)
			(xy 347.99524 -266.132818) (xy 347.99651 -266.120118) (xy 347.991176 -266.10818) (xy 347.983254 -266.089145)
			(xy 347.972022 -266.049473) (xy 347.96623 -266.008651) (xy 347.965776 -265.988038) (xy 347.965776 -265.981434)
			(xy 347.966584 -265.95768) (xy 347.974652 -265.910843) (xy 347.989881 -265.865821) (xy 348.011903 -265.823705)
			(xy 348.040187 -265.78551) (xy 348.074049 -265.75216) (xy 348.11267 -265.724461) (xy 348.155118 -265.703083)
			(xy 348.200365 -265.688541) (xy 348.24732 -265.681188) (xy 348.271084 -265.680698) (xy 348.29703 -265.681216)
			(xy 348.348175 -265.689985) (xy 348.397102 -265.707272) (xy 348.442402 -265.732581) (xy 348.482773 -265.765183)
			(xy 348.517052 -265.80414) (xy 348.544253 -265.84833) (xy 348.563593 -265.896483) (xy 348.569534 -265.921744)
			(xy 348.569534 -265.921998) (xy 348.571261 -265.928633) (xy 348.577692 -265.940738) (xy 348.582234 -265.945874)
			(xy 348.586806 -265.9507) (xy 348.597982 -265.957812) (xy 348.690438 -265.98499) (xy 348.699271 -265.987225)
			(xy 348.717434 -265.985976) (xy 348.734009 -265.978442) (xy 348.74073 -265.97229) (xy 348.925642 -265.787378)
			(xy 348.930627 -265.781878) (xy 348.937466 -265.76871) (xy 348.939104 -265.76147) (xy 348.94012 -265.751818)
			(xy 348.94012 -264.506964) (xy 348.935294 -264.496804) (xy 348.92422 -264.47211) (xy 348.910001 -264.419897)
			(xy 348.905212 -264.365995) (xy 348.910003 -264.312093) (xy 348.924224 -264.25988) (xy 348.935294 -264.235184)
			(xy 348.94012 -264.225024) (xy 348.94012 -262.886952) (xy 348.935294 -262.876792) (xy 348.924221 -262.852098)
			(xy 348.910004 -262.799885) (xy 348.905218 -262.745984) (xy 348.91001 -262.692083) (xy 348.924232 -262.639871)
			(xy 348.935294 -262.615172) (xy 348.94012 -262.605012) (xy 348.94012 -262.382762) (xy 348.940551 -262.372695)
			(xy 348.948277 -262.354103) (xy 348.955106 -262.346694) (xy 349.362268 -261.939532) (xy 349.365365 -261.936336)
			(xy 349.370484 -261.929057) (xy 349.372428 -261.925054) (xy 349.375984 -261.917434) (xy 349.377 -261.90829)
			(xy 349.379787 -261.883322) (xy 349.392472 -261.834716) (xy 349.412942 -261.788841) (xy 349.440644 -261.746935)
			(xy 349.474832 -261.710128) (xy 349.514583 -261.679413) (xy 349.558825 -261.655619) (xy 349.606365 -261.639387)
			(xy 349.655921 -261.631155) (xy 349.681038 -261.630668) (xy 349.70691 -261.631215) (xy 349.757913 -261.63994)
			(xy 349.806716 -261.657135) (xy 349.851924 -261.682307) (xy 349.892245 -261.714736) (xy 349.926524 -261.753496)
			(xy 349.940626 -261.775194) (xy 349.947766 -261.783729) (xy 349.967401 -261.794146) (xy 349.978472 -261.79526)
			(xy 350.321118 -261.79526) (xy 350.323658 -261.79526) (xy 350.334716 -261.794098) (xy 350.354345 -261.783701)
			(xy 350.361504 -261.775194) (xy 350.374472 -261.755134) (xy 350.405639 -261.718938) (xy 350.442062 -261.688037)
			(xy 350.482853 -261.663185) (xy 350.527015 -261.644987) (xy 350.573473 -261.633887) (xy 350.621092 -261.630157)
			(xy 350.668711 -261.633887) (xy 350.715169 -261.644987) (xy 350.759331 -261.663185) (xy 350.800122 -261.688037)
			(xy 350.836545 -261.718938) (xy 350.867712 -261.755134) (xy 350.88068 -261.775194) (xy 350.887817 -261.783736)
			(xy 350.90745 -261.794171) (xy 350.918526 -261.79526) (xy 355.977952 -261.79526) (xy 355.987604 -261.794244)
			(xy 355.994844 -261.792609) (xy 356.008001 -261.785756) (xy 356.013512 -261.780782) (xy 356.169976 -261.624318)
			(xy 356.17497 -261.618822) (xy 356.181828 -261.605658) (xy 356.183438 -261.59841) (xy 356.184454 -261.588758)
			(xy 356.184454 -258.787392) (xy 356.184292 -258.781381) (xy 356.18148 -258.769693) (xy 356.178866 -258.764278)
			(xy 356.177025 -258.760805) (xy 356.172429 -258.754428) (xy 356.169722 -258.751578) (xy 355.919786 -258.501642)
			(xy 355.916935 -258.498936) (xy 355.910556 -258.494344) (xy 355.907086 -258.492498) (xy 355.90166 -258.489912)
			(xy 355.88998 -258.487082) (xy 355.883972 -258.48691) (xy 354.706428 -258.48691) (xy 354.699015 -258.487161)
			(xy 354.684814 -258.491419) (xy 354.678488 -258.495292) (xy 354.672392 -258.499356) (xy 354.662994 -258.510278)
			(xy 354.659946 -258.51739) (xy 354.649583 -258.540025) (xy 354.623289 -258.582295) (xy 354.591168 -258.620327)
			(xy 354.553892 -258.653321) (xy 354.512243 -258.680589) (xy 354.467093 -258.701557) (xy 354.419389 -258.715787)
			(xy 354.37013 -258.72298) (xy 354.34524 -258.723384) (xy 354.32 -258.722941) (xy 354.270062 -258.715561)
			(xy 354.221741 -258.700953) (xy 354.176078 -258.679431) (xy 354.134056 -258.65146) (xy 354.096579 -258.617641)
			(xy 354.064453 -258.578703) (xy 354.038371 -258.535482) (xy 354.018894 -258.488911) (xy 354.012246 -258.464558)
			(xy 354.010214 -258.45643) (xy 354.008304 -258.449805) (xy 354.001476 -258.437831) (xy 353.996752 -258.432808)
			(xy 353.887786 -258.323842) (xy 353.881065 -258.316607) (xy 353.873451 -258.298402) (xy 353.873054 -258.288536)
			(xy 353.873054 -257.441192) (xy 353.872892 -257.435181) (xy 353.87008 -257.423493) (xy 353.867466 -257.418078)
			(xy 353.865625 -257.414605) (xy 353.861029 -257.408228) (xy 353.858322 -257.405378) (xy 353.633786 -257.180842)
			(xy 353.630935 -257.178136) (xy 353.624556 -257.173544) (xy 353.621086 -257.171698) (xy 353.61566 -257.169112)
			(xy 353.60398 -257.166282) (xy 353.597972 -257.16611) (xy 348.864428 -257.16611) (xy 348.85459 -257.165574)
			(xy 348.836429 -257.157988) (xy 348.829122 -257.151378) (xy 347.969586 -256.291842) (xy 347.966735 -256.289136)
			(xy 347.960356 -256.284544) (xy 347.956886 -256.282698) (xy 347.95146 -256.280112) (xy 347.93978 -256.277282)
			(xy 347.933772 -256.27711) (xy 347.345254 -256.27711) (xy 347.343984 -256.27711) (xy 347.332159 -256.278035)
			(xy 347.31125 -256.289172) (xy 347.303852 -256.298446) (xy 347.299788 -256.304542) (xy 347.26118 -256.386076)
			(xy 347.260418 -256.387854) (xy 347.256557 -256.398245) (xy 347.257228 -256.420376) (xy 347.261688 -256.430526)
			(xy 347.26626 -256.43967) (xy 347.269816 -256.443734) (xy 347.285214 -256.463867) (xy 347.309816 -256.508179)
			(xy 347.326769 -256.555944) (xy 347.335608 -256.60585) (xy 347.336364 -256.631186) (xy 347.336364 -256.641854)
			(xy 347.335338 -256.665453) (xy 347.32691 -256.71193) (xy 347.311423 -256.756553) (xy 347.289247 -256.798258)
			(xy 347.260912 -256.83605) (xy 347.227093 -256.869026) (xy 347.188599 -256.896399) (xy 347.146348 -256.917516)
			(xy 347.101348 -256.931873) (xy 347.054673 -256.939127) (xy 347.031056 -256.939542) (xy 347.007066 -256.939068)
			(xy 346.959678 -256.931557) (xy 346.914047 -256.916726) (xy 346.871298 -256.894941) (xy 346.832483 -256.866737)
			(xy 346.798556 -256.832809) (xy 346.770354 -256.793993) (xy 346.74857 -256.751243) (xy 346.733741 -256.705613)
			(xy 346.726231 -256.658224) (xy 346.725748 -256.634234) (xy 346.726304 -256.608079) (xy 346.735267 -256.556541)
			(xy 346.752901 -256.507292) (xy 346.778689 -256.461778) (xy 346.794836 -256.441194) (xy 346.79509 -256.440686)
			(xy 346.79509 -256.440432) (xy 346.799346 -256.43485) (xy 346.804896 -256.421962) (xy 346.806012 -256.415032)
			(xy 346.806774 -256.40792) (xy 346.804742 -256.39395) (xy 346.763086 -256.30632) (xy 346.760292 -256.300986)
			(xy 346.753796 -256.291767) (xy 346.734811 -256.279645) (xy 346.723716 -256.277618) (xy 346.717112 -256.27711)
			(xy 345.4654 -256.27711) (xy 345.46413 -256.27711) (xy 345.4523 -256.278026) (xy 345.431375 -256.289152)
			(xy 345.423998 -256.298446) (xy 345.419934 -256.304542) (xy 345.381326 -256.386076) (xy 345.380564 -256.387854)
			(xy 345.376701 -256.398245) (xy 345.377373 -256.420376) (xy 345.381834 -256.430526) (xy 345.386406 -256.43967)
			(xy 345.389962 -256.443734) (xy 345.405358 -256.463868) (xy 345.429956 -256.508181) (xy 345.446906 -256.555945)
			(xy 345.455744 -256.605851) (xy 345.45651 -256.631186) (xy 345.45651 -256.641854) (xy 345.455484 -256.665452)
			(xy 345.447055 -256.711925) (xy 345.431567 -256.756545) (xy 345.409391 -256.798246) (xy 345.381054 -256.836033)
			(xy 345.347235 -256.869004) (xy 345.308741 -256.896371) (xy 345.266489 -256.917482) (xy 345.22149 -256.931831)
			(xy 345.174818 -256.939077) (xy 345.151202 -256.939542) (xy 345.12721 -256.939072) (xy 345.079816 -256.931566)
			(xy 345.034179 -256.916739) (xy 344.991424 -256.894956) (xy 344.952602 -256.866753) (xy 344.91867 -256.832825)
			(xy 344.890463 -256.794007) (xy 344.868675 -256.751254) (xy 344.853842 -256.705619) (xy 344.846331 -256.658226)
			(xy 344.845894 -256.634234) (xy 344.846449 -256.608078) (xy 344.855411 -256.55654) (xy 344.873043 -256.507289)
			(xy 344.898827 -256.461772) (xy 344.914982 -256.441194) (xy 344.915236 -256.440686) (xy 344.915236 -256.440432)
			(xy 344.919489 -256.434848) (xy 344.925034 -256.42196) (xy 344.926158 -256.415032) (xy 344.92692 -256.40792)
			(xy 344.924888 -256.39395) (xy 344.883232 -256.30632) (xy 344.880438 -256.300986) (xy 344.873945 -256.29176)
			(xy 344.854963 -256.279622) (xy 344.843862 -256.277618) (xy 344.837258 -256.27711) (xy 343.585292 -256.27711)
			(xy 343.584022 -256.27711) (xy 343.572193 -256.278027) (xy 343.551271 -256.289156) (xy 343.54389 -256.298446)
			(xy 343.539826 -256.304542) (xy 343.501218 -256.386076) (xy 343.500456 -256.387854) (xy 343.496593 -256.398245)
			(xy 343.497265 -256.420376) (xy 343.501726 -256.430526) (xy 343.506298 -256.43967) (xy 343.509854 -256.443734)
			(xy 343.525251 -256.463868) (xy 343.549849 -256.508181) (xy 343.5668 -256.555945) (xy 343.575638 -256.605851)
			(xy 343.576402 -256.631186) (xy 343.576402 -256.641854) (xy 343.575376 -256.665451) (xy 343.566947 -256.711924)
			(xy 343.551459 -256.756544) (xy 343.529282 -256.798244) (xy 343.500946 -256.836031) (xy 343.467127 -256.869001)
			(xy 343.428632 -256.896367) (xy 343.386381 -256.917477) (xy 343.341382 -256.931825) (xy 343.29471 -256.93907)
			(xy 343.271094 -256.939542) (xy 343.247102 -256.939071) (xy 343.199709 -256.931564) (xy 343.154074 -256.916737)
			(xy 343.111319 -256.894953) (xy 343.072499 -256.866751) (xy 343.038568 -256.832822) (xy 343.010361 -256.794004)
			(xy 342.988574 -256.751252) (xy 342.973742 -256.705618) (xy 342.966231 -256.658226) (xy 342.965786 -256.634234)
			(xy 342.966341 -256.608078) (xy 342.975303 -256.556539) (xy 342.992934 -256.507288) (xy 343.018718 -256.461771)
			(xy 343.034874 -256.441194) (xy 343.035128 -256.440686) (xy 343.035128 -256.440432) (xy 343.039381 -256.434848)
			(xy 343.044927 -256.42196) (xy 343.04605 -256.415032) (xy 343.046812 -256.40792) (xy 343.04478 -256.39395)
			(xy 343.003124 -256.30632) (xy 343.00033 -256.300986) (xy 342.993837 -256.291761) (xy 342.974854 -256.279626)
			(xy 342.963754 -256.277618) (xy 342.95715 -256.27711) (xy 342.645238 -256.27711) (xy 342.643968 -256.27711)
			(xy 342.632133 -256.278018) (xy 342.611196 -256.289136) (xy 342.603836 -256.298446) (xy 342.599772 -256.304542)
			(xy 342.562688 -256.383536) (xy 342.559834 -256.390066) (xy 342.557519 -256.40412) (xy 342.558116 -256.411222)
			(xy 342.558624 -256.41554) (xy 342.574988 -256.433258) (xy 342.602691 -256.472736) (xy 342.624064 -256.51597)
			(xy 342.63861 -256.561952) (xy 342.64599 -256.609612) (xy 342.646508 -256.633726) (xy 342.646508 -256.634234)
			(xy 342.646022 -256.659024) (xy 342.638266 -256.707992) (xy 342.622945 -256.755145) (xy 342.600436 -256.79932)
			(xy 342.571294 -256.839431) (xy 342.536237 -256.874488) (xy 342.496126 -256.90363) (xy 342.451951 -256.926139)
			(xy 342.404798 -256.94146) (xy 342.35583 -256.949216) (xy 342.30625 -256.949216) (xy 342.257282 -256.94146)
			(xy 342.210129 -256.926139) (xy 342.165954 -256.90363) (xy 342.125843 -256.874488) (xy 342.090786 -256.839431)
			(xy 342.061644 -256.79932) (xy 342.039135 -256.755145) (xy 342.023814 -256.707992) (xy 342.016058 -256.659024)
			(xy 342.015572 -256.634234) (xy 342.015572 -256.633726) (xy 342.016194 -256.606186) (xy 342.025799 -256.551948)
			(xy 342.04467 -256.500199) (xy 342.072234 -256.45251) (xy 342.089486 -256.431034) (xy 342.106504 -256.410968)
			(xy 342.107012 -256.407412) (xy 342.107774 -256.400554) (xy 342.06307 -256.30632) (xy 342.060276 -256.300986)
			(xy 342.053779 -256.291769) (xy 342.034793 -256.279654) (xy 342.0237 -256.277618) (xy 342.017096 -256.27711)
			(xy 341.705184 -256.27711) (xy 341.703914 -256.27711) (xy 341.692086 -256.278029) (xy 341.671167 -256.289159)
			(xy 341.663782 -256.298446) (xy 341.659718 -256.304542) (xy 341.62111 -256.386076) (xy 341.620348 -256.387854)
			(xy 341.616486 -256.398245) (xy 341.617157 -256.420376) (xy 341.621618 -256.430526) (xy 341.62619 -256.43967)
			(xy 341.629746 -256.443734) (xy 341.645143 -256.463868) (xy 341.669742 -256.508181) (xy 341.686693 -256.555945)
			(xy 341.695531 -256.605851) (xy 341.696294 -256.631186) (xy 341.696294 -256.641854) (xy 341.695268 -256.665451)
			(xy 341.686839 -256.711923) (xy 341.671351 -256.756542) (xy 341.649174 -256.798243) (xy 341.620838 -256.836028)
			(xy 341.587018 -256.868998) (xy 341.548523 -256.896363) (xy 341.506272 -256.917472) (xy 341.461273 -256.931819)
			(xy 341.414602 -256.939062) (xy 341.390986 -256.939542) (xy 341.366995 -256.93907) (xy 341.319603 -256.931563)
			(xy 341.273968 -256.916735) (xy 341.231215 -256.894951) (xy 341.192395 -256.866748) (xy 341.158465 -256.83282)
			(xy 341.13026 -256.794002) (xy 341.108473 -256.75125) (xy 341.093642 -256.705617) (xy 341.086131 -256.658225)
			(xy 341.085678 -256.634234) (xy 341.086233 -256.608078) (xy 341.095195 -256.556539) (xy 341.112826 -256.507288)
			(xy 341.138609 -256.46177) (xy 341.154766 -256.441194) (xy 341.15502 -256.440686) (xy 341.15502 -256.440432)
			(xy 341.159274 -256.434849) (xy 341.164821 -256.421961) (xy 341.165942 -256.415032) (xy 341.166704 -256.40792)
			(xy 341.164672 -256.39395) (xy 341.123016 -256.30632) (xy 341.120222 -256.300986) (xy 341.113728 -256.291763)
			(xy 341.094745 -256.279631) (xy 341.083646 -256.277618) (xy 341.077042 -256.27711) (xy 340.765384 -256.27711)
			(xy 340.764114 -256.27711) (xy 340.752286 -256.278029) (xy 340.731367 -256.289159) (xy 340.723982 -256.298446)
			(xy 340.719918 -256.304542) (xy 340.68131 -256.386076) (xy 340.680548 -256.387854) (xy 340.676686 -256.398245)
			(xy 340.677357 -256.420376) (xy 340.681818 -256.430526) (xy 340.68639 -256.43967) (xy 340.689946 -256.443734)
			(xy 340.705343 -256.463868) (xy 340.729942 -256.508181) (xy 340.746893 -256.555945) (xy 340.755731 -256.605851)
			(xy 340.756494 -256.631186) (xy 340.756494 -256.641854) (xy 340.755468 -256.665451) (xy 340.747039 -256.711923)
			(xy 340.731551 -256.756542) (xy 340.709374 -256.798243) (xy 340.681038 -256.836028) (xy 340.647218 -256.868998)
			(xy 340.608723 -256.896363) (xy 340.566472 -256.917472) (xy 340.521473 -256.931819) (xy 340.474802 -256.939062)
			(xy 340.451186 -256.939542) (xy 340.427195 -256.93907) (xy 340.379803 -256.931563) (xy 340.334168 -256.916735)
			(xy 340.291415 -256.894951) (xy 340.252595 -256.866748) (xy 340.218665 -256.83282) (xy 340.19046 -256.794002)
			(xy 340.168673 -256.75125) (xy 340.153842 -256.705617) (xy 340.146331 -256.658225) (xy 340.145878 -256.634234)
			(xy 340.146433 -256.608078) (xy 340.155395 -256.556539) (xy 340.173026 -256.507288) (xy 340.198809 -256.46177)
			(xy 340.214966 -256.441194) (xy 340.21522 -256.440686) (xy 340.21522 -256.440432) (xy 340.219474 -256.434849)
			(xy 340.225021 -256.421961) (xy 340.226142 -256.415032) (xy 340.226904 -256.40792) (xy 340.224872 -256.39395)
			(xy 340.183216 -256.30632) (xy 340.180422 -256.300986) (xy 340.173928 -256.291763) (xy 340.154945 -256.279631)
			(xy 340.143846 -256.277618) (xy 340.137242 -256.27711) (xy 339.82533 -256.27711) (xy 339.82406 -256.27711)
			(xy 339.812226 -256.27802) (xy 339.791292 -256.289139) (xy 339.783928 -256.298446) (xy 339.779864 -256.304542)
			(xy 339.741256 -256.386076) (xy 339.740494 -256.387854) (xy 339.736634 -256.398245) (xy 339.737305 -256.420376)
			(xy 339.741764 -256.430526) (xy 339.746336 -256.43967) (xy 339.749892 -256.443734) (xy 339.765291 -256.463867)
			(xy 339.789895 -256.508179) (xy 339.806849 -256.555943) (xy 339.815689 -256.60585) (xy 339.81644 -256.631186)
			(xy 339.81644 -256.641854) (xy 339.815414 -256.665452) (xy 339.806985 -256.711927) (xy 339.791498 -256.756549)
			(xy 339.769322 -256.798253) (xy 339.740986 -256.836043) (xy 339.707167 -256.869016) (xy 339.668673 -256.896387)
			(xy 339.626422 -256.917501) (xy 339.581422 -256.931855) (xy 339.534749 -256.939105) (xy 339.511132 -256.939542)
			(xy 339.487138 -256.939074) (xy 339.439741 -256.931572) (xy 339.3941 -256.916748) (xy 339.351341 -256.894966)
			(xy 339.312515 -256.866764) (xy 339.278579 -256.832836) (xy 339.250368 -256.794016) (xy 339.228578 -256.751261)
			(xy 339.213744 -256.705624) (xy 339.206231 -256.658228) (xy 339.205824 -256.634234) (xy 339.20638 -256.608079)
			(xy 339.215342 -256.55654) (xy 339.232976 -256.50729) (xy 339.258761 -256.461776) (xy 339.274912 -256.441194)
			(xy 339.275166 -256.440686) (xy 339.275166 -256.440432) (xy 339.279416 -256.434847) (xy 339.284958 -256.421959)
			(xy 339.286088 -256.415032) (xy 339.28685 -256.40792) (xy 339.284818 -256.39395) (xy 339.243162 -256.30632)
			(xy 339.240368 -256.300986) (xy 339.23387 -256.29177) (xy 339.214884 -256.279658) (xy 339.203792 -256.277618)
			(xy 339.197188 -256.27711) (xy 338.885276 -256.27711) (xy 338.884006 -256.27711) (xy 338.872178 -256.27803)
			(xy 338.851262 -256.289163) (xy 338.843874 -256.298446) (xy 338.83981 -256.304542) (xy 338.802726 -256.383536)
			(xy 338.799875 -256.390066) (xy 338.797563 -256.40412) (xy 338.798154 -256.411222) (xy 338.798662 -256.41554)
			(xy 338.815088 -256.433285) (xy 338.842897 -256.47284) (xy 338.864346 -256.516174) (xy 338.878934 -256.562273)
			(xy 338.88632 -256.610058) (xy 338.8868 -256.634234) (xy 338.886313 -256.659044) (xy 338.878551 -256.708052)
			(xy 338.863218 -256.755242) (xy 338.840691 -256.799453) (xy 338.811526 -256.839596) (xy 338.77644 -256.874682)
			(xy 338.736297 -256.903847) (xy 338.692086 -256.926374) (xy 338.644896 -256.941707) (xy 338.595888 -256.949469)
			(xy 338.546268 -256.949469) (xy 338.49726 -256.941707) (xy 338.45007 -256.926374) (xy 338.405859 -256.903847)
			(xy 338.365716 -256.874682) (xy 338.33063 -256.839596) (xy 338.301465 -256.799453) (xy 338.278938 -256.755242)
			(xy 338.263605 -256.708052) (xy 338.255843 -256.659044) (xy 338.255356 -256.634234) (xy 338.255925 -256.606613)
			(xy 338.265536 -256.552215) (xy 338.284472 -256.500321) (xy 338.312153 -256.452515) (xy 338.329524 -256.431034)
			(xy 338.346542 -256.410968) (xy 338.34705 -256.407412) (xy 338.347812 -256.400554) (xy 338.303108 -256.30632)
			(xy 338.300314 -256.300986) (xy 338.293819 -256.291764) (xy 338.274836 -256.279635) (xy 338.263738 -256.277618)
			(xy 338.257134 -256.27711) (xy 337.945222 -256.27711) (xy 337.943952 -256.27711) (xy 337.932119 -256.278021)
			(xy 337.911187 -256.289143) (xy 337.90382 -256.298446) (xy 337.899756 -256.304542) (xy 337.861148 -256.386076)
			(xy 337.860386 -256.387854) (xy 337.856527 -256.398245) (xy 337.857197 -256.420376) (xy 337.861656 -256.430526)
			(xy 337.866228 -256.43967) (xy 337.869784 -256.443734) (xy 337.885179 -256.463869) (xy 337.909775 -256.508182)
			(xy 337.926724 -256.555946) (xy 337.935561 -256.605851) (xy 337.936332 -256.631186) (xy 337.936332 -256.641854)
			(xy 337.935306 -256.665452) (xy 337.926877 -256.711927) (xy 337.91139 -256.756548) (xy 337.889214 -256.798251)
			(xy 337.860878 -256.83604) (xy 337.827059 -256.869013) (xy 337.788564 -256.896383) (xy 337.746313 -256.917496)
			(xy 337.701314 -256.931848) (xy 337.654641 -256.939097) (xy 337.631024 -256.939542) (xy 337.607031 -256.939073)
			(xy 337.559634 -256.93157) (xy 337.513995 -256.916745) (xy 337.471236 -256.894964) (xy 337.432411 -256.866761)
			(xy 337.398476 -256.832833) (xy 337.370267 -256.794013) (xy 337.348477 -256.751259) (xy 337.333643 -256.705623)
			(xy 337.326131 -256.658227) (xy 337.325716 -256.634234) (xy 337.326272 -256.608078) (xy 337.335234 -256.55654)
			(xy 337.352867 -256.50729) (xy 337.378652 -256.461775) (xy 337.394804 -256.441194) (xy 337.395058 -256.440686)
			(xy 337.395058 -256.440432) (xy 337.399309 -256.434847) (xy 337.404852 -256.421959) (xy 337.40598 -256.415032)
			(xy 337.406742 -256.40792) (xy 337.40471 -256.39395) (xy 337.363054 -256.30632) (xy 337.36026 -256.300986)
			(xy 337.353762 -256.291771) (xy 337.334775 -256.279662) (xy 337.323684 -256.277618) (xy 337.31708 -256.27711)
			(xy 337.005422 -256.27711) (xy 337.004152 -256.27711) (xy 336.992319 -256.278021) (xy 336.971387 -256.289143)
			(xy 336.96402 -256.298446) (xy 336.959956 -256.304542) (xy 336.921348 -256.386076) (xy 336.920586 -256.387854)
			(xy 336.916727 -256.398245) (xy 336.917397 -256.420376) (xy 336.921856 -256.430526) (xy 336.926428 -256.43967)
			(xy 336.929984 -256.443734) (xy 336.945379 -256.463869) (xy 336.969975 -256.508182) (xy 336.986924 -256.555946)
			(xy 336.995761 -256.605851) (xy 336.996532 -256.631186) (xy 336.996532 -256.641854) (xy 336.995506 -256.665452)
			(xy 336.987077 -256.711927) (xy 336.97159 -256.756548) (xy 336.949414 -256.798251) (xy 336.921078 -256.83604)
			(xy 336.887259 -256.869013) (xy 336.848764 -256.896383) (xy 336.806513 -256.917496) (xy 336.761514 -256.931848)
			(xy 336.714841 -256.939097) (xy 336.691224 -256.939542) (xy 336.667231 -256.939073) (xy 336.619834 -256.93157)
			(xy 336.574195 -256.916745) (xy 336.531436 -256.894964) (xy 336.492611 -256.866761) (xy 336.458676 -256.832833)
			(xy 336.430467 -256.794013) (xy 336.408677 -256.751259) (xy 336.393843 -256.705623) (xy 336.386331 -256.658227)
			(xy 336.385916 -256.634234) (xy 336.386472 -256.608078) (xy 336.395434 -256.55654) (xy 336.413067 -256.50729)
			(xy 336.438852 -256.461775) (xy 336.455004 -256.441194) (xy 336.455258 -256.440686) (xy 336.455258 -256.440432)
			(xy 336.459509 -256.434847) (xy 336.465052 -256.421959) (xy 336.46618 -256.415032) (xy 336.466942 -256.40792)
			(xy 336.46491 -256.39395) (xy 336.423254 -256.30632) (xy 336.42046 -256.300986) (xy 336.413962 -256.291771)
			(xy 336.394975 -256.279662) (xy 336.383884 -256.277618) (xy 336.37728 -256.27711) (xy 336.065368 -256.27711)
			(xy 336.064098 -256.27711) (xy 336.052271 -256.278032) (xy 336.031358 -256.289166) (xy 336.023966 -256.298446)
			(xy 336.019902 -256.304542) (xy 335.981294 -256.386076) (xy 335.980532 -256.387854) (xy 335.97667 -256.398245)
			(xy 335.977342 -256.420376) (xy 335.981802 -256.430526) (xy 335.986374 -256.43967) (xy 335.98993 -256.443734)
			(xy 336.005328 -256.463867) (xy 336.029928 -256.50818) (xy 336.04688 -256.555944) (xy 336.055719 -256.605851)
			(xy 336.056478 -256.631186) (xy 336.056478 -256.641854) (xy 336.055452 -256.665454) (xy 336.047024 -256.711931)
			(xy 336.031537 -256.756555) (xy 336.009361 -256.798262) (xy 335.981026 -256.836055) (xy 335.947208 -256.869032)
			(xy 335.908714 -256.896407) (xy 335.866463 -256.917525) (xy 335.821463 -256.931884) (xy 335.774788 -256.93914)
			(xy 335.75117 -256.939542) (xy 335.726316 -256.939052) (xy 335.677263 -256.931001) (xy 335.630161 -256.915115)
			(xy 335.586251 -256.891814) (xy 335.546692 -256.861712) (xy 335.512528 -256.825604) (xy 335.48466 -256.784441)
			(xy 335.463823 -256.73931) (xy 335.450565 -256.691402) (xy 335.447386 -256.666746) (xy 335.447132 -256.663952)
			(xy 335.445608 -256.634234) (xy 335.446163 -256.607897) (xy 335.455194 -256.556004) (xy 335.472977 -256.506423)
			(xy 335.498987 -256.46062) (xy 335.532456 -256.419947) (xy 335.572395 -256.385605) (xy 335.594706 -256.371598)
			(xy 335.596484 -256.370582) (xy 335.606754 -256.363112) (xy 335.618888 -256.340843) (xy 335.619598 -256.328164)
			(xy 335.619598 -256.32791) (xy 335.61918 -256.317888) (xy 335.611512 -256.299367) (xy 335.597339 -256.285193)
			(xy 335.57882 -256.277521) (xy 335.568798 -256.27711) (xy 335.478628 -256.27711) (xy 335.46888 -256.277629)
			(xy 335.450858 -256.285085) (xy 335.443576 -256.291588) (xy 335.13141 -256.603754) (xy 335.124806 -256.611882)
			(xy 335.12125 -256.618232) (xy 335.116678 -256.629408) (xy 335.116424 -256.63906) (xy 335.116424 -256.64287)
			(xy 335.115279 -256.666852) (xy 335.106389 -256.714032) (xy 335.090223 -256.759239) (xy 335.067179 -256.801357)
			(xy 335.037827 -256.839349) (xy 335.002888 -256.872278) (xy 334.983328 -256.886202) (xy 334.978502 -256.889504)
			(xy 334.974692 -256.893822) (xy 334.968088 -256.902712) (xy 334.956658 -256.922778) (xy 334.953568 -256.928596)
			(xy 334.950235 -256.941338) (xy 334.950054 -256.947924) (xy 334.950054 -257.930142) (xy 346.651329 -257.930142)
			(xy 346.655359 -257.877644) (xy 346.667356 -257.826376) (xy 346.687039 -257.777541) (xy 346.713945 -257.732282)
			(xy 346.747445 -257.691661) (xy 346.786753 -257.65663) (xy 346.830948 -257.62801) (xy 346.878993 -257.606471)
			(xy 346.929764 -257.592519) (xy 346.982069 -257.586481) (xy 347.034683 -257.588498) (xy 347.086373 -257.598522)
			(xy 347.135926 -257.61632) (xy 347.182182 -257.641473) (xy 347.224056 -257.673392) (xy 347.260568 -257.71133)
			(xy 347.29086 -257.754396) (xy 347.314223 -257.801581) (xy 347.330109 -257.85178) (xy 347.338146 -257.903816)
			(xy 347.33865 -257.930142) (xy 348.551249 -257.930142) (xy 348.555279 -257.877644) (xy 348.567276 -257.826376)
			(xy 348.586959 -257.777541) (xy 348.613865 -257.732282) (xy 348.647365 -257.691661) (xy 348.686673 -257.65663)
			(xy 348.730868 -257.62801) (xy 348.778913 -257.606471) (xy 348.829684 -257.592519) (xy 348.881989 -257.586481)
			(xy 348.934603 -257.588498) (xy 348.986293 -257.598522) (xy 349.035846 -257.61632) (xy 349.082102 -257.641473)
			(xy 349.123976 -257.673392) (xy 349.160488 -257.71133) (xy 349.19078 -257.754396) (xy 349.214143 -257.801581)
			(xy 349.230029 -257.85178) (xy 349.238066 -257.903816) (xy 349.23857 -257.930142) (xy 350.451169 -257.930142)
			(xy 350.455199 -257.877644) (xy 350.467196 -257.826376) (xy 350.486879 -257.777541) (xy 350.513785 -257.732282)
			(xy 350.547285 -257.691661) (xy 350.586593 -257.65663) (xy 350.630788 -257.62801) (xy 350.678833 -257.606471)
			(xy 350.729604 -257.592519) (xy 350.781909 -257.586481) (xy 350.834523 -257.588498) (xy 350.886213 -257.598522)
			(xy 350.935766 -257.61632) (xy 350.982022 -257.641473) (xy 351.023896 -257.673392) (xy 351.060408 -257.71133)
			(xy 351.0907 -257.754396) (xy 351.114063 -257.801581) (xy 351.129949 -257.85178) (xy 351.137986 -257.903816)
			(xy 351.13849 -257.930142) (xy 351.137986 -257.956468) (xy 351.129949 -258.008504) (xy 351.114063 -258.058703)
			(xy 351.0907 -258.105888) (xy 351.060408 -258.148954) (xy 351.023896 -258.186892) (xy 350.982022 -258.218811)
			(xy 350.935766 -258.243964) (xy 350.886213 -258.261762) (xy 350.834523 -258.271786) (xy 350.781909 -258.273803)
			(xy 350.729604 -258.267765) (xy 350.678833 -258.253813) (xy 350.630788 -258.232274) (xy 350.586593 -258.203654)
			(xy 350.547285 -258.168623) (xy 350.513785 -258.128002) (xy 350.486879 -258.082743) (xy 350.467196 -258.033908)
			(xy 350.455199 -257.98264) (xy 350.451169 -257.930142) (xy 349.23857 -257.930142) (xy 349.238066 -257.956468)
			(xy 349.230029 -258.008504) (xy 349.214143 -258.058703) (xy 349.19078 -258.105888) (xy 349.160488 -258.148954)
			(xy 349.123976 -258.186892) (xy 349.082102 -258.218811) (xy 349.035846 -258.243964) (xy 348.986293 -258.261762)
			(xy 348.934603 -258.271786) (xy 348.881989 -258.273803) (xy 348.829684 -258.267765) (xy 348.778913 -258.253813)
			(xy 348.730868 -258.232274) (xy 348.686673 -258.203654) (xy 348.647365 -258.168623) (xy 348.613865 -258.128002)
			(xy 348.586959 -258.082743) (xy 348.567276 -258.033908) (xy 348.555279 -257.98264) (xy 348.551249 -257.930142)
			(xy 347.33865 -257.930142) (xy 347.338146 -257.956468) (xy 347.330109 -258.008504) (xy 347.314223 -258.058703)
			(xy 347.29086 -258.105888) (xy 347.260568 -258.148954) (xy 347.224056 -258.186892) (xy 347.182182 -258.218811)
			(xy 347.135926 -258.243964) (xy 347.086373 -258.261762) (xy 347.034683 -258.271786) (xy 346.982069 -258.273803)
			(xy 346.929764 -258.267765) (xy 346.878993 -258.253813) (xy 346.830948 -258.232274) (xy 346.786753 -258.203654)
			(xy 346.747445 -258.168623) (xy 346.713945 -258.128002) (xy 346.687039 -258.082743) (xy 346.667356 -258.033908)
			(xy 346.655359 -257.98264) (xy 346.651329 -257.930142) (xy 334.950054 -257.930142) (xy 334.950054 -258.830064)
			(xy 346.651329 -258.830064) (xy 346.655359 -258.777566) (xy 346.667356 -258.726298) (xy 346.687039 -258.677463)
			(xy 346.713945 -258.632204) (xy 346.747445 -258.591583) (xy 346.786753 -258.556552) (xy 346.830948 -258.527932)
			(xy 346.878993 -258.506393) (xy 346.929764 -258.492441) (xy 346.982069 -258.486403) (xy 347.034683 -258.48842)
			(xy 347.086373 -258.498444) (xy 347.135926 -258.516242) (xy 347.182182 -258.541395) (xy 347.224056 -258.573314)
			(xy 347.260568 -258.611252) (xy 347.29086 -258.654318) (xy 347.314223 -258.701503) (xy 347.330109 -258.751702)
			(xy 347.338146 -258.803738) (xy 347.33865 -258.830064) (xy 348.551249 -258.830064) (xy 348.555279 -258.777566)
			(xy 348.567276 -258.726298) (xy 348.586959 -258.677463) (xy 348.613865 -258.632204) (xy 348.647365 -258.591583)
			(xy 348.686673 -258.556552) (xy 348.730868 -258.527932) (xy 348.778913 -258.506393) (xy 348.829684 -258.492441)
			(xy 348.881989 -258.486403) (xy 348.934603 -258.48842) (xy 348.986293 -258.498444) (xy 349.035846 -258.516242)
			(xy 349.082102 -258.541395) (xy 349.123976 -258.573314) (xy 349.160488 -258.611252) (xy 349.19078 -258.654318)
			(xy 349.214143 -258.701503) (xy 349.230029 -258.751702) (xy 349.238066 -258.803738) (xy 349.23857 -258.830064)
			(xy 350.451169 -258.830064) (xy 350.455199 -258.777566) (xy 350.467196 -258.726298) (xy 350.486879 -258.677463)
			(xy 350.513785 -258.632204) (xy 350.547285 -258.591583) (xy 350.586593 -258.556552) (xy 350.630788 -258.527932)
			(xy 350.678833 -258.506393) (xy 350.729604 -258.492441) (xy 350.781909 -258.486403) (xy 350.834523 -258.48842)
			(xy 350.886213 -258.498444) (xy 350.935766 -258.516242) (xy 350.982022 -258.541395) (xy 351.023896 -258.573314)
			(xy 351.060408 -258.611252) (xy 351.0907 -258.654318) (xy 351.114063 -258.701503) (xy 351.129949 -258.751702)
			(xy 351.137986 -258.803738) (xy 351.13849 -258.830064) (xy 351.137986 -258.85639) (xy 351.129949 -258.908426)
			(xy 351.114063 -258.958625) (xy 351.0907 -259.00581) (xy 351.060408 -259.048876) (xy 351.023896 -259.086814)
			(xy 350.982022 -259.118733) (xy 350.935766 -259.143886) (xy 350.886213 -259.161684) (xy 350.834523 -259.171708)
			(xy 350.781909 -259.173725) (xy 350.729604 -259.167687) (xy 350.678833 -259.153735) (xy 350.630788 -259.132196)
			(xy 350.586593 -259.103576) (xy 350.547285 -259.068545) (xy 350.513785 -259.027924) (xy 350.486879 -258.982665)
			(xy 350.467196 -258.93383) (xy 350.455199 -258.882562) (xy 350.451169 -258.830064) (xy 349.23857 -258.830064)
			(xy 349.238066 -258.85639) (xy 349.230029 -258.908426) (xy 349.214143 -258.958625) (xy 349.19078 -259.00581)
			(xy 349.160488 -259.048876) (xy 349.123976 -259.086814) (xy 349.082102 -259.118733) (xy 349.035846 -259.143886)
			(xy 348.986293 -259.161684) (xy 348.934603 -259.171708) (xy 348.881989 -259.173725) (xy 348.829684 -259.167687)
			(xy 348.778913 -259.153735) (xy 348.730868 -259.132196) (xy 348.686673 -259.103576) (xy 348.647365 -259.068545)
			(xy 348.613865 -259.027924) (xy 348.586959 -258.982665) (xy 348.567276 -258.93383) (xy 348.555279 -258.882562)
			(xy 348.551249 -258.830064) (xy 347.33865 -258.830064) (xy 347.338146 -258.85639) (xy 347.330109 -258.908426)
			(xy 347.314223 -258.958625) (xy 347.29086 -259.00581) (xy 347.260568 -259.048876) (xy 347.224056 -259.086814)
			(xy 347.182182 -259.118733) (xy 347.135926 -259.143886) (xy 347.086373 -259.161684) (xy 347.034683 -259.171708)
			(xy 346.982069 -259.173725) (xy 346.929764 -259.167687) (xy 346.878993 -259.153735) (xy 346.830948 -259.132196)
			(xy 346.786753 -259.103576) (xy 346.747445 -259.068545) (xy 346.713945 -259.027924) (xy 346.687039 -258.982665)
			(xy 346.667356 -258.93383) (xy 346.655359 -258.882562) (xy 346.651329 -258.830064) (xy 334.950054 -258.830064)
			(xy 334.950054 -259.33019) (xy 354.001327 -259.33019) (xy 354.005357 -259.277692) (xy 354.017354 -259.226424)
			(xy 354.037037 -259.177589) (xy 354.063943 -259.13233) (xy 354.097443 -259.091709) (xy 354.136751 -259.056678)
			(xy 354.180946 -259.028058) (xy 354.228991 -259.006519) (xy 354.279762 -258.992567) (xy 354.332067 -258.986529)
			(xy 354.384681 -258.988546) (xy 354.436371 -258.99857) (xy 354.485924 -259.016368) (xy 354.53218 -259.041521)
			(xy 354.574054 -259.07344) (xy 354.610566 -259.111378) (xy 354.640858 -259.154444) (xy 354.664221 -259.201629)
			(xy 354.680107 -259.251828) (xy 354.688144 -259.303864) (xy 354.688648 -259.33019) (xy 354.688144 -259.356516)
			(xy 354.680107 -259.408552) (xy 354.664221 -259.458751) (xy 354.640858 -259.505936) (xy 354.610566 -259.549002)
			(xy 354.574054 -259.58694) (xy 354.53218 -259.618859) (xy 354.485924 -259.644012) (xy 354.436371 -259.66181)
			(xy 354.384681 -259.671834) (xy 354.332067 -259.673851) (xy 354.279762 -259.667813) (xy 354.228991 -259.653861)
			(xy 354.180946 -259.632322) (xy 354.136751 -259.603702) (xy 354.097443 -259.568671) (xy 354.063943 -259.52805)
			(xy 354.037037 -259.482791) (xy 354.017354 -259.433956) (xy 354.005357 -259.382688) (xy 354.001327 -259.33019)
			(xy 334.950054 -259.33019) (xy 334.950054 -259.729986) (xy 346.651329 -259.729986) (xy 346.655359 -259.677488)
			(xy 346.667356 -259.62622) (xy 346.687039 -259.577385) (xy 346.713945 -259.532126) (xy 346.747445 -259.491505)
			(xy 346.786753 -259.456474) (xy 346.830948 -259.427854) (xy 346.878993 -259.406315) (xy 346.929764 -259.392363)
			(xy 346.982069 -259.386325) (xy 347.034683 -259.388342) (xy 347.086373 -259.398366) (xy 347.135926 -259.416164)
			(xy 347.182182 -259.441317) (xy 347.224056 -259.473236) (xy 347.260568 -259.511174) (xy 347.29086 -259.55424)
			(xy 347.314223 -259.601425) (xy 347.330109 -259.651624) (xy 347.338146 -259.70366) (xy 347.33865 -259.729986)
			(xy 348.551249 -259.729986) (xy 348.555279 -259.677488) (xy 348.567276 -259.62622) (xy 348.586959 -259.577385)
			(xy 348.613865 -259.532126) (xy 348.647365 -259.491505) (xy 348.686673 -259.456474) (xy 348.730868 -259.427854)
			(xy 348.778913 -259.406315) (xy 348.829684 -259.392363) (xy 348.881989 -259.386325) (xy 348.934603 -259.388342)
			(xy 348.986293 -259.398366) (xy 349.035846 -259.416164) (xy 349.082102 -259.441317) (xy 349.123976 -259.473236)
			(xy 349.160488 -259.511174) (xy 349.19078 -259.55424) (xy 349.214143 -259.601425) (xy 349.230029 -259.651624)
			(xy 349.238066 -259.70366) (xy 349.23857 -259.729986) (xy 350.451169 -259.729986) (xy 350.455199 -259.677488)
			(xy 350.467196 -259.62622) (xy 350.486879 -259.577385) (xy 350.513785 -259.532126) (xy 350.547285 -259.491505)
			(xy 350.586593 -259.456474) (xy 350.630788 -259.427854) (xy 350.678833 -259.406315) (xy 350.729604 -259.392363)
			(xy 350.781909 -259.386325) (xy 350.834523 -259.388342) (xy 350.886213 -259.398366) (xy 350.935766 -259.416164)
			(xy 350.982022 -259.441317) (xy 351.023896 -259.473236) (xy 351.060408 -259.511174) (xy 351.0907 -259.55424)
			(xy 351.114063 -259.601425) (xy 351.129949 -259.651624) (xy 351.137986 -259.70366) (xy 351.13849 -259.729986)
			(xy 351.137986 -259.756312) (xy 351.129949 -259.808348) (xy 351.114063 -259.858547) (xy 351.0907 -259.905732)
			(xy 351.060408 -259.948798) (xy 351.023896 -259.986736) (xy 350.982022 -260.018655) (xy 350.935766 -260.043808)
			(xy 350.886213 -260.061606) (xy 350.834523 -260.07163) (xy 350.781909 -260.073647) (xy 350.729604 -260.067609)
			(xy 350.678833 -260.053657) (xy 350.630788 -260.032118) (xy 350.586593 -260.003498) (xy 350.547285 -259.968467)
			(xy 350.513785 -259.927846) (xy 350.486879 -259.882587) (xy 350.467196 -259.833752) (xy 350.455199 -259.782484)
			(xy 350.451169 -259.729986) (xy 349.23857 -259.729986) (xy 349.238066 -259.756312) (xy 349.230029 -259.808348)
			(xy 349.214143 -259.858547) (xy 349.19078 -259.905732) (xy 349.160488 -259.948798) (xy 349.123976 -259.986736)
			(xy 349.082102 -260.018655) (xy 349.035846 -260.043808) (xy 348.986293 -260.061606) (xy 348.934603 -260.07163)
			(xy 348.881989 -260.073647) (xy 348.829684 -260.067609) (xy 348.778913 -260.053657) (xy 348.730868 -260.032118)
			(xy 348.686673 -260.003498) (xy 348.647365 -259.968467) (xy 348.613865 -259.927846) (xy 348.586959 -259.882587)
			(xy 348.567276 -259.833752) (xy 348.555279 -259.782484) (xy 348.551249 -259.729986) (xy 347.33865 -259.729986)
			(xy 347.338146 -259.756312) (xy 347.330109 -259.808348) (xy 347.314223 -259.858547) (xy 347.29086 -259.905732)
			(xy 347.260568 -259.948798) (xy 347.224056 -259.986736) (xy 347.182182 -260.018655) (xy 347.135926 -260.043808)
			(xy 347.086373 -260.061606) (xy 347.034683 -260.07163) (xy 346.982069 -260.073647) (xy 346.929764 -260.067609)
			(xy 346.878993 -260.053657) (xy 346.830948 -260.032118) (xy 346.786753 -260.003498) (xy 346.747445 -259.968467)
			(xy 346.713945 -259.927846) (xy 346.687039 -259.882587) (xy 346.667356 -259.833752) (xy 346.655359 -259.782484)
			(xy 346.651329 -259.729986) (xy 334.950054 -259.729986) (xy 334.950054 -260.28015) (xy 354.001327 -260.28015)
			(xy 354.005357 -260.227652) (xy 354.017354 -260.176384) (xy 354.037037 -260.127549) (xy 354.063943 -260.08229)
			(xy 354.097443 -260.041669) (xy 354.136751 -260.006638) (xy 354.180946 -259.978018) (xy 354.228991 -259.956479)
			(xy 354.279762 -259.942527) (xy 354.332067 -259.936489) (xy 354.384681 -259.938506) (xy 354.436371 -259.94853)
			(xy 354.485924 -259.966328) (xy 354.53218 -259.991481) (xy 354.574054 -260.0234) (xy 354.610566 -260.061338)
			(xy 354.640858 -260.104404) (xy 354.664221 -260.151589) (xy 354.680107 -260.201788) (xy 354.688144 -260.253824)
			(xy 354.688648 -260.28015) (xy 354.688144 -260.306476) (xy 354.680107 -260.358512) (xy 354.664221 -260.408711)
			(xy 354.640858 -260.455896) (xy 354.610566 -260.498962) (xy 354.574054 -260.5369) (xy 354.53218 -260.568819)
			(xy 354.485924 -260.593972) (xy 354.436371 -260.61177) (xy 354.384681 -260.621794) (xy 354.332067 -260.623811)
			(xy 354.279762 -260.617773) (xy 354.228991 -260.603821) (xy 354.180946 -260.582282) (xy 354.136751 -260.553662)
			(xy 354.097443 -260.518631) (xy 354.063943 -260.47801) (xy 354.037037 -260.432751) (xy 354.017354 -260.383916)
			(xy 354.005357 -260.332648) (xy 354.001327 -260.28015) (xy 334.950054 -260.28015) (xy 334.950054 -261.12597)
			(xy 335.74534 -261.12597) (xy 335.7493 -261.076916) (xy 335.761077 -261.029132) (xy 335.780368 -260.983856)
			(xy 335.806671 -260.94226) (xy 335.839306 -260.905423) (xy 335.877427 -260.874298) (xy 335.920048 -260.849691)
			(xy 335.966064 -260.832239) (xy 336.014283 -260.822395) (xy 336.063458 -260.820414) (xy 336.112313 -260.826346)
			(xy 336.159584 -260.840038) (xy 336.204046 -260.861136) (xy 336.244549 -260.889092) (xy 336.280042 -260.923184)
			(xy 336.309607 -260.962528) (xy 336.332478 -261.006105) (xy 336.348062 -261.052786) (xy 336.355957 -261.101363)
			(xy 336.356452 -261.12597) (xy 336.685394 -261.12597) (xy 336.689354 -261.076916) (xy 336.701131 -261.029132)
			(xy 336.720422 -260.983856) (xy 336.746725 -260.94226) (xy 336.77936 -260.905423) (xy 336.817481 -260.874298)
			(xy 336.860102 -260.849691) (xy 336.906118 -260.832239) (xy 336.954337 -260.822395) (xy 337.003512 -260.820414)
			(xy 337.052367 -260.826346) (xy 337.099638 -260.840038) (xy 337.1441 -260.861136) (xy 337.184603 -260.889092)
			(xy 337.220096 -260.923184) (xy 337.249661 -260.962528) (xy 337.272532 -261.006105) (xy 337.288116 -261.052786)
			(xy 337.296011 -261.101363) (xy 337.296506 -261.12597) (xy 337.625194 -261.12597) (xy 337.629154 -261.076916)
			(xy 337.640931 -261.029132) (xy 337.660222 -260.983856) (xy 337.686525 -260.94226) (xy 337.71916 -260.905423)
			(xy 337.757281 -260.874298) (xy 337.799902 -260.849691) (xy 337.845918 -260.832239) (xy 337.894137 -260.822395)
			(xy 337.943312 -260.820414) (xy 337.992167 -260.826346) (xy 338.039438 -260.840038) (xy 338.0839 -260.861136)
			(xy 338.124403 -260.889092) (xy 338.159896 -260.923184) (xy 338.189461 -260.962528) (xy 338.212332 -261.006105)
			(xy 338.227916 -261.052786) (xy 338.235811 -261.101363) (xy 338.236306 -261.12597) (xy 338.565248 -261.12597)
			(xy 338.569208 -261.076916) (xy 338.580985 -261.029132) (xy 338.600276 -260.983856) (xy 338.626579 -260.94226)
			(xy 338.659214 -260.905423) (xy 338.697335 -260.874298) (xy 338.739956 -260.849691) (xy 338.785972 -260.832239)
			(xy 338.834191 -260.822395) (xy 338.883366 -260.820414) (xy 338.932221 -260.826346) (xy 338.979492 -260.840038)
			(xy 339.023954 -260.861136) (xy 339.064457 -260.889092) (xy 339.09995 -260.923184) (xy 339.129515 -260.962528)
			(xy 339.152386 -261.006105) (xy 339.16797 -261.052786) (xy 339.175865 -261.101363) (xy 339.17636 -261.12597)
			(xy 339.505302 -261.12597) (xy 339.509262 -261.076916) (xy 339.521039 -261.029132) (xy 339.54033 -260.983856)
			(xy 339.566633 -260.94226) (xy 339.599268 -260.905423) (xy 339.637389 -260.874298) (xy 339.68001 -260.849691)
			(xy 339.726026 -260.832239) (xy 339.774245 -260.822395) (xy 339.82342 -260.820414) (xy 339.872275 -260.826346)
			(xy 339.919546 -260.840038) (xy 339.964008 -260.861136) (xy 340.004511 -260.889092) (xy 340.040004 -260.923184)
			(xy 340.069569 -260.962528) (xy 340.09244 -261.006105) (xy 340.108024 -261.052786) (xy 340.115919 -261.101363)
			(xy 340.116414 -261.12597) (xy 340.445356 -261.12597) (xy 340.449316 -261.076916) (xy 340.461093 -261.029132)
			(xy 340.480384 -260.983856) (xy 340.506687 -260.94226) (xy 340.539322 -260.905423) (xy 340.577443 -260.874298)
			(xy 340.620064 -260.849691) (xy 340.66608 -260.832239) (xy 340.714299 -260.822395) (xy 340.763474 -260.820414)
			(xy 340.812329 -260.826346) (xy 340.8596 -260.840038) (xy 340.904062 -260.861136) (xy 340.944565 -260.889092)
			(xy 340.980058 -260.923184) (xy 341.009623 -260.962528) (xy 341.032494 -261.006105) (xy 341.048078 -261.052786)
			(xy 341.055973 -261.101363) (xy 341.056468 -261.12597) (xy 342.32521 -261.12597) (xy 342.32917 -261.076916)
			(xy 342.340947 -261.029132) (xy 342.360238 -260.983856) (xy 342.386541 -260.94226) (xy 342.419176 -260.905423)
			(xy 342.457297 -260.874298) (xy 342.499918 -260.849691) (xy 342.545934 -260.832239) (xy 342.594153 -260.822395)
			(xy 342.643328 -260.820414) (xy 342.692183 -260.826346) (xy 342.739454 -260.840038) (xy 342.783916 -260.861136)
			(xy 342.824419 -260.889092) (xy 342.859912 -260.923184) (xy 342.889477 -260.962528) (xy 342.912348 -261.006105)
			(xy 342.927932 -261.052786) (xy 342.935827 -261.101363) (xy 342.936322 -261.12597) (xy 343.265264 -261.12597)
			(xy 343.269224 -261.076916) (xy 343.281001 -261.029132) (xy 343.300292 -260.983856) (xy 343.326595 -260.94226)
			(xy 343.35923 -260.905423) (xy 343.397351 -260.874298) (xy 343.439972 -260.849691) (xy 343.485988 -260.832239)
			(xy 343.534207 -260.822395) (xy 343.583382 -260.820414) (xy 343.632237 -260.826346) (xy 343.679508 -260.840038)
			(xy 343.72397 -260.861136) (xy 343.764473 -260.889092) (xy 343.799966 -260.923184) (xy 343.829531 -260.962528)
			(xy 343.852402 -261.006105) (xy 343.867986 -261.052786) (xy 343.875881 -261.101363) (xy 343.876376 -261.12597)
			(xy 344.205318 -261.12597) (xy 344.209278 -261.076916) (xy 344.221055 -261.029132) (xy 344.240346 -260.983856)
			(xy 344.266649 -260.94226) (xy 344.299284 -260.905423) (xy 344.337405 -260.874298) (xy 344.380026 -260.849691)
			(xy 344.426042 -260.832239) (xy 344.474261 -260.822395) (xy 344.523436 -260.820414) (xy 344.572291 -260.826346)
			(xy 344.619562 -260.840038) (xy 344.664024 -260.861136) (xy 344.704527 -260.889092) (xy 344.74002 -260.923184)
			(xy 344.769585 -260.962528) (xy 344.792456 -261.006105) (xy 344.80804 -261.052786) (xy 344.815935 -261.101363)
			(xy 344.81643 -261.12597) (xy 346.085426 -261.12597) (xy 346.089386 -261.076916) (xy 346.101163 -261.029132)
			(xy 346.120454 -260.983856) (xy 346.146757 -260.94226) (xy 346.179392 -260.905423) (xy 346.217513 -260.874298)
			(xy 346.260134 -260.849691) (xy 346.30615 -260.832239) (xy 346.354369 -260.822395) (xy 346.403544 -260.820414)
			(xy 346.452399 -260.826346) (xy 346.49967 -260.840038) (xy 346.544132 -260.861136) (xy 346.584635 -260.889092)
			(xy 346.620128 -260.923184) (xy 346.649693 -260.962528) (xy 346.672564 -261.006105) (xy 346.688148 -261.052786)
			(xy 346.696043 -261.101363) (xy 346.696538 -261.12597) (xy 347.96528 -261.12597) (xy 347.96924 -261.076916)
			(xy 347.981017 -261.029132) (xy 348.000308 -260.983856) (xy 348.026611 -260.94226) (xy 348.059246 -260.905423)
			(xy 348.097367 -260.874298) (xy 348.139988 -260.849691) (xy 348.186004 -260.832239) (xy 348.234223 -260.822395)
			(xy 348.283398 -260.820414) (xy 348.332253 -260.826346) (xy 348.379524 -260.840038) (xy 348.423986 -260.861136)
			(xy 348.464489 -260.889092) (xy 348.499982 -260.923184) (xy 348.529547 -260.962528) (xy 348.552418 -261.006105)
			(xy 348.568002 -261.052786) (xy 348.575897 -261.101363) (xy 348.576392 -261.12597) (xy 348.905334 -261.12597)
			(xy 348.909294 -261.076916) (xy 348.921071 -261.029132) (xy 348.940362 -260.983856) (xy 348.966665 -260.94226)
			(xy 348.9993 -260.905423) (xy 349.037421 -260.874298) (xy 349.080042 -260.849691) (xy 349.126058 -260.832239)
			(xy 349.174277 -260.822395) (xy 349.223452 -260.820414) (xy 349.272307 -260.826346) (xy 349.319578 -260.840038)
			(xy 349.36404 -260.861136) (xy 349.404543 -260.889092) (xy 349.440036 -260.923184) (xy 349.469601 -260.962528)
			(xy 349.492472 -261.006105) (xy 349.508056 -261.052786) (xy 349.515951 -261.101363) (xy 349.516446 -261.12597)
			(xy 349.845388 -261.12597) (xy 349.849348 -261.076916) (xy 349.861125 -261.029132) (xy 349.880416 -260.983856)
			(xy 349.906719 -260.94226) (xy 349.939354 -260.905423) (xy 349.977475 -260.874298) (xy 350.020096 -260.849691)
			(xy 350.066112 -260.832239) (xy 350.114331 -260.822395) (xy 350.163506 -260.820414) (xy 350.212361 -260.826346)
			(xy 350.259632 -260.840038) (xy 350.304094 -260.861136) (xy 350.344597 -260.889092) (xy 350.38009 -260.923184)
			(xy 350.409655 -260.962528) (xy 350.432526 -261.006105) (xy 350.44811 -261.052786) (xy 350.456005 -261.101363)
			(xy 350.4565 -261.12597) (xy 350.456459 -261.128002) (xy 350.78214 -261.128002) (xy 350.7861 -261.078948)
			(xy 350.797877 -261.031164) (xy 350.817168 -260.985888) (xy 350.843471 -260.944292) (xy 350.876106 -260.907455)
			(xy 350.914227 -260.87633) (xy 350.956848 -260.851723) (xy 351.002864 -260.834271) (xy 351.051083 -260.824427)
			(xy 351.100258 -260.822446) (xy 351.149113 -260.828378) (xy 351.196384 -260.84207) (xy 351.240846 -260.863168)
			(xy 351.281349 -260.891124) (xy 351.316842 -260.925216) (xy 351.346407 -260.96456) (xy 351.369278 -261.008137)
			(xy 351.384862 -261.054818) (xy 351.392757 -261.103395) (xy 351.393252 -261.128002) (xy 351.722194 -261.128002)
			(xy 351.726154 -261.078948) (xy 351.737931 -261.031164) (xy 351.757222 -260.985888) (xy 351.783525 -260.944292)
			(xy 351.81616 -260.907455) (xy 351.854281 -260.87633) (xy 351.896902 -260.851723) (xy 351.942918 -260.834271)
			(xy 351.991137 -260.824427) (xy 352.040312 -260.822446) (xy 352.089167 -260.828378) (xy 352.136438 -260.84207)
			(xy 352.1809 -260.863168) (xy 352.221403 -260.891124) (xy 352.256896 -260.925216) (xy 352.286461 -260.96456)
			(xy 352.309332 -261.008137) (xy 352.324916 -261.054818) (xy 352.332811 -261.103395) (xy 352.333306 -261.128002)
			(xy 352.332811 -261.152609) (xy 352.324916 -261.201186) (xy 352.31526 -261.23011) (xy 354.001327 -261.23011)
			(xy 354.005357 -261.177612) (xy 354.017354 -261.126344) (xy 354.037037 -261.077509) (xy 354.063943 -261.03225)
			(xy 354.097443 -260.991629) (xy 354.136751 -260.956598) (xy 354.180946 -260.927978) (xy 354.228991 -260.906439)
			(xy 354.279762 -260.892487) (xy 354.332067 -260.886449) (xy 354.384681 -260.888466) (xy 354.436371 -260.89849)
			(xy 354.485924 -260.916288) (xy 354.53218 -260.941441) (xy 354.574054 -260.97336) (xy 354.610566 -261.011298)
			(xy 354.640858 -261.054364) (xy 354.664221 -261.101549) (xy 354.680107 -261.151748) (xy 354.688144 -261.203784)
			(xy 354.688648 -261.23011) (xy 354.688144 -261.256436) (xy 354.680107 -261.308472) (xy 354.675566 -261.32282)
			(xy 355.244149 -261.32282) (xy 355.248179 -261.270322) (xy 355.260176 -261.219054) (xy 355.279859 -261.170219)
			(xy 355.306765 -261.12496) (xy 355.340265 -261.084339) (xy 355.379573 -261.049308) (xy 355.423768 -261.020688)
			(xy 355.471813 -260.999149) (xy 355.522584 -260.985197) (xy 355.574889 -260.979159) (xy 355.627503 -260.981176)
			(xy 355.679193 -260.9912) (xy 355.728746 -261.008998) (xy 355.775002 -261.034151) (xy 355.816876 -261.06607)
			(xy 355.853388 -261.104008) (xy 355.88368 -261.147074) (xy 355.907043 -261.194259) (xy 355.922929 -261.244458)
			(xy 355.930966 -261.296494) (xy 355.93147 -261.32282) (xy 355.930966 -261.349146) (xy 355.922929 -261.401182)
			(xy 355.907043 -261.451381) (xy 355.88368 -261.498566) (xy 355.853388 -261.541632) (xy 355.816876 -261.57957)
			(xy 355.775002 -261.611489) (xy 355.728746 -261.636642) (xy 355.679193 -261.65444) (xy 355.627503 -261.664464)
			(xy 355.574889 -261.666481) (xy 355.522584 -261.660443) (xy 355.471813 -261.646491) (xy 355.423768 -261.624952)
			(xy 355.379573 -261.596332) (xy 355.340265 -261.561301) (xy 355.306765 -261.52068) (xy 355.279859 -261.475421)
			(xy 355.260176 -261.426586) (xy 355.248179 -261.375318) (xy 355.244149 -261.32282) (xy 354.675566 -261.32282)
			(xy 354.664221 -261.358671) (xy 354.640858 -261.405856) (xy 354.610566 -261.448922) (xy 354.574054 -261.48686)
			(xy 354.53218 -261.518779) (xy 354.485924 -261.543932) (xy 354.436371 -261.56173) (xy 354.384681 -261.571754)
			(xy 354.332067 -261.573771) (xy 354.279762 -261.567733) (xy 354.228991 -261.553781) (xy 354.180946 -261.532242)
			(xy 354.136751 -261.503622) (xy 354.097443 -261.468591) (xy 354.063943 -261.42797) (xy 354.037037 -261.382711)
			(xy 354.017354 -261.333876) (xy 354.005357 -261.282608) (xy 354.001327 -261.23011) (xy 352.31526 -261.23011)
			(xy 352.309332 -261.247867) (xy 352.286461 -261.291444) (xy 352.256896 -261.330788) (xy 352.221403 -261.36488)
			(xy 352.1809 -261.392836) (xy 352.136438 -261.413934) (xy 352.089167 -261.427626) (xy 352.040312 -261.433558)
			(xy 351.991137 -261.431577) (xy 351.942918 -261.421733) (xy 351.896902 -261.404281) (xy 351.854281 -261.379674)
			(xy 351.81616 -261.348549) (xy 351.783525 -261.311712) (xy 351.757222 -261.270116) (xy 351.737931 -261.22484)
			(xy 351.726154 -261.177056) (xy 351.722194 -261.128002) (xy 351.393252 -261.128002) (xy 351.392757 -261.152609)
			(xy 351.384862 -261.201186) (xy 351.369278 -261.247867) (xy 351.346407 -261.291444) (xy 351.316842 -261.330788)
			(xy 351.281349 -261.36488) (xy 351.240846 -261.392836) (xy 351.196384 -261.413934) (xy 351.149113 -261.427626)
			(xy 351.100258 -261.433558) (xy 351.051083 -261.431577) (xy 351.002864 -261.421733) (xy 350.956848 -261.404281)
			(xy 350.914227 -261.379674) (xy 350.876106 -261.348549) (xy 350.843471 -261.311712) (xy 350.817168 -261.270116)
			(xy 350.797877 -261.22484) (xy 350.7861 -261.177056) (xy 350.78214 -261.128002) (xy 350.456459 -261.128002)
			(xy 350.456005 -261.150577) (xy 350.44811 -261.199154) (xy 350.432526 -261.245835) (xy 350.409655 -261.289412)
			(xy 350.38009 -261.328756) (xy 350.344597 -261.362848) (xy 350.304094 -261.390804) (xy 350.259632 -261.411902)
			(xy 350.212361 -261.425594) (xy 350.163506 -261.431526) (xy 350.114331 -261.429545) (xy 350.066112 -261.419701)
			(xy 350.020096 -261.402249) (xy 349.977475 -261.377642) (xy 349.939354 -261.346517) (xy 349.906719 -261.30968)
			(xy 349.880416 -261.268084) (xy 349.861125 -261.222808) (xy 349.849348 -261.175024) (xy 349.845388 -261.12597)
			(xy 349.516446 -261.12597) (xy 349.515951 -261.150577) (xy 349.508056 -261.199154) (xy 349.492472 -261.245835)
			(xy 349.469601 -261.289412) (xy 349.440036 -261.328756) (xy 349.404543 -261.362848) (xy 349.36404 -261.390804)
			(xy 349.319578 -261.411902) (xy 349.272307 -261.425594) (xy 349.223452 -261.431526) (xy 349.174277 -261.429545)
			(xy 349.126058 -261.419701) (xy 349.080042 -261.402249) (xy 349.037421 -261.377642) (xy 348.9993 -261.346517)
			(xy 348.966665 -261.30968) (xy 348.940362 -261.268084) (xy 348.921071 -261.222808) (xy 348.909294 -261.175024)
			(xy 348.905334 -261.12597) (xy 348.576392 -261.12597) (xy 348.575897 -261.150577) (xy 348.568002 -261.199154)
			(xy 348.552418 -261.245835) (xy 348.529547 -261.289412) (xy 348.499982 -261.328756) (xy 348.464489 -261.362848)
			(xy 348.423986 -261.390804) (xy 348.379524 -261.411902) (xy 348.332253 -261.425594) (xy 348.283398 -261.431526)
			(xy 348.234223 -261.429545) (xy 348.186004 -261.419701) (xy 348.139988 -261.402249) (xy 348.097367 -261.377642)
			(xy 348.059246 -261.346517) (xy 348.026611 -261.30968) (xy 348.000308 -261.268084) (xy 347.981017 -261.222808)
			(xy 347.96924 -261.175024) (xy 347.96528 -261.12597) (xy 346.696538 -261.12597) (xy 346.696043 -261.150577)
			(xy 346.688148 -261.199154) (xy 346.672564 -261.245835) (xy 346.649693 -261.289412) (xy 346.620128 -261.328756)
			(xy 346.584635 -261.362848) (xy 346.544132 -261.390804) (xy 346.49967 -261.411902) (xy 346.452399 -261.425594)
			(xy 346.403544 -261.431526) (xy 346.354369 -261.429545) (xy 346.30615 -261.419701) (xy 346.260134 -261.402249)
			(xy 346.217513 -261.377642) (xy 346.179392 -261.346517) (xy 346.146757 -261.30968) (xy 346.120454 -261.268084)
			(xy 346.101163 -261.222808) (xy 346.089386 -261.175024) (xy 346.085426 -261.12597) (xy 344.81643 -261.12597)
			(xy 344.815935 -261.150577) (xy 344.80804 -261.199154) (xy 344.792456 -261.245835) (xy 344.769585 -261.289412)
			(xy 344.74002 -261.328756) (xy 344.704527 -261.362848) (xy 344.664024 -261.390804) (xy 344.619562 -261.411902)
			(xy 344.572291 -261.425594) (xy 344.523436 -261.431526) (xy 344.474261 -261.429545) (xy 344.426042 -261.419701)
			(xy 344.380026 -261.402249) (xy 344.337405 -261.377642) (xy 344.299284 -261.346517) (xy 344.266649 -261.30968)
			(xy 344.240346 -261.268084) (xy 344.221055 -261.222808) (xy 344.209278 -261.175024) (xy 344.205318 -261.12597)
			(xy 343.876376 -261.12597) (xy 343.875881 -261.150577) (xy 343.867986 -261.199154) (xy 343.852402 -261.245835)
			(xy 343.829531 -261.289412) (xy 343.799966 -261.328756) (xy 343.764473 -261.362848) (xy 343.72397 -261.390804)
			(xy 343.679508 -261.411902) (xy 343.632237 -261.425594) (xy 343.583382 -261.431526) (xy 343.534207 -261.429545)
			(xy 343.485988 -261.419701) (xy 343.439972 -261.402249) (xy 343.397351 -261.377642) (xy 343.35923 -261.346517)
			(xy 343.326595 -261.30968) (xy 343.300292 -261.268084) (xy 343.281001 -261.222808) (xy 343.269224 -261.175024)
			(xy 343.265264 -261.12597) (xy 342.936322 -261.12597) (xy 342.935827 -261.150577) (xy 342.927932 -261.199154)
			(xy 342.912348 -261.245835) (xy 342.889477 -261.289412) (xy 342.859912 -261.328756) (xy 342.824419 -261.362848)
			(xy 342.783916 -261.390804) (xy 342.739454 -261.411902) (xy 342.692183 -261.425594) (xy 342.643328 -261.431526)
			(xy 342.594153 -261.429545) (xy 342.545934 -261.419701) (xy 342.499918 -261.402249) (xy 342.457297 -261.377642)
			(xy 342.419176 -261.346517) (xy 342.386541 -261.30968) (xy 342.360238 -261.268084) (xy 342.340947 -261.222808)
			(xy 342.32917 -261.175024) (xy 342.32521 -261.12597) (xy 341.056468 -261.12597) (xy 341.055973 -261.150577)
			(xy 341.048078 -261.199154) (xy 341.032494 -261.245835) (xy 341.009623 -261.289412) (xy 340.980058 -261.328756)
			(xy 340.944565 -261.362848) (xy 340.904062 -261.390804) (xy 340.8596 -261.411902) (xy 340.812329 -261.425594)
			(xy 340.763474 -261.431526) (xy 340.714299 -261.429545) (xy 340.66608 -261.419701) (xy 340.620064 -261.402249)
			(xy 340.577443 -261.377642) (xy 340.539322 -261.346517) (xy 340.506687 -261.30968) (xy 340.480384 -261.268084)
			(xy 340.461093 -261.222808) (xy 340.449316 -261.175024) (xy 340.445356 -261.12597) (xy 340.116414 -261.12597)
			(xy 340.115919 -261.150577) (xy 340.108024 -261.199154) (xy 340.09244 -261.245835) (xy 340.069569 -261.289412)
			(xy 340.040004 -261.328756) (xy 340.004511 -261.362848) (xy 339.964008 -261.390804) (xy 339.919546 -261.411902)
			(xy 339.872275 -261.425594) (xy 339.82342 -261.431526) (xy 339.774245 -261.429545) (xy 339.726026 -261.419701)
			(xy 339.68001 -261.402249) (xy 339.637389 -261.377642) (xy 339.599268 -261.346517) (xy 339.566633 -261.30968)
			(xy 339.54033 -261.268084) (xy 339.521039 -261.222808) (xy 339.509262 -261.175024) (xy 339.505302 -261.12597)
			(xy 339.17636 -261.12597) (xy 339.175865 -261.150577) (xy 339.16797 -261.199154) (xy 339.152386 -261.245835)
			(xy 339.129515 -261.289412) (xy 339.09995 -261.328756) (xy 339.064457 -261.362848) (xy 339.023954 -261.390804)
			(xy 338.979492 -261.411902) (xy 338.932221 -261.425594) (xy 338.883366 -261.431526) (xy 338.834191 -261.429545)
			(xy 338.785972 -261.419701) (xy 338.739956 -261.402249) (xy 338.697335 -261.377642) (xy 338.659214 -261.346517)
			(xy 338.626579 -261.30968) (xy 338.600276 -261.268084) (xy 338.580985 -261.222808) (xy 338.569208 -261.175024)
			(xy 338.565248 -261.12597) (xy 338.236306 -261.12597) (xy 338.235811 -261.150577) (xy 338.227916 -261.199154)
			(xy 338.212332 -261.245835) (xy 338.189461 -261.289412) (xy 338.159896 -261.328756) (xy 338.124403 -261.362848)
			(xy 338.0839 -261.390804) (xy 338.039438 -261.411902) (xy 337.992167 -261.425594) (xy 337.943312 -261.431526)
			(xy 337.894137 -261.429545) (xy 337.845918 -261.419701) (xy 337.799902 -261.402249) (xy 337.757281 -261.377642)
			(xy 337.71916 -261.346517) (xy 337.686525 -261.30968) (xy 337.660222 -261.268084) (xy 337.640931 -261.222808)
			(xy 337.629154 -261.175024) (xy 337.625194 -261.12597) (xy 337.296506 -261.12597) (xy 337.296011 -261.150577)
			(xy 337.288116 -261.199154) (xy 337.272532 -261.245835) (xy 337.249661 -261.289412) (xy 337.220096 -261.328756)
			(xy 337.184603 -261.362848) (xy 337.1441 -261.390804) (xy 337.099638 -261.411902) (xy 337.052367 -261.425594)
			(xy 337.003512 -261.431526) (xy 336.954337 -261.429545) (xy 336.906118 -261.419701) (xy 336.860102 -261.402249)
			(xy 336.817481 -261.377642) (xy 336.77936 -261.346517) (xy 336.746725 -261.30968) (xy 336.720422 -261.268084)
			(xy 336.701131 -261.222808) (xy 336.689354 -261.175024) (xy 336.685394 -261.12597) (xy 336.356452 -261.12597)
			(xy 336.355957 -261.150577) (xy 336.348062 -261.199154) (xy 336.332478 -261.245835) (xy 336.309607 -261.289412)
			(xy 336.280042 -261.328756) (xy 336.244549 -261.362848) (xy 336.204046 -261.390804) (xy 336.159584 -261.411902)
			(xy 336.112313 -261.425594) (xy 336.063458 -261.431526) (xy 336.014283 -261.429545) (xy 335.966064 -261.419701)
			(xy 335.920048 -261.402249) (xy 335.877427 -261.377642) (xy 335.839306 -261.346517) (xy 335.806671 -261.30968)
			(xy 335.780368 -261.268084) (xy 335.761077 -261.222808) (xy 335.7493 -261.175024) (xy 335.74534 -261.12597)
			(xy 334.950054 -261.12597) (xy 334.950054 -261.935976) (xy 335.275186 -261.935976) (xy 335.279146 -261.886922)
			(xy 335.290923 -261.839138) (xy 335.310214 -261.793862) (xy 335.336517 -261.752266) (xy 335.369152 -261.715429)
			(xy 335.407273 -261.684304) (xy 335.449894 -261.659697) (xy 335.49591 -261.642245) (xy 335.544129 -261.632401)
			(xy 335.593304 -261.63042) (xy 335.642159 -261.636352) (xy 335.68943 -261.650044) (xy 335.733892 -261.671142)
			(xy 335.774395 -261.699098) (xy 335.809888 -261.73319) (xy 335.839453 -261.772534) (xy 335.862324 -261.816111)
			(xy 335.877908 -261.862792) (xy 335.885803 -261.911369) (xy 335.886298 -261.935976) (xy 336.21524 -261.935976)
			(xy 336.2192 -261.886922) (xy 336.230977 -261.839138) (xy 336.250268 -261.793862) (xy 336.276571 -261.752266)
			(xy 336.309206 -261.715429) (xy 336.347327 -261.684304) (xy 336.389948 -261.659697) (xy 336.435964 -261.642245)
			(xy 336.484183 -261.632401) (xy 336.533358 -261.63042) (xy 336.582213 -261.636352) (xy 336.629484 -261.650044)
			(xy 336.673946 -261.671142) (xy 336.714449 -261.699098) (xy 336.749942 -261.73319) (xy 336.779507 -261.772534)
			(xy 336.802378 -261.816111) (xy 336.817962 -261.862792) (xy 336.825857 -261.911369) (xy 336.826352 -261.935976)
			(xy 337.155294 -261.935976) (xy 337.159254 -261.886922) (xy 337.171031 -261.839138) (xy 337.190322 -261.793862)
			(xy 337.216625 -261.752266) (xy 337.24926 -261.715429) (xy 337.287381 -261.684304) (xy 337.330002 -261.659697)
			(xy 337.376018 -261.642245) (xy 337.424237 -261.632401) (xy 337.473412 -261.63042) (xy 337.522267 -261.636352)
			(xy 337.569538 -261.650044) (xy 337.614 -261.671142) (xy 337.654503 -261.699098) (xy 337.689996 -261.73319)
			(xy 337.719561 -261.772534) (xy 337.742432 -261.816111) (xy 337.758016 -261.862792) (xy 337.765911 -261.911369)
			(xy 337.766406 -261.935976) (xy 338.095348 -261.935976) (xy 338.099308 -261.886922) (xy 338.111085 -261.839138)
			(xy 338.130376 -261.793862) (xy 338.156679 -261.752266) (xy 338.189314 -261.715429) (xy 338.227435 -261.684304)
			(xy 338.270056 -261.659697) (xy 338.316072 -261.642245) (xy 338.364291 -261.632401) (xy 338.413466 -261.63042)
			(xy 338.462321 -261.636352) (xy 338.509592 -261.650044) (xy 338.554054 -261.671142) (xy 338.594557 -261.699098)
			(xy 338.63005 -261.73319) (xy 338.659615 -261.772534) (xy 338.682486 -261.816111) (xy 338.69807 -261.862792)
			(xy 338.705965 -261.911369) (xy 338.70646 -261.935976) (xy 339.035402 -261.935976) (xy 339.039362 -261.886922)
			(xy 339.051139 -261.839138) (xy 339.07043 -261.793862) (xy 339.096733 -261.752266) (xy 339.129368 -261.715429)
			(xy 339.167489 -261.684304) (xy 339.21011 -261.659697) (xy 339.256126 -261.642245) (xy 339.304345 -261.632401)
			(xy 339.35352 -261.63042) (xy 339.402375 -261.636352) (xy 339.449646 -261.650044) (xy 339.494108 -261.671142)
			(xy 339.534611 -261.699098) (xy 339.570104 -261.73319) (xy 339.599669 -261.772534) (xy 339.62254 -261.816111)
			(xy 339.638124 -261.862792) (xy 339.646019 -261.911369) (xy 339.646514 -261.935976) (xy 339.964771 -261.935976)
			(xy 339.968866 -261.885248) (xy 339.981045 -261.835834) (xy 340.000993 -261.789014) (xy 340.028194 -261.746)
			(xy 340.061942 -261.707906) (xy 340.101364 -261.675719) (xy 340.145438 -261.650273) (xy 340.193024 -261.632226)
			(xy 340.242888 -261.622046) (xy 340.29374 -261.619997) (xy 340.344261 -261.626131) (xy 340.393145 -261.640291)
			(xy 340.439124 -261.662108) (xy 340.481008 -261.691018) (xy 340.517712 -261.726273) (xy 340.548285 -261.766959)
			(xy 340.571936 -261.812022) (xy 340.588052 -261.860296) (xy 340.596216 -261.91053) (xy 340.596728 -261.935976)
			(xy 340.915256 -261.935976) (xy 340.919216 -261.886922) (xy 340.930993 -261.839138) (xy 340.950284 -261.793862)
			(xy 340.976587 -261.752266) (xy 341.009222 -261.715429) (xy 341.047343 -261.684304) (xy 341.089964 -261.659697)
			(xy 341.13598 -261.642245) (xy 341.184199 -261.632401) (xy 341.233374 -261.63042) (xy 341.282229 -261.636352)
			(xy 341.3295 -261.650044) (xy 341.373962 -261.671142) (xy 341.414465 -261.699098) (xy 341.449958 -261.73319)
			(xy 341.479523 -261.772534) (xy 341.502394 -261.816111) (xy 341.517978 -261.862792) (xy 341.525873 -261.911369)
			(xy 341.526368 -261.935976) (xy 341.85531 -261.935976) (xy 341.85927 -261.886922) (xy 341.871047 -261.839138)
			(xy 341.890338 -261.793862) (xy 341.916641 -261.752266) (xy 341.949276 -261.715429) (xy 341.987397 -261.684304)
			(xy 342.030018 -261.659697) (xy 342.076034 -261.642245) (xy 342.124253 -261.632401) (xy 342.173428 -261.63042)
			(xy 342.222283 -261.636352) (xy 342.269554 -261.650044) (xy 342.314016 -261.671142) (xy 342.354519 -261.699098)
			(xy 342.390012 -261.73319) (xy 342.419577 -261.772534) (xy 342.442448 -261.816111) (xy 342.458032 -261.862792)
			(xy 342.465927 -261.911369) (xy 342.466422 -261.935976) (xy 342.795364 -261.935976) (xy 342.799324 -261.886922)
			(xy 342.811101 -261.839138) (xy 342.830392 -261.793862) (xy 342.856695 -261.752266) (xy 342.88933 -261.715429)
			(xy 342.927451 -261.684304) (xy 342.970072 -261.659697) (xy 343.016088 -261.642245) (xy 343.064307 -261.632401)
			(xy 343.113482 -261.63042) (xy 343.162337 -261.636352) (xy 343.209608 -261.650044) (xy 343.25407 -261.671142)
			(xy 343.294573 -261.699098) (xy 343.330066 -261.73319) (xy 343.359631 -261.772534) (xy 343.382502 -261.816111)
			(xy 343.398086 -261.862792) (xy 343.405981 -261.911369) (xy 343.406476 -261.935976) (xy 343.724987 -261.935976)
			(xy 343.729082 -261.885248) (xy 343.741261 -261.835834) (xy 343.761209 -261.789014) (xy 343.78841 -261.746)
			(xy 343.822158 -261.707906) (xy 343.86158 -261.675719) (xy 343.905654 -261.650273) (xy 343.95324 -261.632226)
			(xy 344.003104 -261.622046) (xy 344.053956 -261.619997) (xy 344.104477 -261.626131) (xy 344.153361 -261.640291)
			(xy 344.19934 -261.662108) (xy 344.241224 -261.691018) (xy 344.277928 -261.726273) (xy 344.308501 -261.766959)
			(xy 344.332152 -261.812022) (xy 344.348268 -261.860296) (xy 344.356432 -261.91053) (xy 344.356944 -261.935976)
			(xy 345.615272 -261.935976) (xy 345.619232 -261.886922) (xy 345.631009 -261.839138) (xy 345.6503 -261.793862)
			(xy 345.676603 -261.752266) (xy 345.709238 -261.715429) (xy 345.747359 -261.684304) (xy 345.78998 -261.659697)
			(xy 345.835996 -261.642245) (xy 345.884215 -261.632401) (xy 345.93339 -261.63042) (xy 345.982245 -261.636352)
			(xy 346.029516 -261.650044) (xy 346.073978 -261.671142) (xy 346.114481 -261.699098) (xy 346.149974 -261.73319)
			(xy 346.179539 -261.772534) (xy 346.20241 -261.816111) (xy 346.217994 -261.862792) (xy 346.225889 -261.911369)
			(xy 346.226384 -261.935976) (xy 347.49538 -261.935976) (xy 347.49934 -261.886922) (xy 347.511117 -261.839138)
			(xy 347.530408 -261.793862) (xy 347.556711 -261.752266) (xy 347.589346 -261.715429) (xy 347.627467 -261.684304)
			(xy 347.670088 -261.659697) (xy 347.716104 -261.642245) (xy 347.764323 -261.632401) (xy 347.813498 -261.63042)
			(xy 347.862353 -261.636352) (xy 347.909624 -261.650044) (xy 347.954086 -261.671142) (xy 347.994589 -261.699098)
			(xy 348.030082 -261.73319) (xy 348.059647 -261.772534) (xy 348.082518 -261.816111) (xy 348.098102 -261.862792)
			(xy 348.105997 -261.911369) (xy 348.106492 -261.935976) (xy 348.105997 -261.960583) (xy 348.098102 -262.00916)
			(xy 348.082518 -262.055841) (xy 348.059647 -262.099418) (xy 348.030082 -262.138762) (xy 347.994589 -262.172854)
			(xy 347.954086 -262.20081) (xy 347.909624 -262.221908) (xy 347.862353 -262.2356) (xy 347.813498 -262.241532)
			(xy 347.764323 -262.239551) (xy 347.716104 -262.229707) (xy 347.670088 -262.212255) (xy 347.627467 -262.187648)
			(xy 347.589346 -262.156523) (xy 347.556711 -262.119686) (xy 347.530408 -262.07809) (xy 347.511117 -262.032814)
			(xy 347.49934 -261.98503) (xy 347.49538 -261.935976) (xy 346.226384 -261.935976) (xy 346.225889 -261.960583)
			(xy 346.217994 -262.00916) (xy 346.20241 -262.055841) (xy 346.179539 -262.099418) (xy 346.149974 -262.138762)
			(xy 346.114481 -262.172854) (xy 346.073978 -262.20081) (xy 346.029516 -262.221908) (xy 345.982245 -262.2356)
			(xy 345.93339 -262.241532) (xy 345.884215 -262.239551) (xy 345.835996 -262.229707) (xy 345.78998 -262.212255)
			(xy 345.747359 -262.187648) (xy 345.709238 -262.156523) (xy 345.676603 -262.119686) (xy 345.6503 -262.07809)
			(xy 345.631009 -262.032814) (xy 345.619232 -261.98503) (xy 345.615272 -261.935976) (xy 344.356944 -261.935976)
			(xy 344.356432 -261.961422) (xy 344.348268 -262.011656) (xy 344.332152 -262.05993) (xy 344.308501 -262.104993)
			(xy 344.277928 -262.145679) (xy 344.241224 -262.180934) (xy 344.19934 -262.209844) (xy 344.153361 -262.231661)
			(xy 344.104477 -262.245821) (xy 344.053956 -262.251955) (xy 344.003104 -262.249906) (xy 343.95324 -262.239726)
			(xy 343.905654 -262.221679) (xy 343.86158 -262.196233) (xy 343.822158 -262.164046) (xy 343.78841 -262.125952)
			(xy 343.761209 -262.082938) (xy 343.741261 -262.036118) (xy 343.729082 -261.986704) (xy 343.724987 -261.935976)
			(xy 343.406476 -261.935976) (xy 343.405981 -261.960583) (xy 343.398086 -262.00916) (xy 343.382502 -262.055841)
			(xy 343.359631 -262.099418) (xy 343.330066 -262.138762) (xy 343.294573 -262.172854) (xy 343.25407 -262.20081)
			(xy 343.209608 -262.221908) (xy 343.162337 -262.2356) (xy 343.113482 -262.241532) (xy 343.064307 -262.239551)
			(xy 343.016088 -262.229707) (xy 342.970072 -262.212255) (xy 342.927451 -262.187648) (xy 342.88933 -262.156523)
			(xy 342.856695 -262.119686) (xy 342.830392 -262.07809) (xy 342.811101 -262.032814) (xy 342.799324 -261.98503)
			(xy 342.795364 -261.935976) (xy 342.466422 -261.935976) (xy 342.465927 -261.960583) (xy 342.458032 -262.00916)
			(xy 342.442448 -262.055841) (xy 342.419577 -262.099418) (xy 342.390012 -262.138762) (xy 342.354519 -262.172854)
			(xy 342.314016 -262.20081) (xy 342.269554 -262.221908) (xy 342.222283 -262.2356) (xy 342.173428 -262.241532)
			(xy 342.124253 -262.239551) (xy 342.076034 -262.229707) (xy 342.030018 -262.212255) (xy 341.987397 -262.187648)
			(xy 341.949276 -262.156523) (xy 341.916641 -262.119686) (xy 341.890338 -262.07809) (xy 341.871047 -262.032814)
			(xy 341.85927 -261.98503) (xy 341.85531 -261.935976) (xy 341.526368 -261.935976) (xy 341.525873 -261.960583)
			(xy 341.517978 -262.00916) (xy 341.502394 -262.055841) (xy 341.479523 -262.099418) (xy 341.449958 -262.138762)
			(xy 341.414465 -262.172854) (xy 341.373962 -262.20081) (xy 341.3295 -262.221908) (xy 341.282229 -262.2356)
			(xy 341.233374 -262.241532) (xy 341.184199 -262.239551) (xy 341.13598 -262.229707) (xy 341.089964 -262.212255)
			(xy 341.047343 -262.187648) (xy 341.009222 -262.156523) (xy 340.976587 -262.119686) (xy 340.950284 -262.07809)
			(xy 340.930993 -262.032814) (xy 340.919216 -261.98503) (xy 340.915256 -261.935976) (xy 340.596728 -261.935976)
			(xy 340.596216 -261.961422) (xy 340.588052 -262.011656) (xy 340.571936 -262.05993) (xy 340.548285 -262.104993)
			(xy 340.517712 -262.145679) (xy 340.481008 -262.180934) (xy 340.439124 -262.209844) (xy 340.393145 -262.231661)
			(xy 340.344261 -262.245821) (xy 340.29374 -262.251955) (xy 340.242888 -262.249906) (xy 340.193024 -262.239726)
			(xy 340.145438 -262.221679) (xy 340.101364 -262.196233) (xy 340.061942 -262.164046) (xy 340.028194 -262.125952)
			(xy 340.000993 -262.082938) (xy 339.981045 -262.036118) (xy 339.968866 -261.986704) (xy 339.964771 -261.935976)
			(xy 339.646514 -261.935976) (xy 339.646019 -261.960583) (xy 339.638124 -262.00916) (xy 339.62254 -262.055841)
			(xy 339.599669 -262.099418) (xy 339.570104 -262.138762) (xy 339.534611 -262.172854) (xy 339.494108 -262.20081)
			(xy 339.449646 -262.221908) (xy 339.402375 -262.2356) (xy 339.35352 -262.241532) (xy 339.304345 -262.239551)
			(xy 339.256126 -262.229707) (xy 339.21011 -262.212255) (xy 339.167489 -262.187648) (xy 339.129368 -262.156523)
			(xy 339.096733 -262.119686) (xy 339.07043 -262.07809) (xy 339.051139 -262.032814) (xy 339.039362 -261.98503)
			(xy 339.035402 -261.935976) (xy 338.70646 -261.935976) (xy 338.705965 -261.960583) (xy 338.69807 -262.00916)
			(xy 338.682486 -262.055841) (xy 338.659615 -262.099418) (xy 338.63005 -262.138762) (xy 338.594557 -262.172854)
			(xy 338.554054 -262.20081) (xy 338.509592 -262.221908) (xy 338.462321 -262.2356) (xy 338.413466 -262.241532)
			(xy 338.364291 -262.239551) (xy 338.316072 -262.229707) (xy 338.270056 -262.212255) (xy 338.227435 -262.187648)
			(xy 338.189314 -262.156523) (xy 338.156679 -262.119686) (xy 338.130376 -262.07809) (xy 338.111085 -262.032814)
			(xy 338.099308 -261.98503) (xy 338.095348 -261.935976) (xy 337.766406 -261.935976) (xy 337.765911 -261.960583)
			(xy 337.758016 -262.00916) (xy 337.742432 -262.055841) (xy 337.719561 -262.099418) (xy 337.689996 -262.138762)
			(xy 337.654503 -262.172854) (xy 337.614 -262.20081) (xy 337.569538 -262.221908) (xy 337.522267 -262.2356)
			(xy 337.473412 -262.241532) (xy 337.424237 -262.239551) (xy 337.376018 -262.229707) (xy 337.330002 -262.212255)
			(xy 337.287381 -262.187648) (xy 337.24926 -262.156523) (xy 337.216625 -262.119686) (xy 337.190322 -262.07809)
			(xy 337.171031 -262.032814) (xy 337.159254 -261.98503) (xy 337.155294 -261.935976) (xy 336.826352 -261.935976)
			(xy 336.825857 -261.960583) (xy 336.817962 -262.00916) (xy 336.802378 -262.055841) (xy 336.779507 -262.099418)
			(xy 336.749942 -262.138762) (xy 336.714449 -262.172854) (xy 336.673946 -262.20081) (xy 336.629484 -262.221908)
			(xy 336.582213 -262.2356) (xy 336.533358 -262.241532) (xy 336.484183 -262.239551) (xy 336.435964 -262.229707)
			(xy 336.389948 -262.212255) (xy 336.347327 -262.187648) (xy 336.309206 -262.156523) (xy 336.276571 -262.119686)
			(xy 336.250268 -262.07809) (xy 336.230977 -262.032814) (xy 336.2192 -261.98503) (xy 336.21524 -261.935976)
			(xy 335.886298 -261.935976) (xy 335.885803 -261.960583) (xy 335.877908 -262.00916) (xy 335.862324 -262.055841)
			(xy 335.839453 -262.099418) (xy 335.809888 -262.138762) (xy 335.774395 -262.172854) (xy 335.733892 -262.20081)
			(xy 335.68943 -262.221908) (xy 335.642159 -262.2356) (xy 335.593304 -262.241532) (xy 335.544129 -262.239551)
			(xy 335.49591 -262.229707) (xy 335.449894 -262.212255) (xy 335.407273 -262.187648) (xy 335.369152 -262.156523)
			(xy 335.336517 -262.119686) (xy 335.310214 -262.07809) (xy 335.290923 -262.032814) (xy 335.279146 -261.98503)
			(xy 335.275186 -261.935976) (xy 334.950054 -261.935976) (xy 334.950054 -262.344662) (xy 334.950054 -262.347202)
			(xy 334.950963 -262.35687) (xy 334.959062 -262.374501) (xy 334.965802 -262.381492) (xy 335.024476 -262.432038)
			(xy 335.028708 -262.435513) (xy 335.038317 -262.440761) (xy 335.043526 -262.442452) (xy 335.054194 -262.4455)
			(xy 335.065116 -262.443976) (xy 335.076354 -262.44242) (xy 335.098983 -262.440765) (xy 335.110328 -262.440674)
			(xy 335.11109 -262.440674) (xy 335.13635 -262.441166) (xy 335.18618 -262.44948) (xy 335.233963 -262.465882)
			(xy 335.278394 -262.489926) (xy 335.318262 -262.520955) (xy 335.352478 -262.558123) (xy 335.38011 -262.600415)
			(xy 335.400404 -262.64668) (xy 335.412806 -262.695653) (xy 335.416977 -262.745982) (xy 335.74534 -262.745982)
			(xy 335.7493 -262.696928) (xy 335.761077 -262.649144) (xy 335.780368 -262.603868) (xy 335.806671 -262.562272)
			(xy 335.839306 -262.525435) (xy 335.877427 -262.49431) (xy 335.920048 -262.469703) (xy 335.966064 -262.452251)
			(xy 336.014283 -262.442407) (xy 336.063458 -262.440426) (xy 336.112313 -262.446358) (xy 336.159584 -262.46005)
			(xy 336.204046 -262.481148) (xy 336.244549 -262.509104) (xy 336.280042 -262.543196) (xy 336.309607 -262.58254)
			(xy 336.332478 -262.626117) (xy 336.348062 -262.672798) (xy 336.355957 -262.721375) (xy 336.356452 -262.745982)
			(xy 336.685394 -262.745982) (xy 336.689354 -262.696928) (xy 336.701131 -262.649144) (xy 336.720422 -262.603868)
			(xy 336.746725 -262.562272) (xy 336.77936 -262.525435) (xy 336.817481 -262.49431) (xy 336.860102 -262.469703)
			(xy 336.906118 -262.452251) (xy 336.954337 -262.442407) (xy 337.003512 -262.440426) (xy 337.052367 -262.446358)
			(xy 337.099638 -262.46005) (xy 337.1441 -262.481148) (xy 337.184603 -262.509104) (xy 337.220096 -262.543196)
			(xy 337.249661 -262.58254) (xy 337.272532 -262.626117) (xy 337.288116 -262.672798) (xy 337.296011 -262.721375)
			(xy 337.296506 -262.745982) (xy 337.625194 -262.745982) (xy 337.629154 -262.696928) (xy 337.640931 -262.649144)
			(xy 337.660222 -262.603868) (xy 337.686525 -262.562272) (xy 337.71916 -262.525435) (xy 337.757281 -262.49431)
			(xy 337.799902 -262.469703) (xy 337.845918 -262.452251) (xy 337.894137 -262.442407) (xy 337.943312 -262.440426)
			(xy 337.992167 -262.446358) (xy 338.039438 -262.46005) (xy 338.0839 -262.481148) (xy 338.124403 -262.509104)
			(xy 338.159896 -262.543196) (xy 338.189461 -262.58254) (xy 338.212332 -262.626117) (xy 338.227916 -262.672798)
			(xy 338.235811 -262.721375) (xy 338.236306 -262.745982) (xy 338.554817 -262.745982) (xy 338.558912 -262.695254)
			(xy 338.571091 -262.64584) (xy 338.591039 -262.59902) (xy 338.61824 -262.556006) (xy 338.651988 -262.517912)
			(xy 338.69141 -262.485725) (xy 338.735484 -262.460279) (xy 338.78307 -262.442232) (xy 338.832934 -262.432052)
			(xy 338.883786 -262.430003) (xy 338.934307 -262.436137) (xy 338.983191 -262.450297) (xy 339.02917 -262.472114)
			(xy 339.071054 -262.501024) (xy 339.107758 -262.536279) (xy 339.138331 -262.576965) (xy 339.161982 -262.622028)
			(xy 339.178098 -262.670302) (xy 339.186262 -262.720536) (xy 339.186774 -262.745982) (xy 339.505302 -262.745982)
			(xy 339.509262 -262.696928) (xy 339.521039 -262.649144) (xy 339.54033 -262.603868) (xy 339.566633 -262.562272)
			(xy 339.599268 -262.525435) (xy 339.637389 -262.49431) (xy 339.68001 -262.469703) (xy 339.726026 -262.452251)
			(xy 339.774245 -262.442407) (xy 339.82342 -262.440426) (xy 339.872275 -262.446358) (xy 339.919546 -262.46005)
			(xy 339.964008 -262.481148) (xy 340.004511 -262.509104) (xy 340.040004 -262.543196) (xy 340.069569 -262.58254)
			(xy 340.09244 -262.626117) (xy 340.108024 -262.672798) (xy 340.115919 -262.721375) (xy 340.116414 -262.745982)
			(xy 340.434925 -262.745982) (xy 340.43902 -262.695254) (xy 340.451199 -262.64584) (xy 340.471147 -262.59902)
			(xy 340.498348 -262.556006) (xy 340.532096 -262.517912) (xy 340.571518 -262.485725) (xy 340.615592 -262.460279)
			(xy 340.663178 -262.442232) (xy 340.713042 -262.432052) (xy 340.763894 -262.430003) (xy 340.814415 -262.436137)
			(xy 340.863299 -262.450297) (xy 340.909278 -262.472114) (xy 340.951162 -262.501024) (xy 340.987866 -262.536279)
			(xy 341.018439 -262.576965) (xy 341.04209 -262.622028) (xy 341.058206 -262.670302) (xy 341.06637 -262.720536)
			(xy 341.066882 -262.745982) (xy 341.38541 -262.745982) (xy 341.38937 -262.696928) (xy 341.401147 -262.649144)
			(xy 341.420438 -262.603868) (xy 341.446741 -262.562272) (xy 341.479376 -262.525435) (xy 341.517497 -262.49431)
			(xy 341.560118 -262.469703) (xy 341.606134 -262.452251) (xy 341.654353 -262.442407) (xy 341.703528 -262.440426)
			(xy 341.752383 -262.446358) (xy 341.799654 -262.46005) (xy 341.844116 -262.481148) (xy 341.884619 -262.509104)
			(xy 341.920112 -262.543196) (xy 341.949677 -262.58254) (xy 341.972548 -262.626117) (xy 341.988132 -262.672798)
			(xy 341.996027 -262.721375) (xy 341.996522 -262.745982) (xy 342.314779 -262.745982) (xy 342.318874 -262.695254)
			(xy 342.331053 -262.64584) (xy 342.351001 -262.59902) (xy 342.378202 -262.556006) (xy 342.41195 -262.517912)
			(xy 342.451372 -262.485725) (xy 342.495446 -262.460279) (xy 342.543032 -262.442232) (xy 342.592896 -262.432052)
			(xy 342.643748 -262.430003) (xy 342.694269 -262.436137) (xy 342.743153 -262.450297) (xy 342.789132 -262.472114)
			(xy 342.831016 -262.501024) (xy 342.86772 -262.536279) (xy 342.898293 -262.576965) (xy 342.921944 -262.622028)
			(xy 342.93806 -262.670302) (xy 342.946224 -262.720536) (xy 342.946736 -262.745982) (xy 343.254833 -262.745982)
			(xy 343.258928 -262.695254) (xy 343.271107 -262.64584) (xy 343.291055 -262.59902) (xy 343.318256 -262.556006)
			(xy 343.352004 -262.517912) (xy 343.391426 -262.485725) (xy 343.4355 -262.460279) (xy 343.483086 -262.442232)
			(xy 343.53295 -262.432052) (xy 343.583802 -262.430003) (xy 343.634323 -262.436137) (xy 343.683207 -262.450297)
			(xy 343.729186 -262.472114) (xy 343.77107 -262.501024) (xy 343.807774 -262.536279) (xy 343.838347 -262.576965)
			(xy 343.861998 -262.622028) (xy 343.878114 -262.670302) (xy 343.886278 -262.720536) (xy 343.88679 -262.745982)
			(xy 344.205318 -262.745982) (xy 344.209278 -262.696928) (xy 344.221055 -262.649144) (xy 344.240346 -262.603868)
			(xy 344.266649 -262.562272) (xy 344.299284 -262.525435) (xy 344.337405 -262.49431) (xy 344.380026 -262.469703)
			(xy 344.426042 -262.452251) (xy 344.474261 -262.442407) (xy 344.523436 -262.440426) (xy 344.572291 -262.446358)
			(xy 344.619562 -262.46005) (xy 344.664024 -262.481148) (xy 344.704527 -262.509104) (xy 344.74002 -262.543196)
			(xy 344.769585 -262.58254) (xy 344.792456 -262.626117) (xy 344.80804 -262.672798) (xy 344.815935 -262.721375)
			(xy 344.81643 -262.745982) (xy 346.085426 -262.745982) (xy 346.089386 -262.696928) (xy 346.101163 -262.649144)
			(xy 346.120454 -262.603868) (xy 346.146757 -262.562272) (xy 346.179392 -262.525435) (xy 346.217513 -262.49431)
			(xy 346.260134 -262.469703) (xy 346.30615 -262.452251) (xy 346.354369 -262.442407) (xy 346.403544 -262.440426)
			(xy 346.452399 -262.446358) (xy 346.49967 -262.46005) (xy 346.544132 -262.481148) (xy 346.584635 -262.509104)
			(xy 346.620128 -262.543196) (xy 346.649693 -262.58254) (xy 346.672564 -262.626117) (xy 346.688148 -262.672798)
			(xy 346.696043 -262.721375) (xy 346.696538 -262.745982) (xy 347.96528 -262.745982) (xy 347.96924 -262.696928)
			(xy 347.981017 -262.649144) (xy 348.000308 -262.603868) (xy 348.026611 -262.562272) (xy 348.059246 -262.525435)
			(xy 348.097367 -262.49431) (xy 348.139988 -262.469703) (xy 348.186004 -262.452251) (xy 348.234223 -262.442407)
			(xy 348.283398 -262.440426) (xy 348.332253 -262.446358) (xy 348.379524 -262.46005) (xy 348.423986 -262.481148)
			(xy 348.464489 -262.509104) (xy 348.499982 -262.543196) (xy 348.529547 -262.58254) (xy 348.552418 -262.626117)
			(xy 348.568002 -262.672798) (xy 348.575897 -262.721375) (xy 348.576392 -262.745982) (xy 348.575897 -262.770589)
			(xy 348.568002 -262.819166) (xy 348.552418 -262.865847) (xy 348.529547 -262.909424) (xy 348.499982 -262.948768)
			(xy 348.464489 -262.98286) (xy 348.423986 -263.010816) (xy 348.379524 -263.031914) (xy 348.332253 -263.045606)
			(xy 348.283398 -263.051538) (xy 348.234223 -263.049557) (xy 348.186004 -263.039713) (xy 348.139988 -263.022261)
			(xy 348.097367 -262.997654) (xy 348.059246 -262.966529) (xy 348.026611 -262.929692) (xy 348.000308 -262.888096)
			(xy 347.981017 -262.84282) (xy 347.96924 -262.795036) (xy 347.96528 -262.745982) (xy 346.696538 -262.745982)
			(xy 346.696043 -262.770589) (xy 346.688148 -262.819166) (xy 346.672564 -262.865847) (xy 346.649693 -262.909424)
			(xy 346.620128 -262.948768) (xy 346.584635 -262.98286) (xy 346.544132 -263.010816) (xy 346.49967 -263.031914)
			(xy 346.452399 -263.045606) (xy 346.403544 -263.051538) (xy 346.354369 -263.049557) (xy 346.30615 -263.039713)
			(xy 346.260134 -263.022261) (xy 346.217513 -262.997654) (xy 346.179392 -262.966529) (xy 346.146757 -262.929692)
			(xy 346.120454 -262.888096) (xy 346.101163 -262.84282) (xy 346.089386 -262.795036) (xy 346.085426 -262.745982)
			(xy 344.81643 -262.745982) (xy 344.815935 -262.770589) (xy 344.80804 -262.819166) (xy 344.792456 -262.865847)
			(xy 344.769585 -262.909424) (xy 344.74002 -262.948768) (xy 344.704527 -262.98286) (xy 344.664024 -263.010816)
			(xy 344.619562 -263.031914) (xy 344.572291 -263.045606) (xy 344.523436 -263.051538) (xy 344.474261 -263.049557)
			(xy 344.426042 -263.039713) (xy 344.380026 -263.022261) (xy 344.337405 -262.997654) (xy 344.299284 -262.966529)
			(xy 344.266649 -262.929692) (xy 344.240346 -262.888096) (xy 344.221055 -262.84282) (xy 344.209278 -262.795036)
			(xy 344.205318 -262.745982) (xy 343.88679 -262.745982) (xy 343.886278 -262.771428) (xy 343.878114 -262.821662)
			(xy 343.861998 -262.869936) (xy 343.838347 -262.914999) (xy 343.807774 -262.955685) (xy 343.77107 -262.99094)
			(xy 343.729186 -263.01985) (xy 343.683207 -263.041667) (xy 343.634323 -263.055827) (xy 343.583802 -263.061961)
			(xy 343.53295 -263.059912) (xy 343.483086 -263.049732) (xy 343.4355 -263.031685) (xy 343.391426 -263.006239)
			(xy 343.352004 -262.974052) (xy 343.318256 -262.935958) (xy 343.291055 -262.892944) (xy 343.271107 -262.846124)
			(xy 343.258928 -262.79671) (xy 343.254833 -262.745982) (xy 342.946736 -262.745982) (xy 342.946224 -262.771428)
			(xy 342.93806 -262.821662) (xy 342.921944 -262.869936) (xy 342.898293 -262.914999) (xy 342.86772 -262.955685)
			(xy 342.831016 -262.99094) (xy 342.789132 -263.01985) (xy 342.743153 -263.041667) (xy 342.694269 -263.055827)
			(xy 342.643748 -263.061961) (xy 342.592896 -263.059912) (xy 342.543032 -263.049732) (xy 342.495446 -263.031685)
			(xy 342.451372 -263.006239) (xy 342.41195 -262.974052) (xy 342.378202 -262.935958) (xy 342.351001 -262.892944)
			(xy 342.331053 -262.846124) (xy 342.318874 -262.79671) (xy 342.314779 -262.745982) (xy 341.996522 -262.745982)
			(xy 341.996027 -262.770589) (xy 341.988132 -262.819166) (xy 341.972548 -262.865847) (xy 341.949677 -262.909424)
			(xy 341.920112 -262.948768) (xy 341.884619 -262.98286) (xy 341.844116 -263.010816) (xy 341.799654 -263.031914)
			(xy 341.752383 -263.045606) (xy 341.703528 -263.051538) (xy 341.654353 -263.049557) (xy 341.606134 -263.039713)
			(xy 341.560118 -263.022261) (xy 341.517497 -262.997654) (xy 341.479376 -262.966529) (xy 341.446741 -262.929692)
			(xy 341.420438 -262.888096) (xy 341.401147 -262.84282) (xy 341.38937 -262.795036) (xy 341.38541 -262.745982)
			(xy 341.066882 -262.745982) (xy 341.06637 -262.771428) (xy 341.058206 -262.821662) (xy 341.04209 -262.869936)
			(xy 341.018439 -262.914999) (xy 340.987866 -262.955685) (xy 340.951162 -262.99094) (xy 340.909278 -263.01985)
			(xy 340.863299 -263.041667) (xy 340.814415 -263.055827) (xy 340.763894 -263.061961) (xy 340.713042 -263.059912)
			(xy 340.663178 -263.049732) (xy 340.615592 -263.031685) (xy 340.571518 -263.006239) (xy 340.532096 -262.974052)
			(xy 340.498348 -262.935958) (xy 340.471147 -262.892944) (xy 340.451199 -262.846124) (xy 340.43902 -262.79671)
			(xy 340.434925 -262.745982) (xy 340.116414 -262.745982) (xy 340.115919 -262.770589) (xy 340.108024 -262.819166)
			(xy 340.09244 -262.865847) (xy 340.069569 -262.909424) (xy 340.040004 -262.948768) (xy 340.004511 -262.98286)
			(xy 339.964008 -263.010816) (xy 339.919546 -263.031914) (xy 339.872275 -263.045606) (xy 339.82342 -263.051538)
			(xy 339.774245 -263.049557) (xy 339.726026 -263.039713) (xy 339.68001 -263.022261) (xy 339.637389 -262.997654)
			(xy 339.599268 -262.966529) (xy 339.566633 -262.929692) (xy 339.54033 -262.888096) (xy 339.521039 -262.84282)
			(xy 339.509262 -262.795036) (xy 339.505302 -262.745982) (xy 339.186774 -262.745982) (xy 339.186262 -262.771428)
			(xy 339.178098 -262.821662) (xy 339.161982 -262.869936) (xy 339.138331 -262.914999) (xy 339.107758 -262.955685)
			(xy 339.071054 -262.99094) (xy 339.02917 -263.01985) (xy 338.983191 -263.041667) (xy 338.934307 -263.055827)
			(xy 338.883786 -263.061961) (xy 338.832934 -263.059912) (xy 338.78307 -263.049732) (xy 338.735484 -263.031685)
			(xy 338.69141 -263.006239) (xy 338.651988 -262.974052) (xy 338.61824 -262.935958) (xy 338.591039 -262.892944)
			(xy 338.571091 -262.846124) (xy 338.558912 -262.79671) (xy 338.554817 -262.745982) (xy 338.236306 -262.745982)
			(xy 338.235811 -262.770589) (xy 338.227916 -262.819166) (xy 338.212332 -262.865847) (xy 338.189461 -262.909424)
			(xy 338.159896 -262.948768) (xy 338.124403 -262.98286) (xy 338.0839 -263.010816) (xy 338.039438 -263.031914)
			(xy 337.992167 -263.045606) (xy 337.943312 -263.051538) (xy 337.894137 -263.049557) (xy 337.845918 -263.039713)
			(xy 337.799902 -263.022261) (xy 337.757281 -262.997654) (xy 337.71916 -262.966529) (xy 337.686525 -262.929692)
			(xy 337.660222 -262.888096) (xy 337.640931 -262.84282) (xy 337.629154 -262.795036) (xy 337.625194 -262.745982)
			(xy 337.296506 -262.745982) (xy 337.296011 -262.770589) (xy 337.288116 -262.819166) (xy 337.272532 -262.865847)
			(xy 337.249661 -262.909424) (xy 337.220096 -262.948768) (xy 337.184603 -262.98286) (xy 337.1441 -263.010816)
			(xy 337.099638 -263.031914) (xy 337.052367 -263.045606) (xy 337.003512 -263.051538) (xy 336.954337 -263.049557)
			(xy 336.906118 -263.039713) (xy 336.860102 -263.022261) (xy 336.817481 -262.997654) (xy 336.77936 -262.966529)
			(xy 336.746725 -262.929692) (xy 336.720422 -262.888096) (xy 336.701131 -262.84282) (xy 336.689354 -262.795036)
			(xy 336.685394 -262.745982) (xy 336.356452 -262.745982) (xy 336.355957 -262.770589) (xy 336.348062 -262.819166)
			(xy 336.332478 -262.865847) (xy 336.309607 -262.909424) (xy 336.280042 -262.948768) (xy 336.244549 -262.98286)
			(xy 336.204046 -263.010816) (xy 336.159584 -263.031914) (xy 336.112313 -263.045606) (xy 336.063458 -263.051538)
			(xy 336.014283 -263.049557) (xy 335.966064 -263.039713) (xy 335.920048 -263.022261) (xy 335.877427 -262.997654)
			(xy 335.839306 -262.966529) (xy 335.806671 -262.929692) (xy 335.780368 -262.888096) (xy 335.761077 -262.84282)
			(xy 335.7493 -262.795036) (xy 335.74534 -262.745982) (xy 335.416977 -262.745982) (xy 335.416978 -262.746)
			(xy 335.412806 -262.796347) (xy 335.400404 -262.84532) (xy 335.38011 -262.891585) (xy 335.352478 -262.933877)
			(xy 335.318262 -262.971045) (xy 335.278394 -263.002074) (xy 335.233963 -263.026118) (xy 335.18618 -263.04252)
			(xy 335.13635 -263.050834) (xy 335.11109 -263.05129) (xy 335.110582 -263.05129) (xy 335.097433 -263.05114)
			(xy 335.071234 -263.048848) (xy 335.058258 -263.046718) (xy 335.054448 -263.04621) (xy 335.04378 -263.049258)
			(xy 335.03889 -263.05079) (xy 335.029801 -263.055523) (xy 335.025746 -263.058656) (xy 334.967072 -263.108948)
			(xy 334.959461 -263.116517) (xy 334.950682 -263.136077) (xy 334.950054 -263.146794) (xy 334.950054 -263.43737)
			(xy 334.952848 -263.445752) (xy 334.961675 -263.472455) (xy 334.971246 -263.527871) (xy 334.971898 -263.555988)
			(xy 335.275186 -263.555988) (xy 335.279146 -263.506934) (xy 335.290923 -263.45915) (xy 335.310214 -263.413874)
			(xy 335.336517 -263.372278) (xy 335.369152 -263.335441) (xy 335.407273 -263.304316) (xy 335.449894 -263.279709)
			(xy 335.49591 -263.262257) (xy 335.544129 -263.252413) (xy 335.593304 -263.250432) (xy 335.642159 -263.256364)
			(xy 335.68943 -263.270056) (xy 335.733892 -263.291154) (xy 335.774395 -263.31911) (xy 335.809888 -263.353202)
			(xy 335.839453 -263.392546) (xy 335.862324 -263.436123) (xy 335.877908 -263.482804) (xy 335.885803 -263.531381)
			(xy 335.886298 -263.555988) (xy 336.21524 -263.555988) (xy 336.2192 -263.506934) (xy 336.230977 -263.45915)
			(xy 336.250268 -263.413874) (xy 336.276571 -263.372278) (xy 336.309206 -263.335441) (xy 336.347327 -263.304316)
			(xy 336.389948 -263.279709) (xy 336.435964 -263.262257) (xy 336.484183 -263.252413) (xy 336.533358 -263.250432)
			(xy 336.582213 -263.256364) (xy 336.629484 -263.270056) (xy 336.673946 -263.291154) (xy 336.714449 -263.31911)
			(xy 336.749942 -263.353202) (xy 336.779507 -263.392546) (xy 336.802378 -263.436123) (xy 336.817962 -263.482804)
			(xy 336.825857 -263.531381) (xy 336.826352 -263.555988) (xy 337.155294 -263.555988) (xy 337.159254 -263.506934)
			(xy 337.171031 -263.45915) (xy 337.190322 -263.413874) (xy 337.216625 -263.372278) (xy 337.24926 -263.335441)
			(xy 337.287381 -263.304316) (xy 337.330002 -263.279709) (xy 337.376018 -263.262257) (xy 337.424237 -263.252413)
			(xy 337.473412 -263.250432) (xy 337.522267 -263.256364) (xy 337.569538 -263.270056) (xy 337.614 -263.291154)
			(xy 337.654503 -263.31911) (xy 337.689996 -263.353202) (xy 337.719561 -263.392546) (xy 337.742432 -263.436123)
			(xy 337.758016 -263.482804) (xy 337.765911 -263.531381) (xy 337.766406 -263.555988) (xy 338.095348 -263.555988)
			(xy 338.099308 -263.506934) (xy 338.111085 -263.45915) (xy 338.130376 -263.413874) (xy 338.156679 -263.372278)
			(xy 338.189314 -263.335441) (xy 338.227435 -263.304316) (xy 338.270056 -263.279709) (xy 338.316072 -263.262257)
			(xy 338.364291 -263.252413) (xy 338.413466 -263.250432) (xy 338.462321 -263.256364) (xy 338.509592 -263.270056)
			(xy 338.554054 -263.291154) (xy 338.594557 -263.31911) (xy 338.63005 -263.353202) (xy 338.659615 -263.392546)
			(xy 338.682486 -263.436123) (xy 338.69807 -263.482804) (xy 338.705965 -263.531381) (xy 338.70646 -263.555988)
			(xy 339.024971 -263.555988) (xy 339.029066 -263.50526) (xy 339.041245 -263.455846) (xy 339.061193 -263.409026)
			(xy 339.088394 -263.366012) (xy 339.122142 -263.327918) (xy 339.161564 -263.295731) (xy 339.205638 -263.270285)
			(xy 339.253224 -263.252238) (xy 339.303088 -263.242058) (xy 339.35394 -263.240009) (xy 339.404461 -263.246143)
			(xy 339.453345 -263.260303) (xy 339.499324 -263.28212) (xy 339.541208 -263.31103) (xy 339.577912 -263.346285)
			(xy 339.608485 -263.386971) (xy 339.632136 -263.432034) (xy 339.648252 -263.480308) (xy 339.656416 -263.530542)
			(xy 339.656928 -263.555988) (xy 339.964771 -263.555988) (xy 339.968866 -263.50526) (xy 339.981045 -263.455846)
			(xy 340.000993 -263.409026) (xy 340.028194 -263.366012) (xy 340.061942 -263.327918) (xy 340.101364 -263.295731)
			(xy 340.145438 -263.270285) (xy 340.193024 -263.252238) (xy 340.242888 -263.242058) (xy 340.29374 -263.240009)
			(xy 340.344261 -263.246143) (xy 340.393145 -263.260303) (xy 340.439124 -263.28212) (xy 340.481008 -263.31103)
			(xy 340.517712 -263.346285) (xy 340.548285 -263.386971) (xy 340.571936 -263.432034) (xy 340.588052 -263.480308)
			(xy 340.596216 -263.530542) (xy 340.596728 -263.555988) (xy 341.844879 -263.555988) (xy 341.848974 -263.50526)
			(xy 341.861153 -263.455846) (xy 341.881101 -263.409026) (xy 341.908302 -263.366012) (xy 341.94205 -263.327918)
			(xy 341.981472 -263.295731) (xy 342.025546 -263.270285) (xy 342.073132 -263.252238) (xy 342.122996 -263.242058)
			(xy 342.173848 -263.240009) (xy 342.224369 -263.246143) (xy 342.273253 -263.260303) (xy 342.319232 -263.28212)
			(xy 342.361116 -263.31103) (xy 342.39782 -263.346285) (xy 342.428393 -263.386971) (xy 342.452044 -263.432034)
			(xy 342.46816 -263.480308) (xy 342.476324 -263.530542) (xy 342.476836 -263.555988) (xy 342.795364 -263.555988)
			(xy 342.799324 -263.506934) (xy 342.811101 -263.45915) (xy 342.830392 -263.413874) (xy 342.856695 -263.372278)
			(xy 342.88933 -263.335441) (xy 342.927451 -263.304316) (xy 342.970072 -263.279709) (xy 343.016088 -263.262257)
			(xy 343.064307 -263.252413) (xy 343.113482 -263.250432) (xy 343.162337 -263.256364) (xy 343.209608 -263.270056)
			(xy 343.25407 -263.291154) (xy 343.294573 -263.31911) (xy 343.330066 -263.353202) (xy 343.359631 -263.392546)
			(xy 343.382502 -263.436123) (xy 343.398086 -263.482804) (xy 343.405981 -263.531381) (xy 343.406476 -263.555988)
			(xy 343.724987 -263.555988) (xy 343.729082 -263.50526) (xy 343.741261 -263.455846) (xy 343.761209 -263.409026)
			(xy 343.78841 -263.366012) (xy 343.822158 -263.327918) (xy 343.86158 -263.295731) (xy 343.905654 -263.270285)
			(xy 343.95324 -263.252238) (xy 344.003104 -263.242058) (xy 344.053956 -263.240009) (xy 344.104477 -263.246143)
			(xy 344.153361 -263.260303) (xy 344.19934 -263.28212) (xy 344.241224 -263.31103) (xy 344.277928 -263.346285)
			(xy 344.308501 -263.386971) (xy 344.332152 -263.432034) (xy 344.348268 -263.480308) (xy 344.356432 -263.530542)
			(xy 344.356944 -263.555988) (xy 345.615272 -263.555988) (xy 345.619232 -263.506934) (xy 345.631009 -263.45915)
			(xy 345.6503 -263.413874) (xy 345.676603 -263.372278) (xy 345.709238 -263.335441) (xy 345.747359 -263.304316)
			(xy 345.78998 -263.279709) (xy 345.835996 -263.262257) (xy 345.884215 -263.252413) (xy 345.93339 -263.250432)
			(xy 345.982245 -263.256364) (xy 346.029516 -263.270056) (xy 346.073978 -263.291154) (xy 346.114481 -263.31911)
			(xy 346.149974 -263.353202) (xy 346.179539 -263.392546) (xy 346.20241 -263.436123) (xy 346.217994 -263.482804)
			(xy 346.225889 -263.531381) (xy 346.226384 -263.555988) (xy 347.49538 -263.555988) (xy 347.49934 -263.506934)
			(xy 347.511117 -263.45915) (xy 347.530408 -263.413874) (xy 347.556711 -263.372278) (xy 347.589346 -263.335441)
			(xy 347.627467 -263.304316) (xy 347.670088 -263.279709) (xy 347.716104 -263.262257) (xy 347.764323 -263.252413)
			(xy 347.813498 -263.250432) (xy 347.862353 -263.256364) (xy 347.909624 -263.270056) (xy 347.954086 -263.291154)
			(xy 347.994589 -263.31911) (xy 348.030082 -263.353202) (xy 348.059647 -263.392546) (xy 348.082518 -263.436123)
			(xy 348.098102 -263.482804) (xy 348.105997 -263.531381) (xy 348.106492 -263.555988) (xy 348.105997 -263.580595)
			(xy 348.098102 -263.629172) (xy 348.082518 -263.675853) (xy 348.059647 -263.71943) (xy 348.030082 -263.758774)
			(xy 347.994589 -263.792866) (xy 347.954086 -263.820822) (xy 347.909624 -263.84192) (xy 347.862353 -263.855612)
			(xy 347.813498 -263.861544) (xy 347.764323 -263.859563) (xy 347.716104 -263.849719) (xy 347.670088 -263.832267)
			(xy 347.627467 -263.80766) (xy 347.589346 -263.776535) (xy 347.556711 -263.739698) (xy 347.530408 -263.698102)
			(xy 347.511117 -263.652826) (xy 347.49934 -263.605042) (xy 347.49538 -263.555988) (xy 346.226384 -263.555988)
			(xy 346.225889 -263.580595) (xy 346.217994 -263.629172) (xy 346.20241 -263.675853) (xy 346.179539 -263.71943)
			(xy 346.149974 -263.758774) (xy 346.114481 -263.792866) (xy 346.073978 -263.820822) (xy 346.029516 -263.84192)
			(xy 345.982245 -263.855612) (xy 345.93339 -263.861544) (xy 345.884215 -263.859563) (xy 345.835996 -263.849719)
			(xy 345.78998 -263.832267) (xy 345.747359 -263.80766) (xy 345.709238 -263.776535) (xy 345.676603 -263.739698)
			(xy 345.6503 -263.698102) (xy 345.631009 -263.652826) (xy 345.619232 -263.605042) (xy 345.615272 -263.555988)
			(xy 344.356944 -263.555988) (xy 344.356432 -263.581434) (xy 344.348268 -263.631668) (xy 344.332152 -263.679942)
			(xy 344.308501 -263.725005) (xy 344.277928 -263.765691) (xy 344.241224 -263.800946) (xy 344.19934 -263.829856)
			(xy 344.153361 -263.851673) (xy 344.104477 -263.865833) (xy 344.053956 -263.871967) (xy 344.003104 -263.869918)
			(xy 343.95324 -263.859738) (xy 343.905654 -263.841691) (xy 343.86158 -263.816245) (xy 343.822158 -263.784058)
			(xy 343.78841 -263.745964) (xy 343.761209 -263.70295) (xy 343.741261 -263.65613) (xy 343.729082 -263.606716)
			(xy 343.724987 -263.555988) (xy 343.406476 -263.555988) (xy 343.405981 -263.580595) (xy 343.398086 -263.629172)
			(xy 343.382502 -263.675853) (xy 343.359631 -263.71943) (xy 343.330066 -263.758774) (xy 343.294573 -263.792866)
			(xy 343.25407 -263.820822) (xy 343.209608 -263.84192) (xy 343.162337 -263.855612) (xy 343.113482 -263.861544)
			(xy 343.064307 -263.859563) (xy 343.016088 -263.849719) (xy 342.970072 -263.832267) (xy 342.927451 -263.80766)
			(xy 342.88933 -263.776535) (xy 342.856695 -263.739698) (xy 342.830392 -263.698102) (xy 342.811101 -263.652826)
			(xy 342.799324 -263.605042) (xy 342.795364 -263.555988) (xy 342.476836 -263.555988) (xy 342.476324 -263.581434)
			(xy 342.46816 -263.631668) (xy 342.452044 -263.679942) (xy 342.428393 -263.725005) (xy 342.39782 -263.765691)
			(xy 342.361116 -263.800946) (xy 342.319232 -263.829856) (xy 342.273253 -263.851673) (xy 342.224369 -263.865833)
			(xy 342.173848 -263.871967) (xy 342.122996 -263.869918) (xy 342.073132 -263.859738) (xy 342.025546 -263.841691)
			(xy 341.981472 -263.816245) (xy 341.94205 -263.784058) (xy 341.908302 -263.745964) (xy 341.881101 -263.70295)
			(xy 341.861153 -263.65613) (xy 341.848974 -263.606716) (xy 341.844879 -263.555988) (xy 340.596728 -263.555988)
			(xy 340.596216 -263.581434) (xy 340.588052 -263.631668) (xy 340.571936 -263.679942) (xy 340.548285 -263.725005)
			(xy 340.517712 -263.765691) (xy 340.481008 -263.800946) (xy 340.439124 -263.829856) (xy 340.393145 -263.851673)
			(xy 340.344261 -263.865833) (xy 340.29374 -263.871967) (xy 340.242888 -263.869918) (xy 340.193024 -263.859738)
			(xy 340.145438 -263.841691) (xy 340.101364 -263.816245) (xy 340.061942 -263.784058) (xy 340.028194 -263.745964)
			(xy 340.000993 -263.70295) (xy 339.981045 -263.65613) (xy 339.968866 -263.606716) (xy 339.964771 -263.555988)
			(xy 339.656928 -263.555988) (xy 339.656416 -263.581434) (xy 339.648252 -263.631668) (xy 339.632136 -263.679942)
			(xy 339.608485 -263.725005) (xy 339.577912 -263.765691) (xy 339.541208 -263.800946) (xy 339.499324 -263.829856)
			(xy 339.453345 -263.851673) (xy 339.404461 -263.865833) (xy 339.35394 -263.871967) (xy 339.303088 -263.869918)
			(xy 339.253224 -263.859738) (xy 339.205638 -263.841691) (xy 339.161564 -263.816245) (xy 339.122142 -263.784058)
			(xy 339.088394 -263.745964) (xy 339.061193 -263.70295) (xy 339.041245 -263.65613) (xy 339.029066 -263.606716)
			(xy 339.024971 -263.555988) (xy 338.70646 -263.555988) (xy 338.705965 -263.580595) (xy 338.69807 -263.629172)
			(xy 338.682486 -263.675853) (xy 338.659615 -263.71943) (xy 338.63005 -263.758774) (xy 338.594557 -263.792866)
			(xy 338.554054 -263.820822) (xy 338.509592 -263.84192) (xy 338.462321 -263.855612) (xy 338.413466 -263.861544)
			(xy 338.364291 -263.859563) (xy 338.316072 -263.849719) (xy 338.270056 -263.832267) (xy 338.227435 -263.80766)
			(xy 338.189314 -263.776535) (xy 338.156679 -263.739698) (xy 338.130376 -263.698102) (xy 338.111085 -263.652826)
			(xy 338.099308 -263.605042) (xy 338.095348 -263.555988) (xy 337.766406 -263.555988) (xy 337.765911 -263.580595)
			(xy 337.758016 -263.629172) (xy 337.742432 -263.675853) (xy 337.719561 -263.71943) (xy 337.689996 -263.758774)
			(xy 337.654503 -263.792866) (xy 337.614 -263.820822) (xy 337.569538 -263.84192) (xy 337.522267 -263.855612)
			(xy 337.473412 -263.861544) (xy 337.424237 -263.859563) (xy 337.376018 -263.849719) (xy 337.330002 -263.832267)
			(xy 337.287381 -263.80766) (xy 337.24926 -263.776535) (xy 337.216625 -263.739698) (xy 337.190322 -263.698102)
			(xy 337.171031 -263.652826) (xy 337.159254 -263.605042) (xy 337.155294 -263.555988) (xy 336.826352 -263.555988)
			(xy 336.825857 -263.580595) (xy 336.817962 -263.629172) (xy 336.802378 -263.675853) (xy 336.779507 -263.71943)
			(xy 336.749942 -263.758774) (xy 336.714449 -263.792866) (xy 336.673946 -263.820822) (xy 336.629484 -263.84192)
			(xy 336.582213 -263.855612) (xy 336.533358 -263.861544) (xy 336.484183 -263.859563) (xy 336.435964 -263.849719)
			(xy 336.389948 -263.832267) (xy 336.347327 -263.80766) (xy 336.309206 -263.776535) (xy 336.276571 -263.739698)
			(xy 336.250268 -263.698102) (xy 336.230977 -263.652826) (xy 336.2192 -263.605042) (xy 336.21524 -263.555988)
			(xy 335.886298 -263.555988) (xy 335.885803 -263.580595) (xy 335.877908 -263.629172) (xy 335.862324 -263.675853)
			(xy 335.839453 -263.71943) (xy 335.809888 -263.758774) (xy 335.774395 -263.792866) (xy 335.733892 -263.820822)
			(xy 335.68943 -263.84192) (xy 335.642159 -263.855612) (xy 335.593304 -263.861544) (xy 335.544129 -263.859563)
			(xy 335.49591 -263.849719) (xy 335.449894 -263.832267) (xy 335.407273 -263.80766) (xy 335.369152 -263.776535)
			(xy 335.336517 -263.739698) (xy 335.310214 -263.698102) (xy 335.290923 -263.652826) (xy 335.279146 -263.605042)
			(xy 335.275186 -263.555988) (xy 334.971898 -263.555988) (xy 334.971318 -263.584112) (xy 334.961746 -263.639539)
			(xy 334.952848 -263.666224) (xy 334.950054 -263.674606) (xy 334.950054 -263.964674) (xy 334.950054 -263.967214)
			(xy 334.950965 -263.976881) (xy 334.959067 -263.994509) (xy 334.965802 -264.001504) (xy 335.024476 -264.05205)
			(xy 335.028708 -264.055525) (xy 335.038318 -264.060771) (xy 335.043526 -264.062464) (xy 335.054194 -264.065512)
			(xy 335.065116 -264.063988) (xy 335.076354 -264.062432) (xy 335.098983 -264.060777) (xy 335.110328 -264.060686)
			(xy 335.11109 -264.060686) (xy 335.136349 -264.061178) (xy 335.186177 -264.069491) (xy 335.233958 -264.085893)
			(xy 335.278388 -264.109936) (xy 335.318254 -264.140963) (xy 335.352469 -264.17813) (xy 335.3801 -264.220421)
			(xy 335.400393 -264.266683) (xy 335.412794 -264.315655) (xy 335.416966 -264.365994) (xy 335.74534 -264.365994)
			(xy 335.7493 -264.31694) (xy 335.761077 -264.269156) (xy 335.780368 -264.22388) (xy 335.806671 -264.182284)
			(xy 335.839306 -264.145447) (xy 335.877427 -264.114322) (xy 335.920048 -264.089715) (xy 335.966064 -264.072263)
			(xy 336.014283 -264.062419) (xy 336.063458 -264.060438) (xy 336.112313 -264.06637) (xy 336.159584 -264.080062)
			(xy 336.204046 -264.10116) (xy 336.244549 -264.129116) (xy 336.280042 -264.163208) (xy 336.309607 -264.202552)
			(xy 336.332478 -264.246129) (xy 336.348062 -264.29281) (xy 336.355957 -264.341387) (xy 336.356452 -264.365994)
			(xy 336.685394 -264.365994) (xy 336.689354 -264.31694) (xy 336.701131 -264.269156) (xy 336.720422 -264.22388)
			(xy 336.746725 -264.182284) (xy 336.77936 -264.145447) (xy 336.817481 -264.114322) (xy 336.860102 -264.089715)
			(xy 336.906118 -264.072263) (xy 336.954337 -264.062419) (xy 337.003512 -264.060438) (xy 337.052367 -264.06637)
			(xy 337.099638 -264.080062) (xy 337.1441 -264.10116) (xy 337.184603 -264.129116) (xy 337.220096 -264.163208)
			(xy 337.249661 -264.202552) (xy 337.272532 -264.246129) (xy 337.288116 -264.29281) (xy 337.296011 -264.341387)
			(xy 337.296506 -264.365994) (xy 337.625194 -264.365994) (xy 337.629154 -264.31694) (xy 337.640931 -264.269156)
			(xy 337.660222 -264.22388) (xy 337.686525 -264.182284) (xy 337.71916 -264.145447) (xy 337.757281 -264.114322)
			(xy 337.799902 -264.089715) (xy 337.845918 -264.072263) (xy 337.894137 -264.062419) (xy 337.943312 -264.060438)
			(xy 337.992167 -264.06637) (xy 338.039438 -264.080062) (xy 338.0839 -264.10116) (xy 338.124403 -264.129116)
			(xy 338.159896 -264.163208) (xy 338.189461 -264.202552) (xy 338.212332 -264.246129) (xy 338.227916 -264.29281)
			(xy 338.235811 -264.341387) (xy 338.236306 -264.365994) (xy 338.554817 -264.365994) (xy 338.558912 -264.315266)
			(xy 338.571091 -264.265852) (xy 338.591039 -264.219032) (xy 338.61824 -264.176018) (xy 338.651988 -264.137924)
			(xy 338.69141 -264.105737) (xy 338.735484 -264.080291) (xy 338.78307 -264.062244) (xy 338.832934 -264.052064)
			(xy 338.883786 -264.050015) (xy 338.934307 -264.056149) (xy 338.983191 -264.070309) (xy 339.02917 -264.092126)
			(xy 339.071054 -264.121036) (xy 339.107758 -264.156291) (xy 339.138331 -264.196977) (xy 339.161982 -264.24204)
			(xy 339.178098 -264.290314) (xy 339.186262 -264.340548) (xy 339.186774 -264.365994) (xy 339.505302 -264.365994)
			(xy 339.509262 -264.31694) (xy 339.521039 -264.269156) (xy 339.54033 -264.22388) (xy 339.566633 -264.182284)
			(xy 339.599268 -264.145447) (xy 339.637389 -264.114322) (xy 339.68001 -264.089715) (xy 339.726026 -264.072263)
			(xy 339.774245 -264.062419) (xy 339.82342 -264.060438) (xy 339.872275 -264.06637) (xy 339.919546 -264.080062)
			(xy 339.964008 -264.10116) (xy 340.004511 -264.129116) (xy 340.040004 -264.163208) (xy 340.069569 -264.202552)
			(xy 340.09244 -264.246129) (xy 340.108024 -264.29281) (xy 340.115919 -264.341387) (xy 340.116414 -264.365994)
			(xy 340.434925 -264.365994) (xy 340.43902 -264.315266) (xy 340.451199 -264.265852) (xy 340.471147 -264.219032)
			(xy 340.498348 -264.176018) (xy 340.532096 -264.137924) (xy 340.571518 -264.105737) (xy 340.615592 -264.080291)
			(xy 340.663178 -264.062244) (xy 340.713042 -264.052064) (xy 340.763894 -264.050015) (xy 340.814415 -264.056149)
			(xy 340.863299 -264.070309) (xy 340.909278 -264.092126) (xy 340.951162 -264.121036) (xy 340.987866 -264.156291)
			(xy 341.018439 -264.196977) (xy 341.04209 -264.24204) (xy 341.058206 -264.290314) (xy 341.06637 -264.340548)
			(xy 341.066882 -264.365994) (xy 341.38541 -264.365994) (xy 341.38937 -264.31694) (xy 341.401147 -264.269156)
			(xy 341.420438 -264.22388) (xy 341.446741 -264.182284) (xy 341.479376 -264.145447) (xy 341.517497 -264.114322)
			(xy 341.560118 -264.089715) (xy 341.606134 -264.072263) (xy 341.654353 -264.062419) (xy 341.703528 -264.060438)
			(xy 341.752383 -264.06637) (xy 341.799654 -264.080062) (xy 341.844116 -264.10116) (xy 341.884619 -264.129116)
			(xy 341.920112 -264.163208) (xy 341.949677 -264.202552) (xy 341.972548 -264.246129) (xy 341.988132 -264.29281)
			(xy 341.996027 -264.341387) (xy 341.996522 -264.365994) (xy 342.314779 -264.365994) (xy 342.318874 -264.315266)
			(xy 342.331053 -264.265852) (xy 342.351001 -264.219032) (xy 342.378202 -264.176018) (xy 342.41195 -264.137924)
			(xy 342.451372 -264.105737) (xy 342.495446 -264.080291) (xy 342.543032 -264.062244) (xy 342.592896 -264.052064)
			(xy 342.643748 -264.050015) (xy 342.694269 -264.056149) (xy 342.743153 -264.070309) (xy 342.789132 -264.092126)
			(xy 342.831016 -264.121036) (xy 342.86772 -264.156291) (xy 342.898293 -264.196977) (xy 342.921944 -264.24204)
			(xy 342.93806 -264.290314) (xy 342.946224 -264.340548) (xy 342.946736 -264.365994) (xy 343.254833 -264.365994)
			(xy 343.258928 -264.315266) (xy 343.271107 -264.265852) (xy 343.291055 -264.219032) (xy 343.318256 -264.176018)
			(xy 343.352004 -264.137924) (xy 343.391426 -264.105737) (xy 343.4355 -264.080291) (xy 343.483086 -264.062244)
			(xy 343.53295 -264.052064) (xy 343.583802 -264.050015) (xy 343.634323 -264.056149) (xy 343.683207 -264.070309)
			(xy 343.729186 -264.092126) (xy 343.77107 -264.121036) (xy 343.807774 -264.156291) (xy 343.838347 -264.196977)
			(xy 343.861998 -264.24204) (xy 343.878114 -264.290314) (xy 343.886278 -264.340548) (xy 343.88679 -264.365994)
			(xy 344.205318 -264.365994) (xy 344.209278 -264.31694) (xy 344.221055 -264.269156) (xy 344.240346 -264.22388)
			(xy 344.266649 -264.182284) (xy 344.299284 -264.145447) (xy 344.337405 -264.114322) (xy 344.380026 -264.089715)
			(xy 344.426042 -264.072263) (xy 344.474261 -264.062419) (xy 344.523436 -264.060438) (xy 344.572291 -264.06637)
			(xy 344.619562 -264.080062) (xy 344.664024 -264.10116) (xy 344.704527 -264.129116) (xy 344.74002 -264.163208)
			(xy 344.769585 -264.202552) (xy 344.792456 -264.246129) (xy 344.80804 -264.29281) (xy 344.815935 -264.341387)
			(xy 344.81643 -264.365994) (xy 346.085426 -264.365994) (xy 346.089386 -264.31694) (xy 346.101163 -264.269156)
			(xy 346.120454 -264.22388) (xy 346.146757 -264.182284) (xy 346.179392 -264.145447) (xy 346.217513 -264.114322)
			(xy 346.260134 -264.089715) (xy 346.30615 -264.072263) (xy 346.354369 -264.062419) (xy 346.403544 -264.060438)
			(xy 346.452399 -264.06637) (xy 346.49967 -264.080062) (xy 346.544132 -264.10116) (xy 346.584635 -264.129116)
			(xy 346.620128 -264.163208) (xy 346.649693 -264.202552) (xy 346.672564 -264.246129) (xy 346.688148 -264.29281)
			(xy 346.696043 -264.341387) (xy 346.696538 -264.365994) (xy 347.96528 -264.365994) (xy 347.96924 -264.31694)
			(xy 347.981017 -264.269156) (xy 348.000308 -264.22388) (xy 348.026611 -264.182284) (xy 348.059246 -264.145447)
			(xy 348.097367 -264.114322) (xy 348.139988 -264.089715) (xy 348.186004 -264.072263) (xy 348.234223 -264.062419)
			(xy 348.283398 -264.060438) (xy 348.332253 -264.06637) (xy 348.379524 -264.080062) (xy 348.423986 -264.10116)
			(xy 348.464489 -264.129116) (xy 348.499982 -264.163208) (xy 348.529547 -264.202552) (xy 348.552418 -264.246129)
			(xy 348.568002 -264.29281) (xy 348.575897 -264.341387) (xy 348.576392 -264.365994) (xy 348.575897 -264.390601)
			(xy 348.568002 -264.439178) (xy 348.552418 -264.485859) (xy 348.529547 -264.529436) (xy 348.499982 -264.56878)
			(xy 348.464489 -264.602872) (xy 348.423986 -264.630828) (xy 348.379524 -264.651926) (xy 348.332253 -264.665618)
			(xy 348.283398 -264.67155) (xy 348.234223 -264.669569) (xy 348.186004 -264.659725) (xy 348.139988 -264.642273)
			(xy 348.097367 -264.617666) (xy 348.059246 -264.586541) (xy 348.026611 -264.549704) (xy 348.000308 -264.508108)
			(xy 347.981017 -264.462832) (xy 347.96924 -264.415048) (xy 347.96528 -264.365994) (xy 346.696538 -264.365994)
			(xy 346.696043 -264.390601) (xy 346.688148 -264.439178) (xy 346.672564 -264.485859) (xy 346.649693 -264.529436)
			(xy 346.620128 -264.56878) (xy 346.584635 -264.602872) (xy 346.544132 -264.630828) (xy 346.49967 -264.651926)
			(xy 346.452399 -264.665618) (xy 346.403544 -264.67155) (xy 346.354369 -264.669569) (xy 346.30615 -264.659725)
			(xy 346.260134 -264.642273) (xy 346.217513 -264.617666) (xy 346.179392 -264.586541) (xy 346.146757 -264.549704)
			(xy 346.120454 -264.508108) (xy 346.101163 -264.462832) (xy 346.089386 -264.415048) (xy 346.085426 -264.365994)
			(xy 344.81643 -264.365994) (xy 344.815935 -264.390601) (xy 344.80804 -264.439178) (xy 344.792456 -264.485859)
			(xy 344.769585 -264.529436) (xy 344.74002 -264.56878) (xy 344.704527 -264.602872) (xy 344.664024 -264.630828)
			(xy 344.619562 -264.651926) (xy 344.572291 -264.665618) (xy 344.523436 -264.67155) (xy 344.474261 -264.669569)
			(xy 344.426042 -264.659725) (xy 344.380026 -264.642273) (xy 344.337405 -264.617666) (xy 344.299284 -264.586541)
			(xy 344.266649 -264.549704) (xy 344.240346 -264.508108) (xy 344.221055 -264.462832) (xy 344.209278 -264.415048)
			(xy 344.205318 -264.365994) (xy 343.88679 -264.365994) (xy 343.886278 -264.39144) (xy 343.878114 -264.441674)
			(xy 343.861998 -264.489948) (xy 343.838347 -264.535011) (xy 343.807774 -264.575697) (xy 343.77107 -264.610952)
			(xy 343.729186 -264.639862) (xy 343.683207 -264.661679) (xy 343.634323 -264.675839) (xy 343.583802 -264.681973)
			(xy 343.53295 -264.679924) (xy 343.483086 -264.669744) (xy 343.4355 -264.651697) (xy 343.391426 -264.626251)
			(xy 343.352004 -264.594064) (xy 343.318256 -264.55597) (xy 343.291055 -264.512956) (xy 343.271107 -264.466136)
			(xy 343.258928 -264.416722) (xy 343.254833 -264.365994) (xy 342.946736 -264.365994) (xy 342.946224 -264.39144)
			(xy 342.93806 -264.441674) (xy 342.921944 -264.489948) (xy 342.898293 -264.535011) (xy 342.86772 -264.575697)
			(xy 342.831016 -264.610952) (xy 342.789132 -264.639862) (xy 342.743153 -264.661679) (xy 342.694269 -264.675839)
			(xy 342.643748 -264.681973) (xy 342.592896 -264.679924) (xy 342.543032 -264.669744) (xy 342.495446 -264.651697)
			(xy 342.451372 -264.626251) (xy 342.41195 -264.594064) (xy 342.378202 -264.55597) (xy 342.351001 -264.512956)
			(xy 342.331053 -264.466136) (xy 342.318874 -264.416722) (xy 342.314779 -264.365994) (xy 341.996522 -264.365994)
			(xy 341.996027 -264.390601) (xy 341.988132 -264.439178) (xy 341.972548 -264.485859) (xy 341.949677 -264.529436)
			(xy 341.920112 -264.56878) (xy 341.884619 -264.602872) (xy 341.844116 -264.630828) (xy 341.799654 -264.651926)
			(xy 341.752383 -264.665618) (xy 341.703528 -264.67155) (xy 341.654353 -264.669569) (xy 341.606134 -264.659725)
			(xy 341.560118 -264.642273) (xy 341.517497 -264.617666) (xy 341.479376 -264.586541) (xy 341.446741 -264.549704)
			(xy 341.420438 -264.508108) (xy 341.401147 -264.462832) (xy 341.38937 -264.415048) (xy 341.38541 -264.365994)
			(xy 341.066882 -264.365994) (xy 341.06637 -264.39144) (xy 341.058206 -264.441674) (xy 341.04209 -264.489948)
			(xy 341.018439 -264.535011) (xy 340.987866 -264.575697) (xy 340.951162 -264.610952) (xy 340.909278 -264.639862)
			(xy 340.863299 -264.661679) (xy 340.814415 -264.675839) (xy 340.763894 -264.681973) (xy 340.713042 -264.679924)
			(xy 340.663178 -264.669744) (xy 340.615592 -264.651697) (xy 340.571518 -264.626251) (xy 340.532096 -264.594064)
			(xy 340.498348 -264.55597) (xy 340.471147 -264.512956) (xy 340.451199 -264.466136) (xy 340.43902 -264.416722)
			(xy 340.434925 -264.365994) (xy 340.116414 -264.365994) (xy 340.115919 -264.390601) (xy 340.108024 -264.439178)
			(xy 340.09244 -264.485859) (xy 340.069569 -264.529436) (xy 340.040004 -264.56878) (xy 340.004511 -264.602872)
			(xy 339.964008 -264.630828) (xy 339.919546 -264.651926) (xy 339.872275 -264.665618) (xy 339.82342 -264.67155)
			(xy 339.774245 -264.669569) (xy 339.726026 -264.659725) (xy 339.68001 -264.642273) (xy 339.637389 -264.617666)
			(xy 339.599268 -264.586541) (xy 339.566633 -264.549704) (xy 339.54033 -264.508108) (xy 339.521039 -264.462832)
			(xy 339.509262 -264.415048) (xy 339.505302 -264.365994) (xy 339.186774 -264.365994) (xy 339.186262 -264.39144)
			(xy 339.178098 -264.441674) (xy 339.161982 -264.489948) (xy 339.138331 -264.535011) (xy 339.107758 -264.575697)
			(xy 339.071054 -264.610952) (xy 339.02917 -264.639862) (xy 338.983191 -264.661679) (xy 338.934307 -264.675839)
			(xy 338.883786 -264.681973) (xy 338.832934 -264.679924) (xy 338.78307 -264.669744) (xy 338.735484 -264.651697)
			(xy 338.69141 -264.626251) (xy 338.651988 -264.594064) (xy 338.61824 -264.55597) (xy 338.591039 -264.512956)
			(xy 338.571091 -264.466136) (xy 338.558912 -264.416722) (xy 338.554817 -264.365994) (xy 338.236306 -264.365994)
			(xy 338.235811 -264.390601) (xy 338.227916 -264.439178) (xy 338.212332 -264.485859) (xy 338.189461 -264.529436)
			(xy 338.159896 -264.56878) (xy 338.124403 -264.602872) (xy 338.0839 -264.630828) (xy 338.039438 -264.651926)
			(xy 337.992167 -264.665618) (xy 337.943312 -264.67155) (xy 337.894137 -264.669569) (xy 337.845918 -264.659725)
			(xy 337.799902 -264.642273) (xy 337.757281 -264.617666) (xy 337.71916 -264.586541) (xy 337.686525 -264.549704)
			(xy 337.660222 -264.508108) (xy 337.640931 -264.462832) (xy 337.629154 -264.415048) (xy 337.625194 -264.365994)
			(xy 337.296506 -264.365994) (xy 337.296011 -264.390601) (xy 337.288116 -264.439178) (xy 337.272532 -264.485859)
			(xy 337.249661 -264.529436) (xy 337.220096 -264.56878) (xy 337.184603 -264.602872) (xy 337.1441 -264.630828)
			(xy 337.099638 -264.651926) (xy 337.052367 -264.665618) (xy 337.003512 -264.67155) (xy 336.954337 -264.669569)
			(xy 336.906118 -264.659725) (xy 336.860102 -264.642273) (xy 336.817481 -264.617666) (xy 336.77936 -264.586541)
			(xy 336.746725 -264.549704) (xy 336.720422 -264.508108) (xy 336.701131 -264.462832) (xy 336.689354 -264.415048)
			(xy 336.685394 -264.365994) (xy 336.356452 -264.365994) (xy 336.355957 -264.390601) (xy 336.348062 -264.439178)
			(xy 336.332478 -264.485859) (xy 336.309607 -264.529436) (xy 336.280042 -264.56878) (xy 336.244549 -264.602872)
			(xy 336.204046 -264.630828) (xy 336.159584 -264.651926) (xy 336.112313 -264.665618) (xy 336.063458 -264.67155)
			(xy 336.014283 -264.669569) (xy 335.966064 -264.659725) (xy 335.920048 -264.642273) (xy 335.877427 -264.617666)
			(xy 335.839306 -264.586541) (xy 335.806671 -264.549704) (xy 335.780368 -264.508108) (xy 335.761077 -264.462832)
			(xy 335.7493 -264.415048) (xy 335.74534 -264.365994) (xy 335.416966 -264.365994) (xy 335.416966 -264.366)
			(xy 335.412794 -264.416345) (xy 335.400393 -264.465317) (xy 335.3801 -264.511579) (xy 335.352469 -264.55387)
			(xy 335.318254 -264.591037) (xy 335.278388 -264.622064) (xy 335.233958 -264.646107) (xy 335.186177 -264.662509)
			(xy 335.136349 -264.670822) (xy 335.11109 -264.671302) (xy 335.110582 -264.671302) (xy 335.097433 -264.671153)
			(xy 335.071234 -264.66886) (xy 335.058258 -264.66673) (xy 335.054448 -264.666222) (xy 335.04378 -264.66927)
			(xy 335.03889 -264.670803) (xy 335.029802 -264.675536) (xy 335.025746 -264.678668) (xy 334.967072 -264.72896)
			(xy 334.959463 -264.73653) (xy 334.950689 -264.756089) (xy 334.950054 -264.766806) (xy 334.950054 -265.176)
			(xy 335.275186 -265.176) (xy 335.279146 -265.126946) (xy 335.290923 -265.079162) (xy 335.310214 -265.033886)
			(xy 335.336517 -264.99229) (xy 335.369152 -264.955453) (xy 335.407273 -264.924328) (xy 335.449894 -264.899721)
			(xy 335.49591 -264.882269) (xy 335.544129 -264.872425) (xy 335.593304 -264.870444) (xy 335.642159 -264.876376)
			(xy 335.68943 -264.890068) (xy 335.733892 -264.911166) (xy 335.774395 -264.939122) (xy 335.809888 -264.973214)
			(xy 335.839453 -265.012558) (xy 335.862324 -265.056135) (xy 335.877908 -265.102816) (xy 335.885803 -265.151393)
			(xy 335.886298 -265.176) (xy 336.21524 -265.176) (xy 336.2192 -265.126946) (xy 336.230977 -265.079162)
			(xy 336.250268 -265.033886) (xy 336.276571 -264.99229) (xy 336.309206 -264.955453) (xy 336.347327 -264.924328)
			(xy 336.389948 -264.899721) (xy 336.435964 -264.882269) (xy 336.484183 -264.872425) (xy 336.533358 -264.870444)
			(xy 336.582213 -264.876376) (xy 336.629484 -264.890068) (xy 336.673946 -264.911166) (xy 336.714449 -264.939122)
			(xy 336.749942 -264.973214) (xy 336.779507 -265.012558) (xy 336.802378 -265.056135) (xy 336.817962 -265.102816)
			(xy 336.825857 -265.151393) (xy 336.826352 -265.176) (xy 337.155294 -265.176) (xy 337.159254 -265.126946)
			(xy 337.171031 -265.079162) (xy 337.190322 -265.033886) (xy 337.216625 -264.99229) (xy 337.24926 -264.955453)
			(xy 337.287381 -264.924328) (xy 337.330002 -264.899721) (xy 337.376018 -264.882269) (xy 337.424237 -264.872425)
			(xy 337.473412 -264.870444) (xy 337.522267 -264.876376) (xy 337.569538 -264.890068) (xy 337.614 -264.911166)
			(xy 337.654503 -264.939122) (xy 337.689996 -264.973214) (xy 337.719561 -265.012558) (xy 337.742432 -265.056135)
			(xy 337.758016 -265.102816) (xy 337.765911 -265.151393) (xy 337.766406 -265.176) (xy 338.095348 -265.176)
			(xy 338.099308 -265.126946) (xy 338.111085 -265.079162) (xy 338.130376 -265.033886) (xy 338.156679 -264.99229)
			(xy 338.189314 -264.955453) (xy 338.227435 -264.924328) (xy 338.270056 -264.899721) (xy 338.316072 -264.882269)
			(xy 338.364291 -264.872425) (xy 338.413466 -264.870444) (xy 338.462321 -264.876376) (xy 338.509592 -264.890068)
			(xy 338.554054 -264.911166) (xy 338.594557 -264.939122) (xy 338.63005 -264.973214) (xy 338.659615 -265.012558)
			(xy 338.682486 -265.056135) (xy 338.69807 -265.102816) (xy 338.705965 -265.151393) (xy 338.70646 -265.176)
			(xy 339.024971 -265.176) (xy 339.029066 -265.125272) (xy 339.041245 -265.075858) (xy 339.061193 -265.029038)
			(xy 339.088394 -264.986024) (xy 339.122142 -264.94793) (xy 339.161564 -264.915743) (xy 339.205638 -264.890297)
			(xy 339.253224 -264.87225) (xy 339.303088 -264.86207) (xy 339.35394 -264.860021) (xy 339.404461 -264.866155)
			(xy 339.453345 -264.880315) (xy 339.499324 -264.902132) (xy 339.541208 -264.931042) (xy 339.577912 -264.966297)
			(xy 339.608485 -265.006983) (xy 339.632136 -265.052046) (xy 339.648252 -265.10032) (xy 339.656416 -265.150554)
			(xy 339.656928 -265.176) (xy 339.975202 -265.176) (xy 339.979162 -265.126946) (xy 339.990939 -265.079162)
			(xy 340.01023 -265.033886) (xy 340.036533 -264.99229) (xy 340.069168 -264.955453) (xy 340.107289 -264.924328)
			(xy 340.14991 -264.899721) (xy 340.195926 -264.882269) (xy 340.244145 -264.872425) (xy 340.29332 -264.870444)
			(xy 340.342175 -264.876376) (xy 340.389446 -264.890068) (xy 340.433908 -264.911166) (xy 340.474411 -264.939122)
			(xy 340.509904 -264.973214) (xy 340.539469 -265.012558) (xy 340.56234 -265.056135) (xy 340.577924 -265.102816)
			(xy 340.585819 -265.151393) (xy 340.586314 -265.176) (xy 340.915256 -265.176) (xy 340.919216 -265.126946)
			(xy 340.930993 -265.079162) (xy 340.950284 -265.033886) (xy 340.976587 -264.99229) (xy 341.009222 -264.955453)
			(xy 341.047343 -264.924328) (xy 341.089964 -264.899721) (xy 341.13598 -264.882269) (xy 341.184199 -264.872425)
			(xy 341.233374 -264.870444) (xy 341.282229 -264.876376) (xy 341.3295 -264.890068) (xy 341.373962 -264.911166)
			(xy 341.414465 -264.939122) (xy 341.449958 -264.973214) (xy 341.479523 -265.012558) (xy 341.502394 -265.056135)
			(xy 341.517978 -265.102816) (xy 341.525873 -265.151393) (xy 341.526368 -265.176) (xy 341.844879 -265.176)
			(xy 341.848974 -265.125272) (xy 341.861153 -265.075858) (xy 341.881101 -265.029038) (xy 341.908302 -264.986024)
			(xy 341.94205 -264.94793) (xy 341.981472 -264.915743) (xy 342.025546 -264.890297) (xy 342.073132 -264.87225)
			(xy 342.122996 -264.86207) (xy 342.173848 -264.860021) (xy 342.224369 -264.866155) (xy 342.273253 -264.880315)
			(xy 342.319232 -264.902132) (xy 342.361116 -264.931042) (xy 342.39782 -264.966297) (xy 342.428393 -265.006983)
			(xy 342.452044 -265.052046) (xy 342.46816 -265.10032) (xy 342.476324 -265.150554) (xy 342.476836 -265.176)
			(xy 342.795364 -265.176) (xy 342.799324 -265.126946) (xy 342.811101 -265.079162) (xy 342.830392 -265.033886)
			(xy 342.856695 -264.99229) (xy 342.88933 -264.955453) (xy 342.927451 -264.924328) (xy 342.970072 -264.899721)
			(xy 343.016088 -264.882269) (xy 343.064307 -264.872425) (xy 343.113482 -264.870444) (xy 343.162337 -264.876376)
			(xy 343.209608 -264.890068) (xy 343.25407 -264.911166) (xy 343.294573 -264.939122) (xy 343.330066 -264.973214)
			(xy 343.359631 -265.012558) (xy 343.382502 -265.056135) (xy 343.398086 -265.102816) (xy 343.405981 -265.151393)
			(xy 343.406476 -265.176) (xy 343.735418 -265.176) (xy 343.739378 -265.126946) (xy 343.751155 -265.079162)
			(xy 343.770446 -265.033886) (xy 343.796749 -264.99229) (xy 343.829384 -264.955453) (xy 343.867505 -264.924328)
			(xy 343.910126 -264.899721) (xy 343.956142 -264.882269) (xy 344.004361 -264.872425) (xy 344.053536 -264.870444)
			(xy 344.102391 -264.876376) (xy 344.149662 -264.890068) (xy 344.194124 -264.911166) (xy 344.234627 -264.939122)
			(xy 344.27012 -264.973214) (xy 344.299685 -265.012558) (xy 344.322556 -265.056135) (xy 344.33814 -265.102816)
			(xy 344.346035 -265.151393) (xy 344.34653 -265.176) (xy 345.615272 -265.176) (xy 345.619232 -265.126946)
			(xy 345.631009 -265.079162) (xy 345.6503 -265.033886) (xy 345.676603 -264.99229) (xy 345.709238 -264.955453)
			(xy 345.747359 -264.924328) (xy 345.78998 -264.899721) (xy 345.835996 -264.882269) (xy 345.884215 -264.872425)
			(xy 345.93339 -264.870444) (xy 345.982245 -264.876376) (xy 346.029516 -264.890068) (xy 346.073978 -264.911166)
			(xy 346.114481 -264.939122) (xy 346.149974 -264.973214) (xy 346.179539 -265.012558) (xy 346.20241 -265.056135)
			(xy 346.217994 -265.102816) (xy 346.225889 -265.151393) (xy 346.226384 -265.176) (xy 347.49538 -265.176)
			(xy 347.49934 -265.126946) (xy 347.511117 -265.079162) (xy 347.530408 -265.033886) (xy 347.556711 -264.99229)
			(xy 347.589346 -264.955453) (xy 347.627467 -264.924328) (xy 347.670088 -264.899721) (xy 347.716104 -264.882269)
			(xy 347.764323 -264.872425) (xy 347.813498 -264.870444) (xy 347.862353 -264.876376) (xy 347.909624 -264.890068)
			(xy 347.954086 -264.911166) (xy 347.994589 -264.939122) (xy 348.030082 -264.973214) (xy 348.059647 -265.012558)
			(xy 348.082518 -265.056135) (xy 348.098102 -265.102816) (xy 348.105997 -265.151393) (xy 348.106492 -265.176)
			(xy 348.105997 -265.200607) (xy 348.098102 -265.249184) (xy 348.082518 -265.295865) (xy 348.059647 -265.339442)
			(xy 348.030082 -265.378786) (xy 347.994589 -265.412878) (xy 347.954086 -265.440834) (xy 347.909624 -265.461932)
			(xy 347.862353 -265.475624) (xy 347.813498 -265.481556) (xy 347.764323 -265.479575) (xy 347.716104 -265.469731)
			(xy 347.670088 -265.452279) (xy 347.627467 -265.427672) (xy 347.589346 -265.396547) (xy 347.556711 -265.35971)
			(xy 347.530408 -265.318114) (xy 347.511117 -265.272838) (xy 347.49934 -265.225054) (xy 347.49538 -265.176)
			(xy 346.226384 -265.176) (xy 346.225889 -265.200607) (xy 346.217994 -265.249184) (xy 346.20241 -265.295865)
			(xy 346.179539 -265.339442) (xy 346.149974 -265.378786) (xy 346.114481 -265.412878) (xy 346.073978 -265.440834)
			(xy 346.029516 -265.461932) (xy 345.982245 -265.475624) (xy 345.93339 -265.481556) (xy 345.884215 -265.479575)
			(xy 345.835996 -265.469731) (xy 345.78998 -265.452279) (xy 345.747359 -265.427672) (xy 345.709238 -265.396547)
			(xy 345.676603 -265.35971) (xy 345.6503 -265.318114) (xy 345.631009 -265.272838) (xy 345.619232 -265.225054)
			(xy 345.615272 -265.176) (xy 344.34653 -265.176) (xy 344.346035 -265.200607) (xy 344.33814 -265.249184)
			(xy 344.322556 -265.295865) (xy 344.299685 -265.339442) (xy 344.27012 -265.378786) (xy 344.234627 -265.412878)
			(xy 344.194124 -265.440834) (xy 344.149662 -265.461932) (xy 344.102391 -265.475624) (xy 344.053536 -265.481556)
			(xy 344.004361 -265.479575) (xy 343.956142 -265.469731) (xy 343.910126 -265.452279) (xy 343.867505 -265.427672)
			(xy 343.829384 -265.396547) (xy 343.796749 -265.35971) (xy 343.770446 -265.318114) (xy 343.751155 -265.272838)
			(xy 343.739378 -265.225054) (xy 343.735418 -265.176) (xy 343.406476 -265.176) (xy 343.405981 -265.200607)
			(xy 343.398086 -265.249184) (xy 343.382502 -265.295865) (xy 343.359631 -265.339442) (xy 343.330066 -265.378786)
			(xy 343.294573 -265.412878) (xy 343.25407 -265.440834) (xy 343.209608 -265.461932) (xy 343.162337 -265.475624)
			(xy 343.113482 -265.481556) (xy 343.064307 -265.479575) (xy 343.016088 -265.469731) (xy 342.970072 -265.452279)
			(xy 342.927451 -265.427672) (xy 342.88933 -265.396547) (xy 342.856695 -265.35971) (xy 342.830392 -265.318114)
			(xy 342.811101 -265.272838) (xy 342.799324 -265.225054) (xy 342.795364 -265.176) (xy 342.476836 -265.176)
			(xy 342.476324 -265.201446) (xy 342.46816 -265.25168) (xy 342.452044 -265.299954) (xy 342.428393 -265.345017)
			(xy 342.39782 -265.385703) (xy 342.361116 -265.420958) (xy 342.319232 -265.449868) (xy 342.273253 -265.471685)
			(xy 342.224369 -265.485845) (xy 342.173848 -265.491979) (xy 342.122996 -265.48993) (xy 342.073132 -265.47975)
			(xy 342.025546 -265.461703) (xy 341.981472 -265.436257) (xy 341.94205 -265.40407) (xy 341.908302 -265.365976)
			(xy 341.881101 -265.322962) (xy 341.861153 -265.276142) (xy 341.848974 -265.226728) (xy 341.844879 -265.176)
			(xy 341.526368 -265.176) (xy 341.525873 -265.200607) (xy 341.517978 -265.249184) (xy 341.502394 -265.295865)
			(xy 341.479523 -265.339442) (xy 341.449958 -265.378786) (xy 341.414465 -265.412878) (xy 341.373962 -265.440834)
			(xy 341.3295 -265.461932) (xy 341.282229 -265.475624) (xy 341.233374 -265.481556) (xy 341.184199 -265.479575)
			(xy 341.13598 -265.469731) (xy 341.089964 -265.452279) (xy 341.047343 -265.427672) (xy 341.009222 -265.396547)
			(xy 340.976587 -265.35971) (xy 340.950284 -265.318114) (xy 340.930993 -265.272838) (xy 340.919216 -265.225054)
			(xy 340.915256 -265.176) (xy 340.586314 -265.176) (xy 340.585819 -265.200607) (xy 340.577924 -265.249184)
			(xy 340.56234 -265.295865) (xy 340.539469 -265.339442) (xy 340.509904 -265.378786) (xy 340.474411 -265.412878)
			(xy 340.433908 -265.440834) (xy 340.389446 -265.461932) (xy 340.342175 -265.475624) (xy 340.29332 -265.481556)
			(xy 340.244145 -265.479575) (xy 340.195926 -265.469731) (xy 340.14991 -265.452279) (xy 340.107289 -265.427672)
			(xy 340.069168 -265.396547) (xy 340.036533 -265.35971) (xy 340.01023 -265.318114) (xy 339.990939 -265.272838)
			(xy 339.979162 -265.225054) (xy 339.975202 -265.176) (xy 339.656928 -265.176) (xy 339.656416 -265.201446)
			(xy 339.648252 -265.25168) (xy 339.632136 -265.299954) (xy 339.608485 -265.345017) (xy 339.577912 -265.385703)
			(xy 339.541208 -265.420958) (xy 339.499324 -265.449868) (xy 339.453345 -265.471685) (xy 339.404461 -265.485845)
			(xy 339.35394 -265.491979) (xy 339.303088 -265.48993) (xy 339.253224 -265.47975) (xy 339.205638 -265.461703)
			(xy 339.161564 -265.436257) (xy 339.122142 -265.40407) (xy 339.088394 -265.365976) (xy 339.061193 -265.322962)
			(xy 339.041245 -265.276142) (xy 339.029066 -265.226728) (xy 339.024971 -265.176) (xy 338.70646 -265.176)
			(xy 338.705965 -265.200607) (xy 338.69807 -265.249184) (xy 338.682486 -265.295865) (xy 338.659615 -265.339442)
			(xy 338.63005 -265.378786) (xy 338.594557 -265.412878) (xy 338.554054 -265.440834) (xy 338.509592 -265.461932)
			(xy 338.462321 -265.475624) (xy 338.413466 -265.481556) (xy 338.364291 -265.479575) (xy 338.316072 -265.469731)
			(xy 338.270056 -265.452279) (xy 338.227435 -265.427672) (xy 338.189314 -265.396547) (xy 338.156679 -265.35971)
			(xy 338.130376 -265.318114) (xy 338.111085 -265.272838) (xy 338.099308 -265.225054) (xy 338.095348 -265.176)
			(xy 337.766406 -265.176) (xy 337.765911 -265.200607) (xy 337.758016 -265.249184) (xy 337.742432 -265.295865)
			(xy 337.719561 -265.339442) (xy 337.689996 -265.378786) (xy 337.654503 -265.412878) (xy 337.614 -265.440834)
			(xy 337.569538 -265.461932) (xy 337.522267 -265.475624) (xy 337.473412 -265.481556) (xy 337.424237 -265.479575)
			(xy 337.376018 -265.469731) (xy 337.330002 -265.452279) (xy 337.287381 -265.427672) (xy 337.24926 -265.396547)
			(xy 337.216625 -265.35971) (xy 337.190322 -265.318114) (xy 337.171031 -265.272838) (xy 337.159254 -265.225054)
			(xy 337.155294 -265.176) (xy 336.826352 -265.176) (xy 336.825857 -265.200607) (xy 336.817962 -265.249184)
			(xy 336.802378 -265.295865) (xy 336.779507 -265.339442) (xy 336.749942 -265.378786) (xy 336.714449 -265.412878)
			(xy 336.673946 -265.440834) (xy 336.629484 -265.461932) (xy 336.582213 -265.475624) (xy 336.533358 -265.481556)
			(xy 336.484183 -265.479575) (xy 336.435964 -265.469731) (xy 336.389948 -265.452279) (xy 336.347327 -265.427672)
			(xy 336.309206 -265.396547) (xy 336.276571 -265.35971) (xy 336.250268 -265.318114) (xy 336.230977 -265.272838)
			(xy 336.2192 -265.225054) (xy 336.21524 -265.176) (xy 335.886298 -265.176) (xy 335.885803 -265.200607)
			(xy 335.877908 -265.249184) (xy 335.862324 -265.295865) (xy 335.839453 -265.339442) (xy 335.809888 -265.378786)
			(xy 335.774395 -265.412878) (xy 335.733892 -265.440834) (xy 335.68943 -265.461932) (xy 335.642159 -265.475624)
			(xy 335.593304 -265.481556) (xy 335.544129 -265.479575) (xy 335.49591 -265.469731) (xy 335.449894 -265.452279)
			(xy 335.407273 -265.427672) (xy 335.369152 -265.396547) (xy 335.336517 -265.35971) (xy 335.310214 -265.318114)
			(xy 335.290923 -265.272838) (xy 335.279146 -265.225054) (xy 335.275186 -265.176) (xy 334.950054 -265.176)
			(xy 334.950054 -265.986006) (xy 335.74534 -265.986006) (xy 335.7493 -265.936952) (xy 335.761077 -265.889168)
			(xy 335.780368 -265.843892) (xy 335.806671 -265.802296) (xy 335.839306 -265.765459) (xy 335.877427 -265.734334)
			(xy 335.920048 -265.709727) (xy 335.966064 -265.692275) (xy 336.014283 -265.682431) (xy 336.063458 -265.68045)
			(xy 336.112313 -265.686382) (xy 336.159584 -265.700074) (xy 336.204046 -265.721172) (xy 336.244549 -265.749128)
			(xy 336.280042 -265.78322) (xy 336.309607 -265.822564) (xy 336.332478 -265.866141) (xy 336.348062 -265.912822)
			(xy 336.355957 -265.961399) (xy 336.356452 -265.986006) (xy 336.685394 -265.986006) (xy 336.689354 -265.936952)
			(xy 336.701131 -265.889168) (xy 336.720422 -265.843892) (xy 336.746725 -265.802296) (xy 336.77936 -265.765459)
			(xy 336.817481 -265.734334) (xy 336.860102 -265.709727) (xy 336.906118 -265.692275) (xy 336.954337 -265.682431)
			(xy 337.003512 -265.68045) (xy 337.052367 -265.686382) (xy 337.099638 -265.700074) (xy 337.1441 -265.721172)
			(xy 337.184603 -265.749128) (xy 337.220096 -265.78322) (xy 337.249661 -265.822564) (xy 337.272532 -265.866141)
			(xy 337.288116 -265.912822) (xy 337.296011 -265.961399) (xy 337.296506 -265.986006) (xy 337.625194 -265.986006)
			(xy 337.629154 -265.936952) (xy 337.640931 -265.889168) (xy 337.660222 -265.843892) (xy 337.686525 -265.802296)
			(xy 337.71916 -265.765459) (xy 337.757281 -265.734334) (xy 337.799902 -265.709727) (xy 337.845918 -265.692275)
			(xy 337.894137 -265.682431) (xy 337.943312 -265.68045) (xy 337.992167 -265.686382) (xy 338.039438 -265.700074)
			(xy 338.0839 -265.721172) (xy 338.124403 -265.749128) (xy 338.159896 -265.78322) (xy 338.189461 -265.822564)
			(xy 338.212332 -265.866141) (xy 338.227916 -265.912822) (xy 338.235811 -265.961399) (xy 338.236306 -265.986006)
			(xy 338.565248 -265.986006) (xy 338.569208 -265.936952) (xy 338.580985 -265.889168) (xy 338.600276 -265.843892)
			(xy 338.626579 -265.802296) (xy 338.659214 -265.765459) (xy 338.697335 -265.734334) (xy 338.739956 -265.709727)
			(xy 338.785972 -265.692275) (xy 338.834191 -265.682431) (xy 338.883366 -265.68045) (xy 338.932221 -265.686382)
			(xy 338.979492 -265.700074) (xy 339.023954 -265.721172) (xy 339.064457 -265.749128) (xy 339.09995 -265.78322)
			(xy 339.129515 -265.822564) (xy 339.152386 -265.866141) (xy 339.16797 -265.912822) (xy 339.175865 -265.961399)
			(xy 339.17636 -265.986006) (xy 339.505302 -265.986006) (xy 339.509262 -265.936952) (xy 339.521039 -265.889168)
			(xy 339.54033 -265.843892) (xy 339.566633 -265.802296) (xy 339.599268 -265.765459) (xy 339.637389 -265.734334)
			(xy 339.68001 -265.709727) (xy 339.726026 -265.692275) (xy 339.774245 -265.682431) (xy 339.82342 -265.68045)
			(xy 339.872275 -265.686382) (xy 339.919546 -265.700074) (xy 339.964008 -265.721172) (xy 340.004511 -265.749128)
			(xy 340.040004 -265.78322) (xy 340.069569 -265.822564) (xy 340.09244 -265.866141) (xy 340.108024 -265.912822)
			(xy 340.115919 -265.961399) (xy 340.116414 -265.986006) (xy 340.434925 -265.986006) (xy 340.43902 -265.935278)
			(xy 340.451199 -265.885864) (xy 340.471147 -265.839044) (xy 340.498348 -265.79603) (xy 340.532096 -265.757936)
			(xy 340.571518 -265.725749) (xy 340.615592 -265.700303) (xy 340.663178 -265.682256) (xy 340.713042 -265.672076)
			(xy 340.763894 -265.670027) (xy 340.814415 -265.676161) (xy 340.863299 -265.690321) (xy 340.909278 -265.712138)
			(xy 340.951162 -265.741048) (xy 340.987866 -265.776303) (xy 341.018439 -265.816989) (xy 341.04209 -265.862052)
			(xy 341.058206 -265.910326) (xy 341.06637 -265.96056) (xy 341.066882 -265.986006) (xy 342.32521 -265.986006)
			(xy 342.32917 -265.936952) (xy 342.340947 -265.889168) (xy 342.360238 -265.843892) (xy 342.386541 -265.802296)
			(xy 342.419176 -265.765459) (xy 342.457297 -265.734334) (xy 342.499918 -265.709727) (xy 342.545934 -265.692275)
			(xy 342.594153 -265.682431) (xy 342.643328 -265.68045) (xy 342.692183 -265.686382) (xy 342.739454 -265.700074)
			(xy 342.783916 -265.721172) (xy 342.824419 -265.749128) (xy 342.859912 -265.78322) (xy 342.889477 -265.822564)
			(xy 342.912348 -265.866141) (xy 342.927932 -265.912822) (xy 342.935827 -265.961399) (xy 342.936322 -265.986006)
			(xy 343.254833 -265.986006) (xy 343.258928 -265.935278) (xy 343.271107 -265.885864) (xy 343.291055 -265.839044)
			(xy 343.318256 -265.79603) (xy 343.352004 -265.757936) (xy 343.391426 -265.725749) (xy 343.4355 -265.700303)
			(xy 343.483086 -265.682256) (xy 343.53295 -265.672076) (xy 343.583802 -265.670027) (xy 343.634323 -265.676161)
			(xy 343.683207 -265.690321) (xy 343.729186 -265.712138) (xy 343.77107 -265.741048) (xy 343.807774 -265.776303)
			(xy 343.838347 -265.816989) (xy 343.861998 -265.862052) (xy 343.878114 -265.910326) (xy 343.886278 -265.96056)
			(xy 343.88679 -265.986006) (xy 344.205318 -265.986006) (xy 344.209278 -265.936952) (xy 344.221055 -265.889168)
			(xy 344.240346 -265.843892) (xy 344.266649 -265.802296) (xy 344.299284 -265.765459) (xy 344.337405 -265.734334)
			(xy 344.380026 -265.709727) (xy 344.426042 -265.692275) (xy 344.474261 -265.682431) (xy 344.523436 -265.68045)
			(xy 344.572291 -265.686382) (xy 344.619562 -265.700074) (xy 344.664024 -265.721172) (xy 344.704527 -265.749128)
			(xy 344.74002 -265.78322) (xy 344.769585 -265.822564) (xy 344.792456 -265.866141) (xy 344.80804 -265.912822)
			(xy 344.815935 -265.961399) (xy 344.81643 -265.986006) (xy 344.815935 -266.010613) (xy 344.80804 -266.05919)
			(xy 344.792456 -266.105871) (xy 344.769585 -266.149448) (xy 344.74002 -266.188792) (xy 344.704527 -266.222884)
			(xy 344.664024 -266.25084) (xy 344.619562 -266.271938) (xy 344.572291 -266.28563) (xy 344.523436 -266.291562)
			(xy 344.474261 -266.289581) (xy 344.426042 -266.279737) (xy 344.380026 -266.262285) (xy 344.337405 -266.237678)
			(xy 344.299284 -266.206553) (xy 344.266649 -266.169716) (xy 344.240346 -266.12812) (xy 344.221055 -266.082844)
			(xy 344.209278 -266.03506) (xy 344.205318 -265.986006) (xy 343.88679 -265.986006) (xy 343.886278 -266.011452)
			(xy 343.878114 -266.061686) (xy 343.861998 -266.10996) (xy 343.838347 -266.155023) (xy 343.807774 -266.195709)
			(xy 343.77107 -266.230964) (xy 343.729186 -266.259874) (xy 343.683207 -266.281691) (xy 343.634323 -266.295851)
			(xy 343.583802 -266.301985) (xy 343.53295 -266.299936) (xy 343.483086 -266.289756) (xy 343.4355 -266.271709)
			(xy 343.391426 -266.246263) (xy 343.352004 -266.214076) (xy 343.318256 -266.175982) (xy 343.291055 -266.132968)
			(xy 343.271107 -266.086148) (xy 343.258928 -266.036734) (xy 343.254833 -265.986006) (xy 342.936322 -265.986006)
			(xy 342.935827 -266.010613) (xy 342.927932 -266.05919) (xy 342.912348 -266.105871) (xy 342.889477 -266.149448)
			(xy 342.859912 -266.188792) (xy 342.824419 -266.222884) (xy 342.783916 -266.25084) (xy 342.739454 -266.271938)
			(xy 342.692183 -266.28563) (xy 342.643328 -266.291562) (xy 342.594153 -266.289581) (xy 342.545934 -266.279737)
			(xy 342.499918 -266.262285) (xy 342.457297 -266.237678) (xy 342.419176 -266.206553) (xy 342.386541 -266.169716)
			(xy 342.360238 -266.12812) (xy 342.340947 -266.082844) (xy 342.32917 -266.03506) (xy 342.32521 -265.986006)
			(xy 341.066882 -265.986006) (xy 341.06637 -266.011452) (xy 341.058206 -266.061686) (xy 341.04209 -266.10996)
			(xy 341.018439 -266.155023) (xy 340.987866 -266.195709) (xy 340.951162 -266.230964) (xy 340.909278 -266.259874)
			(xy 340.863299 -266.281691) (xy 340.814415 -266.295851) (xy 340.763894 -266.301985) (xy 340.713042 -266.299936)
			(xy 340.663178 -266.289756) (xy 340.615592 -266.271709) (xy 340.571518 -266.246263) (xy 340.532096 -266.214076)
			(xy 340.498348 -266.175982) (xy 340.471147 -266.132968) (xy 340.451199 -266.086148) (xy 340.43902 -266.036734)
			(xy 340.434925 -265.986006) (xy 340.116414 -265.986006) (xy 340.115919 -266.010613) (xy 340.108024 -266.05919)
			(xy 340.09244 -266.105871) (xy 340.069569 -266.149448) (xy 340.040004 -266.188792) (xy 340.004511 -266.222884)
			(xy 339.964008 -266.25084) (xy 339.919546 -266.271938) (xy 339.872275 -266.28563) (xy 339.82342 -266.291562)
			(xy 339.774245 -266.289581) (xy 339.726026 -266.279737) (xy 339.68001 -266.262285) (xy 339.637389 -266.237678)
			(xy 339.599268 -266.206553) (xy 339.566633 -266.169716) (xy 339.54033 -266.12812) (xy 339.521039 -266.082844)
			(xy 339.509262 -266.03506) (xy 339.505302 -265.986006) (xy 339.17636 -265.986006) (xy 339.175865 -266.010613)
			(xy 339.16797 -266.05919) (xy 339.152386 -266.105871) (xy 339.129515 -266.149448) (xy 339.09995 -266.188792)
			(xy 339.064457 -266.222884) (xy 339.023954 -266.25084) (xy 338.979492 -266.271938) (xy 338.932221 -266.28563)
			(xy 338.883366 -266.291562) (xy 338.834191 -266.289581) (xy 338.785972 -266.279737) (xy 338.739956 -266.262285)
			(xy 338.697335 -266.237678) (xy 338.659214 -266.206553) (xy 338.626579 -266.169716) (xy 338.600276 -266.12812)
			(xy 338.580985 -266.082844) (xy 338.569208 -266.03506) (xy 338.565248 -265.986006) (xy 338.236306 -265.986006)
			(xy 338.235811 -266.010613) (xy 338.227916 -266.05919) (xy 338.212332 -266.105871) (xy 338.189461 -266.149448)
			(xy 338.159896 -266.188792) (xy 338.124403 -266.222884) (xy 338.0839 -266.25084) (xy 338.039438 -266.271938)
			(xy 337.992167 -266.28563) (xy 337.943312 -266.291562) (xy 337.894137 -266.289581) (xy 337.845918 -266.279737)
			(xy 337.799902 -266.262285) (xy 337.757281 -266.237678) (xy 337.71916 -266.206553) (xy 337.686525 -266.169716)
			(xy 337.660222 -266.12812) (xy 337.640931 -266.082844) (xy 337.629154 -266.03506) (xy 337.625194 -265.986006)
			(xy 337.296506 -265.986006) (xy 337.296011 -266.010613) (xy 337.288116 -266.05919) (xy 337.272532 -266.105871)
			(xy 337.249661 -266.149448) (xy 337.220096 -266.188792) (xy 337.184603 -266.222884) (xy 337.1441 -266.25084)
			(xy 337.099638 -266.271938) (xy 337.052367 -266.28563) (xy 337.003512 -266.291562) (xy 336.954337 -266.289581)
			(xy 336.906118 -266.279737) (xy 336.860102 -266.262285) (xy 336.817481 -266.237678) (xy 336.77936 -266.206553)
			(xy 336.746725 -266.169716) (xy 336.720422 -266.12812) (xy 336.701131 -266.082844) (xy 336.689354 -266.03506)
			(xy 336.685394 -265.986006) (xy 336.356452 -265.986006) (xy 336.355957 -266.010613) (xy 336.348062 -266.05919)
			(xy 336.332478 -266.105871) (xy 336.309607 -266.149448) (xy 336.280042 -266.188792) (xy 336.244549 -266.222884)
			(xy 336.204046 -266.25084) (xy 336.159584 -266.271938) (xy 336.112313 -266.28563) (xy 336.063458 -266.291562)
			(xy 336.014283 -266.289581) (xy 335.966064 -266.279737) (xy 335.920048 -266.262285) (xy 335.877427 -266.237678)
			(xy 335.839306 -266.206553) (xy 335.806671 -266.169716) (xy 335.780368 -266.12812) (xy 335.761077 -266.082844)
			(xy 335.7493 -266.03506) (xy 335.74534 -265.986006) (xy 334.950054 -265.986006) (xy 334.950054 -266.796012)
			(xy 335.275186 -266.796012) (xy 335.279146 -266.746958) (xy 335.290923 -266.699174) (xy 335.310214 -266.653898)
			(xy 335.336517 -266.612302) (xy 335.369152 -266.575465) (xy 335.407273 -266.54434) (xy 335.449894 -266.519733)
			(xy 335.49591 -266.502281) (xy 335.544129 -266.492437) (xy 335.593304 -266.490456) (xy 335.642159 -266.496388)
			(xy 335.68943 -266.51008) (xy 335.733892 -266.531178) (xy 335.774395 -266.559134) (xy 335.809888 -266.593226)
			(xy 335.839453 -266.63257) (xy 335.862324 -266.676147) (xy 335.877908 -266.722828) (xy 335.885803 -266.771405)
			(xy 335.886298 -266.796012) (xy 336.21524 -266.796012) (xy 336.2192 -266.746958) (xy 336.230977 -266.699174)
			(xy 336.250268 -266.653898) (xy 336.276571 -266.612302) (xy 336.309206 -266.575465) (xy 336.347327 -266.54434)
			(xy 336.389948 -266.519733) (xy 336.435964 -266.502281) (xy 336.484183 -266.492437) (xy 336.533358 -266.490456)
			(xy 336.582213 -266.496388) (xy 336.629484 -266.51008) (xy 336.673946 -266.531178) (xy 336.714449 -266.559134)
			(xy 336.749942 -266.593226) (xy 336.779507 -266.63257) (xy 336.802378 -266.676147) (xy 336.817962 -266.722828)
			(xy 336.825857 -266.771405) (xy 336.826352 -266.796012) (xy 337.155294 -266.796012) (xy 337.159254 -266.746958)
			(xy 337.171031 -266.699174) (xy 337.190322 -266.653898) (xy 337.216625 -266.612302) (xy 337.24926 -266.575465)
			(xy 337.287381 -266.54434) (xy 337.330002 -266.519733) (xy 337.376018 -266.502281) (xy 337.424237 -266.492437)
			(xy 337.473412 -266.490456) (xy 337.522267 -266.496388) (xy 337.569538 -266.51008) (xy 337.614 -266.531178)
			(xy 337.654503 -266.559134) (xy 337.689996 -266.593226) (xy 337.719561 -266.63257) (xy 337.742432 -266.676147)
			(xy 337.758016 -266.722828) (xy 337.765911 -266.771405) (xy 337.766406 -266.796012) (xy 338.095348 -266.796012)
			(xy 338.099308 -266.746958) (xy 338.111085 -266.699174) (xy 338.130376 -266.653898) (xy 338.156679 -266.612302)
			(xy 338.189314 -266.575465) (xy 338.227435 -266.54434) (xy 338.270056 -266.519733) (xy 338.316072 -266.502281)
			(xy 338.364291 -266.492437) (xy 338.413466 -266.490456) (xy 338.462321 -266.496388) (xy 338.509592 -266.51008)
			(xy 338.554054 -266.531178) (xy 338.594557 -266.559134) (xy 338.63005 -266.593226) (xy 338.659615 -266.63257)
			(xy 338.682486 -266.676147) (xy 338.69807 -266.722828) (xy 338.705965 -266.771405) (xy 338.70646 -266.796012)
			(xy 339.024971 -266.796012) (xy 339.029066 -266.745284) (xy 339.041245 -266.69587) (xy 339.061193 -266.64905)
			(xy 339.088394 -266.606036) (xy 339.122142 -266.567942) (xy 339.161564 -266.535755) (xy 339.205638 -266.510309)
			(xy 339.253224 -266.492262) (xy 339.303088 -266.482082) (xy 339.35394 -266.480033) (xy 339.404461 -266.486167)
			(xy 339.453345 -266.500327) (xy 339.499324 -266.522144) (xy 339.541208 -266.551054) (xy 339.577912 -266.586309)
			(xy 339.608485 -266.626995) (xy 339.632136 -266.672058) (xy 339.648252 -266.720332) (xy 339.656416 -266.770566)
			(xy 339.656928 -266.796012) (xy 339.964771 -266.796012) (xy 339.968866 -266.745284) (xy 339.981045 -266.69587)
			(xy 340.000993 -266.64905) (xy 340.028194 -266.606036) (xy 340.061942 -266.567942) (xy 340.101364 -266.535755)
			(xy 340.145438 -266.510309) (xy 340.193024 -266.492262) (xy 340.242888 -266.482082) (xy 340.29374 -266.480033)
			(xy 340.344261 -266.486167) (xy 340.393145 -266.500327) (xy 340.439124 -266.522144) (xy 340.481008 -266.551054)
			(xy 340.517712 -266.586309) (xy 340.548285 -266.626995) (xy 340.571936 -266.672058) (xy 340.588052 -266.720332)
			(xy 340.596216 -266.770566) (xy 340.596728 -266.796012) (xy 340.915256 -266.796012) (xy 340.919216 -266.746958)
			(xy 340.930993 -266.699174) (xy 340.950284 -266.653898) (xy 340.976587 -266.612302) (xy 341.009222 -266.575465)
			(xy 341.047343 -266.54434) (xy 341.089964 -266.519733) (xy 341.13598 -266.502281) (xy 341.184199 -266.492437)
			(xy 341.233374 -266.490456) (xy 341.282229 -266.496388) (xy 341.3295 -266.51008) (xy 341.373962 -266.531178)
			(xy 341.414465 -266.559134) (xy 341.449958 -266.593226) (xy 341.479523 -266.63257) (xy 341.502394 -266.676147)
			(xy 341.517978 -266.722828) (xy 341.525873 -266.771405) (xy 341.526368 -266.796012) (xy 341.844879 -266.796012)
			(xy 341.848974 -266.745284) (xy 341.861153 -266.69587) (xy 341.881101 -266.64905) (xy 341.908302 -266.606036)
			(xy 341.94205 -266.567942) (xy 341.981472 -266.535755) (xy 342.025546 -266.510309) (xy 342.073132 -266.492262)
			(xy 342.122996 -266.482082) (xy 342.173848 -266.480033) (xy 342.224369 -266.486167) (xy 342.273253 -266.500327)
			(xy 342.319232 -266.522144) (xy 342.361116 -266.551054) (xy 342.39782 -266.586309) (xy 342.428393 -266.626995)
			(xy 342.452044 -266.672058) (xy 342.46816 -266.720332) (xy 342.476324 -266.770566) (xy 342.476836 -266.796012)
			(xy 342.795364 -266.796012) (xy 342.799324 -266.746958) (xy 342.811101 -266.699174) (xy 342.830392 -266.653898)
			(xy 342.856695 -266.612302) (xy 342.88933 -266.575465) (xy 342.927451 -266.54434) (xy 342.970072 -266.519733)
			(xy 343.016088 -266.502281) (xy 343.064307 -266.492437) (xy 343.113482 -266.490456) (xy 343.162337 -266.496388)
			(xy 343.209608 -266.51008) (xy 343.25407 -266.531178) (xy 343.294573 -266.559134) (xy 343.330066 -266.593226)
			(xy 343.359631 -266.63257) (xy 343.382502 -266.676147) (xy 343.398086 -266.722828) (xy 343.405981 -266.771405)
			(xy 343.406476 -266.796012) (xy 343.724987 -266.796012) (xy 343.729082 -266.745284) (xy 343.741261 -266.69587)
			(xy 343.761209 -266.64905) (xy 343.78841 -266.606036) (xy 343.822158 -266.567942) (xy 343.86158 -266.535755)
			(xy 343.905654 -266.510309) (xy 343.95324 -266.492262) (xy 344.003104 -266.482082) (xy 344.053956 -266.480033)
			(xy 344.104477 -266.486167) (xy 344.153361 -266.500327) (xy 344.19934 -266.522144) (xy 344.241224 -266.551054)
			(xy 344.277928 -266.586309) (xy 344.308501 -266.626995) (xy 344.332152 -266.672058) (xy 344.348268 -266.720332)
			(xy 344.356432 -266.770566) (xy 344.356944 -266.796012) (xy 344.356432 -266.821458) (xy 344.348268 -266.871692)
			(xy 344.332152 -266.919966) (xy 344.308501 -266.965029) (xy 344.277928 -267.005715) (xy 344.241224 -267.04097)
			(xy 344.19934 -267.06988) (xy 344.153361 -267.091697) (xy 344.104477 -267.105857) (xy 344.053956 -267.111991)
			(xy 344.003104 -267.109942) (xy 343.95324 -267.099762) (xy 343.905654 -267.081715) (xy 343.86158 -267.056269)
			(xy 343.822158 -267.024082) (xy 343.78841 -266.985988) (xy 343.761209 -266.942974) (xy 343.741261 -266.896154)
			(xy 343.729082 -266.84674) (xy 343.724987 -266.796012) (xy 343.406476 -266.796012) (xy 343.405981 -266.820619)
			(xy 343.398086 -266.869196) (xy 343.382502 -266.915877) (xy 343.359631 -266.959454) (xy 343.330066 -266.998798)
			(xy 343.294573 -267.03289) (xy 343.25407 -267.060846) (xy 343.209608 -267.081944) (xy 343.162337 -267.095636)
			(xy 343.113482 -267.101568) (xy 343.064307 -267.099587) (xy 343.016088 -267.089743) (xy 342.970072 -267.072291)
			(xy 342.927451 -267.047684) (xy 342.88933 -267.016559) (xy 342.856695 -266.979722) (xy 342.830392 -266.938126)
			(xy 342.811101 -266.89285) (xy 342.799324 -266.845066) (xy 342.795364 -266.796012) (xy 342.476836 -266.796012)
			(xy 342.476324 -266.821458) (xy 342.46816 -266.871692) (xy 342.452044 -266.919966) (xy 342.428393 -266.965029)
			(xy 342.39782 -267.005715) (xy 342.361116 -267.04097) (xy 342.319232 -267.06988) (xy 342.273253 -267.091697)
			(xy 342.224369 -267.105857) (xy 342.173848 -267.111991) (xy 342.122996 -267.109942) (xy 342.073132 -267.099762)
			(xy 342.025546 -267.081715) (xy 341.981472 -267.056269) (xy 341.94205 -267.024082) (xy 341.908302 -266.985988)
			(xy 341.881101 -266.942974) (xy 341.861153 -266.896154) (xy 341.848974 -266.84674) (xy 341.844879 -266.796012)
			(xy 341.526368 -266.796012) (xy 341.525873 -266.820619) (xy 341.517978 -266.869196) (xy 341.502394 -266.915877)
			(xy 341.479523 -266.959454) (xy 341.449958 -266.998798) (xy 341.414465 -267.03289) (xy 341.373962 -267.060846)
			(xy 341.3295 -267.081944) (xy 341.282229 -267.095636) (xy 341.233374 -267.101568) (xy 341.184199 -267.099587)
			(xy 341.13598 -267.089743) (xy 341.089964 -267.072291) (xy 341.047343 -267.047684) (xy 341.009222 -267.016559)
			(xy 340.976587 -266.979722) (xy 340.950284 -266.938126) (xy 340.930993 -266.89285) (xy 340.919216 -266.845066)
			(xy 340.915256 -266.796012) (xy 340.596728 -266.796012) (xy 340.596216 -266.821458) (xy 340.588052 -266.871692)
			(xy 340.571936 -266.919966) (xy 340.548285 -266.965029) (xy 340.517712 -267.005715) (xy 340.481008 -267.04097)
			(xy 340.439124 -267.06988) (xy 340.393145 -267.091697) (xy 340.344261 -267.105857) (xy 340.29374 -267.111991)
			(xy 340.242888 -267.109942) (xy 340.193024 -267.099762) (xy 340.145438 -267.081715) (xy 340.101364 -267.056269)
			(xy 340.061942 -267.024082) (xy 340.028194 -266.985988) (xy 340.000993 -266.942974) (xy 339.981045 -266.896154)
			(xy 339.968866 -266.84674) (xy 339.964771 -266.796012) (xy 339.656928 -266.796012) (xy 339.656416 -266.821458)
			(xy 339.648252 -266.871692) (xy 339.632136 -266.919966) (xy 339.608485 -266.965029) (xy 339.577912 -267.005715)
			(xy 339.541208 -267.04097) (xy 339.499324 -267.06988) (xy 339.453345 -267.091697) (xy 339.404461 -267.105857)
			(xy 339.35394 -267.111991) (xy 339.303088 -267.109942) (xy 339.253224 -267.099762) (xy 339.205638 -267.081715)
			(xy 339.161564 -267.056269) (xy 339.122142 -267.024082) (xy 339.088394 -266.985988) (xy 339.061193 -266.942974)
			(xy 339.041245 -266.896154) (xy 339.029066 -266.84674) (xy 339.024971 -266.796012) (xy 338.70646 -266.796012)
			(xy 338.705965 -266.820619) (xy 338.69807 -266.869196) (xy 338.682486 -266.915877) (xy 338.659615 -266.959454)
			(xy 338.63005 -266.998798) (xy 338.594557 -267.03289) (xy 338.554054 -267.060846) (xy 338.509592 -267.081944)
			(xy 338.462321 -267.095636) (xy 338.413466 -267.101568) (xy 338.364291 -267.099587) (xy 338.316072 -267.089743)
			(xy 338.270056 -267.072291) (xy 338.227435 -267.047684) (xy 338.189314 -267.016559) (xy 338.156679 -266.979722)
			(xy 338.130376 -266.938126) (xy 338.111085 -266.89285) (xy 338.099308 -266.845066) (xy 338.095348 -266.796012)
			(xy 337.766406 -266.796012) (xy 337.765911 -266.820619) (xy 337.758016 -266.869196) (xy 337.742432 -266.915877)
			(xy 337.719561 -266.959454) (xy 337.689996 -266.998798) (xy 337.654503 -267.03289) (xy 337.614 -267.060846)
			(xy 337.569538 -267.081944) (xy 337.522267 -267.095636) (xy 337.473412 -267.101568) (xy 337.424237 -267.099587)
			(xy 337.376018 -267.089743) (xy 337.330002 -267.072291) (xy 337.287381 -267.047684) (xy 337.24926 -267.016559)
			(xy 337.216625 -266.979722) (xy 337.190322 -266.938126) (xy 337.171031 -266.89285) (xy 337.159254 -266.845066)
			(xy 337.155294 -266.796012) (xy 336.826352 -266.796012) (xy 336.825857 -266.820619) (xy 336.817962 -266.869196)
			(xy 336.802378 -266.915877) (xy 336.779507 -266.959454) (xy 336.749942 -266.998798) (xy 336.714449 -267.03289)
			(xy 336.673946 -267.060846) (xy 336.629484 -267.081944) (xy 336.582213 -267.095636) (xy 336.533358 -267.101568)
			(xy 336.484183 -267.099587) (xy 336.435964 -267.089743) (xy 336.389948 -267.072291) (xy 336.347327 -267.047684)
			(xy 336.309206 -267.016559) (xy 336.276571 -266.979722) (xy 336.250268 -266.938126) (xy 336.230977 -266.89285)
			(xy 336.2192 -266.845066) (xy 336.21524 -266.796012) (xy 335.886298 -266.796012) (xy 335.885803 -266.820619)
			(xy 335.877908 -266.869196) (xy 335.862324 -266.915877) (xy 335.839453 -266.959454) (xy 335.809888 -266.998798)
			(xy 335.774395 -267.03289) (xy 335.733892 -267.060846) (xy 335.68943 -267.081944) (xy 335.642159 -267.095636)
			(xy 335.593304 -267.101568) (xy 335.544129 -267.099587) (xy 335.49591 -267.089743) (xy 335.449894 -267.072291)
			(xy 335.407273 -267.047684) (xy 335.369152 -267.016559) (xy 335.336517 -266.979722) (xy 335.310214 -266.938126)
			(xy 335.290923 -266.89285) (xy 335.279146 -266.845066) (xy 335.275186 -266.796012) (xy 334.950054 -266.796012)
			(xy 334.950054 -267.204698) (xy 334.950054 -267.207238) (xy 334.950969 -267.216903) (xy 334.959076 -267.234525)
			(xy 334.965802 -267.241528) (xy 335.024476 -267.292074) (xy 335.028709 -267.295547) (xy 335.038319 -267.300792)
			(xy 335.043526 -267.302488) (xy 335.054194 -267.305536) (xy 335.065116 -267.304012) (xy 335.076354 -267.302456)
			(xy 335.098983 -267.300801) (xy 335.110328 -267.30071) (xy 335.11109 -267.30071) (xy 335.136347 -267.301202)
			(xy 335.186172 -267.309515) (xy 335.233949 -267.325915) (xy 335.278374 -267.349956) (xy 335.318237 -267.380981)
			(xy 335.35245 -267.418145) (xy 335.380079 -267.460433) (xy 335.40037 -267.506691) (xy 335.412771 -267.555659)
			(xy 335.416942 -267.606) (xy 335.416941 -267.606018) (xy 335.74534 -267.606018) (xy 335.7493 -267.556964)
			(xy 335.761077 -267.50918) (xy 335.780368 -267.463904) (xy 335.806671 -267.422308) (xy 335.839306 -267.385471)
			(xy 335.877427 -267.354346) (xy 335.920048 -267.329739) (xy 335.966064 -267.312287) (xy 336.014283 -267.302443)
			(xy 336.063458 -267.300462) (xy 336.112313 -267.306394) (xy 336.159584 -267.320086) (xy 336.204046 -267.341184)
			(xy 336.244549 -267.36914) (xy 336.280042 -267.403232) (xy 336.309607 -267.442576) (xy 336.332478 -267.486153)
			(xy 336.348062 -267.532834) (xy 336.355957 -267.581411) (xy 336.356452 -267.606018) (xy 336.685394 -267.606018)
			(xy 336.689354 -267.556964) (xy 336.701131 -267.50918) (xy 336.720422 -267.463904) (xy 336.746725 -267.422308)
			(xy 336.77936 -267.385471) (xy 336.817481 -267.354346) (xy 336.860102 -267.329739) (xy 336.906118 -267.312287)
			(xy 336.954337 -267.302443) (xy 337.003512 -267.300462) (xy 337.052367 -267.306394) (xy 337.099638 -267.320086)
			(xy 337.1441 -267.341184) (xy 337.184603 -267.36914) (xy 337.220096 -267.403232) (xy 337.249661 -267.442576)
			(xy 337.272532 -267.486153) (xy 337.288116 -267.532834) (xy 337.296011 -267.581411) (xy 337.296506 -267.606018)
			(xy 337.625194 -267.606018) (xy 337.629154 -267.556964) (xy 337.640931 -267.50918) (xy 337.660222 -267.463904)
			(xy 337.686525 -267.422308) (xy 337.71916 -267.385471) (xy 337.757281 -267.354346) (xy 337.799902 -267.329739)
			(xy 337.845918 -267.312287) (xy 337.894137 -267.302443) (xy 337.943312 -267.300462) (xy 337.992167 -267.306394)
			(xy 338.039438 -267.320086) (xy 338.0839 -267.341184) (xy 338.124403 -267.36914) (xy 338.159896 -267.403232)
			(xy 338.189461 -267.442576) (xy 338.212332 -267.486153) (xy 338.227916 -267.532834) (xy 338.235811 -267.581411)
			(xy 338.236306 -267.606018) (xy 338.554817 -267.606018) (xy 338.558912 -267.55529) (xy 338.571091 -267.505876)
			(xy 338.591039 -267.459056) (xy 338.61824 -267.416042) (xy 338.651988 -267.377948) (xy 338.69141 -267.345761)
			(xy 338.735484 -267.320315) (xy 338.78307 -267.302268) (xy 338.832934 -267.292088) (xy 338.883786 -267.290039)
			(xy 338.934307 -267.296173) (xy 338.983191 -267.310333) (xy 339.02917 -267.33215) (xy 339.071054 -267.36106)
			(xy 339.107758 -267.396315) (xy 339.138331 -267.437001) (xy 339.161982 -267.482064) (xy 339.178098 -267.530338)
			(xy 339.186262 -267.580572) (xy 339.186774 -267.606018) (xy 339.505302 -267.606018) (xy 339.509262 -267.556964)
			(xy 339.521039 -267.50918) (xy 339.54033 -267.463904) (xy 339.566633 -267.422308) (xy 339.599268 -267.385471)
			(xy 339.637389 -267.354346) (xy 339.68001 -267.329739) (xy 339.726026 -267.312287) (xy 339.774245 -267.302443)
			(xy 339.82342 -267.300462) (xy 339.872275 -267.306394) (xy 339.919546 -267.320086) (xy 339.964008 -267.341184)
			(xy 340.004511 -267.36914) (xy 340.040004 -267.403232) (xy 340.069569 -267.442576) (xy 340.09244 -267.486153)
			(xy 340.108024 -267.532834) (xy 340.115919 -267.581411) (xy 340.116414 -267.606018) (xy 340.445356 -267.606018)
			(xy 340.449316 -267.556964) (xy 340.461093 -267.50918) (xy 340.480384 -267.463904) (xy 340.506687 -267.422308)
			(xy 340.539322 -267.385471) (xy 340.577443 -267.354346) (xy 340.620064 -267.329739) (xy 340.66608 -267.312287)
			(xy 340.714299 -267.302443) (xy 340.763474 -267.300462) (xy 340.812329 -267.306394) (xy 340.8596 -267.320086)
			(xy 340.904062 -267.341184) (xy 340.944565 -267.36914) (xy 340.980058 -267.403232) (xy 341.009623 -267.442576)
			(xy 341.032494 -267.486153) (xy 341.048078 -267.532834) (xy 341.055973 -267.581411) (xy 341.056468 -267.606018)
			(xy 341.38541 -267.606018) (xy 341.38937 -267.556964) (xy 341.401147 -267.50918) (xy 341.420438 -267.463904)
			(xy 341.446741 -267.422308) (xy 341.479376 -267.385471) (xy 341.517497 -267.354346) (xy 341.560118 -267.329739)
			(xy 341.606134 -267.312287) (xy 341.654353 -267.302443) (xy 341.703528 -267.300462) (xy 341.752383 -267.306394)
			(xy 341.799654 -267.320086) (xy 341.844116 -267.341184) (xy 341.884619 -267.36914) (xy 341.920112 -267.403232)
			(xy 341.949677 -267.442576) (xy 341.972548 -267.486153) (xy 341.988132 -267.532834) (xy 341.996027 -267.581411)
			(xy 341.996522 -267.606018) (xy 342.314779 -267.606018) (xy 342.318874 -267.55529) (xy 342.331053 -267.505876)
			(xy 342.351001 -267.459056) (xy 342.378202 -267.416042) (xy 342.41195 -267.377948) (xy 342.451372 -267.345761)
			(xy 342.495446 -267.320315) (xy 342.543032 -267.302268) (xy 342.592896 -267.292088) (xy 342.643748 -267.290039)
			(xy 342.694269 -267.296173) (xy 342.743153 -267.310333) (xy 342.789132 -267.33215) (xy 342.831016 -267.36106)
			(xy 342.86772 -267.396315) (xy 342.898293 -267.437001) (xy 342.921944 -267.482064) (xy 342.93806 -267.530338)
			(xy 342.946224 -267.580572) (xy 342.946736 -267.606018) (xy 343.265264 -267.606018) (xy 343.269224 -267.556964)
			(xy 343.281001 -267.50918) (xy 343.300292 -267.463904) (xy 343.326595 -267.422308) (xy 343.35923 -267.385471)
			(xy 343.397351 -267.354346) (xy 343.439972 -267.329739) (xy 343.485988 -267.312287) (xy 343.534207 -267.302443)
			(xy 343.583382 -267.300462) (xy 343.632237 -267.306394) (xy 343.679508 -267.320086) (xy 343.72397 -267.341184)
			(xy 343.764473 -267.36914) (xy 343.799966 -267.403232) (xy 343.829531 -267.442576) (xy 343.852402 -267.486153)
			(xy 343.867986 -267.532834) (xy 343.875881 -267.581411) (xy 343.876376 -267.606018) (xy 343.875881 -267.630625)
			(xy 343.867986 -267.679202) (xy 343.852402 -267.725883) (xy 343.829531 -267.76946) (xy 343.799966 -267.808804)
			(xy 343.764473 -267.842896) (xy 343.72397 -267.870852) (xy 343.679508 -267.89195) (xy 343.632237 -267.905642)
			(xy 343.583382 -267.911574) (xy 343.534207 -267.909593) (xy 343.485988 -267.899749) (xy 343.439972 -267.882297)
			(xy 343.397351 -267.85769) (xy 343.35923 -267.826565) (xy 343.326595 -267.789728) (xy 343.300292 -267.748132)
			(xy 343.281001 -267.702856) (xy 343.269224 -267.655072) (xy 343.265264 -267.606018) (xy 342.946736 -267.606018)
			(xy 342.946224 -267.631464) (xy 342.93806 -267.681698) (xy 342.921944 -267.729972) (xy 342.898293 -267.775035)
			(xy 342.86772 -267.815721) (xy 342.831016 -267.850976) (xy 342.789132 -267.879886) (xy 342.743153 -267.901703)
			(xy 342.694269 -267.915863) (xy 342.643748 -267.921997) (xy 342.592896 -267.919948) (xy 342.543032 -267.909768)
			(xy 342.495446 -267.891721) (xy 342.451372 -267.866275) (xy 342.41195 -267.834088) (xy 342.378202 -267.795994)
			(xy 342.351001 -267.75298) (xy 342.331053 -267.70616) (xy 342.318874 -267.656746) (xy 342.314779 -267.606018)
			(xy 341.996522 -267.606018) (xy 341.996027 -267.630625) (xy 341.988132 -267.679202) (xy 341.972548 -267.725883)
			(xy 341.949677 -267.76946) (xy 341.920112 -267.808804) (xy 341.884619 -267.842896) (xy 341.844116 -267.870852)
			(xy 341.799654 -267.89195) (xy 341.752383 -267.905642) (xy 341.703528 -267.911574) (xy 341.654353 -267.909593)
			(xy 341.606134 -267.899749) (xy 341.560118 -267.882297) (xy 341.517497 -267.85769) (xy 341.479376 -267.826565)
			(xy 341.446741 -267.789728) (xy 341.420438 -267.748132) (xy 341.401147 -267.702856) (xy 341.38937 -267.655072)
			(xy 341.38541 -267.606018) (xy 341.056468 -267.606018) (xy 341.055973 -267.630625) (xy 341.048078 -267.679202)
			(xy 341.032494 -267.725883) (xy 341.009623 -267.76946) (xy 340.980058 -267.808804) (xy 340.944565 -267.842896)
			(xy 340.904062 -267.870852) (xy 340.8596 -267.89195) (xy 340.812329 -267.905642) (xy 340.763474 -267.911574)
			(xy 340.714299 -267.909593) (xy 340.66608 -267.899749) (xy 340.620064 -267.882297) (xy 340.577443 -267.85769)
			(xy 340.539322 -267.826565) (xy 340.506687 -267.789728) (xy 340.480384 -267.748132) (xy 340.461093 -267.702856)
			(xy 340.449316 -267.655072) (xy 340.445356 -267.606018) (xy 340.116414 -267.606018) (xy 340.115919 -267.630625)
			(xy 340.108024 -267.679202) (xy 340.09244 -267.725883) (xy 340.069569 -267.76946) (xy 340.040004 -267.808804)
			(xy 340.004511 -267.842896) (xy 339.964008 -267.870852) (xy 339.919546 -267.89195) (xy 339.872275 -267.905642)
			(xy 339.82342 -267.911574) (xy 339.774245 -267.909593) (xy 339.726026 -267.899749) (xy 339.68001 -267.882297)
			(xy 339.637389 -267.85769) (xy 339.599268 -267.826565) (xy 339.566633 -267.789728) (xy 339.54033 -267.748132)
			(xy 339.521039 -267.702856) (xy 339.509262 -267.655072) (xy 339.505302 -267.606018) (xy 339.186774 -267.606018)
			(xy 339.186262 -267.631464) (xy 339.178098 -267.681698) (xy 339.161982 -267.729972) (xy 339.138331 -267.775035)
			(xy 339.107758 -267.815721) (xy 339.071054 -267.850976) (xy 339.02917 -267.879886) (xy 338.983191 -267.901703)
			(xy 338.934307 -267.915863) (xy 338.883786 -267.921997) (xy 338.832934 -267.919948) (xy 338.78307 -267.909768)
			(xy 338.735484 -267.891721) (xy 338.69141 -267.866275) (xy 338.651988 -267.834088) (xy 338.61824 -267.795994)
			(xy 338.591039 -267.75298) (xy 338.571091 -267.70616) (xy 338.558912 -267.656746) (xy 338.554817 -267.606018)
			(xy 338.236306 -267.606018) (xy 338.235811 -267.630625) (xy 338.227916 -267.679202) (xy 338.212332 -267.725883)
			(xy 338.189461 -267.76946) (xy 338.159896 -267.808804) (xy 338.124403 -267.842896) (xy 338.0839 -267.870852)
			(xy 338.039438 -267.89195) (xy 337.992167 -267.905642) (xy 337.943312 -267.911574) (xy 337.894137 -267.909593)
			(xy 337.845918 -267.899749) (xy 337.799902 -267.882297) (xy 337.757281 -267.85769) (xy 337.71916 -267.826565)
			(xy 337.686525 -267.789728) (xy 337.660222 -267.748132) (xy 337.640931 -267.702856) (xy 337.629154 -267.655072)
			(xy 337.625194 -267.606018) (xy 337.296506 -267.606018) (xy 337.296011 -267.630625) (xy 337.288116 -267.679202)
			(xy 337.272532 -267.725883) (xy 337.249661 -267.76946) (xy 337.220096 -267.808804) (xy 337.184603 -267.842896)
			(xy 337.1441 -267.870852) (xy 337.099638 -267.89195) (xy 337.052367 -267.905642) (xy 337.003512 -267.911574)
			(xy 336.954337 -267.909593) (xy 336.906118 -267.899749) (xy 336.860102 -267.882297) (xy 336.817481 -267.85769)
			(xy 336.77936 -267.826565) (xy 336.746725 -267.789728) (xy 336.720422 -267.748132) (xy 336.701131 -267.702856)
			(xy 336.689354 -267.655072) (xy 336.685394 -267.606018) (xy 336.356452 -267.606018) (xy 336.355957 -267.630625)
			(xy 336.348062 -267.679202) (xy 336.332478 -267.725883) (xy 336.309607 -267.76946) (xy 336.280042 -267.808804)
			(xy 336.244549 -267.842896) (xy 336.204046 -267.870852) (xy 336.159584 -267.89195) (xy 336.112313 -267.905642)
			(xy 336.063458 -267.911574) (xy 336.014283 -267.909593) (xy 335.966064 -267.899749) (xy 335.920048 -267.882297)
			(xy 335.877427 -267.85769) (xy 335.839306 -267.826565) (xy 335.806671 -267.789728) (xy 335.780368 -267.748132)
			(xy 335.761077 -267.702856) (xy 335.7493 -267.655072) (xy 335.74534 -267.606018) (xy 335.416941 -267.606018)
			(xy 335.412771 -267.656341) (xy 335.40037 -267.705309) (xy 335.380079 -267.751567) (xy 335.35245 -267.793855)
			(xy 335.318237 -267.831019) (xy 335.278374 -267.862044) (xy 335.233949 -267.886085) (xy 335.186172 -267.902485)
			(xy 335.136347 -267.910798) (xy 335.11109 -267.911326) (xy 335.110582 -267.911326) (xy 335.097433 -267.911176)
			(xy 335.071234 -267.908884) (xy 335.058258 -267.906754) (xy 335.054448 -267.906246) (xy 335.04378 -267.909294)
			(xy 335.03889 -267.910828) (xy 335.029804 -267.915563) (xy 335.025746 -267.918692) (xy 334.967072 -267.968984)
			(xy 334.959451 -267.976549) (xy 334.950648 -267.996109) (xy 334.950054 -268.00683) (xy 334.950054 -268.297406)
			(xy 334.952848 -268.305788) (xy 334.96168 -268.33249) (xy 334.971262 -268.387906) (xy 334.971898 -268.416024)
			(xy 335.275186 -268.416024) (xy 335.279146 -268.36697) (xy 335.290923 -268.319186) (xy 335.310214 -268.27391)
			(xy 335.336517 -268.232314) (xy 335.369152 -268.195477) (xy 335.407273 -268.164352) (xy 335.449894 -268.139745)
			(xy 335.49591 -268.122293) (xy 335.544129 -268.112449) (xy 335.593304 -268.110468) (xy 335.642159 -268.1164)
			(xy 335.68943 -268.130092) (xy 335.733892 -268.15119) (xy 335.774395 -268.179146) (xy 335.809888 -268.213238)
			(xy 335.839453 -268.252582) (xy 335.862324 -268.296159) (xy 335.877908 -268.34284) (xy 335.885803 -268.391417)
			(xy 335.886298 -268.416024) (xy 336.21524 -268.416024) (xy 336.2192 -268.36697) (xy 336.230977 -268.319186)
			(xy 336.250268 -268.27391) (xy 336.276571 -268.232314) (xy 336.309206 -268.195477) (xy 336.347327 -268.164352)
			(xy 336.389948 -268.139745) (xy 336.435964 -268.122293) (xy 336.484183 -268.112449) (xy 336.533358 -268.110468)
			(xy 336.582213 -268.1164) (xy 336.629484 -268.130092) (xy 336.673946 -268.15119) (xy 336.714449 -268.179146)
			(xy 336.749942 -268.213238) (xy 336.779507 -268.252582) (xy 336.802378 -268.296159) (xy 336.817962 -268.34284)
			(xy 336.825857 -268.391417) (xy 336.826352 -268.416024) (xy 337.155294 -268.416024) (xy 337.159254 -268.36697)
			(xy 337.171031 -268.319186) (xy 337.190322 -268.27391) (xy 337.216625 -268.232314) (xy 337.24926 -268.195477)
			(xy 337.287381 -268.164352) (xy 337.330002 -268.139745) (xy 337.376018 -268.122293) (xy 337.424237 -268.112449)
			(xy 337.473412 -268.110468) (xy 337.522267 -268.1164) (xy 337.569538 -268.130092) (xy 337.614 -268.15119)
			(xy 337.654503 -268.179146) (xy 337.689996 -268.213238) (xy 337.719561 -268.252582) (xy 337.742432 -268.296159)
			(xy 337.758016 -268.34284) (xy 337.765911 -268.391417) (xy 337.766406 -268.416024) (xy 338.095348 -268.416024)
			(xy 338.099308 -268.36697) (xy 338.111085 -268.319186) (xy 338.130376 -268.27391) (xy 338.156679 -268.232314)
			(xy 338.189314 -268.195477) (xy 338.227435 -268.164352) (xy 338.270056 -268.139745) (xy 338.316072 -268.122293)
			(xy 338.364291 -268.112449) (xy 338.413466 -268.110468) (xy 338.462321 -268.1164) (xy 338.509592 -268.130092)
			(xy 338.554054 -268.15119) (xy 338.594557 -268.179146) (xy 338.63005 -268.213238) (xy 338.659615 -268.252582)
			(xy 338.682486 -268.296159) (xy 338.69807 -268.34284) (xy 338.705965 -268.391417) (xy 338.70646 -268.416024)
			(xy 339.035402 -268.416024) (xy 339.039362 -268.36697) (xy 339.051139 -268.319186) (xy 339.07043 -268.27391)
			(xy 339.096733 -268.232314) (xy 339.129368 -268.195477) (xy 339.167489 -268.164352) (xy 339.21011 -268.139745)
			(xy 339.256126 -268.122293) (xy 339.304345 -268.112449) (xy 339.35352 -268.110468) (xy 339.402375 -268.1164)
			(xy 339.449646 -268.130092) (xy 339.494108 -268.15119) (xy 339.534611 -268.179146) (xy 339.570104 -268.213238)
			(xy 339.599669 -268.252582) (xy 339.62254 -268.296159) (xy 339.638124 -268.34284) (xy 339.646019 -268.391417)
			(xy 339.646514 -268.416024) (xy 339.975202 -268.416024) (xy 339.979162 -268.36697) (xy 339.990939 -268.319186)
			(xy 340.01023 -268.27391) (xy 340.036533 -268.232314) (xy 340.069168 -268.195477) (xy 340.107289 -268.164352)
			(xy 340.14991 -268.139745) (xy 340.195926 -268.122293) (xy 340.244145 -268.112449) (xy 340.29332 -268.110468)
			(xy 340.342175 -268.1164) (xy 340.389446 -268.130092) (xy 340.433908 -268.15119) (xy 340.474411 -268.179146)
			(xy 340.509904 -268.213238) (xy 340.539469 -268.252582) (xy 340.56234 -268.296159) (xy 340.577924 -268.34284)
			(xy 340.585819 -268.391417) (xy 340.586314 -268.416024) (xy 341.85531 -268.416024) (xy 341.85927 -268.36697)
			(xy 341.871047 -268.319186) (xy 341.890338 -268.27391) (xy 341.916641 -268.232314) (xy 341.949276 -268.195477)
			(xy 341.987397 -268.164352) (xy 342.030018 -268.139745) (xy 342.076034 -268.122293) (xy 342.124253 -268.112449)
			(xy 342.173428 -268.110468) (xy 342.222283 -268.1164) (xy 342.269554 -268.130092) (xy 342.314016 -268.15119)
			(xy 342.354519 -268.179146) (xy 342.390012 -268.213238) (xy 342.419577 -268.252582) (xy 342.442448 -268.296159)
			(xy 342.458032 -268.34284) (xy 342.465927 -268.391417) (xy 342.466422 -268.416024) (xy 342.795364 -268.416024)
			(xy 342.799324 -268.36697) (xy 342.811101 -268.319186) (xy 342.830392 -268.27391) (xy 342.856695 -268.232314)
			(xy 342.88933 -268.195477) (xy 342.927451 -268.164352) (xy 342.970072 -268.139745) (xy 343.016088 -268.122293)
			(xy 343.064307 -268.112449) (xy 343.113482 -268.110468) (xy 343.162337 -268.1164) (xy 343.209608 -268.130092)
			(xy 343.25407 -268.15119) (xy 343.294573 -268.179146) (xy 343.330066 -268.213238) (xy 343.359631 -268.252582)
			(xy 343.382502 -268.296159) (xy 343.398086 -268.34284) (xy 343.405981 -268.391417) (xy 343.406476 -268.416024)
			(xy 343.735418 -268.416024) (xy 343.739378 -268.36697) (xy 343.751155 -268.319186) (xy 343.770446 -268.27391)
			(xy 343.796749 -268.232314) (xy 343.829384 -268.195477) (xy 343.867505 -268.164352) (xy 343.910126 -268.139745)
			(xy 343.956142 -268.122293) (xy 344.004361 -268.112449) (xy 344.053536 -268.110468) (xy 344.102391 -268.1164)
			(xy 344.149662 -268.130092) (xy 344.194124 -268.15119) (xy 344.234627 -268.179146) (xy 344.27012 -268.213238)
			(xy 344.299685 -268.252582) (xy 344.322556 -268.296159) (xy 344.33814 -268.34284) (xy 344.346035 -268.391417)
			(xy 344.34653 -268.416024) (xy 344.346035 -268.440631) (xy 344.33814 -268.489208) (xy 344.322556 -268.535889)
			(xy 344.299685 -268.579466) (xy 344.27012 -268.61881) (xy 344.234627 -268.652902) (xy 344.194124 -268.680858)
			(xy 344.149662 -268.701956) (xy 344.102391 -268.715648) (xy 344.053536 -268.72158) (xy 344.004361 -268.719599)
			(xy 343.956142 -268.709755) (xy 343.910126 -268.692303) (xy 343.867505 -268.667696) (xy 343.829384 -268.636571)
			(xy 343.796749 -268.599734) (xy 343.770446 -268.558138) (xy 343.751155 -268.512862) (xy 343.739378 -268.465078)
			(xy 343.735418 -268.416024) (xy 343.406476 -268.416024) (xy 343.405981 -268.440631) (xy 343.398086 -268.489208)
			(xy 343.382502 -268.535889) (xy 343.359631 -268.579466) (xy 343.330066 -268.61881) (xy 343.294573 -268.652902)
			(xy 343.25407 -268.680858) (xy 343.209608 -268.701956) (xy 343.162337 -268.715648) (xy 343.113482 -268.72158)
			(xy 343.064307 -268.719599) (xy 343.016088 -268.709755) (xy 342.970072 -268.692303) (xy 342.927451 -268.667696)
			(xy 342.88933 -268.636571) (xy 342.856695 -268.599734) (xy 342.830392 -268.558138) (xy 342.811101 -268.512862)
			(xy 342.799324 -268.465078) (xy 342.795364 -268.416024) (xy 342.466422 -268.416024) (xy 342.465927 -268.440631)
			(xy 342.458032 -268.489208) (xy 342.442448 -268.535889) (xy 342.419577 -268.579466) (xy 342.390012 -268.61881)
			(xy 342.354519 -268.652902) (xy 342.314016 -268.680858) (xy 342.269554 -268.701956) (xy 342.222283 -268.715648)
			(xy 342.173428 -268.72158) (xy 342.124253 -268.719599) (xy 342.076034 -268.709755) (xy 342.030018 -268.692303)
			(xy 341.987397 -268.667696) (xy 341.949276 -268.636571) (xy 341.916641 -268.599734) (xy 341.890338 -268.558138)
			(xy 341.871047 -268.512862) (xy 341.85927 -268.465078) (xy 341.85531 -268.416024) (xy 340.586314 -268.416024)
			(xy 340.585819 -268.440631) (xy 340.577924 -268.489208) (xy 340.56234 -268.535889) (xy 340.539469 -268.579466)
			(xy 340.509904 -268.61881) (xy 340.474411 -268.652902) (xy 340.433908 -268.680858) (xy 340.389446 -268.701956)
			(xy 340.342175 -268.715648) (xy 340.29332 -268.72158) (xy 340.244145 -268.719599) (xy 340.195926 -268.709755)
			(xy 340.14991 -268.692303) (xy 340.107289 -268.667696) (xy 340.069168 -268.636571) (xy 340.036533 -268.599734)
			(xy 340.01023 -268.558138) (xy 339.990939 -268.512862) (xy 339.979162 -268.465078) (xy 339.975202 -268.416024)
			(xy 339.646514 -268.416024) (xy 339.646019 -268.440631) (xy 339.638124 -268.489208) (xy 339.62254 -268.535889)
			(xy 339.599669 -268.579466) (xy 339.570104 -268.61881) (xy 339.534611 -268.652902) (xy 339.494108 -268.680858)
			(xy 339.449646 -268.701956) (xy 339.402375 -268.715648) (xy 339.35352 -268.72158) (xy 339.304345 -268.719599)
			(xy 339.256126 -268.709755) (xy 339.21011 -268.692303) (xy 339.167489 -268.667696) (xy 339.129368 -268.636571)
			(xy 339.096733 -268.599734) (xy 339.07043 -268.558138) (xy 339.051139 -268.512862) (xy 339.039362 -268.465078)
			(xy 339.035402 -268.416024) (xy 338.70646 -268.416024) (xy 338.705965 -268.440631) (xy 338.69807 -268.489208)
			(xy 338.682486 -268.535889) (xy 338.659615 -268.579466) (xy 338.63005 -268.61881) (xy 338.594557 -268.652902)
			(xy 338.554054 -268.680858) (xy 338.509592 -268.701956) (xy 338.462321 -268.715648) (xy 338.413466 -268.72158)
			(xy 338.364291 -268.719599) (xy 338.316072 -268.709755) (xy 338.270056 -268.692303) (xy 338.227435 -268.667696)
			(xy 338.189314 -268.636571) (xy 338.156679 -268.599734) (xy 338.130376 -268.558138) (xy 338.111085 -268.512862)
			(xy 338.099308 -268.465078) (xy 338.095348 -268.416024) (xy 337.766406 -268.416024) (xy 337.765911 -268.440631)
			(xy 337.758016 -268.489208) (xy 337.742432 -268.535889) (xy 337.719561 -268.579466) (xy 337.689996 -268.61881)
			(xy 337.654503 -268.652902) (xy 337.614 -268.680858) (xy 337.569538 -268.701956) (xy 337.522267 -268.715648)
			(xy 337.473412 -268.72158) (xy 337.424237 -268.719599) (xy 337.376018 -268.709755) (xy 337.330002 -268.692303)
			(xy 337.287381 -268.667696) (xy 337.24926 -268.636571) (xy 337.216625 -268.599734) (xy 337.190322 -268.558138)
			(xy 337.171031 -268.512862) (xy 337.159254 -268.465078) (xy 337.155294 -268.416024) (xy 336.826352 -268.416024)
			(xy 336.825857 -268.440631) (xy 336.817962 -268.489208) (xy 336.802378 -268.535889) (xy 336.779507 -268.579466)
			(xy 336.749942 -268.61881) (xy 336.714449 -268.652902) (xy 336.673946 -268.680858) (xy 336.629484 -268.701956)
			(xy 336.582213 -268.715648) (xy 336.533358 -268.72158) (xy 336.484183 -268.719599) (xy 336.435964 -268.709755)
			(xy 336.389948 -268.692303) (xy 336.347327 -268.667696) (xy 336.309206 -268.636571) (xy 336.276571 -268.599734)
			(xy 336.250268 -268.558138) (xy 336.230977 -268.512862) (xy 336.2192 -268.465078) (xy 336.21524 -268.416024)
			(xy 335.886298 -268.416024) (xy 335.885803 -268.440631) (xy 335.877908 -268.489208) (xy 335.862324 -268.535889)
			(xy 335.839453 -268.579466) (xy 335.809888 -268.61881) (xy 335.774395 -268.652902) (xy 335.733892 -268.680858)
			(xy 335.68943 -268.701956) (xy 335.642159 -268.715648) (xy 335.593304 -268.72158) (xy 335.544129 -268.719599)
			(xy 335.49591 -268.709755) (xy 335.449894 -268.692303) (xy 335.407273 -268.667696) (xy 335.369152 -268.636571)
			(xy 335.336517 -268.599734) (xy 335.310214 -268.558138) (xy 335.290923 -268.512862) (xy 335.279146 -268.465078)
			(xy 335.275186 -268.416024) (xy 334.971898 -268.416024) (xy 334.971315 -268.444147) (xy 334.961737 -268.499572)
			(xy 334.952848 -268.52626) (xy 334.950054 -268.534642) (xy 334.950054 -268.82471) (xy 334.950054 -268.82725)
			(xy 334.950971 -268.836914) (xy 334.959081 -268.854533) (xy 334.965802 -268.86154) (xy 335.024476 -268.912086)
			(xy 335.02871 -268.915559) (xy 335.03832 -268.920802) (xy 335.043526 -268.9225) (xy 335.054194 -268.925548)
			(xy 335.065116 -268.924024) (xy 335.076354 -268.922468) (xy 335.098983 -268.920813) (xy 335.110328 -268.920722)
			(xy 335.11109 -268.920722) (xy 335.136346 -268.921214) (xy 335.186169 -268.929526) (xy 335.233944 -268.945926)
			(xy 335.278368 -268.969966) (xy 335.318229 -269.00099) (xy 335.35244 -269.038152) (xy 335.380068 -269.080438)
			(xy 335.400359 -269.126695) (xy 335.412759 -269.175661) (xy 335.41693 -269.226) (xy 335.416928 -269.22603)
			(xy 335.74534 -269.22603) (xy 335.7493 -269.176976) (xy 335.761077 -269.129192) (xy 335.780368 -269.083916)
			(xy 335.806671 -269.04232) (xy 335.839306 -269.005483) (xy 335.877427 -268.974358) (xy 335.920048 -268.949751)
			(xy 335.966064 -268.932299) (xy 336.014283 -268.922455) (xy 336.063458 -268.920474) (xy 336.112313 -268.926406)
			(xy 336.159584 -268.940098) (xy 336.204046 -268.961196) (xy 336.244549 -268.989152) (xy 336.280042 -269.023244)
			(xy 336.309607 -269.062588) (xy 336.332478 -269.106165) (xy 336.348062 -269.152846) (xy 336.355957 -269.201423)
			(xy 336.356452 -269.22603) (xy 336.685394 -269.22603) (xy 336.689354 -269.176976) (xy 336.701131 -269.129192)
			(xy 336.720422 -269.083916) (xy 336.746725 -269.04232) (xy 336.77936 -269.005483) (xy 336.817481 -268.974358)
			(xy 336.860102 -268.949751) (xy 336.906118 -268.932299) (xy 336.954337 -268.922455) (xy 337.003512 -268.920474)
			(xy 337.052367 -268.926406) (xy 337.099638 -268.940098) (xy 337.1441 -268.961196) (xy 337.184603 -268.989152)
			(xy 337.220096 -269.023244) (xy 337.249661 -269.062588) (xy 337.272532 -269.106165) (xy 337.288116 -269.152846)
			(xy 337.296011 -269.201423) (xy 337.296506 -269.22603) (xy 337.625194 -269.22603) (xy 337.629154 -269.176976)
			(xy 337.640931 -269.129192) (xy 337.660222 -269.083916) (xy 337.686525 -269.04232) (xy 337.71916 -269.005483)
			(xy 337.757281 -268.974358) (xy 337.799902 -268.949751) (xy 337.845918 -268.932299) (xy 337.894137 -268.922455)
			(xy 337.943312 -268.920474) (xy 337.992167 -268.926406) (xy 338.039438 -268.940098) (xy 338.0839 -268.961196)
			(xy 338.124403 -268.989152) (xy 338.159896 -269.023244) (xy 338.189461 -269.062588) (xy 338.212332 -269.106165)
			(xy 338.227916 -269.152846) (xy 338.235811 -269.201423) (xy 338.236306 -269.22603) (xy 338.554817 -269.22603)
			(xy 338.558912 -269.175302) (xy 338.571091 -269.125888) (xy 338.591039 -269.079068) (xy 338.61824 -269.036054)
			(xy 338.651988 -268.99796) (xy 338.69141 -268.965773) (xy 338.735484 -268.940327) (xy 338.78307 -268.92228)
			(xy 338.832934 -268.9121) (xy 338.883786 -268.910051) (xy 338.934307 -268.916185) (xy 338.983191 -268.930345)
			(xy 339.02917 -268.952162) (xy 339.071054 -268.981072) (xy 339.107758 -269.016327) (xy 339.138331 -269.057013)
			(xy 339.161982 -269.102076) (xy 339.178098 -269.15035) (xy 339.186262 -269.200584) (xy 339.186774 -269.22603)
			(xy 339.505302 -269.22603) (xy 339.509262 -269.176976) (xy 339.521039 -269.129192) (xy 339.54033 -269.083916)
			(xy 339.566633 -269.04232) (xy 339.599268 -269.005483) (xy 339.637389 -268.974358) (xy 339.68001 -268.949751)
			(xy 339.726026 -268.932299) (xy 339.774245 -268.922455) (xy 339.82342 -268.920474) (xy 339.872275 -268.926406)
			(xy 339.919546 -268.940098) (xy 339.964008 -268.961196) (xy 340.004511 -268.989152) (xy 340.040004 -269.023244)
			(xy 340.069569 -269.062588) (xy 340.09244 -269.106165) (xy 340.108024 -269.152846) (xy 340.115919 -269.201423)
			(xy 340.116414 -269.22603) (xy 340.445356 -269.22603) (xy 340.449316 -269.176976) (xy 340.461093 -269.129192)
			(xy 340.480384 -269.083916) (xy 340.506687 -269.04232) (xy 340.539322 -269.005483) (xy 340.577443 -268.974358)
			(xy 340.620064 -268.949751) (xy 340.66608 -268.932299) (xy 340.714299 -268.922455) (xy 340.763474 -268.920474)
			(xy 340.812329 -268.926406) (xy 340.8596 -268.940098) (xy 340.904062 -268.961196) (xy 340.944565 -268.989152)
			(xy 340.980058 -269.023244) (xy 341.009623 -269.062588) (xy 341.032494 -269.106165) (xy 341.048078 -269.152846)
			(xy 341.055973 -269.201423) (xy 341.056468 -269.22603) (xy 341.38541 -269.22603) (xy 341.38937 -269.176976)
			(xy 341.401147 -269.129192) (xy 341.420438 -269.083916) (xy 341.446741 -269.04232) (xy 341.479376 -269.005483)
			(xy 341.517497 -268.974358) (xy 341.560118 -268.949751) (xy 341.606134 -268.932299) (xy 341.654353 -268.922455)
			(xy 341.703528 -268.920474) (xy 341.752383 -268.926406) (xy 341.799654 -268.940098) (xy 341.844116 -268.961196)
			(xy 341.884619 -268.989152) (xy 341.920112 -269.023244) (xy 341.949677 -269.062588) (xy 341.972548 -269.106165)
			(xy 341.988132 -269.152846) (xy 341.996027 -269.201423) (xy 341.996522 -269.22603) (xy 342.314779 -269.22603)
			(xy 342.318874 -269.175302) (xy 342.331053 -269.125888) (xy 342.351001 -269.079068) (xy 342.378202 -269.036054)
			(xy 342.41195 -268.99796) (xy 342.451372 -268.965773) (xy 342.495446 -268.940327) (xy 342.543032 -268.92228)
			(xy 342.592896 -268.9121) (xy 342.643748 -268.910051) (xy 342.694269 -268.916185) (xy 342.743153 -268.930345)
			(xy 342.789132 -268.952162) (xy 342.831016 -268.981072) (xy 342.86772 -269.016327) (xy 342.898293 -269.057013)
			(xy 342.921944 -269.102076) (xy 342.93806 -269.15035) (xy 342.946224 -269.200584) (xy 342.946736 -269.22603)
			(xy 343.265264 -269.22603) (xy 343.269224 -269.176976) (xy 343.281001 -269.129192) (xy 343.300292 -269.083916)
			(xy 343.326595 -269.04232) (xy 343.35923 -269.005483) (xy 343.397351 -268.974358) (xy 343.439972 -268.949751)
			(xy 343.485988 -268.932299) (xy 343.534207 -268.922455) (xy 343.583382 -268.920474) (xy 343.632237 -268.926406)
			(xy 343.679508 -268.940098) (xy 343.72397 -268.961196) (xy 343.764473 -268.989152) (xy 343.799966 -269.023244)
			(xy 343.829531 -269.062588) (xy 343.852402 -269.106165) (xy 343.867986 -269.152846) (xy 343.875881 -269.201423)
			(xy 343.876376 -269.22603) (xy 343.875881 -269.250637) (xy 343.867986 -269.299214) (xy 343.852402 -269.345895)
			(xy 343.829531 -269.389472) (xy 343.799966 -269.428816) (xy 343.764473 -269.462908) (xy 343.72397 -269.490864)
			(xy 343.679508 -269.511962) (xy 343.632237 -269.525654) (xy 343.583382 -269.531586) (xy 343.534207 -269.529605)
			(xy 343.485988 -269.519761) (xy 343.439972 -269.502309) (xy 343.397351 -269.477702) (xy 343.35923 -269.446577)
			(xy 343.326595 -269.40974) (xy 343.300292 -269.368144) (xy 343.281001 -269.322868) (xy 343.269224 -269.275084)
			(xy 343.265264 -269.22603) (xy 342.946736 -269.22603) (xy 342.946224 -269.251476) (xy 342.93806 -269.30171)
			(xy 342.921944 -269.349984) (xy 342.898293 -269.395047) (xy 342.86772 -269.435733) (xy 342.831016 -269.470988)
			(xy 342.789132 -269.499898) (xy 342.743153 -269.521715) (xy 342.694269 -269.535875) (xy 342.643748 -269.542009)
			(xy 342.592896 -269.53996) (xy 342.543032 -269.52978) (xy 342.495446 -269.511733) (xy 342.451372 -269.486287)
			(xy 342.41195 -269.4541) (xy 342.378202 -269.416006) (xy 342.351001 -269.372992) (xy 342.331053 -269.326172)
			(xy 342.318874 -269.276758) (xy 342.314779 -269.22603) (xy 341.996522 -269.22603) (xy 341.996027 -269.250637)
			(xy 341.988132 -269.299214) (xy 341.972548 -269.345895) (xy 341.949677 -269.389472) (xy 341.920112 -269.428816)
			(xy 341.884619 -269.462908) (xy 341.844116 -269.490864) (xy 341.799654 -269.511962) (xy 341.752383 -269.525654)
			(xy 341.703528 -269.531586) (xy 341.654353 -269.529605) (xy 341.606134 -269.519761) (xy 341.560118 -269.502309)
			(xy 341.517497 -269.477702) (xy 341.479376 -269.446577) (xy 341.446741 -269.40974) (xy 341.420438 -269.368144)
			(xy 341.401147 -269.322868) (xy 341.38937 -269.275084) (xy 341.38541 -269.22603) (xy 341.056468 -269.22603)
			(xy 341.055973 -269.250637) (xy 341.048078 -269.299214) (xy 341.032494 -269.345895) (xy 341.009623 -269.389472)
			(xy 340.980058 -269.428816) (xy 340.944565 -269.462908) (xy 340.904062 -269.490864) (xy 340.8596 -269.511962)
			(xy 340.812329 -269.525654) (xy 340.763474 -269.531586) (xy 340.714299 -269.529605) (xy 340.66608 -269.519761)
			(xy 340.620064 -269.502309) (xy 340.577443 -269.477702) (xy 340.539322 -269.446577) (xy 340.506687 -269.40974)
			(xy 340.480384 -269.368144) (xy 340.461093 -269.322868) (xy 340.449316 -269.275084) (xy 340.445356 -269.22603)
			(xy 340.116414 -269.22603) (xy 340.115919 -269.250637) (xy 340.108024 -269.299214) (xy 340.09244 -269.345895)
			(xy 340.069569 -269.389472) (xy 340.040004 -269.428816) (xy 340.004511 -269.462908) (xy 339.964008 -269.490864)
			(xy 339.919546 -269.511962) (xy 339.872275 -269.525654) (xy 339.82342 -269.531586) (xy 339.774245 -269.529605)
			(xy 339.726026 -269.519761) (xy 339.68001 -269.502309) (xy 339.637389 -269.477702) (xy 339.599268 -269.446577)
			(xy 339.566633 -269.40974) (xy 339.54033 -269.368144) (xy 339.521039 -269.322868) (xy 339.509262 -269.275084)
			(xy 339.505302 -269.22603) (xy 339.186774 -269.22603) (xy 339.186262 -269.251476) (xy 339.178098 -269.30171)
			(xy 339.161982 -269.349984) (xy 339.138331 -269.395047) (xy 339.107758 -269.435733) (xy 339.071054 -269.470988)
			(xy 339.02917 -269.499898) (xy 338.983191 -269.521715) (xy 338.934307 -269.535875) (xy 338.883786 -269.542009)
			(xy 338.832934 -269.53996) (xy 338.78307 -269.52978) (xy 338.735484 -269.511733) (xy 338.69141 -269.486287)
			(xy 338.651988 -269.4541) (xy 338.61824 -269.416006) (xy 338.591039 -269.372992) (xy 338.571091 -269.326172)
			(xy 338.558912 -269.276758) (xy 338.554817 -269.22603) (xy 338.236306 -269.22603) (xy 338.235811 -269.250637)
			(xy 338.227916 -269.299214) (xy 338.212332 -269.345895) (xy 338.189461 -269.389472) (xy 338.159896 -269.428816)
			(xy 338.124403 -269.462908) (xy 338.0839 -269.490864) (xy 338.039438 -269.511962) (xy 337.992167 -269.525654)
			(xy 337.943312 -269.531586) (xy 337.894137 -269.529605) (xy 337.845918 -269.519761) (xy 337.799902 -269.502309)
			(xy 337.757281 -269.477702) (xy 337.71916 -269.446577) (xy 337.686525 -269.40974) (xy 337.660222 -269.368144)
			(xy 337.640931 -269.322868) (xy 337.629154 -269.275084) (xy 337.625194 -269.22603) (xy 337.296506 -269.22603)
			(xy 337.296011 -269.250637) (xy 337.288116 -269.299214) (xy 337.272532 -269.345895) (xy 337.249661 -269.389472)
			(xy 337.220096 -269.428816) (xy 337.184603 -269.462908) (xy 337.1441 -269.490864) (xy 337.099638 -269.511962)
			(xy 337.052367 -269.525654) (xy 337.003512 -269.531586) (xy 336.954337 -269.529605) (xy 336.906118 -269.519761)
			(xy 336.860102 -269.502309) (xy 336.817481 -269.477702) (xy 336.77936 -269.446577) (xy 336.746725 -269.40974)
			(xy 336.720422 -269.368144) (xy 336.701131 -269.322868) (xy 336.689354 -269.275084) (xy 336.685394 -269.22603)
			(xy 336.356452 -269.22603) (xy 336.355957 -269.250637) (xy 336.348062 -269.299214) (xy 336.332478 -269.345895)
			(xy 336.309607 -269.389472) (xy 336.280042 -269.428816) (xy 336.244549 -269.462908) (xy 336.204046 -269.490864)
			(xy 336.159584 -269.511962) (xy 336.112313 -269.525654) (xy 336.063458 -269.531586) (xy 336.014283 -269.529605)
			(xy 335.966064 -269.519761) (xy 335.920048 -269.502309) (xy 335.877427 -269.477702) (xy 335.839306 -269.446577)
			(xy 335.806671 -269.40974) (xy 335.780368 -269.368144) (xy 335.761077 -269.322868) (xy 335.7493 -269.275084)
			(xy 335.74534 -269.22603) (xy 335.416928 -269.22603) (xy 335.412759 -269.276339) (xy 335.400359 -269.325305)
			(xy 335.380068 -269.371562) (xy 335.35244 -269.413848) (xy 335.318229 -269.45101) (xy 335.278368 -269.482034)
			(xy 335.233944 -269.506074) (xy 335.186169 -269.522474) (xy 335.136346 -269.530786) (xy 335.11109 -269.531338)
			(xy 335.110582 -269.531338) (xy 335.097433 -269.531188) (xy 335.071234 -269.528896) (xy 335.058258 -269.526766)
			(xy 335.054448 -269.526258) (xy 335.04378 -269.529306) (xy 335.038891 -269.53084) (xy 335.029805 -269.535576)
			(xy 335.025746 -269.538704) (xy 334.967072 -269.588996) (xy 334.959452 -269.596562) (xy 334.950654 -269.616121)
			(xy 334.950054 -269.626842) (xy 334.950054 -270.036036) (xy 335.275186 -270.036036) (xy 335.279146 -269.986982)
			(xy 335.290923 -269.939198) (xy 335.310214 -269.893922) (xy 335.336517 -269.852326) (xy 335.369152 -269.815489)
			(xy 335.407273 -269.784364) (xy 335.449894 -269.759757) (xy 335.49591 -269.742305) (xy 335.544129 -269.732461)
			(xy 335.593304 -269.73048) (xy 335.642159 -269.736412) (xy 335.68943 -269.750104) (xy 335.733892 -269.771202)
			(xy 335.774395 -269.799158) (xy 335.809888 -269.83325) (xy 335.839453 -269.872594) (xy 335.862324 -269.916171)
			(xy 335.877908 -269.962852) (xy 335.885803 -270.011429) (xy 335.886298 -270.036036) (xy 336.21524 -270.036036)
			(xy 336.2192 -269.986982) (xy 336.230977 -269.939198) (xy 336.250268 -269.893922) (xy 336.276571 -269.852326)
			(xy 336.309206 -269.815489) (xy 336.347327 -269.784364) (xy 336.389948 -269.759757) (xy 336.435964 -269.742305)
			(xy 336.484183 -269.732461) (xy 336.533358 -269.73048) (xy 336.582213 -269.736412) (xy 336.629484 -269.750104)
			(xy 336.673946 -269.771202) (xy 336.714449 -269.799158) (xy 336.749942 -269.83325) (xy 336.779507 -269.872594)
			(xy 336.802378 -269.916171) (xy 336.817962 -269.962852) (xy 336.825857 -270.011429) (xy 336.826352 -270.036036)
			(xy 337.155294 -270.036036) (xy 337.159254 -269.986982) (xy 337.171031 -269.939198) (xy 337.190322 -269.893922)
			(xy 337.216625 -269.852326) (xy 337.24926 -269.815489) (xy 337.287381 -269.784364) (xy 337.330002 -269.759757)
			(xy 337.376018 -269.742305) (xy 337.424237 -269.732461) (xy 337.473412 -269.73048) (xy 337.522267 -269.736412)
			(xy 337.569538 -269.750104) (xy 337.614 -269.771202) (xy 337.654503 -269.799158) (xy 337.689996 -269.83325)
			(xy 337.719561 -269.872594) (xy 337.742432 -269.916171) (xy 337.758016 -269.962852) (xy 337.765911 -270.011429)
			(xy 337.766406 -270.036036) (xy 338.095348 -270.036036) (xy 338.099308 -269.986982) (xy 338.111085 -269.939198)
			(xy 338.130376 -269.893922) (xy 338.156679 -269.852326) (xy 338.189314 -269.815489) (xy 338.227435 -269.784364)
			(xy 338.270056 -269.759757) (xy 338.316072 -269.742305) (xy 338.364291 -269.732461) (xy 338.413466 -269.73048)
			(xy 338.462321 -269.736412) (xy 338.509592 -269.750104) (xy 338.554054 -269.771202) (xy 338.594557 -269.799158)
			(xy 338.63005 -269.83325) (xy 338.659615 -269.872594) (xy 338.682486 -269.916171) (xy 338.69807 -269.962852)
			(xy 338.705965 -270.011429) (xy 338.70646 -270.036036) (xy 339.024971 -270.036036) (xy 339.029066 -269.985308)
			(xy 339.041245 -269.935894) (xy 339.061193 -269.889074) (xy 339.088394 -269.84606) (xy 339.122142 -269.807966)
			(xy 339.161564 -269.775779) (xy 339.205638 -269.750333) (xy 339.253224 -269.732286) (xy 339.303088 -269.722106)
			(xy 339.35394 -269.720057) (xy 339.404461 -269.726191) (xy 339.453345 -269.740351) (xy 339.499324 -269.762168)
			(xy 339.541208 -269.791078) (xy 339.577912 -269.826333) (xy 339.608485 -269.867019) (xy 339.632136 -269.912082)
			(xy 339.648252 -269.960356) (xy 339.656416 -270.01059) (xy 339.656928 -270.036036) (xy 339.964771 -270.036036)
			(xy 339.968866 -269.985308) (xy 339.981045 -269.935894) (xy 340.000993 -269.889074) (xy 340.028194 -269.84606)
			(xy 340.061942 -269.807966) (xy 340.101364 -269.775779) (xy 340.145438 -269.750333) (xy 340.193024 -269.732286)
			(xy 340.242888 -269.722106) (xy 340.29374 -269.720057) (xy 340.344261 -269.726191) (xy 340.393145 -269.740351)
			(xy 340.439124 -269.762168) (xy 340.481008 -269.791078) (xy 340.517712 -269.826333) (xy 340.548285 -269.867019)
			(xy 340.571936 -269.912082) (xy 340.588052 -269.960356) (xy 340.596216 -270.01059) (xy 340.596728 -270.036036)
			(xy 340.915256 -270.036036) (xy 340.919216 -269.986982) (xy 340.930993 -269.939198) (xy 340.950284 -269.893922)
			(xy 340.976587 -269.852326) (xy 341.009222 -269.815489) (xy 341.047343 -269.784364) (xy 341.089964 -269.759757)
			(xy 341.13598 -269.742305) (xy 341.184199 -269.732461) (xy 341.233374 -269.73048) (xy 341.282229 -269.736412)
			(xy 341.3295 -269.750104) (xy 341.373962 -269.771202) (xy 341.414465 -269.799158) (xy 341.449958 -269.83325)
			(xy 341.479523 -269.872594) (xy 341.502394 -269.916171) (xy 341.517978 -269.962852) (xy 341.525873 -270.011429)
			(xy 341.526368 -270.036036) (xy 341.844879 -270.036036) (xy 341.848974 -269.985308) (xy 341.861153 -269.935894)
			(xy 341.881101 -269.889074) (xy 341.908302 -269.84606) (xy 341.94205 -269.807966) (xy 341.981472 -269.775779)
			(xy 342.025546 -269.750333) (xy 342.073132 -269.732286) (xy 342.122996 -269.722106) (xy 342.173848 -269.720057)
			(xy 342.224369 -269.726191) (xy 342.273253 -269.740351) (xy 342.319232 -269.762168) (xy 342.361116 -269.791078)
			(xy 342.39782 -269.826333) (xy 342.428393 -269.867019) (xy 342.452044 -269.912082) (xy 342.46816 -269.960356)
			(xy 342.476324 -270.01059) (xy 342.476836 -270.036036) (xy 342.795364 -270.036036) (xy 342.799324 -269.986982)
			(xy 342.811101 -269.939198) (xy 342.830392 -269.893922) (xy 342.856695 -269.852326) (xy 342.88933 -269.815489)
			(xy 342.927451 -269.784364) (xy 342.970072 -269.759757) (xy 343.016088 -269.742305) (xy 343.064307 -269.732461)
			(xy 343.113482 -269.73048) (xy 343.162337 -269.736412) (xy 343.209608 -269.750104) (xy 343.25407 -269.771202)
			(xy 343.294573 -269.799158) (xy 343.330066 -269.83325) (xy 343.359631 -269.872594) (xy 343.382502 -269.916171)
			(xy 343.398086 -269.962852) (xy 343.405981 -270.011429) (xy 343.406476 -270.036036) (xy 343.724987 -270.036036)
			(xy 343.729082 -269.985308) (xy 343.741261 -269.935894) (xy 343.761209 -269.889074) (xy 343.78841 -269.84606)
			(xy 343.822158 -269.807966) (xy 343.86158 -269.775779) (xy 343.905654 -269.750333) (xy 343.95324 -269.732286)
			(xy 344.003104 -269.722106) (xy 344.053956 -269.720057) (xy 344.104477 -269.726191) (xy 344.153361 -269.740351)
			(xy 344.19934 -269.762168) (xy 344.241224 -269.791078) (xy 344.277928 -269.826333) (xy 344.308501 -269.867019)
			(xy 344.332152 -269.912082) (xy 344.348268 -269.960356) (xy 344.356432 -270.01059) (xy 344.356944 -270.036036)
			(xy 344.356432 -270.061482) (xy 344.348268 -270.111716) (xy 344.332152 -270.15999) (xy 344.308501 -270.205053)
			(xy 344.277928 -270.245739) (xy 344.241224 -270.280994) (xy 344.19934 -270.309904) (xy 344.153361 -270.331721)
			(xy 344.104477 -270.345881) (xy 344.053956 -270.352015) (xy 344.003104 -270.349966) (xy 343.95324 -270.339786)
			(xy 343.905654 -270.321739) (xy 343.86158 -270.296293) (xy 343.822158 -270.264106) (xy 343.78841 -270.226012)
			(xy 343.761209 -270.182998) (xy 343.741261 -270.136178) (xy 343.729082 -270.086764) (xy 343.724987 -270.036036)
			(xy 343.406476 -270.036036) (xy 343.405981 -270.060643) (xy 343.398086 -270.10922) (xy 343.382502 -270.155901)
			(xy 343.359631 -270.199478) (xy 343.330066 -270.238822) (xy 343.294573 -270.272914) (xy 343.25407 -270.30087)
			(xy 343.209608 -270.321968) (xy 343.162337 -270.33566) (xy 343.113482 -270.341592) (xy 343.064307 -270.339611)
			(xy 343.016088 -270.329767) (xy 342.970072 -270.312315) (xy 342.927451 -270.287708) (xy 342.88933 -270.256583)
			(xy 342.856695 -270.219746) (xy 342.830392 -270.17815) (xy 342.811101 -270.132874) (xy 342.799324 -270.08509)
			(xy 342.795364 -270.036036) (xy 342.476836 -270.036036) (xy 342.476324 -270.061482) (xy 342.46816 -270.111716)
			(xy 342.452044 -270.15999) (xy 342.428393 -270.205053) (xy 342.39782 -270.245739) (xy 342.361116 -270.280994)
			(xy 342.319232 -270.309904) (xy 342.273253 -270.331721) (xy 342.224369 -270.345881) (xy 342.173848 -270.352015)
			(xy 342.122996 -270.349966) (xy 342.073132 -270.339786) (xy 342.025546 -270.321739) (xy 341.981472 -270.296293)
			(xy 341.94205 -270.264106) (xy 341.908302 -270.226012) (xy 341.881101 -270.182998) (xy 341.861153 -270.136178)
			(xy 341.848974 -270.086764) (xy 341.844879 -270.036036) (xy 341.526368 -270.036036) (xy 341.525873 -270.060643)
			(xy 341.517978 -270.10922) (xy 341.502394 -270.155901) (xy 341.479523 -270.199478) (xy 341.449958 -270.238822)
			(xy 341.414465 -270.272914) (xy 341.373962 -270.30087) (xy 341.3295 -270.321968) (xy 341.282229 -270.33566)
			(xy 341.233374 -270.341592) (xy 341.184199 -270.339611) (xy 341.13598 -270.329767) (xy 341.089964 -270.312315)
			(xy 341.047343 -270.287708) (xy 341.009222 -270.256583) (xy 340.976587 -270.219746) (xy 340.950284 -270.17815)
			(xy 340.930993 -270.132874) (xy 340.919216 -270.08509) (xy 340.915256 -270.036036) (xy 340.596728 -270.036036)
			(xy 340.596216 -270.061482) (xy 340.588052 -270.111716) (xy 340.571936 -270.15999) (xy 340.548285 -270.205053)
			(xy 340.517712 -270.245739) (xy 340.481008 -270.280994) (xy 340.439124 -270.309904) (xy 340.393145 -270.331721)
			(xy 340.344261 -270.345881) (xy 340.29374 -270.352015) (xy 340.242888 -270.349966) (xy 340.193024 -270.339786)
			(xy 340.145438 -270.321739) (xy 340.101364 -270.296293) (xy 340.061942 -270.264106) (xy 340.028194 -270.226012)
			(xy 340.000993 -270.182998) (xy 339.981045 -270.136178) (xy 339.968866 -270.086764) (xy 339.964771 -270.036036)
			(xy 339.656928 -270.036036) (xy 339.656416 -270.061482) (xy 339.648252 -270.111716) (xy 339.632136 -270.15999)
			(xy 339.608485 -270.205053) (xy 339.577912 -270.245739) (xy 339.541208 -270.280994) (xy 339.499324 -270.309904)
			(xy 339.453345 -270.331721) (xy 339.404461 -270.345881) (xy 339.35394 -270.352015) (xy 339.303088 -270.349966)
			(xy 339.253224 -270.339786) (xy 339.205638 -270.321739) (xy 339.161564 -270.296293) (xy 339.122142 -270.264106)
			(xy 339.088394 -270.226012) (xy 339.061193 -270.182998) (xy 339.041245 -270.136178) (xy 339.029066 -270.086764)
			(xy 339.024971 -270.036036) (xy 338.70646 -270.036036) (xy 338.705965 -270.060643) (xy 338.69807 -270.10922)
			(xy 338.682486 -270.155901) (xy 338.659615 -270.199478) (xy 338.63005 -270.238822) (xy 338.594557 -270.272914)
			(xy 338.554054 -270.30087) (xy 338.509592 -270.321968) (xy 338.462321 -270.33566) (xy 338.413466 -270.341592)
			(xy 338.364291 -270.339611) (xy 338.316072 -270.329767) (xy 338.270056 -270.312315) (xy 338.227435 -270.287708)
			(xy 338.189314 -270.256583) (xy 338.156679 -270.219746) (xy 338.130376 -270.17815) (xy 338.111085 -270.132874)
			(xy 338.099308 -270.08509) (xy 338.095348 -270.036036) (xy 337.766406 -270.036036) (xy 337.765911 -270.060643)
			(xy 337.758016 -270.10922) (xy 337.742432 -270.155901) (xy 337.719561 -270.199478) (xy 337.689996 -270.238822)
			(xy 337.654503 -270.272914) (xy 337.614 -270.30087) (xy 337.569538 -270.321968) (xy 337.522267 -270.33566)
			(xy 337.473412 -270.341592) (xy 337.424237 -270.339611) (xy 337.376018 -270.329767) (xy 337.330002 -270.312315)
			(xy 337.287381 -270.287708) (xy 337.24926 -270.256583) (xy 337.216625 -270.219746) (xy 337.190322 -270.17815)
			(xy 337.171031 -270.132874) (xy 337.159254 -270.08509) (xy 337.155294 -270.036036) (xy 336.826352 -270.036036)
			(xy 336.825857 -270.060643) (xy 336.817962 -270.10922) (xy 336.802378 -270.155901) (xy 336.779507 -270.199478)
			(xy 336.749942 -270.238822) (xy 336.714449 -270.272914) (xy 336.673946 -270.30087) (xy 336.629484 -270.321968)
			(xy 336.582213 -270.33566) (xy 336.533358 -270.341592) (xy 336.484183 -270.339611) (xy 336.435964 -270.329767)
			(xy 336.389948 -270.312315) (xy 336.347327 -270.287708) (xy 336.309206 -270.256583) (xy 336.276571 -270.219746)
			(xy 336.250268 -270.17815) (xy 336.230977 -270.132874) (xy 336.2192 -270.08509) (xy 336.21524 -270.036036)
			(xy 335.886298 -270.036036) (xy 335.885803 -270.060643) (xy 335.877908 -270.10922) (xy 335.862324 -270.155901)
			(xy 335.839453 -270.199478) (xy 335.809888 -270.238822) (xy 335.774395 -270.272914) (xy 335.733892 -270.30087)
			(xy 335.68943 -270.321968) (xy 335.642159 -270.33566) (xy 335.593304 -270.341592) (xy 335.544129 -270.339611)
			(xy 335.49591 -270.329767) (xy 335.449894 -270.312315) (xy 335.407273 -270.287708) (xy 335.369152 -270.256583)
			(xy 335.336517 -270.219746) (xy 335.310214 -270.17815) (xy 335.290923 -270.132874) (xy 335.279146 -270.08509)
			(xy 335.275186 -270.036036) (xy 334.950054 -270.036036) (xy 334.950054 -270.846042) (xy 335.74534 -270.846042)
			(xy 335.7493 -270.796988) (xy 335.761077 -270.749204) (xy 335.780368 -270.703928) (xy 335.806671 -270.662332)
			(xy 335.839306 -270.625495) (xy 335.877427 -270.59437) (xy 335.920048 -270.569763) (xy 335.966064 -270.552311)
			(xy 336.014283 -270.542467) (xy 336.063458 -270.540486) (xy 336.112313 -270.546418) (xy 336.159584 -270.56011)
			(xy 336.204046 -270.581208) (xy 336.244549 -270.609164) (xy 336.280042 -270.643256) (xy 336.309607 -270.6826)
			(xy 336.332478 -270.726177) (xy 336.348062 -270.772858) (xy 336.355957 -270.821435) (xy 336.356452 -270.846042)
			(xy 336.685394 -270.846042) (xy 336.689354 -270.796988) (xy 336.701131 -270.749204) (xy 336.720422 -270.703928)
			(xy 336.746725 -270.662332) (xy 336.77936 -270.625495) (xy 336.817481 -270.59437) (xy 336.860102 -270.569763)
			(xy 336.906118 -270.552311) (xy 336.954337 -270.542467) (xy 337.003512 -270.540486) (xy 337.052367 -270.546418)
			(xy 337.099638 -270.56011) (xy 337.1441 -270.581208) (xy 337.184603 -270.609164) (xy 337.220096 -270.643256)
			(xy 337.249661 -270.6826) (xy 337.272532 -270.726177) (xy 337.288116 -270.772858) (xy 337.296011 -270.821435)
			(xy 337.296506 -270.846042) (xy 337.625194 -270.846042) (xy 337.629154 -270.796988) (xy 337.640931 -270.749204)
			(xy 337.660222 -270.703928) (xy 337.686525 -270.662332) (xy 337.71916 -270.625495) (xy 337.757281 -270.59437)
			(xy 337.799902 -270.569763) (xy 337.845918 -270.552311) (xy 337.894137 -270.542467) (xy 337.943312 -270.540486)
			(xy 337.992167 -270.546418) (xy 338.039438 -270.56011) (xy 338.0839 -270.581208) (xy 338.124403 -270.609164)
			(xy 338.159896 -270.643256) (xy 338.189461 -270.6826) (xy 338.212332 -270.726177) (xy 338.227916 -270.772858)
			(xy 338.235811 -270.821435) (xy 338.236306 -270.846042) (xy 338.554817 -270.846042) (xy 338.558912 -270.795314)
			(xy 338.571091 -270.7459) (xy 338.591039 -270.69908) (xy 338.61824 -270.656066) (xy 338.651988 -270.617972)
			(xy 338.69141 -270.585785) (xy 338.735484 -270.560339) (xy 338.78307 -270.542292) (xy 338.832934 -270.532112)
			(xy 338.883786 -270.530063) (xy 338.934307 -270.536197) (xy 338.983191 -270.550357) (xy 339.02917 -270.572174)
			(xy 339.071054 -270.601084) (xy 339.107758 -270.636339) (xy 339.138331 -270.677025) (xy 339.161982 -270.722088)
			(xy 339.178098 -270.770362) (xy 339.186262 -270.820596) (xy 339.186774 -270.846042) (xy 339.505302 -270.846042)
			(xy 339.509262 -270.796988) (xy 339.521039 -270.749204) (xy 339.54033 -270.703928) (xy 339.566633 -270.662332)
			(xy 339.599268 -270.625495) (xy 339.637389 -270.59437) (xy 339.68001 -270.569763) (xy 339.726026 -270.552311)
			(xy 339.774245 -270.542467) (xy 339.82342 -270.540486) (xy 339.872275 -270.546418) (xy 339.919546 -270.56011)
			(xy 339.964008 -270.581208) (xy 340.004511 -270.609164) (xy 340.040004 -270.643256) (xy 340.069569 -270.6826)
			(xy 340.09244 -270.726177) (xy 340.108024 -270.772858) (xy 340.115919 -270.821435) (xy 340.116414 -270.846042)
			(xy 340.434925 -270.846042) (xy 340.43902 -270.795314) (xy 340.451199 -270.7459) (xy 340.471147 -270.69908)
			(xy 340.498348 -270.656066) (xy 340.532096 -270.617972) (xy 340.571518 -270.585785) (xy 340.615592 -270.560339)
			(xy 340.663178 -270.542292) (xy 340.713042 -270.532112) (xy 340.763894 -270.530063) (xy 340.814415 -270.536197)
			(xy 340.863299 -270.550357) (xy 340.909278 -270.572174) (xy 340.951162 -270.601084) (xy 340.987866 -270.636339)
			(xy 341.018439 -270.677025) (xy 341.04209 -270.722088) (xy 341.058206 -270.770362) (xy 341.06637 -270.820596)
			(xy 341.066882 -270.846042) (xy 342.314779 -270.846042) (xy 342.318874 -270.795314) (xy 342.331053 -270.7459)
			(xy 342.351001 -270.69908) (xy 342.378202 -270.656066) (xy 342.41195 -270.617972) (xy 342.451372 -270.585785)
			(xy 342.495446 -270.560339) (xy 342.543032 -270.542292) (xy 342.592896 -270.532112) (xy 342.643748 -270.530063)
			(xy 342.694269 -270.536197) (xy 342.743153 -270.550357) (xy 342.789132 -270.572174) (xy 342.831016 -270.601084)
			(xy 342.86772 -270.636339) (xy 342.898293 -270.677025) (xy 342.921944 -270.722088) (xy 342.93806 -270.770362)
			(xy 342.946224 -270.820596) (xy 342.946736 -270.846042) (xy 343.254833 -270.846042) (xy 343.258928 -270.795314)
			(xy 343.271107 -270.7459) (xy 343.291055 -270.69908) (xy 343.318256 -270.656066) (xy 343.352004 -270.617972)
			(xy 343.391426 -270.585785) (xy 343.4355 -270.560339) (xy 343.483086 -270.542292) (xy 343.53295 -270.532112)
			(xy 343.583802 -270.530063) (xy 343.634323 -270.536197) (xy 343.683207 -270.550357) (xy 343.729186 -270.572174)
			(xy 343.77107 -270.601084) (xy 343.807774 -270.636339) (xy 343.838347 -270.677025) (xy 343.861998 -270.722088)
			(xy 343.878114 -270.770362) (xy 343.886278 -270.820596) (xy 343.88679 -270.846042) (xy 343.886278 -270.871488)
			(xy 343.878114 -270.921722) (xy 343.861998 -270.969996) (xy 343.838347 -271.015059) (xy 343.807774 -271.055745)
			(xy 343.77107 -271.091) (xy 343.729186 -271.11991) (xy 343.683207 -271.141727) (xy 343.634323 -271.155887)
			(xy 343.583802 -271.162021) (xy 343.53295 -271.159972) (xy 343.483086 -271.149792) (xy 343.4355 -271.131745)
			(xy 343.391426 -271.106299) (xy 343.352004 -271.074112) (xy 343.318256 -271.036018) (xy 343.291055 -270.993004)
			(xy 343.271107 -270.946184) (xy 343.258928 -270.89677) (xy 343.254833 -270.846042) (xy 342.946736 -270.846042)
			(xy 342.946224 -270.871488) (xy 342.93806 -270.921722) (xy 342.921944 -270.969996) (xy 342.898293 -271.015059)
			(xy 342.86772 -271.055745) (xy 342.831016 -271.091) (xy 342.789132 -271.11991) (xy 342.743153 -271.141727)
			(xy 342.694269 -271.155887) (xy 342.643748 -271.162021) (xy 342.592896 -271.159972) (xy 342.543032 -271.149792)
			(xy 342.495446 -271.131745) (xy 342.451372 -271.106299) (xy 342.41195 -271.074112) (xy 342.378202 -271.036018)
			(xy 342.351001 -270.993004) (xy 342.331053 -270.946184) (xy 342.318874 -270.89677) (xy 342.314779 -270.846042)
			(xy 341.066882 -270.846042) (xy 341.06637 -270.871488) (xy 341.058206 -270.921722) (xy 341.04209 -270.969996)
			(xy 341.018439 -271.015059) (xy 340.987866 -271.055745) (xy 340.951162 -271.091) (xy 340.909278 -271.11991)
			(xy 340.863299 -271.141727) (xy 340.814415 -271.155887) (xy 340.763894 -271.162021) (xy 340.713042 -271.159972)
			(xy 340.663178 -271.149792) (xy 340.615592 -271.131745) (xy 340.571518 -271.106299) (xy 340.532096 -271.074112)
			(xy 340.498348 -271.036018) (xy 340.471147 -270.993004) (xy 340.451199 -270.946184) (xy 340.43902 -270.89677)
			(xy 340.434925 -270.846042) (xy 340.116414 -270.846042) (xy 340.115919 -270.870649) (xy 340.108024 -270.919226)
			(xy 340.09244 -270.965907) (xy 340.069569 -271.009484) (xy 340.040004 -271.048828) (xy 340.004511 -271.08292)
			(xy 339.964008 -271.110876) (xy 339.919546 -271.131974) (xy 339.872275 -271.145666) (xy 339.82342 -271.151598)
			(xy 339.774245 -271.149617) (xy 339.726026 -271.139773) (xy 339.68001 -271.122321) (xy 339.637389 -271.097714)
			(xy 339.599268 -271.066589) (xy 339.566633 -271.029752) (xy 339.54033 -270.988156) (xy 339.521039 -270.94288)
			(xy 339.509262 -270.895096) (xy 339.505302 -270.846042) (xy 339.186774 -270.846042) (xy 339.186262 -270.871488)
			(xy 339.178098 -270.921722) (xy 339.161982 -270.969996) (xy 339.138331 -271.015059) (xy 339.107758 -271.055745)
			(xy 339.071054 -271.091) (xy 339.02917 -271.11991) (xy 338.983191 -271.141727) (xy 338.934307 -271.155887)
			(xy 338.883786 -271.162021) (xy 338.832934 -271.159972) (xy 338.78307 -271.149792) (xy 338.735484 -271.131745)
			(xy 338.69141 -271.106299) (xy 338.651988 -271.074112) (xy 338.61824 -271.036018) (xy 338.591039 -270.993004)
			(xy 338.571091 -270.946184) (xy 338.558912 -270.89677) (xy 338.554817 -270.846042) (xy 338.236306 -270.846042)
			(xy 338.235811 -270.870649) (xy 338.227916 -270.919226) (xy 338.212332 -270.965907) (xy 338.189461 -271.009484)
			(xy 338.159896 -271.048828) (xy 338.124403 -271.08292) (xy 338.0839 -271.110876) (xy 338.039438 -271.131974)
			(xy 337.992167 -271.145666) (xy 337.943312 -271.151598) (xy 337.894137 -271.149617) (xy 337.845918 -271.139773)
			(xy 337.799902 -271.122321) (xy 337.757281 -271.097714) (xy 337.71916 -271.066589) (xy 337.686525 -271.029752)
			(xy 337.660222 -270.988156) (xy 337.640931 -270.94288) (xy 337.629154 -270.895096) (xy 337.625194 -270.846042)
			(xy 337.296506 -270.846042) (xy 337.296011 -270.870649) (xy 337.288116 -270.919226) (xy 337.272532 -270.965907)
			(xy 337.249661 -271.009484) (xy 337.220096 -271.048828) (xy 337.184603 -271.08292) (xy 337.1441 -271.110876)
			(xy 337.099638 -271.131974) (xy 337.052367 -271.145666) (xy 337.003512 -271.151598) (xy 336.954337 -271.149617)
			(xy 336.906118 -271.139773) (xy 336.860102 -271.122321) (xy 336.817481 -271.097714) (xy 336.77936 -271.066589)
			(xy 336.746725 -271.029752) (xy 336.720422 -270.988156) (xy 336.701131 -270.94288) (xy 336.689354 -270.895096)
			(xy 336.685394 -270.846042) (xy 336.356452 -270.846042) (xy 336.355957 -270.870649) (xy 336.348062 -270.919226)
			(xy 336.332478 -270.965907) (xy 336.309607 -271.009484) (xy 336.280042 -271.048828) (xy 336.244549 -271.08292)
			(xy 336.204046 -271.110876) (xy 336.159584 -271.131974) (xy 336.112313 -271.145666) (xy 336.063458 -271.151598)
			(xy 336.014283 -271.149617) (xy 335.966064 -271.139773) (xy 335.920048 -271.122321) (xy 335.877427 -271.097714)
			(xy 335.839306 -271.066589) (xy 335.806671 -271.029752) (xy 335.780368 -270.988156) (xy 335.761077 -270.94288)
			(xy 335.7493 -270.895096) (xy 335.74534 -270.846042) (xy 334.950054 -270.846042) (xy 334.950054 -271.656048)
			(xy 335.275186 -271.656048) (xy 335.279146 -271.606994) (xy 335.290923 -271.55921) (xy 335.310214 -271.513934)
			(xy 335.336517 -271.472338) (xy 335.369152 -271.435501) (xy 335.407273 -271.404376) (xy 335.449894 -271.379769)
			(xy 335.49591 -271.362317) (xy 335.544129 -271.352473) (xy 335.593304 -271.350492) (xy 335.642159 -271.356424)
			(xy 335.68943 -271.370116) (xy 335.733892 -271.391214) (xy 335.774395 -271.41917) (xy 335.809888 -271.453262)
			(xy 335.839453 -271.492606) (xy 335.862324 -271.536183) (xy 335.877908 -271.582864) (xy 335.885803 -271.631441)
			(xy 335.886298 -271.656048) (xy 336.21524 -271.656048) (xy 336.2192 -271.606994) (xy 336.230977 -271.55921)
			(xy 336.250268 -271.513934) (xy 336.276571 -271.472338) (xy 336.309206 -271.435501) (xy 336.347327 -271.404376)
			(xy 336.389948 -271.379769) (xy 336.435964 -271.362317) (xy 336.484183 -271.352473) (xy 336.533358 -271.350492)
			(xy 336.582213 -271.356424) (xy 336.629484 -271.370116) (xy 336.673946 -271.391214) (xy 336.714449 -271.41917)
			(xy 336.749942 -271.453262) (xy 336.779507 -271.492606) (xy 336.802378 -271.536183) (xy 336.817962 -271.582864)
			(xy 336.825857 -271.631441) (xy 336.826352 -271.656048) (xy 337.155294 -271.656048) (xy 337.159254 -271.606994)
			(xy 337.171031 -271.55921) (xy 337.190322 -271.513934) (xy 337.216625 -271.472338) (xy 337.24926 -271.435501)
			(xy 337.287381 -271.404376) (xy 337.330002 -271.379769) (xy 337.376018 -271.362317) (xy 337.424237 -271.352473)
			(xy 337.473412 -271.350492) (xy 337.522267 -271.356424) (xy 337.569538 -271.370116) (xy 337.614 -271.391214)
			(xy 337.654503 -271.41917) (xy 337.689996 -271.453262) (xy 337.719561 -271.492606) (xy 337.742432 -271.536183)
			(xy 337.758016 -271.582864) (xy 337.765911 -271.631441) (xy 337.766406 -271.656048) (xy 338.095348 -271.656048)
			(xy 338.099308 -271.606994) (xy 338.111085 -271.55921) (xy 338.130376 -271.513934) (xy 338.156679 -271.472338)
			(xy 338.189314 -271.435501) (xy 338.227435 -271.404376) (xy 338.270056 -271.379769) (xy 338.316072 -271.362317)
			(xy 338.364291 -271.352473) (xy 338.413466 -271.350492) (xy 338.462321 -271.356424) (xy 338.509592 -271.370116)
			(xy 338.554054 -271.391214) (xy 338.594557 -271.41917) (xy 338.63005 -271.453262) (xy 338.659615 -271.492606)
			(xy 338.682486 -271.536183) (xy 338.69807 -271.582864) (xy 338.705965 -271.631441) (xy 338.70646 -271.656048)
			(xy 339.024971 -271.656048) (xy 339.029066 -271.60532) (xy 339.041245 -271.555906) (xy 339.061193 -271.509086)
			(xy 339.088394 -271.466072) (xy 339.122142 -271.427978) (xy 339.161564 -271.395791) (xy 339.205638 -271.370345)
			(xy 339.253224 -271.352298) (xy 339.303088 -271.342118) (xy 339.35394 -271.340069) (xy 339.404461 -271.346203)
			(xy 339.453345 -271.360363) (xy 339.499324 -271.38218) (xy 339.541208 -271.41109) (xy 339.577912 -271.446345)
			(xy 339.608485 -271.487031) (xy 339.632136 -271.532094) (xy 339.648252 -271.580368) (xy 339.656416 -271.630602)
			(xy 339.656928 -271.656048) (xy 339.964771 -271.656048) (xy 339.968866 -271.60532) (xy 339.981045 -271.555906)
			(xy 340.000993 -271.509086) (xy 340.028194 -271.466072) (xy 340.061942 -271.427978) (xy 340.101364 -271.395791)
			(xy 340.145438 -271.370345) (xy 340.193024 -271.352298) (xy 340.242888 -271.342118) (xy 340.29374 -271.340069)
			(xy 340.344261 -271.346203) (xy 340.393145 -271.360363) (xy 340.439124 -271.38218) (xy 340.481008 -271.41109)
			(xy 340.517712 -271.446345) (xy 340.548285 -271.487031) (xy 340.571936 -271.532094) (xy 340.588052 -271.580368)
			(xy 340.596216 -271.630602) (xy 340.596728 -271.656048) (xy 340.915256 -271.656048) (xy 340.919216 -271.606994)
			(xy 340.930993 -271.55921) (xy 340.950284 -271.513934) (xy 340.976587 -271.472338) (xy 341.009222 -271.435501)
			(xy 341.047343 -271.404376) (xy 341.089964 -271.379769) (xy 341.13598 -271.362317) (xy 341.184199 -271.352473)
			(xy 341.233374 -271.350492) (xy 341.282229 -271.356424) (xy 341.3295 -271.370116) (xy 341.373962 -271.391214)
			(xy 341.414465 -271.41917) (xy 341.449958 -271.453262) (xy 341.479523 -271.492606) (xy 341.502394 -271.536183)
			(xy 341.517978 -271.582864) (xy 341.525873 -271.631441) (xy 341.526368 -271.656048) (xy 341.844879 -271.656048)
			(xy 341.848974 -271.60532) (xy 341.861153 -271.555906) (xy 341.881101 -271.509086) (xy 341.908302 -271.466072)
			(xy 341.94205 -271.427978) (xy 341.981472 -271.395791) (xy 342.025546 -271.370345) (xy 342.073132 -271.352298)
			(xy 342.122996 -271.342118) (xy 342.173848 -271.340069) (xy 342.224369 -271.346203) (xy 342.273253 -271.360363)
			(xy 342.319232 -271.38218) (xy 342.361116 -271.41109) (xy 342.39782 -271.446345) (xy 342.428393 -271.487031)
			(xy 342.452044 -271.532094) (xy 342.46816 -271.580368) (xy 342.476324 -271.630602) (xy 342.476836 -271.656048)
			(xy 342.795364 -271.656048) (xy 342.799324 -271.606994) (xy 342.811101 -271.55921) (xy 342.830392 -271.513934)
			(xy 342.856695 -271.472338) (xy 342.88933 -271.435501) (xy 342.927451 -271.404376) (xy 342.970072 -271.379769)
			(xy 343.016088 -271.362317) (xy 343.064307 -271.352473) (xy 343.113482 -271.350492) (xy 343.162337 -271.356424)
			(xy 343.209608 -271.370116) (xy 343.25407 -271.391214) (xy 343.294573 -271.41917) (xy 343.330066 -271.453262)
			(xy 343.359631 -271.492606) (xy 343.382502 -271.536183) (xy 343.398086 -271.582864) (xy 343.405981 -271.631441)
			(xy 343.406476 -271.656048) (xy 343.724987 -271.656048) (xy 343.729082 -271.60532) (xy 343.741261 -271.555906)
			(xy 343.761209 -271.509086) (xy 343.78841 -271.466072) (xy 343.822158 -271.427978) (xy 343.86158 -271.395791)
			(xy 343.905654 -271.370345) (xy 343.95324 -271.352298) (xy 344.003104 -271.342118) (xy 344.053956 -271.340069)
			(xy 344.104477 -271.346203) (xy 344.153361 -271.360363) (xy 344.19934 -271.38218) (xy 344.241224 -271.41109)
			(xy 344.277928 -271.446345) (xy 344.308501 -271.487031) (xy 344.332152 -271.532094) (xy 344.348268 -271.580368)
			(xy 344.356432 -271.630602) (xy 344.356944 -271.656048) (xy 344.356432 -271.681494) (xy 344.348268 -271.731728)
			(xy 344.332152 -271.780002) (xy 344.308501 -271.825065) (xy 344.277928 -271.865751) (xy 344.241224 -271.901006)
			(xy 344.19934 -271.929916) (xy 344.153361 -271.951733) (xy 344.104477 -271.965893) (xy 344.053956 -271.972027)
			(xy 344.003104 -271.969978) (xy 343.95324 -271.959798) (xy 343.905654 -271.941751) (xy 343.86158 -271.916305)
			(xy 343.822158 -271.884118) (xy 343.78841 -271.846024) (xy 343.761209 -271.80301) (xy 343.741261 -271.75619)
			(xy 343.729082 -271.706776) (xy 343.724987 -271.656048) (xy 343.406476 -271.656048) (xy 343.405981 -271.680655)
			(xy 343.398086 -271.729232) (xy 343.382502 -271.775913) (xy 343.359631 -271.81949) (xy 343.330066 -271.858834)
			(xy 343.294573 -271.892926) (xy 343.25407 -271.920882) (xy 343.209608 -271.94198) (xy 343.162337 -271.955672)
			(xy 343.113482 -271.961604) (xy 343.064307 -271.959623) (xy 343.016088 -271.949779) (xy 342.970072 -271.932327)
			(xy 342.927451 -271.90772) (xy 342.88933 -271.876595) (xy 342.856695 -271.839758) (xy 342.830392 -271.798162)
			(xy 342.811101 -271.752886) (xy 342.799324 -271.705102) (xy 342.795364 -271.656048) (xy 342.476836 -271.656048)
			(xy 342.476324 -271.681494) (xy 342.46816 -271.731728) (xy 342.452044 -271.780002) (xy 342.428393 -271.825065)
			(xy 342.39782 -271.865751) (xy 342.361116 -271.901006) (xy 342.319232 -271.929916) (xy 342.273253 -271.951733)
			(xy 342.224369 -271.965893) (xy 342.173848 -271.972027) (xy 342.122996 -271.969978) (xy 342.073132 -271.959798)
			(xy 342.025546 -271.941751) (xy 341.981472 -271.916305) (xy 341.94205 -271.884118) (xy 341.908302 -271.846024)
			(xy 341.881101 -271.80301) (xy 341.861153 -271.75619) (xy 341.848974 -271.706776) (xy 341.844879 -271.656048)
			(xy 341.526368 -271.656048) (xy 341.525873 -271.680655) (xy 341.517978 -271.729232) (xy 341.502394 -271.775913)
			(xy 341.479523 -271.81949) (xy 341.449958 -271.858834) (xy 341.414465 -271.892926) (xy 341.373962 -271.920882)
			(xy 341.3295 -271.94198) (xy 341.282229 -271.955672) (xy 341.233374 -271.961604) (xy 341.184199 -271.959623)
			(xy 341.13598 -271.949779) (xy 341.089964 -271.932327) (xy 341.047343 -271.90772) (xy 341.009222 -271.876595)
			(xy 340.976587 -271.839758) (xy 340.950284 -271.798162) (xy 340.930993 -271.752886) (xy 340.919216 -271.705102)
			(xy 340.915256 -271.656048) (xy 340.596728 -271.656048) (xy 340.596216 -271.681494) (xy 340.588052 -271.731728)
			(xy 340.571936 -271.780002) (xy 340.548285 -271.825065) (xy 340.517712 -271.865751) (xy 340.481008 -271.901006)
			(xy 340.439124 -271.929916) (xy 340.393145 -271.951733) (xy 340.344261 -271.965893) (xy 340.29374 -271.972027)
			(xy 340.242888 -271.969978) (xy 340.193024 -271.959798) (xy 340.145438 -271.941751) (xy 340.101364 -271.916305)
			(xy 340.061942 -271.884118) (xy 340.028194 -271.846024) (xy 340.000993 -271.80301) (xy 339.981045 -271.75619)
			(xy 339.968866 -271.706776) (xy 339.964771 -271.656048) (xy 339.656928 -271.656048) (xy 339.656416 -271.681494)
			(xy 339.648252 -271.731728) (xy 339.632136 -271.780002) (xy 339.608485 -271.825065) (xy 339.577912 -271.865751)
			(xy 339.541208 -271.901006) (xy 339.499324 -271.929916) (xy 339.453345 -271.951733) (xy 339.404461 -271.965893)
			(xy 339.35394 -271.972027) (xy 339.303088 -271.969978) (xy 339.253224 -271.959798) (xy 339.205638 -271.941751)
			(xy 339.161564 -271.916305) (xy 339.122142 -271.884118) (xy 339.088394 -271.846024) (xy 339.061193 -271.80301)
			(xy 339.041245 -271.75619) (xy 339.029066 -271.706776) (xy 339.024971 -271.656048) (xy 338.70646 -271.656048)
			(xy 338.705965 -271.680655) (xy 338.69807 -271.729232) (xy 338.682486 -271.775913) (xy 338.659615 -271.81949)
			(xy 338.63005 -271.858834) (xy 338.594557 -271.892926) (xy 338.554054 -271.920882) (xy 338.509592 -271.94198)
			(xy 338.462321 -271.955672) (xy 338.413466 -271.961604) (xy 338.364291 -271.959623) (xy 338.316072 -271.949779)
			(xy 338.270056 -271.932327) (xy 338.227435 -271.90772) (xy 338.189314 -271.876595) (xy 338.156679 -271.839758)
			(xy 338.130376 -271.798162) (xy 338.111085 -271.752886) (xy 338.099308 -271.705102) (xy 338.095348 -271.656048)
			(xy 337.766406 -271.656048) (xy 337.765911 -271.680655) (xy 337.758016 -271.729232) (xy 337.742432 -271.775913)
			(xy 337.719561 -271.81949) (xy 337.689996 -271.858834) (xy 337.654503 -271.892926) (xy 337.614 -271.920882)
			(xy 337.569538 -271.94198) (xy 337.522267 -271.955672) (xy 337.473412 -271.961604) (xy 337.424237 -271.959623)
			(xy 337.376018 -271.949779) (xy 337.330002 -271.932327) (xy 337.287381 -271.90772) (xy 337.24926 -271.876595)
			(xy 337.216625 -271.839758) (xy 337.190322 -271.798162) (xy 337.171031 -271.752886) (xy 337.159254 -271.705102)
			(xy 337.155294 -271.656048) (xy 336.826352 -271.656048) (xy 336.825857 -271.680655) (xy 336.817962 -271.729232)
			(xy 336.802378 -271.775913) (xy 336.779507 -271.81949) (xy 336.749942 -271.858834) (xy 336.714449 -271.892926)
			(xy 336.673946 -271.920882) (xy 336.629484 -271.94198) (xy 336.582213 -271.955672) (xy 336.533358 -271.961604)
			(xy 336.484183 -271.959623) (xy 336.435964 -271.949779) (xy 336.389948 -271.932327) (xy 336.347327 -271.90772)
			(xy 336.309206 -271.876595) (xy 336.276571 -271.839758) (xy 336.250268 -271.798162) (xy 336.230977 -271.752886)
			(xy 336.2192 -271.705102) (xy 336.21524 -271.656048) (xy 335.886298 -271.656048) (xy 335.885803 -271.680655)
			(xy 335.877908 -271.729232) (xy 335.862324 -271.775913) (xy 335.839453 -271.81949) (xy 335.809888 -271.858834)
			(xy 335.774395 -271.892926) (xy 335.733892 -271.920882) (xy 335.68943 -271.94198) (xy 335.642159 -271.955672)
			(xy 335.593304 -271.961604) (xy 335.544129 -271.959623) (xy 335.49591 -271.949779) (xy 335.449894 -271.932327)
			(xy 335.407273 -271.90772) (xy 335.369152 -271.876595) (xy 335.336517 -271.839758) (xy 335.310214 -271.798162)
			(xy 335.290923 -271.752886) (xy 335.279146 -271.705102) (xy 335.275186 -271.656048) (xy 334.950054 -271.656048)
			(xy 334.950054 -272.064734) (xy 334.950054 -272.067274) (xy 334.950958 -272.076944) (xy 334.95905 -272.094583)
			(xy 334.965802 -272.101564) (xy 335.024476 -272.15211) (xy 335.02871 -272.155581) (xy 335.038321 -272.160822)
			(xy 335.043526 -272.162524) (xy 335.054194 -272.165572) (xy 335.065116 -272.164048) (xy 335.076354 -272.162492)
			(xy 335.098983 -272.160837) (xy 335.110328 -272.160746) (xy 335.11109 -272.160746) (xy 335.136352 -272.161238)
			(xy 335.186187 -272.169553) (xy 335.233974 -272.185956) (xy 335.278409 -272.210002) (xy 335.318281 -272.241034)
			(xy 335.3525 -272.278205) (xy 335.380135 -272.320502) (xy 335.40043 -272.36677) (xy 335.412834 -272.415748)
			(xy 335.417002 -272.466054) (xy 335.74534 -272.466054) (xy 335.7493 -272.417) (xy 335.761077 -272.369216)
			(xy 335.780368 -272.32394) (xy 335.806671 -272.282344) (xy 335.839306 -272.245507) (xy 335.877427 -272.214382)
			(xy 335.920048 -272.189775) (xy 335.966064 -272.172323) (xy 336.014283 -272.162479) (xy 336.063458 -272.160498)
			(xy 336.112313 -272.16643) (xy 336.159584 -272.180122) (xy 336.204046 -272.20122) (xy 336.244549 -272.229176)
			(xy 336.280042 -272.263268) (xy 336.309607 -272.302612) (xy 336.332478 -272.346189) (xy 336.348062 -272.39287)
			(xy 336.355957 -272.441447) (xy 336.356452 -272.466054) (xy 336.685394 -272.466054) (xy 336.689354 -272.417)
			(xy 336.701131 -272.369216) (xy 336.720422 -272.32394) (xy 336.746725 -272.282344) (xy 336.77936 -272.245507)
			(xy 336.817481 -272.214382) (xy 336.860102 -272.189775) (xy 336.906118 -272.172323) (xy 336.954337 -272.162479)
			(xy 337.003512 -272.160498) (xy 337.052367 -272.16643) (xy 337.099638 -272.180122) (xy 337.1441 -272.20122)
			(xy 337.184603 -272.229176) (xy 337.220096 -272.263268) (xy 337.249661 -272.302612) (xy 337.272532 -272.346189)
			(xy 337.288116 -272.39287) (xy 337.296011 -272.441447) (xy 337.296506 -272.466054) (xy 337.625194 -272.466054)
			(xy 337.629154 -272.417) (xy 337.640931 -272.369216) (xy 337.660222 -272.32394) (xy 337.686525 -272.282344)
			(xy 337.71916 -272.245507) (xy 337.757281 -272.214382) (xy 337.799902 -272.189775) (xy 337.845918 -272.172323)
			(xy 337.894137 -272.162479) (xy 337.943312 -272.160498) (xy 337.992167 -272.16643) (xy 338.039438 -272.180122)
			(xy 338.0839 -272.20122) (xy 338.124403 -272.229176) (xy 338.159896 -272.263268) (xy 338.189461 -272.302612)
			(xy 338.212332 -272.346189) (xy 338.227916 -272.39287) (xy 338.235811 -272.441447) (xy 338.236306 -272.466054)
			(xy 338.554817 -272.466054) (xy 338.558912 -272.415326) (xy 338.571091 -272.365912) (xy 338.591039 -272.319092)
			(xy 338.61824 -272.276078) (xy 338.651988 -272.237984) (xy 338.69141 -272.205797) (xy 338.735484 -272.180351)
			(xy 338.78307 -272.162304) (xy 338.832934 -272.152124) (xy 338.883786 -272.150075) (xy 338.934307 -272.156209)
			(xy 338.983191 -272.170369) (xy 339.02917 -272.192186) (xy 339.071054 -272.221096) (xy 339.107758 -272.256351)
			(xy 339.138331 -272.297037) (xy 339.161982 -272.3421) (xy 339.178098 -272.390374) (xy 339.186262 -272.440608)
			(xy 339.186774 -272.466054) (xy 339.505302 -272.466054) (xy 339.509262 -272.417) (xy 339.521039 -272.369216)
			(xy 339.54033 -272.32394) (xy 339.566633 -272.282344) (xy 339.599268 -272.245507) (xy 339.637389 -272.214382)
			(xy 339.68001 -272.189775) (xy 339.726026 -272.172323) (xy 339.774245 -272.162479) (xy 339.82342 -272.160498)
			(xy 339.872275 -272.16643) (xy 339.919546 -272.180122) (xy 339.964008 -272.20122) (xy 340.004511 -272.229176)
			(xy 340.040004 -272.263268) (xy 340.069569 -272.302612) (xy 340.09244 -272.346189) (xy 340.108024 -272.39287)
			(xy 340.115919 -272.441447) (xy 340.116414 -272.466054) (xy 340.434925 -272.466054) (xy 340.43902 -272.415326)
			(xy 340.451199 -272.365912) (xy 340.471147 -272.319092) (xy 340.498348 -272.276078) (xy 340.532096 -272.237984)
			(xy 340.571518 -272.205797) (xy 340.615592 -272.180351) (xy 340.663178 -272.162304) (xy 340.713042 -272.152124)
			(xy 340.763894 -272.150075) (xy 340.814415 -272.156209) (xy 340.863299 -272.170369) (xy 340.909278 -272.192186)
			(xy 340.951162 -272.221096) (xy 340.987866 -272.256351) (xy 341.018439 -272.297037) (xy 341.04209 -272.3421)
			(xy 341.058206 -272.390374) (xy 341.06637 -272.440608) (xy 341.066882 -272.466054) (xy 341.38541 -272.466054)
			(xy 341.38937 -272.417) (xy 341.401147 -272.369216) (xy 341.420438 -272.32394) (xy 341.446741 -272.282344)
			(xy 341.479376 -272.245507) (xy 341.517497 -272.214382) (xy 341.560118 -272.189775) (xy 341.606134 -272.172323)
			(xy 341.654353 -272.162479) (xy 341.703528 -272.160498) (xy 341.752383 -272.16643) (xy 341.799654 -272.180122)
			(xy 341.844116 -272.20122) (xy 341.884619 -272.229176) (xy 341.920112 -272.263268) (xy 341.949677 -272.302612)
			(xy 341.972548 -272.346189) (xy 341.988132 -272.39287) (xy 341.996027 -272.441447) (xy 341.996522 -272.466054)
			(xy 342.314779 -272.466054) (xy 342.318874 -272.415326) (xy 342.331053 -272.365912) (xy 342.351001 -272.319092)
			(xy 342.378202 -272.276078) (xy 342.41195 -272.237984) (xy 342.451372 -272.205797) (xy 342.495446 -272.180351)
			(xy 342.543032 -272.162304) (xy 342.592896 -272.152124) (xy 342.643748 -272.150075) (xy 342.694269 -272.156209)
			(xy 342.743153 -272.170369) (xy 342.789132 -272.192186) (xy 342.831016 -272.221096) (xy 342.86772 -272.256351)
			(xy 342.898293 -272.297037) (xy 342.921944 -272.3421) (xy 342.93806 -272.390374) (xy 342.946224 -272.440608)
			(xy 342.946736 -272.466054) (xy 343.254833 -272.466054) (xy 343.258928 -272.415326) (xy 343.271107 -272.365912)
			(xy 343.291055 -272.319092) (xy 343.318256 -272.276078) (xy 343.352004 -272.237984) (xy 343.391426 -272.205797)
			(xy 343.4355 -272.180351) (xy 343.483086 -272.162304) (xy 343.53295 -272.152124) (xy 343.583802 -272.150075)
			(xy 343.634323 -272.156209) (xy 343.683207 -272.170369) (xy 343.729186 -272.192186) (xy 343.77107 -272.221096)
			(xy 343.807774 -272.256351) (xy 343.838347 -272.297037) (xy 343.861998 -272.3421) (xy 343.878114 -272.390374)
			(xy 343.886278 -272.440608) (xy 343.88679 -272.466054) (xy 343.886278 -272.4915) (xy 343.878114 -272.541734)
			(xy 343.861998 -272.590008) (xy 343.838347 -272.635071) (xy 343.807774 -272.675757) (xy 343.77107 -272.711012)
			(xy 343.729186 -272.739922) (xy 343.683207 -272.761739) (xy 343.634323 -272.775899) (xy 343.583802 -272.782033)
			(xy 343.53295 -272.779984) (xy 343.483086 -272.769804) (xy 343.4355 -272.751757) (xy 343.391426 -272.726311)
			(xy 343.352004 -272.694124) (xy 343.318256 -272.65603) (xy 343.291055 -272.613016) (xy 343.271107 -272.566196)
			(xy 343.258928 -272.516782) (xy 343.254833 -272.466054) (xy 342.946736 -272.466054) (xy 342.946224 -272.4915)
			(xy 342.93806 -272.541734) (xy 342.921944 -272.590008) (xy 342.898293 -272.635071) (xy 342.86772 -272.675757)
			(xy 342.831016 -272.711012) (xy 342.789132 -272.739922) (xy 342.743153 -272.761739) (xy 342.694269 -272.775899)
			(xy 342.643748 -272.782033) (xy 342.592896 -272.779984) (xy 342.543032 -272.769804) (xy 342.495446 -272.751757)
			(xy 342.451372 -272.726311) (xy 342.41195 -272.694124) (xy 342.378202 -272.65603) (xy 342.351001 -272.613016)
			(xy 342.331053 -272.566196) (xy 342.318874 -272.516782) (xy 342.314779 -272.466054) (xy 341.996522 -272.466054)
			(xy 341.996027 -272.490661) (xy 341.988132 -272.539238) (xy 341.972548 -272.585919) (xy 341.949677 -272.629496)
			(xy 341.920112 -272.66884) (xy 341.884619 -272.702932) (xy 341.844116 -272.730888) (xy 341.799654 -272.751986)
			(xy 341.752383 -272.765678) (xy 341.703528 -272.77161) (xy 341.654353 -272.769629) (xy 341.606134 -272.759785)
			(xy 341.560118 -272.742333) (xy 341.517497 -272.717726) (xy 341.479376 -272.686601) (xy 341.446741 -272.649764)
			(xy 341.420438 -272.608168) (xy 341.401147 -272.562892) (xy 341.38937 -272.515108) (xy 341.38541 -272.466054)
			(xy 341.066882 -272.466054) (xy 341.06637 -272.4915) (xy 341.058206 -272.541734) (xy 341.04209 -272.590008)
			(xy 341.018439 -272.635071) (xy 340.987866 -272.675757) (xy 340.951162 -272.711012) (xy 340.909278 -272.739922)
			(xy 340.863299 -272.761739) (xy 340.814415 -272.775899) (xy 340.763894 -272.782033) (xy 340.713042 -272.779984)
			(xy 340.663178 -272.769804) (xy 340.615592 -272.751757) (xy 340.571518 -272.726311) (xy 340.532096 -272.694124)
			(xy 340.498348 -272.65603) (xy 340.471147 -272.613016) (xy 340.451199 -272.566196) (xy 340.43902 -272.516782)
			(xy 340.434925 -272.466054) (xy 340.116414 -272.466054) (xy 340.115919 -272.490661) (xy 340.108024 -272.539238)
			(xy 340.09244 -272.585919) (xy 340.069569 -272.629496) (xy 340.040004 -272.66884) (xy 340.004511 -272.702932)
			(xy 339.964008 -272.730888) (xy 339.919546 -272.751986) (xy 339.872275 -272.765678) (xy 339.82342 -272.77161)
			(xy 339.774245 -272.769629) (xy 339.726026 -272.759785) (xy 339.68001 -272.742333) (xy 339.637389 -272.717726)
			(xy 339.599268 -272.686601) (xy 339.566633 -272.649764) (xy 339.54033 -272.608168) (xy 339.521039 -272.562892)
			(xy 339.509262 -272.515108) (xy 339.505302 -272.466054) (xy 339.186774 -272.466054) (xy 339.186262 -272.4915)
			(xy 339.178098 -272.541734) (xy 339.161982 -272.590008) (xy 339.138331 -272.635071) (xy 339.107758 -272.675757)
			(xy 339.071054 -272.711012) (xy 339.02917 -272.739922) (xy 338.983191 -272.761739) (xy 338.934307 -272.775899)
			(xy 338.883786 -272.782033) (xy 338.832934 -272.779984) (xy 338.78307 -272.769804) (xy 338.735484 -272.751757)
			(xy 338.69141 -272.726311) (xy 338.651988 -272.694124) (xy 338.61824 -272.65603) (xy 338.591039 -272.613016)
			(xy 338.571091 -272.566196) (xy 338.558912 -272.516782) (xy 338.554817 -272.466054) (xy 338.236306 -272.466054)
			(xy 338.235811 -272.490661) (xy 338.227916 -272.539238) (xy 338.212332 -272.585919) (xy 338.189461 -272.629496)
			(xy 338.159896 -272.66884) (xy 338.124403 -272.702932) (xy 338.0839 -272.730888) (xy 338.039438 -272.751986)
			(xy 337.992167 -272.765678) (xy 337.943312 -272.77161) (xy 337.894137 -272.769629) (xy 337.845918 -272.759785)
			(xy 337.799902 -272.742333) (xy 337.757281 -272.717726) (xy 337.71916 -272.686601) (xy 337.686525 -272.649764)
			(xy 337.660222 -272.608168) (xy 337.640931 -272.562892) (xy 337.629154 -272.515108) (xy 337.625194 -272.466054)
			(xy 337.296506 -272.466054) (xy 337.296011 -272.490661) (xy 337.288116 -272.539238) (xy 337.272532 -272.585919)
			(xy 337.249661 -272.629496) (xy 337.220096 -272.66884) (xy 337.184603 -272.702932) (xy 337.1441 -272.730888)
			(xy 337.099638 -272.751986) (xy 337.052367 -272.765678) (xy 337.003512 -272.77161) (xy 336.954337 -272.769629)
			(xy 336.906118 -272.759785) (xy 336.860102 -272.742333) (xy 336.817481 -272.717726) (xy 336.77936 -272.686601)
			(xy 336.746725 -272.649764) (xy 336.720422 -272.608168) (xy 336.701131 -272.562892) (xy 336.689354 -272.515108)
			(xy 336.685394 -272.466054) (xy 336.356452 -272.466054) (xy 336.355957 -272.490661) (xy 336.348062 -272.539238)
			(xy 336.332478 -272.585919) (xy 336.309607 -272.629496) (xy 336.280042 -272.66884) (xy 336.244549 -272.702932)
			(xy 336.204046 -272.730888) (xy 336.159584 -272.751986) (xy 336.112313 -272.765678) (xy 336.063458 -272.77161)
			(xy 336.014283 -272.769629) (xy 335.966064 -272.759785) (xy 335.920048 -272.742333) (xy 335.877427 -272.717726)
			(xy 335.839306 -272.686601) (xy 335.806671 -272.649764) (xy 335.780368 -272.608168) (xy 335.761077 -272.562892)
			(xy 335.7493 -272.515108) (xy 335.74534 -272.466054) (xy 335.417002 -272.466054) (xy 335.417006 -272.4661)
			(xy 335.412834 -272.516452) (xy 335.40043 -272.56543) (xy 335.380135 -272.611698) (xy 335.3525 -272.653995)
			(xy 335.318281 -272.691166) (xy 335.278409 -272.722198) (xy 335.233974 -272.746244) (xy 335.186187 -272.762647)
			(xy 335.136352 -272.770962) (xy 335.11109 -272.771362) (xy 335.110582 -272.771362) (xy 335.097433 -272.771212)
			(xy 335.071234 -272.76892) (xy 335.058258 -272.76679) (xy 335.054448 -272.766282) (xy 335.04378 -272.76933)
			(xy 335.038889 -272.770861) (xy 335.029799 -272.775592) (xy 335.025746 -272.778728) (xy 334.967072 -272.82902)
			(xy 334.959457 -272.836587) (xy 334.950667 -272.856147) (xy 334.950054 -272.866866) (xy 334.950054 -273.157442)
			(xy 334.952848 -273.165824) (xy 334.961677 -273.192527) (xy 334.971253 -273.247943) (xy 334.971898 -273.27606)
			(xy 335.275186 -273.27606) (xy 335.279146 -273.227006) (xy 335.290923 -273.179222) (xy 335.310214 -273.133946)
			(xy 335.336517 -273.09235) (xy 335.369152 -273.055513) (xy 335.407273 -273.024388) (xy 335.449894 -272.999781)
			(xy 335.49591 -272.982329) (xy 335.544129 -272.972485) (xy 335.593304 -272.970504) (xy 335.642159 -272.976436)
			(xy 335.68943 -272.990128) (xy 335.733892 -273.011226) (xy 335.774395 -273.039182) (xy 335.809888 -273.073274)
			(xy 335.839453 -273.112618) (xy 335.862324 -273.156195) (xy 335.877908 -273.202876) (xy 335.885803 -273.251453)
			(xy 335.886298 -273.27606) (xy 336.21524 -273.27606) (xy 336.2192 -273.227006) (xy 336.230977 -273.179222)
			(xy 336.250268 -273.133946) (xy 336.276571 -273.09235) (xy 336.309206 -273.055513) (xy 336.347327 -273.024388)
			(xy 336.389948 -272.999781) (xy 336.435964 -272.982329) (xy 336.484183 -272.972485) (xy 336.533358 -272.970504)
			(xy 336.582213 -272.976436) (xy 336.629484 -272.990128) (xy 336.673946 -273.011226) (xy 336.714449 -273.039182)
			(xy 336.749942 -273.073274) (xy 336.779507 -273.112618) (xy 336.802378 -273.156195) (xy 336.817962 -273.202876)
			(xy 336.825857 -273.251453) (xy 336.826352 -273.27606) (xy 337.155294 -273.27606) (xy 337.159254 -273.227006)
			(xy 337.171031 -273.179222) (xy 337.190322 -273.133946) (xy 337.216625 -273.09235) (xy 337.24926 -273.055513)
			(xy 337.287381 -273.024388) (xy 337.330002 -272.999781) (xy 337.376018 -272.982329) (xy 337.424237 -272.972485)
			(xy 337.473412 -272.970504) (xy 337.522267 -272.976436) (xy 337.569538 -272.990128) (xy 337.614 -273.011226)
			(xy 337.654503 -273.039182) (xy 337.689996 -273.073274) (xy 337.719561 -273.112618) (xy 337.742432 -273.156195)
			(xy 337.758016 -273.202876) (xy 337.765911 -273.251453) (xy 337.766406 -273.27606) (xy 338.095348 -273.27606)
			(xy 338.099308 -273.227006) (xy 338.111085 -273.179222) (xy 338.130376 -273.133946) (xy 338.156679 -273.09235)
			(xy 338.189314 -273.055513) (xy 338.227435 -273.024388) (xy 338.270056 -272.999781) (xy 338.316072 -272.982329)
			(xy 338.364291 -272.972485) (xy 338.413466 -272.970504) (xy 338.462321 -272.976436) (xy 338.509592 -272.990128)
			(xy 338.554054 -273.011226) (xy 338.594557 -273.039182) (xy 338.63005 -273.073274) (xy 338.659615 -273.112618)
			(xy 338.682486 -273.156195) (xy 338.69807 -273.202876) (xy 338.705965 -273.251453) (xy 338.70646 -273.27606)
			(xy 339.024971 -273.27606) (xy 339.029066 -273.225332) (xy 339.041245 -273.175918) (xy 339.061193 -273.129098)
			(xy 339.088394 -273.086084) (xy 339.122142 -273.04799) (xy 339.161564 -273.015803) (xy 339.205638 -272.990357)
			(xy 339.253224 -272.97231) (xy 339.303088 -272.96213) (xy 339.35394 -272.960081) (xy 339.404461 -272.966215)
			(xy 339.453345 -272.980375) (xy 339.499324 -273.002192) (xy 339.541208 -273.031102) (xy 339.577912 -273.066357)
			(xy 339.608485 -273.107043) (xy 339.632136 -273.152106) (xy 339.648252 -273.20038) (xy 339.656416 -273.250614)
			(xy 339.656928 -273.27606) (xy 339.964771 -273.27606) (xy 339.968866 -273.225332) (xy 339.981045 -273.175918)
			(xy 340.000993 -273.129098) (xy 340.028194 -273.086084) (xy 340.061942 -273.04799) (xy 340.101364 -273.015803)
			(xy 340.145438 -272.990357) (xy 340.193024 -272.97231) (xy 340.242888 -272.96213) (xy 340.29374 -272.960081)
			(xy 340.344261 -272.966215) (xy 340.393145 -272.980375) (xy 340.439124 -273.002192) (xy 340.481008 -273.031102)
			(xy 340.517712 -273.066357) (xy 340.548285 -273.107043) (xy 340.571936 -273.152106) (xy 340.588052 -273.20038)
			(xy 340.596216 -273.250614) (xy 340.596728 -273.27606) (xy 341.844879 -273.27606) (xy 341.848974 -273.225332)
			(xy 341.861153 -273.175918) (xy 341.881101 -273.129098) (xy 341.908302 -273.086084) (xy 341.94205 -273.04799)
			(xy 341.981472 -273.015803) (xy 342.025546 -272.990357) (xy 342.073132 -272.97231) (xy 342.122996 -272.96213)
			(xy 342.173848 -272.960081) (xy 342.224369 -272.966215) (xy 342.273253 -272.980375) (xy 342.319232 -273.002192)
			(xy 342.361116 -273.031102) (xy 342.39782 -273.066357) (xy 342.428393 -273.107043) (xy 342.452044 -273.152106)
			(xy 342.46816 -273.20038) (xy 342.476324 -273.250614) (xy 342.476836 -273.27606) (xy 342.795364 -273.27606)
			(xy 342.799324 -273.227006) (xy 342.811101 -273.179222) (xy 342.830392 -273.133946) (xy 342.856695 -273.09235)
			(xy 342.88933 -273.055513) (xy 342.927451 -273.024388) (xy 342.970072 -272.999781) (xy 343.016088 -272.982329)
			(xy 343.064307 -272.972485) (xy 343.113482 -272.970504) (xy 343.162337 -272.976436) (xy 343.209608 -272.990128)
			(xy 343.25407 -273.011226) (xy 343.294573 -273.039182) (xy 343.330066 -273.073274) (xy 343.359631 -273.112618)
			(xy 343.382502 -273.156195) (xy 343.398086 -273.202876) (xy 343.405981 -273.251453) (xy 343.406476 -273.27606)
			(xy 343.724987 -273.27606) (xy 343.729082 -273.225332) (xy 343.741261 -273.175918) (xy 343.761209 -273.129098)
			(xy 343.78841 -273.086084) (xy 343.822158 -273.04799) (xy 343.86158 -273.015803) (xy 343.905654 -272.990357)
			(xy 343.95324 -272.97231) (xy 344.003104 -272.96213) (xy 344.053956 -272.960081) (xy 344.104477 -272.966215)
			(xy 344.153361 -272.980375) (xy 344.19934 -273.002192) (xy 344.241224 -273.031102) (xy 344.277928 -273.066357)
			(xy 344.308501 -273.107043) (xy 344.332152 -273.152106) (xy 344.348268 -273.20038) (xy 344.356432 -273.250614)
			(xy 344.356944 -273.27606) (xy 344.356432 -273.301506) (xy 344.348268 -273.35174) (xy 344.332152 -273.400014)
			(xy 344.308501 -273.445077) (xy 344.277928 -273.485763) (xy 344.241224 -273.521018) (xy 344.19934 -273.549928)
			(xy 344.153361 -273.571745) (xy 344.104477 -273.585905) (xy 344.053956 -273.592039) (xy 344.003104 -273.58999)
			(xy 343.95324 -273.57981) (xy 343.905654 -273.561763) (xy 343.86158 -273.536317) (xy 343.822158 -273.50413)
			(xy 343.78841 -273.466036) (xy 343.761209 -273.423022) (xy 343.741261 -273.376202) (xy 343.729082 -273.326788)
			(xy 343.724987 -273.27606) (xy 343.406476 -273.27606) (xy 343.405981 -273.300667) (xy 343.398086 -273.349244)
			(xy 343.382502 -273.395925) (xy 343.359631 -273.439502) (xy 343.330066 -273.478846) (xy 343.294573 -273.512938)
			(xy 343.25407 -273.540894) (xy 343.209608 -273.561992) (xy 343.162337 -273.575684) (xy 343.113482 -273.581616)
			(xy 343.064307 -273.579635) (xy 343.016088 -273.569791) (xy 342.970072 -273.552339) (xy 342.927451 -273.527732)
			(xy 342.88933 -273.496607) (xy 342.856695 -273.45977) (xy 342.830392 -273.418174) (xy 342.811101 -273.372898)
			(xy 342.799324 -273.325114) (xy 342.795364 -273.27606) (xy 342.476836 -273.27606) (xy 342.476324 -273.301506)
			(xy 342.46816 -273.35174) (xy 342.452044 -273.400014) (xy 342.428393 -273.445077) (xy 342.39782 -273.485763)
			(xy 342.361116 -273.521018) (xy 342.319232 -273.549928) (xy 342.273253 -273.571745) (xy 342.224369 -273.585905)
			(xy 342.173848 -273.592039) (xy 342.122996 -273.58999) (xy 342.073132 -273.57981) (xy 342.025546 -273.561763)
			(xy 341.981472 -273.536317) (xy 341.94205 -273.50413) (xy 341.908302 -273.466036) (xy 341.881101 -273.423022)
			(xy 341.861153 -273.376202) (xy 341.848974 -273.326788) (xy 341.844879 -273.27606) (xy 340.596728 -273.27606)
			(xy 340.596216 -273.301506) (xy 340.588052 -273.35174) (xy 340.571936 -273.400014) (xy 340.548285 -273.445077)
			(xy 340.517712 -273.485763) (xy 340.481008 -273.521018) (xy 340.439124 -273.549928) (xy 340.393145 -273.571745)
			(xy 340.344261 -273.585905) (xy 340.29374 -273.592039) (xy 340.242888 -273.58999) (xy 340.193024 -273.57981)
			(xy 340.145438 -273.561763) (xy 340.101364 -273.536317) (xy 340.061942 -273.50413) (xy 340.028194 -273.466036)
			(xy 340.000993 -273.423022) (xy 339.981045 -273.376202) (xy 339.968866 -273.326788) (xy 339.964771 -273.27606)
			(xy 339.656928 -273.27606) (xy 339.656416 -273.301506) (xy 339.648252 -273.35174) (xy 339.632136 -273.400014)
			(xy 339.608485 -273.445077) (xy 339.577912 -273.485763) (xy 339.541208 -273.521018) (xy 339.499324 -273.549928)
			(xy 339.453345 -273.571745) (xy 339.404461 -273.585905) (xy 339.35394 -273.592039) (xy 339.303088 -273.58999)
			(xy 339.253224 -273.57981) (xy 339.205638 -273.561763) (xy 339.161564 -273.536317) (xy 339.122142 -273.50413)
			(xy 339.088394 -273.466036) (xy 339.061193 -273.423022) (xy 339.041245 -273.376202) (xy 339.029066 -273.326788)
			(xy 339.024971 -273.27606) (xy 338.70646 -273.27606) (xy 338.705965 -273.300667) (xy 338.69807 -273.349244)
			(xy 338.682486 -273.395925) (xy 338.659615 -273.439502) (xy 338.63005 -273.478846) (xy 338.594557 -273.512938)
			(xy 338.554054 -273.540894) (xy 338.509592 -273.561992) (xy 338.462321 -273.575684) (xy 338.413466 -273.581616)
			(xy 338.364291 -273.579635) (xy 338.316072 -273.569791) (xy 338.270056 -273.552339) (xy 338.227435 -273.527732)
			(xy 338.189314 -273.496607) (xy 338.156679 -273.45977) (xy 338.130376 -273.418174) (xy 338.111085 -273.372898)
			(xy 338.099308 -273.325114) (xy 338.095348 -273.27606) (xy 337.766406 -273.27606) (xy 337.765911 -273.300667)
			(xy 337.758016 -273.349244) (xy 337.742432 -273.395925) (xy 337.719561 -273.439502) (xy 337.689996 -273.478846)
			(xy 337.654503 -273.512938) (xy 337.614 -273.540894) (xy 337.569538 -273.561992) (xy 337.522267 -273.575684)
			(xy 337.473412 -273.581616) (xy 337.424237 -273.579635) (xy 337.376018 -273.569791) (xy 337.330002 -273.552339)
			(xy 337.287381 -273.527732) (xy 337.24926 -273.496607) (xy 337.216625 -273.45977) (xy 337.190322 -273.418174)
			(xy 337.171031 -273.372898) (xy 337.159254 -273.325114) (xy 337.155294 -273.27606) (xy 336.826352 -273.27606)
			(xy 336.825857 -273.300667) (xy 336.817962 -273.349244) (xy 336.802378 -273.395925) (xy 336.779507 -273.439502)
			(xy 336.749942 -273.478846) (xy 336.714449 -273.512938) (xy 336.673946 -273.540894) (xy 336.629484 -273.561992)
			(xy 336.582213 -273.575684) (xy 336.533358 -273.581616) (xy 336.484183 -273.579635) (xy 336.435964 -273.569791)
			(xy 336.389948 -273.552339) (xy 336.347327 -273.527732) (xy 336.309206 -273.496607) (xy 336.276571 -273.45977)
			(xy 336.250268 -273.418174) (xy 336.230977 -273.372898) (xy 336.2192 -273.325114) (xy 336.21524 -273.27606)
			(xy 335.886298 -273.27606) (xy 335.885803 -273.300667) (xy 335.877908 -273.349244) (xy 335.862324 -273.395925)
			(xy 335.839453 -273.439502) (xy 335.809888 -273.478846) (xy 335.774395 -273.512938) (xy 335.733892 -273.540894)
			(xy 335.68943 -273.561992) (xy 335.642159 -273.575684) (xy 335.593304 -273.581616) (xy 335.544129 -273.579635)
			(xy 335.49591 -273.569791) (xy 335.449894 -273.552339) (xy 335.407273 -273.527732) (xy 335.369152 -273.496607)
			(xy 335.336517 -273.45977) (xy 335.310214 -273.418174) (xy 335.290923 -273.372898) (xy 335.279146 -273.325114)
			(xy 335.275186 -273.27606) (xy 334.971898 -273.27606) (xy 334.971312 -273.304183) (xy 334.961728 -273.359606)
			(xy 334.952848 -273.386296) (xy 334.950054 -273.394678) (xy 334.950054 -273.684746) (xy 334.950054 -273.687286)
			(xy 334.95096 -273.696955) (xy 334.959055 -273.714591) (xy 334.965802 -273.721576) (xy 335.024476 -273.772122)
			(xy 335.028711 -273.775593) (xy 335.038322 -273.780832) (xy 335.043526 -273.782536) (xy 335.054194 -273.785584)
			(xy 335.065116 -273.78406) (xy 335.076354 -273.782504) (xy 335.098983 -273.780849) (xy 335.110328 -273.780758)
			(xy 335.11109 -273.780758) (xy 335.136351 -273.78125) (xy 335.186184 -273.789564) (xy 335.233969 -273.805967)
			(xy 335.278403 -273.830012) (xy 335.318272 -273.861043) (xy 335.352491 -273.898213) (xy 335.380124 -273.940508)
			(xy 335.400419 -273.986774) (xy 335.412822 -274.03575) (xy 335.416991 -274.086066) (xy 335.74534 -274.086066)
			(xy 335.7493 -274.037012) (xy 335.761077 -273.989228) (xy 335.780368 -273.943952) (xy 335.806671 -273.902356)
			(xy 335.839306 -273.865519) (xy 335.877427 -273.834394) (xy 335.920048 -273.809787) (xy 335.966064 -273.792335)
			(xy 336.014283 -273.782491) (xy 336.063458 -273.78051) (xy 336.112313 -273.786442) (xy 336.159584 -273.800134)
			(xy 336.204046 -273.821232) (xy 336.244549 -273.849188) (xy 336.280042 -273.88328) (xy 336.309607 -273.922624)
			(xy 336.332478 -273.966201) (xy 336.348062 -274.012882) (xy 336.355957 -274.061459) (xy 336.356452 -274.086066)
			(xy 336.685394 -274.086066) (xy 336.689354 -274.037012) (xy 336.701131 -273.989228) (xy 336.720422 -273.943952)
			(xy 336.746725 -273.902356) (xy 336.77936 -273.865519) (xy 336.817481 -273.834394) (xy 336.860102 -273.809787)
			(xy 336.906118 -273.792335) (xy 336.954337 -273.782491) (xy 337.003512 -273.78051) (xy 337.052367 -273.786442)
			(xy 337.099638 -273.800134) (xy 337.1441 -273.821232) (xy 337.184603 -273.849188) (xy 337.220096 -273.88328)
			(xy 337.249661 -273.922624) (xy 337.272532 -273.966201) (xy 337.288116 -274.012882) (xy 337.296011 -274.061459)
			(xy 337.296506 -274.086066) (xy 337.625194 -274.086066) (xy 337.629154 -274.037012) (xy 337.640931 -273.989228)
			(xy 337.660222 -273.943952) (xy 337.686525 -273.902356) (xy 337.71916 -273.865519) (xy 337.757281 -273.834394)
			(xy 337.799902 -273.809787) (xy 337.845918 -273.792335) (xy 337.894137 -273.782491) (xy 337.943312 -273.78051)
			(xy 337.992167 -273.786442) (xy 338.039438 -273.800134) (xy 338.0839 -273.821232) (xy 338.124403 -273.849188)
			(xy 338.159896 -273.88328) (xy 338.189461 -273.922624) (xy 338.212332 -273.966201) (xy 338.227916 -274.012882)
			(xy 338.235811 -274.061459) (xy 338.236306 -274.086066) (xy 338.554817 -274.086066) (xy 338.558912 -274.035338)
			(xy 338.571091 -273.985924) (xy 338.591039 -273.939104) (xy 338.61824 -273.89609) (xy 338.651988 -273.857996)
			(xy 338.69141 -273.825809) (xy 338.735484 -273.800363) (xy 338.78307 -273.782316) (xy 338.832934 -273.772136)
			(xy 338.883786 -273.770087) (xy 338.934307 -273.776221) (xy 338.983191 -273.790381) (xy 339.02917 -273.812198)
			(xy 339.071054 -273.841108) (xy 339.107758 -273.876363) (xy 339.138331 -273.917049) (xy 339.161982 -273.962112)
			(xy 339.178098 -274.010386) (xy 339.186262 -274.06062) (xy 339.186774 -274.086066) (xy 339.505302 -274.086066)
			(xy 339.509262 -274.037012) (xy 339.521039 -273.989228) (xy 339.54033 -273.943952) (xy 339.566633 -273.902356)
			(xy 339.599268 -273.865519) (xy 339.637389 -273.834394) (xy 339.68001 -273.809787) (xy 339.726026 -273.792335)
			(xy 339.774245 -273.782491) (xy 339.82342 -273.78051) (xy 339.872275 -273.786442) (xy 339.919546 -273.800134)
			(xy 339.964008 -273.821232) (xy 340.004511 -273.849188) (xy 340.040004 -273.88328) (xy 340.069569 -273.922624)
			(xy 340.09244 -273.966201) (xy 340.108024 -274.012882) (xy 340.115919 -274.061459) (xy 340.116414 -274.086066)
			(xy 340.434925 -274.086066) (xy 340.43902 -274.035338) (xy 340.451199 -273.985924) (xy 340.471147 -273.939104)
			(xy 340.498348 -273.89609) (xy 340.532096 -273.857996) (xy 340.571518 -273.825809) (xy 340.615592 -273.800363)
			(xy 340.663178 -273.782316) (xy 340.713042 -273.772136) (xy 340.763894 -273.770087) (xy 340.814415 -273.776221)
			(xy 340.863299 -273.790381) (xy 340.909278 -273.812198) (xy 340.951162 -273.841108) (xy 340.987866 -273.876363)
			(xy 341.018439 -273.917049) (xy 341.04209 -273.962112) (xy 341.058206 -274.010386) (xy 341.06637 -274.06062)
			(xy 341.066882 -274.086066) (xy 341.38541 -274.086066) (xy 341.38937 -274.037012) (xy 341.401147 -273.989228)
			(xy 341.420438 -273.943952) (xy 341.446741 -273.902356) (xy 341.479376 -273.865519) (xy 341.517497 -273.834394)
			(xy 341.560118 -273.809787) (xy 341.606134 -273.792335) (xy 341.654353 -273.782491) (xy 341.703528 -273.78051)
			(xy 341.752383 -273.786442) (xy 341.799654 -273.800134) (xy 341.844116 -273.821232) (xy 341.884619 -273.849188)
			(xy 341.920112 -273.88328) (xy 341.949677 -273.922624) (xy 341.972548 -273.966201) (xy 341.988132 -274.012882)
			(xy 341.996027 -274.061459) (xy 341.996522 -274.086066) (xy 342.314779 -274.086066) (xy 342.318874 -274.035338)
			(xy 342.331053 -273.985924) (xy 342.351001 -273.939104) (xy 342.378202 -273.89609) (xy 342.41195 -273.857996)
			(xy 342.451372 -273.825809) (xy 342.495446 -273.800363) (xy 342.543032 -273.782316) (xy 342.592896 -273.772136)
			(xy 342.643748 -273.770087) (xy 342.694269 -273.776221) (xy 342.743153 -273.790381) (xy 342.789132 -273.812198)
			(xy 342.831016 -273.841108) (xy 342.86772 -273.876363) (xy 342.898293 -273.917049) (xy 342.921944 -273.962112)
			(xy 342.93806 -274.010386) (xy 342.946224 -274.06062) (xy 342.946736 -274.086066) (xy 343.254833 -274.086066)
			(xy 343.258928 -274.035338) (xy 343.271107 -273.985924) (xy 343.291055 -273.939104) (xy 343.318256 -273.89609)
			(xy 343.352004 -273.857996) (xy 343.391426 -273.825809) (xy 343.4355 -273.800363) (xy 343.483086 -273.782316)
			(xy 343.53295 -273.772136) (xy 343.583802 -273.770087) (xy 343.634323 -273.776221) (xy 343.683207 -273.790381)
			(xy 343.729186 -273.812198) (xy 343.77107 -273.841108) (xy 343.807774 -273.876363) (xy 343.838347 -273.917049)
			(xy 343.861998 -273.962112) (xy 343.878114 -274.010386) (xy 343.886278 -274.06062) (xy 343.88679 -274.086066)
			(xy 343.886278 -274.111512) (xy 343.878114 -274.161746) (xy 343.861998 -274.21002) (xy 343.838347 -274.255083)
			(xy 343.807774 -274.295769) (xy 343.77107 -274.331024) (xy 343.729186 -274.359934) (xy 343.683207 -274.381751)
			(xy 343.634323 -274.395911) (xy 343.583802 -274.402045) (xy 343.53295 -274.399996) (xy 343.483086 -274.389816)
			(xy 343.4355 -274.371769) (xy 343.391426 -274.346323) (xy 343.352004 -274.314136) (xy 343.318256 -274.276042)
			(xy 343.291055 -274.233028) (xy 343.271107 -274.186208) (xy 343.258928 -274.136794) (xy 343.254833 -274.086066)
			(xy 342.946736 -274.086066) (xy 342.946224 -274.111512) (xy 342.93806 -274.161746) (xy 342.921944 -274.21002)
			(xy 342.898293 -274.255083) (xy 342.86772 -274.295769) (xy 342.831016 -274.331024) (xy 342.789132 -274.359934)
			(xy 342.743153 -274.381751) (xy 342.694269 -274.395911) (xy 342.643748 -274.402045) (xy 342.592896 -274.399996)
			(xy 342.543032 -274.389816) (xy 342.495446 -274.371769) (xy 342.451372 -274.346323) (xy 342.41195 -274.314136)
			(xy 342.378202 -274.276042) (xy 342.351001 -274.233028) (xy 342.331053 -274.186208) (xy 342.318874 -274.136794)
			(xy 342.314779 -274.086066) (xy 341.996522 -274.086066) (xy 341.996027 -274.110673) (xy 341.988132 -274.15925)
			(xy 341.972548 -274.205931) (xy 341.949677 -274.249508) (xy 341.920112 -274.288852) (xy 341.884619 -274.322944)
			(xy 341.844116 -274.3509) (xy 341.799654 -274.371998) (xy 341.752383 -274.38569) (xy 341.703528 -274.391622)
			(xy 341.654353 -274.389641) (xy 341.606134 -274.379797) (xy 341.560118 -274.362345) (xy 341.517497 -274.337738)
			(xy 341.479376 -274.306613) (xy 341.446741 -274.269776) (xy 341.420438 -274.22818) (xy 341.401147 -274.182904)
			(xy 341.38937 -274.13512) (xy 341.38541 -274.086066) (xy 341.066882 -274.086066) (xy 341.06637 -274.111512)
			(xy 341.058206 -274.161746) (xy 341.04209 -274.21002) (xy 341.018439 -274.255083) (xy 340.987866 -274.295769)
			(xy 340.951162 -274.331024) (xy 340.909278 -274.359934) (xy 340.863299 -274.381751) (xy 340.814415 -274.395911)
			(xy 340.763894 -274.402045) (xy 340.713042 -274.399996) (xy 340.663178 -274.389816) (xy 340.615592 -274.371769)
			(xy 340.571518 -274.346323) (xy 340.532096 -274.314136) (xy 340.498348 -274.276042) (xy 340.471147 -274.233028)
			(xy 340.451199 -274.186208) (xy 340.43902 -274.136794) (xy 340.434925 -274.086066) (xy 340.116414 -274.086066)
			(xy 340.115919 -274.110673) (xy 340.108024 -274.15925) (xy 340.09244 -274.205931) (xy 340.069569 -274.249508)
			(xy 340.040004 -274.288852) (xy 340.004511 -274.322944) (xy 339.964008 -274.3509) (xy 339.919546 -274.371998)
			(xy 339.872275 -274.38569) (xy 339.82342 -274.391622) (xy 339.774245 -274.389641) (xy 339.726026 -274.379797)
			(xy 339.68001 -274.362345) (xy 339.637389 -274.337738) (xy 339.599268 -274.306613) (xy 339.566633 -274.269776)
			(xy 339.54033 -274.22818) (xy 339.521039 -274.182904) (xy 339.509262 -274.13512) (xy 339.505302 -274.086066)
			(xy 339.186774 -274.086066) (xy 339.186262 -274.111512) (xy 339.178098 -274.161746) (xy 339.161982 -274.21002)
			(xy 339.138331 -274.255083) (xy 339.107758 -274.295769) (xy 339.071054 -274.331024) (xy 339.02917 -274.359934)
			(xy 338.983191 -274.381751) (xy 338.934307 -274.395911) (xy 338.883786 -274.402045) (xy 338.832934 -274.399996)
			(xy 338.78307 -274.389816) (xy 338.735484 -274.371769) (xy 338.69141 -274.346323) (xy 338.651988 -274.314136)
			(xy 338.61824 -274.276042) (xy 338.591039 -274.233028) (xy 338.571091 -274.186208) (xy 338.558912 -274.136794)
			(xy 338.554817 -274.086066) (xy 338.236306 -274.086066) (xy 338.235811 -274.110673) (xy 338.227916 -274.15925)
			(xy 338.212332 -274.205931) (xy 338.189461 -274.249508) (xy 338.159896 -274.288852) (xy 338.124403 -274.322944)
			(xy 338.0839 -274.3509) (xy 338.039438 -274.371998) (xy 337.992167 -274.38569) (xy 337.943312 -274.391622)
			(xy 337.894137 -274.389641) (xy 337.845918 -274.379797) (xy 337.799902 -274.362345) (xy 337.757281 -274.337738)
			(xy 337.71916 -274.306613) (xy 337.686525 -274.269776) (xy 337.660222 -274.22818) (xy 337.640931 -274.182904)
			(xy 337.629154 -274.13512) (xy 337.625194 -274.086066) (xy 337.296506 -274.086066) (xy 337.296011 -274.110673)
			(xy 337.288116 -274.15925) (xy 337.272532 -274.205931) (xy 337.249661 -274.249508) (xy 337.220096 -274.288852)
			(xy 337.184603 -274.322944) (xy 337.1441 -274.3509) (xy 337.099638 -274.371998) (xy 337.052367 -274.38569)
			(xy 337.003512 -274.391622) (xy 336.954337 -274.389641) (xy 336.906118 -274.379797) (xy 336.860102 -274.362345)
			(xy 336.817481 -274.337738) (xy 336.77936 -274.306613) (xy 336.746725 -274.269776) (xy 336.720422 -274.22818)
			(xy 336.701131 -274.182904) (xy 336.689354 -274.13512) (xy 336.685394 -274.086066) (xy 336.356452 -274.086066)
			(xy 336.355957 -274.110673) (xy 336.348062 -274.15925) (xy 336.332478 -274.205931) (xy 336.309607 -274.249508)
			(xy 336.280042 -274.288852) (xy 336.244549 -274.322944) (xy 336.204046 -274.3509) (xy 336.159584 -274.371998)
			(xy 336.112313 -274.38569) (xy 336.063458 -274.391622) (xy 336.014283 -274.389641) (xy 335.966064 -274.379797)
			(xy 335.920048 -274.362345) (xy 335.877427 -274.337738) (xy 335.839306 -274.306613) (xy 335.806671 -274.269776)
			(xy 335.780368 -274.22818) (xy 335.761077 -274.182904) (xy 335.7493 -274.13512) (xy 335.74534 -274.086066)
			(xy 335.416991 -274.086066) (xy 335.416994 -274.0861) (xy 335.412822 -274.13645) (xy 335.400419 -274.185426)
			(xy 335.380124 -274.231692) (xy 335.352491 -274.273987) (xy 335.318272 -274.311157) (xy 335.278403 -274.342188)
			(xy 335.233969 -274.366233) (xy 335.186184 -274.382636) (xy 335.136351 -274.39095) (xy 335.11109 -274.391374)
			(xy 335.110582 -274.391374) (xy 335.097433 -274.391224) (xy 335.071234 -274.388932) (xy 335.058258 -274.386802)
			(xy 335.054448 -274.386294) (xy 335.04378 -274.389342) (xy 335.038889 -274.390874) (xy 335.0298 -274.395605)
			(xy 335.025746 -274.39874) (xy 334.967072 -274.449032) (xy 334.959458 -274.4566) (xy 334.950674 -274.47616)
			(xy 334.950054 -274.486878) (xy 334.950054 -274.896072) (xy 335.275186 -274.896072) (xy 335.279146 -274.847018)
			(xy 335.290923 -274.799234) (xy 335.310214 -274.753958) (xy 335.336517 -274.712362) (xy 335.369152 -274.675525)
			(xy 335.407273 -274.6444) (xy 335.449894 -274.619793) (xy 335.49591 -274.602341) (xy 335.544129 -274.592497)
			(xy 335.593304 -274.590516) (xy 335.642159 -274.596448) (xy 335.68943 -274.61014) (xy 335.733892 -274.631238)
			(xy 335.774395 -274.659194) (xy 335.809888 -274.693286) (xy 335.839453 -274.73263) (xy 335.862324 -274.776207)
			(xy 335.877908 -274.822888) (xy 335.885803 -274.871465) (xy 335.886298 -274.896072) (xy 336.21524 -274.896072)
			(xy 336.2192 -274.847018) (xy 336.230977 -274.799234) (xy 336.250268 -274.753958) (xy 336.276571 -274.712362)
			(xy 336.309206 -274.675525) (xy 336.347327 -274.6444) (xy 336.389948 -274.619793) (xy 336.435964 -274.602341)
			(xy 336.484183 -274.592497) (xy 336.533358 -274.590516) (xy 336.582213 -274.596448) (xy 336.629484 -274.61014)
			(xy 336.673946 -274.631238) (xy 336.714449 -274.659194) (xy 336.749942 -274.693286) (xy 336.779507 -274.73263)
			(xy 336.802378 -274.776207) (xy 336.817962 -274.822888) (xy 336.825857 -274.871465) (xy 336.826352 -274.896072)
			(xy 337.155294 -274.896072) (xy 337.159254 -274.847018) (xy 337.171031 -274.799234) (xy 337.190322 -274.753958)
			(xy 337.216625 -274.712362) (xy 337.24926 -274.675525) (xy 337.287381 -274.6444) (xy 337.330002 -274.619793)
			(xy 337.376018 -274.602341) (xy 337.424237 -274.592497) (xy 337.473412 -274.590516) (xy 337.522267 -274.596448)
			(xy 337.569538 -274.61014) (xy 337.614 -274.631238) (xy 337.654503 -274.659194) (xy 337.689996 -274.693286)
			(xy 337.719561 -274.73263) (xy 337.742432 -274.776207) (xy 337.758016 -274.822888) (xy 337.765911 -274.871465)
			(xy 337.766406 -274.896072) (xy 338.095348 -274.896072) (xy 338.099308 -274.847018) (xy 338.111085 -274.799234)
			(xy 338.130376 -274.753958) (xy 338.156679 -274.712362) (xy 338.189314 -274.675525) (xy 338.227435 -274.6444)
			(xy 338.270056 -274.619793) (xy 338.316072 -274.602341) (xy 338.364291 -274.592497) (xy 338.413466 -274.590516)
			(xy 338.462321 -274.596448) (xy 338.509592 -274.61014) (xy 338.554054 -274.631238) (xy 338.594557 -274.659194)
			(xy 338.63005 -274.693286) (xy 338.659615 -274.73263) (xy 338.682486 -274.776207) (xy 338.69807 -274.822888)
			(xy 338.705965 -274.871465) (xy 338.70646 -274.896072) (xy 339.024971 -274.896072) (xy 339.029066 -274.845344)
			(xy 339.041245 -274.79593) (xy 339.061193 -274.74911) (xy 339.088394 -274.706096) (xy 339.122142 -274.668002)
			(xy 339.161564 -274.635815) (xy 339.205638 -274.610369) (xy 339.253224 -274.592322) (xy 339.303088 -274.582142)
			(xy 339.35394 -274.580093) (xy 339.404461 -274.586227) (xy 339.453345 -274.600387) (xy 339.499324 -274.622204)
			(xy 339.541208 -274.651114) (xy 339.577912 -274.686369) (xy 339.608485 -274.727055) (xy 339.632136 -274.772118)
			(xy 339.648252 -274.820392) (xy 339.656416 -274.870626) (xy 339.656928 -274.896072) (xy 339.964771 -274.896072)
			(xy 339.968866 -274.845344) (xy 339.981045 -274.79593) (xy 340.000993 -274.74911) (xy 340.028194 -274.706096)
			(xy 340.061942 -274.668002) (xy 340.101364 -274.635815) (xy 340.145438 -274.610369) (xy 340.193024 -274.592322)
			(xy 340.242888 -274.582142) (xy 340.29374 -274.580093) (xy 340.344261 -274.586227) (xy 340.393145 -274.600387)
			(xy 340.439124 -274.622204) (xy 340.481008 -274.651114) (xy 340.517712 -274.686369) (xy 340.548285 -274.727055)
			(xy 340.571936 -274.772118) (xy 340.588052 -274.820392) (xy 340.596216 -274.870626) (xy 340.596728 -274.896072)
			(xy 340.915256 -274.896072) (xy 340.919216 -274.847018) (xy 340.930993 -274.799234) (xy 340.950284 -274.753958)
			(xy 340.976587 -274.712362) (xy 341.009222 -274.675525) (xy 341.047343 -274.6444) (xy 341.089964 -274.619793)
			(xy 341.13598 -274.602341) (xy 341.184199 -274.592497) (xy 341.233374 -274.590516) (xy 341.282229 -274.596448)
			(xy 341.3295 -274.61014) (xy 341.373962 -274.631238) (xy 341.414465 -274.659194) (xy 341.449958 -274.693286)
			(xy 341.479523 -274.73263) (xy 341.502394 -274.776207) (xy 341.517978 -274.822888) (xy 341.525873 -274.871465)
			(xy 341.526368 -274.896072) (xy 341.844879 -274.896072) (xy 341.848974 -274.845344) (xy 341.861153 -274.79593)
			(xy 341.881101 -274.74911) (xy 341.908302 -274.706096) (xy 341.94205 -274.668002) (xy 341.981472 -274.635815)
			(xy 342.025546 -274.610369) (xy 342.073132 -274.592322) (xy 342.122996 -274.582142) (xy 342.173848 -274.580093)
			(xy 342.224369 -274.586227) (xy 342.273253 -274.600387) (xy 342.319232 -274.622204) (xy 342.361116 -274.651114)
			(xy 342.39782 -274.686369) (xy 342.428393 -274.727055) (xy 342.452044 -274.772118) (xy 342.46816 -274.820392)
			(xy 342.476324 -274.870626) (xy 342.476836 -274.896072) (xy 342.795364 -274.896072) (xy 342.799324 -274.847018)
			(xy 342.811101 -274.799234) (xy 342.830392 -274.753958) (xy 342.856695 -274.712362) (xy 342.88933 -274.675525)
			(xy 342.927451 -274.6444) (xy 342.970072 -274.619793) (xy 343.016088 -274.602341) (xy 343.064307 -274.592497)
			(xy 343.113482 -274.590516) (xy 343.162337 -274.596448) (xy 343.209608 -274.61014) (xy 343.25407 -274.631238)
			(xy 343.294573 -274.659194) (xy 343.330066 -274.693286) (xy 343.359631 -274.73263) (xy 343.382502 -274.776207)
			(xy 343.398086 -274.822888) (xy 343.405981 -274.871465) (xy 343.406476 -274.896072) (xy 343.724987 -274.896072)
			(xy 343.729082 -274.845344) (xy 343.741261 -274.79593) (xy 343.761209 -274.74911) (xy 343.78841 -274.706096)
			(xy 343.822158 -274.668002) (xy 343.86158 -274.635815) (xy 343.905654 -274.610369) (xy 343.95324 -274.592322)
			(xy 344.003104 -274.582142) (xy 344.053956 -274.580093) (xy 344.104477 -274.586227) (xy 344.153361 -274.600387)
			(xy 344.19934 -274.622204) (xy 344.241224 -274.651114) (xy 344.277928 -274.686369) (xy 344.308501 -274.727055)
			(xy 344.332152 -274.772118) (xy 344.348268 -274.820392) (xy 344.356432 -274.870626) (xy 344.356944 -274.896072)
			(xy 344.356432 -274.921518) (xy 344.348268 -274.971752) (xy 344.332152 -275.020026) (xy 344.308501 -275.065089)
			(xy 344.277928 -275.105775) (xy 344.241224 -275.14103) (xy 344.19934 -275.16994) (xy 344.153361 -275.191757)
			(xy 344.104477 -275.205917) (xy 344.053956 -275.212051) (xy 344.003104 -275.210002) (xy 343.95324 -275.199822)
			(xy 343.905654 -275.181775) (xy 343.86158 -275.156329) (xy 343.822158 -275.124142) (xy 343.78841 -275.086048)
			(xy 343.761209 -275.043034) (xy 343.741261 -274.996214) (xy 343.729082 -274.9468) (xy 343.724987 -274.896072)
			(xy 343.406476 -274.896072) (xy 343.405981 -274.920679) (xy 343.398086 -274.969256) (xy 343.382502 -275.015937)
			(xy 343.359631 -275.059514) (xy 343.330066 -275.098858) (xy 343.294573 -275.13295) (xy 343.25407 -275.160906)
			(xy 343.209608 -275.182004) (xy 343.162337 -275.195696) (xy 343.113482 -275.201628) (xy 343.064307 -275.199647)
			(xy 343.016088 -275.189803) (xy 342.970072 -275.172351) (xy 342.927451 -275.147744) (xy 342.88933 -275.116619)
			(xy 342.856695 -275.079782) (xy 342.830392 -275.038186) (xy 342.811101 -274.99291) (xy 342.799324 -274.945126)
			(xy 342.795364 -274.896072) (xy 342.476836 -274.896072) (xy 342.476324 -274.921518) (xy 342.46816 -274.971752)
			(xy 342.452044 -275.020026) (xy 342.428393 -275.065089) (xy 342.39782 -275.105775) (xy 342.361116 -275.14103)
			(xy 342.319232 -275.16994) (xy 342.273253 -275.191757) (xy 342.224369 -275.205917) (xy 342.173848 -275.212051)
			(xy 342.122996 -275.210002) (xy 342.073132 -275.199822) (xy 342.025546 -275.181775) (xy 341.981472 -275.156329)
			(xy 341.94205 -275.124142) (xy 341.908302 -275.086048) (xy 341.881101 -275.043034) (xy 341.861153 -274.996214)
			(xy 341.848974 -274.9468) (xy 341.844879 -274.896072) (xy 341.526368 -274.896072) (xy 341.525873 -274.920679)
			(xy 341.517978 -274.969256) (xy 341.502394 -275.015937) (xy 341.479523 -275.059514) (xy 341.449958 -275.098858)
			(xy 341.414465 -275.13295) (xy 341.373962 -275.160906) (xy 341.3295 -275.182004) (xy 341.282229 -275.195696)
			(xy 341.233374 -275.201628) (xy 341.184199 -275.199647) (xy 341.13598 -275.189803) (xy 341.089964 -275.172351)
			(xy 341.047343 -275.147744) (xy 341.009222 -275.116619) (xy 340.976587 -275.079782) (xy 340.950284 -275.038186)
			(xy 340.930993 -274.99291) (xy 340.919216 -274.945126) (xy 340.915256 -274.896072) (xy 340.596728 -274.896072)
			(xy 340.596216 -274.921518) (xy 340.588052 -274.971752) (xy 340.571936 -275.020026) (xy 340.548285 -275.065089)
			(xy 340.517712 -275.105775) (xy 340.481008 -275.14103) (xy 340.439124 -275.16994) (xy 340.393145 -275.191757)
			(xy 340.344261 -275.205917) (xy 340.29374 -275.212051) (xy 340.242888 -275.210002) (xy 340.193024 -275.199822)
			(xy 340.145438 -275.181775) (xy 340.101364 -275.156329) (xy 340.061942 -275.124142) (xy 340.028194 -275.086048)
			(xy 340.000993 -275.043034) (xy 339.981045 -274.996214) (xy 339.968866 -274.9468) (xy 339.964771 -274.896072)
			(xy 339.656928 -274.896072) (xy 339.656416 -274.921518) (xy 339.648252 -274.971752) (xy 339.632136 -275.020026)
			(xy 339.608485 -275.065089) (xy 339.577912 -275.105775) (xy 339.541208 -275.14103) (xy 339.499324 -275.16994)
			(xy 339.453345 -275.191757) (xy 339.404461 -275.205917) (xy 339.35394 -275.212051) (xy 339.303088 -275.210002)
			(xy 339.253224 -275.199822) (xy 339.205638 -275.181775) (xy 339.161564 -275.156329) (xy 339.122142 -275.124142)
			(xy 339.088394 -275.086048) (xy 339.061193 -275.043034) (xy 339.041245 -274.996214) (xy 339.029066 -274.9468)
			(xy 339.024971 -274.896072) (xy 338.70646 -274.896072) (xy 338.705965 -274.920679) (xy 338.69807 -274.969256)
			(xy 338.682486 -275.015937) (xy 338.659615 -275.059514) (xy 338.63005 -275.098858) (xy 338.594557 -275.13295)
			(xy 338.554054 -275.160906) (xy 338.509592 -275.182004) (xy 338.462321 -275.195696) (xy 338.413466 -275.201628)
			(xy 338.364291 -275.199647) (xy 338.316072 -275.189803) (xy 338.270056 -275.172351) (xy 338.227435 -275.147744)
			(xy 338.189314 -275.116619) (xy 338.156679 -275.079782) (xy 338.130376 -275.038186) (xy 338.111085 -274.99291)
			(xy 338.099308 -274.945126) (xy 338.095348 -274.896072) (xy 337.766406 -274.896072) (xy 337.765911 -274.920679)
			(xy 337.758016 -274.969256) (xy 337.742432 -275.015937) (xy 337.719561 -275.059514) (xy 337.689996 -275.098858)
			(xy 337.654503 -275.13295) (xy 337.614 -275.160906) (xy 337.569538 -275.182004) (xy 337.522267 -275.195696)
			(xy 337.473412 -275.201628) (xy 337.424237 -275.199647) (xy 337.376018 -275.189803) (xy 337.330002 -275.172351)
			(xy 337.287381 -275.147744) (xy 337.24926 -275.116619) (xy 337.216625 -275.079782) (xy 337.190322 -275.038186)
			(xy 337.171031 -274.99291) (xy 337.159254 -274.945126) (xy 337.155294 -274.896072) (xy 336.826352 -274.896072)
			(xy 336.825857 -274.920679) (xy 336.817962 -274.969256) (xy 336.802378 -275.015937) (xy 336.779507 -275.059514)
			(xy 336.749942 -275.098858) (xy 336.714449 -275.13295) (xy 336.673946 -275.160906) (xy 336.629484 -275.182004)
			(xy 336.582213 -275.195696) (xy 336.533358 -275.201628) (xy 336.484183 -275.199647) (xy 336.435964 -275.189803)
			(xy 336.389948 -275.172351) (xy 336.347327 -275.147744) (xy 336.309206 -275.116619) (xy 336.276571 -275.079782)
			(xy 336.250268 -275.038186) (xy 336.230977 -274.99291) (xy 336.2192 -274.945126) (xy 336.21524 -274.896072)
			(xy 335.886298 -274.896072) (xy 335.885803 -274.920679) (xy 335.877908 -274.969256) (xy 335.862324 -275.015937)
			(xy 335.839453 -275.059514) (xy 335.809888 -275.098858) (xy 335.774395 -275.13295) (xy 335.733892 -275.160906)
			(xy 335.68943 -275.182004) (xy 335.642159 -275.195696) (xy 335.593304 -275.201628) (xy 335.544129 -275.199647)
			(xy 335.49591 -275.189803) (xy 335.449894 -275.172351) (xy 335.407273 -275.147744) (xy 335.369152 -275.116619)
			(xy 335.336517 -275.079782) (xy 335.310214 -275.038186) (xy 335.290923 -274.99291) (xy 335.279146 -274.945126)
			(xy 335.275186 -274.896072) (xy 334.950054 -274.896072) (xy 334.950054 -275.706078) (xy 335.74534 -275.706078)
			(xy 335.7493 -275.657024) (xy 335.761077 -275.60924) (xy 335.780368 -275.563964) (xy 335.806671 -275.522368)
			(xy 335.839306 -275.485531) (xy 335.877427 -275.454406) (xy 335.920048 -275.429799) (xy 335.966064 -275.412347)
			(xy 336.014283 -275.402503) (xy 336.063458 -275.400522) (xy 336.112313 -275.406454) (xy 336.159584 -275.420146)
			(xy 336.204046 -275.441244) (xy 336.244549 -275.4692) (xy 336.280042 -275.503292) (xy 336.309607 -275.542636)
			(xy 336.332478 -275.586213) (xy 336.348062 -275.632894) (xy 336.355957 -275.681471) (xy 336.356452 -275.706078)
			(xy 336.685394 -275.706078) (xy 336.689354 -275.657024) (xy 336.701131 -275.60924) (xy 336.720422 -275.563964)
			(xy 336.746725 -275.522368) (xy 336.77936 -275.485531) (xy 336.817481 -275.454406) (xy 336.860102 -275.429799)
			(xy 336.906118 -275.412347) (xy 336.954337 -275.402503) (xy 337.003512 -275.400522) (xy 337.052367 -275.406454)
			(xy 337.099638 -275.420146) (xy 337.1441 -275.441244) (xy 337.184603 -275.4692) (xy 337.220096 -275.503292)
			(xy 337.249661 -275.542636) (xy 337.272532 -275.586213) (xy 337.288116 -275.632894) (xy 337.296011 -275.681471)
			(xy 337.296506 -275.706078) (xy 337.625194 -275.706078) (xy 337.629154 -275.657024) (xy 337.640931 -275.60924)
			(xy 337.660222 -275.563964) (xy 337.686525 -275.522368) (xy 337.71916 -275.485531) (xy 337.757281 -275.454406)
			(xy 337.799902 -275.429799) (xy 337.845918 -275.412347) (xy 337.894137 -275.402503) (xy 337.943312 -275.400522)
			(xy 337.992167 -275.406454) (xy 338.039438 -275.420146) (xy 338.0839 -275.441244) (xy 338.124403 -275.4692)
			(xy 338.159896 -275.503292) (xy 338.189461 -275.542636) (xy 338.212332 -275.586213) (xy 338.227916 -275.632894)
			(xy 338.235811 -275.681471) (xy 338.236306 -275.706078) (xy 338.554817 -275.706078) (xy 338.558912 -275.65535)
			(xy 338.571091 -275.605936) (xy 338.591039 -275.559116) (xy 338.61824 -275.516102) (xy 338.651988 -275.478008)
			(xy 338.69141 -275.445821) (xy 338.735484 -275.420375) (xy 338.78307 -275.402328) (xy 338.832934 -275.392148)
			(xy 338.883786 -275.390099) (xy 338.934307 -275.396233) (xy 338.983191 -275.410393) (xy 339.02917 -275.43221)
			(xy 339.071054 -275.46112) (xy 339.107758 -275.496375) (xy 339.138331 -275.537061) (xy 339.161982 -275.582124)
			(xy 339.178098 -275.630398) (xy 339.186262 -275.680632) (xy 339.186774 -275.706078) (xy 339.505302 -275.706078)
			(xy 339.509262 -275.657024) (xy 339.521039 -275.60924) (xy 339.54033 -275.563964) (xy 339.566633 -275.522368)
			(xy 339.599268 -275.485531) (xy 339.637389 -275.454406) (xy 339.68001 -275.429799) (xy 339.726026 -275.412347)
			(xy 339.774245 -275.402503) (xy 339.82342 -275.400522) (xy 339.872275 -275.406454) (xy 339.919546 -275.420146)
			(xy 339.964008 -275.441244) (xy 340.004511 -275.4692) (xy 340.040004 -275.503292) (xy 340.069569 -275.542636)
			(xy 340.09244 -275.586213) (xy 340.108024 -275.632894) (xy 340.115919 -275.681471) (xy 340.116414 -275.706078)
			(xy 340.434925 -275.706078) (xy 340.43902 -275.65535) (xy 340.451199 -275.605936) (xy 340.471147 -275.559116)
			(xy 340.498348 -275.516102) (xy 340.532096 -275.478008) (xy 340.571518 -275.445821) (xy 340.615592 -275.420375)
			(xy 340.663178 -275.402328) (xy 340.713042 -275.392148) (xy 340.763894 -275.390099) (xy 340.814415 -275.396233)
			(xy 340.863299 -275.410393) (xy 340.909278 -275.43221) (xy 340.951162 -275.46112) (xy 340.987866 -275.496375)
			(xy 341.018439 -275.537061) (xy 341.04209 -275.582124) (xy 341.058206 -275.630398) (xy 341.06637 -275.680632)
			(xy 341.066882 -275.706078) (xy 342.314779 -275.706078) (xy 342.318874 -275.65535) (xy 342.331053 -275.605936)
			(xy 342.351001 -275.559116) (xy 342.378202 -275.516102) (xy 342.41195 -275.478008) (xy 342.451372 -275.445821)
			(xy 342.495446 -275.420375) (xy 342.543032 -275.402328) (xy 342.592896 -275.392148) (xy 342.643748 -275.390099)
			(xy 342.694269 -275.396233) (xy 342.743153 -275.410393) (xy 342.789132 -275.43221) (xy 342.831016 -275.46112)
			(xy 342.86772 -275.496375) (xy 342.898293 -275.537061) (xy 342.921944 -275.582124) (xy 342.93806 -275.630398)
			(xy 342.946224 -275.680632) (xy 342.946736 -275.706078) (xy 343.254833 -275.706078) (xy 343.258928 -275.65535)
			(xy 343.271107 -275.605936) (xy 343.291055 -275.559116) (xy 343.318256 -275.516102) (xy 343.352004 -275.478008)
			(xy 343.391426 -275.445821) (xy 343.4355 -275.420375) (xy 343.483086 -275.402328) (xy 343.53295 -275.392148)
			(xy 343.583802 -275.390099) (xy 343.634323 -275.396233) (xy 343.683207 -275.410393) (xy 343.729186 -275.43221)
			(xy 343.77107 -275.46112) (xy 343.807774 -275.496375) (xy 343.838347 -275.537061) (xy 343.861998 -275.582124)
			(xy 343.878114 -275.630398) (xy 343.886278 -275.680632) (xy 343.88679 -275.706078) (xy 343.886278 -275.731524)
			(xy 343.878114 -275.781758) (xy 343.861998 -275.830032) (xy 343.838347 -275.875095) (xy 343.807774 -275.915781)
			(xy 343.77107 -275.951036) (xy 343.729186 -275.979946) (xy 343.683207 -276.001763) (xy 343.634323 -276.015923)
			(xy 343.583802 -276.022057) (xy 343.53295 -276.020008) (xy 343.483086 -276.009828) (xy 343.4355 -275.991781)
			(xy 343.391426 -275.966335) (xy 343.352004 -275.934148) (xy 343.318256 -275.896054) (xy 343.291055 -275.85304)
			(xy 343.271107 -275.80622) (xy 343.258928 -275.756806) (xy 343.254833 -275.706078) (xy 342.946736 -275.706078)
			(xy 342.946224 -275.731524) (xy 342.93806 -275.781758) (xy 342.921944 -275.830032) (xy 342.898293 -275.875095)
			(xy 342.86772 -275.915781) (xy 342.831016 -275.951036) (xy 342.789132 -275.979946) (xy 342.743153 -276.001763)
			(xy 342.694269 -276.015923) (xy 342.643748 -276.022057) (xy 342.592896 -276.020008) (xy 342.543032 -276.009828)
			(xy 342.495446 -275.991781) (xy 342.451372 -275.966335) (xy 342.41195 -275.934148) (xy 342.378202 -275.896054)
			(xy 342.351001 -275.85304) (xy 342.331053 -275.80622) (xy 342.318874 -275.756806) (xy 342.314779 -275.706078)
			(xy 341.066882 -275.706078) (xy 341.06637 -275.731524) (xy 341.058206 -275.781758) (xy 341.04209 -275.830032)
			(xy 341.018439 -275.875095) (xy 340.987866 -275.915781) (xy 340.951162 -275.951036) (xy 340.909278 -275.979946)
			(xy 340.863299 -276.001763) (xy 340.814415 -276.015923) (xy 340.763894 -276.022057) (xy 340.713042 -276.020008)
			(xy 340.663178 -276.009828) (xy 340.615592 -275.991781) (xy 340.571518 -275.966335) (xy 340.532096 -275.934148)
			(xy 340.498348 -275.896054) (xy 340.471147 -275.85304) (xy 340.451199 -275.80622) (xy 340.43902 -275.756806)
			(xy 340.434925 -275.706078) (xy 340.116414 -275.706078) (xy 340.115919 -275.730685) (xy 340.108024 -275.779262)
			(xy 340.09244 -275.825943) (xy 340.069569 -275.86952) (xy 340.040004 -275.908864) (xy 340.004511 -275.942956)
			(xy 339.964008 -275.970912) (xy 339.919546 -275.99201) (xy 339.872275 -276.005702) (xy 339.82342 -276.011634)
			(xy 339.774245 -276.009653) (xy 339.726026 -275.999809) (xy 339.68001 -275.982357) (xy 339.637389 -275.95775)
			(xy 339.599268 -275.926625) (xy 339.566633 -275.889788) (xy 339.54033 -275.848192) (xy 339.521039 -275.802916)
			(xy 339.509262 -275.755132) (xy 339.505302 -275.706078) (xy 339.186774 -275.706078) (xy 339.186262 -275.731524)
			(xy 339.178098 -275.781758) (xy 339.161982 -275.830032) (xy 339.138331 -275.875095) (xy 339.107758 -275.915781)
			(xy 339.071054 -275.951036) (xy 339.02917 -275.979946) (xy 338.983191 -276.001763) (xy 338.934307 -276.015923)
			(xy 338.883786 -276.022057) (xy 338.832934 -276.020008) (xy 338.78307 -276.009828) (xy 338.735484 -275.991781)
			(xy 338.69141 -275.966335) (xy 338.651988 -275.934148) (xy 338.61824 -275.896054) (xy 338.591039 -275.85304)
			(xy 338.571091 -275.80622) (xy 338.558912 -275.756806) (xy 338.554817 -275.706078) (xy 338.236306 -275.706078)
			(xy 338.235811 -275.730685) (xy 338.227916 -275.779262) (xy 338.212332 -275.825943) (xy 338.189461 -275.86952)
			(xy 338.159896 -275.908864) (xy 338.124403 -275.942956) (xy 338.0839 -275.970912) (xy 338.039438 -275.99201)
			(xy 337.992167 -276.005702) (xy 337.943312 -276.011634) (xy 337.894137 -276.009653) (xy 337.845918 -275.999809)
			(xy 337.799902 -275.982357) (xy 337.757281 -275.95775) (xy 337.71916 -275.926625) (xy 337.686525 -275.889788)
			(xy 337.660222 -275.848192) (xy 337.640931 -275.802916) (xy 337.629154 -275.755132) (xy 337.625194 -275.706078)
			(xy 337.296506 -275.706078) (xy 337.296011 -275.730685) (xy 337.288116 -275.779262) (xy 337.272532 -275.825943)
			(xy 337.249661 -275.86952) (xy 337.220096 -275.908864) (xy 337.184603 -275.942956) (xy 337.1441 -275.970912)
			(xy 337.099638 -275.99201) (xy 337.052367 -276.005702) (xy 337.003512 -276.011634) (xy 336.954337 -276.009653)
			(xy 336.906118 -275.999809) (xy 336.860102 -275.982357) (xy 336.817481 -275.95775) (xy 336.77936 -275.926625)
			(xy 336.746725 -275.889788) (xy 336.720422 -275.848192) (xy 336.701131 -275.802916) (xy 336.689354 -275.755132)
			(xy 336.685394 -275.706078) (xy 336.356452 -275.706078) (xy 336.355957 -275.730685) (xy 336.348062 -275.779262)
			(xy 336.332478 -275.825943) (xy 336.309607 -275.86952) (xy 336.280042 -275.908864) (xy 336.244549 -275.942956)
			(xy 336.204046 -275.970912) (xy 336.159584 -275.99201) (xy 336.112313 -276.005702) (xy 336.063458 -276.011634)
			(xy 336.014283 -276.009653) (xy 335.966064 -275.999809) (xy 335.920048 -275.982357) (xy 335.877427 -275.95775)
			(xy 335.839306 -275.926625) (xy 335.806671 -275.889788) (xy 335.780368 -275.848192) (xy 335.761077 -275.802916)
			(xy 335.7493 -275.755132) (xy 335.74534 -275.706078) (xy 334.950054 -275.706078) (xy 334.950054 -276.516084)
			(xy 335.275186 -276.516084) (xy 335.279146 -276.46703) (xy 335.290923 -276.419246) (xy 335.310214 -276.37397)
			(xy 335.336517 -276.332374) (xy 335.369152 -276.295537) (xy 335.407273 -276.264412) (xy 335.449894 -276.239805)
			(xy 335.49591 -276.222353) (xy 335.544129 -276.212509) (xy 335.593304 -276.210528) (xy 335.642159 -276.21646)
			(xy 335.68943 -276.230152) (xy 335.733892 -276.25125) (xy 335.774395 -276.279206) (xy 335.809888 -276.313298)
			(xy 335.839453 -276.352642) (xy 335.862324 -276.396219) (xy 335.877908 -276.4429) (xy 335.885803 -276.491477)
			(xy 335.886298 -276.516084) (xy 336.21524 -276.516084) (xy 336.2192 -276.46703) (xy 336.230977 -276.419246)
			(xy 336.250268 -276.37397) (xy 336.276571 -276.332374) (xy 336.309206 -276.295537) (xy 336.347327 -276.264412)
			(xy 336.389948 -276.239805) (xy 336.435964 -276.222353) (xy 336.484183 -276.212509) (xy 336.533358 -276.210528)
			(xy 336.582213 -276.21646) (xy 336.629484 -276.230152) (xy 336.673946 -276.25125) (xy 336.714449 -276.279206)
			(xy 336.749942 -276.313298) (xy 336.779507 -276.352642) (xy 336.802378 -276.396219) (xy 336.817962 -276.4429)
			(xy 336.825857 -276.491477) (xy 336.826352 -276.516084) (xy 337.155294 -276.516084) (xy 337.159254 -276.46703)
			(xy 337.171031 -276.419246) (xy 337.190322 -276.37397) (xy 337.216625 -276.332374) (xy 337.24926 -276.295537)
			(xy 337.287381 -276.264412) (xy 337.330002 -276.239805) (xy 337.376018 -276.222353) (xy 337.424237 -276.212509)
			(xy 337.473412 -276.210528) (xy 337.522267 -276.21646) (xy 337.569538 -276.230152) (xy 337.614 -276.25125)
			(xy 337.654503 -276.279206) (xy 337.689996 -276.313298) (xy 337.719561 -276.352642) (xy 337.742432 -276.396219)
			(xy 337.758016 -276.4429) (xy 337.765911 -276.491477) (xy 337.766406 -276.516084) (xy 338.095348 -276.516084)
			(xy 338.099308 -276.46703) (xy 338.111085 -276.419246) (xy 338.130376 -276.37397) (xy 338.156679 -276.332374)
			(xy 338.189314 -276.295537) (xy 338.227435 -276.264412) (xy 338.270056 -276.239805) (xy 338.316072 -276.222353)
			(xy 338.364291 -276.212509) (xy 338.413466 -276.210528) (xy 338.462321 -276.21646) (xy 338.509592 -276.230152)
			(xy 338.554054 -276.25125) (xy 338.594557 -276.279206) (xy 338.63005 -276.313298) (xy 338.659615 -276.352642)
			(xy 338.682486 -276.396219) (xy 338.69807 -276.4429) (xy 338.705965 -276.491477) (xy 338.70646 -276.516084)
			(xy 339.024971 -276.516084) (xy 339.029066 -276.465356) (xy 339.041245 -276.415942) (xy 339.061193 -276.369122)
			(xy 339.088394 -276.326108) (xy 339.122142 -276.288014) (xy 339.161564 -276.255827) (xy 339.205638 -276.230381)
			(xy 339.253224 -276.212334) (xy 339.303088 -276.202154) (xy 339.35394 -276.200105) (xy 339.404461 -276.206239)
			(xy 339.453345 -276.220399) (xy 339.499324 -276.242216) (xy 339.541208 -276.271126) (xy 339.577912 -276.306381)
			(xy 339.608485 -276.347067) (xy 339.632136 -276.39213) (xy 339.648252 -276.440404) (xy 339.656416 -276.490638)
			(xy 339.656928 -276.516084) (xy 339.964771 -276.516084) (xy 339.968866 -276.465356) (xy 339.981045 -276.415942)
			(xy 340.000993 -276.369122) (xy 340.028194 -276.326108) (xy 340.061942 -276.288014) (xy 340.101364 -276.255827)
			(xy 340.145438 -276.230381) (xy 340.193024 -276.212334) (xy 340.242888 -276.202154) (xy 340.29374 -276.200105)
			(xy 340.344261 -276.206239) (xy 340.393145 -276.220399) (xy 340.439124 -276.242216) (xy 340.481008 -276.271126)
			(xy 340.517712 -276.306381) (xy 340.548285 -276.347067) (xy 340.571936 -276.39213) (xy 340.588052 -276.440404)
			(xy 340.596216 -276.490638) (xy 340.596728 -276.516084) (xy 340.915256 -276.516084) (xy 340.919216 -276.46703)
			(xy 340.930993 -276.419246) (xy 340.950284 -276.37397) (xy 340.976587 -276.332374) (xy 341.009222 -276.295537)
			(xy 341.047343 -276.264412) (xy 341.089964 -276.239805) (xy 341.13598 -276.222353) (xy 341.184199 -276.212509)
			(xy 341.233374 -276.210528) (xy 341.282229 -276.21646) (xy 341.3295 -276.230152) (xy 341.373962 -276.25125)
			(xy 341.414465 -276.279206) (xy 341.449958 -276.313298) (xy 341.479523 -276.352642) (xy 341.502394 -276.396219)
			(xy 341.517978 -276.4429) (xy 341.525873 -276.491477) (xy 341.526368 -276.516084) (xy 341.844879 -276.516084)
			(xy 341.848974 -276.465356) (xy 341.861153 -276.415942) (xy 341.881101 -276.369122) (xy 341.908302 -276.326108)
			(xy 341.94205 -276.288014) (xy 341.981472 -276.255827) (xy 342.025546 -276.230381) (xy 342.073132 -276.212334)
			(xy 342.122996 -276.202154) (xy 342.173848 -276.200105) (xy 342.224369 -276.206239) (xy 342.273253 -276.220399)
			(xy 342.319232 -276.242216) (xy 342.361116 -276.271126) (xy 342.39782 -276.306381) (xy 342.428393 -276.347067)
			(xy 342.452044 -276.39213) (xy 342.46816 -276.440404) (xy 342.476324 -276.490638) (xy 342.476836 -276.516084)
			(xy 342.795364 -276.516084) (xy 342.799324 -276.46703) (xy 342.811101 -276.419246) (xy 342.830392 -276.37397)
			(xy 342.856695 -276.332374) (xy 342.88933 -276.295537) (xy 342.927451 -276.264412) (xy 342.970072 -276.239805)
			(xy 343.016088 -276.222353) (xy 343.064307 -276.212509) (xy 343.113482 -276.210528) (xy 343.162337 -276.21646)
			(xy 343.209608 -276.230152) (xy 343.25407 -276.25125) (xy 343.294573 -276.279206) (xy 343.330066 -276.313298)
			(xy 343.359631 -276.352642) (xy 343.382502 -276.396219) (xy 343.398086 -276.4429) (xy 343.405981 -276.491477)
			(xy 343.406476 -276.516084) (xy 343.724987 -276.516084) (xy 343.729082 -276.465356) (xy 343.741261 -276.415942)
			(xy 343.761209 -276.369122) (xy 343.78841 -276.326108) (xy 343.822158 -276.288014) (xy 343.86158 -276.255827)
			(xy 343.905654 -276.230381) (xy 343.95324 -276.212334) (xy 344.003104 -276.202154) (xy 344.053956 -276.200105)
			(xy 344.104477 -276.206239) (xy 344.153361 -276.220399) (xy 344.19934 -276.242216) (xy 344.241224 -276.271126)
			(xy 344.277928 -276.306381) (xy 344.308501 -276.347067) (xy 344.332152 -276.39213) (xy 344.348268 -276.440404)
			(xy 344.356432 -276.490638) (xy 344.356944 -276.516084) (xy 344.356432 -276.54153) (xy 344.348268 -276.591764)
			(xy 344.332152 -276.640038) (xy 344.308501 -276.685101) (xy 344.277928 -276.725787) (xy 344.241224 -276.761042)
			(xy 344.19934 -276.789952) (xy 344.153361 -276.811769) (xy 344.104477 -276.825929) (xy 344.053956 -276.832063)
			(xy 344.003104 -276.830014) (xy 343.95324 -276.819834) (xy 343.905654 -276.801787) (xy 343.86158 -276.776341)
			(xy 343.822158 -276.744154) (xy 343.78841 -276.70606) (xy 343.761209 -276.663046) (xy 343.741261 -276.616226)
			(xy 343.729082 -276.566812) (xy 343.724987 -276.516084) (xy 343.406476 -276.516084) (xy 343.405981 -276.540691)
			(xy 343.398086 -276.589268) (xy 343.382502 -276.635949) (xy 343.359631 -276.679526) (xy 343.330066 -276.71887)
			(xy 343.294573 -276.752962) (xy 343.25407 -276.780918) (xy 343.209608 -276.802016) (xy 343.162337 -276.815708)
			(xy 343.113482 -276.82164) (xy 343.064307 -276.819659) (xy 343.016088 -276.809815) (xy 342.970072 -276.792363)
			(xy 342.927451 -276.767756) (xy 342.88933 -276.736631) (xy 342.856695 -276.699794) (xy 342.830392 -276.658198)
			(xy 342.811101 -276.612922) (xy 342.799324 -276.565138) (xy 342.795364 -276.516084) (xy 342.476836 -276.516084)
			(xy 342.476324 -276.54153) (xy 342.46816 -276.591764) (xy 342.452044 -276.640038) (xy 342.428393 -276.685101)
			(xy 342.39782 -276.725787) (xy 342.361116 -276.761042) (xy 342.319232 -276.789952) (xy 342.273253 -276.811769)
			(xy 342.224369 -276.825929) (xy 342.173848 -276.832063) (xy 342.122996 -276.830014) (xy 342.073132 -276.819834)
			(xy 342.025546 -276.801787) (xy 341.981472 -276.776341) (xy 341.94205 -276.744154) (xy 341.908302 -276.70606)
			(xy 341.881101 -276.663046) (xy 341.861153 -276.616226) (xy 341.848974 -276.566812) (xy 341.844879 -276.516084)
			(xy 341.526368 -276.516084) (xy 341.525873 -276.540691) (xy 341.517978 -276.589268) (xy 341.502394 -276.635949)
			(xy 341.479523 -276.679526) (xy 341.449958 -276.71887) (xy 341.414465 -276.752962) (xy 341.373962 -276.780918)
			(xy 341.3295 -276.802016) (xy 341.282229 -276.815708) (xy 341.233374 -276.82164) (xy 341.184199 -276.819659)
			(xy 341.13598 -276.809815) (xy 341.089964 -276.792363) (xy 341.047343 -276.767756) (xy 341.009222 -276.736631)
			(xy 340.976587 -276.699794) (xy 340.950284 -276.658198) (xy 340.930993 -276.612922) (xy 340.919216 -276.565138)
			(xy 340.915256 -276.516084) (xy 340.596728 -276.516084) (xy 340.596216 -276.54153) (xy 340.588052 -276.591764)
			(xy 340.571936 -276.640038) (xy 340.548285 -276.685101) (xy 340.517712 -276.725787) (xy 340.481008 -276.761042)
			(xy 340.439124 -276.789952) (xy 340.393145 -276.811769) (xy 340.344261 -276.825929) (xy 340.29374 -276.832063)
			(xy 340.242888 -276.830014) (xy 340.193024 -276.819834) (xy 340.145438 -276.801787) (xy 340.101364 -276.776341)
			(xy 340.061942 -276.744154) (xy 340.028194 -276.70606) (xy 340.000993 -276.663046) (xy 339.981045 -276.616226)
			(xy 339.968866 -276.566812) (xy 339.964771 -276.516084) (xy 339.656928 -276.516084) (xy 339.656416 -276.54153)
			(xy 339.648252 -276.591764) (xy 339.632136 -276.640038) (xy 339.608485 -276.685101) (xy 339.577912 -276.725787)
			(xy 339.541208 -276.761042) (xy 339.499324 -276.789952) (xy 339.453345 -276.811769) (xy 339.404461 -276.825929)
			(xy 339.35394 -276.832063) (xy 339.303088 -276.830014) (xy 339.253224 -276.819834) (xy 339.205638 -276.801787)
			(xy 339.161564 -276.776341) (xy 339.122142 -276.744154) (xy 339.088394 -276.70606) (xy 339.061193 -276.663046)
			(xy 339.041245 -276.616226) (xy 339.029066 -276.566812) (xy 339.024971 -276.516084) (xy 338.70646 -276.516084)
			(xy 338.705965 -276.540691) (xy 338.69807 -276.589268) (xy 338.682486 -276.635949) (xy 338.659615 -276.679526)
			(xy 338.63005 -276.71887) (xy 338.594557 -276.752962) (xy 338.554054 -276.780918) (xy 338.509592 -276.802016)
			(xy 338.462321 -276.815708) (xy 338.413466 -276.82164) (xy 338.364291 -276.819659) (xy 338.316072 -276.809815)
			(xy 338.270056 -276.792363) (xy 338.227435 -276.767756) (xy 338.189314 -276.736631) (xy 338.156679 -276.699794)
			(xy 338.130376 -276.658198) (xy 338.111085 -276.612922) (xy 338.099308 -276.565138) (xy 338.095348 -276.516084)
			(xy 337.766406 -276.516084) (xy 337.765911 -276.540691) (xy 337.758016 -276.589268) (xy 337.742432 -276.635949)
			(xy 337.719561 -276.679526) (xy 337.689996 -276.71887) (xy 337.654503 -276.752962) (xy 337.614 -276.780918)
			(xy 337.569538 -276.802016) (xy 337.522267 -276.815708) (xy 337.473412 -276.82164) (xy 337.424237 -276.819659)
			(xy 337.376018 -276.809815) (xy 337.330002 -276.792363) (xy 337.287381 -276.767756) (xy 337.24926 -276.736631)
			(xy 337.216625 -276.699794) (xy 337.190322 -276.658198) (xy 337.171031 -276.612922) (xy 337.159254 -276.565138)
			(xy 337.155294 -276.516084) (xy 336.826352 -276.516084) (xy 336.825857 -276.540691) (xy 336.817962 -276.589268)
			(xy 336.802378 -276.635949) (xy 336.779507 -276.679526) (xy 336.749942 -276.71887) (xy 336.714449 -276.752962)
			(xy 336.673946 -276.780918) (xy 336.629484 -276.802016) (xy 336.582213 -276.815708) (xy 336.533358 -276.82164)
			(xy 336.484183 -276.819659) (xy 336.435964 -276.809815) (xy 336.389948 -276.792363) (xy 336.347327 -276.767756)
			(xy 336.309206 -276.736631) (xy 336.276571 -276.699794) (xy 336.250268 -276.658198) (xy 336.230977 -276.612922)
			(xy 336.2192 -276.565138) (xy 336.21524 -276.516084) (xy 335.886298 -276.516084) (xy 335.885803 -276.540691)
			(xy 335.877908 -276.589268) (xy 335.862324 -276.635949) (xy 335.839453 -276.679526) (xy 335.809888 -276.71887)
			(xy 335.774395 -276.752962) (xy 335.733892 -276.780918) (xy 335.68943 -276.802016) (xy 335.642159 -276.815708)
			(xy 335.593304 -276.82164) (xy 335.544129 -276.819659) (xy 335.49591 -276.809815) (xy 335.449894 -276.792363)
			(xy 335.407273 -276.767756) (xy 335.369152 -276.736631) (xy 335.336517 -276.699794) (xy 335.310214 -276.658198)
			(xy 335.290923 -276.612922) (xy 335.279146 -276.565138) (xy 335.275186 -276.516084) (xy 334.950054 -276.516084)
			(xy 334.950054 -276.92477) (xy 334.950054 -276.92731) (xy 334.950964 -276.936977) (xy 334.959065 -276.954607)
			(xy 334.965802 -276.9616) (xy 335.024476 -277.012146) (xy 335.028708 -277.015621) (xy 335.038318 -277.020868)
			(xy 335.043526 -277.02256) (xy 335.054194 -277.025608) (xy 335.065116 -277.024084) (xy 335.076354 -277.022528)
			(xy 335.098983 -277.020873) (xy 335.110328 -277.020782) (xy 335.11109 -277.020782) (xy 335.136349 -277.021274)
			(xy 335.186178 -277.029587) (xy 335.23396 -277.045989) (xy 335.27839 -277.070032) (xy 335.318256 -277.101061)
			(xy 335.352472 -277.138227) (xy 335.380103 -277.180519) (xy 335.400396 -277.226782) (xy 335.412798 -277.275754)
			(xy 335.416969 -277.32609) (xy 335.74534 -277.32609) (xy 335.7493 -277.277036) (xy 335.761077 -277.229252)
			(xy 335.780368 -277.183976) (xy 335.806671 -277.14238) (xy 335.839306 -277.105543) (xy 335.877427 -277.074418)
			(xy 335.920048 -277.049811) (xy 335.966064 -277.032359) (xy 336.014283 -277.022515) (xy 336.063458 -277.020534)
			(xy 336.112313 -277.026466) (xy 336.159584 -277.040158) (xy 336.204046 -277.061256) (xy 336.244549 -277.089212)
			(xy 336.280042 -277.123304) (xy 336.309607 -277.162648) (xy 336.332478 -277.206225) (xy 336.348062 -277.252906)
			(xy 336.355957 -277.301483) (xy 336.356452 -277.32609) (xy 336.685394 -277.32609) (xy 336.689354 -277.277036)
			(xy 336.701131 -277.229252) (xy 336.720422 -277.183976) (xy 336.746725 -277.14238) (xy 336.77936 -277.105543)
			(xy 336.817481 -277.074418) (xy 336.860102 -277.049811) (xy 336.906118 -277.032359) (xy 336.954337 -277.022515)
			(xy 337.003512 -277.020534) (xy 337.052367 -277.026466) (xy 337.099638 -277.040158) (xy 337.1441 -277.061256)
			(xy 337.184603 -277.089212) (xy 337.220096 -277.123304) (xy 337.249661 -277.162648) (xy 337.272532 -277.206225)
			(xy 337.288116 -277.252906) (xy 337.296011 -277.301483) (xy 337.296506 -277.32609) (xy 337.625194 -277.32609)
			(xy 337.629154 -277.277036) (xy 337.640931 -277.229252) (xy 337.660222 -277.183976) (xy 337.686525 -277.14238)
			(xy 337.71916 -277.105543) (xy 337.757281 -277.074418) (xy 337.799902 -277.049811) (xy 337.845918 -277.032359)
			(xy 337.894137 -277.022515) (xy 337.943312 -277.020534) (xy 337.992167 -277.026466) (xy 338.039438 -277.040158)
			(xy 338.0839 -277.061256) (xy 338.124403 -277.089212) (xy 338.159896 -277.123304) (xy 338.189461 -277.162648)
			(xy 338.212332 -277.206225) (xy 338.227916 -277.252906) (xy 338.235811 -277.301483) (xy 338.236306 -277.32609)
			(xy 338.554817 -277.32609) (xy 338.558912 -277.275362) (xy 338.571091 -277.225948) (xy 338.591039 -277.179128)
			(xy 338.61824 -277.136114) (xy 338.651988 -277.09802) (xy 338.69141 -277.065833) (xy 338.735484 -277.040387)
			(xy 338.78307 -277.02234) (xy 338.832934 -277.01216) (xy 338.883786 -277.010111) (xy 338.934307 -277.016245)
			(xy 338.983191 -277.030405) (xy 339.02917 -277.052222) (xy 339.071054 -277.081132) (xy 339.107758 -277.116387)
			(xy 339.138331 -277.157073) (xy 339.161982 -277.202136) (xy 339.178098 -277.25041) (xy 339.186262 -277.300644)
			(xy 339.186774 -277.32609) (xy 339.505302 -277.32609) (xy 339.509262 -277.277036) (xy 339.521039 -277.229252)
			(xy 339.54033 -277.183976) (xy 339.566633 -277.14238) (xy 339.599268 -277.105543) (xy 339.637389 -277.074418)
			(xy 339.68001 -277.049811) (xy 339.726026 -277.032359) (xy 339.774245 -277.022515) (xy 339.82342 -277.020534)
			(xy 339.872275 -277.026466) (xy 339.919546 -277.040158) (xy 339.964008 -277.061256) (xy 340.004511 -277.089212)
			(xy 340.040004 -277.123304) (xy 340.069569 -277.162648) (xy 340.09244 -277.206225) (xy 340.108024 -277.252906)
			(xy 340.115919 -277.301483) (xy 340.116414 -277.32609) (xy 340.434925 -277.32609) (xy 340.43902 -277.275362)
			(xy 340.451199 -277.225948) (xy 340.471147 -277.179128) (xy 340.498348 -277.136114) (xy 340.532096 -277.09802)
			(xy 340.571518 -277.065833) (xy 340.615592 -277.040387) (xy 340.663178 -277.02234) (xy 340.713042 -277.01216)
			(xy 340.763894 -277.010111) (xy 340.814415 -277.016245) (xy 340.863299 -277.030405) (xy 340.909278 -277.052222)
			(xy 340.951162 -277.081132) (xy 340.987866 -277.116387) (xy 341.018439 -277.157073) (xy 341.04209 -277.202136)
			(xy 341.058206 -277.25041) (xy 341.06637 -277.300644) (xy 341.066882 -277.32609) (xy 341.38541 -277.32609)
			(xy 341.38937 -277.277036) (xy 341.401147 -277.229252) (xy 341.420438 -277.183976) (xy 341.446741 -277.14238)
			(xy 341.479376 -277.105543) (xy 341.517497 -277.074418) (xy 341.560118 -277.049811) (xy 341.606134 -277.032359)
			(xy 341.654353 -277.022515) (xy 341.703528 -277.020534) (xy 341.752383 -277.026466) (xy 341.799654 -277.040158)
			(xy 341.844116 -277.061256) (xy 341.884619 -277.089212) (xy 341.920112 -277.123304) (xy 341.949677 -277.162648)
			(xy 341.972548 -277.206225) (xy 341.988132 -277.252906) (xy 341.996027 -277.301483) (xy 341.996522 -277.32609)
			(xy 342.314779 -277.32609) (xy 342.318874 -277.275362) (xy 342.331053 -277.225948) (xy 342.351001 -277.179128)
			(xy 342.378202 -277.136114) (xy 342.41195 -277.09802) (xy 342.451372 -277.065833) (xy 342.495446 -277.040387)
			(xy 342.543032 -277.02234) (xy 342.592896 -277.01216) (xy 342.643748 -277.010111) (xy 342.694269 -277.016245)
			(xy 342.743153 -277.030405) (xy 342.789132 -277.052222) (xy 342.831016 -277.081132) (xy 342.86772 -277.116387)
			(xy 342.898293 -277.157073) (xy 342.921944 -277.202136) (xy 342.93806 -277.25041) (xy 342.946224 -277.300644)
			(xy 342.946736 -277.32609) (xy 343.254833 -277.32609) (xy 343.258928 -277.275362) (xy 343.271107 -277.225948)
			(xy 343.291055 -277.179128) (xy 343.318256 -277.136114) (xy 343.352004 -277.09802) (xy 343.391426 -277.065833)
			(xy 343.4355 -277.040387) (xy 343.483086 -277.02234) (xy 343.53295 -277.01216) (xy 343.583802 -277.010111)
			(xy 343.634323 -277.016245) (xy 343.683207 -277.030405) (xy 343.729186 -277.052222) (xy 343.77107 -277.081132)
			(xy 343.807774 -277.116387) (xy 343.838347 -277.157073) (xy 343.861998 -277.202136) (xy 343.878114 -277.25041)
			(xy 343.886278 -277.300644) (xy 343.88679 -277.32609) (xy 343.886278 -277.351536) (xy 343.878114 -277.40177)
			(xy 343.861998 -277.450044) (xy 343.838347 -277.495107) (xy 343.807774 -277.535793) (xy 343.77107 -277.571048)
			(xy 343.729186 -277.599958) (xy 343.683207 -277.621775) (xy 343.634323 -277.635935) (xy 343.583802 -277.642069)
			(xy 343.53295 -277.64002) (xy 343.483086 -277.62984) (xy 343.4355 -277.611793) (xy 343.391426 -277.586347)
			(xy 343.352004 -277.55416) (xy 343.318256 -277.516066) (xy 343.291055 -277.473052) (xy 343.271107 -277.426232)
			(xy 343.258928 -277.376818) (xy 343.254833 -277.32609) (xy 342.946736 -277.32609) (xy 342.946224 -277.351536)
			(xy 342.93806 -277.40177) (xy 342.921944 -277.450044) (xy 342.898293 -277.495107) (xy 342.86772 -277.535793)
			(xy 342.831016 -277.571048) (xy 342.789132 -277.599958) (xy 342.743153 -277.621775) (xy 342.694269 -277.635935)
			(xy 342.643748 -277.642069) (xy 342.592896 -277.64002) (xy 342.543032 -277.62984) (xy 342.495446 -277.611793)
			(xy 342.451372 -277.586347) (xy 342.41195 -277.55416) (xy 342.378202 -277.516066) (xy 342.351001 -277.473052)
			(xy 342.331053 -277.426232) (xy 342.318874 -277.376818) (xy 342.314779 -277.32609) (xy 341.996522 -277.32609)
			(xy 341.996027 -277.350697) (xy 341.988132 -277.399274) (xy 341.972548 -277.445955) (xy 341.949677 -277.489532)
			(xy 341.920112 -277.528876) (xy 341.884619 -277.562968) (xy 341.844116 -277.590924) (xy 341.799654 -277.612022)
			(xy 341.752383 -277.625714) (xy 341.703528 -277.631646) (xy 341.654353 -277.629665) (xy 341.606134 -277.619821)
			(xy 341.560118 -277.602369) (xy 341.517497 -277.577762) (xy 341.479376 -277.546637) (xy 341.446741 -277.5098)
			(xy 341.420438 -277.468204) (xy 341.401147 -277.422928) (xy 341.38937 -277.375144) (xy 341.38541 -277.32609)
			(xy 341.066882 -277.32609) (xy 341.06637 -277.351536) (xy 341.058206 -277.40177) (xy 341.04209 -277.450044)
			(xy 341.018439 -277.495107) (xy 340.987866 -277.535793) (xy 340.951162 -277.571048) (xy 340.909278 -277.599958)
			(xy 340.863299 -277.621775) (xy 340.814415 -277.635935) (xy 340.763894 -277.642069) (xy 340.713042 -277.64002)
			(xy 340.663178 -277.62984) (xy 340.615592 -277.611793) (xy 340.571518 -277.586347) (xy 340.532096 -277.55416)
			(xy 340.498348 -277.516066) (xy 340.471147 -277.473052) (xy 340.451199 -277.426232) (xy 340.43902 -277.376818)
			(xy 340.434925 -277.32609) (xy 340.116414 -277.32609) (xy 340.115919 -277.350697) (xy 340.108024 -277.399274)
			(xy 340.09244 -277.445955) (xy 340.069569 -277.489532) (xy 340.040004 -277.528876) (xy 340.004511 -277.562968)
			(xy 339.964008 -277.590924) (xy 339.919546 -277.612022) (xy 339.872275 -277.625714) (xy 339.82342 -277.631646)
			(xy 339.774245 -277.629665) (xy 339.726026 -277.619821) (xy 339.68001 -277.602369) (xy 339.637389 -277.577762)
			(xy 339.599268 -277.546637) (xy 339.566633 -277.5098) (xy 339.54033 -277.468204) (xy 339.521039 -277.422928)
			(xy 339.509262 -277.375144) (xy 339.505302 -277.32609) (xy 339.186774 -277.32609) (xy 339.186262 -277.351536)
			(xy 339.178098 -277.40177) (xy 339.161982 -277.450044) (xy 339.138331 -277.495107) (xy 339.107758 -277.535793)
			(xy 339.071054 -277.571048) (xy 339.02917 -277.599958) (xy 338.983191 -277.621775) (xy 338.934307 -277.635935)
			(xy 338.883786 -277.642069) (xy 338.832934 -277.64002) (xy 338.78307 -277.62984) (xy 338.735484 -277.611793)
			(xy 338.69141 -277.586347) (xy 338.651988 -277.55416) (xy 338.61824 -277.516066) (xy 338.591039 -277.473052)
			(xy 338.571091 -277.426232) (xy 338.558912 -277.376818) (xy 338.554817 -277.32609) (xy 338.236306 -277.32609)
			(xy 338.235811 -277.350697) (xy 338.227916 -277.399274) (xy 338.212332 -277.445955) (xy 338.189461 -277.489532)
			(xy 338.159896 -277.528876) (xy 338.124403 -277.562968) (xy 338.0839 -277.590924) (xy 338.039438 -277.612022)
			(xy 337.992167 -277.625714) (xy 337.943312 -277.631646) (xy 337.894137 -277.629665) (xy 337.845918 -277.619821)
			(xy 337.799902 -277.602369) (xy 337.757281 -277.577762) (xy 337.71916 -277.546637) (xy 337.686525 -277.5098)
			(xy 337.660222 -277.468204) (xy 337.640931 -277.422928) (xy 337.629154 -277.375144) (xy 337.625194 -277.32609)
			(xy 337.296506 -277.32609) (xy 337.296011 -277.350697) (xy 337.288116 -277.399274) (xy 337.272532 -277.445955)
			(xy 337.249661 -277.489532) (xy 337.220096 -277.528876) (xy 337.184603 -277.562968) (xy 337.1441 -277.590924)
			(xy 337.099638 -277.612022) (xy 337.052367 -277.625714) (xy 337.003512 -277.631646) (xy 336.954337 -277.629665)
			(xy 336.906118 -277.619821) (xy 336.860102 -277.602369) (xy 336.817481 -277.577762) (xy 336.77936 -277.546637)
			(xy 336.746725 -277.5098) (xy 336.720422 -277.468204) (xy 336.701131 -277.422928) (xy 336.689354 -277.375144)
			(xy 336.685394 -277.32609) (xy 336.356452 -277.32609) (xy 336.355957 -277.350697) (xy 336.348062 -277.399274)
			(xy 336.332478 -277.445955) (xy 336.309607 -277.489532) (xy 336.280042 -277.528876) (xy 336.244549 -277.562968)
			(xy 336.204046 -277.590924) (xy 336.159584 -277.612022) (xy 336.112313 -277.625714) (xy 336.063458 -277.631646)
			(xy 336.014283 -277.629665) (xy 335.966064 -277.619821) (xy 335.920048 -277.602369) (xy 335.877427 -277.577762)
			(xy 335.839306 -277.546637) (xy 335.806671 -277.5098) (xy 335.780368 -277.468204) (xy 335.761077 -277.422928)
			(xy 335.7493 -277.375144) (xy 335.74534 -277.32609) (xy 335.416969 -277.32609) (xy 335.41697 -277.3261)
			(xy 335.412798 -277.376446) (xy 335.400396 -277.425418) (xy 335.380103 -277.471681) (xy 335.352472 -277.513973)
			(xy 335.318256 -277.551139) (xy 335.27839 -277.582168) (xy 335.23396 -277.606211) (xy 335.186178 -277.622613)
			(xy 335.136349 -277.630926) (xy 335.11109 -277.631398) (xy 335.110582 -277.631398) (xy 335.097433 -277.631248)
			(xy 335.071234 -277.628956) (xy 335.058258 -277.626826) (xy 335.054448 -277.626318) (xy 335.04378 -277.629366)
			(xy 335.03889 -277.630899) (xy 335.029802 -277.635631) (xy 335.025746 -277.638764) (xy 334.967072 -277.689056)
			(xy 334.959462 -277.696625) (xy 334.950686 -277.716185) (xy 334.950054 -277.726902) (xy 334.950054 -278.017478)
			(xy 334.952848 -278.02586) (xy 334.961674 -278.052563) (xy 334.971244 -278.107979) (xy 334.971898 -278.136096)
			(xy 335.275186 -278.136096) (xy 335.279146 -278.087042) (xy 335.290923 -278.039258) (xy 335.310214 -277.993982)
			(xy 335.336517 -277.952386) (xy 335.369152 -277.915549) (xy 335.407273 -277.884424) (xy 335.449894 -277.859817)
			(xy 335.49591 -277.842365) (xy 335.544129 -277.832521) (xy 335.593304 -277.83054) (xy 335.642159 -277.836472)
			(xy 335.68943 -277.850164) (xy 335.733892 -277.871262) (xy 335.774395 -277.899218) (xy 335.809888 -277.93331)
			(xy 335.839453 -277.972654) (xy 335.862324 -278.016231) (xy 335.877908 -278.062912) (xy 335.885803 -278.111489)
			(xy 335.886298 -278.136096) (xy 336.21524 -278.136096) (xy 336.2192 -278.087042) (xy 336.230977 -278.039258)
			(xy 336.250268 -277.993982) (xy 336.276571 -277.952386) (xy 336.309206 -277.915549) (xy 336.347327 -277.884424)
			(xy 336.389948 -277.859817) (xy 336.435964 -277.842365) (xy 336.484183 -277.832521) (xy 336.533358 -277.83054)
			(xy 336.582213 -277.836472) (xy 336.629484 -277.850164) (xy 336.673946 -277.871262) (xy 336.714449 -277.899218)
			(xy 336.749942 -277.93331) (xy 336.779507 -277.972654) (xy 336.802378 -278.016231) (xy 336.817962 -278.062912)
			(xy 336.825857 -278.111489) (xy 336.826352 -278.136096) (xy 337.155294 -278.136096) (xy 337.159254 -278.087042)
			(xy 337.171031 -278.039258) (xy 337.190322 -277.993982) (xy 337.216625 -277.952386) (xy 337.24926 -277.915549)
			(xy 337.287381 -277.884424) (xy 337.330002 -277.859817) (xy 337.376018 -277.842365) (xy 337.424237 -277.832521)
			(xy 337.473412 -277.83054) (xy 337.522267 -277.836472) (xy 337.569538 -277.850164) (xy 337.614 -277.871262)
			(xy 337.654503 -277.899218) (xy 337.689996 -277.93331) (xy 337.719561 -277.972654) (xy 337.742432 -278.016231)
			(xy 337.758016 -278.062912) (xy 337.765911 -278.111489) (xy 337.766406 -278.136096) (xy 338.095348 -278.136096)
			(xy 338.099308 -278.087042) (xy 338.111085 -278.039258) (xy 338.130376 -277.993982) (xy 338.156679 -277.952386)
			(xy 338.189314 -277.915549) (xy 338.227435 -277.884424) (xy 338.270056 -277.859817) (xy 338.316072 -277.842365)
			(xy 338.364291 -277.832521) (xy 338.413466 -277.83054) (xy 338.462321 -277.836472) (xy 338.509592 -277.850164)
			(xy 338.554054 -277.871262) (xy 338.594557 -277.899218) (xy 338.63005 -277.93331) (xy 338.659615 -277.972654)
			(xy 338.682486 -278.016231) (xy 338.69807 -278.062912) (xy 338.705965 -278.111489) (xy 338.70646 -278.136096)
			(xy 339.024971 -278.136096) (xy 339.029066 -278.085368) (xy 339.041245 -278.035954) (xy 339.061193 -277.989134)
			(xy 339.088394 -277.94612) (xy 339.122142 -277.908026) (xy 339.161564 -277.875839) (xy 339.205638 -277.850393)
			(xy 339.253224 -277.832346) (xy 339.303088 -277.822166) (xy 339.35394 -277.820117) (xy 339.404461 -277.826251)
			(xy 339.453345 -277.840411) (xy 339.499324 -277.862228) (xy 339.541208 -277.891138) (xy 339.577912 -277.926393)
			(xy 339.608485 -277.967079) (xy 339.632136 -278.012142) (xy 339.648252 -278.060416) (xy 339.656416 -278.11065)
			(xy 339.656928 -278.136096) (xy 339.964771 -278.136096) (xy 339.968866 -278.085368) (xy 339.981045 -278.035954)
			(xy 340.000993 -277.989134) (xy 340.028194 -277.94612) (xy 340.061942 -277.908026) (xy 340.101364 -277.875839)
			(xy 340.145438 -277.850393) (xy 340.193024 -277.832346) (xy 340.242888 -277.822166) (xy 340.29374 -277.820117)
			(xy 340.344261 -277.826251) (xy 340.393145 -277.840411) (xy 340.439124 -277.862228) (xy 340.481008 -277.891138)
			(xy 340.517712 -277.926393) (xy 340.548285 -277.967079) (xy 340.571936 -278.012142) (xy 340.588052 -278.060416)
			(xy 340.596216 -278.11065) (xy 340.596728 -278.136096) (xy 341.844879 -278.136096) (xy 341.848974 -278.085368)
			(xy 341.861153 -278.035954) (xy 341.881101 -277.989134) (xy 341.908302 -277.94612) (xy 341.94205 -277.908026)
			(xy 341.981472 -277.875839) (xy 342.025546 -277.850393) (xy 342.073132 -277.832346) (xy 342.122996 -277.822166)
			(xy 342.173848 -277.820117) (xy 342.224369 -277.826251) (xy 342.273253 -277.840411) (xy 342.319232 -277.862228)
			(xy 342.361116 -277.891138) (xy 342.39782 -277.926393) (xy 342.428393 -277.967079) (xy 342.452044 -278.012142)
			(xy 342.46816 -278.060416) (xy 342.476324 -278.11065) (xy 342.476836 -278.136096) (xy 342.795364 -278.136096)
			(xy 342.799324 -278.087042) (xy 342.811101 -278.039258) (xy 342.830392 -277.993982) (xy 342.856695 -277.952386)
			(xy 342.88933 -277.915549) (xy 342.927451 -277.884424) (xy 342.970072 -277.859817) (xy 343.016088 -277.842365)
			(xy 343.064307 -277.832521) (xy 343.113482 -277.83054) (xy 343.162337 -277.836472) (xy 343.209608 -277.850164)
			(xy 343.25407 -277.871262) (xy 343.294573 -277.899218) (xy 343.330066 -277.93331) (xy 343.359631 -277.972654)
			(xy 343.382502 -278.016231) (xy 343.398086 -278.062912) (xy 343.405981 -278.111489) (xy 343.406476 -278.136096)
			(xy 343.724987 -278.136096) (xy 343.729082 -278.085368) (xy 343.741261 -278.035954) (xy 343.761209 -277.989134)
			(xy 343.78841 -277.94612) (xy 343.822158 -277.908026) (xy 343.86158 -277.875839) (xy 343.905654 -277.850393)
			(xy 343.95324 -277.832346) (xy 344.003104 -277.822166) (xy 344.053956 -277.820117) (xy 344.104477 -277.826251)
			(xy 344.153361 -277.840411) (xy 344.19934 -277.862228) (xy 344.241224 -277.891138) (xy 344.277928 -277.926393)
			(xy 344.308501 -277.967079) (xy 344.332152 -278.012142) (xy 344.348268 -278.060416) (xy 344.356432 -278.11065)
			(xy 344.356944 -278.136096) (xy 344.356432 -278.161542) (xy 344.348268 -278.211776) (xy 344.332152 -278.26005)
			(xy 344.308501 -278.305113) (xy 344.277928 -278.345799) (xy 344.241224 -278.381054) (xy 344.19934 -278.409964)
			(xy 344.153361 -278.431781) (xy 344.104477 -278.445941) (xy 344.053956 -278.452075) (xy 344.003104 -278.450026)
			(xy 343.95324 -278.439846) (xy 343.905654 -278.421799) (xy 343.86158 -278.396353) (xy 343.822158 -278.364166)
			(xy 343.78841 -278.326072) (xy 343.761209 -278.283058) (xy 343.741261 -278.236238) (xy 343.729082 -278.186824)
			(xy 343.724987 -278.136096) (xy 343.406476 -278.136096) (xy 343.405981 -278.160703) (xy 343.398086 -278.20928)
			(xy 343.382502 -278.255961) (xy 343.359631 -278.299538) (xy 343.330066 -278.338882) (xy 343.294573 -278.372974)
			(xy 343.25407 -278.40093) (xy 343.209608 -278.422028) (xy 343.162337 -278.43572) (xy 343.113482 -278.441652)
			(xy 343.064307 -278.439671) (xy 343.016088 -278.429827) (xy 342.970072 -278.412375) (xy 342.927451 -278.387768)
			(xy 342.88933 -278.356643) (xy 342.856695 -278.319806) (xy 342.830392 -278.27821) (xy 342.811101 -278.232934)
			(xy 342.799324 -278.18515) (xy 342.795364 -278.136096) (xy 342.476836 -278.136096) (xy 342.476324 -278.161542)
			(xy 342.46816 -278.211776) (xy 342.452044 -278.26005) (xy 342.428393 -278.305113) (xy 342.39782 -278.345799)
			(xy 342.361116 -278.381054) (xy 342.319232 -278.409964) (xy 342.273253 -278.431781) (xy 342.224369 -278.445941)
			(xy 342.173848 -278.452075) (xy 342.122996 -278.450026) (xy 342.073132 -278.439846) (xy 342.025546 -278.421799)
			(xy 341.981472 -278.396353) (xy 341.94205 -278.364166) (xy 341.908302 -278.326072) (xy 341.881101 -278.283058)
			(xy 341.861153 -278.236238) (xy 341.848974 -278.186824) (xy 341.844879 -278.136096) (xy 340.596728 -278.136096)
			(xy 340.596216 -278.161542) (xy 340.588052 -278.211776) (xy 340.571936 -278.26005) (xy 340.548285 -278.305113)
			(xy 340.517712 -278.345799) (xy 340.481008 -278.381054) (xy 340.439124 -278.409964) (xy 340.393145 -278.431781)
			(xy 340.344261 -278.445941) (xy 340.29374 -278.452075) (xy 340.242888 -278.450026) (xy 340.193024 -278.439846)
			(xy 340.145438 -278.421799) (xy 340.101364 -278.396353) (xy 340.061942 -278.364166) (xy 340.028194 -278.326072)
			(xy 340.000993 -278.283058) (xy 339.981045 -278.236238) (xy 339.968866 -278.186824) (xy 339.964771 -278.136096)
			(xy 339.656928 -278.136096) (xy 339.656416 -278.161542) (xy 339.648252 -278.211776) (xy 339.632136 -278.26005)
			(xy 339.608485 -278.305113) (xy 339.577912 -278.345799) (xy 339.541208 -278.381054) (xy 339.499324 -278.409964)
			(xy 339.453345 -278.431781) (xy 339.404461 -278.445941) (xy 339.35394 -278.452075) (xy 339.303088 -278.450026)
			(xy 339.253224 -278.439846) (xy 339.205638 -278.421799) (xy 339.161564 -278.396353) (xy 339.122142 -278.364166)
			(xy 339.088394 -278.326072) (xy 339.061193 -278.283058) (xy 339.041245 -278.236238) (xy 339.029066 -278.186824)
			(xy 339.024971 -278.136096) (xy 338.70646 -278.136096) (xy 338.705965 -278.160703) (xy 338.69807 -278.20928)
			(xy 338.682486 -278.255961) (xy 338.659615 -278.299538) (xy 338.63005 -278.338882) (xy 338.594557 -278.372974)
			(xy 338.554054 -278.40093) (xy 338.509592 -278.422028) (xy 338.462321 -278.43572) (xy 338.413466 -278.441652)
			(xy 338.364291 -278.439671) (xy 338.316072 -278.429827) (xy 338.270056 -278.412375) (xy 338.227435 -278.387768)
			(xy 338.189314 -278.356643) (xy 338.156679 -278.319806) (xy 338.130376 -278.27821) (xy 338.111085 -278.232934)
			(xy 338.099308 -278.18515) (xy 338.095348 -278.136096) (xy 337.766406 -278.136096) (xy 337.765911 -278.160703)
			(xy 337.758016 -278.20928) (xy 337.742432 -278.255961) (xy 337.719561 -278.299538) (xy 337.689996 -278.338882)
			(xy 337.654503 -278.372974) (xy 337.614 -278.40093) (xy 337.569538 -278.422028) (xy 337.522267 -278.43572)
			(xy 337.473412 -278.441652) (xy 337.424237 -278.439671) (xy 337.376018 -278.429827) (xy 337.330002 -278.412375)
			(xy 337.287381 -278.387768) (xy 337.24926 -278.356643) (xy 337.216625 -278.319806) (xy 337.190322 -278.27821)
			(xy 337.171031 -278.232934) (xy 337.159254 -278.18515) (xy 337.155294 -278.136096) (xy 336.826352 -278.136096)
			(xy 336.825857 -278.160703) (xy 336.817962 -278.20928) (xy 336.802378 -278.255961) (xy 336.779507 -278.299538)
			(xy 336.749942 -278.338882) (xy 336.714449 -278.372974) (xy 336.673946 -278.40093) (xy 336.629484 -278.422028)
			(xy 336.582213 -278.43572) (xy 336.533358 -278.441652) (xy 336.484183 -278.439671) (xy 336.435964 -278.429827)
			(xy 336.389948 -278.412375) (xy 336.347327 -278.387768) (xy 336.309206 -278.356643) (xy 336.276571 -278.319806)
			(xy 336.250268 -278.27821) (xy 336.230977 -278.232934) (xy 336.2192 -278.18515) (xy 336.21524 -278.136096)
			(xy 335.886298 -278.136096) (xy 335.885803 -278.160703) (xy 335.877908 -278.20928) (xy 335.862324 -278.255961)
			(xy 335.839453 -278.299538) (xy 335.809888 -278.338882) (xy 335.774395 -278.372974) (xy 335.733892 -278.40093)
			(xy 335.68943 -278.422028) (xy 335.642159 -278.43572) (xy 335.593304 -278.441652) (xy 335.544129 -278.439671)
			(xy 335.49591 -278.429827) (xy 335.449894 -278.412375) (xy 335.407273 -278.387768) (xy 335.369152 -278.356643)
			(xy 335.336517 -278.319806) (xy 335.310214 -278.27821) (xy 335.290923 -278.232934) (xy 335.279146 -278.18515)
			(xy 335.275186 -278.136096) (xy 334.971898 -278.136096) (xy 334.971317 -278.16422) (xy 334.961744 -278.219646)
			(xy 334.952848 -278.246332) (xy 334.950054 -278.254714) (xy 334.950054 -278.544782) (xy 334.950054 -278.547322)
			(xy 334.950967 -278.556988) (xy 334.95907 -278.574615) (xy 334.965802 -278.581612) (xy 335.024476 -278.632158)
			(xy 335.028709 -278.635632) (xy 335.038318 -278.640878) (xy 335.043526 -278.642572) (xy 335.054194 -278.64562)
			(xy 335.065116 -278.644096) (xy 335.076354 -278.64254) (xy 335.098983 -278.640885) (xy 335.110328 -278.640794)
			(xy 335.11109 -278.640794) (xy 335.136348 -278.641286) (xy 335.186176 -278.649599) (xy 335.233955 -278.666)
			(xy 335.278383 -278.690042) (xy 335.318248 -278.721069) (xy 335.352462 -278.758235) (xy 335.380093 -278.800525)
			(xy 335.400385 -278.846786) (xy 335.412786 -278.895756) (xy 335.416958 -278.9461) (xy 335.416958 -278.946102)
			(xy 335.74534 -278.946102) (xy 335.7493 -278.897048) (xy 335.761077 -278.849264) (xy 335.780368 -278.803988)
			(xy 335.806671 -278.762392) (xy 335.839306 -278.725555) (xy 335.877427 -278.69443) (xy 335.920048 -278.669823)
			(xy 335.966064 -278.652371) (xy 336.014283 -278.642527) (xy 336.063458 -278.640546) (xy 336.112313 -278.646478)
			(xy 336.159584 -278.66017) (xy 336.204046 -278.681268) (xy 336.244549 -278.709224) (xy 336.280042 -278.743316)
			(xy 336.309607 -278.78266) (xy 336.332478 -278.826237) (xy 336.348062 -278.872918) (xy 336.355957 -278.921495)
			(xy 336.356452 -278.946102) (xy 336.685394 -278.946102) (xy 336.689354 -278.897048) (xy 336.701131 -278.849264)
			(xy 336.720422 -278.803988) (xy 336.746725 -278.762392) (xy 336.77936 -278.725555) (xy 336.817481 -278.69443)
			(xy 336.860102 -278.669823) (xy 336.906118 -278.652371) (xy 336.954337 -278.642527) (xy 337.003512 -278.640546)
			(xy 337.052367 -278.646478) (xy 337.099638 -278.66017) (xy 337.1441 -278.681268) (xy 337.184603 -278.709224)
			(xy 337.220096 -278.743316) (xy 337.249661 -278.78266) (xy 337.272532 -278.826237) (xy 337.288116 -278.872918)
			(xy 337.296011 -278.921495) (xy 337.296506 -278.946102) (xy 337.625194 -278.946102) (xy 337.629154 -278.897048)
			(xy 337.640931 -278.849264) (xy 337.660222 -278.803988) (xy 337.686525 -278.762392) (xy 337.71916 -278.725555)
			(xy 337.757281 -278.69443) (xy 337.799902 -278.669823) (xy 337.845918 -278.652371) (xy 337.894137 -278.642527)
			(xy 337.943312 -278.640546) (xy 337.992167 -278.646478) (xy 338.039438 -278.66017) (xy 338.0839 -278.681268)
			(xy 338.124403 -278.709224) (xy 338.159896 -278.743316) (xy 338.189461 -278.78266) (xy 338.212332 -278.826237)
			(xy 338.227916 -278.872918) (xy 338.235811 -278.921495) (xy 338.236306 -278.946102) (xy 338.554817 -278.946102)
			(xy 338.558912 -278.895374) (xy 338.571091 -278.84596) (xy 338.591039 -278.79914) (xy 338.61824 -278.756126)
			(xy 338.651988 -278.718032) (xy 338.69141 -278.685845) (xy 338.735484 -278.660399) (xy 338.78307 -278.642352)
			(xy 338.832934 -278.632172) (xy 338.883786 -278.630123) (xy 338.934307 -278.636257) (xy 338.983191 -278.650417)
			(xy 339.02917 -278.672234) (xy 339.071054 -278.701144) (xy 339.107758 -278.736399) (xy 339.138331 -278.777085)
			(xy 339.161982 -278.822148) (xy 339.178098 -278.870422) (xy 339.186262 -278.920656) (xy 339.186774 -278.946102)
			(xy 339.505302 -278.946102) (xy 339.509262 -278.897048) (xy 339.521039 -278.849264) (xy 339.54033 -278.803988)
			(xy 339.566633 -278.762392) (xy 339.599268 -278.725555) (xy 339.637389 -278.69443) (xy 339.68001 -278.669823)
			(xy 339.726026 -278.652371) (xy 339.774245 -278.642527) (xy 339.82342 -278.640546) (xy 339.872275 -278.646478)
			(xy 339.919546 -278.66017) (xy 339.964008 -278.681268) (xy 340.004511 -278.709224) (xy 340.040004 -278.743316)
			(xy 340.069569 -278.78266) (xy 340.09244 -278.826237) (xy 340.108024 -278.872918) (xy 340.115919 -278.921495)
			(xy 340.116414 -278.946102) (xy 340.434925 -278.946102) (xy 340.43902 -278.895374) (xy 340.451199 -278.84596)
			(xy 340.471147 -278.79914) (xy 340.498348 -278.756126) (xy 340.532096 -278.718032) (xy 340.571518 -278.685845)
			(xy 340.615592 -278.660399) (xy 340.663178 -278.642352) (xy 340.713042 -278.632172) (xy 340.763894 -278.630123)
			(xy 340.814415 -278.636257) (xy 340.863299 -278.650417) (xy 340.909278 -278.672234) (xy 340.951162 -278.701144)
			(xy 340.987866 -278.736399) (xy 341.018439 -278.777085) (xy 341.04209 -278.822148) (xy 341.058206 -278.870422)
			(xy 341.06637 -278.920656) (xy 341.066882 -278.946102) (xy 341.38541 -278.946102) (xy 341.38937 -278.897048)
			(xy 341.401147 -278.849264) (xy 341.420438 -278.803988) (xy 341.446741 -278.762392) (xy 341.479376 -278.725555)
			(xy 341.517497 -278.69443) (xy 341.560118 -278.669823) (xy 341.606134 -278.652371) (xy 341.654353 -278.642527)
			(xy 341.703528 -278.640546) (xy 341.752383 -278.646478) (xy 341.799654 -278.66017) (xy 341.844116 -278.681268)
			(xy 341.884619 -278.709224) (xy 341.920112 -278.743316) (xy 341.949677 -278.78266) (xy 341.972548 -278.826237)
			(xy 341.988132 -278.872918) (xy 341.996027 -278.921495) (xy 341.996522 -278.946102) (xy 342.314779 -278.946102)
			(xy 342.318874 -278.895374) (xy 342.331053 -278.84596) (xy 342.351001 -278.79914) (xy 342.378202 -278.756126)
			(xy 342.41195 -278.718032) (xy 342.451372 -278.685845) (xy 342.495446 -278.660399) (xy 342.543032 -278.642352)
			(xy 342.592896 -278.632172) (xy 342.643748 -278.630123) (xy 342.694269 -278.636257) (xy 342.743153 -278.650417)
			(xy 342.789132 -278.672234) (xy 342.831016 -278.701144) (xy 342.86772 -278.736399) (xy 342.898293 -278.777085)
			(xy 342.921944 -278.822148) (xy 342.93806 -278.870422) (xy 342.946224 -278.920656) (xy 342.946736 -278.946102)
			(xy 343.254833 -278.946102) (xy 343.258928 -278.895374) (xy 343.271107 -278.84596) (xy 343.291055 -278.79914)
			(xy 343.318256 -278.756126) (xy 343.352004 -278.718032) (xy 343.391426 -278.685845) (xy 343.4355 -278.660399)
			(xy 343.483086 -278.642352) (xy 343.53295 -278.632172) (xy 343.583802 -278.630123) (xy 343.634323 -278.636257)
			(xy 343.683207 -278.650417) (xy 343.729186 -278.672234) (xy 343.77107 -278.701144) (xy 343.807774 -278.736399)
			(xy 343.838347 -278.777085) (xy 343.861998 -278.822148) (xy 343.878114 -278.870422) (xy 343.886278 -278.920656)
			(xy 343.88679 -278.946102) (xy 343.886278 -278.971548) (xy 343.878114 -279.021782) (xy 343.861998 -279.070056)
			(xy 343.838347 -279.115119) (xy 343.807774 -279.155805) (xy 343.77107 -279.19106) (xy 343.729186 -279.21997)
			(xy 343.683207 -279.241787) (xy 343.634323 -279.255947) (xy 343.583802 -279.262081) (xy 343.53295 -279.260032)
			(xy 343.483086 -279.249852) (xy 343.4355 -279.231805) (xy 343.391426 -279.206359) (xy 343.352004 -279.174172)
			(xy 343.318256 -279.136078) (xy 343.291055 -279.093064) (xy 343.271107 -279.046244) (xy 343.258928 -278.99683)
			(xy 343.254833 -278.946102) (xy 342.946736 -278.946102) (xy 342.946224 -278.971548) (xy 342.93806 -279.021782)
			(xy 342.921944 -279.070056) (xy 342.898293 -279.115119) (xy 342.86772 -279.155805) (xy 342.831016 -279.19106)
			(xy 342.789132 -279.21997) (xy 342.743153 -279.241787) (xy 342.694269 -279.255947) (xy 342.643748 -279.262081)
			(xy 342.592896 -279.260032) (xy 342.543032 -279.249852) (xy 342.495446 -279.231805) (xy 342.451372 -279.206359)
			(xy 342.41195 -279.174172) (xy 342.378202 -279.136078) (xy 342.351001 -279.093064) (xy 342.331053 -279.046244)
			(xy 342.318874 -278.99683) (xy 342.314779 -278.946102) (xy 341.996522 -278.946102) (xy 341.996027 -278.970709)
			(xy 341.988132 -279.019286) (xy 341.972548 -279.065967) (xy 341.949677 -279.109544) (xy 341.920112 -279.148888)
			(xy 341.884619 -279.18298) (xy 341.844116 -279.210936) (xy 341.799654 -279.232034) (xy 341.752383 -279.245726)
			(xy 341.703528 -279.251658) (xy 341.654353 -279.249677) (xy 341.606134 -279.239833) (xy 341.560118 -279.222381)
			(xy 341.517497 -279.197774) (xy 341.479376 -279.166649) (xy 341.446741 -279.129812) (xy 341.420438 -279.088216)
			(xy 341.401147 -279.04294) (xy 341.38937 -278.995156) (xy 341.38541 -278.946102) (xy 341.066882 -278.946102)
			(xy 341.06637 -278.971548) (xy 341.058206 -279.021782) (xy 341.04209 -279.070056) (xy 341.018439 -279.115119)
			(xy 340.987866 -279.155805) (xy 340.951162 -279.19106) (xy 340.909278 -279.21997) (xy 340.863299 -279.241787)
			(xy 340.814415 -279.255947) (xy 340.763894 -279.262081) (xy 340.713042 -279.260032) (xy 340.663178 -279.249852)
			(xy 340.615592 -279.231805) (xy 340.571518 -279.206359) (xy 340.532096 -279.174172) (xy 340.498348 -279.136078)
			(xy 340.471147 -279.093064) (xy 340.451199 -279.046244) (xy 340.43902 -278.99683) (xy 340.434925 -278.946102)
			(xy 340.116414 -278.946102) (xy 340.115919 -278.970709) (xy 340.108024 -279.019286) (xy 340.09244 -279.065967)
			(xy 340.069569 -279.109544) (xy 340.040004 -279.148888) (xy 340.004511 -279.18298) (xy 339.964008 -279.210936)
			(xy 339.919546 -279.232034) (xy 339.872275 -279.245726) (xy 339.82342 -279.251658) (xy 339.774245 -279.249677)
			(xy 339.726026 -279.239833) (xy 339.68001 -279.222381) (xy 339.637389 -279.197774) (xy 339.599268 -279.166649)
			(xy 339.566633 -279.129812) (xy 339.54033 -279.088216) (xy 339.521039 -279.04294) (xy 339.509262 -278.995156)
			(xy 339.505302 -278.946102) (xy 339.186774 -278.946102) (xy 339.186262 -278.971548) (xy 339.178098 -279.021782)
			(xy 339.161982 -279.070056) (xy 339.138331 -279.115119) (xy 339.107758 -279.155805) (xy 339.071054 -279.19106)
			(xy 339.02917 -279.21997) (xy 338.983191 -279.241787) (xy 338.934307 -279.255947) (xy 338.883786 -279.262081)
			(xy 338.832934 -279.260032) (xy 338.78307 -279.249852) (xy 338.735484 -279.231805) (xy 338.69141 -279.206359)
			(xy 338.651988 -279.174172) (xy 338.61824 -279.136078) (xy 338.591039 -279.093064) (xy 338.571091 -279.046244)
			(xy 338.558912 -278.99683) (xy 338.554817 -278.946102) (xy 338.236306 -278.946102) (xy 338.235811 -278.970709)
			(xy 338.227916 -279.019286) (xy 338.212332 -279.065967) (xy 338.189461 -279.109544) (xy 338.159896 -279.148888)
			(xy 338.124403 -279.18298) (xy 338.0839 -279.210936) (xy 338.039438 -279.232034) (xy 337.992167 -279.245726)
			(xy 337.943312 -279.251658) (xy 337.894137 -279.249677) (xy 337.845918 -279.239833) (xy 337.799902 -279.222381)
			(xy 337.757281 -279.197774) (xy 337.71916 -279.166649) (xy 337.686525 -279.129812) (xy 337.660222 -279.088216)
			(xy 337.640931 -279.04294) (xy 337.629154 -278.995156) (xy 337.625194 -278.946102) (xy 337.296506 -278.946102)
			(xy 337.296011 -278.970709) (xy 337.288116 -279.019286) (xy 337.272532 -279.065967) (xy 337.249661 -279.109544)
			(xy 337.220096 -279.148888) (xy 337.184603 -279.18298) (xy 337.1441 -279.210936) (xy 337.099638 -279.232034)
			(xy 337.052367 -279.245726) (xy 337.003512 -279.251658) (xy 336.954337 -279.249677) (xy 336.906118 -279.239833)
			(xy 336.860102 -279.222381) (xy 336.817481 -279.197774) (xy 336.77936 -279.166649) (xy 336.746725 -279.129812)
			(xy 336.720422 -279.088216) (xy 336.701131 -279.04294) (xy 336.689354 -278.995156) (xy 336.685394 -278.946102)
			(xy 336.356452 -278.946102) (xy 336.355957 -278.970709) (xy 336.348062 -279.019286) (xy 336.332478 -279.065967)
			(xy 336.309607 -279.109544) (xy 336.280042 -279.148888) (xy 336.244549 -279.18298) (xy 336.204046 -279.210936)
			(xy 336.159584 -279.232034) (xy 336.112313 -279.245726) (xy 336.063458 -279.251658) (xy 336.014283 -279.249677)
			(xy 335.966064 -279.239833) (xy 335.920048 -279.222381) (xy 335.877427 -279.197774) (xy 335.839306 -279.166649)
			(xy 335.806671 -279.129812) (xy 335.780368 -279.088216) (xy 335.761077 -279.04294) (xy 335.7493 -278.995156)
			(xy 335.74534 -278.946102) (xy 335.416958 -278.946102) (xy 335.412786 -278.996444) (xy 335.400385 -279.045414)
			(xy 335.380093 -279.091675) (xy 335.352462 -279.133965) (xy 335.318248 -279.171131) (xy 335.278383 -279.202158)
			(xy 335.233955 -279.2262) (xy 335.186176 -279.242601) (xy 335.136348 -279.250914) (xy 335.11109 -279.25141)
			(xy 335.110582 -279.25141) (xy 335.097433 -279.251261) (xy 335.071234 -279.248968) (xy 335.058258 -279.246838)
			(xy 335.054448 -279.24633) (xy 335.04378 -279.249378) (xy 335.03889 -279.250911) (xy 335.029803 -279.255645)
			(xy 335.025746 -279.258776) (xy 334.967072 -279.309068) (xy 334.959448 -279.316632) (xy 334.950639 -279.336191)
			(xy 334.950054 -279.346914) (xy 334.950054 -279.756108) (xy 335.275186 -279.756108) (xy 335.279146 -279.707054)
			(xy 335.290923 -279.65927) (xy 335.310214 -279.613994) (xy 335.336517 -279.572398) (xy 335.369152 -279.535561)
			(xy 335.407273 -279.504436) (xy 335.449894 -279.479829) (xy 335.49591 -279.462377) (xy 335.544129 -279.452533)
			(xy 335.593304 -279.450552) (xy 335.642159 -279.456484) (xy 335.68943 -279.470176) (xy 335.733892 -279.491274)
			(xy 335.774395 -279.51923) (xy 335.809888 -279.553322) (xy 335.839453 -279.592666) (xy 335.862324 -279.636243)
			(xy 335.877908 -279.682924) (xy 335.885803 -279.731501) (xy 335.886298 -279.756108) (xy 336.21524 -279.756108)
			(xy 336.2192 -279.707054) (xy 336.230977 -279.65927) (xy 336.250268 -279.613994) (xy 336.276571 -279.572398)
			(xy 336.309206 -279.535561) (xy 336.347327 -279.504436) (xy 336.389948 -279.479829) (xy 336.435964 -279.462377)
			(xy 336.484183 -279.452533) (xy 336.533358 -279.450552) (xy 336.582213 -279.456484) (xy 336.629484 -279.470176)
			(xy 336.673946 -279.491274) (xy 336.714449 -279.51923) (xy 336.749942 -279.553322) (xy 336.779507 -279.592666)
			(xy 336.802378 -279.636243) (xy 336.817962 -279.682924) (xy 336.825857 -279.731501) (xy 336.826352 -279.756108)
			(xy 337.155294 -279.756108) (xy 337.159254 -279.707054) (xy 337.171031 -279.65927) (xy 337.190322 -279.613994)
			(xy 337.216625 -279.572398) (xy 337.24926 -279.535561) (xy 337.287381 -279.504436) (xy 337.330002 -279.479829)
			(xy 337.376018 -279.462377) (xy 337.424237 -279.452533) (xy 337.473412 -279.450552) (xy 337.522267 -279.456484)
			(xy 337.569538 -279.470176) (xy 337.614 -279.491274) (xy 337.654503 -279.51923) (xy 337.689996 -279.553322)
			(xy 337.719561 -279.592666) (xy 337.742432 -279.636243) (xy 337.758016 -279.682924) (xy 337.765911 -279.731501)
			(xy 337.766406 -279.756108) (xy 338.095348 -279.756108) (xy 338.099308 -279.707054) (xy 338.111085 -279.65927)
			(xy 338.130376 -279.613994) (xy 338.156679 -279.572398) (xy 338.189314 -279.535561) (xy 338.227435 -279.504436)
			(xy 338.270056 -279.479829) (xy 338.316072 -279.462377) (xy 338.364291 -279.452533) (xy 338.413466 -279.450552)
			(xy 338.462321 -279.456484) (xy 338.509592 -279.470176) (xy 338.554054 -279.491274) (xy 338.594557 -279.51923)
			(xy 338.63005 -279.553322) (xy 338.659615 -279.592666) (xy 338.682486 -279.636243) (xy 338.69807 -279.682924)
			(xy 338.705965 -279.731501) (xy 338.70646 -279.756108) (xy 339.024971 -279.756108) (xy 339.029066 -279.70538)
			(xy 339.041245 -279.655966) (xy 339.061193 -279.609146) (xy 339.088394 -279.566132) (xy 339.122142 -279.528038)
			(xy 339.161564 -279.495851) (xy 339.205638 -279.470405) (xy 339.253224 -279.452358) (xy 339.303088 -279.442178)
			(xy 339.35394 -279.440129) (xy 339.404461 -279.446263) (xy 339.453345 -279.460423) (xy 339.499324 -279.48224)
			(xy 339.541208 -279.51115) (xy 339.577912 -279.546405) (xy 339.608485 -279.587091) (xy 339.632136 -279.632154)
			(xy 339.648252 -279.680428) (xy 339.656416 -279.730662) (xy 339.656928 -279.756108) (xy 339.964771 -279.756108)
			(xy 339.968866 -279.70538) (xy 339.981045 -279.655966) (xy 340.000993 -279.609146) (xy 340.028194 -279.566132)
			(xy 340.061942 -279.528038) (xy 340.101364 -279.495851) (xy 340.145438 -279.470405) (xy 340.193024 -279.452358)
			(xy 340.242888 -279.442178) (xy 340.29374 -279.440129) (xy 340.344261 -279.446263) (xy 340.393145 -279.460423)
			(xy 340.439124 -279.48224) (xy 340.481008 -279.51115) (xy 340.517712 -279.546405) (xy 340.548285 -279.587091)
			(xy 340.571936 -279.632154) (xy 340.588052 -279.680428) (xy 340.596216 -279.730662) (xy 340.596728 -279.756108)
			(xy 340.915256 -279.756108) (xy 340.919216 -279.707054) (xy 340.930993 -279.65927) (xy 340.950284 -279.613994)
			(xy 340.976587 -279.572398) (xy 341.009222 -279.535561) (xy 341.047343 -279.504436) (xy 341.089964 -279.479829)
			(xy 341.13598 -279.462377) (xy 341.184199 -279.452533) (xy 341.233374 -279.450552) (xy 341.282229 -279.456484)
			(xy 341.3295 -279.470176) (xy 341.373962 -279.491274) (xy 341.414465 -279.51923) (xy 341.449958 -279.553322)
			(xy 341.479523 -279.592666) (xy 341.502394 -279.636243) (xy 341.517978 -279.682924) (xy 341.525873 -279.731501)
			(xy 341.526368 -279.756108) (xy 341.844879 -279.756108) (xy 341.848974 -279.70538) (xy 341.861153 -279.655966)
			(xy 341.881101 -279.609146) (xy 341.908302 -279.566132) (xy 341.94205 -279.528038) (xy 341.981472 -279.495851)
			(xy 342.025546 -279.470405) (xy 342.073132 -279.452358) (xy 342.122996 -279.442178) (xy 342.173848 -279.440129)
			(xy 342.224369 -279.446263) (xy 342.273253 -279.460423) (xy 342.319232 -279.48224) (xy 342.361116 -279.51115)
			(xy 342.39782 -279.546405) (xy 342.428393 -279.587091) (xy 342.452044 -279.632154) (xy 342.46816 -279.680428)
			(xy 342.476324 -279.730662) (xy 342.476836 -279.756108) (xy 342.795364 -279.756108) (xy 342.799324 -279.707054)
			(xy 342.811101 -279.65927) (xy 342.830392 -279.613994) (xy 342.856695 -279.572398) (xy 342.88933 -279.535561)
			(xy 342.927451 -279.504436) (xy 342.970072 -279.479829) (xy 343.016088 -279.462377) (xy 343.064307 -279.452533)
			(xy 343.113482 -279.450552) (xy 343.162337 -279.456484) (xy 343.209608 -279.470176) (xy 343.25407 -279.491274)
			(xy 343.294573 -279.51923) (xy 343.330066 -279.553322) (xy 343.359631 -279.592666) (xy 343.382502 -279.636243)
			(xy 343.398086 -279.682924) (xy 343.405981 -279.731501) (xy 343.406476 -279.756108) (xy 343.405981 -279.780715)
			(xy 343.398086 -279.829292) (xy 343.382502 -279.875973) (xy 343.359631 -279.91955) (xy 343.330066 -279.958894)
			(xy 343.294573 -279.992986) (xy 343.25407 -280.020942) (xy 343.209608 -280.04204) (xy 343.162337 -280.055732)
			(xy 343.113482 -280.061664) (xy 343.064307 -280.059683) (xy 343.016088 -280.049839) (xy 342.970072 -280.032387)
			(xy 342.927451 -280.00778) (xy 342.88933 -279.976655) (xy 342.856695 -279.939818) (xy 342.830392 -279.898222)
			(xy 342.811101 -279.852946) (xy 342.799324 -279.805162) (xy 342.795364 -279.756108) (xy 342.476836 -279.756108)
			(xy 342.476324 -279.781554) (xy 342.46816 -279.831788) (xy 342.452044 -279.880062) (xy 342.428393 -279.925125)
			(xy 342.39782 -279.965811) (xy 342.361116 -280.001066) (xy 342.319232 -280.029976) (xy 342.273253 -280.051793)
			(xy 342.224369 -280.065953) (xy 342.173848 -280.072087) (xy 342.122996 -280.070038) (xy 342.073132 -280.059858)
			(xy 342.025546 -280.041811) (xy 341.981472 -280.016365) (xy 341.94205 -279.984178) (xy 341.908302 -279.946084)
			(xy 341.881101 -279.90307) (xy 341.861153 -279.85625) (xy 341.848974 -279.806836) (xy 341.844879 -279.756108)
			(xy 341.526368 -279.756108) (xy 341.525873 -279.780715) (xy 341.517978 -279.829292) (xy 341.502394 -279.875973)
			(xy 341.479523 -279.91955) (xy 341.449958 -279.958894) (xy 341.414465 -279.992986) (xy 341.373962 -280.020942)
			(xy 341.3295 -280.04204) (xy 341.282229 -280.055732) (xy 341.233374 -280.061664) (xy 341.184199 -280.059683)
			(xy 341.13598 -280.049839) (xy 341.089964 -280.032387) (xy 341.047343 -280.00778) (xy 341.009222 -279.976655)
			(xy 340.976587 -279.939818) (xy 340.950284 -279.898222) (xy 340.930993 -279.852946) (xy 340.919216 -279.805162)
			(xy 340.915256 -279.756108) (xy 340.596728 -279.756108) (xy 340.596216 -279.781554) (xy 340.588052 -279.831788)
			(xy 340.571936 -279.880062) (xy 340.548285 -279.925125) (xy 340.517712 -279.965811) (xy 340.481008 -280.001066)
			(xy 340.439124 -280.029976) (xy 340.393145 -280.051793) (xy 340.344261 -280.065953) (xy 340.29374 -280.072087)
			(xy 340.242888 -280.070038) (xy 340.193024 -280.059858) (xy 340.145438 -280.041811) (xy 340.101364 -280.016365)
			(xy 340.061942 -279.984178) (xy 340.028194 -279.946084) (xy 340.000993 -279.90307) (xy 339.981045 -279.85625)
			(xy 339.968866 -279.806836) (xy 339.964771 -279.756108) (xy 339.656928 -279.756108) (xy 339.656416 -279.781554)
			(xy 339.648252 -279.831788) (xy 339.632136 -279.880062) (xy 339.608485 -279.925125) (xy 339.577912 -279.965811)
			(xy 339.541208 -280.001066) (xy 339.499324 -280.029976) (xy 339.453345 -280.051793) (xy 339.404461 -280.065953)
			(xy 339.35394 -280.072087) (xy 339.303088 -280.070038) (xy 339.253224 -280.059858) (xy 339.205638 -280.041811)
			(xy 339.161564 -280.016365) (xy 339.122142 -279.984178) (xy 339.088394 -279.946084) (xy 339.061193 -279.90307)
			(xy 339.041245 -279.85625) (xy 339.029066 -279.806836) (xy 339.024971 -279.756108) (xy 338.70646 -279.756108)
			(xy 338.705965 -279.780715) (xy 338.69807 -279.829292) (xy 338.682486 -279.875973) (xy 338.659615 -279.91955)
			(xy 338.63005 -279.958894) (xy 338.594557 -279.992986) (xy 338.554054 -280.020942) (xy 338.509592 -280.04204)
			(xy 338.462321 -280.055732) (xy 338.413466 -280.061664) (xy 338.364291 -280.059683) (xy 338.316072 -280.049839)
			(xy 338.270056 -280.032387) (xy 338.227435 -280.00778) (xy 338.189314 -279.976655) (xy 338.156679 -279.939818)
			(xy 338.130376 -279.898222) (xy 338.111085 -279.852946) (xy 338.099308 -279.805162) (xy 338.095348 -279.756108)
			(xy 337.766406 -279.756108) (xy 337.765911 -279.780715) (xy 337.758016 -279.829292) (xy 337.742432 -279.875973)
			(xy 337.719561 -279.91955) (xy 337.689996 -279.958894) (xy 337.654503 -279.992986) (xy 337.614 -280.020942)
			(xy 337.569538 -280.04204) (xy 337.522267 -280.055732) (xy 337.473412 -280.061664) (xy 337.424237 -280.059683)
			(xy 337.376018 -280.049839) (xy 337.330002 -280.032387) (xy 337.287381 -280.00778) (xy 337.24926 -279.976655)
			(xy 337.216625 -279.939818) (xy 337.190322 -279.898222) (xy 337.171031 -279.852946) (xy 337.159254 -279.805162)
			(xy 337.155294 -279.756108) (xy 336.826352 -279.756108) (xy 336.825857 -279.780715) (xy 336.817962 -279.829292)
			(xy 336.802378 -279.875973) (xy 336.779507 -279.91955) (xy 336.749942 -279.958894) (xy 336.714449 -279.992986)
			(xy 336.673946 -280.020942) (xy 336.629484 -280.04204) (xy 336.582213 -280.055732) (xy 336.533358 -280.061664)
			(xy 336.484183 -280.059683) (xy 336.435964 -280.049839) (xy 336.389948 -280.032387) (xy 336.347327 -280.00778)
			(xy 336.309206 -279.976655) (xy 336.276571 -279.939818) (xy 336.250268 -279.898222) (xy 336.230977 -279.852946)
			(xy 336.2192 -279.805162) (xy 336.21524 -279.756108) (xy 335.886298 -279.756108) (xy 335.885803 -279.780715)
			(xy 335.877908 -279.829292) (xy 335.862324 -279.875973) (xy 335.839453 -279.91955) (xy 335.809888 -279.958894)
			(xy 335.774395 -279.992986) (xy 335.733892 -280.020942) (xy 335.68943 -280.04204) (xy 335.642159 -280.055732)
			(xy 335.593304 -280.061664) (xy 335.544129 -280.059683) (xy 335.49591 -280.049839) (xy 335.449894 -280.032387)
			(xy 335.407273 -280.00778) (xy 335.369152 -279.976655) (xy 335.336517 -279.939818) (xy 335.310214 -279.898222)
			(xy 335.290923 -279.852946) (xy 335.279146 -279.805162) (xy 335.275186 -279.756108) (xy 334.950054 -279.756108)
			(xy 334.950054 -280.566114) (xy 335.74534 -280.566114) (xy 335.7493 -280.51706) (xy 335.761077 -280.469276)
			(xy 335.780368 -280.424) (xy 335.806671 -280.382404) (xy 335.839306 -280.345567) (xy 335.877427 -280.314442)
			(xy 335.920048 -280.289835) (xy 335.966064 -280.272383) (xy 336.014283 -280.262539) (xy 336.063458 -280.260558)
			(xy 336.112313 -280.26649) (xy 336.159584 -280.280182) (xy 336.204046 -280.30128) (xy 336.244549 -280.329236)
			(xy 336.280042 -280.363328) (xy 336.309607 -280.402672) (xy 336.332478 -280.446249) (xy 336.348062 -280.49293)
			(xy 336.355957 -280.541507) (xy 336.356452 -280.566114) (xy 336.685394 -280.566114) (xy 336.689354 -280.51706)
			(xy 336.701131 -280.469276) (xy 336.720422 -280.424) (xy 336.746725 -280.382404) (xy 336.77936 -280.345567)
			(xy 336.817481 -280.314442) (xy 336.860102 -280.289835) (xy 336.906118 -280.272383) (xy 336.954337 -280.262539)
			(xy 337.003512 -280.260558) (xy 337.052367 -280.26649) (xy 337.099638 -280.280182) (xy 337.1441 -280.30128)
			(xy 337.184603 -280.329236) (xy 337.220096 -280.363328) (xy 337.249661 -280.402672) (xy 337.272532 -280.446249)
			(xy 337.288116 -280.49293) (xy 337.296011 -280.541507) (xy 337.296506 -280.566114) (xy 337.625194 -280.566114)
			(xy 337.629154 -280.51706) (xy 337.640931 -280.469276) (xy 337.660222 -280.424) (xy 337.686525 -280.382404)
			(xy 337.71916 -280.345567) (xy 337.757281 -280.314442) (xy 337.799902 -280.289835) (xy 337.845918 -280.272383)
			(xy 337.894137 -280.262539) (xy 337.943312 -280.260558) (xy 337.992167 -280.26649) (xy 338.039438 -280.280182)
			(xy 338.0839 -280.30128) (xy 338.124403 -280.329236) (xy 338.159896 -280.363328) (xy 338.189461 -280.402672)
			(xy 338.212332 -280.446249) (xy 338.227916 -280.49293) (xy 338.235811 -280.541507) (xy 338.236306 -280.566114)
			(xy 338.554817 -280.566114) (xy 338.558912 -280.515386) (xy 338.571091 -280.465972) (xy 338.591039 -280.419152)
			(xy 338.61824 -280.376138) (xy 338.651988 -280.338044) (xy 338.69141 -280.305857) (xy 338.735484 -280.280411)
			(xy 338.78307 -280.262364) (xy 338.832934 -280.252184) (xy 338.883786 -280.250135) (xy 338.934307 -280.256269)
			(xy 338.983191 -280.270429) (xy 339.02917 -280.292246) (xy 339.071054 -280.321156) (xy 339.107758 -280.356411)
			(xy 339.138331 -280.397097) (xy 339.161982 -280.44216) (xy 339.178098 -280.490434) (xy 339.186262 -280.540668)
			(xy 339.186774 -280.566114) (xy 339.505302 -280.566114) (xy 339.509262 -280.51706) (xy 339.521039 -280.469276)
			(xy 339.54033 -280.424) (xy 339.566633 -280.382404) (xy 339.599268 -280.345567) (xy 339.637389 -280.314442)
			(xy 339.68001 -280.289835) (xy 339.726026 -280.272383) (xy 339.774245 -280.262539) (xy 339.82342 -280.260558)
			(xy 339.872275 -280.26649) (xy 339.919546 -280.280182) (xy 339.964008 -280.30128) (xy 340.004511 -280.329236)
			(xy 340.040004 -280.363328) (xy 340.069569 -280.402672) (xy 340.09244 -280.446249) (xy 340.108024 -280.49293)
			(xy 340.115919 -280.541507) (xy 340.116414 -280.566114) (xy 340.434925 -280.566114) (xy 340.43902 -280.515386)
			(xy 340.451199 -280.465972) (xy 340.471147 -280.419152) (xy 340.498348 -280.376138) (xy 340.532096 -280.338044)
			(xy 340.571518 -280.305857) (xy 340.615592 -280.280411) (xy 340.663178 -280.262364) (xy 340.713042 -280.252184)
			(xy 340.763894 -280.250135) (xy 340.814415 -280.256269) (xy 340.863299 -280.270429) (xy 340.909278 -280.292246)
			(xy 340.951162 -280.321156) (xy 340.987866 -280.356411) (xy 341.018439 -280.397097) (xy 341.04209 -280.44216)
			(xy 341.058206 -280.490434) (xy 341.06637 -280.540668) (xy 341.066882 -280.566114) (xy 342.314779 -280.566114)
			(xy 342.318874 -280.515386) (xy 342.331053 -280.465972) (xy 342.351001 -280.419152) (xy 342.378202 -280.376138)
			(xy 342.41195 -280.338044) (xy 342.451372 -280.305857) (xy 342.495446 -280.280411) (xy 342.543032 -280.262364)
			(xy 342.592896 -280.252184) (xy 342.643748 -280.250135) (xy 342.694269 -280.256269) (xy 342.743153 -280.270429)
			(xy 342.789132 -280.292246) (xy 342.831016 -280.321156) (xy 342.86772 -280.356411) (xy 342.898293 -280.397097)
			(xy 342.921944 -280.44216) (xy 342.93806 -280.490434) (xy 342.946224 -280.540668) (xy 342.946736 -280.566114)
			(xy 343.254833 -280.566114) (xy 343.258928 -280.515386) (xy 343.271107 -280.465972) (xy 343.291055 -280.419152)
			(xy 343.318256 -280.376138) (xy 343.352004 -280.338044) (xy 343.391426 -280.305857) (xy 343.4355 -280.280411)
			(xy 343.483086 -280.262364) (xy 343.53295 -280.252184) (xy 343.583802 -280.250135) (xy 343.634323 -280.256269)
			(xy 343.683207 -280.270429) (xy 343.729186 -280.292246) (xy 343.77107 -280.321156) (xy 343.807774 -280.356411)
			(xy 343.838347 -280.397097) (xy 343.861998 -280.44216) (xy 343.878114 -280.490434) (xy 343.886278 -280.540668)
			(xy 343.88679 -280.566114) (xy 343.886278 -280.59156) (xy 343.878114 -280.641794) (xy 343.861998 -280.690068)
			(xy 343.838347 -280.735131) (xy 343.807774 -280.775817) (xy 343.77107 -280.811072) (xy 343.729186 -280.839982)
			(xy 343.683207 -280.861799) (xy 343.634323 -280.875959) (xy 343.583802 -280.882093) (xy 343.53295 -280.880044)
			(xy 343.483086 -280.869864) (xy 343.4355 -280.851817) (xy 343.391426 -280.826371) (xy 343.352004 -280.794184)
			(xy 343.318256 -280.75609) (xy 343.291055 -280.713076) (xy 343.271107 -280.666256) (xy 343.258928 -280.616842)
			(xy 343.254833 -280.566114) (xy 342.946736 -280.566114) (xy 342.946224 -280.59156) (xy 342.93806 -280.641794)
			(xy 342.921944 -280.690068) (xy 342.898293 -280.735131) (xy 342.86772 -280.775817) (xy 342.831016 -280.811072)
			(xy 342.789132 -280.839982) (xy 342.743153 -280.861799) (xy 342.694269 -280.875959) (xy 342.643748 -280.882093)
			(xy 342.592896 -280.880044) (xy 342.543032 -280.869864) (xy 342.495446 -280.851817) (xy 342.451372 -280.826371)
			(xy 342.41195 -280.794184) (xy 342.378202 -280.75609) (xy 342.351001 -280.713076) (xy 342.331053 -280.666256)
			(xy 342.318874 -280.616842) (xy 342.314779 -280.566114) (xy 341.066882 -280.566114) (xy 341.06637 -280.59156)
			(xy 341.058206 -280.641794) (xy 341.04209 -280.690068) (xy 341.018439 -280.735131) (xy 340.987866 -280.775817)
			(xy 340.951162 -280.811072) (xy 340.909278 -280.839982) (xy 340.863299 -280.861799) (xy 340.814415 -280.875959)
			(xy 340.763894 -280.882093) (xy 340.713042 -280.880044) (xy 340.663178 -280.869864) (xy 340.615592 -280.851817)
			(xy 340.571518 -280.826371) (xy 340.532096 -280.794184) (xy 340.498348 -280.75609) (xy 340.471147 -280.713076)
			(xy 340.451199 -280.666256) (xy 340.43902 -280.616842) (xy 340.434925 -280.566114) (xy 340.116414 -280.566114)
			(xy 340.115919 -280.590721) (xy 340.108024 -280.639298) (xy 340.09244 -280.685979) (xy 340.069569 -280.729556)
			(xy 340.040004 -280.7689) (xy 340.004511 -280.802992) (xy 339.964008 -280.830948) (xy 339.919546 -280.852046)
			(xy 339.872275 -280.865738) (xy 339.82342 -280.87167) (xy 339.774245 -280.869689) (xy 339.726026 -280.859845)
			(xy 339.68001 -280.842393) (xy 339.637389 -280.817786) (xy 339.599268 -280.786661) (xy 339.566633 -280.749824)
			(xy 339.54033 -280.708228) (xy 339.521039 -280.662952) (xy 339.509262 -280.615168) (xy 339.505302 -280.566114)
			(xy 339.186774 -280.566114) (xy 339.186262 -280.59156) (xy 339.178098 -280.641794) (xy 339.161982 -280.690068)
			(xy 339.138331 -280.735131) (xy 339.107758 -280.775817) (xy 339.071054 -280.811072) (xy 339.02917 -280.839982)
			(xy 338.983191 -280.861799) (xy 338.934307 -280.875959) (xy 338.883786 -280.882093) (xy 338.832934 -280.880044)
			(xy 338.78307 -280.869864) (xy 338.735484 -280.851817) (xy 338.69141 -280.826371) (xy 338.651988 -280.794184)
			(xy 338.61824 -280.75609) (xy 338.591039 -280.713076) (xy 338.571091 -280.666256) (xy 338.558912 -280.616842)
			(xy 338.554817 -280.566114) (xy 338.236306 -280.566114) (xy 338.235811 -280.590721) (xy 338.227916 -280.639298)
			(xy 338.212332 -280.685979) (xy 338.189461 -280.729556) (xy 338.159896 -280.7689) (xy 338.124403 -280.802992)
			(xy 338.0839 -280.830948) (xy 338.039438 -280.852046) (xy 337.992167 -280.865738) (xy 337.943312 -280.87167)
			(xy 337.894137 -280.869689) (xy 337.845918 -280.859845) (xy 337.799902 -280.842393) (xy 337.757281 -280.817786)
			(xy 337.71916 -280.786661) (xy 337.686525 -280.749824) (xy 337.660222 -280.708228) (xy 337.640931 -280.662952)
			(xy 337.629154 -280.615168) (xy 337.625194 -280.566114) (xy 337.296506 -280.566114) (xy 337.296011 -280.590721)
			(xy 337.288116 -280.639298) (xy 337.272532 -280.685979) (xy 337.249661 -280.729556) (xy 337.220096 -280.7689)
			(xy 337.184603 -280.802992) (xy 337.1441 -280.830948) (xy 337.099638 -280.852046) (xy 337.052367 -280.865738)
			(xy 337.003512 -280.87167) (xy 336.954337 -280.869689) (xy 336.906118 -280.859845) (xy 336.860102 -280.842393)
			(xy 336.817481 -280.817786) (xy 336.77936 -280.786661) (xy 336.746725 -280.749824) (xy 336.720422 -280.708228)
			(xy 336.701131 -280.662952) (xy 336.689354 -280.615168) (xy 336.685394 -280.566114) (xy 336.356452 -280.566114)
			(xy 336.355957 -280.590721) (xy 336.348062 -280.639298) (xy 336.332478 -280.685979) (xy 336.309607 -280.729556)
			(xy 336.280042 -280.7689) (xy 336.244549 -280.802992) (xy 336.204046 -280.830948) (xy 336.159584 -280.852046)
			(xy 336.112313 -280.865738) (xy 336.063458 -280.87167) (xy 336.014283 -280.869689) (xy 335.966064 -280.859845)
			(xy 335.920048 -280.842393) (xy 335.877427 -280.817786) (xy 335.839306 -280.786661) (xy 335.806671 -280.749824)
			(xy 335.780368 -280.708228) (xy 335.761077 -280.662952) (xy 335.7493 -280.615168) (xy 335.74534 -280.566114)
			(xy 334.950054 -280.566114) (xy 334.950054 -281.37612) (xy 335.275186 -281.37612) (xy 335.279146 -281.327066)
			(xy 335.290923 -281.279282) (xy 335.310214 -281.234006) (xy 335.336517 -281.19241) (xy 335.369152 -281.155573)
			(xy 335.407273 -281.124448) (xy 335.449894 -281.099841) (xy 335.49591 -281.082389) (xy 335.544129 -281.072545)
			(xy 335.593304 -281.070564) (xy 335.642159 -281.076496) (xy 335.68943 -281.090188) (xy 335.733892 -281.111286)
			(xy 335.774395 -281.139242) (xy 335.809888 -281.173334) (xy 335.839453 -281.212678) (xy 335.862324 -281.256255)
			(xy 335.877908 -281.302936) (xy 335.885803 -281.351513) (xy 335.886298 -281.37612) (xy 336.21524 -281.37612)
			(xy 336.2192 -281.327066) (xy 336.230977 -281.279282) (xy 336.250268 -281.234006) (xy 336.276571 -281.19241)
			(xy 336.309206 -281.155573) (xy 336.347327 -281.124448) (xy 336.389948 -281.099841) (xy 336.435964 -281.082389)
			(xy 336.484183 -281.072545) (xy 336.533358 -281.070564) (xy 336.582213 -281.076496) (xy 336.629484 -281.090188)
			(xy 336.673946 -281.111286) (xy 336.714449 -281.139242) (xy 336.749942 -281.173334) (xy 336.779507 -281.212678)
			(xy 336.802378 -281.256255) (xy 336.817962 -281.302936) (xy 336.825857 -281.351513) (xy 336.826352 -281.37612)
			(xy 337.155294 -281.37612) (xy 337.159254 -281.327066) (xy 337.171031 -281.279282) (xy 337.190322 -281.234006)
			(xy 337.216625 -281.19241) (xy 337.24926 -281.155573) (xy 337.287381 -281.124448) (xy 337.330002 -281.099841)
			(xy 337.376018 -281.082389) (xy 337.424237 -281.072545) (xy 337.473412 -281.070564) (xy 337.522267 -281.076496)
			(xy 337.569538 -281.090188) (xy 337.614 -281.111286) (xy 337.654503 -281.139242) (xy 337.689996 -281.173334)
			(xy 337.719561 -281.212678) (xy 337.742432 -281.256255) (xy 337.758016 -281.302936) (xy 337.765911 -281.351513)
			(xy 337.766406 -281.37612) (xy 338.095348 -281.37612) (xy 338.099308 -281.327066) (xy 338.111085 -281.279282)
			(xy 338.130376 -281.234006) (xy 338.156679 -281.19241) (xy 338.189314 -281.155573) (xy 338.227435 -281.124448)
			(xy 338.270056 -281.099841) (xy 338.316072 -281.082389) (xy 338.364291 -281.072545) (xy 338.413466 -281.070564)
			(xy 338.462321 -281.076496) (xy 338.509592 -281.090188) (xy 338.554054 -281.111286) (xy 338.594557 -281.139242)
			(xy 338.63005 -281.173334) (xy 338.659615 -281.212678) (xy 338.682486 -281.256255) (xy 338.69807 -281.302936)
			(xy 338.705965 -281.351513) (xy 338.70646 -281.37612) (xy 339.024971 -281.37612) (xy 339.029066 -281.325392)
			(xy 339.041245 -281.275978) (xy 339.061193 -281.229158) (xy 339.088394 -281.186144) (xy 339.122142 -281.14805)
			(xy 339.161564 -281.115863) (xy 339.205638 -281.090417) (xy 339.253224 -281.07237) (xy 339.303088 -281.06219)
			(xy 339.35394 -281.060141) (xy 339.404461 -281.066275) (xy 339.453345 -281.080435) (xy 339.499324 -281.102252)
			(xy 339.541208 -281.131162) (xy 339.577912 -281.166417) (xy 339.608485 -281.207103) (xy 339.632136 -281.252166)
			(xy 339.648252 -281.30044) (xy 339.656416 -281.350674) (xy 339.656928 -281.37612) (xy 339.964771 -281.37612)
			(xy 339.968866 -281.325392) (xy 339.981045 -281.275978) (xy 340.000993 -281.229158) (xy 340.028194 -281.186144)
			(xy 340.061942 -281.14805) (xy 340.101364 -281.115863) (xy 340.145438 -281.090417) (xy 340.193024 -281.07237)
			(xy 340.242888 -281.06219) (xy 340.29374 -281.060141) (xy 340.344261 -281.066275) (xy 340.393145 -281.080435)
			(xy 340.439124 -281.102252) (xy 340.481008 -281.131162) (xy 340.517712 -281.166417) (xy 340.548285 -281.207103)
			(xy 340.571936 -281.252166) (xy 340.588052 -281.30044) (xy 340.596216 -281.350674) (xy 340.596728 -281.37612)
			(xy 340.915256 -281.37612) (xy 340.919216 -281.327066) (xy 340.930993 -281.279282) (xy 340.950284 -281.234006)
			(xy 340.976587 -281.19241) (xy 341.009222 -281.155573) (xy 341.047343 -281.124448) (xy 341.089964 -281.099841)
			(xy 341.13598 -281.082389) (xy 341.184199 -281.072545) (xy 341.233374 -281.070564) (xy 341.282229 -281.076496)
			(xy 341.3295 -281.090188) (xy 341.373962 -281.111286) (xy 341.414465 -281.139242) (xy 341.449958 -281.173334)
			(xy 341.479523 -281.212678) (xy 341.502394 -281.256255) (xy 341.517978 -281.302936) (xy 341.525873 -281.351513)
			(xy 341.526368 -281.37612) (xy 341.844879 -281.37612) (xy 341.848974 -281.325392) (xy 341.861153 -281.275978)
			(xy 341.881101 -281.229158) (xy 341.908302 -281.186144) (xy 341.94205 -281.14805) (xy 341.981472 -281.115863)
			(xy 342.025546 -281.090417) (xy 342.073132 -281.07237) (xy 342.122996 -281.06219) (xy 342.173848 -281.060141)
			(xy 342.224369 -281.066275) (xy 342.273253 -281.080435) (xy 342.319232 -281.102252) (xy 342.361116 -281.131162)
			(xy 342.39782 -281.166417) (xy 342.428393 -281.207103) (xy 342.452044 -281.252166) (xy 342.46816 -281.30044)
			(xy 342.476324 -281.350674) (xy 342.476836 -281.37612) (xy 342.795364 -281.37612) (xy 342.799324 -281.327066)
			(xy 342.811101 -281.279282) (xy 342.830392 -281.234006) (xy 342.856695 -281.19241) (xy 342.88933 -281.155573)
			(xy 342.927451 -281.124448) (xy 342.970072 -281.099841) (xy 343.016088 -281.082389) (xy 343.064307 -281.072545)
			(xy 343.113482 -281.070564) (xy 343.162337 -281.076496) (xy 343.209608 -281.090188) (xy 343.25407 -281.111286)
			(xy 343.294573 -281.139242) (xy 343.330066 -281.173334) (xy 343.359631 -281.212678) (xy 343.382502 -281.256255)
			(xy 343.398086 -281.302936) (xy 343.405981 -281.351513) (xy 343.406476 -281.37612) (xy 343.724987 -281.37612)
			(xy 343.729082 -281.325392) (xy 343.741261 -281.275978) (xy 343.761209 -281.229158) (xy 343.78841 -281.186144)
			(xy 343.822158 -281.14805) (xy 343.86158 -281.115863) (xy 343.905654 -281.090417) (xy 343.95324 -281.07237)
			(xy 344.003104 -281.06219) (xy 344.053956 -281.060141) (xy 344.104477 -281.066275) (xy 344.153361 -281.080435)
			(xy 344.19934 -281.102252) (xy 344.241224 -281.131162) (xy 344.277928 -281.166417) (xy 344.308501 -281.207103)
			(xy 344.332152 -281.252166) (xy 344.348268 -281.30044) (xy 344.356432 -281.350674) (xy 344.356944 -281.37612)
			(xy 344.356432 -281.401566) (xy 344.348268 -281.4518) (xy 344.332152 -281.500074) (xy 344.308501 -281.545137)
			(xy 344.277928 -281.585823) (xy 344.241224 -281.621078) (xy 344.19934 -281.649988) (xy 344.153361 -281.671805)
			(xy 344.104477 -281.685965) (xy 344.053956 -281.692099) (xy 344.003104 -281.69005) (xy 343.95324 -281.67987)
			(xy 343.905654 -281.661823) (xy 343.86158 -281.636377) (xy 343.822158 -281.60419) (xy 343.78841 -281.566096)
			(xy 343.761209 -281.523082) (xy 343.741261 -281.476262) (xy 343.729082 -281.426848) (xy 343.724987 -281.37612)
			(xy 343.406476 -281.37612) (xy 343.405981 -281.400727) (xy 343.398086 -281.449304) (xy 343.382502 -281.495985)
			(xy 343.359631 -281.539562) (xy 343.330066 -281.578906) (xy 343.294573 -281.612998) (xy 343.25407 -281.640954)
			(xy 343.209608 -281.662052) (xy 343.162337 -281.675744) (xy 343.113482 -281.681676) (xy 343.064307 -281.679695)
			(xy 343.016088 -281.669851) (xy 342.970072 -281.652399) (xy 342.927451 -281.627792) (xy 342.88933 -281.596667)
			(xy 342.856695 -281.55983) (xy 342.830392 -281.518234) (xy 342.811101 -281.472958) (xy 342.799324 -281.425174)
			(xy 342.795364 -281.37612) (xy 342.476836 -281.37612) (xy 342.476324 -281.401566) (xy 342.46816 -281.4518)
			(xy 342.452044 -281.500074) (xy 342.428393 -281.545137) (xy 342.39782 -281.585823) (xy 342.361116 -281.621078)
			(xy 342.319232 -281.649988) (xy 342.273253 -281.671805) (xy 342.224369 -281.685965) (xy 342.173848 -281.692099)
			(xy 342.122996 -281.69005) (xy 342.073132 -281.67987) (xy 342.025546 -281.661823) (xy 341.981472 -281.636377)
			(xy 341.94205 -281.60419) (xy 341.908302 -281.566096) (xy 341.881101 -281.523082) (xy 341.861153 -281.476262)
			(xy 341.848974 -281.426848) (xy 341.844879 -281.37612) (xy 341.526368 -281.37612) (xy 341.525873 -281.400727)
			(xy 341.517978 -281.449304) (xy 341.502394 -281.495985) (xy 341.479523 -281.539562) (xy 341.449958 -281.578906)
			(xy 341.414465 -281.612998) (xy 341.373962 -281.640954) (xy 341.3295 -281.662052) (xy 341.282229 -281.675744)
			(xy 341.233374 -281.681676) (xy 341.184199 -281.679695) (xy 341.13598 -281.669851) (xy 341.089964 -281.652399)
			(xy 341.047343 -281.627792) (xy 341.009222 -281.596667) (xy 340.976587 -281.55983) (xy 340.950284 -281.518234)
			(xy 340.930993 -281.472958) (xy 340.919216 -281.425174) (xy 340.915256 -281.37612) (xy 340.596728 -281.37612)
			(xy 340.596216 -281.401566) (xy 340.588052 -281.4518) (xy 340.571936 -281.500074) (xy 340.548285 -281.545137)
			(xy 340.517712 -281.585823) (xy 340.481008 -281.621078) (xy 340.439124 -281.649988) (xy 340.393145 -281.671805)
			(xy 340.344261 -281.685965) (xy 340.29374 -281.692099) (xy 340.242888 -281.69005) (xy 340.193024 -281.67987)
			(xy 340.145438 -281.661823) (xy 340.101364 -281.636377) (xy 340.061942 -281.60419) (xy 340.028194 -281.566096)
			(xy 340.000993 -281.523082) (xy 339.981045 -281.476262) (xy 339.968866 -281.426848) (xy 339.964771 -281.37612)
			(xy 339.656928 -281.37612) (xy 339.656416 -281.401566) (xy 339.648252 -281.4518) (xy 339.632136 -281.500074)
			(xy 339.608485 -281.545137) (xy 339.577912 -281.585823) (xy 339.541208 -281.621078) (xy 339.499324 -281.649988)
			(xy 339.453345 -281.671805) (xy 339.404461 -281.685965) (xy 339.35394 -281.692099) (xy 339.303088 -281.69005)
			(xy 339.253224 -281.67987) (xy 339.205638 -281.661823) (xy 339.161564 -281.636377) (xy 339.122142 -281.60419)
			(xy 339.088394 -281.566096) (xy 339.061193 -281.523082) (xy 339.041245 -281.476262) (xy 339.029066 -281.426848)
			(xy 339.024971 -281.37612) (xy 338.70646 -281.37612) (xy 338.705965 -281.400727) (xy 338.69807 -281.449304)
			(xy 338.682486 -281.495985) (xy 338.659615 -281.539562) (xy 338.63005 -281.578906) (xy 338.594557 -281.612998)
			(xy 338.554054 -281.640954) (xy 338.509592 -281.662052) (xy 338.462321 -281.675744) (xy 338.413466 -281.681676)
			(xy 338.364291 -281.679695) (xy 338.316072 -281.669851) (xy 338.270056 -281.652399) (xy 338.227435 -281.627792)
			(xy 338.189314 -281.596667) (xy 338.156679 -281.55983) (xy 338.130376 -281.518234) (xy 338.111085 -281.472958)
			(xy 338.099308 -281.425174) (xy 338.095348 -281.37612) (xy 337.766406 -281.37612) (xy 337.765911 -281.400727)
			(xy 337.758016 -281.449304) (xy 337.742432 -281.495985) (xy 337.719561 -281.539562) (xy 337.689996 -281.578906)
			(xy 337.654503 -281.612998) (xy 337.614 -281.640954) (xy 337.569538 -281.662052) (xy 337.522267 -281.675744)
			(xy 337.473412 -281.681676) (xy 337.424237 -281.679695) (xy 337.376018 -281.669851) (xy 337.330002 -281.652399)
			(xy 337.287381 -281.627792) (xy 337.24926 -281.596667) (xy 337.216625 -281.55983) (xy 337.190322 -281.518234)
			(xy 337.171031 -281.472958) (xy 337.159254 -281.425174) (xy 337.155294 -281.37612) (xy 336.826352 -281.37612)
			(xy 336.825857 -281.400727) (xy 336.817962 -281.449304) (xy 336.802378 -281.495985) (xy 336.779507 -281.539562)
			(xy 336.749942 -281.578906) (xy 336.714449 -281.612998) (xy 336.673946 -281.640954) (xy 336.629484 -281.662052)
			(xy 336.582213 -281.675744) (xy 336.533358 -281.681676) (xy 336.484183 -281.679695) (xy 336.435964 -281.669851)
			(xy 336.389948 -281.652399) (xy 336.347327 -281.627792) (xy 336.309206 -281.596667) (xy 336.276571 -281.55983)
			(xy 336.250268 -281.518234) (xy 336.230977 -281.472958) (xy 336.2192 -281.425174) (xy 336.21524 -281.37612)
			(xy 335.886298 -281.37612) (xy 335.885803 -281.400727) (xy 335.877908 -281.449304) (xy 335.862324 -281.495985)
			(xy 335.839453 -281.539562) (xy 335.809888 -281.578906) (xy 335.774395 -281.612998) (xy 335.733892 -281.640954)
			(xy 335.68943 -281.662052) (xy 335.642159 -281.675744) (xy 335.593304 -281.681676) (xy 335.544129 -281.679695)
			(xy 335.49591 -281.669851) (xy 335.449894 -281.652399) (xy 335.407273 -281.627792) (xy 335.369152 -281.596667)
			(xy 335.336517 -281.55983) (xy 335.310214 -281.518234) (xy 335.290923 -281.472958) (xy 335.279146 -281.425174)
			(xy 335.275186 -281.37612) (xy 334.950054 -281.37612) (xy 334.950054 -281.784806) (xy 334.950054 -281.787346)
			(xy 334.950971 -281.79701) (xy 334.95908 -281.81463) (xy 334.965802 -281.821636) (xy 335.024476 -281.872182)
			(xy 335.028709 -281.875655) (xy 335.03832 -281.880898) (xy 335.043526 -281.882596) (xy 335.054194 -281.885644)
			(xy 335.065116 -281.88412) (xy 335.076354 -281.882564) (xy 335.098983 -281.880909) (xy 335.110328 -281.880818)
			(xy 335.11109 -281.880818) (xy 335.136346 -281.88131) (xy 335.18617 -281.889622) (xy 335.233945 -281.906022)
			(xy 335.27837 -281.930063) (xy 335.318232 -281.961087) (xy 335.352443 -281.99825) (xy 335.380071 -282.040536)
			(xy 335.400362 -282.086794) (xy 335.412763 -282.13576) (xy 335.416934 -282.1861) (xy 335.416932 -282.186126)
			(xy 335.74534 -282.186126) (xy 335.7493 -282.137072) (xy 335.761077 -282.089288) (xy 335.780368 -282.044012)
			(xy 335.806671 -282.002416) (xy 335.839306 -281.965579) (xy 335.877427 -281.934454) (xy 335.920048 -281.909847)
			(xy 335.966064 -281.892395) (xy 336.014283 -281.882551) (xy 336.063458 -281.88057) (xy 336.112313 -281.886502)
			(xy 336.159584 -281.900194) (xy 336.204046 -281.921292) (xy 336.244549 -281.949248) (xy 336.280042 -281.98334)
			(xy 336.309607 -282.022684) (xy 336.332478 -282.066261) (xy 336.348062 -282.112942) (xy 336.355957 -282.161519)
			(xy 336.356452 -282.186126) (xy 336.685394 -282.186126) (xy 336.689354 -282.137072) (xy 336.701131 -282.089288)
			(xy 336.720422 -282.044012) (xy 336.746725 -282.002416) (xy 336.77936 -281.965579) (xy 336.817481 -281.934454)
			(xy 336.860102 -281.909847) (xy 336.906118 -281.892395) (xy 336.954337 -281.882551) (xy 337.003512 -281.88057)
			(xy 337.052367 -281.886502) (xy 337.099638 -281.900194) (xy 337.1441 -281.921292) (xy 337.184603 -281.949248)
			(xy 337.220096 -281.98334) (xy 337.249661 -282.022684) (xy 337.272532 -282.066261) (xy 337.288116 -282.112942)
			(xy 337.296011 -282.161519) (xy 337.296506 -282.186126) (xy 337.625194 -282.186126) (xy 337.629154 -282.137072)
			(xy 337.640931 -282.089288) (xy 337.660222 -282.044012) (xy 337.686525 -282.002416) (xy 337.71916 -281.965579)
			(xy 337.757281 -281.934454) (xy 337.799902 -281.909847) (xy 337.845918 -281.892395) (xy 337.894137 -281.882551)
			(xy 337.943312 -281.88057) (xy 337.992167 -281.886502) (xy 338.039438 -281.900194) (xy 338.0839 -281.921292)
			(xy 338.124403 -281.949248) (xy 338.159896 -281.98334) (xy 338.189461 -282.022684) (xy 338.212332 -282.066261)
			(xy 338.227916 -282.112942) (xy 338.235811 -282.161519) (xy 338.236306 -282.186126) (xy 338.554817 -282.186126)
			(xy 338.558912 -282.135398) (xy 338.571091 -282.085984) (xy 338.591039 -282.039164) (xy 338.61824 -281.99615)
			(xy 338.651988 -281.958056) (xy 338.69141 -281.925869) (xy 338.735484 -281.900423) (xy 338.78307 -281.882376)
			(xy 338.832934 -281.872196) (xy 338.883786 -281.870147) (xy 338.934307 -281.876281) (xy 338.983191 -281.890441)
			(xy 339.02917 -281.912258) (xy 339.071054 -281.941168) (xy 339.107758 -281.976423) (xy 339.138331 -282.017109)
			(xy 339.161982 -282.062172) (xy 339.178098 -282.110446) (xy 339.186262 -282.16068) (xy 339.186774 -282.186126)
			(xy 339.505302 -282.186126) (xy 339.509262 -282.137072) (xy 339.521039 -282.089288) (xy 339.54033 -282.044012)
			(xy 339.566633 -282.002416) (xy 339.599268 -281.965579) (xy 339.637389 -281.934454) (xy 339.68001 -281.909847)
			(xy 339.726026 -281.892395) (xy 339.774245 -281.882551) (xy 339.82342 -281.88057) (xy 339.872275 -281.886502)
			(xy 339.919546 -281.900194) (xy 339.964008 -281.921292) (xy 340.004511 -281.949248) (xy 340.040004 -281.98334)
			(xy 340.069569 -282.022684) (xy 340.09244 -282.066261) (xy 340.108024 -282.112942) (xy 340.115919 -282.161519)
			(xy 340.116414 -282.186126) (xy 340.434925 -282.186126) (xy 340.43902 -282.135398) (xy 340.451199 -282.085984)
			(xy 340.471147 -282.039164) (xy 340.498348 -281.99615) (xy 340.532096 -281.958056) (xy 340.571518 -281.925869)
			(xy 340.615592 -281.900423) (xy 340.663178 -281.882376) (xy 340.713042 -281.872196) (xy 340.763894 -281.870147)
			(xy 340.814415 -281.876281) (xy 340.863299 -281.890441) (xy 340.909278 -281.912258) (xy 340.951162 -281.941168)
			(xy 340.987866 -281.976423) (xy 341.018439 -282.017109) (xy 341.04209 -282.062172) (xy 341.058206 -282.110446)
			(xy 341.06637 -282.16068) (xy 341.066882 -282.186126) (xy 341.38541 -282.186126) (xy 341.38937 -282.137072)
			(xy 341.401147 -282.089288) (xy 341.420438 -282.044012) (xy 341.446741 -282.002416) (xy 341.479376 -281.965579)
			(xy 341.517497 -281.934454) (xy 341.560118 -281.909847) (xy 341.606134 -281.892395) (xy 341.654353 -281.882551)
			(xy 341.703528 -281.88057) (xy 341.752383 -281.886502) (xy 341.799654 -281.900194) (xy 341.844116 -281.921292)
			(xy 341.884619 -281.949248) (xy 341.920112 -281.98334) (xy 341.949677 -282.022684) (xy 341.972548 -282.066261)
			(xy 341.988132 -282.112942) (xy 341.996027 -282.161519) (xy 341.996522 -282.186126) (xy 342.314779 -282.186126)
			(xy 342.318874 -282.135398) (xy 342.331053 -282.085984) (xy 342.351001 -282.039164) (xy 342.378202 -281.99615)
			(xy 342.41195 -281.958056) (xy 342.451372 -281.925869) (xy 342.495446 -281.900423) (xy 342.543032 -281.882376)
			(xy 342.592896 -281.872196) (xy 342.643748 -281.870147) (xy 342.694269 -281.876281) (xy 342.743153 -281.890441)
			(xy 342.789132 -281.912258) (xy 342.831016 -281.941168) (xy 342.86772 -281.976423) (xy 342.898293 -282.017109)
			(xy 342.921944 -282.062172) (xy 342.93806 -282.110446) (xy 342.946224 -282.16068) (xy 342.946736 -282.186126)
			(xy 343.254833 -282.186126) (xy 343.258928 -282.135398) (xy 343.271107 -282.085984) (xy 343.291055 -282.039164)
			(xy 343.318256 -281.99615) (xy 343.352004 -281.958056) (xy 343.391426 -281.925869) (xy 343.4355 -281.900423)
			(xy 343.483086 -281.882376) (xy 343.53295 -281.872196) (xy 343.583802 -281.870147) (xy 343.634323 -281.876281)
			(xy 343.683207 -281.890441) (xy 343.729186 -281.912258) (xy 343.77107 -281.941168) (xy 343.807774 -281.976423)
			(xy 343.838347 -282.017109) (xy 343.861998 -282.062172) (xy 343.878114 -282.110446) (xy 343.886278 -282.16068)
			(xy 343.88679 -282.186126) (xy 343.886278 -282.211572) (xy 343.878114 -282.261806) (xy 343.861998 -282.31008)
			(xy 343.838347 -282.355143) (xy 343.807774 -282.395829) (xy 343.77107 -282.431084) (xy 343.729186 -282.459994)
			(xy 343.683207 -282.481811) (xy 343.634323 -282.495971) (xy 343.583802 -282.502105) (xy 343.53295 -282.500056)
			(xy 343.483086 -282.489876) (xy 343.4355 -282.471829) (xy 343.391426 -282.446383) (xy 343.352004 -282.414196)
			(xy 343.318256 -282.376102) (xy 343.291055 -282.333088) (xy 343.271107 -282.286268) (xy 343.258928 -282.236854)
			(xy 343.254833 -282.186126) (xy 342.946736 -282.186126) (xy 342.946224 -282.211572) (xy 342.93806 -282.261806)
			(xy 342.921944 -282.31008) (xy 342.898293 -282.355143) (xy 342.86772 -282.395829) (xy 342.831016 -282.431084)
			(xy 342.789132 -282.459994) (xy 342.743153 -282.481811) (xy 342.694269 -282.495971) (xy 342.643748 -282.502105)
			(xy 342.592896 -282.500056) (xy 342.543032 -282.489876) (xy 342.495446 -282.471829) (xy 342.451372 -282.446383)
			(xy 342.41195 -282.414196) (xy 342.378202 -282.376102) (xy 342.351001 -282.333088) (xy 342.331053 -282.286268)
			(xy 342.318874 -282.236854) (xy 342.314779 -282.186126) (xy 341.996522 -282.186126) (xy 341.996027 -282.210733)
			(xy 341.988132 -282.25931) (xy 341.972548 -282.305991) (xy 341.949677 -282.349568) (xy 341.920112 -282.388912)
			(xy 341.884619 -282.423004) (xy 341.844116 -282.45096) (xy 341.799654 -282.472058) (xy 341.752383 -282.48575)
			(xy 341.703528 -282.491682) (xy 341.654353 -282.489701) (xy 341.606134 -282.479857) (xy 341.560118 -282.462405)
			(xy 341.517497 -282.437798) (xy 341.479376 -282.406673) (xy 341.446741 -282.369836) (xy 341.420438 -282.32824)
			(xy 341.401147 -282.282964) (xy 341.38937 -282.23518) (xy 341.38541 -282.186126) (xy 341.066882 -282.186126)
			(xy 341.06637 -282.211572) (xy 341.058206 -282.261806) (xy 341.04209 -282.31008) (xy 341.018439 -282.355143)
			(xy 340.987866 -282.395829) (xy 340.951162 -282.431084) (xy 340.909278 -282.459994) (xy 340.863299 -282.481811)
			(xy 340.814415 -282.495971) (xy 340.763894 -282.502105) (xy 340.713042 -282.500056) (xy 340.663178 -282.489876)
			(xy 340.615592 -282.471829) (xy 340.571518 -282.446383) (xy 340.532096 -282.414196) (xy 340.498348 -282.376102)
			(xy 340.471147 -282.333088) (xy 340.451199 -282.286268) (xy 340.43902 -282.236854) (xy 340.434925 -282.186126)
			(xy 340.116414 -282.186126) (xy 340.115919 -282.210733) (xy 340.108024 -282.25931) (xy 340.09244 -282.305991)
			(xy 340.069569 -282.349568) (xy 340.040004 -282.388912) (xy 340.004511 -282.423004) (xy 339.964008 -282.45096)
			(xy 339.919546 -282.472058) (xy 339.872275 -282.48575) (xy 339.82342 -282.491682) (xy 339.774245 -282.489701)
			(xy 339.726026 -282.479857) (xy 339.68001 -282.462405) (xy 339.637389 -282.437798) (xy 339.599268 -282.406673)
			(xy 339.566633 -282.369836) (xy 339.54033 -282.32824) (xy 339.521039 -282.282964) (xy 339.509262 -282.23518)
			(xy 339.505302 -282.186126) (xy 339.186774 -282.186126) (xy 339.186262 -282.211572) (xy 339.178098 -282.261806)
			(xy 339.161982 -282.31008) (xy 339.138331 -282.355143) (xy 339.107758 -282.395829) (xy 339.071054 -282.431084)
			(xy 339.02917 -282.459994) (xy 338.983191 -282.481811) (xy 338.934307 -282.495971) (xy 338.883786 -282.502105)
			(xy 338.832934 -282.500056) (xy 338.78307 -282.489876) (xy 338.735484 -282.471829) (xy 338.69141 -282.446383)
			(xy 338.651988 -282.414196) (xy 338.61824 -282.376102) (xy 338.591039 -282.333088) (xy 338.571091 -282.286268)
			(xy 338.558912 -282.236854) (xy 338.554817 -282.186126) (xy 338.236306 -282.186126) (xy 338.235811 -282.210733)
			(xy 338.227916 -282.25931) (xy 338.212332 -282.305991) (xy 338.189461 -282.349568) (xy 338.159896 -282.388912)
			(xy 338.124403 -282.423004) (xy 338.0839 -282.45096) (xy 338.039438 -282.472058) (xy 337.992167 -282.48575)
			(xy 337.943312 -282.491682) (xy 337.894137 -282.489701) (xy 337.845918 -282.479857) (xy 337.799902 -282.462405)
			(xy 337.757281 -282.437798) (xy 337.71916 -282.406673) (xy 337.686525 -282.369836) (xy 337.660222 -282.32824)
			(xy 337.640931 -282.282964) (xy 337.629154 -282.23518) (xy 337.625194 -282.186126) (xy 337.296506 -282.186126)
			(xy 337.296011 -282.210733) (xy 337.288116 -282.25931) (xy 337.272532 -282.305991) (xy 337.249661 -282.349568)
			(xy 337.220096 -282.388912) (xy 337.184603 -282.423004) (xy 337.1441 -282.45096) (xy 337.099638 -282.472058)
			(xy 337.052367 -282.48575) (xy 337.003512 -282.491682) (xy 336.954337 -282.489701) (xy 336.906118 -282.479857)
			(xy 336.860102 -282.462405) (xy 336.817481 -282.437798) (xy 336.77936 -282.406673) (xy 336.746725 -282.369836)
			(xy 336.720422 -282.32824) (xy 336.701131 -282.282964) (xy 336.689354 -282.23518) (xy 336.685394 -282.186126)
			(xy 336.356452 -282.186126) (xy 336.355957 -282.210733) (xy 336.348062 -282.25931) (xy 336.332478 -282.305991)
			(xy 336.309607 -282.349568) (xy 336.280042 -282.388912) (xy 336.244549 -282.423004) (xy 336.204046 -282.45096)
			(xy 336.159584 -282.472058) (xy 336.112313 -282.48575) (xy 336.063458 -282.491682) (xy 336.014283 -282.489701)
			(xy 335.966064 -282.479857) (xy 335.920048 -282.462405) (xy 335.877427 -282.437798) (xy 335.839306 -282.406673)
			(xy 335.806671 -282.369836) (xy 335.780368 -282.32824) (xy 335.761077 -282.282964) (xy 335.7493 -282.23518)
			(xy 335.74534 -282.186126) (xy 335.416932 -282.186126) (xy 335.412763 -282.23644) (xy 335.400362 -282.285406)
			(xy 335.380071 -282.331664) (xy 335.352443 -282.37395) (xy 335.318232 -282.411113) (xy 335.27837 -282.442137)
			(xy 335.233945 -282.466178) (xy 335.18617 -282.482578) (xy 335.136346 -282.49089) (xy 335.11109 -282.491434)
			(xy 335.110582 -282.491434) (xy 335.097433 -282.491284) (xy 335.071234 -282.488992) (xy 335.058258 -282.486862)
			(xy 335.054448 -282.486354) (xy 335.04378 -282.489402) (xy 335.038891 -282.490936) (xy 335.029805 -282.495672)
			(xy 335.025746 -282.4988) (xy 334.967072 -282.549092) (xy 334.959452 -282.556658) (xy 334.950652 -282.576217)
			(xy 334.950054 -282.586938) (xy 334.950054 -282.877514) (xy 334.952848 -282.885896) (xy 334.96168 -282.912599)
			(xy 334.97126 -282.968014) (xy 334.971898 -282.996132) (xy 335.275186 -282.996132) (xy 335.279146 -282.947078)
			(xy 335.290923 -282.899294) (xy 335.310214 -282.854018) (xy 335.336517 -282.812422) (xy 335.369152 -282.775585)
			(xy 335.407273 -282.74446) (xy 335.449894 -282.719853) (xy 335.49591 -282.702401) (xy 335.544129 -282.692557)
			(xy 335.593304 -282.690576) (xy 335.642159 -282.696508) (xy 335.68943 -282.7102) (xy 335.733892 -282.731298)
			(xy 335.774395 -282.759254) (xy 335.809888 -282.793346) (xy 335.839453 -282.83269) (xy 335.862324 -282.876267)
			(xy 335.877908 -282.922948) (xy 335.885803 -282.971525) (xy 335.886298 -282.996132) (xy 336.21524 -282.996132)
			(xy 336.2192 -282.947078) (xy 336.230977 -282.899294) (xy 336.250268 -282.854018) (xy 336.276571 -282.812422)
			(xy 336.309206 -282.775585) (xy 336.347327 -282.74446) (xy 336.389948 -282.719853) (xy 336.435964 -282.702401)
			(xy 336.484183 -282.692557) (xy 336.533358 -282.690576) (xy 336.582213 -282.696508) (xy 336.629484 -282.7102)
			(xy 336.673946 -282.731298) (xy 336.714449 -282.759254) (xy 336.749942 -282.793346) (xy 336.779507 -282.83269)
			(xy 336.802378 -282.876267) (xy 336.817962 -282.922948) (xy 336.825857 -282.971525) (xy 336.826352 -282.996132)
			(xy 337.155294 -282.996132) (xy 337.159254 -282.947078) (xy 337.171031 -282.899294) (xy 337.190322 -282.854018)
			(xy 337.216625 -282.812422) (xy 337.24926 -282.775585) (xy 337.287381 -282.74446) (xy 337.330002 -282.719853)
			(xy 337.376018 -282.702401) (xy 337.424237 -282.692557) (xy 337.473412 -282.690576) (xy 337.522267 -282.696508)
			(xy 337.569538 -282.7102) (xy 337.614 -282.731298) (xy 337.654503 -282.759254) (xy 337.689996 -282.793346)
			(xy 337.719561 -282.83269) (xy 337.742432 -282.876267) (xy 337.758016 -282.922948) (xy 337.765911 -282.971525)
			(xy 337.766406 -282.996132) (xy 338.095348 -282.996132) (xy 338.099308 -282.947078) (xy 338.111085 -282.899294)
			(xy 338.130376 -282.854018) (xy 338.156679 -282.812422) (xy 338.189314 -282.775585) (xy 338.227435 -282.74446)
			(xy 338.270056 -282.719853) (xy 338.316072 -282.702401) (xy 338.364291 -282.692557) (xy 338.413466 -282.690576)
			(xy 338.462321 -282.696508) (xy 338.509592 -282.7102) (xy 338.554054 -282.731298) (xy 338.594557 -282.759254)
			(xy 338.63005 -282.793346) (xy 338.659615 -282.83269) (xy 338.682486 -282.876267) (xy 338.69807 -282.922948)
			(xy 338.705965 -282.971525) (xy 338.70646 -282.996132) (xy 339.024971 -282.996132) (xy 339.029066 -282.945404)
			(xy 339.041245 -282.89599) (xy 339.061193 -282.84917) (xy 339.088394 -282.806156) (xy 339.122142 -282.768062)
			(xy 339.161564 -282.735875) (xy 339.205638 -282.710429) (xy 339.253224 -282.692382) (xy 339.303088 -282.682202)
			(xy 339.35394 -282.680153) (xy 339.404461 -282.686287) (xy 339.453345 -282.700447) (xy 339.499324 -282.722264)
			(xy 339.541208 -282.751174) (xy 339.577912 -282.786429) (xy 339.608485 -282.827115) (xy 339.632136 -282.872178)
			(xy 339.648252 -282.920452) (xy 339.656416 -282.970686) (xy 339.656928 -282.996132) (xy 339.964771 -282.996132)
			(xy 339.968866 -282.945404) (xy 339.981045 -282.89599) (xy 340.000993 -282.84917) (xy 340.028194 -282.806156)
			(xy 340.061942 -282.768062) (xy 340.101364 -282.735875) (xy 340.145438 -282.710429) (xy 340.193024 -282.692382)
			(xy 340.242888 -282.682202) (xy 340.29374 -282.680153) (xy 340.344261 -282.686287) (xy 340.393145 -282.700447)
			(xy 340.439124 -282.722264) (xy 340.481008 -282.751174) (xy 340.517712 -282.786429) (xy 340.548285 -282.827115)
			(xy 340.571936 -282.872178) (xy 340.588052 -282.920452) (xy 340.596216 -282.970686) (xy 340.596728 -282.996132)
			(xy 341.844879 -282.996132) (xy 341.848974 -282.945404) (xy 341.861153 -282.89599) (xy 341.881101 -282.84917)
			(xy 341.908302 -282.806156) (xy 341.94205 -282.768062) (xy 341.981472 -282.735875) (xy 342.025546 -282.710429)
			(xy 342.073132 -282.692382) (xy 342.122996 -282.682202) (xy 342.173848 -282.680153) (xy 342.224369 -282.686287)
			(xy 342.273253 -282.700447) (xy 342.319232 -282.722264) (xy 342.361116 -282.751174) (xy 342.39782 -282.786429)
			(xy 342.428393 -282.827115) (xy 342.452044 -282.872178) (xy 342.46816 -282.920452) (xy 342.476324 -282.970686)
			(xy 342.476836 -282.996132) (xy 342.795364 -282.996132) (xy 342.799324 -282.947078) (xy 342.811101 -282.899294)
			(xy 342.830392 -282.854018) (xy 342.856695 -282.812422) (xy 342.88933 -282.775585) (xy 342.927451 -282.74446)
			(xy 342.970072 -282.719853) (xy 343.016088 -282.702401) (xy 343.064307 -282.692557) (xy 343.113482 -282.690576)
			(xy 343.162337 -282.696508) (xy 343.209608 -282.7102) (xy 343.25407 -282.731298) (xy 343.294573 -282.759254)
			(xy 343.330066 -282.793346) (xy 343.359631 -282.83269) (xy 343.382502 -282.876267) (xy 343.398086 -282.922948)
			(xy 343.405981 -282.971525) (xy 343.406476 -282.996132) (xy 343.724987 -282.996132) (xy 343.729082 -282.945404)
			(xy 343.741261 -282.89599) (xy 343.761209 -282.84917) (xy 343.78841 -282.806156) (xy 343.822158 -282.768062)
			(xy 343.86158 -282.735875) (xy 343.905654 -282.710429) (xy 343.95324 -282.692382) (xy 344.003104 -282.682202)
			(xy 344.053956 -282.680153) (xy 344.104477 -282.686287) (xy 344.153361 -282.700447) (xy 344.19934 -282.722264)
			(xy 344.241224 -282.751174) (xy 344.277928 -282.786429) (xy 344.308501 -282.827115) (xy 344.332152 -282.872178)
			(xy 344.348268 -282.920452) (xy 344.356432 -282.970686) (xy 344.356944 -282.996132) (xy 344.356432 -283.021578)
			(xy 344.348268 -283.071812) (xy 344.332152 -283.120086) (xy 344.308501 -283.165149) (xy 344.277928 -283.205835)
			(xy 344.241224 -283.24109) (xy 344.19934 -283.27) (xy 344.153361 -283.291817) (xy 344.104477 -283.305977)
			(xy 344.053956 -283.312111) (xy 344.003104 -283.310062) (xy 343.95324 -283.299882) (xy 343.905654 -283.281835)
			(xy 343.86158 -283.256389) (xy 343.822158 -283.224202) (xy 343.78841 -283.186108) (xy 343.761209 -283.143094)
			(xy 343.741261 -283.096274) (xy 343.729082 -283.04686) (xy 343.724987 -282.996132) (xy 343.406476 -282.996132)
			(xy 343.405981 -283.020739) (xy 343.398086 -283.069316) (xy 343.382502 -283.115997) (xy 343.359631 -283.159574)
			(xy 343.330066 -283.198918) (xy 343.294573 -283.23301) (xy 343.25407 -283.260966) (xy 343.209608 -283.282064)
			(xy 343.162337 -283.295756) (xy 343.113482 -283.301688) (xy 343.064307 -283.299707) (xy 343.016088 -283.289863)
			(xy 342.970072 -283.272411) (xy 342.927451 -283.247804) (xy 342.88933 -283.216679) (xy 342.856695 -283.179842)
			(xy 342.830392 -283.138246) (xy 342.811101 -283.09297) (xy 342.799324 -283.045186) (xy 342.795364 -282.996132)
			(xy 342.476836 -282.996132) (xy 342.476324 -283.021578) (xy 342.46816 -283.071812) (xy 342.452044 -283.120086)
			(xy 342.428393 -283.165149) (xy 342.39782 -283.205835) (xy 342.361116 -283.24109) (xy 342.319232 -283.27)
			(xy 342.273253 -283.291817) (xy 342.224369 -283.305977) (xy 342.173848 -283.312111) (xy 342.122996 -283.310062)
			(xy 342.073132 -283.299882) (xy 342.025546 -283.281835) (xy 341.981472 -283.256389) (xy 341.94205 -283.224202)
			(xy 341.908302 -283.186108) (xy 341.881101 -283.143094) (xy 341.861153 -283.096274) (xy 341.848974 -283.04686)
			(xy 341.844879 -282.996132) (xy 340.596728 -282.996132) (xy 340.596216 -283.021578) (xy 340.588052 -283.071812)
			(xy 340.571936 -283.120086) (xy 340.548285 -283.165149) (xy 340.517712 -283.205835) (xy 340.481008 -283.24109)
			(xy 340.439124 -283.27) (xy 340.393145 -283.291817) (xy 340.344261 -283.305977) (xy 340.29374 -283.312111)
			(xy 340.242888 -283.310062) (xy 340.193024 -283.299882) (xy 340.145438 -283.281835) (xy 340.101364 -283.256389)
			(xy 340.061942 -283.224202) (xy 340.028194 -283.186108) (xy 340.000993 -283.143094) (xy 339.981045 -283.096274)
			(xy 339.968866 -283.04686) (xy 339.964771 -282.996132) (xy 339.656928 -282.996132) (xy 339.656416 -283.021578)
			(xy 339.648252 -283.071812) (xy 339.632136 -283.120086) (xy 339.608485 -283.165149) (xy 339.577912 -283.205835)
			(xy 339.541208 -283.24109) (xy 339.499324 -283.27) (xy 339.453345 -283.291817) (xy 339.404461 -283.305977)
			(xy 339.35394 -283.312111) (xy 339.303088 -283.310062) (xy 339.253224 -283.299882) (xy 339.205638 -283.281835)
			(xy 339.161564 -283.256389) (xy 339.122142 -283.224202) (xy 339.088394 -283.186108) (xy 339.061193 -283.143094)
			(xy 339.041245 -283.096274) (xy 339.029066 -283.04686) (xy 339.024971 -282.996132) (xy 338.70646 -282.996132)
			(xy 338.705965 -283.020739) (xy 338.69807 -283.069316) (xy 338.682486 -283.115997) (xy 338.659615 -283.159574)
			(xy 338.63005 -283.198918) (xy 338.594557 -283.23301) (xy 338.554054 -283.260966) (xy 338.509592 -283.282064)
			(xy 338.462321 -283.295756) (xy 338.413466 -283.301688) (xy 338.364291 -283.299707) (xy 338.316072 -283.289863)
			(xy 338.270056 -283.272411) (xy 338.227435 -283.247804) (xy 338.189314 -283.216679) (xy 338.156679 -283.179842)
			(xy 338.130376 -283.138246) (xy 338.111085 -283.09297) (xy 338.099308 -283.045186) (xy 338.095348 -282.996132)
			(xy 337.766406 -282.996132) (xy 337.765911 -283.020739) (xy 337.758016 -283.069316) (xy 337.742432 -283.115997)
			(xy 337.719561 -283.159574) (xy 337.689996 -283.198918) (xy 337.654503 -283.23301) (xy 337.614 -283.260966)
			(xy 337.569538 -283.282064) (xy 337.522267 -283.295756) (xy 337.473412 -283.301688) (xy 337.424237 -283.299707)
			(xy 337.376018 -283.289863) (xy 337.330002 -283.272411) (xy 337.287381 -283.247804) (xy 337.24926 -283.216679)
			(xy 337.216625 -283.179842) (xy 337.190322 -283.138246) (xy 337.171031 -283.09297) (xy 337.159254 -283.045186)
			(xy 337.155294 -282.996132) (xy 336.826352 -282.996132) (xy 336.825857 -283.020739) (xy 336.817962 -283.069316)
			(xy 336.802378 -283.115997) (xy 336.779507 -283.159574) (xy 336.749942 -283.198918) (xy 336.714449 -283.23301)
			(xy 336.673946 -283.260966) (xy 336.629484 -283.282064) (xy 336.582213 -283.295756) (xy 336.533358 -283.301688)
			(xy 336.484183 -283.299707) (xy 336.435964 -283.289863) (xy 336.389948 -283.272411) (xy 336.347327 -283.247804)
			(xy 336.309206 -283.216679) (xy 336.276571 -283.179842) (xy 336.250268 -283.138246) (xy 336.230977 -283.09297)
			(xy 336.2192 -283.045186) (xy 336.21524 -282.996132) (xy 335.886298 -282.996132) (xy 335.885803 -283.020739)
			(xy 335.877908 -283.069316) (xy 335.862324 -283.115997) (xy 335.839453 -283.159574) (xy 335.809888 -283.198918)
			(xy 335.774395 -283.23301) (xy 335.733892 -283.260966) (xy 335.68943 -283.282064) (xy 335.642159 -283.295756)
			(xy 335.593304 -283.301688) (xy 335.544129 -283.299707) (xy 335.49591 -283.289863) (xy 335.449894 -283.272411)
			(xy 335.407273 -283.247804) (xy 335.369152 -283.216679) (xy 335.336517 -283.179842) (xy 335.310214 -283.138246)
			(xy 335.290923 -283.09297) (xy 335.279146 -283.045186) (xy 335.275186 -282.996132) (xy 334.971898 -282.996132)
			(xy 334.971314 -283.024255) (xy 334.961735 -283.07968) (xy 334.952848 -283.106368) (xy 334.950054 -283.11475)
			(xy 334.950054 -283.404818) (xy 334.950054 -283.407358) (xy 334.950973 -283.417021) (xy 334.959085 -283.434638)
			(xy 334.965802 -283.441648) (xy 335.024476 -283.492194) (xy 335.02871 -283.495666) (xy 335.03832 -283.500908)
			(xy 335.043526 -283.502608) (xy 335.054194 -283.505656) (xy 335.065116 -283.504132) (xy 335.076354 -283.502576)
			(xy 335.098983 -283.500921) (xy 335.110328 -283.50083) (xy 335.11109 -283.50083) (xy 335.136345 -283.501322)
			(xy 335.186167 -283.509634) (xy 335.233941 -283.526033) (xy 335.278363 -283.550073) (xy 335.318224 -283.581096)
			(xy 335.352434 -283.618257) (xy 335.380061 -283.660542) (xy 335.400351 -283.706798) (xy 335.412751 -283.755762)
			(xy 335.416922 -283.8061) (xy 335.416919 -283.806138) (xy 335.74534 -283.806138) (xy 335.7493 -283.757084)
			(xy 335.761077 -283.7093) (xy 335.780368 -283.664024) (xy 335.806671 -283.622428) (xy 335.839306 -283.585591)
			(xy 335.877427 -283.554466) (xy 335.920048 -283.529859) (xy 335.966064 -283.512407) (xy 336.014283 -283.502563)
			(xy 336.063458 -283.500582) (xy 336.112313 -283.506514) (xy 336.159584 -283.520206) (xy 336.204046 -283.541304)
			(xy 336.244549 -283.56926) (xy 336.280042 -283.603352) (xy 336.309607 -283.642696) (xy 336.332478 -283.686273)
			(xy 336.348062 -283.732954) (xy 336.355957 -283.781531) (xy 336.356452 -283.806138) (xy 336.685394 -283.806138)
			(xy 336.689354 -283.757084) (xy 336.701131 -283.7093) (xy 336.720422 -283.664024) (xy 336.746725 -283.622428)
			(xy 336.77936 -283.585591) (xy 336.817481 -283.554466) (xy 336.860102 -283.529859) (xy 336.906118 -283.512407)
			(xy 336.954337 -283.502563) (xy 337.003512 -283.500582) (xy 337.052367 -283.506514) (xy 337.099638 -283.520206)
			(xy 337.1441 -283.541304) (xy 337.184603 -283.56926) (xy 337.220096 -283.603352) (xy 337.249661 -283.642696)
			(xy 337.272532 -283.686273) (xy 337.288116 -283.732954) (xy 337.296011 -283.781531) (xy 337.296506 -283.806138)
			(xy 337.625194 -283.806138) (xy 337.629154 -283.757084) (xy 337.640931 -283.7093) (xy 337.660222 -283.664024)
			(xy 337.686525 -283.622428) (xy 337.71916 -283.585591) (xy 337.757281 -283.554466) (xy 337.799902 -283.529859)
			(xy 337.845918 -283.512407) (xy 337.894137 -283.502563) (xy 337.943312 -283.500582) (xy 337.992167 -283.506514)
			(xy 338.039438 -283.520206) (xy 338.0839 -283.541304) (xy 338.124403 -283.56926) (xy 338.159896 -283.603352)
			(xy 338.189461 -283.642696) (xy 338.212332 -283.686273) (xy 338.227916 -283.732954) (xy 338.235811 -283.781531)
			(xy 338.236306 -283.806138) (xy 338.554817 -283.806138) (xy 338.558912 -283.75541) (xy 338.571091 -283.705996)
			(xy 338.591039 -283.659176) (xy 338.61824 -283.616162) (xy 338.651988 -283.578068) (xy 338.69141 -283.545881)
			(xy 338.735484 -283.520435) (xy 338.78307 -283.502388) (xy 338.832934 -283.492208) (xy 338.883786 -283.490159)
			(xy 338.934307 -283.496293) (xy 338.983191 -283.510453) (xy 339.02917 -283.53227) (xy 339.071054 -283.56118)
			(xy 339.107758 -283.596435) (xy 339.138331 -283.637121) (xy 339.161982 -283.682184) (xy 339.178098 -283.730458)
			(xy 339.186262 -283.780692) (xy 339.186774 -283.806138) (xy 339.505302 -283.806138) (xy 339.509262 -283.757084)
			(xy 339.521039 -283.7093) (xy 339.54033 -283.664024) (xy 339.566633 -283.622428) (xy 339.599268 -283.585591)
			(xy 339.637389 -283.554466) (xy 339.68001 -283.529859) (xy 339.726026 -283.512407) (xy 339.774245 -283.502563)
			(xy 339.82342 -283.500582) (xy 339.872275 -283.506514) (xy 339.919546 -283.520206) (xy 339.964008 -283.541304)
			(xy 340.004511 -283.56926) (xy 340.040004 -283.603352) (xy 340.069569 -283.642696) (xy 340.09244 -283.686273)
			(xy 340.108024 -283.732954) (xy 340.115919 -283.781531) (xy 340.116414 -283.806138) (xy 340.434925 -283.806138)
			(xy 340.43902 -283.75541) (xy 340.451199 -283.705996) (xy 340.471147 -283.659176) (xy 340.498348 -283.616162)
			(xy 340.532096 -283.578068) (xy 340.571518 -283.545881) (xy 340.615592 -283.520435) (xy 340.663178 -283.502388)
			(xy 340.713042 -283.492208) (xy 340.763894 -283.490159) (xy 340.814415 -283.496293) (xy 340.863299 -283.510453)
			(xy 340.909278 -283.53227) (xy 340.951162 -283.56118) (xy 340.987866 -283.596435) (xy 341.018439 -283.637121)
			(xy 341.04209 -283.682184) (xy 341.058206 -283.730458) (xy 341.06637 -283.780692) (xy 341.066882 -283.806138)
			(xy 341.38541 -283.806138) (xy 341.38937 -283.757084) (xy 341.401147 -283.7093) (xy 341.420438 -283.664024)
			(xy 341.446741 -283.622428) (xy 341.479376 -283.585591) (xy 341.517497 -283.554466) (xy 341.560118 -283.529859)
			(xy 341.606134 -283.512407) (xy 341.654353 -283.502563) (xy 341.703528 -283.500582) (xy 341.752383 -283.506514)
			(xy 341.799654 -283.520206) (xy 341.844116 -283.541304) (xy 341.884619 -283.56926) (xy 341.920112 -283.603352)
			(xy 341.949677 -283.642696) (xy 341.972548 -283.686273) (xy 341.988132 -283.732954) (xy 341.996027 -283.781531)
			(xy 341.996522 -283.806138) (xy 342.314779 -283.806138) (xy 342.318874 -283.75541) (xy 342.331053 -283.705996)
			(xy 342.351001 -283.659176) (xy 342.378202 -283.616162) (xy 342.41195 -283.578068) (xy 342.451372 -283.545881)
			(xy 342.495446 -283.520435) (xy 342.543032 -283.502388) (xy 342.592896 -283.492208) (xy 342.643748 -283.490159)
			(xy 342.694269 -283.496293) (xy 342.743153 -283.510453) (xy 342.789132 -283.53227) (xy 342.831016 -283.56118)
			(xy 342.86772 -283.596435) (xy 342.898293 -283.637121) (xy 342.921944 -283.682184) (xy 342.93806 -283.730458)
			(xy 342.946224 -283.780692) (xy 342.946736 -283.806138) (xy 343.254833 -283.806138) (xy 343.258928 -283.75541)
			(xy 343.271107 -283.705996) (xy 343.291055 -283.659176) (xy 343.318256 -283.616162) (xy 343.352004 -283.578068)
			(xy 343.391426 -283.545881) (xy 343.4355 -283.520435) (xy 343.483086 -283.502388) (xy 343.53295 -283.492208)
			(xy 343.583802 -283.490159) (xy 343.634323 -283.496293) (xy 343.683207 -283.510453) (xy 343.729186 -283.53227)
			(xy 343.77107 -283.56118) (xy 343.807774 -283.596435) (xy 343.838347 -283.637121) (xy 343.861998 -283.682184)
			(xy 343.878114 -283.730458) (xy 343.886278 -283.780692) (xy 343.88679 -283.806138) (xy 343.886278 -283.831584)
			(xy 343.878114 -283.881818) (xy 343.861998 -283.930092) (xy 343.838347 -283.975155) (xy 343.807774 -284.015841)
			(xy 343.77107 -284.051096) (xy 343.729186 -284.080006) (xy 343.683207 -284.101823) (xy 343.634323 -284.115983)
			(xy 343.583802 -284.122117) (xy 343.53295 -284.120068) (xy 343.483086 -284.109888) (xy 343.4355 -284.091841)
			(xy 343.391426 -284.066395) (xy 343.352004 -284.034208) (xy 343.318256 -283.996114) (xy 343.291055 -283.9531)
			(xy 343.271107 -283.90628) (xy 343.258928 -283.856866) (xy 343.254833 -283.806138) (xy 342.946736 -283.806138)
			(xy 342.946224 -283.831584) (xy 342.93806 -283.881818) (xy 342.921944 -283.930092) (xy 342.898293 -283.975155)
			(xy 342.86772 -284.015841) (xy 342.831016 -284.051096) (xy 342.789132 -284.080006) (xy 342.743153 -284.101823)
			(xy 342.694269 -284.115983) (xy 342.643748 -284.122117) (xy 342.592896 -284.120068) (xy 342.543032 -284.109888)
			(xy 342.495446 -284.091841) (xy 342.451372 -284.066395) (xy 342.41195 -284.034208) (xy 342.378202 -283.996114)
			(xy 342.351001 -283.9531) (xy 342.331053 -283.90628) (xy 342.318874 -283.856866) (xy 342.314779 -283.806138)
			(xy 341.996522 -283.806138) (xy 341.996027 -283.830745) (xy 341.988132 -283.879322) (xy 341.972548 -283.926003)
			(xy 341.949677 -283.96958) (xy 341.920112 -284.008924) (xy 341.884619 -284.043016) (xy 341.844116 -284.070972)
			(xy 341.799654 -284.09207) (xy 341.752383 -284.105762) (xy 341.703528 -284.111694) (xy 341.654353 -284.109713)
			(xy 341.606134 -284.099869) (xy 341.560118 -284.082417) (xy 341.517497 -284.05781) (xy 341.479376 -284.026685)
			(xy 341.446741 -283.989848) (xy 341.420438 -283.948252) (xy 341.401147 -283.902976) (xy 341.38937 -283.855192)
			(xy 341.38541 -283.806138) (xy 341.066882 -283.806138) (xy 341.06637 -283.831584) (xy 341.058206 -283.881818)
			(xy 341.04209 -283.930092) (xy 341.018439 -283.975155) (xy 340.987866 -284.015841) (xy 340.951162 -284.051096)
			(xy 340.909278 -284.080006) (xy 340.863299 -284.101823) (xy 340.814415 -284.115983) (xy 340.763894 -284.122117)
			(xy 340.713042 -284.120068) (xy 340.663178 -284.109888) (xy 340.615592 -284.091841) (xy 340.571518 -284.066395)
			(xy 340.532096 -284.034208) (xy 340.498348 -283.996114) (xy 340.471147 -283.9531) (xy 340.451199 -283.90628)
			(xy 340.43902 -283.856866) (xy 340.434925 -283.806138) (xy 340.116414 -283.806138) (xy 340.115919 -283.830745)
			(xy 340.108024 -283.879322) (xy 340.09244 -283.926003) (xy 340.069569 -283.96958) (xy 340.040004 -284.008924)
			(xy 340.004511 -284.043016) (xy 339.964008 -284.070972) (xy 339.919546 -284.09207) (xy 339.872275 -284.105762)
			(xy 339.82342 -284.111694) (xy 339.774245 -284.109713) (xy 339.726026 -284.099869) (xy 339.68001 -284.082417)
			(xy 339.637389 -284.05781) (xy 339.599268 -284.026685) (xy 339.566633 -283.989848) (xy 339.54033 -283.948252)
			(xy 339.521039 -283.902976) (xy 339.509262 -283.855192) (xy 339.505302 -283.806138) (xy 339.186774 -283.806138)
			(xy 339.186262 -283.831584) (xy 339.178098 -283.881818) (xy 339.161982 -283.930092) (xy 339.138331 -283.975155)
			(xy 339.107758 -284.015841) (xy 339.071054 -284.051096) (xy 339.02917 -284.080006) (xy 338.983191 -284.101823)
			(xy 338.934307 -284.115983) (xy 338.883786 -284.122117) (xy 338.832934 -284.120068) (xy 338.78307 -284.109888)
			(xy 338.735484 -284.091841) (xy 338.69141 -284.066395) (xy 338.651988 -284.034208) (xy 338.61824 -283.996114)
			(xy 338.591039 -283.9531) (xy 338.571091 -283.90628) (xy 338.558912 -283.856866) (xy 338.554817 -283.806138)
			(xy 338.236306 -283.806138) (xy 338.235811 -283.830745) (xy 338.227916 -283.879322) (xy 338.212332 -283.926003)
			(xy 338.189461 -283.96958) (xy 338.159896 -284.008924) (xy 338.124403 -284.043016) (xy 338.0839 -284.070972)
			(xy 338.039438 -284.09207) (xy 337.992167 -284.105762) (xy 337.943312 -284.111694) (xy 337.894137 -284.109713)
			(xy 337.845918 -284.099869) (xy 337.799902 -284.082417) (xy 337.757281 -284.05781) (xy 337.71916 -284.026685)
			(xy 337.686525 -283.989848) (xy 337.660222 -283.948252) (xy 337.640931 -283.902976) (xy 337.629154 -283.855192)
			(xy 337.625194 -283.806138) (xy 337.296506 -283.806138) (xy 337.296011 -283.830745) (xy 337.288116 -283.879322)
			(xy 337.272532 -283.926003) (xy 337.249661 -283.96958) (xy 337.220096 -284.008924) (xy 337.184603 -284.043016)
			(xy 337.1441 -284.070972) (xy 337.099638 -284.09207) (xy 337.052367 -284.105762) (xy 337.003512 -284.111694)
			(xy 336.954337 -284.109713) (xy 336.906118 -284.099869) (xy 336.860102 -284.082417) (xy 336.817481 -284.05781)
			(xy 336.77936 -284.026685) (xy 336.746725 -283.989848) (xy 336.720422 -283.948252) (xy 336.701131 -283.902976)
			(xy 336.689354 -283.855192) (xy 336.685394 -283.806138) (xy 336.356452 -283.806138) (xy 336.355957 -283.830745)
			(xy 336.348062 -283.879322) (xy 336.332478 -283.926003) (xy 336.309607 -283.96958) (xy 336.280042 -284.008924)
			(xy 336.244549 -284.043016) (xy 336.204046 -284.070972) (xy 336.159584 -284.09207) (xy 336.112313 -284.105762)
			(xy 336.063458 -284.111694) (xy 336.014283 -284.109713) (xy 335.966064 -284.099869) (xy 335.920048 -284.082417)
			(xy 335.877427 -284.05781) (xy 335.839306 -284.026685) (xy 335.806671 -283.989848) (xy 335.780368 -283.948252)
			(xy 335.761077 -283.902976) (xy 335.7493 -283.855192) (xy 335.74534 -283.806138) (xy 335.416919 -283.806138)
			(xy 335.412751 -283.856438) (xy 335.400351 -283.905402) (xy 335.380061 -283.951658) (xy 335.352434 -283.993943)
			(xy 335.318224 -284.031104) (xy 335.278363 -284.062127) (xy 335.233941 -284.086167) (xy 335.186167 -284.102566)
			(xy 335.136345 -284.110878) (xy 335.11109 -284.111446) (xy 335.110582 -284.111446) (xy 335.097433 -284.111296)
			(xy 335.071234 -284.109004) (xy 335.058258 -284.106874) (xy 335.054448 -284.106366) (xy 335.04378 -284.109414)
			(xy 335.038891 -284.110948) (xy 335.029806 -284.115685) (xy 335.025746 -284.118812) (xy 334.967072 -284.169104)
			(xy 334.959454 -284.17667) (xy 334.950658 -284.19623) (xy 334.950054 -284.20695) (xy 334.950054 -284.616144)
			(xy 335.275186 -284.616144) (xy 335.279146 -284.56709) (xy 335.290923 -284.519306) (xy 335.310214 -284.47403)
			(xy 335.336517 -284.432434) (xy 335.369152 -284.395597) (xy 335.407273 -284.364472) (xy 335.449894 -284.339865)
			(xy 335.49591 -284.322413) (xy 335.544129 -284.312569) (xy 335.593304 -284.310588) (xy 335.642159 -284.31652)
			(xy 335.68943 -284.330212) (xy 335.733892 -284.35131) (xy 335.774395 -284.379266) (xy 335.809888 -284.413358)
			(xy 335.839453 -284.452702) (xy 335.862324 -284.496279) (xy 335.877908 -284.54296) (xy 335.885803 -284.591537)
			(xy 335.886298 -284.616144) (xy 336.21524 -284.616144) (xy 336.2192 -284.56709) (xy 336.230977 -284.519306)
			(xy 336.250268 -284.47403) (xy 336.276571 -284.432434) (xy 336.309206 -284.395597) (xy 336.347327 -284.364472)
			(xy 336.389948 -284.339865) (xy 336.435964 -284.322413) (xy 336.484183 -284.312569) (xy 336.533358 -284.310588)
			(xy 336.582213 -284.31652) (xy 336.629484 -284.330212) (xy 336.673946 -284.35131) (xy 336.714449 -284.379266)
			(xy 336.749942 -284.413358) (xy 336.779507 -284.452702) (xy 336.802378 -284.496279) (xy 336.817962 -284.54296)
			(xy 336.825857 -284.591537) (xy 336.826352 -284.616144) (xy 337.155294 -284.616144) (xy 337.159254 -284.56709)
			(xy 337.171031 -284.519306) (xy 337.190322 -284.47403) (xy 337.216625 -284.432434) (xy 337.24926 -284.395597)
			(xy 337.287381 -284.364472) (xy 337.330002 -284.339865) (xy 337.376018 -284.322413) (xy 337.424237 -284.312569)
			(xy 337.473412 -284.310588) (xy 337.522267 -284.31652) (xy 337.569538 -284.330212) (xy 337.614 -284.35131)
			(xy 337.654503 -284.379266) (xy 337.689996 -284.413358) (xy 337.719561 -284.452702) (xy 337.742432 -284.496279)
			(xy 337.758016 -284.54296) (xy 337.765911 -284.591537) (xy 337.766406 -284.616144) (xy 338.095348 -284.616144)
			(xy 338.099308 -284.56709) (xy 338.111085 -284.519306) (xy 338.130376 -284.47403) (xy 338.156679 -284.432434)
			(xy 338.189314 -284.395597) (xy 338.227435 -284.364472) (xy 338.270056 -284.339865) (xy 338.316072 -284.322413)
			(xy 338.364291 -284.312569) (xy 338.413466 -284.310588) (xy 338.462321 -284.31652) (xy 338.509592 -284.330212)
			(xy 338.554054 -284.35131) (xy 338.594557 -284.379266) (xy 338.63005 -284.413358) (xy 338.659615 -284.452702)
			(xy 338.682486 -284.496279) (xy 338.69807 -284.54296) (xy 338.705965 -284.591537) (xy 338.70646 -284.616144)
			(xy 339.024971 -284.616144) (xy 339.029066 -284.565416) (xy 339.041245 -284.516002) (xy 339.061193 -284.469182)
			(xy 339.088394 -284.426168) (xy 339.122142 -284.388074) (xy 339.161564 -284.355887) (xy 339.205638 -284.330441)
			(xy 339.253224 -284.312394) (xy 339.303088 -284.302214) (xy 339.35394 -284.300165) (xy 339.404461 -284.306299)
			(xy 339.453345 -284.320459) (xy 339.499324 -284.342276) (xy 339.541208 -284.371186) (xy 339.577912 -284.406441)
			(xy 339.608485 -284.447127) (xy 339.632136 -284.49219) (xy 339.648252 -284.540464) (xy 339.656416 -284.590698)
			(xy 339.656928 -284.616144) (xy 339.964771 -284.616144) (xy 339.968866 -284.565416) (xy 339.981045 -284.516002)
			(xy 340.000993 -284.469182) (xy 340.028194 -284.426168) (xy 340.061942 -284.388074) (xy 340.101364 -284.355887)
			(xy 340.145438 -284.330441) (xy 340.193024 -284.312394) (xy 340.242888 -284.302214) (xy 340.29374 -284.300165)
			(xy 340.344261 -284.306299) (xy 340.393145 -284.320459) (xy 340.439124 -284.342276) (xy 340.481008 -284.371186)
			(xy 340.517712 -284.406441) (xy 340.548285 -284.447127) (xy 340.571936 -284.49219) (xy 340.588052 -284.540464)
			(xy 340.596216 -284.590698) (xy 340.596728 -284.616144) (xy 340.915256 -284.616144) (xy 340.919216 -284.56709)
			(xy 340.930993 -284.519306) (xy 340.950284 -284.47403) (xy 340.976587 -284.432434) (xy 341.009222 -284.395597)
			(xy 341.047343 -284.364472) (xy 341.089964 -284.339865) (xy 341.13598 -284.322413) (xy 341.184199 -284.312569)
			(xy 341.233374 -284.310588) (xy 341.282229 -284.31652) (xy 341.3295 -284.330212) (xy 341.373962 -284.35131)
			(xy 341.414465 -284.379266) (xy 341.449958 -284.413358) (xy 341.479523 -284.452702) (xy 341.502394 -284.496279)
			(xy 341.517978 -284.54296) (xy 341.525873 -284.591537) (xy 341.526368 -284.616144) (xy 341.844879 -284.616144)
			(xy 341.848974 -284.565416) (xy 341.861153 -284.516002) (xy 341.881101 -284.469182) (xy 341.908302 -284.426168)
			(xy 341.94205 -284.388074) (xy 341.981472 -284.355887) (xy 342.025546 -284.330441) (xy 342.073132 -284.312394)
			(xy 342.122996 -284.302214) (xy 342.173848 -284.300165) (xy 342.224369 -284.306299) (xy 342.273253 -284.320459)
			(xy 342.319232 -284.342276) (xy 342.361116 -284.371186) (xy 342.39782 -284.406441) (xy 342.428393 -284.447127)
			(xy 342.452044 -284.49219) (xy 342.46816 -284.540464) (xy 342.476324 -284.590698) (xy 342.476836 -284.616144)
			(xy 342.795364 -284.616144) (xy 342.799324 -284.56709) (xy 342.811101 -284.519306) (xy 342.830392 -284.47403)
			(xy 342.856695 -284.432434) (xy 342.88933 -284.395597) (xy 342.927451 -284.364472) (xy 342.970072 -284.339865)
			(xy 343.016088 -284.322413) (xy 343.064307 -284.312569) (xy 343.113482 -284.310588) (xy 343.162337 -284.31652)
			(xy 343.209608 -284.330212) (xy 343.25407 -284.35131) (xy 343.294573 -284.379266) (xy 343.330066 -284.413358)
			(xy 343.359631 -284.452702) (xy 343.382502 -284.496279) (xy 343.398086 -284.54296) (xy 343.405981 -284.591537)
			(xy 343.406476 -284.616144) (xy 343.405981 -284.640751) (xy 343.398086 -284.689328) (xy 343.382502 -284.736009)
			(xy 343.359631 -284.779586) (xy 343.330066 -284.81893) (xy 343.294573 -284.853022) (xy 343.25407 -284.880978)
			(xy 343.209608 -284.902076) (xy 343.162337 -284.915768) (xy 343.113482 -284.9217) (xy 343.064307 -284.919719)
			(xy 343.016088 -284.909875) (xy 342.970072 -284.892423) (xy 342.927451 -284.867816) (xy 342.88933 -284.836691)
			(xy 342.856695 -284.799854) (xy 342.830392 -284.758258) (xy 342.811101 -284.712982) (xy 342.799324 -284.665198)
			(xy 342.795364 -284.616144) (xy 342.476836 -284.616144) (xy 342.476324 -284.64159) (xy 342.46816 -284.691824)
			(xy 342.452044 -284.740098) (xy 342.428393 -284.785161) (xy 342.39782 -284.825847) (xy 342.361116 -284.861102)
			(xy 342.319232 -284.890012) (xy 342.273253 -284.911829) (xy 342.224369 -284.925989) (xy 342.173848 -284.932123)
			(xy 342.122996 -284.930074) (xy 342.073132 -284.919894) (xy 342.025546 -284.901847) (xy 341.981472 -284.876401)
			(xy 341.94205 -284.844214) (xy 341.908302 -284.80612) (xy 341.881101 -284.763106) (xy 341.861153 -284.716286)
			(xy 341.848974 -284.666872) (xy 341.844879 -284.616144) (xy 341.526368 -284.616144) (xy 341.525873 -284.640751)
			(xy 341.517978 -284.689328) (xy 341.502394 -284.736009) (xy 341.479523 -284.779586) (xy 341.449958 -284.81893)
			(xy 341.414465 -284.853022) (xy 341.373962 -284.880978) (xy 341.3295 -284.902076) (xy 341.282229 -284.915768)
			(xy 341.233374 -284.9217) (xy 341.184199 -284.919719) (xy 341.13598 -284.909875) (xy 341.089964 -284.892423)
			(xy 341.047343 -284.867816) (xy 341.009222 -284.836691) (xy 340.976587 -284.799854) (xy 340.950284 -284.758258)
			(xy 340.930993 -284.712982) (xy 340.919216 -284.665198) (xy 340.915256 -284.616144) (xy 340.596728 -284.616144)
			(xy 340.596216 -284.64159) (xy 340.588052 -284.691824) (xy 340.571936 -284.740098) (xy 340.548285 -284.785161)
			(xy 340.517712 -284.825847) (xy 340.481008 -284.861102) (xy 340.439124 -284.890012) (xy 340.393145 -284.911829)
			(xy 340.344261 -284.925989) (xy 340.29374 -284.932123) (xy 340.242888 -284.930074) (xy 340.193024 -284.919894)
			(xy 340.145438 -284.901847) (xy 340.101364 -284.876401) (xy 340.061942 -284.844214) (xy 340.028194 -284.80612)
			(xy 340.000993 -284.763106) (xy 339.981045 -284.716286) (xy 339.968866 -284.666872) (xy 339.964771 -284.616144)
			(xy 339.656928 -284.616144) (xy 339.656416 -284.64159) (xy 339.648252 -284.691824) (xy 339.632136 -284.740098)
			(xy 339.608485 -284.785161) (xy 339.577912 -284.825847) (xy 339.541208 -284.861102) (xy 339.499324 -284.890012)
			(xy 339.453345 -284.911829) (xy 339.404461 -284.925989) (xy 339.35394 -284.932123) (xy 339.303088 -284.930074)
			(xy 339.253224 -284.919894) (xy 339.205638 -284.901847) (xy 339.161564 -284.876401) (xy 339.122142 -284.844214)
			(xy 339.088394 -284.80612) (xy 339.061193 -284.763106) (xy 339.041245 -284.716286) (xy 339.029066 -284.666872)
			(xy 339.024971 -284.616144) (xy 338.70646 -284.616144) (xy 338.705965 -284.640751) (xy 338.69807 -284.689328)
			(xy 338.682486 -284.736009) (xy 338.659615 -284.779586) (xy 338.63005 -284.81893) (xy 338.594557 -284.853022)
			(xy 338.554054 -284.880978) (xy 338.509592 -284.902076) (xy 338.462321 -284.915768) (xy 338.413466 -284.9217)
			(xy 338.364291 -284.919719) (xy 338.316072 -284.909875) (xy 338.270056 -284.892423) (xy 338.227435 -284.867816)
			(xy 338.189314 -284.836691) (xy 338.156679 -284.799854) (xy 338.130376 -284.758258) (xy 338.111085 -284.712982)
			(xy 338.099308 -284.665198) (xy 338.095348 -284.616144) (xy 337.766406 -284.616144) (xy 337.765911 -284.640751)
			(xy 337.758016 -284.689328) (xy 337.742432 -284.736009) (xy 337.719561 -284.779586) (xy 337.689996 -284.81893)
			(xy 337.654503 -284.853022) (xy 337.614 -284.880978) (xy 337.569538 -284.902076) (xy 337.522267 -284.915768)
			(xy 337.473412 -284.9217) (xy 337.424237 -284.919719) (xy 337.376018 -284.909875) (xy 337.330002 -284.892423)
			(xy 337.287381 -284.867816) (xy 337.24926 -284.836691) (xy 337.216625 -284.799854) (xy 337.190322 -284.758258)
			(xy 337.171031 -284.712982) (xy 337.159254 -284.665198) (xy 337.155294 -284.616144) (xy 336.826352 -284.616144)
			(xy 336.825857 -284.640751) (xy 336.817962 -284.689328) (xy 336.802378 -284.736009) (xy 336.779507 -284.779586)
			(xy 336.749942 -284.81893) (xy 336.714449 -284.853022) (xy 336.673946 -284.880978) (xy 336.629484 -284.902076)
			(xy 336.582213 -284.915768) (xy 336.533358 -284.9217) (xy 336.484183 -284.919719) (xy 336.435964 -284.909875)
			(xy 336.389948 -284.892423) (xy 336.347327 -284.867816) (xy 336.309206 -284.836691) (xy 336.276571 -284.799854)
			(xy 336.250268 -284.758258) (xy 336.230977 -284.712982) (xy 336.2192 -284.665198) (xy 336.21524 -284.616144)
			(xy 335.886298 -284.616144) (xy 335.885803 -284.640751) (xy 335.877908 -284.689328) (xy 335.862324 -284.736009)
			(xy 335.839453 -284.779586) (xy 335.809888 -284.81893) (xy 335.774395 -284.853022) (xy 335.733892 -284.880978)
			(xy 335.68943 -284.902076) (xy 335.642159 -284.915768) (xy 335.593304 -284.9217) (xy 335.544129 -284.919719)
			(xy 335.49591 -284.909875) (xy 335.449894 -284.892423) (xy 335.407273 -284.867816) (xy 335.369152 -284.836691)
			(xy 335.336517 -284.799854) (xy 335.310214 -284.758258) (xy 335.290923 -284.712982) (xy 335.279146 -284.665198)
			(xy 335.275186 -284.616144) (xy 334.950054 -284.616144) (xy 334.950054 -285.42615) (xy 335.74534 -285.42615)
			(xy 335.7493 -285.377096) (xy 335.761077 -285.329312) (xy 335.780368 -285.284036) (xy 335.806671 -285.24244)
			(xy 335.839306 -285.205603) (xy 335.877427 -285.174478) (xy 335.920048 -285.149871) (xy 335.966064 -285.132419)
			(xy 336.014283 -285.122575) (xy 336.063458 -285.120594) (xy 336.112313 -285.126526) (xy 336.159584 -285.140218)
			(xy 336.204046 -285.161316) (xy 336.244549 -285.189272) (xy 336.280042 -285.223364) (xy 336.309607 -285.262708)
			(xy 336.332478 -285.306285) (xy 336.348062 -285.352966) (xy 336.355957 -285.401543) (xy 336.356452 -285.42615)
			(xy 336.685394 -285.42615) (xy 336.689354 -285.377096) (xy 336.701131 -285.329312) (xy 336.720422 -285.284036)
			(xy 336.746725 -285.24244) (xy 336.77936 -285.205603) (xy 336.817481 -285.174478) (xy 336.860102 -285.149871)
			(xy 336.906118 -285.132419) (xy 336.954337 -285.122575) (xy 337.003512 -285.120594) (xy 337.052367 -285.126526)
			(xy 337.099638 -285.140218) (xy 337.1441 -285.161316) (xy 337.184603 -285.189272) (xy 337.220096 -285.223364)
			(xy 337.249661 -285.262708) (xy 337.272532 -285.306285) (xy 337.288116 -285.352966) (xy 337.296011 -285.401543)
			(xy 337.296506 -285.42615) (xy 337.625194 -285.42615) (xy 337.629154 -285.377096) (xy 337.640931 -285.329312)
			(xy 337.660222 -285.284036) (xy 337.686525 -285.24244) (xy 337.71916 -285.205603) (xy 337.757281 -285.174478)
			(xy 337.799902 -285.149871) (xy 337.845918 -285.132419) (xy 337.894137 -285.122575) (xy 337.943312 -285.120594)
			(xy 337.992167 -285.126526) (xy 338.039438 -285.140218) (xy 338.0839 -285.161316) (xy 338.124403 -285.189272)
			(xy 338.159896 -285.223364) (xy 338.189461 -285.262708) (xy 338.212332 -285.306285) (xy 338.227916 -285.352966)
			(xy 338.235811 -285.401543) (xy 338.236306 -285.42615) (xy 338.554817 -285.42615) (xy 338.558912 -285.375422)
			(xy 338.571091 -285.326008) (xy 338.591039 -285.279188) (xy 338.61824 -285.236174) (xy 338.651988 -285.19808)
			(xy 338.69141 -285.165893) (xy 338.735484 -285.140447) (xy 338.78307 -285.1224) (xy 338.832934 -285.11222)
			(xy 338.883786 -285.110171) (xy 338.934307 -285.116305) (xy 338.983191 -285.130465) (xy 339.02917 -285.152282)
			(xy 339.071054 -285.181192) (xy 339.107758 -285.216447) (xy 339.138331 -285.257133) (xy 339.161982 -285.302196)
			(xy 339.178098 -285.35047) (xy 339.186262 -285.400704) (xy 339.186774 -285.42615) (xy 339.505302 -285.42615)
			(xy 339.509262 -285.377096) (xy 339.521039 -285.329312) (xy 339.54033 -285.284036) (xy 339.566633 -285.24244)
			(xy 339.599268 -285.205603) (xy 339.637389 -285.174478) (xy 339.68001 -285.149871) (xy 339.726026 -285.132419)
			(xy 339.774245 -285.122575) (xy 339.82342 -285.120594) (xy 339.872275 -285.126526) (xy 339.919546 -285.140218)
			(xy 339.964008 -285.161316) (xy 340.004511 -285.189272) (xy 340.040004 -285.223364) (xy 340.069569 -285.262708)
			(xy 340.09244 -285.306285) (xy 340.108024 -285.352966) (xy 340.115919 -285.401543) (xy 340.116414 -285.42615)
			(xy 340.434925 -285.42615) (xy 340.43902 -285.375422) (xy 340.451199 -285.326008) (xy 340.471147 -285.279188)
			(xy 340.498348 -285.236174) (xy 340.532096 -285.19808) (xy 340.571518 -285.165893) (xy 340.615592 -285.140447)
			(xy 340.663178 -285.1224) (xy 340.713042 -285.11222) (xy 340.763894 -285.110171) (xy 340.814415 -285.116305)
			(xy 340.863299 -285.130465) (xy 340.909278 -285.152282) (xy 340.951162 -285.181192) (xy 340.987866 -285.216447)
			(xy 341.018439 -285.257133) (xy 341.04209 -285.302196) (xy 341.058206 -285.35047) (xy 341.06637 -285.400704)
			(xy 341.066882 -285.42615) (xy 342.314779 -285.42615) (xy 342.318874 -285.375422) (xy 342.331053 -285.326008)
			(xy 342.351001 -285.279188) (xy 342.378202 -285.236174) (xy 342.41195 -285.19808) (xy 342.451372 -285.165893)
			(xy 342.495446 -285.140447) (xy 342.543032 -285.1224) (xy 342.592896 -285.11222) (xy 342.643748 -285.110171)
			(xy 342.694269 -285.116305) (xy 342.743153 -285.130465) (xy 342.789132 -285.152282) (xy 342.831016 -285.181192)
			(xy 342.86772 -285.216447) (xy 342.898293 -285.257133) (xy 342.921944 -285.302196) (xy 342.93806 -285.35047)
			(xy 342.946224 -285.400704) (xy 342.946736 -285.42615) (xy 342.946224 -285.451596) (xy 342.93806 -285.50183)
			(xy 342.921944 -285.550104) (xy 342.898293 -285.595167) (xy 342.86772 -285.635853) (xy 342.831016 -285.671108)
			(xy 342.789132 -285.700018) (xy 342.743153 -285.721835) (xy 342.694269 -285.735995) (xy 342.643748 -285.742129)
			(xy 342.592896 -285.74008) (xy 342.543032 -285.7299) (xy 342.495446 -285.711853) (xy 342.451372 -285.686407)
			(xy 342.41195 -285.65422) (xy 342.378202 -285.616126) (xy 342.351001 -285.573112) (xy 342.331053 -285.526292)
			(xy 342.318874 -285.476878) (xy 342.314779 -285.42615) (xy 341.066882 -285.42615) (xy 341.06637 -285.451596)
			(xy 341.058206 -285.50183) (xy 341.04209 -285.550104) (xy 341.018439 -285.595167) (xy 340.987866 -285.635853)
			(xy 340.951162 -285.671108) (xy 340.909278 -285.700018) (xy 340.863299 -285.721835) (xy 340.814415 -285.735995)
			(xy 340.763894 -285.742129) (xy 340.713042 -285.74008) (xy 340.663178 -285.7299) (xy 340.615592 -285.711853)
			(xy 340.571518 -285.686407) (xy 340.532096 -285.65422) (xy 340.498348 -285.616126) (xy 340.471147 -285.573112)
			(xy 340.451199 -285.526292) (xy 340.43902 -285.476878) (xy 340.434925 -285.42615) (xy 340.116414 -285.42615)
			(xy 340.115919 -285.450757) (xy 340.108024 -285.499334) (xy 340.09244 -285.546015) (xy 340.069569 -285.589592)
			(xy 340.040004 -285.628936) (xy 340.004511 -285.663028) (xy 339.964008 -285.690984) (xy 339.919546 -285.712082)
			(xy 339.872275 -285.725774) (xy 339.82342 -285.731706) (xy 339.774245 -285.729725) (xy 339.726026 -285.719881)
			(xy 339.68001 -285.702429) (xy 339.637389 -285.677822) (xy 339.599268 -285.646697) (xy 339.566633 -285.60986)
			(xy 339.54033 -285.568264) (xy 339.521039 -285.522988) (xy 339.509262 -285.475204) (xy 339.505302 -285.42615)
			(xy 339.186774 -285.42615) (xy 339.186262 -285.451596) (xy 339.178098 -285.50183) (xy 339.161982 -285.550104)
			(xy 339.138331 -285.595167) (xy 339.107758 -285.635853) (xy 339.071054 -285.671108) (xy 339.02917 -285.700018)
			(xy 338.983191 -285.721835) (xy 338.934307 -285.735995) (xy 338.883786 -285.742129) (xy 338.832934 -285.74008)
			(xy 338.78307 -285.7299) (xy 338.735484 -285.711853) (xy 338.69141 -285.686407) (xy 338.651988 -285.65422)
			(xy 338.61824 -285.616126) (xy 338.591039 -285.573112) (xy 338.571091 -285.526292) (xy 338.558912 -285.476878)
			(xy 338.554817 -285.42615) (xy 338.236306 -285.42615) (xy 338.235811 -285.450757) (xy 338.227916 -285.499334)
			(xy 338.212332 -285.546015) (xy 338.189461 -285.589592) (xy 338.159896 -285.628936) (xy 338.124403 -285.663028)
			(xy 338.0839 -285.690984) (xy 338.039438 -285.712082) (xy 337.992167 -285.725774) (xy 337.943312 -285.731706)
			(xy 337.894137 -285.729725) (xy 337.845918 -285.719881) (xy 337.799902 -285.702429) (xy 337.757281 -285.677822)
			(xy 337.71916 -285.646697) (xy 337.686525 -285.60986) (xy 337.660222 -285.568264) (xy 337.640931 -285.522988)
			(xy 337.629154 -285.475204) (xy 337.625194 -285.42615) (xy 337.296506 -285.42615) (xy 337.296011 -285.450757)
			(xy 337.288116 -285.499334) (xy 337.272532 -285.546015) (xy 337.249661 -285.589592) (xy 337.220096 -285.628936)
			(xy 337.184603 -285.663028) (xy 337.1441 -285.690984) (xy 337.099638 -285.712082) (xy 337.052367 -285.725774)
			(xy 337.003512 -285.731706) (xy 336.954337 -285.729725) (xy 336.906118 -285.719881) (xy 336.860102 -285.702429)
			(xy 336.817481 -285.677822) (xy 336.77936 -285.646697) (xy 336.746725 -285.60986) (xy 336.720422 -285.568264)
			(xy 336.701131 -285.522988) (xy 336.689354 -285.475204) (xy 336.685394 -285.42615) (xy 336.356452 -285.42615)
			(xy 336.355957 -285.450757) (xy 336.348062 -285.499334) (xy 336.332478 -285.546015) (xy 336.309607 -285.589592)
			(xy 336.280042 -285.628936) (xy 336.244549 -285.663028) (xy 336.204046 -285.690984) (xy 336.159584 -285.712082)
			(xy 336.112313 -285.725774) (xy 336.063458 -285.731706) (xy 336.014283 -285.729725) (xy 335.966064 -285.719881)
			(xy 335.920048 -285.702429) (xy 335.877427 -285.677822) (xy 335.839306 -285.646697) (xy 335.806671 -285.60986)
			(xy 335.780368 -285.568264) (xy 335.761077 -285.522988) (xy 335.7493 -285.475204) (xy 335.74534 -285.42615)
			(xy 334.950054 -285.42615) (xy 334.950054 -286.236156) (xy 335.275186 -286.236156) (xy 335.279146 -286.187102)
			(xy 335.290923 -286.139318) (xy 335.310214 -286.094042) (xy 335.336517 -286.052446) (xy 335.369152 -286.015609)
			(xy 335.407273 -285.984484) (xy 335.449894 -285.959877) (xy 335.49591 -285.942425) (xy 335.544129 -285.932581)
			(xy 335.593304 -285.9306) (xy 335.642159 -285.936532) (xy 335.68943 -285.950224) (xy 335.733892 -285.971322)
			(xy 335.774395 -285.999278) (xy 335.809888 -286.03337) (xy 335.839453 -286.072714) (xy 335.862324 -286.116291)
			(xy 335.877908 -286.162972) (xy 335.885803 -286.211549) (xy 335.886298 -286.236156) (xy 336.21524 -286.236156)
			(xy 336.2192 -286.187102) (xy 336.230977 -286.139318) (xy 336.250268 -286.094042) (xy 336.276571 -286.052446)
			(xy 336.309206 -286.015609) (xy 336.347327 -285.984484) (xy 336.389948 -285.959877) (xy 336.435964 -285.942425)
			(xy 336.484183 -285.932581) (xy 336.533358 -285.9306) (xy 336.582213 -285.936532) (xy 336.629484 -285.950224)
			(xy 336.673946 -285.971322) (xy 336.714449 -285.999278) (xy 336.749942 -286.03337) (xy 336.779507 -286.072714)
			(xy 336.802378 -286.116291) (xy 336.817962 -286.162972) (xy 336.825857 -286.211549) (xy 336.826352 -286.236156)
			(xy 337.155294 -286.236156) (xy 337.159254 -286.187102) (xy 337.171031 -286.139318) (xy 337.190322 -286.094042)
			(xy 337.216625 -286.052446) (xy 337.24926 -286.015609) (xy 337.287381 -285.984484) (xy 337.330002 -285.959877)
			(xy 337.376018 -285.942425) (xy 337.424237 -285.932581) (xy 337.473412 -285.9306) (xy 337.522267 -285.936532)
			(xy 337.569538 -285.950224) (xy 337.614 -285.971322) (xy 337.654503 -285.999278) (xy 337.689996 -286.03337)
			(xy 337.719561 -286.072714) (xy 337.742432 -286.116291) (xy 337.758016 -286.162972) (xy 337.765911 -286.211549)
			(xy 337.766406 -286.236156) (xy 338.095348 -286.236156) (xy 338.099308 -286.187102) (xy 338.111085 -286.139318)
			(xy 338.130376 -286.094042) (xy 338.156679 -286.052446) (xy 338.189314 -286.015609) (xy 338.227435 -285.984484)
			(xy 338.270056 -285.959877) (xy 338.316072 -285.942425) (xy 338.364291 -285.932581) (xy 338.413466 -285.9306)
			(xy 338.462321 -285.936532) (xy 338.509592 -285.950224) (xy 338.554054 -285.971322) (xy 338.594557 -285.999278)
			(xy 338.63005 -286.03337) (xy 338.659615 -286.072714) (xy 338.682486 -286.116291) (xy 338.69807 -286.162972)
			(xy 338.705965 -286.211549) (xy 338.70646 -286.236156) (xy 339.024971 -286.236156) (xy 339.029066 -286.185428)
			(xy 339.041245 -286.136014) (xy 339.061193 -286.089194) (xy 339.088394 -286.04618) (xy 339.122142 -286.008086)
			(xy 339.161564 -285.975899) (xy 339.205638 -285.950453) (xy 339.253224 -285.932406) (xy 339.303088 -285.922226)
			(xy 339.35394 -285.920177) (xy 339.404461 -285.926311) (xy 339.453345 -285.940471) (xy 339.499324 -285.962288)
			(xy 339.541208 -285.991198) (xy 339.577912 -286.026453) (xy 339.608485 -286.067139) (xy 339.632136 -286.112202)
			(xy 339.648252 -286.160476) (xy 339.656416 -286.21071) (xy 339.656928 -286.236156) (xy 339.964771 -286.236156)
			(xy 339.968866 -286.185428) (xy 339.981045 -286.136014) (xy 340.000993 -286.089194) (xy 340.028194 -286.04618)
			(xy 340.061942 -286.008086) (xy 340.101364 -285.975899) (xy 340.145438 -285.950453) (xy 340.193024 -285.932406)
			(xy 340.242888 -285.922226) (xy 340.29374 -285.920177) (xy 340.344261 -285.926311) (xy 340.393145 -285.940471)
			(xy 340.439124 -285.962288) (xy 340.481008 -285.991198) (xy 340.517712 -286.026453) (xy 340.548285 -286.067139)
			(xy 340.571936 -286.112202) (xy 340.588052 -286.160476) (xy 340.596216 -286.21071) (xy 340.596728 -286.236156)
			(xy 340.915256 -286.236156) (xy 340.919216 -286.187102) (xy 340.930993 -286.139318) (xy 340.950284 -286.094042)
			(xy 340.976587 -286.052446) (xy 341.009222 -286.015609) (xy 341.047343 -285.984484) (xy 341.089964 -285.959877)
			(xy 341.13598 -285.942425) (xy 341.184199 -285.932581) (xy 341.233374 -285.9306) (xy 341.282229 -285.936532)
			(xy 341.3295 -285.950224) (xy 341.373962 -285.971322) (xy 341.414465 -285.999278) (xy 341.449958 -286.03337)
			(xy 341.479523 -286.072714) (xy 341.502394 -286.116291) (xy 341.517978 -286.162972) (xy 341.525873 -286.211549)
			(xy 341.526368 -286.236156) (xy 341.844879 -286.236156) (xy 341.848974 -286.185428) (xy 341.861153 -286.136014)
			(xy 341.881101 -286.089194) (xy 341.908302 -286.04618) (xy 341.94205 -286.008086) (xy 341.981472 -285.975899)
			(xy 342.025546 -285.950453) (xy 342.073132 -285.932406) (xy 342.122996 -285.922226) (xy 342.173848 -285.920177)
			(xy 342.224369 -285.926311) (xy 342.273253 -285.940471) (xy 342.319232 -285.962288) (xy 342.361116 -285.991198)
			(xy 342.39782 -286.026453) (xy 342.428393 -286.067139) (xy 342.452044 -286.112202) (xy 342.46816 -286.160476)
			(xy 342.476324 -286.21071) (xy 342.476836 -286.236156) (xy 342.476324 -286.261602) (xy 342.46816 -286.311836)
			(xy 342.452044 -286.36011) (xy 342.428393 -286.405173) (xy 342.39782 -286.445859) (xy 342.361116 -286.481114)
			(xy 342.319232 -286.510024) (xy 342.273253 -286.531841) (xy 342.224369 -286.546001) (xy 342.173848 -286.552135)
			(xy 342.122996 -286.550086) (xy 342.073132 -286.539906) (xy 342.025546 -286.521859) (xy 341.981472 -286.496413)
			(xy 341.94205 -286.464226) (xy 341.908302 -286.426132) (xy 341.881101 -286.383118) (xy 341.861153 -286.336298)
			(xy 341.848974 -286.286884) (xy 341.844879 -286.236156) (xy 341.526368 -286.236156) (xy 341.525873 -286.260763)
			(xy 341.517978 -286.30934) (xy 341.502394 -286.356021) (xy 341.479523 -286.399598) (xy 341.449958 -286.438942)
			(xy 341.414465 -286.473034) (xy 341.373962 -286.50099) (xy 341.3295 -286.522088) (xy 341.282229 -286.53578)
			(xy 341.233374 -286.541712) (xy 341.184199 -286.539731) (xy 341.13598 -286.529887) (xy 341.089964 -286.512435)
			(xy 341.047343 -286.487828) (xy 341.009222 -286.456703) (xy 340.976587 -286.419866) (xy 340.950284 -286.37827)
			(xy 340.930993 -286.332994) (xy 340.919216 -286.28521) (xy 340.915256 -286.236156) (xy 340.596728 -286.236156)
			(xy 340.596216 -286.261602) (xy 340.588052 -286.311836) (xy 340.571936 -286.36011) (xy 340.548285 -286.405173)
			(xy 340.517712 -286.445859) (xy 340.481008 -286.481114) (xy 340.439124 -286.510024) (xy 340.393145 -286.531841)
			(xy 340.344261 -286.546001) (xy 340.29374 -286.552135) (xy 340.242888 -286.550086) (xy 340.193024 -286.539906)
			(xy 340.145438 -286.521859) (xy 340.101364 -286.496413) (xy 340.061942 -286.464226) (xy 340.028194 -286.426132)
			(xy 340.000993 -286.383118) (xy 339.981045 -286.336298) (xy 339.968866 -286.286884) (xy 339.964771 -286.236156)
			(xy 339.656928 -286.236156) (xy 339.656416 -286.261602) (xy 339.648252 -286.311836) (xy 339.632136 -286.36011)
			(xy 339.608485 -286.405173) (xy 339.577912 -286.445859) (xy 339.541208 -286.481114) (xy 339.499324 -286.510024)
			(xy 339.453345 -286.531841) (xy 339.404461 -286.546001) (xy 339.35394 -286.552135) (xy 339.303088 -286.550086)
			(xy 339.253224 -286.539906) (xy 339.205638 -286.521859) (xy 339.161564 -286.496413) (xy 339.122142 -286.464226)
			(xy 339.088394 -286.426132) (xy 339.061193 -286.383118) (xy 339.041245 -286.336298) (xy 339.029066 -286.286884)
			(xy 339.024971 -286.236156) (xy 338.70646 -286.236156) (xy 338.705965 -286.260763) (xy 338.69807 -286.30934)
			(xy 338.682486 -286.356021) (xy 338.659615 -286.399598) (xy 338.63005 -286.438942) (xy 338.594557 -286.473034)
			(xy 338.554054 -286.50099) (xy 338.509592 -286.522088) (xy 338.462321 -286.53578) (xy 338.413466 -286.541712)
			(xy 338.364291 -286.539731) (xy 338.316072 -286.529887) (xy 338.270056 -286.512435) (xy 338.227435 -286.487828)
			(xy 338.189314 -286.456703) (xy 338.156679 -286.419866) (xy 338.130376 -286.37827) (xy 338.111085 -286.332994)
			(xy 338.099308 -286.28521) (xy 338.095348 -286.236156) (xy 337.766406 -286.236156) (xy 337.765911 -286.260763)
			(xy 337.758016 -286.30934) (xy 337.742432 -286.356021) (xy 337.719561 -286.399598) (xy 337.689996 -286.438942)
			(xy 337.654503 -286.473034) (xy 337.614 -286.50099) (xy 337.569538 -286.522088) (xy 337.522267 -286.53578)
			(xy 337.473412 -286.541712) (xy 337.424237 -286.539731) (xy 337.376018 -286.529887) (xy 337.330002 -286.512435)
			(xy 337.287381 -286.487828) (xy 337.24926 -286.456703) (xy 337.216625 -286.419866) (xy 337.190322 -286.37827)
			(xy 337.171031 -286.332994) (xy 337.159254 -286.28521) (xy 337.155294 -286.236156) (xy 336.826352 -286.236156)
			(xy 336.825857 -286.260763) (xy 336.817962 -286.30934) (xy 336.802378 -286.356021) (xy 336.779507 -286.399598)
			(xy 336.749942 -286.438942) (xy 336.714449 -286.473034) (xy 336.673946 -286.50099) (xy 336.629484 -286.522088)
			(xy 336.582213 -286.53578) (xy 336.533358 -286.541712) (xy 336.484183 -286.539731) (xy 336.435964 -286.529887)
			(xy 336.389948 -286.512435) (xy 336.347327 -286.487828) (xy 336.309206 -286.456703) (xy 336.276571 -286.419866)
			(xy 336.250268 -286.37827) (xy 336.230977 -286.332994) (xy 336.2192 -286.28521) (xy 336.21524 -286.236156)
			(xy 335.886298 -286.236156) (xy 335.885803 -286.260763) (xy 335.877908 -286.30934) (xy 335.862324 -286.356021)
			(xy 335.839453 -286.399598) (xy 335.809888 -286.438942) (xy 335.774395 -286.473034) (xy 335.733892 -286.50099)
			(xy 335.68943 -286.522088) (xy 335.642159 -286.53578) (xy 335.593304 -286.541712) (xy 335.544129 -286.539731)
			(xy 335.49591 -286.529887) (xy 335.449894 -286.512435) (xy 335.407273 -286.487828) (xy 335.369152 -286.456703)
			(xy 335.336517 -286.419866) (xy 335.310214 -286.37827) (xy 335.290923 -286.332994) (xy 335.279146 -286.28521)
			(xy 335.275186 -286.236156) (xy 334.950054 -286.236156) (xy 334.950054 -286.644588) (xy 334.950054 -286.647128)
			(xy 334.950968 -286.656794) (xy 334.959072 -286.674419) (xy 334.965802 -286.681418) (xy 335.024476 -286.731964)
			(xy 335.028709 -286.735438) (xy 335.038319 -286.740683) (xy 335.043526 -286.742378) (xy 335.054194 -286.745426)
			(xy 335.065116 -286.743902) (xy 335.076354 -286.742346) (xy 335.098983 -286.740691) (xy 335.110328 -286.7406)
			(xy 335.11109 -286.7406) (xy 335.136348 -286.741092) (xy 335.186174 -286.749405) (xy 335.233953 -286.765806)
			(xy 335.27838 -286.789847) (xy 335.318244 -286.820874) (xy 335.352458 -286.858038) (xy 335.380087 -286.900328)
			(xy 335.400379 -286.946588) (xy 335.41278 -286.995557) (xy 335.416952 -287.0459) (xy 335.416951 -287.045908)
			(xy 335.74534 -287.045908) (xy 335.7493 -286.996854) (xy 335.761077 -286.94907) (xy 335.780368 -286.903794)
			(xy 335.806671 -286.862198) (xy 335.839306 -286.825361) (xy 335.877427 -286.794236) (xy 335.920048 -286.769629)
			(xy 335.966064 -286.752177) (xy 336.014283 -286.742333) (xy 336.063458 -286.740352) (xy 336.112313 -286.746284)
			(xy 336.159584 -286.759976) (xy 336.204046 -286.781074) (xy 336.244549 -286.80903) (xy 336.280042 -286.843122)
			(xy 336.309607 -286.882466) (xy 336.332478 -286.926043) (xy 336.348062 -286.972724) (xy 336.355957 -287.021301)
			(xy 336.356452 -287.045908) (xy 336.685394 -287.045908) (xy 336.689354 -286.996854) (xy 336.701131 -286.94907)
			(xy 336.720422 -286.903794) (xy 336.746725 -286.862198) (xy 336.77936 -286.825361) (xy 336.817481 -286.794236)
			(xy 336.860102 -286.769629) (xy 336.906118 -286.752177) (xy 336.954337 -286.742333) (xy 337.003512 -286.740352)
			(xy 337.052367 -286.746284) (xy 337.099638 -286.759976) (xy 337.1441 -286.781074) (xy 337.184603 -286.80903)
			(xy 337.220096 -286.843122) (xy 337.249661 -286.882466) (xy 337.272532 -286.926043) (xy 337.288116 -286.972724)
			(xy 337.296011 -287.021301) (xy 337.296506 -287.045908) (xy 337.625702 -287.045908) (xy 337.629662 -286.996854)
			(xy 337.641439 -286.94907) (xy 337.66073 -286.903794) (xy 337.687033 -286.862198) (xy 337.719668 -286.825361)
			(xy 337.757789 -286.794236) (xy 337.80041 -286.769629) (xy 337.846426 -286.752177) (xy 337.894645 -286.742333)
			(xy 337.94382 -286.740352) (xy 337.992675 -286.746284) (xy 338.039946 -286.759976) (xy 338.084408 -286.781074)
			(xy 338.124911 -286.80903) (xy 338.160404 -286.843122) (xy 338.189969 -286.882466) (xy 338.21284 -286.926043)
			(xy 338.228424 -286.972724) (xy 338.236319 -287.021301) (xy 338.236814 -287.045908) (xy 338.554817 -287.045908)
			(xy 338.558912 -286.99518) (xy 338.571091 -286.945766) (xy 338.591039 -286.898946) (xy 338.61824 -286.855932)
			(xy 338.651988 -286.817838) (xy 338.69141 -286.785651) (xy 338.735484 -286.760205) (xy 338.78307 -286.742158)
			(xy 338.832934 -286.731978) (xy 338.883786 -286.729929) (xy 338.934307 -286.736063) (xy 338.983191 -286.750223)
			(xy 339.02917 -286.77204) (xy 339.071054 -286.80095) (xy 339.107758 -286.836205) (xy 339.138331 -286.876891)
			(xy 339.161982 -286.921954) (xy 339.178098 -286.970228) (xy 339.186262 -287.020462) (xy 339.186774 -287.045908)
			(xy 339.505302 -287.045908) (xy 339.509262 -286.996854) (xy 339.521039 -286.94907) (xy 339.54033 -286.903794)
			(xy 339.566633 -286.862198) (xy 339.599268 -286.825361) (xy 339.637389 -286.794236) (xy 339.68001 -286.769629)
			(xy 339.726026 -286.752177) (xy 339.774245 -286.742333) (xy 339.82342 -286.740352) (xy 339.872275 -286.746284)
			(xy 339.919546 -286.759976) (xy 339.964008 -286.781074) (xy 340.004511 -286.80903) (xy 340.040004 -286.843122)
			(xy 340.069569 -286.882466) (xy 340.09244 -286.926043) (xy 340.108024 -286.972724) (xy 340.115919 -287.021301)
			(xy 340.116414 -287.045908) (xy 340.434925 -287.045908) (xy 340.43902 -286.99518) (xy 340.451199 -286.945766)
			(xy 340.471147 -286.898946) (xy 340.498348 -286.855932) (xy 340.532096 -286.817838) (xy 340.571518 -286.785651)
			(xy 340.615592 -286.760205) (xy 340.663178 -286.742158) (xy 340.713042 -286.731978) (xy 340.763894 -286.729929)
			(xy 340.814415 -286.736063) (xy 340.863299 -286.750223) (xy 340.909278 -286.77204) (xy 340.951162 -286.80095)
			(xy 340.987866 -286.836205) (xy 341.018439 -286.876891) (xy 341.04209 -286.921954) (xy 341.058206 -286.970228)
			(xy 341.06637 -287.020462) (xy 341.066882 -287.045908) (xy 341.38541 -287.045908) (xy 341.38937 -286.996854)
			(xy 341.401147 -286.94907) (xy 341.420438 -286.903794) (xy 341.446741 -286.862198) (xy 341.479376 -286.825361)
			(xy 341.517497 -286.794236) (xy 341.560118 -286.769629) (xy 341.606134 -286.752177) (xy 341.654353 -286.742333)
			(xy 341.703528 -286.740352) (xy 341.752383 -286.746284) (xy 341.799654 -286.759976) (xy 341.844116 -286.781074)
			(xy 341.884619 -286.80903) (xy 341.920112 -286.843122) (xy 341.949677 -286.882466) (xy 341.972548 -286.926043)
			(xy 341.988132 -286.972724) (xy 341.996027 -287.021301) (xy 341.996522 -287.045908) (xy 342.314779 -287.045908)
			(xy 342.318874 -286.99518) (xy 342.331053 -286.945766) (xy 342.351001 -286.898946) (xy 342.378202 -286.855932)
			(xy 342.41195 -286.817838) (xy 342.451372 -286.785651) (xy 342.495446 -286.760205) (xy 342.543032 -286.742158)
			(xy 342.592896 -286.731978) (xy 342.643748 -286.729929) (xy 342.694269 -286.736063) (xy 342.743153 -286.750223)
			(xy 342.789132 -286.77204) (xy 342.831016 -286.80095) (xy 342.86772 -286.836205) (xy 342.898293 -286.876891)
			(xy 342.921944 -286.921954) (xy 342.93806 -286.970228) (xy 342.946224 -287.020462) (xy 342.946736 -287.045908)
			(xy 342.946224 -287.071354) (xy 342.93806 -287.121588) (xy 342.921944 -287.169862) (xy 342.898293 -287.214925)
			(xy 342.86772 -287.255611) (xy 342.831016 -287.290866) (xy 342.789132 -287.319776) (xy 342.743153 -287.341593)
			(xy 342.694269 -287.355753) (xy 342.643748 -287.361887) (xy 342.592896 -287.359838) (xy 342.543032 -287.349658)
			(xy 342.495446 -287.331611) (xy 342.451372 -287.306165) (xy 342.41195 -287.273978) (xy 342.378202 -287.235884)
			(xy 342.351001 -287.19287) (xy 342.331053 -287.14605) (xy 342.318874 -287.096636) (xy 342.314779 -287.045908)
			(xy 341.996522 -287.045908) (xy 341.996027 -287.070515) (xy 341.988132 -287.119092) (xy 341.972548 -287.165773)
			(xy 341.949677 -287.20935) (xy 341.920112 -287.248694) (xy 341.884619 -287.282786) (xy 341.844116 -287.310742)
			(xy 341.799654 -287.33184) (xy 341.752383 -287.345532) (xy 341.703528 -287.351464) (xy 341.654353 -287.349483)
			(xy 341.606134 -287.339639) (xy 341.560118 -287.322187) (xy 341.517497 -287.29758) (xy 341.479376 -287.266455)
			(xy 341.446741 -287.229618) (xy 341.420438 -287.188022) (xy 341.401147 -287.142746) (xy 341.38937 -287.094962)
			(xy 341.38541 -287.045908) (xy 341.066882 -287.045908) (xy 341.06637 -287.071354) (xy 341.058206 -287.121588)
			(xy 341.04209 -287.169862) (xy 341.018439 -287.214925) (xy 340.987866 -287.255611) (xy 340.951162 -287.290866)
			(xy 340.909278 -287.319776) (xy 340.863299 -287.341593) (xy 340.814415 -287.355753) (xy 340.763894 -287.361887)
			(xy 340.713042 -287.359838) (xy 340.663178 -287.349658) (xy 340.615592 -287.331611) (xy 340.571518 -287.306165)
			(xy 340.532096 -287.273978) (xy 340.498348 -287.235884) (xy 340.471147 -287.19287) (xy 340.451199 -287.14605)
			(xy 340.43902 -287.096636) (xy 340.434925 -287.045908) (xy 340.116414 -287.045908) (xy 340.115919 -287.070515)
			(xy 340.108024 -287.119092) (xy 340.09244 -287.165773) (xy 340.069569 -287.20935) (xy 340.040004 -287.248694)
			(xy 340.004511 -287.282786) (xy 339.964008 -287.310742) (xy 339.919546 -287.33184) (xy 339.872275 -287.345532)
			(xy 339.82342 -287.351464) (xy 339.774245 -287.349483) (xy 339.726026 -287.339639) (xy 339.68001 -287.322187)
			(xy 339.637389 -287.29758) (xy 339.599268 -287.266455) (xy 339.566633 -287.229618) (xy 339.54033 -287.188022)
			(xy 339.521039 -287.142746) (xy 339.509262 -287.094962) (xy 339.505302 -287.045908) (xy 339.186774 -287.045908)
			(xy 339.186262 -287.071354) (xy 339.178098 -287.121588) (xy 339.161982 -287.169862) (xy 339.138331 -287.214925)
			(xy 339.107758 -287.255611) (xy 339.071054 -287.290866) (xy 339.02917 -287.319776) (xy 338.983191 -287.341593)
			(xy 338.934307 -287.355753) (xy 338.883786 -287.361887) (xy 338.832934 -287.359838) (xy 338.78307 -287.349658)
			(xy 338.735484 -287.331611) (xy 338.69141 -287.306165) (xy 338.651988 -287.273978) (xy 338.61824 -287.235884)
			(xy 338.591039 -287.19287) (xy 338.571091 -287.14605) (xy 338.558912 -287.096636) (xy 338.554817 -287.045908)
			(xy 338.236814 -287.045908) (xy 338.236319 -287.070515) (xy 338.228424 -287.119092) (xy 338.21284 -287.165773)
			(xy 338.189969 -287.20935) (xy 338.160404 -287.248694) (xy 338.124911 -287.282786) (xy 338.084408 -287.310742)
			(xy 338.039946 -287.33184) (xy 337.992675 -287.345532) (xy 337.94382 -287.351464) (xy 337.894645 -287.349483)
			(xy 337.846426 -287.339639) (xy 337.80041 -287.322187) (xy 337.757789 -287.29758) (xy 337.719668 -287.266455)
			(xy 337.687033 -287.229618) (xy 337.66073 -287.188022) (xy 337.641439 -287.142746) (xy 337.629662 -287.094962)
			(xy 337.625702 -287.045908) (xy 337.296506 -287.045908) (xy 337.296011 -287.070515) (xy 337.288116 -287.119092)
			(xy 337.272532 -287.165773) (xy 337.249661 -287.20935) (xy 337.220096 -287.248694) (xy 337.184603 -287.282786)
			(xy 337.1441 -287.310742) (xy 337.099638 -287.33184) (xy 337.052367 -287.345532) (xy 337.003512 -287.351464)
			(xy 336.954337 -287.349483) (xy 336.906118 -287.339639) (xy 336.860102 -287.322187) (xy 336.817481 -287.29758)
			(xy 336.77936 -287.266455) (xy 336.746725 -287.229618) (xy 336.720422 -287.188022) (xy 336.701131 -287.142746)
			(xy 336.689354 -287.094962) (xy 336.685394 -287.045908) (xy 336.356452 -287.045908) (xy 336.355957 -287.070515)
			(xy 336.348062 -287.119092) (xy 336.332478 -287.165773) (xy 336.309607 -287.20935) (xy 336.280042 -287.248694)
			(xy 336.244549 -287.282786) (xy 336.204046 -287.310742) (xy 336.159584 -287.33184) (xy 336.112313 -287.345532)
			(xy 336.063458 -287.351464) (xy 336.014283 -287.349483) (xy 335.966064 -287.339639) (xy 335.920048 -287.322187)
			(xy 335.877427 -287.29758) (xy 335.839306 -287.266455) (xy 335.806671 -287.229618) (xy 335.780368 -287.188022)
			(xy 335.761077 -287.142746) (xy 335.7493 -287.094962) (xy 335.74534 -287.045908) (xy 335.416951 -287.045908)
			(xy 335.41278 -287.096243) (xy 335.400379 -287.145212) (xy 335.380087 -287.191472) (xy 335.352458 -287.233762)
			(xy 335.318244 -287.270926) (xy 335.27838 -287.301953) (xy 335.233953 -287.325994) (xy 335.186174 -287.342395)
			(xy 335.136348 -287.350708) (xy 335.11109 -287.351216) (xy 335.110582 -287.351216) (xy 335.097433 -287.351067)
			(xy 335.071234 -287.348775) (xy 335.058258 -287.346644) (xy 335.054448 -287.346136) (xy 335.04378 -287.349184)
			(xy 335.03889 -287.350717) (xy 335.029803 -287.355452) (xy 335.025746 -287.358582) (xy 334.967072 -287.408874)
			(xy 334.959449 -287.416439) (xy 334.950642 -287.435998) (xy 334.950054 -287.44672) (xy 334.950054 -287.73755)
			(xy 334.952848 -287.745932) (xy 334.961677 -287.772635) (xy 334.971251 -287.828051) (xy 334.971898 -287.856168)
			(xy 335.275186 -287.856168) (xy 335.279146 -287.807114) (xy 335.290923 -287.75933) (xy 335.310214 -287.714054)
			(xy 335.336517 -287.672458) (xy 335.369152 -287.635621) (xy 335.407273 -287.604496) (xy 335.449894 -287.579889)
			(xy 335.49591 -287.562437) (xy 335.544129 -287.552593) (xy 335.593304 -287.550612) (xy 335.642159 -287.556544)
			(xy 335.68943 -287.570236) (xy 335.733892 -287.591334) (xy 335.774395 -287.61929) (xy 335.809888 -287.653382)
			(xy 335.839453 -287.692726) (xy 335.862324 -287.736303) (xy 335.877908 -287.782984) (xy 335.885803 -287.831561)
			(xy 335.886298 -287.856168) (xy 336.21524 -287.856168) (xy 336.2192 -287.807114) (xy 336.230977 -287.75933)
			(xy 336.250268 -287.714054) (xy 336.276571 -287.672458) (xy 336.309206 -287.635621) (xy 336.347327 -287.604496)
			(xy 336.389948 -287.579889) (xy 336.435964 -287.562437) (xy 336.484183 -287.552593) (xy 336.533358 -287.550612)
			(xy 336.582213 -287.556544) (xy 336.629484 -287.570236) (xy 336.673946 -287.591334) (xy 336.714449 -287.61929)
			(xy 336.749942 -287.653382) (xy 336.779507 -287.692726) (xy 336.802378 -287.736303) (xy 336.817962 -287.782984)
			(xy 336.825857 -287.831561) (xy 336.826352 -287.856168) (xy 337.155294 -287.856168) (xy 337.159254 -287.807114)
			(xy 337.171031 -287.75933) (xy 337.190322 -287.714054) (xy 337.216625 -287.672458) (xy 337.24926 -287.635621)
			(xy 337.287381 -287.604496) (xy 337.330002 -287.579889) (xy 337.376018 -287.562437) (xy 337.424237 -287.552593)
			(xy 337.473412 -287.550612) (xy 337.522267 -287.556544) (xy 337.569538 -287.570236) (xy 337.614 -287.591334)
			(xy 337.654503 -287.61929) (xy 337.689996 -287.653382) (xy 337.719561 -287.692726) (xy 337.742432 -287.736303)
			(xy 337.758016 -287.782984) (xy 337.765911 -287.831561) (xy 337.766406 -287.856168) (xy 338.095348 -287.856168)
			(xy 338.099308 -287.807114) (xy 338.111085 -287.75933) (xy 338.130376 -287.714054) (xy 338.156679 -287.672458)
			(xy 338.189314 -287.635621) (xy 338.227435 -287.604496) (xy 338.270056 -287.579889) (xy 338.316072 -287.562437)
			(xy 338.364291 -287.552593) (xy 338.413466 -287.550612) (xy 338.462321 -287.556544) (xy 338.509592 -287.570236)
			(xy 338.554054 -287.591334) (xy 338.594557 -287.61929) (xy 338.63005 -287.653382) (xy 338.659615 -287.692726)
			(xy 338.682486 -287.736303) (xy 338.69807 -287.782984) (xy 338.705965 -287.831561) (xy 338.70646 -287.856168)
			(xy 339.024971 -287.856168) (xy 339.029066 -287.80544) (xy 339.041245 -287.756026) (xy 339.061193 -287.709206)
			(xy 339.088394 -287.666192) (xy 339.122142 -287.628098) (xy 339.161564 -287.595911) (xy 339.205638 -287.570465)
			(xy 339.253224 -287.552418) (xy 339.303088 -287.542238) (xy 339.35394 -287.540189) (xy 339.404461 -287.546323)
			(xy 339.453345 -287.560483) (xy 339.499324 -287.5823) (xy 339.541208 -287.61121) (xy 339.577912 -287.646465)
			(xy 339.608485 -287.687151) (xy 339.632136 -287.732214) (xy 339.648252 -287.780488) (xy 339.656416 -287.830722)
			(xy 339.656928 -287.856168) (xy 339.964771 -287.856168) (xy 339.968866 -287.80544) (xy 339.981045 -287.756026)
			(xy 340.000993 -287.709206) (xy 340.028194 -287.666192) (xy 340.061942 -287.628098) (xy 340.101364 -287.595911)
			(xy 340.145438 -287.570465) (xy 340.193024 -287.552418) (xy 340.242888 -287.542238) (xy 340.29374 -287.540189)
			(xy 340.344261 -287.546323) (xy 340.393145 -287.560483) (xy 340.439124 -287.5823) (xy 340.481008 -287.61121)
			(xy 340.517712 -287.646465) (xy 340.548285 -287.687151) (xy 340.571936 -287.732214) (xy 340.588052 -287.780488)
			(xy 340.596216 -287.830722) (xy 340.596728 -287.856168) (xy 341.844879 -287.856168) (xy 341.848974 -287.80544)
			(xy 341.861153 -287.756026) (xy 341.881101 -287.709206) (xy 341.908302 -287.666192) (xy 341.94205 -287.628098)
			(xy 341.981472 -287.595911) (xy 342.025546 -287.570465) (xy 342.073132 -287.552418) (xy 342.122996 -287.542238)
			(xy 342.173848 -287.540189) (xy 342.224369 -287.546323) (xy 342.273253 -287.560483) (xy 342.319232 -287.5823)
			(xy 342.361116 -287.61121) (xy 342.39782 -287.646465) (xy 342.428393 -287.687151) (xy 342.452044 -287.732214)
			(xy 342.46816 -287.780488) (xy 342.476324 -287.830722) (xy 342.476836 -287.856168) (xy 342.476324 -287.881614)
			(xy 342.46816 -287.931848) (xy 342.452044 -287.980122) (xy 342.428393 -288.025185) (xy 342.39782 -288.065871)
			(xy 342.361116 -288.101126) (xy 342.319232 -288.130036) (xy 342.273253 -288.151853) (xy 342.224369 -288.166013)
			(xy 342.173848 -288.172147) (xy 342.122996 -288.170098) (xy 342.073132 -288.159918) (xy 342.025546 -288.141871)
			(xy 341.981472 -288.116425) (xy 341.94205 -288.084238) (xy 341.908302 -288.046144) (xy 341.881101 -288.00313)
			(xy 341.861153 -287.95631) (xy 341.848974 -287.906896) (xy 341.844879 -287.856168) (xy 340.596728 -287.856168)
			(xy 340.596216 -287.881614) (xy 340.588052 -287.931848) (xy 340.571936 -287.980122) (xy 340.548285 -288.025185)
			(xy 340.517712 -288.065871) (xy 340.481008 -288.101126) (xy 340.439124 -288.130036) (xy 340.393145 -288.151853)
			(xy 340.344261 -288.166013) (xy 340.29374 -288.172147) (xy 340.242888 -288.170098) (xy 340.193024 -288.159918)
			(xy 340.145438 -288.141871) (xy 340.101364 -288.116425) (xy 340.061942 -288.084238) (xy 340.028194 -288.046144)
			(xy 340.000993 -288.00313) (xy 339.981045 -287.95631) (xy 339.968866 -287.906896) (xy 339.964771 -287.856168)
			(xy 339.656928 -287.856168) (xy 339.656416 -287.881614) (xy 339.648252 -287.931848) (xy 339.632136 -287.980122)
			(xy 339.608485 -288.025185) (xy 339.577912 -288.065871) (xy 339.541208 -288.101126) (xy 339.499324 -288.130036)
			(xy 339.453345 -288.151853) (xy 339.404461 -288.166013) (xy 339.35394 -288.172147) (xy 339.303088 -288.170098)
			(xy 339.253224 -288.159918) (xy 339.205638 -288.141871) (xy 339.161564 -288.116425) (xy 339.122142 -288.084238)
			(xy 339.088394 -288.046144) (xy 339.061193 -288.00313) (xy 339.041245 -287.95631) (xy 339.029066 -287.906896)
			(xy 339.024971 -287.856168) (xy 338.70646 -287.856168) (xy 338.705965 -287.880775) (xy 338.69807 -287.929352)
			(xy 338.682486 -287.976033) (xy 338.659615 -288.01961) (xy 338.63005 -288.058954) (xy 338.594557 -288.093046)
			(xy 338.554054 -288.121002) (xy 338.509592 -288.1421) (xy 338.462321 -288.155792) (xy 338.413466 -288.161724)
			(xy 338.364291 -288.159743) (xy 338.316072 -288.149899) (xy 338.270056 -288.132447) (xy 338.227435 -288.10784)
			(xy 338.189314 -288.076715) (xy 338.156679 -288.039878) (xy 338.130376 -287.998282) (xy 338.111085 -287.953006)
			(xy 338.099308 -287.905222) (xy 338.095348 -287.856168) (xy 337.766406 -287.856168) (xy 337.765911 -287.880775)
			(xy 337.758016 -287.929352) (xy 337.742432 -287.976033) (xy 337.719561 -288.01961) (xy 337.689996 -288.058954)
			(xy 337.654503 -288.093046) (xy 337.614 -288.121002) (xy 337.569538 -288.1421) (xy 337.522267 -288.155792)
			(xy 337.473412 -288.161724) (xy 337.424237 -288.159743) (xy 337.376018 -288.149899) (xy 337.330002 -288.132447)
			(xy 337.287381 -288.10784) (xy 337.24926 -288.076715) (xy 337.216625 -288.039878) (xy 337.190322 -287.998282)
			(xy 337.171031 -287.953006) (xy 337.159254 -287.905222) (xy 337.155294 -287.856168) (xy 336.826352 -287.856168)
			(xy 336.825857 -287.880775) (xy 336.817962 -287.929352) (xy 336.802378 -287.976033) (xy 336.779507 -288.01961)
			(xy 336.749942 -288.058954) (xy 336.714449 -288.093046) (xy 336.673946 -288.121002) (xy 336.629484 -288.1421)
			(xy 336.582213 -288.155792) (xy 336.533358 -288.161724) (xy 336.484183 -288.159743) (xy 336.435964 -288.149899)
			(xy 336.389948 -288.132447) (xy 336.347327 -288.10784) (xy 336.309206 -288.076715) (xy 336.276571 -288.039878)
			(xy 336.250268 -287.998282) (xy 336.230977 -287.953006) (xy 336.2192 -287.905222) (xy 336.21524 -287.856168)
			(xy 335.886298 -287.856168) (xy 335.885803 -287.880775) (xy 335.877908 -287.929352) (xy 335.862324 -287.976033)
			(xy 335.839453 -288.01961) (xy 335.809888 -288.058954) (xy 335.774395 -288.093046) (xy 335.733892 -288.121002)
			(xy 335.68943 -288.1421) (xy 335.642159 -288.155792) (xy 335.593304 -288.161724) (xy 335.544129 -288.159743)
			(xy 335.49591 -288.149899) (xy 335.449894 -288.132447) (xy 335.407273 -288.10784) (xy 335.369152 -288.076715)
			(xy 335.336517 -288.039878) (xy 335.310214 -287.998282) (xy 335.290923 -287.953006) (xy 335.279146 -287.905222)
			(xy 335.275186 -287.856168) (xy 334.971898 -287.856168) (xy 334.971311 -287.88429) (xy 334.961726 -287.939713)
			(xy 334.952848 -287.966404) (xy 334.950054 -287.974786) (xy 334.950054 -288.2646) (xy 334.950054 -288.26714)
			(xy 334.95097 -288.276805) (xy 334.959077 -288.294426) (xy 334.965802 -288.30143) (xy 335.024476 -288.351976)
			(xy 335.028709 -288.355449) (xy 335.038319 -288.360693) (xy 335.043526 -288.36239) (xy 335.054194 -288.365438)
			(xy 335.065116 -288.363914) (xy 335.076354 -288.362358) (xy 335.098983 -288.360703) (xy 335.110328 -288.360612)
			(xy 335.11109 -288.360612) (xy 335.136347 -288.361104) (xy 335.186171 -288.369417) (xy 335.233948 -288.385817)
			(xy 335.278373 -288.409858) (xy 335.318236 -288.440883) (xy 335.352448 -288.478046) (xy 335.380077 -288.520333)
			(xy 335.400368 -288.566592) (xy 335.412769 -288.615559) (xy 335.41694 -288.6659) (xy 335.416938 -288.66592)
			(xy 335.74534 -288.66592) (xy 335.7493 -288.616866) (xy 335.761077 -288.569082) (xy 335.780368 -288.523806)
			(xy 335.806671 -288.48221) (xy 335.839306 -288.445373) (xy 335.877427 -288.414248) (xy 335.920048 -288.389641)
			(xy 335.966064 -288.372189) (xy 336.014283 -288.362345) (xy 336.063458 -288.360364) (xy 336.112313 -288.366296)
			(xy 336.159584 -288.379988) (xy 336.204046 -288.401086) (xy 336.244549 -288.429042) (xy 336.280042 -288.463134)
			(xy 336.309607 -288.502478) (xy 336.332478 -288.546055) (xy 336.348062 -288.592736) (xy 336.355957 -288.641313)
			(xy 336.356452 -288.66592) (xy 336.685394 -288.66592) (xy 336.689354 -288.616866) (xy 336.701131 -288.569082)
			(xy 336.720422 -288.523806) (xy 336.746725 -288.48221) (xy 336.77936 -288.445373) (xy 336.817481 -288.414248)
			(xy 336.860102 -288.389641) (xy 336.906118 -288.372189) (xy 336.954337 -288.362345) (xy 337.003512 -288.360364)
			(xy 337.052367 -288.366296) (xy 337.099638 -288.379988) (xy 337.1441 -288.401086) (xy 337.184603 -288.429042)
			(xy 337.220096 -288.463134) (xy 337.249661 -288.502478) (xy 337.272532 -288.546055) (xy 337.288116 -288.592736)
			(xy 337.296011 -288.641313) (xy 337.296506 -288.66592) (xy 337.625194 -288.66592) (xy 337.629154 -288.616866)
			(xy 337.640931 -288.569082) (xy 337.660222 -288.523806) (xy 337.686525 -288.48221) (xy 337.71916 -288.445373)
			(xy 337.757281 -288.414248) (xy 337.799902 -288.389641) (xy 337.845918 -288.372189) (xy 337.894137 -288.362345)
			(xy 337.943312 -288.360364) (xy 337.992167 -288.366296) (xy 338.039438 -288.379988) (xy 338.0839 -288.401086)
			(xy 338.124403 -288.429042) (xy 338.159896 -288.463134) (xy 338.189461 -288.502478) (xy 338.212332 -288.546055)
			(xy 338.227916 -288.592736) (xy 338.235811 -288.641313) (xy 338.236306 -288.66592) (xy 338.554817 -288.66592)
			(xy 338.558912 -288.615192) (xy 338.571091 -288.565778) (xy 338.591039 -288.518958) (xy 338.61824 -288.475944)
			(xy 338.651988 -288.43785) (xy 338.69141 -288.405663) (xy 338.735484 -288.380217) (xy 338.78307 -288.36217)
			(xy 338.832934 -288.35199) (xy 338.883786 -288.349941) (xy 338.934307 -288.356075) (xy 338.983191 -288.370235)
			(xy 339.02917 -288.392052) (xy 339.071054 -288.420962) (xy 339.107758 -288.456217) (xy 339.138331 -288.496903)
			(xy 339.161982 -288.541966) (xy 339.178098 -288.59024) (xy 339.186262 -288.640474) (xy 339.186774 -288.66592)
			(xy 339.505302 -288.66592) (xy 339.509262 -288.616866) (xy 339.521039 -288.569082) (xy 339.54033 -288.523806)
			(xy 339.566633 -288.48221) (xy 339.599268 -288.445373) (xy 339.637389 -288.414248) (xy 339.68001 -288.389641)
			(xy 339.726026 -288.372189) (xy 339.774245 -288.362345) (xy 339.82342 -288.360364) (xy 339.872275 -288.366296)
			(xy 339.919546 -288.379988) (xy 339.964008 -288.401086) (xy 340.004511 -288.429042) (xy 340.040004 -288.463134)
			(xy 340.069569 -288.502478) (xy 340.09244 -288.546055) (xy 340.108024 -288.592736) (xy 340.115919 -288.641313)
			(xy 340.116414 -288.66592) (xy 340.434925 -288.66592) (xy 340.43902 -288.615192) (xy 340.451199 -288.565778)
			(xy 340.471147 -288.518958) (xy 340.498348 -288.475944) (xy 340.532096 -288.43785) (xy 340.571518 -288.405663)
			(xy 340.615592 -288.380217) (xy 340.663178 -288.36217) (xy 340.713042 -288.35199) (xy 340.763894 -288.349941)
			(xy 340.814415 -288.356075) (xy 340.863299 -288.370235) (xy 340.909278 -288.392052) (xy 340.951162 -288.420962)
			(xy 340.987866 -288.456217) (xy 341.018439 -288.496903) (xy 341.04209 -288.541966) (xy 341.058206 -288.59024)
			(xy 341.06637 -288.640474) (xy 341.066882 -288.66592) (xy 341.38541 -288.66592) (xy 341.38937 -288.616866)
			(xy 341.401147 -288.569082) (xy 341.420438 -288.523806) (xy 341.446741 -288.48221) (xy 341.479376 -288.445373)
			(xy 341.517497 -288.414248) (xy 341.560118 -288.389641) (xy 341.606134 -288.372189) (xy 341.654353 -288.362345)
			(xy 341.703528 -288.360364) (xy 341.752383 -288.366296) (xy 341.799654 -288.379988) (xy 341.844116 -288.401086)
			(xy 341.884619 -288.429042) (xy 341.920112 -288.463134) (xy 341.949677 -288.502478) (xy 341.972548 -288.546055)
			(xy 341.988132 -288.592736) (xy 341.996027 -288.641313) (xy 341.996522 -288.66592) (xy 342.314779 -288.66592)
			(xy 342.318874 -288.615192) (xy 342.331053 -288.565778) (xy 342.351001 -288.518958) (xy 342.378202 -288.475944)
			(xy 342.41195 -288.43785) (xy 342.451372 -288.405663) (xy 342.495446 -288.380217) (xy 342.543032 -288.36217)
			(xy 342.592896 -288.35199) (xy 342.643748 -288.349941) (xy 342.694269 -288.356075) (xy 342.743153 -288.370235)
			(xy 342.789132 -288.392052) (xy 342.831016 -288.420962) (xy 342.86772 -288.456217) (xy 342.898293 -288.496903)
			(xy 342.921944 -288.541966) (xy 342.93806 -288.59024) (xy 342.946224 -288.640474) (xy 342.946736 -288.66592)
			(xy 342.946224 -288.691366) (xy 342.93806 -288.7416) (xy 342.921944 -288.789874) (xy 342.898293 -288.834937)
			(xy 342.86772 -288.875623) (xy 342.831016 -288.910878) (xy 342.789132 -288.939788) (xy 342.743153 -288.961605)
			(xy 342.694269 -288.975765) (xy 342.643748 -288.981899) (xy 342.592896 -288.97985) (xy 342.543032 -288.96967)
			(xy 342.495446 -288.951623) (xy 342.451372 -288.926177) (xy 342.41195 -288.89399) (xy 342.378202 -288.855896)
			(xy 342.351001 -288.812882) (xy 342.331053 -288.766062) (xy 342.318874 -288.716648) (xy 342.314779 -288.66592)
			(xy 341.996522 -288.66592) (xy 341.996027 -288.690527) (xy 341.988132 -288.739104) (xy 341.972548 -288.785785)
			(xy 341.949677 -288.829362) (xy 341.920112 -288.868706) (xy 341.884619 -288.902798) (xy 341.844116 -288.930754)
			(xy 341.799654 -288.951852) (xy 341.752383 -288.965544) (xy 341.703528 -288.971476) (xy 341.654353 -288.969495)
			(xy 341.606134 -288.959651) (xy 341.560118 -288.942199) (xy 341.517497 -288.917592) (xy 341.479376 -288.886467)
			(xy 341.446741 -288.84963) (xy 341.420438 -288.808034) (xy 341.401147 -288.762758) (xy 341.38937 -288.714974)
			(xy 341.38541 -288.66592) (xy 341.066882 -288.66592) (xy 341.06637 -288.691366) (xy 341.058206 -288.7416)
			(xy 341.04209 -288.789874) (xy 341.018439 -288.834937) (xy 340.987866 -288.875623) (xy 340.951162 -288.910878)
			(xy 340.909278 -288.939788) (xy 340.863299 -288.961605) (xy 340.814415 -288.975765) (xy 340.763894 -288.981899)
			(xy 340.713042 -288.97985) (xy 340.663178 -288.96967) (xy 340.615592 -288.951623) (xy 340.571518 -288.926177)
			(xy 340.532096 -288.89399) (xy 340.498348 -288.855896) (xy 340.471147 -288.812882) (xy 340.451199 -288.766062)
			(xy 340.43902 -288.716648) (xy 340.434925 -288.66592) (xy 340.116414 -288.66592) (xy 340.115919 -288.690527)
			(xy 340.108024 -288.739104) (xy 340.09244 -288.785785) (xy 340.069569 -288.829362) (xy 340.040004 -288.868706)
			(xy 340.004511 -288.902798) (xy 339.964008 -288.930754) (xy 339.919546 -288.951852) (xy 339.872275 -288.965544)
			(xy 339.82342 -288.971476) (xy 339.774245 -288.969495) (xy 339.726026 -288.959651) (xy 339.68001 -288.942199)
			(xy 339.637389 -288.917592) (xy 339.599268 -288.886467) (xy 339.566633 -288.84963) (xy 339.54033 -288.808034)
			(xy 339.521039 -288.762758) (xy 339.509262 -288.714974) (xy 339.505302 -288.66592) (xy 339.186774 -288.66592)
			(xy 339.186262 -288.691366) (xy 339.178098 -288.7416) (xy 339.161982 -288.789874) (xy 339.138331 -288.834937)
			(xy 339.107758 -288.875623) (xy 339.071054 -288.910878) (xy 339.02917 -288.939788) (xy 338.983191 -288.961605)
			(xy 338.934307 -288.975765) (xy 338.883786 -288.981899) (xy 338.832934 -288.97985) (xy 338.78307 -288.96967)
			(xy 338.735484 -288.951623) (xy 338.69141 -288.926177) (xy 338.651988 -288.89399) (xy 338.61824 -288.855896)
			(xy 338.591039 -288.812882) (xy 338.571091 -288.766062) (xy 338.558912 -288.716648) (xy 338.554817 -288.66592)
			(xy 338.236306 -288.66592) (xy 338.235811 -288.690527) (xy 338.227916 -288.739104) (xy 338.212332 -288.785785)
			(xy 338.189461 -288.829362) (xy 338.159896 -288.868706) (xy 338.124403 -288.902798) (xy 338.0839 -288.930754)
			(xy 338.039438 -288.951852) (xy 337.992167 -288.965544) (xy 337.943312 -288.971476) (xy 337.894137 -288.969495)
			(xy 337.845918 -288.959651) (xy 337.799902 -288.942199) (xy 337.757281 -288.917592) (xy 337.71916 -288.886467)
			(xy 337.686525 -288.84963) (xy 337.660222 -288.808034) (xy 337.640931 -288.762758) (xy 337.629154 -288.714974)
			(xy 337.625194 -288.66592) (xy 337.296506 -288.66592) (xy 337.296011 -288.690527) (xy 337.288116 -288.739104)
			(xy 337.272532 -288.785785) (xy 337.249661 -288.829362) (xy 337.220096 -288.868706) (xy 337.184603 -288.902798)
			(xy 337.1441 -288.930754) (xy 337.099638 -288.951852) (xy 337.052367 -288.965544) (xy 337.003512 -288.971476)
			(xy 336.954337 -288.969495) (xy 336.906118 -288.959651) (xy 336.860102 -288.942199) (xy 336.817481 -288.917592)
			(xy 336.77936 -288.886467) (xy 336.746725 -288.84963) (xy 336.720422 -288.808034) (xy 336.701131 -288.762758)
			(xy 336.689354 -288.714974) (xy 336.685394 -288.66592) (xy 336.356452 -288.66592) (xy 336.355957 -288.690527)
			(xy 336.348062 -288.739104) (xy 336.332478 -288.785785) (xy 336.309607 -288.829362) (xy 336.280042 -288.868706)
			(xy 336.244549 -288.902798) (xy 336.204046 -288.930754) (xy 336.159584 -288.951852) (xy 336.112313 -288.965544)
			(xy 336.063458 -288.971476) (xy 336.014283 -288.969495) (xy 335.966064 -288.959651) (xy 335.920048 -288.942199)
			(xy 335.877427 -288.917592) (xy 335.839306 -288.886467) (xy 335.806671 -288.84963) (xy 335.780368 -288.808034)
			(xy 335.761077 -288.762758) (xy 335.7493 -288.714974) (xy 335.74534 -288.66592) (xy 335.416938 -288.66592)
			(xy 335.412769 -288.716241) (xy 335.400368 -288.765208) (xy 335.380077 -288.811467) (xy 335.352448 -288.853754)
			(xy 335.318236 -288.890917) (xy 335.278373 -288.921942) (xy 335.233948 -288.945983) (xy 335.186171 -288.962383)
			(xy 335.136347 -288.970696) (xy 335.11109 -288.971228) (xy 335.110582 -288.971228) (xy 335.097433 -288.971078)
			(xy 335.071234 -288.968786) (xy 335.058258 -288.966656) (xy 335.054448 -288.966148) (xy 335.04378 -288.969196)
			(xy 335.03889 -288.97073) (xy 335.029804 -288.975465) (xy 335.025746 -288.978594) (xy 334.967072 -289.028886)
			(xy 334.959451 -289.036451) (xy 334.950649 -289.056011) (xy 334.950054 -289.066732) (xy 334.950054 -289.475926)
			(xy 335.275186 -289.475926) (xy 335.279146 -289.426872) (xy 335.290923 -289.379088) (xy 335.310214 -289.333812)
			(xy 335.336517 -289.292216) (xy 335.369152 -289.255379) (xy 335.407273 -289.224254) (xy 335.449894 -289.199647)
			(xy 335.49591 -289.182195) (xy 335.544129 -289.172351) (xy 335.593304 -289.17037) (xy 335.642159 -289.176302)
			(xy 335.68943 -289.189994) (xy 335.733892 -289.211092) (xy 335.774395 -289.239048) (xy 335.809888 -289.27314)
			(xy 335.839453 -289.312484) (xy 335.862324 -289.356061) (xy 335.877908 -289.402742) (xy 335.885803 -289.451319)
			(xy 335.886298 -289.475926) (xy 336.21524 -289.475926) (xy 336.2192 -289.426872) (xy 336.230977 -289.379088)
			(xy 336.250268 -289.333812) (xy 336.276571 -289.292216) (xy 336.309206 -289.255379) (xy 336.347327 -289.224254)
			(xy 336.389948 -289.199647) (xy 336.435964 -289.182195) (xy 336.484183 -289.172351) (xy 336.533358 -289.17037)
			(xy 336.582213 -289.176302) (xy 336.629484 -289.189994) (xy 336.673946 -289.211092) (xy 336.714449 -289.239048)
			(xy 336.749942 -289.27314) (xy 336.779507 -289.312484) (xy 336.802378 -289.356061) (xy 336.817962 -289.402742)
			(xy 336.825857 -289.451319) (xy 336.826352 -289.475926) (xy 337.155294 -289.475926) (xy 337.159254 -289.426872)
			(xy 337.171031 -289.379088) (xy 337.190322 -289.333812) (xy 337.216625 -289.292216) (xy 337.24926 -289.255379)
			(xy 337.287381 -289.224254) (xy 337.330002 -289.199647) (xy 337.376018 -289.182195) (xy 337.424237 -289.172351)
			(xy 337.473412 -289.17037) (xy 337.522267 -289.176302) (xy 337.569538 -289.189994) (xy 337.614 -289.211092)
			(xy 337.654503 -289.239048) (xy 337.689996 -289.27314) (xy 337.719561 -289.312484) (xy 337.742432 -289.356061)
			(xy 337.758016 -289.402742) (xy 337.765911 -289.451319) (xy 337.766406 -289.475926) (xy 338.095348 -289.475926)
			(xy 338.099308 -289.426872) (xy 338.111085 -289.379088) (xy 338.130376 -289.333812) (xy 338.156679 -289.292216)
			(xy 338.189314 -289.255379) (xy 338.227435 -289.224254) (xy 338.270056 -289.199647) (xy 338.316072 -289.182195)
			(xy 338.364291 -289.172351) (xy 338.413466 -289.17037) (xy 338.462321 -289.176302) (xy 338.509592 -289.189994)
			(xy 338.554054 -289.211092) (xy 338.594557 -289.239048) (xy 338.63005 -289.27314) (xy 338.659615 -289.312484)
			(xy 338.682486 -289.356061) (xy 338.69807 -289.402742) (xy 338.705965 -289.451319) (xy 338.70646 -289.475926)
			(xy 339.024971 -289.475926) (xy 339.029066 -289.425198) (xy 339.041245 -289.375784) (xy 339.061193 -289.328964)
			(xy 339.088394 -289.28595) (xy 339.122142 -289.247856) (xy 339.161564 -289.215669) (xy 339.205638 -289.190223)
			(xy 339.253224 -289.172176) (xy 339.303088 -289.161996) (xy 339.35394 -289.159947) (xy 339.404461 -289.166081)
			(xy 339.453345 -289.180241) (xy 339.499324 -289.202058) (xy 339.541208 -289.230968) (xy 339.577912 -289.266223)
			(xy 339.608485 -289.306909) (xy 339.632136 -289.351972) (xy 339.648252 -289.400246) (xy 339.656416 -289.45048)
			(xy 339.656928 -289.475926) (xy 339.964771 -289.475926) (xy 339.968866 -289.425198) (xy 339.981045 -289.375784)
			(xy 340.000993 -289.328964) (xy 340.028194 -289.28595) (xy 340.061942 -289.247856) (xy 340.101364 -289.215669)
			(xy 340.145438 -289.190223) (xy 340.193024 -289.172176) (xy 340.242888 -289.161996) (xy 340.29374 -289.159947)
			(xy 340.344261 -289.166081) (xy 340.393145 -289.180241) (xy 340.439124 -289.202058) (xy 340.481008 -289.230968)
			(xy 340.517712 -289.266223) (xy 340.548285 -289.306909) (xy 340.571936 -289.351972) (xy 340.588052 -289.400246)
			(xy 340.596216 -289.45048) (xy 340.596728 -289.475926) (xy 340.915256 -289.475926) (xy 340.919216 -289.426872)
			(xy 340.930993 -289.379088) (xy 340.950284 -289.333812) (xy 340.976587 -289.292216) (xy 341.009222 -289.255379)
			(xy 341.047343 -289.224254) (xy 341.089964 -289.199647) (xy 341.13598 -289.182195) (xy 341.184199 -289.172351)
			(xy 341.233374 -289.17037) (xy 341.282229 -289.176302) (xy 341.3295 -289.189994) (xy 341.373962 -289.211092)
			(xy 341.414465 -289.239048) (xy 341.449958 -289.27314) (xy 341.479523 -289.312484) (xy 341.502394 -289.356061)
			(xy 341.517978 -289.402742) (xy 341.525873 -289.451319) (xy 341.526368 -289.475926) (xy 341.844879 -289.475926)
			(xy 341.848974 -289.425198) (xy 341.861153 -289.375784) (xy 341.881101 -289.328964) (xy 341.908302 -289.28595)
			(xy 341.94205 -289.247856) (xy 341.981472 -289.215669) (xy 342.025546 -289.190223) (xy 342.073132 -289.172176)
			(xy 342.122996 -289.161996) (xy 342.173848 -289.159947) (xy 342.224369 -289.166081) (xy 342.273253 -289.180241)
			(xy 342.319232 -289.202058) (xy 342.361116 -289.230968) (xy 342.39782 -289.266223) (xy 342.428393 -289.306909)
			(xy 342.452044 -289.351972) (xy 342.46816 -289.400246) (xy 342.476324 -289.45048) (xy 342.476836 -289.475926)
			(xy 342.476324 -289.501372) (xy 342.46816 -289.551606) (xy 342.452044 -289.59988) (xy 342.428393 -289.644943)
			(xy 342.39782 -289.685629) (xy 342.361116 -289.720884) (xy 342.319232 -289.749794) (xy 342.273253 -289.771611)
			(xy 342.224369 -289.785771) (xy 342.173848 -289.791905) (xy 342.122996 -289.789856) (xy 342.073132 -289.779676)
			(xy 342.025546 -289.761629) (xy 341.981472 -289.736183) (xy 341.94205 -289.703996) (xy 341.908302 -289.665902)
			(xy 341.881101 -289.622888) (xy 341.861153 -289.576068) (xy 341.848974 -289.526654) (xy 341.844879 -289.475926)
			(xy 341.526368 -289.475926) (xy 341.525873 -289.500533) (xy 341.517978 -289.54911) (xy 341.502394 -289.595791)
			(xy 341.479523 -289.639368) (xy 341.449958 -289.678712) (xy 341.414465 -289.712804) (xy 341.373962 -289.74076)
			(xy 341.3295 -289.761858) (xy 341.282229 -289.77555) (xy 341.233374 -289.781482) (xy 341.184199 -289.779501)
			(xy 341.13598 -289.769657) (xy 341.089964 -289.752205) (xy 341.047343 -289.727598) (xy 341.009222 -289.696473)
			(xy 340.976587 -289.659636) (xy 340.950284 -289.61804) (xy 340.930993 -289.572764) (xy 340.919216 -289.52498)
			(xy 340.915256 -289.475926) (xy 340.596728 -289.475926) (xy 340.596216 -289.501372) (xy 340.588052 -289.551606)
			(xy 340.571936 -289.59988) (xy 340.548285 -289.644943) (xy 340.517712 -289.685629) (xy 340.481008 -289.720884)
			(xy 340.439124 -289.749794) (xy 340.393145 -289.771611) (xy 340.344261 -289.785771) (xy 340.29374 -289.791905)
			(xy 340.242888 -289.789856) (xy 340.193024 -289.779676) (xy 340.145438 -289.761629) (xy 340.101364 -289.736183)
			(xy 340.061942 -289.703996) (xy 340.028194 -289.665902) (xy 340.000993 -289.622888) (xy 339.981045 -289.576068)
			(xy 339.968866 -289.526654) (xy 339.964771 -289.475926) (xy 339.656928 -289.475926) (xy 339.656416 -289.501372)
			(xy 339.648252 -289.551606) (xy 339.632136 -289.59988) (xy 339.608485 -289.644943) (xy 339.577912 -289.685629)
			(xy 339.541208 -289.720884) (xy 339.499324 -289.749794) (xy 339.453345 -289.771611) (xy 339.404461 -289.785771)
			(xy 339.35394 -289.791905) (xy 339.303088 -289.789856) (xy 339.253224 -289.779676) (xy 339.205638 -289.761629)
			(xy 339.161564 -289.736183) (xy 339.122142 -289.703996) (xy 339.088394 -289.665902) (xy 339.061193 -289.622888)
			(xy 339.041245 -289.576068) (xy 339.029066 -289.526654) (xy 339.024971 -289.475926) (xy 338.70646 -289.475926)
			(xy 338.705965 -289.500533) (xy 338.69807 -289.54911) (xy 338.682486 -289.595791) (xy 338.659615 -289.639368)
			(xy 338.63005 -289.678712) (xy 338.594557 -289.712804) (xy 338.554054 -289.74076) (xy 338.509592 -289.761858)
			(xy 338.462321 -289.77555) (xy 338.413466 -289.781482) (xy 338.364291 -289.779501) (xy 338.316072 -289.769657)
			(xy 338.270056 -289.752205) (xy 338.227435 -289.727598) (xy 338.189314 -289.696473) (xy 338.156679 -289.659636)
			(xy 338.130376 -289.61804) (xy 338.111085 -289.572764) (xy 338.099308 -289.52498) (xy 338.095348 -289.475926)
			(xy 337.766406 -289.475926) (xy 337.765911 -289.500533) (xy 337.758016 -289.54911) (xy 337.742432 -289.595791)
			(xy 337.719561 -289.639368) (xy 337.689996 -289.678712) (xy 337.654503 -289.712804) (xy 337.614 -289.74076)
			(xy 337.569538 -289.761858) (xy 337.522267 -289.77555) (xy 337.473412 -289.781482) (xy 337.424237 -289.779501)
			(xy 337.376018 -289.769657) (xy 337.330002 -289.752205) (xy 337.287381 -289.727598) (xy 337.24926 -289.696473)
			(xy 337.216625 -289.659636) (xy 337.190322 -289.61804) (xy 337.171031 -289.572764) (xy 337.159254 -289.52498)
			(xy 337.155294 -289.475926) (xy 336.826352 -289.475926) (xy 336.825857 -289.500533) (xy 336.817962 -289.54911)
			(xy 336.802378 -289.595791) (xy 336.779507 -289.639368) (xy 336.749942 -289.678712) (xy 336.714449 -289.712804)
			(xy 336.673946 -289.74076) (xy 336.629484 -289.761858) (xy 336.582213 -289.77555) (xy 336.533358 -289.781482)
			(xy 336.484183 -289.779501) (xy 336.435964 -289.769657) (xy 336.389948 -289.752205) (xy 336.347327 -289.727598)
			(xy 336.309206 -289.696473) (xy 336.276571 -289.659636) (xy 336.250268 -289.61804) (xy 336.230977 -289.572764)
			(xy 336.2192 -289.52498) (xy 336.21524 -289.475926) (xy 335.886298 -289.475926) (xy 335.885803 -289.500533)
			(xy 335.877908 -289.54911) (xy 335.862324 -289.595791) (xy 335.839453 -289.639368) (xy 335.809888 -289.678712)
			(xy 335.774395 -289.712804) (xy 335.733892 -289.74076) (xy 335.68943 -289.761858) (xy 335.642159 -289.77555)
			(xy 335.593304 -289.781482) (xy 335.544129 -289.779501) (xy 335.49591 -289.769657) (xy 335.449894 -289.752205)
			(xy 335.407273 -289.727598) (xy 335.369152 -289.696473) (xy 335.336517 -289.659636) (xy 335.310214 -289.61804)
			(xy 335.290923 -289.572764) (xy 335.279146 -289.52498) (xy 335.275186 -289.475926) (xy 334.950054 -289.475926)
			(xy 334.950054 -290.285932) (xy 335.74534 -290.285932) (xy 335.7493 -290.236878) (xy 335.761077 -290.189094)
			(xy 335.780368 -290.143818) (xy 335.806671 -290.102222) (xy 335.839306 -290.065385) (xy 335.877427 -290.03426)
			(xy 335.920048 -290.009653) (xy 335.966064 -289.992201) (xy 336.014283 -289.982357) (xy 336.063458 -289.980376)
			(xy 336.112313 -289.986308) (xy 336.159584 -290) (xy 336.204046 -290.021098) (xy 336.244549 -290.049054)
			(xy 336.280042 -290.083146) (xy 336.309607 -290.12249) (xy 336.332478 -290.166067) (xy 336.348062 -290.212748)
			(xy 336.355957 -290.261325) (xy 336.356452 -290.285932) (xy 336.685394 -290.285932) (xy 336.689354 -290.236878)
			(xy 336.701131 -290.189094) (xy 336.720422 -290.143818) (xy 336.746725 -290.102222) (xy 336.77936 -290.065385)
			(xy 336.817481 -290.03426) (xy 336.860102 -290.009653) (xy 336.906118 -289.992201) (xy 336.954337 -289.982357)
			(xy 337.003512 -289.980376) (xy 337.052367 -289.986308) (xy 337.099638 -290) (xy 337.1441 -290.021098)
			(xy 337.184603 -290.049054) (xy 337.220096 -290.083146) (xy 337.249661 -290.12249) (xy 337.272532 -290.166067)
			(xy 337.288116 -290.212748) (xy 337.296011 -290.261325) (xy 337.296506 -290.285932) (xy 337.625194 -290.285932)
			(xy 337.629154 -290.236878) (xy 337.640931 -290.189094) (xy 337.660222 -290.143818) (xy 337.686525 -290.102222)
			(xy 337.71916 -290.065385) (xy 337.757281 -290.03426) (xy 337.799902 -290.009653) (xy 337.845918 -289.992201)
			(xy 337.894137 -289.982357) (xy 337.943312 -289.980376) (xy 337.992167 -289.986308) (xy 338.039438 -290)
			(xy 338.0839 -290.021098) (xy 338.124403 -290.049054) (xy 338.159896 -290.083146) (xy 338.189461 -290.12249)
			(xy 338.212332 -290.166067) (xy 338.227916 -290.212748) (xy 338.235811 -290.261325) (xy 338.236306 -290.285932)
			(xy 338.554817 -290.285932) (xy 338.558912 -290.235204) (xy 338.571091 -290.18579) (xy 338.591039 -290.13897)
			(xy 338.61824 -290.095956) (xy 338.651988 -290.057862) (xy 338.69141 -290.025675) (xy 338.735484 -290.000229)
			(xy 338.78307 -289.982182) (xy 338.832934 -289.972002) (xy 338.883786 -289.969953) (xy 338.934307 -289.976087)
			(xy 338.983191 -289.990247) (xy 339.02917 -290.012064) (xy 339.071054 -290.040974) (xy 339.107758 -290.076229)
			(xy 339.138331 -290.116915) (xy 339.161982 -290.161978) (xy 339.178098 -290.210252) (xy 339.186262 -290.260486)
			(xy 339.186774 -290.285932) (xy 339.505302 -290.285932) (xy 339.509262 -290.236878) (xy 339.521039 -290.189094)
			(xy 339.54033 -290.143818) (xy 339.566633 -290.102222) (xy 339.599268 -290.065385) (xy 339.637389 -290.03426)
			(xy 339.68001 -290.009653) (xy 339.726026 -289.992201) (xy 339.774245 -289.982357) (xy 339.82342 -289.980376)
			(xy 339.872275 -289.986308) (xy 339.919546 -290) (xy 339.964008 -290.021098) (xy 340.004511 -290.049054)
			(xy 340.040004 -290.083146) (xy 340.069569 -290.12249) (xy 340.09244 -290.166067) (xy 340.108024 -290.212748)
			(xy 340.115919 -290.261325) (xy 340.116414 -290.285932) (xy 340.434925 -290.285932) (xy 340.43902 -290.235204)
			(xy 340.451199 -290.18579) (xy 340.471147 -290.13897) (xy 340.498348 -290.095956) (xy 340.532096 -290.057862)
			(xy 340.571518 -290.025675) (xy 340.615592 -290.000229) (xy 340.663178 -289.982182) (xy 340.713042 -289.972002)
			(xy 340.763894 -289.969953) (xy 340.814415 -289.976087) (xy 340.863299 -289.990247) (xy 340.909278 -290.012064)
			(xy 340.951162 -290.040974) (xy 340.987866 -290.076229) (xy 341.018439 -290.116915) (xy 341.04209 -290.161978)
			(xy 341.058206 -290.210252) (xy 341.06637 -290.260486) (xy 341.066882 -290.285932) (xy 342.314779 -290.285932)
			(xy 342.318874 -290.235204) (xy 342.331053 -290.18579) (xy 342.351001 -290.13897) (xy 342.378202 -290.095956)
			(xy 342.41195 -290.057862) (xy 342.451372 -290.025675) (xy 342.495446 -290.000229) (xy 342.543032 -289.982182)
			(xy 342.592896 -289.972002) (xy 342.643748 -289.969953) (xy 342.694269 -289.976087) (xy 342.743153 -289.990247)
			(xy 342.789132 -290.012064) (xy 342.831016 -290.040974) (xy 342.86772 -290.076229) (xy 342.898293 -290.116915)
			(xy 342.921944 -290.161978) (xy 342.93806 -290.210252) (xy 342.946224 -290.260486) (xy 342.946736 -290.285932)
			(xy 342.946224 -290.311378) (xy 342.93806 -290.361612) (xy 342.921944 -290.409886) (xy 342.898293 -290.454949)
			(xy 342.86772 -290.495635) (xy 342.831016 -290.53089) (xy 342.789132 -290.5598) (xy 342.743153 -290.581617)
			(xy 342.694269 -290.595777) (xy 342.643748 -290.601911) (xy 342.592896 -290.599862) (xy 342.543032 -290.589682)
			(xy 342.495446 -290.571635) (xy 342.451372 -290.546189) (xy 342.41195 -290.514002) (xy 342.378202 -290.475908)
			(xy 342.351001 -290.432894) (xy 342.331053 -290.386074) (xy 342.318874 -290.33666) (xy 342.314779 -290.285932)
			(xy 341.066882 -290.285932) (xy 341.06637 -290.311378) (xy 341.058206 -290.361612) (xy 341.04209 -290.409886)
			(xy 341.018439 -290.454949) (xy 340.987866 -290.495635) (xy 340.951162 -290.53089) (xy 340.909278 -290.5598)
			(xy 340.863299 -290.581617) (xy 340.814415 -290.595777) (xy 340.763894 -290.601911) (xy 340.713042 -290.599862)
			(xy 340.663178 -290.589682) (xy 340.615592 -290.571635) (xy 340.571518 -290.546189) (xy 340.532096 -290.514002)
			(xy 340.498348 -290.475908) (xy 340.471147 -290.432894) (xy 340.451199 -290.386074) (xy 340.43902 -290.33666)
			(xy 340.434925 -290.285932) (xy 340.116414 -290.285932) (xy 340.115919 -290.310539) (xy 340.108024 -290.359116)
			(xy 340.09244 -290.405797) (xy 340.069569 -290.449374) (xy 340.040004 -290.488718) (xy 340.004511 -290.52281)
			(xy 339.964008 -290.550766) (xy 339.919546 -290.571864) (xy 339.872275 -290.585556) (xy 339.82342 -290.591488)
			(xy 339.774245 -290.589507) (xy 339.726026 -290.579663) (xy 339.68001 -290.562211) (xy 339.637389 -290.537604)
			(xy 339.599268 -290.506479) (xy 339.566633 -290.469642) (xy 339.54033 -290.428046) (xy 339.521039 -290.38277)
			(xy 339.509262 -290.334986) (xy 339.505302 -290.285932) (xy 339.186774 -290.285932) (xy 339.186262 -290.311378)
			(xy 339.178098 -290.361612) (xy 339.161982 -290.409886) (xy 339.138331 -290.454949) (xy 339.107758 -290.495635)
			(xy 339.071054 -290.53089) (xy 339.02917 -290.5598) (xy 338.983191 -290.581617) (xy 338.934307 -290.595777)
			(xy 338.883786 -290.601911) (xy 338.832934 -290.599862) (xy 338.78307 -290.589682) (xy 338.735484 -290.571635)
			(xy 338.69141 -290.546189) (xy 338.651988 -290.514002) (xy 338.61824 -290.475908) (xy 338.591039 -290.432894)
			(xy 338.571091 -290.386074) (xy 338.558912 -290.33666) (xy 338.554817 -290.285932) (xy 338.236306 -290.285932)
			(xy 338.235811 -290.310539) (xy 338.227916 -290.359116) (xy 338.212332 -290.405797) (xy 338.189461 -290.449374)
			(xy 338.159896 -290.488718) (xy 338.124403 -290.52281) (xy 338.0839 -290.550766) (xy 338.039438 -290.571864)
			(xy 337.992167 -290.585556) (xy 337.943312 -290.591488) (xy 337.894137 -290.589507) (xy 337.845918 -290.579663)
			(xy 337.799902 -290.562211) (xy 337.757281 -290.537604) (xy 337.71916 -290.506479) (xy 337.686525 -290.469642)
			(xy 337.660222 -290.428046) (xy 337.640931 -290.38277) (xy 337.629154 -290.334986) (xy 337.625194 -290.285932)
			(xy 337.296506 -290.285932) (xy 337.296011 -290.310539) (xy 337.288116 -290.359116) (xy 337.272532 -290.405797)
			(xy 337.249661 -290.449374) (xy 337.220096 -290.488718) (xy 337.184603 -290.52281) (xy 337.1441 -290.550766)
			(xy 337.099638 -290.571864) (xy 337.052367 -290.585556) (xy 337.003512 -290.591488) (xy 336.954337 -290.589507)
			(xy 336.906118 -290.579663) (xy 336.860102 -290.562211) (xy 336.817481 -290.537604) (xy 336.77936 -290.506479)
			(xy 336.746725 -290.469642) (xy 336.720422 -290.428046) (xy 336.701131 -290.38277) (xy 336.689354 -290.334986)
			(xy 336.685394 -290.285932) (xy 336.356452 -290.285932) (xy 336.355957 -290.310539) (xy 336.348062 -290.359116)
			(xy 336.332478 -290.405797) (xy 336.309607 -290.449374) (xy 336.280042 -290.488718) (xy 336.244549 -290.52281)
			(xy 336.204046 -290.550766) (xy 336.159584 -290.571864) (xy 336.112313 -290.585556) (xy 336.063458 -290.591488)
			(xy 336.014283 -290.589507) (xy 335.966064 -290.579663) (xy 335.920048 -290.562211) (xy 335.877427 -290.537604)
			(xy 335.839306 -290.506479) (xy 335.806671 -290.469642) (xy 335.780368 -290.428046) (xy 335.761077 -290.38277)
			(xy 335.7493 -290.334986) (xy 335.74534 -290.285932) (xy 334.950054 -290.285932) (xy 334.950054 -291.095938)
			(xy 335.275186 -291.095938) (xy 335.279146 -291.046884) (xy 335.290923 -290.9991) (xy 335.310214 -290.953824)
			(xy 335.336517 -290.912228) (xy 335.369152 -290.875391) (xy 335.407273 -290.844266) (xy 335.449894 -290.819659)
			(xy 335.49591 -290.802207) (xy 335.544129 -290.792363) (xy 335.593304 -290.790382) (xy 335.642159 -290.796314)
			(xy 335.68943 -290.810006) (xy 335.733892 -290.831104) (xy 335.774395 -290.85906) (xy 335.809888 -290.893152)
			(xy 335.839453 -290.932496) (xy 335.862324 -290.976073) (xy 335.877908 -291.022754) (xy 335.885803 -291.071331)
			(xy 335.886298 -291.095938) (xy 336.21524 -291.095938) (xy 336.2192 -291.046884) (xy 336.230977 -290.9991)
			(xy 336.250268 -290.953824) (xy 336.276571 -290.912228) (xy 336.309206 -290.875391) (xy 336.347327 -290.844266)
			(xy 336.389948 -290.819659) (xy 336.435964 -290.802207) (xy 336.484183 -290.792363) (xy 336.533358 -290.790382)
			(xy 336.582213 -290.796314) (xy 336.629484 -290.810006) (xy 336.673946 -290.831104) (xy 336.714449 -290.85906)
			(xy 336.749942 -290.893152) (xy 336.779507 -290.932496) (xy 336.802378 -290.976073) (xy 336.817962 -291.022754)
			(xy 336.825857 -291.071331) (xy 336.826352 -291.095938) (xy 337.155294 -291.095938) (xy 337.159254 -291.046884)
			(xy 337.171031 -290.9991) (xy 337.190322 -290.953824) (xy 337.216625 -290.912228) (xy 337.24926 -290.875391)
			(xy 337.287381 -290.844266) (xy 337.330002 -290.819659) (xy 337.376018 -290.802207) (xy 337.424237 -290.792363)
			(xy 337.473412 -290.790382) (xy 337.522267 -290.796314) (xy 337.569538 -290.810006) (xy 337.614 -290.831104)
			(xy 337.654503 -290.85906) (xy 337.689996 -290.893152) (xy 337.719561 -290.932496) (xy 337.742432 -290.976073)
			(xy 337.758016 -291.022754) (xy 337.765911 -291.071331) (xy 337.766406 -291.095938) (xy 338.095348 -291.095938)
			(xy 338.099308 -291.046884) (xy 338.111085 -290.9991) (xy 338.130376 -290.953824) (xy 338.156679 -290.912228)
			(xy 338.189314 -290.875391) (xy 338.227435 -290.844266) (xy 338.270056 -290.819659) (xy 338.316072 -290.802207)
			(xy 338.364291 -290.792363) (xy 338.413466 -290.790382) (xy 338.462321 -290.796314) (xy 338.509592 -290.810006)
			(xy 338.554054 -290.831104) (xy 338.594557 -290.85906) (xy 338.63005 -290.893152) (xy 338.659615 -290.932496)
			(xy 338.682486 -290.976073) (xy 338.69807 -291.022754) (xy 338.705965 -291.071331) (xy 338.70646 -291.095938)
			(xy 339.024971 -291.095938) (xy 339.029066 -291.04521) (xy 339.041245 -290.995796) (xy 339.061193 -290.948976)
			(xy 339.088394 -290.905962) (xy 339.122142 -290.867868) (xy 339.161564 -290.835681) (xy 339.205638 -290.810235)
			(xy 339.253224 -290.792188) (xy 339.303088 -290.782008) (xy 339.35394 -290.779959) (xy 339.404461 -290.786093)
			(xy 339.453345 -290.800253) (xy 339.499324 -290.82207) (xy 339.541208 -290.85098) (xy 339.577912 -290.886235)
			(xy 339.608485 -290.926921) (xy 339.632136 -290.971984) (xy 339.648252 -291.020258) (xy 339.656416 -291.070492)
			(xy 339.656928 -291.095938) (xy 339.964771 -291.095938) (xy 339.968866 -291.04521) (xy 339.981045 -290.995796)
			(xy 340.000993 -290.948976) (xy 340.028194 -290.905962) (xy 340.061942 -290.867868) (xy 340.101364 -290.835681)
			(xy 340.145438 -290.810235) (xy 340.193024 -290.792188) (xy 340.242888 -290.782008) (xy 340.29374 -290.779959)
			(xy 340.344261 -290.786093) (xy 340.393145 -290.800253) (xy 340.439124 -290.82207) (xy 340.481008 -290.85098)
			(xy 340.517712 -290.886235) (xy 340.548285 -290.926921) (xy 340.571936 -290.971984) (xy 340.588052 -291.020258)
			(xy 340.596216 -291.070492) (xy 340.596728 -291.095938) (xy 340.915256 -291.095938) (xy 340.919216 -291.046884)
			(xy 340.930993 -290.9991) (xy 340.950284 -290.953824) (xy 340.976587 -290.912228) (xy 341.009222 -290.875391)
			(xy 341.047343 -290.844266) (xy 341.089964 -290.819659) (xy 341.13598 -290.802207) (xy 341.184199 -290.792363)
			(xy 341.233374 -290.790382) (xy 341.282229 -290.796314) (xy 341.3295 -290.810006) (xy 341.373962 -290.831104)
			(xy 341.414465 -290.85906) (xy 341.449958 -290.893152) (xy 341.479523 -290.932496) (xy 341.502394 -290.976073)
			(xy 341.517978 -291.022754) (xy 341.525873 -291.071331) (xy 341.526368 -291.095938) (xy 341.844879 -291.095938)
			(xy 341.848974 -291.04521) (xy 341.861153 -290.995796) (xy 341.881101 -290.948976) (xy 341.908302 -290.905962)
			(xy 341.94205 -290.867868) (xy 341.981472 -290.835681) (xy 342.025546 -290.810235) (xy 342.073132 -290.792188)
			(xy 342.122996 -290.782008) (xy 342.173848 -290.779959) (xy 342.224369 -290.786093) (xy 342.273253 -290.800253)
			(xy 342.319232 -290.82207) (xy 342.361116 -290.85098) (xy 342.39782 -290.886235) (xy 342.428393 -290.926921)
			(xy 342.452044 -290.971984) (xy 342.46816 -291.020258) (xy 342.476324 -291.070492) (xy 342.476836 -291.095938)
			(xy 342.476324 -291.121384) (xy 342.46816 -291.171618) (xy 342.452044 -291.219892) (xy 342.428393 -291.264955)
			(xy 342.39782 -291.305641) (xy 342.361116 -291.340896) (xy 342.319232 -291.369806) (xy 342.273253 -291.391623)
			(xy 342.224369 -291.405783) (xy 342.173848 -291.411917) (xy 342.122996 -291.409868) (xy 342.073132 -291.399688)
			(xy 342.025546 -291.381641) (xy 341.981472 -291.356195) (xy 341.94205 -291.324008) (xy 341.908302 -291.285914)
			(xy 341.881101 -291.2429) (xy 341.861153 -291.19608) (xy 341.848974 -291.146666) (xy 341.844879 -291.095938)
			(xy 341.526368 -291.095938) (xy 341.525873 -291.120545) (xy 341.517978 -291.169122) (xy 341.502394 -291.215803)
			(xy 341.479523 -291.25938) (xy 341.449958 -291.298724) (xy 341.414465 -291.332816) (xy 341.373962 -291.360772)
			(xy 341.3295 -291.38187) (xy 341.282229 -291.395562) (xy 341.233374 -291.401494) (xy 341.184199 -291.399513)
			(xy 341.13598 -291.389669) (xy 341.089964 -291.372217) (xy 341.047343 -291.34761) (xy 341.009222 -291.316485)
			(xy 340.976587 -291.279648) (xy 340.950284 -291.238052) (xy 340.930993 -291.192776) (xy 340.919216 -291.144992)
			(xy 340.915256 -291.095938) (xy 340.596728 -291.095938) (xy 340.596216 -291.121384) (xy 340.588052 -291.171618)
			(xy 340.571936 -291.219892) (xy 340.548285 -291.264955) (xy 340.517712 -291.305641) (xy 340.481008 -291.340896)
			(xy 340.439124 -291.369806) (xy 340.393145 -291.391623) (xy 340.344261 -291.405783) (xy 340.29374 -291.411917)
			(xy 340.242888 -291.409868) (xy 340.193024 -291.399688) (xy 340.145438 -291.381641) (xy 340.101364 -291.356195)
			(xy 340.061942 -291.324008) (xy 340.028194 -291.285914) (xy 340.000993 -291.2429) (xy 339.981045 -291.19608)
			(xy 339.968866 -291.146666) (xy 339.964771 -291.095938) (xy 339.656928 -291.095938) (xy 339.656416 -291.121384)
			(xy 339.648252 -291.171618) (xy 339.632136 -291.219892) (xy 339.608485 -291.264955) (xy 339.577912 -291.305641)
			(xy 339.541208 -291.340896) (xy 339.499324 -291.369806) (xy 339.453345 -291.391623) (xy 339.404461 -291.405783)
			(xy 339.35394 -291.411917) (xy 339.303088 -291.409868) (xy 339.253224 -291.399688) (xy 339.205638 -291.381641)
			(xy 339.161564 -291.356195) (xy 339.122142 -291.324008) (xy 339.088394 -291.285914) (xy 339.061193 -291.2429)
			(xy 339.041245 -291.19608) (xy 339.029066 -291.146666) (xy 339.024971 -291.095938) (xy 338.70646 -291.095938)
			(xy 338.705965 -291.120545) (xy 338.69807 -291.169122) (xy 338.682486 -291.215803) (xy 338.659615 -291.25938)
			(xy 338.63005 -291.298724) (xy 338.594557 -291.332816) (xy 338.554054 -291.360772) (xy 338.509592 -291.38187)
			(xy 338.462321 -291.395562) (xy 338.413466 -291.401494) (xy 338.364291 -291.399513) (xy 338.316072 -291.389669)
			(xy 338.270056 -291.372217) (xy 338.227435 -291.34761) (xy 338.189314 -291.316485) (xy 338.156679 -291.279648)
			(xy 338.130376 -291.238052) (xy 338.111085 -291.192776) (xy 338.099308 -291.144992) (xy 338.095348 -291.095938)
			(xy 337.766406 -291.095938) (xy 337.765911 -291.120545) (xy 337.758016 -291.169122) (xy 337.742432 -291.215803)
			(xy 337.719561 -291.25938) (xy 337.689996 -291.298724) (xy 337.654503 -291.332816) (xy 337.614 -291.360772)
			(xy 337.569538 -291.38187) (xy 337.522267 -291.395562) (xy 337.473412 -291.401494) (xy 337.424237 -291.399513)
			(xy 337.376018 -291.389669) (xy 337.330002 -291.372217) (xy 337.287381 -291.34761) (xy 337.24926 -291.316485)
			(xy 337.216625 -291.279648) (xy 337.190322 -291.238052) (xy 337.171031 -291.192776) (xy 337.159254 -291.144992)
			(xy 337.155294 -291.095938) (xy 336.826352 -291.095938) (xy 336.825857 -291.120545) (xy 336.817962 -291.169122)
			(xy 336.802378 -291.215803) (xy 336.779507 -291.25938) (xy 336.749942 -291.298724) (xy 336.714449 -291.332816)
			(xy 336.673946 -291.360772) (xy 336.629484 -291.38187) (xy 336.582213 -291.395562) (xy 336.533358 -291.401494)
			(xy 336.484183 -291.399513) (xy 336.435964 -291.389669) (xy 336.389948 -291.372217) (xy 336.347327 -291.34761)
			(xy 336.309206 -291.316485) (xy 336.276571 -291.279648) (xy 336.250268 -291.238052) (xy 336.230977 -291.192776)
			(xy 336.2192 -291.144992) (xy 336.21524 -291.095938) (xy 335.886298 -291.095938) (xy 335.885803 -291.120545)
			(xy 335.877908 -291.169122) (xy 335.862324 -291.215803) (xy 335.839453 -291.25938) (xy 335.809888 -291.298724)
			(xy 335.774395 -291.332816) (xy 335.733892 -291.360772) (xy 335.68943 -291.38187) (xy 335.642159 -291.395562)
			(xy 335.593304 -291.401494) (xy 335.544129 -291.399513) (xy 335.49591 -291.389669) (xy 335.449894 -291.372217)
			(xy 335.407273 -291.34761) (xy 335.369152 -291.316485) (xy 335.336517 -291.279648) (xy 335.310214 -291.238052)
			(xy 335.290923 -291.192776) (xy 335.279146 -291.144992) (xy 335.275186 -291.095938) (xy 334.950054 -291.095938)
			(xy 334.950054 -291.504624) (xy 334.950054 -291.507164) (xy 334.950956 -291.516835) (xy 334.959046 -291.534476)
			(xy 334.965802 -291.541454) (xy 335.024476 -291.592) (xy 335.02871 -291.595472) (xy 335.038321 -291.600713)
			(xy 335.043526 -291.602414) (xy 335.054194 -291.605462) (xy 335.065116 -291.603938) (xy 335.076354 -291.602382)
			(xy 335.098983 -291.600727) (xy 335.110328 -291.600636) (xy 335.11109 -291.600636) (xy 335.136345 -291.601128)
			(xy 335.186165 -291.60944) (xy 335.233938 -291.625839) (xy 335.27836 -291.649878) (xy 335.31822 -291.6809)
			(xy 335.352429 -291.718061) (xy 335.380056 -291.760345) (xy 335.400345 -291.8066) (xy 335.412745 -291.855563)
			(xy 335.416916 -291.9059) (xy 335.416912 -291.905944) (xy 335.74534 -291.905944) (xy 335.7493 -291.85689)
			(xy 335.761077 -291.809106) (xy 335.780368 -291.76383) (xy 335.806671 -291.722234) (xy 335.839306 -291.685397)
			(xy 335.877427 -291.654272) (xy 335.920048 -291.629665) (xy 335.966064 -291.612213) (xy 336.014283 -291.602369)
			(xy 336.063458 -291.600388) (xy 336.112313 -291.60632) (xy 336.159584 -291.620012) (xy 336.204046 -291.64111)
			(xy 336.244549 -291.669066) (xy 336.280042 -291.703158) (xy 336.309607 -291.742502) (xy 336.332478 -291.786079)
			(xy 336.348062 -291.83276) (xy 336.355957 -291.881337) (xy 336.356452 -291.905944) (xy 336.685394 -291.905944)
			(xy 336.689354 -291.85689) (xy 336.701131 -291.809106) (xy 336.720422 -291.76383) (xy 336.746725 -291.722234)
			(xy 336.77936 -291.685397) (xy 336.817481 -291.654272) (xy 336.860102 -291.629665) (xy 336.906118 -291.612213)
			(xy 336.954337 -291.602369) (xy 337.003512 -291.600388) (xy 337.052367 -291.60632) (xy 337.099638 -291.620012)
			(xy 337.1441 -291.64111) (xy 337.184603 -291.669066) (xy 337.220096 -291.703158) (xy 337.249661 -291.742502)
			(xy 337.272532 -291.786079) (xy 337.288116 -291.83276) (xy 337.296011 -291.881337) (xy 337.296506 -291.905944)
			(xy 337.625194 -291.905944) (xy 337.629154 -291.85689) (xy 337.640931 -291.809106) (xy 337.660222 -291.76383)
			(xy 337.686525 -291.722234) (xy 337.71916 -291.685397) (xy 337.757281 -291.654272) (xy 337.799902 -291.629665)
			(xy 337.845918 -291.612213) (xy 337.894137 -291.602369) (xy 337.943312 -291.600388) (xy 337.992167 -291.60632)
			(xy 338.039438 -291.620012) (xy 338.0839 -291.64111) (xy 338.124403 -291.669066) (xy 338.159896 -291.703158)
			(xy 338.189461 -291.742502) (xy 338.212332 -291.786079) (xy 338.227916 -291.83276) (xy 338.235811 -291.881337)
			(xy 338.236306 -291.905944) (xy 338.554817 -291.905944) (xy 338.558912 -291.855216) (xy 338.571091 -291.805802)
			(xy 338.591039 -291.758982) (xy 338.61824 -291.715968) (xy 338.651988 -291.677874) (xy 338.69141 -291.645687)
			(xy 338.735484 -291.620241) (xy 338.78307 -291.602194) (xy 338.832934 -291.592014) (xy 338.883786 -291.589965)
			(xy 338.934307 -291.596099) (xy 338.983191 -291.610259) (xy 339.02917 -291.632076) (xy 339.071054 -291.660986)
			(xy 339.107758 -291.696241) (xy 339.138331 -291.736927) (xy 339.161982 -291.78199) (xy 339.178098 -291.830264)
			(xy 339.186262 -291.880498) (xy 339.186774 -291.905944) (xy 339.505302 -291.905944) (xy 339.509262 -291.85689)
			(xy 339.521039 -291.809106) (xy 339.54033 -291.76383) (xy 339.566633 -291.722234) (xy 339.599268 -291.685397)
			(xy 339.637389 -291.654272) (xy 339.68001 -291.629665) (xy 339.726026 -291.612213) (xy 339.774245 -291.602369)
			(xy 339.82342 -291.600388) (xy 339.872275 -291.60632) (xy 339.919546 -291.620012) (xy 339.964008 -291.64111)
			(xy 340.004511 -291.669066) (xy 340.040004 -291.703158) (xy 340.069569 -291.742502) (xy 340.09244 -291.786079)
			(xy 340.108024 -291.83276) (xy 340.115919 -291.881337) (xy 340.116414 -291.905944) (xy 340.434925 -291.905944)
			(xy 340.43902 -291.855216) (xy 340.451199 -291.805802) (xy 340.471147 -291.758982) (xy 340.498348 -291.715968)
			(xy 340.532096 -291.677874) (xy 340.571518 -291.645687) (xy 340.615592 -291.620241) (xy 340.663178 -291.602194)
			(xy 340.713042 -291.592014) (xy 340.763894 -291.589965) (xy 340.814415 -291.596099) (xy 340.863299 -291.610259)
			(xy 340.909278 -291.632076) (xy 340.951162 -291.660986) (xy 340.987866 -291.696241) (xy 341.018439 -291.736927)
			(xy 341.04209 -291.78199) (xy 341.058206 -291.830264) (xy 341.06637 -291.880498) (xy 341.066882 -291.905944)
			(xy 341.38541 -291.905944) (xy 341.38937 -291.85689) (xy 341.401147 -291.809106) (xy 341.420438 -291.76383)
			(xy 341.446741 -291.722234) (xy 341.479376 -291.685397) (xy 341.517497 -291.654272) (xy 341.560118 -291.629665)
			(xy 341.606134 -291.612213) (xy 341.654353 -291.602369) (xy 341.703528 -291.600388) (xy 341.752383 -291.60632)
			(xy 341.799654 -291.620012) (xy 341.844116 -291.64111) (xy 341.884619 -291.669066) (xy 341.920112 -291.703158)
			(xy 341.949677 -291.742502) (xy 341.972548 -291.786079) (xy 341.988132 -291.83276) (xy 341.996027 -291.881337)
			(xy 341.996522 -291.905944) (xy 342.314779 -291.905944) (xy 342.318874 -291.855216) (xy 342.331053 -291.805802)
			(xy 342.351001 -291.758982) (xy 342.378202 -291.715968) (xy 342.41195 -291.677874) (xy 342.451372 -291.645687)
			(xy 342.495446 -291.620241) (xy 342.543032 -291.602194) (xy 342.592896 -291.592014) (xy 342.643748 -291.589965)
			(xy 342.694269 -291.596099) (xy 342.743153 -291.610259) (xy 342.789132 -291.632076) (xy 342.831016 -291.660986)
			(xy 342.86772 -291.696241) (xy 342.898293 -291.736927) (xy 342.921944 -291.78199) (xy 342.93806 -291.830264)
			(xy 342.946224 -291.880498) (xy 342.946736 -291.905944) (xy 342.946224 -291.93139) (xy 342.93806 -291.981624)
			(xy 342.921944 -292.029898) (xy 342.898293 -292.074961) (xy 342.86772 -292.115647) (xy 342.831016 -292.150902)
			(xy 342.789132 -292.179812) (xy 342.743153 -292.201629) (xy 342.694269 -292.215789) (xy 342.643748 -292.221923)
			(xy 342.592896 -292.219874) (xy 342.543032 -292.209694) (xy 342.495446 -292.191647) (xy 342.451372 -292.166201)
			(xy 342.41195 -292.134014) (xy 342.378202 -292.09592) (xy 342.351001 -292.052906) (xy 342.331053 -292.006086)
			(xy 342.318874 -291.956672) (xy 342.314779 -291.905944) (xy 341.996522 -291.905944) (xy 341.996027 -291.930551)
			(xy 341.988132 -291.979128) (xy 341.972548 -292.025809) (xy 341.949677 -292.069386) (xy 341.920112 -292.10873)
			(xy 341.884619 -292.142822) (xy 341.844116 -292.170778) (xy 341.799654 -292.191876) (xy 341.752383 -292.205568)
			(xy 341.703528 -292.2115) (xy 341.654353 -292.209519) (xy 341.606134 -292.199675) (xy 341.560118 -292.182223)
			(xy 341.517497 -292.157616) (xy 341.479376 -292.126491) (xy 341.446741 -292.089654) (xy 341.420438 -292.048058)
			(xy 341.401147 -292.002782) (xy 341.38937 -291.954998) (xy 341.38541 -291.905944) (xy 341.066882 -291.905944)
			(xy 341.06637 -291.93139) (xy 341.058206 -291.981624) (xy 341.04209 -292.029898) (xy 341.018439 -292.074961)
			(xy 340.987866 -292.115647) (xy 340.951162 -292.150902) (xy 340.909278 -292.179812) (xy 340.863299 -292.201629)
			(xy 340.814415 -292.215789) (xy 340.763894 -292.221923) (xy 340.713042 -292.219874) (xy 340.663178 -292.209694)
			(xy 340.615592 -292.191647) (xy 340.571518 -292.166201) (xy 340.532096 -292.134014) (xy 340.498348 -292.09592)
			(xy 340.471147 -292.052906) (xy 340.451199 -292.006086) (xy 340.43902 -291.956672) (xy 340.434925 -291.905944)
			(xy 340.116414 -291.905944) (xy 340.115919 -291.930551) (xy 340.108024 -291.979128) (xy 340.09244 -292.025809)
			(xy 340.069569 -292.069386) (xy 340.040004 -292.10873) (xy 340.004511 -292.142822) (xy 339.964008 -292.170778)
			(xy 339.919546 -292.191876) (xy 339.872275 -292.205568) (xy 339.82342 -292.2115) (xy 339.774245 -292.209519)
			(xy 339.726026 -292.199675) (xy 339.68001 -292.182223) (xy 339.637389 -292.157616) (xy 339.599268 -292.126491)
			(xy 339.566633 -292.089654) (xy 339.54033 -292.048058) (xy 339.521039 -292.002782) (xy 339.509262 -291.954998)
			(xy 339.505302 -291.905944) (xy 339.186774 -291.905944) (xy 339.186262 -291.93139) (xy 339.178098 -291.981624)
			(xy 339.161982 -292.029898) (xy 339.138331 -292.074961) (xy 339.107758 -292.115647) (xy 339.071054 -292.150902)
			(xy 339.02917 -292.179812) (xy 338.983191 -292.201629) (xy 338.934307 -292.215789) (xy 338.883786 -292.221923)
			(xy 338.832934 -292.219874) (xy 338.78307 -292.209694) (xy 338.735484 -292.191647) (xy 338.69141 -292.166201)
			(xy 338.651988 -292.134014) (xy 338.61824 -292.09592) (xy 338.591039 -292.052906) (xy 338.571091 -292.006086)
			(xy 338.558912 -291.956672) (xy 338.554817 -291.905944) (xy 338.236306 -291.905944) (xy 338.235811 -291.930551)
			(xy 338.227916 -291.979128) (xy 338.212332 -292.025809) (xy 338.189461 -292.069386) (xy 338.159896 -292.10873)
			(xy 338.124403 -292.142822) (xy 338.0839 -292.170778) (xy 338.039438 -292.191876) (xy 337.992167 -292.205568)
			(xy 337.943312 -292.2115) (xy 337.894137 -292.209519) (xy 337.845918 -292.199675) (xy 337.799902 -292.182223)
			(xy 337.757281 -292.157616) (xy 337.71916 -292.126491) (xy 337.686525 -292.089654) (xy 337.660222 -292.048058)
			(xy 337.640931 -292.002782) (xy 337.629154 -291.954998) (xy 337.625194 -291.905944) (xy 337.296506 -291.905944)
			(xy 337.296011 -291.930551) (xy 337.288116 -291.979128) (xy 337.272532 -292.025809) (xy 337.249661 -292.069386)
			(xy 337.220096 -292.10873) (xy 337.184603 -292.142822) (xy 337.1441 -292.170778) (xy 337.099638 -292.191876)
			(xy 337.052367 -292.205568) (xy 337.003512 -292.2115) (xy 336.954337 -292.209519) (xy 336.906118 -292.199675)
			(xy 336.860102 -292.182223) (xy 336.817481 -292.157616) (xy 336.77936 -292.126491) (xy 336.746725 -292.089654)
			(xy 336.720422 -292.048058) (xy 336.701131 -292.002782) (xy 336.689354 -291.954998) (xy 336.685394 -291.905944)
			(xy 336.356452 -291.905944) (xy 336.355957 -291.930551) (xy 336.348062 -291.979128) (xy 336.332478 -292.025809)
			(xy 336.309607 -292.069386) (xy 336.280042 -292.10873) (xy 336.244549 -292.142822) (xy 336.204046 -292.170778)
			(xy 336.159584 -292.191876) (xy 336.112313 -292.205568) (xy 336.063458 -292.2115) (xy 336.014283 -292.209519)
			(xy 335.966064 -292.199675) (xy 335.920048 -292.182223) (xy 335.877427 -292.157616) (xy 335.839306 -292.126491)
			(xy 335.806671 -292.089654) (xy 335.780368 -292.048058) (xy 335.761077 -292.002782) (xy 335.7493 -291.954998)
			(xy 335.74534 -291.905944) (xy 335.416912 -291.905944) (xy 335.412745 -291.956237) (xy 335.400345 -292.0052)
			(xy 335.380056 -292.051455) (xy 335.352429 -292.093739) (xy 335.31822 -292.1309) (xy 335.27836 -292.161922)
			(xy 335.233938 -292.185961) (xy 335.186165 -292.20236) (xy 335.136345 -292.210672) (xy 335.11109 -292.211252)
			(xy 335.110836 -292.211252) (xy 335.089738 -292.210874) (xy 335.047949 -292.205034) (xy 335.007356 -292.193513)
			(xy 334.9879 -292.185344) (xy 334.983582 -292.183312) (xy 334.980534 -292.182042) (xy 334.965802 -292.180518)
			(xy 334.956912 -292.182296) (xy 334.949724 -292.184026) (xy 334.936697 -292.191004) (xy 334.931258 -292.196012)
			(xy 334.41132 -292.71595) (xy 335.275186 -292.71595) (xy 335.279146 -292.666896) (xy 335.290923 -292.619112)
			(xy 335.310214 -292.573836) (xy 335.336517 -292.53224) (xy 335.369152 -292.495403) (xy 335.407273 -292.464278)
			(xy 335.449894 -292.439671) (xy 335.49591 -292.422219) (xy 335.544129 -292.412375) (xy 335.593304 -292.410394)
			(xy 335.642159 -292.416326) (xy 335.68943 -292.430018) (xy 335.733892 -292.451116) (xy 335.774395 -292.479072)
			(xy 335.809888 -292.513164) (xy 335.839453 -292.552508) (xy 335.862324 -292.596085) (xy 335.877908 -292.642766)
			(xy 335.885803 -292.691343) (xy 335.886298 -292.71595) (xy 336.21524 -292.71595) (xy 336.2192 -292.666896)
			(xy 336.230977 -292.619112) (xy 336.250268 -292.573836) (xy 336.276571 -292.53224) (xy 336.309206 -292.495403)
			(xy 336.347327 -292.464278) (xy 336.389948 -292.439671) (xy 336.435964 -292.422219) (xy 336.484183 -292.412375)
			(xy 336.533358 -292.410394) (xy 336.582213 -292.416326) (xy 336.629484 -292.430018) (xy 336.673946 -292.451116)
			(xy 336.714449 -292.479072) (xy 336.749942 -292.513164) (xy 336.779507 -292.552508) (xy 336.802378 -292.596085)
			(xy 336.817962 -292.642766) (xy 336.825857 -292.691343) (xy 336.826352 -292.71595) (xy 337.155294 -292.71595)
			(xy 337.159254 -292.666896) (xy 337.171031 -292.619112) (xy 337.190322 -292.573836) (xy 337.216625 -292.53224)
			(xy 337.24926 -292.495403) (xy 337.287381 -292.464278) (xy 337.330002 -292.439671) (xy 337.376018 -292.422219)
			(xy 337.424237 -292.412375) (xy 337.473412 -292.410394) (xy 337.522267 -292.416326) (xy 337.569538 -292.430018)
			(xy 337.614 -292.451116) (xy 337.654503 -292.479072) (xy 337.689996 -292.513164) (xy 337.719561 -292.552508)
			(xy 337.742432 -292.596085) (xy 337.758016 -292.642766) (xy 337.765911 -292.691343) (xy 337.766406 -292.71595)
			(xy 338.095348 -292.71595) (xy 338.099308 -292.666896) (xy 338.111085 -292.619112) (xy 338.130376 -292.573836)
			(xy 338.156679 -292.53224) (xy 338.189314 -292.495403) (xy 338.227435 -292.464278) (xy 338.270056 -292.439671)
			(xy 338.316072 -292.422219) (xy 338.364291 -292.412375) (xy 338.413466 -292.410394) (xy 338.462321 -292.416326)
			(xy 338.509592 -292.430018) (xy 338.554054 -292.451116) (xy 338.594557 -292.479072) (xy 338.63005 -292.513164)
			(xy 338.659615 -292.552508) (xy 338.682486 -292.596085) (xy 338.69807 -292.642766) (xy 338.705965 -292.691343)
			(xy 338.70646 -292.71595) (xy 339.024971 -292.71595) (xy 339.029066 -292.665222) (xy 339.041245 -292.615808)
			(xy 339.061193 -292.568988) (xy 339.088394 -292.525974) (xy 339.122142 -292.48788) (xy 339.161564 -292.455693)
			(xy 339.205638 -292.430247) (xy 339.253224 -292.4122) (xy 339.303088 -292.40202) (xy 339.35394 -292.399971)
			(xy 339.404461 -292.406105) (xy 339.453345 -292.420265) (xy 339.499324 -292.442082) (xy 339.541208 -292.470992)
			(xy 339.577912 -292.506247) (xy 339.608485 -292.546933) (xy 339.632136 -292.591996) (xy 339.648252 -292.64027)
			(xy 339.656416 -292.690504) (xy 339.656928 -292.71595) (xy 339.964771 -292.71595) (xy 339.968866 -292.665222)
			(xy 339.981045 -292.615808) (xy 340.000993 -292.568988) (xy 340.028194 -292.525974) (xy 340.061942 -292.48788)
			(xy 340.101364 -292.455693) (xy 340.145438 -292.430247) (xy 340.193024 -292.4122) (xy 340.242888 -292.40202)
			(xy 340.29374 -292.399971) (xy 340.344261 -292.406105) (xy 340.393145 -292.420265) (xy 340.439124 -292.442082)
			(xy 340.481008 -292.470992) (xy 340.517712 -292.506247) (xy 340.548285 -292.546933) (xy 340.571936 -292.591996)
			(xy 340.588052 -292.64027) (xy 340.596216 -292.690504) (xy 340.596728 -292.71595) (xy 341.844879 -292.71595)
			(xy 341.848974 -292.665222) (xy 341.861153 -292.615808) (xy 341.881101 -292.568988) (xy 341.908302 -292.525974)
			(xy 341.94205 -292.48788) (xy 341.981472 -292.455693) (xy 342.025546 -292.430247) (xy 342.073132 -292.4122)
			(xy 342.122996 -292.40202) (xy 342.173848 -292.399971) (xy 342.224369 -292.406105) (xy 342.273253 -292.420265)
			(xy 342.319232 -292.442082) (xy 342.361116 -292.470992) (xy 342.39782 -292.506247) (xy 342.428393 -292.546933)
			(xy 342.452044 -292.591996) (xy 342.46816 -292.64027) (xy 342.476324 -292.690504) (xy 342.476836 -292.71595)
			(xy 342.476324 -292.741396) (xy 342.46816 -292.79163) (xy 342.452044 -292.839904) (xy 342.428393 -292.884967)
			(xy 342.39782 -292.925653) (xy 342.361116 -292.960908) (xy 342.319232 -292.989818) (xy 342.273253 -293.011635)
			(xy 342.224369 -293.025795) (xy 342.173848 -293.031929) (xy 342.122996 -293.02988) (xy 342.073132 -293.0197)
			(xy 342.025546 -293.001653) (xy 341.981472 -292.976207) (xy 341.94205 -292.94402) (xy 341.908302 -292.905926)
			(xy 341.881101 -292.862912) (xy 341.861153 -292.816092) (xy 341.848974 -292.766678) (xy 341.844879 -292.71595)
			(xy 340.596728 -292.71595) (xy 340.596216 -292.741396) (xy 340.588052 -292.79163) (xy 340.571936 -292.839904)
			(xy 340.548285 -292.884967) (xy 340.517712 -292.925653) (xy 340.481008 -292.960908) (xy 340.439124 -292.989818)
			(xy 340.393145 -293.011635) (xy 340.344261 -293.025795) (xy 340.29374 -293.031929) (xy 340.242888 -293.02988)
			(xy 340.193024 -293.0197) (xy 340.145438 -293.001653) (xy 340.101364 -292.976207) (xy 340.061942 -292.94402)
			(xy 340.028194 -292.905926) (xy 340.000993 -292.862912) (xy 339.981045 -292.816092) (xy 339.968866 -292.766678)
			(xy 339.964771 -292.71595) (xy 339.656928 -292.71595) (xy 339.656416 -292.741396) (xy 339.648252 -292.79163)
			(xy 339.632136 -292.839904) (xy 339.608485 -292.884967) (xy 339.577912 -292.925653) (xy 339.541208 -292.960908)
			(xy 339.499324 -292.989818) (xy 339.453345 -293.011635) (xy 339.404461 -293.025795) (xy 339.35394 -293.031929)
			(xy 339.303088 -293.02988) (xy 339.253224 -293.0197) (xy 339.205638 -293.001653) (xy 339.161564 -292.976207)
			(xy 339.122142 -292.94402) (xy 339.088394 -292.905926) (xy 339.061193 -292.862912) (xy 339.041245 -292.816092)
			(xy 339.029066 -292.766678) (xy 339.024971 -292.71595) (xy 338.70646 -292.71595) (xy 338.705965 -292.740557)
			(xy 338.69807 -292.789134) (xy 338.682486 -292.835815) (xy 338.659615 -292.879392) (xy 338.63005 -292.918736)
			(xy 338.594557 -292.952828) (xy 338.554054 -292.980784) (xy 338.509592 -293.001882) (xy 338.462321 -293.015574)
			(xy 338.413466 -293.021506) (xy 338.364291 -293.019525) (xy 338.316072 -293.009681) (xy 338.270056 -292.992229)
			(xy 338.227435 -292.967622) (xy 338.189314 -292.936497) (xy 338.156679 -292.89966) (xy 338.130376 -292.858064)
			(xy 338.111085 -292.812788) (xy 338.099308 -292.765004) (xy 338.095348 -292.71595) (xy 337.766406 -292.71595)
			(xy 337.765911 -292.740557) (xy 337.758016 -292.789134) (xy 337.742432 -292.835815) (xy 337.719561 -292.879392)
			(xy 337.689996 -292.918736) (xy 337.654503 -292.952828) (xy 337.614 -292.980784) (xy 337.569538 -293.001882)
			(xy 337.522267 -293.015574) (xy 337.473412 -293.021506) (xy 337.424237 -293.019525) (xy 337.376018 -293.009681)
			(xy 337.330002 -292.992229) (xy 337.287381 -292.967622) (xy 337.24926 -292.936497) (xy 337.216625 -292.89966)
			(xy 337.190322 -292.858064) (xy 337.171031 -292.812788) (xy 337.159254 -292.765004) (xy 337.155294 -292.71595)
			(xy 336.826352 -292.71595) (xy 336.825857 -292.740557) (xy 336.817962 -292.789134) (xy 336.802378 -292.835815)
			(xy 336.779507 -292.879392) (xy 336.749942 -292.918736) (xy 336.714449 -292.952828) (xy 336.673946 -292.980784)
			(xy 336.629484 -293.001882) (xy 336.582213 -293.015574) (xy 336.533358 -293.021506) (xy 336.484183 -293.019525)
			(xy 336.435964 -293.009681) (xy 336.389948 -292.992229) (xy 336.347327 -292.967622) (xy 336.309206 -292.936497)
			(xy 336.276571 -292.89966) (xy 336.250268 -292.858064) (xy 336.230977 -292.812788) (xy 336.2192 -292.765004)
			(xy 336.21524 -292.71595) (xy 335.886298 -292.71595) (xy 335.885803 -292.740557) (xy 335.877908 -292.789134)
			(xy 335.862324 -292.835815) (xy 335.839453 -292.879392) (xy 335.809888 -292.918736) (xy 335.774395 -292.952828)
			(xy 335.733892 -292.980784) (xy 335.68943 -293.001882) (xy 335.642159 -293.015574) (xy 335.593304 -293.021506)
			(xy 335.544129 -293.019525) (xy 335.49591 -293.009681) (xy 335.449894 -292.992229) (xy 335.407273 -292.967622)
			(xy 335.369152 -292.936497) (xy 335.336517 -292.89966) (xy 335.310214 -292.858064) (xy 335.290923 -292.812788)
			(xy 335.279146 -292.765004) (xy 335.275186 -292.71595) (xy 334.41132 -292.71595) (xy 334.393794 -292.733476)
			(xy 334.386358 -292.741754) (xy 334.378817 -292.762661) (xy 334.380826 -292.784796) (xy 334.38592 -292.79469)
			(xy 334.437736 -292.884606) (xy 334.442384 -292.893509) (xy 334.444988 -292.913407) (xy 334.442816 -292.923214)
			(xy 334.392778 -293.10965) (xy 334.392778 -293.110158) (xy 334.388968 -293.124382) (xy 334.388968 -293.12489)
			(xy 334.366616 -293.207948) (xy 334.358234 -293.236142) (xy 334.357218 -293.239444) (xy 334.35544 -293.245032)
			(xy 334.355694 -293.253922) (xy 334.356069 -293.258715) (xy 334.358367 -293.268048) (xy 334.360266 -293.272464)
			(xy 334.369664 -293.2938) (xy 334.377538 -293.300912) (xy 334.395835 -293.318406) (xy 334.426945 -293.358335)
			(xy 334.451052 -293.402845) (xy 334.467495 -293.450718) (xy 334.475826 -293.500647) (xy 334.476344 -293.525956)
			(xy 334.805286 -293.525956) (xy 334.809246 -293.476902) (xy 334.821023 -293.429118) (xy 334.840314 -293.383842)
			(xy 334.866617 -293.342246) (xy 334.899252 -293.305409) (xy 334.937373 -293.274284) (xy 334.979994 -293.249677)
			(xy 335.02601 -293.232225) (xy 335.074229 -293.222381) (xy 335.123404 -293.2204) (xy 335.172259 -293.226332)
			(xy 335.21953 -293.240024) (xy 335.263992 -293.261122) (xy 335.304495 -293.289078) (xy 335.339988 -293.32317)
			(xy 335.369553 -293.362514) (xy 335.392424 -293.406091) (xy 335.408008 -293.452772) (xy 335.415903 -293.501349)
			(xy 335.416398 -293.525956) (xy 335.74534 -293.525956) (xy 335.7493 -293.476902) (xy 335.761077 -293.429118)
			(xy 335.780368 -293.383842) (xy 335.806671 -293.342246) (xy 335.839306 -293.305409) (xy 335.877427 -293.274284)
			(xy 335.920048 -293.249677) (xy 335.966064 -293.232225) (xy 336.014283 -293.222381) (xy 336.063458 -293.2204)
			(xy 336.112313 -293.226332) (xy 336.159584 -293.240024) (xy 336.204046 -293.261122) (xy 336.244549 -293.289078)
			(xy 336.280042 -293.32317) (xy 336.309607 -293.362514) (xy 336.332478 -293.406091) (xy 336.348062 -293.452772)
			(xy 336.355957 -293.501349) (xy 336.356452 -293.525956) (xy 336.685394 -293.525956) (xy 336.689354 -293.476902)
			(xy 336.701131 -293.429118) (xy 336.720422 -293.383842) (xy 336.746725 -293.342246) (xy 336.77936 -293.305409)
			(xy 336.817481 -293.274284) (xy 336.860102 -293.249677) (xy 336.906118 -293.232225) (xy 336.954337 -293.222381)
			(xy 337.003512 -293.2204) (xy 337.052367 -293.226332) (xy 337.099638 -293.240024) (xy 337.1441 -293.261122)
			(xy 337.184603 -293.289078) (xy 337.220096 -293.32317) (xy 337.249661 -293.362514) (xy 337.272532 -293.406091)
			(xy 337.288116 -293.452772) (xy 337.296011 -293.501349) (xy 337.296506 -293.525956) (xy 337.625194 -293.525956)
			(xy 337.629154 -293.476902) (xy 337.640931 -293.429118) (xy 337.660222 -293.383842) (xy 337.686525 -293.342246)
			(xy 337.71916 -293.305409) (xy 337.757281 -293.274284) (xy 337.799902 -293.249677) (xy 337.845918 -293.232225)
			(xy 337.894137 -293.222381) (xy 337.943312 -293.2204) (xy 337.992167 -293.226332) (xy 338.039438 -293.240024)
			(xy 338.0839 -293.261122) (xy 338.124403 -293.289078) (xy 338.159896 -293.32317) (xy 338.189461 -293.362514)
			(xy 338.212332 -293.406091) (xy 338.227916 -293.452772) (xy 338.235811 -293.501349) (xy 338.236306 -293.525956)
			(xy 338.554817 -293.525956) (xy 338.558912 -293.475228) (xy 338.571091 -293.425814) (xy 338.591039 -293.378994)
			(xy 338.61824 -293.33598) (xy 338.651988 -293.297886) (xy 338.69141 -293.265699) (xy 338.735484 -293.240253)
			(xy 338.78307 -293.222206) (xy 338.832934 -293.212026) (xy 338.883786 -293.209977) (xy 338.934307 -293.216111)
			(xy 338.983191 -293.230271) (xy 339.02917 -293.252088) (xy 339.071054 -293.280998) (xy 339.107758 -293.316253)
			(xy 339.138331 -293.356939) (xy 339.161982 -293.402002) (xy 339.178098 -293.450276) (xy 339.186262 -293.50051)
			(xy 339.186774 -293.525956) (xy 339.505302 -293.525956) (xy 339.509262 -293.476902) (xy 339.521039 -293.429118)
			(xy 339.54033 -293.383842) (xy 339.566633 -293.342246) (xy 339.599268 -293.305409) (xy 339.637389 -293.274284)
			(xy 339.68001 -293.249677) (xy 339.726026 -293.232225) (xy 339.774245 -293.222381) (xy 339.82342 -293.2204)
			(xy 339.872275 -293.226332) (xy 339.919546 -293.240024) (xy 339.964008 -293.261122) (xy 340.004511 -293.289078)
			(xy 340.040004 -293.32317) (xy 340.069569 -293.362514) (xy 340.09244 -293.406091) (xy 340.108024 -293.452772)
			(xy 340.115919 -293.501349) (xy 340.116414 -293.525956) (xy 340.445356 -293.525956) (xy 340.449316 -293.476902)
			(xy 340.461093 -293.429118) (xy 340.480384 -293.383842) (xy 340.506687 -293.342246) (xy 340.539322 -293.305409)
			(xy 340.577443 -293.274284) (xy 340.620064 -293.249677) (xy 340.66608 -293.232225) (xy 340.714299 -293.222381)
			(xy 340.763474 -293.2204) (xy 340.812329 -293.226332) (xy 340.8596 -293.240024) (xy 340.904062 -293.261122)
			(xy 340.944565 -293.289078) (xy 340.980058 -293.32317) (xy 341.009623 -293.362514) (xy 341.032494 -293.406091)
			(xy 341.048078 -293.452772) (xy 341.055973 -293.501349) (xy 341.056468 -293.525956) (xy 341.38541 -293.525956)
			(xy 341.38937 -293.476902) (xy 341.401147 -293.429118) (xy 341.420438 -293.383842) (xy 341.446741 -293.342246)
			(xy 341.479376 -293.305409) (xy 341.517497 -293.274284) (xy 341.560118 -293.249677) (xy 341.606134 -293.232225)
			(xy 341.654353 -293.222381) (xy 341.703528 -293.2204) (xy 341.752383 -293.226332) (xy 341.799654 -293.240024)
			(xy 341.844116 -293.261122) (xy 341.884619 -293.289078) (xy 341.920112 -293.32317) (xy 341.949677 -293.362514)
			(xy 341.972548 -293.406091) (xy 341.988132 -293.452772) (xy 341.996027 -293.501349) (xy 341.996522 -293.525956)
			(xy 342.32521 -293.525956) (xy 342.32917 -293.476902) (xy 342.340947 -293.429118) (xy 342.360238 -293.383842)
			(xy 342.386541 -293.342246) (xy 342.419176 -293.305409) (xy 342.457297 -293.274284) (xy 342.499918 -293.249677)
			(xy 342.545934 -293.232225) (xy 342.594153 -293.222381) (xy 342.643328 -293.2204) (xy 342.692183 -293.226332)
			(xy 342.739454 -293.240024) (xy 342.783916 -293.261122) (xy 342.824419 -293.289078) (xy 342.859912 -293.32317)
			(xy 342.889477 -293.362514) (xy 342.912348 -293.406091) (xy 342.927932 -293.452772) (xy 342.935827 -293.501349)
			(xy 342.936322 -293.525956) (xy 342.935827 -293.550563) (xy 342.927932 -293.59914) (xy 342.912348 -293.645821)
			(xy 342.889477 -293.689398) (xy 342.859912 -293.728742) (xy 342.824419 -293.762834) (xy 342.783916 -293.79079)
			(xy 342.739454 -293.811888) (xy 342.692183 -293.82558) (xy 342.643328 -293.831512) (xy 342.594153 -293.829531)
			(xy 342.545934 -293.819687) (xy 342.499918 -293.802235) (xy 342.457297 -293.777628) (xy 342.419176 -293.746503)
			(xy 342.386541 -293.709666) (xy 342.360238 -293.66807) (xy 342.340947 -293.622794) (xy 342.32917 -293.57501)
			(xy 342.32521 -293.525956) (xy 341.996522 -293.525956) (xy 341.996027 -293.550563) (xy 341.988132 -293.59914)
			(xy 341.972548 -293.645821) (xy 341.949677 -293.689398) (xy 341.920112 -293.728742) (xy 341.884619 -293.762834)
			(xy 341.844116 -293.79079) (xy 341.799654 -293.811888) (xy 341.752383 -293.82558) (xy 341.703528 -293.831512)
			(xy 341.654353 -293.829531) (xy 341.606134 -293.819687) (xy 341.560118 -293.802235) (xy 341.517497 -293.777628)
			(xy 341.479376 -293.746503) (xy 341.446741 -293.709666) (xy 341.420438 -293.66807) (xy 341.401147 -293.622794)
			(xy 341.38937 -293.57501) (xy 341.38541 -293.525956) (xy 341.056468 -293.525956) (xy 341.055973 -293.550563)
			(xy 341.048078 -293.59914) (xy 341.032494 -293.645821) (xy 341.009623 -293.689398) (xy 340.980058 -293.728742)
			(xy 340.944565 -293.762834) (xy 340.904062 -293.79079) (xy 340.8596 -293.811888) (xy 340.812329 -293.82558)
			(xy 340.763474 -293.831512) (xy 340.714299 -293.829531) (xy 340.66608 -293.819687) (xy 340.620064 -293.802235)
			(xy 340.577443 -293.777628) (xy 340.539322 -293.746503) (xy 340.506687 -293.709666) (xy 340.480384 -293.66807)
			(xy 340.461093 -293.622794) (xy 340.449316 -293.57501) (xy 340.445356 -293.525956) (xy 340.116414 -293.525956)
			(xy 340.115919 -293.550563) (xy 340.108024 -293.59914) (xy 340.09244 -293.645821) (xy 340.069569 -293.689398)
			(xy 340.040004 -293.728742) (xy 340.004511 -293.762834) (xy 339.964008 -293.79079) (xy 339.919546 -293.811888)
			(xy 339.872275 -293.82558) (xy 339.82342 -293.831512) (xy 339.774245 -293.829531) (xy 339.726026 -293.819687)
			(xy 339.68001 -293.802235) (xy 339.637389 -293.777628) (xy 339.599268 -293.746503) (xy 339.566633 -293.709666)
			(xy 339.54033 -293.66807) (xy 339.521039 -293.622794) (xy 339.509262 -293.57501) (xy 339.505302 -293.525956)
			(xy 339.186774 -293.525956) (xy 339.186262 -293.551402) (xy 339.178098 -293.601636) (xy 339.161982 -293.64991)
			(xy 339.138331 -293.694973) (xy 339.107758 -293.735659) (xy 339.071054 -293.770914) (xy 339.02917 -293.799824)
			(xy 338.983191 -293.821641) (xy 338.934307 -293.835801) (xy 338.883786 -293.841935) (xy 338.832934 -293.839886)
			(xy 338.78307 -293.829706) (xy 338.735484 -293.811659) (xy 338.69141 -293.786213) (xy 338.651988 -293.754026)
			(xy 338.61824 -293.715932) (xy 338.591039 -293.672918) (xy 338.571091 -293.626098) (xy 338.558912 -293.576684)
			(xy 338.554817 -293.525956) (xy 338.236306 -293.525956) (xy 338.235811 -293.550563) (xy 338.227916 -293.59914)
			(xy 338.212332 -293.645821) (xy 338.189461 -293.689398) (xy 338.159896 -293.728742) (xy 338.124403 -293.762834)
			(xy 338.0839 -293.79079) (xy 338.039438 -293.811888) (xy 337.992167 -293.82558) (xy 337.943312 -293.831512)
			(xy 337.894137 -293.829531) (xy 337.845918 -293.819687) (xy 337.799902 -293.802235) (xy 337.757281 -293.777628)
			(xy 337.71916 -293.746503) (xy 337.686525 -293.709666) (xy 337.660222 -293.66807) (xy 337.640931 -293.622794)
			(xy 337.629154 -293.57501) (xy 337.625194 -293.525956) (xy 337.296506 -293.525956) (xy 337.296011 -293.550563)
			(xy 337.288116 -293.59914) (xy 337.272532 -293.645821) (xy 337.249661 -293.689398) (xy 337.220096 -293.728742)
			(xy 337.184603 -293.762834) (xy 337.1441 -293.79079) (xy 337.099638 -293.811888) (xy 337.052367 -293.82558)
			(xy 337.003512 -293.831512) (xy 336.954337 -293.829531) (xy 336.906118 -293.819687) (xy 336.860102 -293.802235)
			(xy 336.817481 -293.777628) (xy 336.77936 -293.746503) (xy 336.746725 -293.709666) (xy 336.720422 -293.66807)
			(xy 336.701131 -293.622794) (xy 336.689354 -293.57501) (xy 336.685394 -293.525956) (xy 336.356452 -293.525956)
			(xy 336.355957 -293.550563) (xy 336.348062 -293.59914) (xy 336.332478 -293.645821) (xy 336.309607 -293.689398)
			(xy 336.280042 -293.728742) (xy 336.244549 -293.762834) (xy 336.204046 -293.79079) (xy 336.159584 -293.811888)
			(xy 336.112313 -293.82558) (xy 336.063458 -293.831512) (xy 336.014283 -293.829531) (xy 335.966064 -293.819687)
			(xy 335.920048 -293.802235) (xy 335.877427 -293.777628) (xy 335.839306 -293.746503) (xy 335.806671 -293.709666)
			(xy 335.780368 -293.66807) (xy 335.761077 -293.622794) (xy 335.7493 -293.57501) (xy 335.74534 -293.525956)
			(xy 335.416398 -293.525956) (xy 335.415903 -293.550563) (xy 335.408008 -293.59914) (xy 335.392424 -293.645821)
			(xy 335.369553 -293.689398) (xy 335.339988 -293.728742) (xy 335.304495 -293.762834) (xy 335.263992 -293.79079)
			(xy 335.21953 -293.811888) (xy 335.172259 -293.82558) (xy 335.123404 -293.831512) (xy 335.074229 -293.829531)
			(xy 335.02601 -293.819687) (xy 334.979994 -293.802235) (xy 334.937373 -293.777628) (xy 334.899252 -293.746503)
			(xy 334.866617 -293.709666) (xy 334.840314 -293.66807) (xy 334.821023 -293.622794) (xy 334.809246 -293.57501)
			(xy 334.805286 -293.525956) (xy 334.476344 -293.525956) (xy 334.476344 -293.531036) (xy 334.47609 -293.537386)
			(xy 334.474764 -293.560953) (xy 334.465756 -293.607286) (xy 334.449729 -293.651683) (xy 334.427065 -293.693086)
			(xy 334.398302 -293.730511) (xy 334.364126 -293.763066) (xy 334.325349 -293.789978) (xy 334.282895 -293.810606)
			(xy 334.237773 -293.824459) (xy 334.21447 -293.828216) (xy 334.201516 -293.829994) (xy 334.171036 -293.831518)
			(xy 334.147463 -293.831085) (xy 334.100876 -293.823852) (xy 334.055951 -293.809554) (xy 334.013754 -293.788528)
			(xy 333.975284 -293.761274) (xy 333.941455 -293.728437) (xy 333.913068 -293.690796) (xy 333.901542 -293.670228)
			(xy 333.89824 -293.664132) (xy 333.89443 -293.660068) (xy 333.88427 -293.651432) (xy 333.87665 -293.646606)
			(xy 333.858616 -293.63543) (xy 333.8576 -293.634668) (xy 333.840582 -293.631112) (xy 333.830422 -293.632636)
			(xy 333.78191 -293.63881) (xy 333.684168 -293.642118) (xy 333.63535 -293.63924) (xy 333.61514 -293.637731)
			(xy 333.574866 -293.633158) (xy 333.554832 -293.630096) (xy 333.551784 -293.629588) (xy 333.536036 -293.639748)
			(xy 333.535528 -293.639748) (xy 333.51851 -293.65067) (xy 333.508096 -293.659306) (xy 333.505048 -293.662608)
			(xy 333.501746 -293.667688) (xy 333.500476 -293.669974) (xy 333.488048 -293.692082) (xy 333.457023 -293.732198)
			(xy 333.419802 -293.766643) (xy 333.398876 -293.780972) (xy 333.379744 -293.793053) (xy 333.338678 -293.812048)
			(xy 333.317088 -293.818818) (xy 333.310992 -293.820596) (xy 333.305658 -293.823644) (xy 333.295752 -293.831518)
			(xy 333.024226 -294.103044) (xy 333.023464 -294.103806) (xy 333.022448 -294.10533) (xy 333.016889 -294.111969)
			(xy 333.010251 -294.127947) (xy 333.009494 -294.136572) (xy 333.009341 -294.140943) (xy 333.010359 -294.149629)
			(xy 333.011526 -294.153844) (xy 333.015844 -294.16756) (xy 333.0194 -294.173148) (xy 333.034115 -294.197729)
			(xy 333.055082 -294.251039) (xy 333.065755 -294.30732) (xy 333.06639 -294.335962) (xy 333.395332 -294.335962)
			(xy 333.399292 -294.286908) (xy 333.411069 -294.239124) (xy 333.43036 -294.193848) (xy 333.456663 -294.152252)
			(xy 333.489298 -294.115415) (xy 333.527419 -294.08429) (xy 333.57004 -294.059683) (xy 333.616056 -294.042231)
			(xy 333.664275 -294.032387) (xy 333.71345 -294.030406) (xy 333.762305 -294.036338) (xy 333.809576 -294.05003)
			(xy 333.854038 -294.071128) (xy 333.894541 -294.099084) (xy 333.930034 -294.133176) (xy 333.959599 -294.17252)
			(xy 333.98247 -294.216097) (xy 333.998054 -294.262778) (xy 334.005949 -294.311355) (xy 334.006444 -294.335962)
			(xy 334.335386 -294.335962) (xy 334.339346 -294.286908) (xy 334.351123 -294.239124) (xy 334.370414 -294.193848)
			(xy 334.396717 -294.152252) (xy 334.429352 -294.115415) (xy 334.467473 -294.08429) (xy 334.510094 -294.059683)
			(xy 334.55611 -294.042231) (xy 334.604329 -294.032387) (xy 334.653504 -294.030406) (xy 334.702359 -294.036338)
			(xy 334.74963 -294.05003) (xy 334.794092 -294.071128) (xy 334.834595 -294.099084) (xy 334.870088 -294.133176)
			(xy 334.899653 -294.17252) (xy 334.922524 -294.216097) (xy 334.938108 -294.262778) (xy 334.946003 -294.311355)
			(xy 334.946498 -294.335962) (xy 336.21524 -294.335962) (xy 336.2192 -294.286908) (xy 336.230977 -294.239124)
			(xy 336.250268 -294.193848) (xy 336.276571 -294.152252) (xy 336.309206 -294.115415) (xy 336.347327 -294.08429)
			(xy 336.389948 -294.059683) (xy 336.435964 -294.042231) (xy 336.484183 -294.032387) (xy 336.533358 -294.030406)
			(xy 336.582213 -294.036338) (xy 336.629484 -294.05003) (xy 336.673946 -294.071128) (xy 336.714449 -294.099084)
			(xy 336.749942 -294.133176) (xy 336.779507 -294.17252) (xy 336.802378 -294.216097) (xy 336.817962 -294.262778)
			(xy 336.825857 -294.311355) (xy 336.826352 -294.335962) (xy 337.155294 -294.335962) (xy 337.159254 -294.286908)
			(xy 337.171031 -294.239124) (xy 337.190322 -294.193848) (xy 337.216625 -294.152252) (xy 337.24926 -294.115415)
			(xy 337.287381 -294.08429) (xy 337.330002 -294.059683) (xy 337.376018 -294.042231) (xy 337.424237 -294.032387)
			(xy 337.473412 -294.030406) (xy 337.522267 -294.036338) (xy 337.569538 -294.05003) (xy 337.614 -294.071128)
			(xy 337.654503 -294.099084) (xy 337.689996 -294.133176) (xy 337.719561 -294.17252) (xy 337.742432 -294.216097)
			(xy 337.758016 -294.262778) (xy 337.765911 -294.311355) (xy 337.766406 -294.335962) (xy 338.095348 -294.335962)
			(xy 338.099308 -294.286908) (xy 338.111085 -294.239124) (xy 338.130376 -294.193848) (xy 338.156679 -294.152252)
			(xy 338.189314 -294.115415) (xy 338.227435 -294.08429) (xy 338.270056 -294.059683) (xy 338.316072 -294.042231)
			(xy 338.364291 -294.032387) (xy 338.413466 -294.030406) (xy 338.462321 -294.036338) (xy 338.509592 -294.05003)
			(xy 338.554054 -294.071128) (xy 338.594557 -294.099084) (xy 338.63005 -294.133176) (xy 338.659615 -294.17252)
			(xy 338.682486 -294.216097) (xy 338.69807 -294.262778) (xy 338.705965 -294.311355) (xy 338.70646 -294.335962)
			(xy 339.035402 -294.335962) (xy 339.039362 -294.286908) (xy 339.051139 -294.239124) (xy 339.07043 -294.193848)
			(xy 339.096733 -294.152252) (xy 339.129368 -294.115415) (xy 339.167489 -294.08429) (xy 339.21011 -294.059683)
			(xy 339.256126 -294.042231) (xy 339.304345 -294.032387) (xy 339.35352 -294.030406) (xy 339.402375 -294.036338)
			(xy 339.449646 -294.05003) (xy 339.494108 -294.071128) (xy 339.534611 -294.099084) (xy 339.570104 -294.133176)
			(xy 339.599669 -294.17252) (xy 339.62254 -294.216097) (xy 339.638124 -294.262778) (xy 339.646019 -294.311355)
			(xy 339.646514 -294.335962) (xy 339.975202 -294.335962) (xy 339.979162 -294.286908) (xy 339.990939 -294.239124)
			(xy 340.01023 -294.193848) (xy 340.036533 -294.152252) (xy 340.069168 -294.115415) (xy 340.107289 -294.08429)
			(xy 340.14991 -294.059683) (xy 340.195926 -294.042231) (xy 340.244145 -294.032387) (xy 340.29332 -294.030406)
			(xy 340.342175 -294.036338) (xy 340.389446 -294.05003) (xy 340.433908 -294.071128) (xy 340.474411 -294.099084)
			(xy 340.509904 -294.133176) (xy 340.539469 -294.17252) (xy 340.56234 -294.216097) (xy 340.577924 -294.262778)
			(xy 340.585819 -294.311355) (xy 340.586314 -294.335962) (xy 340.915256 -294.335962) (xy 340.919216 -294.286908)
			(xy 340.930993 -294.239124) (xy 340.950284 -294.193848) (xy 340.976587 -294.152252) (xy 341.009222 -294.115415)
			(xy 341.047343 -294.08429) (xy 341.089964 -294.059683) (xy 341.13598 -294.042231) (xy 341.184199 -294.032387)
			(xy 341.233374 -294.030406) (xy 341.282229 -294.036338) (xy 341.3295 -294.05003) (xy 341.373962 -294.071128)
			(xy 341.414465 -294.099084) (xy 341.449958 -294.133176) (xy 341.479523 -294.17252) (xy 341.502394 -294.216097)
			(xy 341.517978 -294.262778) (xy 341.525873 -294.311355) (xy 341.526368 -294.335962) (xy 341.85531 -294.335962)
			(xy 341.85927 -294.286908) (xy 341.871047 -294.239124) (xy 341.890338 -294.193848) (xy 341.916641 -294.152252)
			(xy 341.949276 -294.115415) (xy 341.987397 -294.08429) (xy 342.030018 -294.059683) (xy 342.076034 -294.042231)
			(xy 342.124253 -294.032387) (xy 342.173428 -294.030406) (xy 342.222283 -294.036338) (xy 342.269554 -294.05003)
			(xy 342.314016 -294.071128) (xy 342.354519 -294.099084) (xy 342.390012 -294.133176) (xy 342.419577 -294.17252)
			(xy 342.442448 -294.216097) (xy 342.458032 -294.262778) (xy 342.465927 -294.311355) (xy 342.466422 -294.335962)
			(xy 342.465927 -294.360569) (xy 342.458032 -294.409146) (xy 342.442448 -294.455827) (xy 342.419577 -294.499404)
			(xy 342.390012 -294.538748) (xy 342.354519 -294.57284) (xy 342.314016 -294.600796) (xy 342.269554 -294.621894)
			(xy 342.222283 -294.635586) (xy 342.173428 -294.641518) (xy 342.124253 -294.639537) (xy 342.076034 -294.629693)
			(xy 342.030018 -294.612241) (xy 341.987397 -294.587634) (xy 341.949276 -294.556509) (xy 341.916641 -294.519672)
			(xy 341.890338 -294.478076) (xy 341.871047 -294.4328) (xy 341.85927 -294.385016) (xy 341.85531 -294.335962)
			(xy 341.526368 -294.335962) (xy 341.525873 -294.360569) (xy 341.517978 -294.409146) (xy 341.502394 -294.455827)
			(xy 341.479523 -294.499404) (xy 341.449958 -294.538748) (xy 341.414465 -294.57284) (xy 341.373962 -294.600796)
			(xy 341.3295 -294.621894) (xy 341.282229 -294.635586) (xy 341.233374 -294.641518) (xy 341.184199 -294.639537)
			(xy 341.13598 -294.629693) (xy 341.089964 -294.612241) (xy 341.047343 -294.587634) (xy 341.009222 -294.556509)
			(xy 340.976587 -294.519672) (xy 340.950284 -294.478076) (xy 340.930993 -294.4328) (xy 340.919216 -294.385016)
			(xy 340.915256 -294.335962) (xy 340.586314 -294.335962) (xy 340.585819 -294.360569) (xy 340.577924 -294.409146)
			(xy 340.56234 -294.455827) (xy 340.539469 -294.499404) (xy 340.509904 -294.538748) (xy 340.474411 -294.57284)
			(xy 340.433908 -294.600796) (xy 340.389446 -294.621894) (xy 340.342175 -294.635586) (xy 340.29332 -294.641518)
			(xy 340.244145 -294.639537) (xy 340.195926 -294.629693) (xy 340.14991 -294.612241) (xy 340.107289 -294.587634)
			(xy 340.069168 -294.556509) (xy 340.036533 -294.519672) (xy 340.01023 -294.478076) (xy 339.990939 -294.4328)
			(xy 339.979162 -294.385016) (xy 339.975202 -294.335962) (xy 339.646514 -294.335962) (xy 339.646019 -294.360569)
			(xy 339.638124 -294.409146) (xy 339.62254 -294.455827) (xy 339.599669 -294.499404) (xy 339.570104 -294.538748)
			(xy 339.534611 -294.57284) (xy 339.494108 -294.600796) (xy 339.449646 -294.621894) (xy 339.402375 -294.635586)
			(xy 339.35352 -294.641518) (xy 339.304345 -294.639537) (xy 339.256126 -294.629693) (xy 339.21011 -294.612241)
			(xy 339.167489 -294.587634) (xy 339.129368 -294.556509) (xy 339.096733 -294.519672) (xy 339.07043 -294.478076)
			(xy 339.051139 -294.4328) (xy 339.039362 -294.385016) (xy 339.035402 -294.335962) (xy 338.70646 -294.335962)
			(xy 338.705965 -294.360569) (xy 338.69807 -294.409146) (xy 338.682486 -294.455827) (xy 338.659615 -294.499404)
			(xy 338.63005 -294.538748) (xy 338.594557 -294.57284) (xy 338.554054 -294.600796) (xy 338.509592 -294.621894)
			(xy 338.462321 -294.635586) (xy 338.413466 -294.641518) (xy 338.364291 -294.639537) (xy 338.316072 -294.629693)
			(xy 338.270056 -294.612241) (xy 338.227435 -294.587634) (xy 338.189314 -294.556509) (xy 338.156679 -294.519672)
			(xy 338.130376 -294.478076) (xy 338.111085 -294.4328) (xy 338.099308 -294.385016) (xy 338.095348 -294.335962)
			(xy 337.766406 -294.335962) (xy 337.765911 -294.360569) (xy 337.758016 -294.409146) (xy 337.742432 -294.455827)
			(xy 337.719561 -294.499404) (xy 337.689996 -294.538748) (xy 337.654503 -294.57284) (xy 337.614 -294.600796)
			(xy 337.569538 -294.621894) (xy 337.522267 -294.635586) (xy 337.473412 -294.641518) (xy 337.424237 -294.639537)
			(xy 337.376018 -294.629693) (xy 337.330002 -294.612241) (xy 337.287381 -294.587634) (xy 337.24926 -294.556509)
			(xy 337.216625 -294.519672) (xy 337.190322 -294.478076) (xy 337.171031 -294.4328) (xy 337.159254 -294.385016)
			(xy 337.155294 -294.335962) (xy 336.826352 -294.335962) (xy 336.825857 -294.360569) (xy 336.817962 -294.409146)
			(xy 336.802378 -294.455827) (xy 336.779507 -294.499404) (xy 336.749942 -294.538748) (xy 336.714449 -294.57284)
			(xy 336.673946 -294.600796) (xy 336.629484 -294.621894) (xy 336.582213 -294.635586) (xy 336.533358 -294.641518)
			(xy 336.484183 -294.639537) (xy 336.435964 -294.629693) (xy 336.389948 -294.612241) (xy 336.347327 -294.587634)
			(xy 336.309206 -294.556509) (xy 336.276571 -294.519672) (xy 336.250268 -294.478076) (xy 336.230977 -294.4328)
			(xy 336.2192 -294.385016) (xy 336.21524 -294.335962) (xy 334.946498 -294.335962) (xy 334.946003 -294.360569)
			(xy 334.938108 -294.409146) (xy 334.922524 -294.455827) (xy 334.899653 -294.499404) (xy 334.870088 -294.538748)
			(xy 334.834595 -294.57284) (xy 334.794092 -294.600796) (xy 334.74963 -294.621894) (xy 334.702359 -294.635586)
			(xy 334.653504 -294.641518) (xy 334.604329 -294.639537) (xy 334.55611 -294.629693) (xy 334.510094 -294.612241)
			(xy 334.467473 -294.587634) (xy 334.429352 -294.556509) (xy 334.396717 -294.519672) (xy 334.370414 -294.478076)
			(xy 334.351123 -294.4328) (xy 334.339346 -294.385016) (xy 334.335386 -294.335962) (xy 334.006444 -294.335962)
			(xy 334.005949 -294.360569) (xy 333.998054 -294.409146) (xy 333.98247 -294.455827) (xy 333.959599 -294.499404)
			(xy 333.930034 -294.538748) (xy 333.894541 -294.57284) (xy 333.854038 -294.600796) (xy 333.809576 -294.621894)
			(xy 333.762305 -294.635586) (xy 333.71345 -294.641518) (xy 333.664275 -294.639537) (xy 333.616056 -294.629693)
			(xy 333.57004 -294.612241) (xy 333.527419 -294.587634) (xy 333.489298 -294.556509) (xy 333.456663 -294.519672)
			(xy 333.43036 -294.478076) (xy 333.411069 -294.4328) (xy 333.399292 -294.385016) (xy 333.395332 -294.335962)
			(xy 333.06639 -294.335962) (xy 333.065947 -294.359957) (xy 333.058445 -294.407356) (xy 333.043619 -294.452997)
			(xy 333.021835 -294.495757) (xy 332.99363 -294.534583) (xy 332.959698 -294.568517) (xy 332.920874 -294.596725)
			(xy 332.878116 -294.618511) (xy 332.832475 -294.63334) (xy 332.785077 -294.640845) (xy 332.761082 -294.64127)
			(xy 332.750414 -294.64127) (xy 332.722588 -294.639676) (xy 332.668169 -294.627666) (xy 332.61682 -294.606008)
			(xy 332.593188 -294.591232) (xy 332.592934 -294.590978) (xy 332.585525 -294.58657) (xy 332.568772 -294.58255)
			(xy 332.560168 -294.583104) (xy 332.551532 -294.583866) (xy 332.536038 -294.591232) (xy 332.410308 -294.716962)
			(xy 332.402394 -294.725809) (xy 332.394971 -294.748325) (xy 332.396084 -294.760142) (xy 332.398878 -294.77843)
			(xy 332.408276 -294.841422) (xy 332.410308 -294.848534) (xy 332.413292 -294.855836) (xy 332.422992 -294.868261)
			(xy 332.429358 -294.872918) (xy 332.435962 -294.876982) (xy 332.456449 -294.888516) (xy 332.493926 -294.916901)
			(xy 332.526613 -294.950691) (xy 332.553737 -294.989091) (xy 332.574658 -295.031192) (xy 332.588883 -295.076002)
			(xy 332.596074 -295.122461) (xy 332.59649 -295.145968) (xy 332.925178 -295.145968) (xy 332.929138 -295.096914)
			(xy 332.940915 -295.04913) (xy 332.960206 -295.003854) (xy 332.986509 -294.962258) (xy 333.019144 -294.925421)
			(xy 333.057265 -294.894296) (xy 333.099886 -294.869689) (xy 333.145902 -294.852237) (xy 333.194121 -294.842393)
			(xy 333.243296 -294.840412) (xy 333.292151 -294.846344) (xy 333.339422 -294.860036) (xy 333.383884 -294.881134)
			(xy 333.424387 -294.90909) (xy 333.45988 -294.943182) (xy 333.489445 -294.982526) (xy 333.512316 -295.026103)
			(xy 333.5279 -295.072784) (xy 333.535795 -295.121361) (xy 333.53629 -295.145968) (xy 333.865232 -295.145968)
			(xy 333.869192 -295.096914) (xy 333.880969 -295.04913) (xy 333.90026 -295.003854) (xy 333.926563 -294.962258)
			(xy 333.959198 -294.925421) (xy 333.997319 -294.894296) (xy 334.03994 -294.869689) (xy 334.085956 -294.852237)
			(xy 334.134175 -294.842393) (xy 334.18335 -294.840412) (xy 334.232205 -294.846344) (xy 334.279476 -294.860036)
			(xy 334.323938 -294.881134) (xy 334.364441 -294.90909) (xy 334.399934 -294.943182) (xy 334.429499 -294.982526)
			(xy 334.45237 -295.026103) (xy 334.467954 -295.072784) (xy 334.475849 -295.121361) (xy 334.476344 -295.145968)
			(xy 334.805286 -295.145968) (xy 334.809246 -295.096914) (xy 334.821023 -295.04913) (xy 334.840314 -295.003854)
			(xy 334.866617 -294.962258) (xy 334.899252 -294.925421) (xy 334.937373 -294.894296) (xy 334.979994 -294.869689)
			(xy 335.02601 -294.852237) (xy 335.074229 -294.842393) (xy 335.123404 -294.840412) (xy 335.172259 -294.846344)
			(xy 335.21953 -294.860036) (xy 335.263992 -294.881134) (xy 335.304495 -294.90909) (xy 335.339988 -294.943182)
			(xy 335.369553 -294.982526) (xy 335.392424 -295.026103) (xy 335.408008 -295.072784) (xy 335.415903 -295.121361)
			(xy 335.416398 -295.145968) (xy 335.74534 -295.145968) (xy 335.7493 -295.096914) (xy 335.761077 -295.04913)
			(xy 335.780368 -295.003854) (xy 335.806671 -294.962258) (xy 335.839306 -294.925421) (xy 335.877427 -294.894296)
			(xy 335.920048 -294.869689) (xy 335.966064 -294.852237) (xy 336.014283 -294.842393) (xy 336.063458 -294.840412)
			(xy 336.112313 -294.846344) (xy 336.159584 -294.860036) (xy 336.204046 -294.881134) (xy 336.244549 -294.90909)
			(xy 336.280042 -294.943182) (xy 336.309607 -294.982526) (xy 336.332478 -295.026103) (xy 336.348062 -295.072784)
			(xy 336.355957 -295.121361) (xy 336.356452 -295.145968) (xy 337.625194 -295.145968) (xy 337.629154 -295.096914)
			(xy 337.640931 -295.04913) (xy 337.660222 -295.003854) (xy 337.686525 -294.962258) (xy 337.71916 -294.925421)
			(xy 337.757281 -294.894296) (xy 337.799902 -294.869689) (xy 337.845918 -294.852237) (xy 337.894137 -294.842393)
			(xy 337.943312 -294.840412) (xy 337.992167 -294.846344) (xy 338.039438 -294.860036) (xy 338.0839 -294.881134)
			(xy 338.124403 -294.90909) (xy 338.159896 -294.943182) (xy 338.189461 -294.982526) (xy 338.212332 -295.026103)
			(xy 338.227916 -295.072784) (xy 338.235811 -295.121361) (xy 338.236306 -295.145968) (xy 338.565248 -295.145968)
			(xy 338.569208 -295.096914) (xy 338.580985 -295.04913) (xy 338.600276 -295.003854) (xy 338.626579 -294.962258)
			(xy 338.659214 -294.925421) (xy 338.697335 -294.894296) (xy 338.739956 -294.869689) (xy 338.785972 -294.852237)
			(xy 338.834191 -294.842393) (xy 338.883366 -294.840412) (xy 338.932221 -294.846344) (xy 338.979492 -294.860036)
			(xy 339.023954 -294.881134) (xy 339.064457 -294.90909) (xy 339.09995 -294.943182) (xy 339.129515 -294.982526)
			(xy 339.152386 -295.026103) (xy 339.16797 -295.072784) (xy 339.175865 -295.121361) (xy 339.17636 -295.145968)
			(xy 339.505302 -295.145968) (xy 339.509262 -295.096914) (xy 339.521039 -295.04913) (xy 339.54033 -295.003854)
			(xy 339.566633 -294.962258) (xy 339.599268 -294.925421) (xy 339.637389 -294.894296) (xy 339.68001 -294.869689)
			(xy 339.726026 -294.852237) (xy 339.774245 -294.842393) (xy 339.82342 -294.840412) (xy 339.872275 -294.846344)
			(xy 339.919546 -294.860036) (xy 339.964008 -294.881134) (xy 340.004511 -294.90909) (xy 340.040004 -294.943182)
			(xy 340.069569 -294.982526) (xy 340.09244 -295.026103) (xy 340.108024 -295.072784) (xy 340.115919 -295.121361)
			(xy 340.116414 -295.145968) (xy 340.445356 -295.145968) (xy 340.449316 -295.096914) (xy 340.461093 -295.04913)
			(xy 340.480384 -295.003854) (xy 340.506687 -294.962258) (xy 340.539322 -294.925421) (xy 340.577443 -294.894296)
			(xy 340.620064 -294.869689) (xy 340.66608 -294.852237) (xy 340.714299 -294.842393) (xy 340.763474 -294.840412)
			(xy 340.812329 -294.846344) (xy 340.8596 -294.860036) (xy 340.904062 -294.881134) (xy 340.944565 -294.90909)
			(xy 340.980058 -294.943182) (xy 341.009623 -294.982526) (xy 341.032494 -295.026103) (xy 341.048078 -295.072784)
			(xy 341.055973 -295.121361) (xy 341.056468 -295.145968) (xy 341.38541 -295.145968) (xy 341.38937 -295.096914)
			(xy 341.401147 -295.04913) (xy 341.420438 -295.003854) (xy 341.446741 -294.962258) (xy 341.479376 -294.925421)
			(xy 341.517497 -294.894296) (xy 341.560118 -294.869689) (xy 341.606134 -294.852237) (xy 341.654353 -294.842393)
			(xy 341.703528 -294.840412) (xy 341.752383 -294.846344) (xy 341.799654 -294.860036) (xy 341.844116 -294.881134)
			(xy 341.884619 -294.90909) (xy 341.920112 -294.943182) (xy 341.949677 -294.982526) (xy 341.972548 -295.026103)
			(xy 341.988132 -295.072784) (xy 341.996027 -295.121361) (xy 341.996522 -295.145968) (xy 342.32521 -295.145968)
			(xy 342.32917 -295.096914) (xy 342.340947 -295.04913) (xy 342.360238 -295.003854) (xy 342.386541 -294.962258)
			(xy 342.419176 -294.925421) (xy 342.457297 -294.894296) (xy 342.499918 -294.869689) (xy 342.545934 -294.852237)
			(xy 342.594153 -294.842393) (xy 342.643328 -294.840412) (xy 342.692183 -294.846344) (xy 342.739454 -294.860036)
			(xy 342.783916 -294.881134) (xy 342.824419 -294.90909) (xy 342.859912 -294.943182) (xy 342.889477 -294.982526)
			(xy 342.912348 -295.026103) (xy 342.927932 -295.072784) (xy 342.935827 -295.121361) (xy 342.936322 -295.145968)
			(xy 342.935827 -295.170575) (xy 342.927932 -295.219152) (xy 342.912348 -295.265833) (xy 342.889477 -295.30941)
			(xy 342.859912 -295.348754) (xy 342.824419 -295.382846) (xy 342.783916 -295.410802) (xy 342.739454 -295.4319)
			(xy 342.692183 -295.445592) (xy 342.643328 -295.451524) (xy 342.594153 -295.449543) (xy 342.545934 -295.439699)
			(xy 342.499918 -295.422247) (xy 342.457297 -295.39764) (xy 342.419176 -295.366515) (xy 342.386541 -295.329678)
			(xy 342.360238 -295.288082) (xy 342.340947 -295.242806) (xy 342.32917 -295.195022) (xy 342.32521 -295.145968)
			(xy 341.996522 -295.145968) (xy 341.996027 -295.170575) (xy 341.988132 -295.219152) (xy 341.972548 -295.265833)
			(xy 341.949677 -295.30941) (xy 341.920112 -295.348754) (xy 341.884619 -295.382846) (xy 341.844116 -295.410802)
			(xy 341.799654 -295.4319) (xy 341.752383 -295.445592) (xy 341.703528 -295.451524) (xy 341.654353 -295.449543)
			(xy 341.606134 -295.439699) (xy 341.560118 -295.422247) (xy 341.517497 -295.39764) (xy 341.479376 -295.366515)
			(xy 341.446741 -295.329678) (xy 341.420438 -295.288082) (xy 341.401147 -295.242806) (xy 341.38937 -295.195022)
			(xy 341.38541 -295.145968) (xy 341.056468 -295.145968) (xy 341.055973 -295.170575) (xy 341.048078 -295.219152)
			(xy 341.032494 -295.265833) (xy 341.009623 -295.30941) (xy 340.980058 -295.348754) (xy 340.944565 -295.382846)
			(xy 340.904062 -295.410802) (xy 340.8596 -295.4319) (xy 340.812329 -295.445592) (xy 340.763474 -295.451524)
			(xy 340.714299 -295.449543) (xy 340.66608 -295.439699) (xy 340.620064 -295.422247) (xy 340.577443 -295.39764)
			(xy 340.539322 -295.366515) (xy 340.506687 -295.329678) (xy 340.480384 -295.288082) (xy 340.461093 -295.242806)
			(xy 340.449316 -295.195022) (xy 340.445356 -295.145968) (xy 340.116414 -295.145968) (xy 340.115919 -295.170575)
			(xy 340.108024 -295.219152) (xy 340.09244 -295.265833) (xy 340.069569 -295.30941) (xy 340.040004 -295.348754)
			(xy 340.004511 -295.382846) (xy 339.964008 -295.410802) (xy 339.919546 -295.4319) (xy 339.872275 -295.445592)
			(xy 339.82342 -295.451524) (xy 339.774245 -295.449543) (xy 339.726026 -295.439699) (xy 339.68001 -295.422247)
			(xy 339.637389 -295.39764) (xy 339.599268 -295.366515) (xy 339.566633 -295.329678) (xy 339.54033 -295.288082)
			(xy 339.521039 -295.242806) (xy 339.509262 -295.195022) (xy 339.505302 -295.145968) (xy 339.17636 -295.145968)
			(xy 339.175865 -295.170575) (xy 339.16797 -295.219152) (xy 339.152386 -295.265833) (xy 339.129515 -295.30941)
			(xy 339.09995 -295.348754) (xy 339.064457 -295.382846) (xy 339.023954 -295.410802) (xy 338.979492 -295.4319)
			(xy 338.932221 -295.445592) (xy 338.883366 -295.451524) (xy 338.834191 -295.449543) (xy 338.785972 -295.439699)
			(xy 338.739956 -295.422247) (xy 338.697335 -295.39764) (xy 338.659214 -295.366515) (xy 338.626579 -295.329678)
			(xy 338.600276 -295.288082) (xy 338.580985 -295.242806) (xy 338.569208 -295.195022) (xy 338.565248 -295.145968)
			(xy 338.236306 -295.145968) (xy 338.235811 -295.170575) (xy 338.227916 -295.219152) (xy 338.212332 -295.265833)
			(xy 338.189461 -295.30941) (xy 338.159896 -295.348754) (xy 338.124403 -295.382846) (xy 338.0839 -295.410802)
			(xy 338.039438 -295.4319) (xy 337.992167 -295.445592) (xy 337.943312 -295.451524) (xy 337.894137 -295.449543)
			(xy 337.845918 -295.439699) (xy 337.799902 -295.422247) (xy 337.757281 -295.39764) (xy 337.71916 -295.366515)
			(xy 337.686525 -295.329678) (xy 337.660222 -295.288082) (xy 337.640931 -295.242806) (xy 337.629154 -295.195022)
			(xy 337.625194 -295.145968) (xy 336.356452 -295.145968) (xy 336.355957 -295.170575) (xy 336.348062 -295.219152)
			(xy 336.332478 -295.265833) (xy 336.309607 -295.30941) (xy 336.280042 -295.348754) (xy 336.244549 -295.382846)
			(xy 336.204046 -295.410802) (xy 336.159584 -295.4319) (xy 336.112313 -295.445592) (xy 336.063458 -295.451524)
			(xy 336.014283 -295.449543) (xy 335.966064 -295.439699) (xy 335.920048 -295.422247) (xy 335.877427 -295.39764)
			(xy 335.839306 -295.366515) (xy 335.806671 -295.329678) (xy 335.780368 -295.288082) (xy 335.761077 -295.242806)
			(xy 335.7493 -295.195022) (xy 335.74534 -295.145968) (xy 335.416398 -295.145968) (xy 335.415903 -295.170575)
			(xy 335.408008 -295.219152) (xy 335.392424 -295.265833) (xy 335.369553 -295.30941) (xy 335.339988 -295.348754)
			(xy 335.304495 -295.382846) (xy 335.263992 -295.410802) (xy 335.21953 -295.4319) (xy 335.172259 -295.445592)
			(xy 335.123404 -295.451524) (xy 335.074229 -295.449543) (xy 335.02601 -295.439699) (xy 334.979994 -295.422247)
			(xy 334.937373 -295.39764) (xy 334.899252 -295.366515) (xy 334.866617 -295.329678) (xy 334.840314 -295.288082)
			(xy 334.821023 -295.242806) (xy 334.809246 -295.195022) (xy 334.805286 -295.145968) (xy 334.476344 -295.145968)
			(xy 334.475849 -295.170575) (xy 334.467954 -295.219152) (xy 334.45237 -295.265833) (xy 334.429499 -295.30941)
			(xy 334.399934 -295.348754) (xy 334.364441 -295.382846) (xy 334.323938 -295.410802) (xy 334.279476 -295.4319)
			(xy 334.232205 -295.445592) (xy 334.18335 -295.451524) (xy 334.134175 -295.449543) (xy 334.085956 -295.439699)
			(xy 334.03994 -295.422247) (xy 333.997319 -295.39764) (xy 333.959198 -295.366515) (xy 333.926563 -295.329678)
			(xy 333.90026 -295.288082) (xy 333.880969 -295.242806) (xy 333.869192 -295.195022) (xy 333.865232 -295.145968)
			(xy 333.53629 -295.145968) (xy 333.535795 -295.170575) (xy 333.5279 -295.219152) (xy 333.512316 -295.265833)
			(xy 333.489445 -295.30941) (xy 333.45988 -295.348754) (xy 333.424387 -295.382846) (xy 333.383884 -295.410802)
			(xy 333.339422 -295.4319) (xy 333.292151 -295.445592) (xy 333.243296 -295.451524) (xy 333.194121 -295.449543)
			(xy 333.145902 -295.439699) (xy 333.099886 -295.422247) (xy 333.057265 -295.39764) (xy 333.019144 -295.366515)
			(xy 332.986509 -295.329678) (xy 332.960206 -295.288082) (xy 332.940915 -295.242806) (xy 332.929138 -295.195022)
			(xy 332.925178 -295.145968) (xy 332.59649 -295.145968) (xy 332.596046 -295.169962) (xy 332.588543 -295.217361)
			(xy 332.573717 -295.263001) (xy 332.551933 -295.305761) (xy 332.523728 -295.344585) (xy 332.489796 -295.378519)
			(xy 332.450973 -295.406726) (xy 332.408214 -295.428512) (xy 332.362574 -295.44334) (xy 332.315176 -295.450845)
			(xy 332.291182 -295.451276) (xy 332.29042 -295.451276) (xy 332.267821 -295.450853) (xy 332.223121 -295.444158)
			(xy 332.179898 -295.430941) (xy 332.139099 -295.411492) (xy 332.101615 -295.386235) (xy 332.08468 -295.371266)
			(xy 332.065812 -295.353254) (xy 332.033886 -295.312006) (xy 332.02118 -295.289224) (xy 332.018386 -295.28389)
			(xy 332.010512 -295.275) (xy 332.005686 -295.271698) (xy 332.00073 -295.268393) (xy 331.989697 -295.263907)
			(xy 331.983842 -295.262808) (xy 331.980032 -295.2623) (xy 331.903578 -295.250616) (xy 331.892192 -295.249986)
			(xy 331.8707 -295.257516) (xy 331.862176 -295.265094) (xy 331.45476 -295.67251) (xy 331.444854 -295.67251)
			(xy 331.20076 -295.916604) (xy 331.19495 -295.923031) (xy 331.187692 -295.93875) (xy 331.186536 -295.947338)
			(xy 331.186536 -295.955974) (xy 331.515224 -295.955974) (xy 331.519184 -295.90692) (xy 331.530961 -295.859136)
			(xy 331.550252 -295.81386) (xy 331.576555 -295.772264) (xy 331.60919 -295.735427) (xy 331.647311 -295.704302)
			(xy 331.689932 -295.679695) (xy 331.735948 -295.662243) (xy 331.784167 -295.652399) (xy 331.833342 -295.650418)
			(xy 331.882197 -295.65635) (xy 331.929468 -295.670042) (xy 331.97393 -295.69114) (xy 332.014433 -295.719096)
			(xy 332.049926 -295.753188) (xy 332.079491 -295.792532) (xy 332.102362 -295.836109) (xy 332.117946 -295.88279)
			(xy 332.125841 -295.931367) (xy 332.126336 -295.955974) (xy 332.455278 -295.955974) (xy 332.459238 -295.90692)
			(xy 332.471015 -295.859136) (xy 332.490306 -295.81386) (xy 332.516609 -295.772264) (xy 332.549244 -295.735427)
			(xy 332.587365 -295.704302) (xy 332.629986 -295.679695) (xy 332.676002 -295.662243) (xy 332.724221 -295.652399)
			(xy 332.773396 -295.650418) (xy 332.822251 -295.65635) (xy 332.869522 -295.670042) (xy 332.913984 -295.69114)
			(xy 332.954487 -295.719096) (xy 332.98998 -295.753188) (xy 333.019545 -295.792532) (xy 333.042416 -295.836109)
			(xy 333.058 -295.88279) (xy 333.065895 -295.931367) (xy 333.06639 -295.955974) (xy 333.395332 -295.955974)
			(xy 333.399292 -295.90692) (xy 333.411069 -295.859136) (xy 333.43036 -295.81386) (xy 333.456663 -295.772264)
			(xy 333.489298 -295.735427) (xy 333.527419 -295.704302) (xy 333.57004 -295.679695) (xy 333.616056 -295.662243)
			(xy 333.664275 -295.652399) (xy 333.71345 -295.650418) (xy 333.762305 -295.65635) (xy 333.809576 -295.670042)
			(xy 333.854038 -295.69114) (xy 333.894541 -295.719096) (xy 333.930034 -295.753188) (xy 333.959599 -295.792532)
			(xy 333.98247 -295.836109) (xy 333.998054 -295.88279) (xy 334.005949 -295.931367) (xy 334.006444 -295.955974)
			(xy 334.335386 -295.955974) (xy 334.339346 -295.90692) (xy 334.351123 -295.859136) (xy 334.370414 -295.81386)
			(xy 334.396717 -295.772264) (xy 334.429352 -295.735427) (xy 334.467473 -295.704302) (xy 334.510094 -295.679695)
			(xy 334.55611 -295.662243) (xy 334.604329 -295.652399) (xy 334.653504 -295.650418) (xy 334.702359 -295.65635)
			(xy 334.74963 -295.670042) (xy 334.794092 -295.69114) (xy 334.834595 -295.719096) (xy 334.870088 -295.753188)
			(xy 334.899653 -295.792532) (xy 334.922524 -295.836109) (xy 334.938108 -295.88279) (xy 334.946003 -295.931367)
			(xy 334.946498 -295.955974) (xy 336.21524 -295.955974) (xy 336.2192 -295.90692) (xy 336.230977 -295.859136)
			(xy 336.250268 -295.81386) (xy 336.276571 -295.772264) (xy 336.309206 -295.735427) (xy 336.347327 -295.704302)
			(xy 336.389948 -295.679695) (xy 336.435964 -295.662243) (xy 336.484183 -295.652399) (xy 336.533358 -295.650418)
			(xy 336.582213 -295.65635) (xy 336.629484 -295.670042) (xy 336.673946 -295.69114) (xy 336.714449 -295.719096)
			(xy 336.749942 -295.753188) (xy 336.779507 -295.792532) (xy 336.802378 -295.836109) (xy 336.817962 -295.88279)
			(xy 336.825857 -295.931367) (xy 336.826352 -295.955974) (xy 338.095348 -295.955974) (xy 338.099308 -295.90692)
			(xy 338.111085 -295.859136) (xy 338.130376 -295.81386) (xy 338.156679 -295.772264) (xy 338.189314 -295.735427)
			(xy 338.227435 -295.704302) (xy 338.270056 -295.679695) (xy 338.316072 -295.662243) (xy 338.364291 -295.652399)
			(xy 338.413466 -295.650418) (xy 338.462321 -295.65635) (xy 338.509592 -295.670042) (xy 338.554054 -295.69114)
			(xy 338.594557 -295.719096) (xy 338.63005 -295.753188) (xy 338.659615 -295.792532) (xy 338.682486 -295.836109)
			(xy 338.69807 -295.88279) (xy 338.705965 -295.931367) (xy 338.70646 -295.955974) (xy 339.035402 -295.955974)
			(xy 339.039362 -295.90692) (xy 339.051139 -295.859136) (xy 339.07043 -295.81386) (xy 339.096733 -295.772264)
			(xy 339.129368 -295.735427) (xy 339.167489 -295.704302) (xy 339.21011 -295.679695) (xy 339.256126 -295.662243)
			(xy 339.304345 -295.652399) (xy 339.35352 -295.650418) (xy 339.402375 -295.65635) (xy 339.449646 -295.670042)
			(xy 339.494108 -295.69114) (xy 339.534611 -295.719096) (xy 339.570104 -295.753188) (xy 339.599669 -295.792532)
			(xy 339.62254 -295.836109) (xy 339.638124 -295.88279) (xy 339.646019 -295.931367) (xy 339.646514 -295.955974)
			(xy 339.975202 -295.955974) (xy 339.979162 -295.90692) (xy 339.990939 -295.859136) (xy 340.01023 -295.81386)
			(xy 340.036533 -295.772264) (xy 340.069168 -295.735427) (xy 340.107289 -295.704302) (xy 340.14991 -295.679695)
			(xy 340.195926 -295.662243) (xy 340.244145 -295.652399) (xy 340.29332 -295.650418) (xy 340.342175 -295.65635)
			(xy 340.389446 -295.670042) (xy 340.433908 -295.69114) (xy 340.474411 -295.719096) (xy 340.509904 -295.753188)
			(xy 340.539469 -295.792532) (xy 340.56234 -295.836109) (xy 340.577924 -295.88279) (xy 340.585819 -295.931367)
			(xy 340.586314 -295.955974) (xy 340.585819 -295.980581) (xy 340.577924 -296.029158) (xy 340.56234 -296.075839)
			(xy 340.539469 -296.119416) (xy 340.509904 -296.15876) (xy 340.474411 -296.192852) (xy 340.433908 -296.220808)
			(xy 340.389446 -296.241906) (xy 340.342175 -296.255598) (xy 340.29332 -296.26153) (xy 340.244145 -296.259549)
			(xy 340.195926 -296.249705) (xy 340.14991 -296.232253) (xy 340.107289 -296.207646) (xy 340.069168 -296.176521)
			(xy 340.036533 -296.139684) (xy 340.01023 -296.098088) (xy 339.990939 -296.052812) (xy 339.979162 -296.005028)
			(xy 339.975202 -295.955974) (xy 339.646514 -295.955974) (xy 339.646019 -295.980581) (xy 339.638124 -296.029158)
			(xy 339.62254 -296.075839) (xy 339.599669 -296.119416) (xy 339.570104 -296.15876) (xy 339.534611 -296.192852)
			(xy 339.494108 -296.220808) (xy 339.449646 -296.241906) (xy 339.402375 -296.255598) (xy 339.35352 -296.26153)
			(xy 339.304345 -296.259549) (xy 339.256126 -296.249705) (xy 339.21011 -296.232253) (xy 339.167489 -296.207646)
			(xy 339.129368 -296.176521) (xy 339.096733 -296.139684) (xy 339.07043 -296.098088) (xy 339.051139 -296.052812)
			(xy 339.039362 -296.005028) (xy 339.035402 -295.955974) (xy 338.70646 -295.955974) (xy 338.705965 -295.980581)
			(xy 338.69807 -296.029158) (xy 338.682486 -296.075839) (xy 338.659615 -296.119416) (xy 338.63005 -296.15876)
			(xy 338.594557 -296.192852) (xy 338.554054 -296.220808) (xy 338.509592 -296.241906) (xy 338.462321 -296.255598)
			(xy 338.413466 -296.26153) (xy 338.364291 -296.259549) (xy 338.316072 -296.249705) (xy 338.270056 -296.232253)
			(xy 338.227435 -296.207646) (xy 338.189314 -296.176521) (xy 338.156679 -296.139684) (xy 338.130376 -296.098088)
			(xy 338.111085 -296.052812) (xy 338.099308 -296.005028) (xy 338.095348 -295.955974) (xy 336.826352 -295.955974)
			(xy 336.825857 -295.980581) (xy 336.817962 -296.029158) (xy 336.802378 -296.075839) (xy 336.779507 -296.119416)
			(xy 336.749942 -296.15876) (xy 336.714449 -296.192852) (xy 336.673946 -296.220808) (xy 336.629484 -296.241906)
			(xy 336.582213 -296.255598) (xy 336.533358 -296.26153) (xy 336.484183 -296.259549) (xy 336.435964 -296.249705)
			(xy 336.389948 -296.232253) (xy 336.347327 -296.207646) (xy 336.309206 -296.176521) (xy 336.276571 -296.139684)
			(xy 336.250268 -296.098088) (xy 336.230977 -296.052812) (xy 336.2192 -296.005028) (xy 336.21524 -295.955974)
			(xy 334.946498 -295.955974) (xy 334.946003 -295.980581) (xy 334.938108 -296.029158) (xy 334.922524 -296.075839)
			(xy 334.899653 -296.119416) (xy 334.870088 -296.15876) (xy 334.834595 -296.192852) (xy 334.794092 -296.220808)
			(xy 334.74963 -296.241906) (xy 334.702359 -296.255598) (xy 334.653504 -296.26153) (xy 334.604329 -296.259549)
			(xy 334.55611 -296.249705) (xy 334.510094 -296.232253) (xy 334.467473 -296.207646) (xy 334.429352 -296.176521)
			(xy 334.396717 -296.139684) (xy 334.370414 -296.098088) (xy 334.351123 -296.052812) (xy 334.339346 -296.005028)
			(xy 334.335386 -295.955974) (xy 334.006444 -295.955974) (xy 334.005949 -295.980581) (xy 333.998054 -296.029158)
			(xy 333.98247 -296.075839) (xy 333.959599 -296.119416) (xy 333.930034 -296.15876) (xy 333.894541 -296.192852)
			(xy 333.854038 -296.220808) (xy 333.809576 -296.241906) (xy 333.762305 -296.255598) (xy 333.71345 -296.26153)
			(xy 333.664275 -296.259549) (xy 333.616056 -296.249705) (xy 333.57004 -296.232253) (xy 333.527419 -296.207646)
			(xy 333.489298 -296.176521) (xy 333.456663 -296.139684) (xy 333.43036 -296.098088) (xy 333.411069 -296.052812)
			(xy 333.399292 -296.005028) (xy 333.395332 -295.955974) (xy 333.06639 -295.955974) (xy 333.065895 -295.980581)
			(xy 333.058 -296.029158) (xy 333.042416 -296.075839) (xy 333.019545 -296.119416) (xy 332.98998 -296.15876)
			(xy 332.954487 -296.192852) (xy 332.913984 -296.220808) (xy 332.869522 -296.241906) (xy 332.822251 -296.255598)
			(xy 332.773396 -296.26153) (xy 332.724221 -296.259549) (xy 332.676002 -296.249705) (xy 332.629986 -296.232253)
			(xy 332.587365 -296.207646) (xy 332.549244 -296.176521) (xy 332.516609 -296.139684) (xy 332.490306 -296.098088)
			(xy 332.471015 -296.052812) (xy 332.459238 -296.005028) (xy 332.455278 -295.955974) (xy 332.126336 -295.955974)
			(xy 332.125841 -295.980581) (xy 332.117946 -296.029158) (xy 332.102362 -296.075839) (xy 332.079491 -296.119416)
			(xy 332.049926 -296.15876) (xy 332.014433 -296.192852) (xy 331.97393 -296.220808) (xy 331.929468 -296.241906)
			(xy 331.882197 -296.255598) (xy 331.833342 -296.26153) (xy 331.784167 -296.259549) (xy 331.735948 -296.249705)
			(xy 331.689932 -296.232253) (xy 331.647311 -296.207646) (xy 331.60919 -296.176521) (xy 331.576555 -296.139684)
			(xy 331.550252 -296.098088) (xy 331.530961 -296.052812) (xy 331.519184 -296.005028) (xy 331.515224 -295.955974)
			(xy 331.186536 -295.955974) (xy 331.186067 -295.979967) (xy 331.178565 -296.027364) (xy 331.16374 -296.073003)
			(xy 331.141958 -296.115761) (xy 331.113756 -296.154586) (xy 331.079827 -296.188521) (xy 331.041008 -296.21673)
			(xy 330.998253 -296.238519) (xy 330.952616 -296.253352) (xy 330.905221 -296.260863) (xy 330.881228 -296.261282)
			(xy 330.867004 -296.261282) (xy 330.857352 -296.265346) (xy 330.852847 -296.267357) (xy 330.84466 -296.272858)
			(xy 330.841096 -296.276268) (xy 327.878378 -299.238946) (xy 339.464724 -299.238946) (xy 339.464724 -299.184454)
			(xy 339.472478 -299.130518) (xy 339.487829 -299.078233) (xy 339.510464 -299.028665) (xy 339.539922 -298.982823)
			(xy 339.575604 -298.941639) (xy 339.616783 -298.905952) (xy 339.662621 -298.876488) (xy 339.712186 -298.853847)
			(xy 339.764469 -298.838489) (xy 339.818404 -298.830728) (xy 339.84565 -298.830238) (xy 339.845904 -298.830238)
			(xy 339.871292 -298.830645) (xy 339.921618 -298.837392) (xy 339.970601 -298.850766) (xy 340.017373 -298.87053)
			(xy 340.039452 -298.88307) (xy 340.048088 -298.88815) (xy 340.067138 -298.891198) (xy 340.154768 -298.870624)
			(xy 340.17077 -298.859702) (xy 340.176104 -298.851828) (xy 340.176104 -298.85132) (xy 340.193797 -298.825344)
			(xy 340.234563 -298.777507) (xy 340.280915 -298.735059) (xy 340.332145 -298.698649) (xy 340.387473 -298.668831)
			(xy 340.446054 -298.64606) (xy 340.506995 -298.630683) (xy 340.569366 -298.622935) (xy 340.600792 -298.622466)
			(xy 340.631522 -298.622964) (xy 340.692533 -298.630371) (xy 340.752208 -298.645078) (xy 340.809674 -298.66687)
			(xy 340.864094 -298.69543) (xy 340.914676 -298.730342) (xy 340.96068 -298.771096) (xy 341.001437 -298.817098)
			(xy 341.036352 -298.867676) (xy 341.064916 -298.922095) (xy 341.086712 -298.97956) (xy 341.101423 -299.039233)
			(xy 341.108834 -299.100244) (xy 341.1093 -299.130974) (xy 341.108709 -299.165939) (xy 341.099111 -299.235208)
			(xy 341.080105 -299.302507) (xy 341.052051 -299.366564) (xy 341.01548 -299.42617) (xy 340.99373 -299.453554)
			(xy 340.988471 -299.46056) (xy 340.982619 -299.477058) (xy 340.9823 -299.485812) (xy 340.9823 -299.792136)
			(xy 340.982648 -299.800884) (xy 340.988495 -299.817376) (xy 340.99373 -299.824394) (xy 341.015469 -299.851784)
			(xy 341.052022 -299.911397) (xy 341.080068 -299.975454) (xy 341.099079 -300.042748) (xy 341.108698 -300.112011)
			(xy 341.1093 -300.146974) (xy 341.108838 -300.177706) (xy 341.101432 -300.238722) (xy 341.086725 -300.2984)
			(xy 341.064932 -300.35587) (xy 341.03637 -300.410295) (xy 341.001456 -300.460879) (xy 340.960699 -300.506886)
			(xy 340.914693 -300.547645) (xy 340.86411 -300.582561) (xy 340.809687 -300.611125) (xy 340.752217 -300.63292)
			(xy 340.692539 -300.647629) (xy 340.631524 -300.655037) (xy 340.600792 -300.655482) (xy 340.56828 -300.654953)
			(xy 340.503784 -300.646678) (xy 340.440868 -300.63025) (xy 340.380559 -300.605939) (xy 340.323841 -300.57414)
			(xy 340.271637 -300.535371) (xy 340.2248 -300.490266) (xy 340.204044 -300.465236) (xy 340.197754 -300.458065)
			(xy 340.181169 -300.44867) (xy 340.171786 -300.446948) (xy 340.140798 -300.442376) (xy 340.131308 -300.441455)
			(xy 340.112779 -300.4459) (xy 340.10473 -300.451012) (xy 340.080718 -300.466961) (xy 340.028902 -300.492213)
			(xy 339.973874 -300.509373) (xy 339.916889 -300.518049) (xy 339.888068 -300.518576) (xy 339.860816 -300.518152)
			(xy 339.806867 -300.510391) (xy 339.754572 -300.495032) (xy 339.704995 -300.472387) (xy 339.659144 -300.442917)
			(xy 339.617954 -300.407223) (xy 339.582263 -300.36603) (xy 339.552798 -300.320177) (xy 339.530157 -300.270598)
			(xy 339.514802 -300.218302) (xy 339.507046 -300.164352) (xy 339.507046 -300.109848) (xy 339.514802 -300.055898)
			(xy 339.530157 -300.003602) (xy 339.552798 -299.954023) (xy 339.582263 -299.90817) (xy 339.617954 -299.866977)
			(xy 339.659144 -299.831283) (xy 339.704995 -299.801813) (xy 339.754572 -299.779168) (xy 339.806867 -299.763809)
			(xy 339.860816 -299.756048) (xy 339.888068 -299.75556) (xy 339.918245 -299.756119) (xy 339.977849 -299.765595)
			(xy 340.035221 -299.784331) (xy 340.088929 -299.811862) (xy 340.11362 -299.82922) (xy 340.121498 -299.834459)
			(xy 340.139736 -299.839419) (xy 340.14918 -299.838872) (xy 340.200742 -299.83303) (xy 340.2076 -299.824648)
			(xy 340.212917 -299.817586) (xy 340.218898 -299.800967) (xy 340.219284 -299.792136) (xy 340.219284 -299.611288)
			(xy 340.218888 -299.602056) (xy 340.212339 -299.584794) (xy 340.200095 -299.570974) (xy 340.192106 -299.56633)
			(xy 340.112604 -299.524166) (xy 340.104349 -299.520193) (xy 340.086198 -299.517807) (xy 340.068366 -299.521952)
			(xy 340.060534 -299.526706) (xy 340.060534 -299.52696) (xy 340.060026 -299.52696) (xy 340.036195 -299.54257)
			(xy 339.984878 -299.567304) (xy 339.930454 -299.584134) (xy 339.874133 -299.592685) (xy 339.84565 -299.593254)
			(xy 339.818404 -299.592672) (xy 339.764469 -299.584911) (xy 339.712186 -299.569553) (xy 339.662621 -299.546912)
			(xy 339.616783 -299.517448) (xy 339.575604 -299.481761) (xy 339.539922 -299.440577) (xy 339.510464 -299.394735)
			(xy 339.487829 -299.345167) (xy 339.472478 -299.292882) (xy 339.464724 -299.238946) (xy 327.878378 -299.238946)
			(xy 325.371938 -301.745353) (xy 340.488772 -301.745353) (xy 340.488772 -301.681431) (xy 340.496783 -301.618013)
			(xy 340.51268 -301.556099) (xy 340.536212 -301.496666) (xy 340.567006 -301.440651) (xy 340.604579 -301.388936)
			(xy 340.648336 -301.342339) (xy 340.697589 -301.301594) (xy 340.75156 -301.267343) (xy 340.809399 -301.240126)
			(xy 340.870192 -301.220373) (xy 340.932982 -301.208395) (xy 340.996778 -301.204382) (xy 341.060574 -301.208395)
			(xy 341.123364 -301.220373) (xy 341.184157 -301.240126) (xy 341.241996 -301.267343) (xy 341.295967 -301.301594)
			(xy 341.34522 -301.342339) (xy 341.388977 -301.388936) (xy 341.42655 -301.440651) (xy 341.457344 -301.496666)
			(xy 341.480876 -301.556099) (xy 341.496773 -301.618013) (xy 341.504784 -301.681431) (xy 341.505286 -301.713392)
			(xy 341.504784 -301.745353) (xy 341.496773 -301.808771) (xy 341.480876 -301.870685) (xy 341.457344 -301.930118)
			(xy 341.42655 -301.986133) (xy 341.388977 -302.037848) (xy 341.34522 -302.084445) (xy 341.295967 -302.12519)
			(xy 341.241996 -302.159441) (xy 341.184157 -302.186658) (xy 341.123364 -302.206411) (xy 341.060574 -302.218389)
			(xy 340.996778 -302.222403) (xy 340.932982 -302.218389) (xy 340.870192 -302.206411) (xy 340.809399 -302.186658)
			(xy 340.75156 -302.159441) (xy 340.697589 -302.12519) (xy 340.648336 -302.084445) (xy 340.604579 -302.037848)
			(xy 340.567006 -301.986133) (xy 340.536212 -301.930118) (xy 340.51268 -301.870685) (xy 340.496783 -301.808771)
			(xy 340.488772 -301.745353) (xy 325.371938 -301.745353) (xy 322.337062 -304.780188) (xy 326.752208 -304.780188)
			(xy 326.756238 -304.637853) (xy 326.768313 -304.495973) (xy 326.788396 -304.355005) (xy 326.816423 -304.215398)
			(xy 326.852303 -304.0776) (xy 326.895921 -303.942053) (xy 326.947138 -303.809191) (xy 327.005789 -303.679439)
			(xy 327.071687 -303.553213) (xy 327.144621 -303.430917) (xy 327.224358 -303.312944) (xy 327.31064 -303.199671)
			(xy 327.403193 -303.09146) (xy 327.50172 -302.988659) (xy 327.605905 -302.891597) (xy 327.715414 -302.800585)
			(xy 327.829897 -302.715913) (xy 327.948987 -302.637855) (xy 328.072302 -302.566659) (xy 328.199448 -302.502553)
			(xy 328.330017 -302.445744) (xy 328.463591 -302.396412) (xy 328.599742 -302.354716) (xy 328.738033 -302.32079)
			(xy 328.878023 -302.294742) (xy 329.019262 -302.276656) (xy 329.161298 -302.266589) (xy 329.303676 -302.264574)
			(xy 329.44594 -302.270617) (xy 329.587634 -302.284699) (xy 329.728304 -302.306775) (xy 329.867501 -302.336775)
			(xy 330.004777 -302.374601) (xy 330.139693 -302.420133) (xy 330.271817 -302.473224) (xy 330.400726 -302.533706)
			(xy 330.526007 -302.601384) (xy 330.647258 -302.676041) (xy 330.764091 -302.757439) (xy 330.876132 -302.845316)
			(xy 330.983022 -302.939391) (xy 331.084419 -303.039363) (xy 331.179997 -303.144911) (xy 331.269451 -303.255697)
			(xy 331.352493 -303.371366) (xy 331.428859 -303.491549) (xy 331.498303 -303.615859) (xy 331.560603 -303.7439)
			(xy 331.615559 -303.875259) (xy 331.662996 -304.009518) (xy 331.70276 -304.146245) (xy 331.734726 -304.285003)
			(xy 331.758791 -304.425347) (xy 331.774877 -304.566828) (xy 331.782932 -304.708992) (xy 331.783436 -304.780188)
			(xy 331.782932 -304.851384) (xy 331.774877 -304.993548) (xy 331.76785 -305.055351) (xy 333.14867 -305.055351)
			(xy 333.14867 -305.000849) (xy 333.156426 -304.946901) (xy 333.171781 -304.894606) (xy 333.194421 -304.845029)
			(xy 333.223887 -304.799178) (xy 333.259578 -304.757988) (xy 333.300767 -304.722295) (xy 333.346617 -304.692828)
			(xy 333.396193 -304.670186) (xy 333.448487 -304.654829) (xy 333.502435 -304.647071) (xy 333.529686 -304.646584)
			(xy 333.539931 -304.646673) (xy 333.560389 -304.647819) (xy 333.57058 -304.64887) (xy 333.579856 -304.649494)
			(xy 333.597831 -304.644786) (xy 333.605632 -304.639726) (xy 333.668116 -304.594768) (xy 333.67853 -304.57902)
			(xy 333.680562 -304.569876) (xy 333.687473 -304.541019) (xy 333.707125 -304.485027) (xy 333.733149 -304.431698)
			(xy 333.765193 -304.381754) (xy 333.783686 -304.358548) (xy 333.788903 -304.35159) (xy 333.794762 -304.335232)
			(xy 333.795116 -304.326544) (xy 333.795116 -304.172112) (xy 333.794731 -304.163429) (xy 333.788888 -304.147071)
			(xy 333.783686 -304.140108) (xy 333.764796 -304.116355) (xy 333.732197 -304.065163) (xy 333.718662 -304.038)
			(xy 333.714459 -304.030064) (xy 333.70158 -304.017567) (xy 333.693516 -304.013616) (xy 333.66583 -304.00117)
			(xy 333.657665 -303.997859) (xy 333.640104 -303.996559) (xy 333.63154 -303.99863) (xy 333.606578 -304.005128)
			(xy 333.555476 -304.012138) (xy 333.529686 -304.0126) (xy 333.502435 -304.012129) (xy 333.448487 -304.004371)
			(xy 333.396193 -303.989014) (xy 333.346617 -303.966372) (xy 333.300767 -303.936905) (xy 333.259578 -303.901212)
			(xy 333.223887 -303.860022) (xy 333.194421 -303.814171) (xy 333.171781 -303.764594) (xy 333.156426 -303.712299)
			(xy 333.14867 -303.658351) (xy 333.14867 -303.603849) (xy 333.156426 -303.549901) (xy 333.171781 -303.497606)
			(xy 333.194421 -303.448029) (xy 333.223887 -303.402178) (xy 333.259578 -303.360988) (xy 333.300767 -303.325295)
			(xy 333.346617 -303.295828) (xy 333.396193 -303.273186) (xy 333.448487 -303.257829) (xy 333.502435 -303.250071)
			(xy 333.529686 -303.249584) (xy 333.556134 -303.250062) (xy 333.608525 -303.257356) (xy 333.659405 -303.27182)
			(xy 333.707797 -303.293177) (xy 333.752775 -303.321016) (xy 333.793473 -303.354804) (xy 333.811626 -303.374044)
			(xy 333.817845 -303.380324) (xy 333.833425 -303.388641) (xy 333.842106 -303.3903) (xy 333.871824 -303.394364)
			(xy 333.880749 -303.395331) (xy 333.898316 -303.391699) (xy 333.906114 -303.387252) (xy 333.936647 -303.368716)
			(xy 334.001821 -303.339487) (xy 334.070443 -303.319665) (xy 334.141164 -303.30964) (xy 334.176878 -303.30902)
			(xy 334.207611 -303.309458) (xy 334.268628 -303.316865) (xy 334.328308 -303.331573) (xy 334.38578 -303.353368)
			(xy 334.440205 -303.381931) (xy 334.49079 -303.416847) (xy 334.536798 -303.457607) (xy 334.577556 -303.503615)
			(xy 334.612472 -303.5542) (xy 334.641035 -303.608626) (xy 334.662829 -303.666098) (xy 334.677536 -303.725778)
			(xy 334.684942 -303.786795) (xy 334.685386 -303.817528) (xy 334.684824 -303.852484) (xy 334.675258 -303.921738)
			(xy 334.656296 -303.989029) (xy 334.628297 -304.053089) (xy 334.591787 -304.112711) (xy 334.57007 -304.140108)
			(xy 334.564825 -304.147048) (xy 334.558984 -304.16342) (xy 334.55864 -304.172112) (xy 334.55864 -304.326544)
			(xy 334.559034 -304.335226) (xy 334.56487 -304.351585) (xy 334.57007 -304.358548) (xy 334.591755 -304.385969)
			(xy 334.628258 -304.445588) (xy 334.656256 -304.509643) (xy 334.675223 -304.576927) (xy 334.684802 -304.646175)
			(xy 334.685386 -304.681128) (xy 334.68497 -304.71186) (xy 334.677558 -304.772877) (xy 334.662845 -304.832555)
			(xy 334.641047 -304.890024) (xy 334.61248 -304.944447) (xy 334.591765 -304.974455) (xy 343.718382 -304.974455)
			(xy 343.718382 -304.910533) (xy 343.726393 -304.847115) (xy 343.74229 -304.785201) (xy 343.765822 -304.725768)
			(xy 343.796616 -304.669753) (xy 343.834189 -304.618038) (xy 343.877946 -304.571441) (xy 343.927199 -304.530696)
			(xy 343.98117 -304.496445) (xy 344.039009 -304.469228) (xy 344.099802 -304.449475) (xy 344.162592 -304.437497)
			(xy 344.226388 -304.433484) (xy 344.290184 -304.437497) (xy 344.352974 -304.449475) (xy 344.413767 -304.469228)
			(xy 344.471606 -304.496445) (xy 344.525577 -304.530696) (xy 344.57483 -304.571441) (xy 344.618587 -304.618038)
			(xy 344.65616 -304.669753) (xy 344.686954 -304.725768) (xy 344.710486 -304.785201) (xy 344.726383 -304.847115)
			(xy 344.734394 -304.910533) (xy 344.734896 -304.942494) (xy 344.734394 -304.974455) (xy 344.726383 -305.037873)
			(xy 344.710486 -305.099787) (xy 344.686954 -305.15922) (xy 344.65616 -305.215235) (xy 344.618587 -305.26695)
			(xy 344.57483 -305.313547) (xy 344.525577 -305.354292) (xy 344.471606 -305.388543) (xy 344.413767 -305.41576)
			(xy 344.352974 -305.435513) (xy 344.290184 -305.447491) (xy 344.226388 -305.451505) (xy 344.162592 -305.447491)
			(xy 344.099802 -305.435513) (xy 344.039009 -305.41576) (xy 343.98117 -305.388543) (xy 343.927199 -305.354292)
			(xy 343.877946 -305.313547) (xy 343.834189 -305.26695) (xy 343.796616 -305.215235) (xy 343.765822 -305.15922)
			(xy 343.74229 -305.099787) (xy 343.726393 -305.037873) (xy 343.718382 -304.974455) (xy 334.591765 -304.974455)
			(xy 334.577561 -304.99503) (xy 334.5368 -305.041035) (xy 334.490791 -305.081792) (xy 334.440205 -305.116706)
			(xy 334.385779 -305.145267) (xy 334.328307 -305.16706) (xy 334.268628 -305.181767) (xy 334.20761 -305.189173)
			(xy 334.176878 -305.189636) (xy 334.145823 -305.189181) (xy 334.084176 -305.181607) (xy 334.023915 -305.166562)
			(xy 333.99476 -305.155854) (xy 333.98587 -305.152552) (xy 333.967582 -305.152552) (xy 333.886302 -305.183286)
			(xy 333.872586 -305.195732) (xy 333.868268 -305.20386) (xy 333.855857 -305.226764) (xy 333.825796 -305.269308)
			(xy 333.790225 -305.307365) (xy 333.749805 -305.340226) (xy 333.705288 -305.367279) (xy 333.657503 -305.388023)
			(xy 333.60734 -305.402069) (xy 333.555732 -305.409157) (xy 333.529686 -305.4096) (xy 333.502435 -305.409129)
			(xy 333.448487 -305.401371) (xy 333.396193 -305.386014) (xy 333.346617 -305.363372) (xy 333.300767 -305.333905)
			(xy 333.259578 -305.298212) (xy 333.223887 -305.257022) (xy 333.194421 -305.211171) (xy 333.171781 -305.161594)
			(xy 333.156426 -305.109299) (xy 333.14867 -305.055351) (xy 331.76785 -305.055351) (xy 331.758791 -305.135029)
			(xy 331.734726 -305.275373) (xy 331.703678 -305.410147) (xy 339.849008 -305.410147) (xy 339.849008 -305.355653)
			(xy 339.856763 -305.301714) (xy 339.872114 -305.249427) (xy 339.89475 -305.199857) (xy 339.924209 -305.154013)
			(xy 339.959893 -305.112827) (xy 340.001074 -305.077138) (xy 340.046915 -305.047673) (xy 340.096482 -305.025031)
			(xy 340.148767 -305.009673) (xy 340.202705 -305.001911) (xy 340.229952 -305.001422) (xy 340.256402 -305.001843)
			(xy 340.308796 -305.009147) (xy 340.359677 -305.023622) (xy 340.40807 -305.044989) (xy 340.453046 -305.072839)
			(xy 340.493741 -305.106637) (xy 340.511892 -305.125882) (xy 340.518099 -305.132176) (xy 340.533688 -305.140486)
			(xy 340.542372 -305.142138) (xy 340.57209 -305.146202) (xy 340.581014 -305.147211) (xy 340.598585 -305.143552)
			(xy 340.60638 -305.13909) (xy 340.636917 -305.120561) (xy 340.70209 -305.091332) (xy 340.770711 -305.071509)
			(xy 340.841431 -305.06148) (xy 340.877144 -305.060858) (xy 340.907875 -305.061314) (xy 340.968887 -305.068727)
			(xy 341.028562 -305.083439) (xy 341.086028 -305.105237) (xy 341.140448 -305.133802) (xy 341.191029 -305.168717)
			(xy 341.237033 -305.209474) (xy 341.277789 -305.255479) (xy 341.312704 -305.30606) (xy 341.341267 -305.360481)
			(xy 341.363063 -305.417948) (xy 341.377775 -305.477623) (xy 341.385186 -305.538635) (xy 341.385652 -305.569366)
			(xy 341.385068 -305.604332) (xy 341.375469 -305.673601) (xy 341.356463 -305.740901) (xy 341.328407 -305.804958)
			(xy 341.291833 -305.864563) (xy 341.270082 -305.891946) (xy 341.264832 -305.898959) (xy 341.258973 -305.915451)
			(xy 341.258652 -305.924204) (xy 341.258652 -306.062634) (xy 342.14054 -306.062634) (xy 342.141042 -306.030119)
			(xy 342.149316 -305.965619) (xy 342.165747 -305.9027) (xy 342.190065 -305.842389) (xy 342.221875 -305.785671)
			(xy 342.260657 -305.733472) (xy 342.305777 -305.686643) (xy 342.356501 -305.64595) (xy 342.411998 -305.612056)
			(xy 342.471364 -305.585514) (xy 342.53363 -305.566758) (xy 342.597779 -305.556095) (xy 342.630252 -305.55438)
			(xy 342.64092 -305.554126) (xy 342.660224 -305.544728) (xy 342.722708 -305.47056) (xy 342.72855 -305.450494)
			(xy 342.72728 -305.44008) (xy 342.72728 -305.439572) (xy 342.725746 -305.427247) (xy 342.724094 -305.402462)
			(xy 342.723978 -305.390042) (xy 342.724464 -305.362791) (xy 342.73222 -305.308843) (xy 342.747575 -305.256548)
			(xy 342.770217 -305.206971) (xy 342.799683 -305.161121) (xy 342.835374 -305.11993) (xy 342.876565 -305.084239)
			(xy 342.922415 -305.054773) (xy 342.971992 -305.032131) (xy 343.024287 -305.016776) (xy 343.078235 -305.00902)
			(xy 343.132737 -305.00902) (xy 343.186685 -305.016776) (xy 343.23898 -305.032131) (xy 343.288557 -305.054773)
			(xy 343.334407 -305.084239) (xy 343.375598 -305.11993) (xy 343.411289 -305.161121) (xy 343.440755 -305.206971)
			(xy 343.463397 -305.256548) (xy 343.478752 -305.308843) (xy 343.486508 -305.362791) (xy 343.486994 -305.390042)
			(xy 343.486505 -305.418099) (xy 343.478267 -305.473605) (xy 343.46199 -305.527306) (xy 343.438024 -305.578044)
			(xy 343.406885 -305.624726) (xy 343.369247 -305.666344) (xy 343.325919 -305.702002) (xy 343.277837 -305.730931)
			(xy 343.226037 -305.752506) (xy 343.198958 -305.759866) (xy 343.188924 -305.763025) (xy 343.172404 -305.776014)
			(xy 343.166954 -305.785012) (xy 343.12606 -305.861212) (xy 343.124536 -305.88204) (xy 343.128092 -305.8922)
			(xy 343.128092 -305.892708) (xy 343.137394 -305.920063) (xy 343.150474 -305.976345) (xy 343.157105 -306.033744)
			(xy 343.157556 -306.062634) (xy 343.157054 -306.094595) (xy 343.149043 -306.158013) (xy 343.133146 -306.219927)
			(xy 343.109614 -306.27936) (xy 343.07882 -306.335375) (xy 343.041247 -306.38709) (xy 342.99749 -306.433687)
			(xy 342.948237 -306.474432) (xy 342.894266 -306.508683) (xy 342.836427 -306.5359) (xy 342.775634 -306.555653)
			(xy 342.712844 -306.567631) (xy 342.649048 -306.571645) (xy 342.585252 -306.567631) (xy 342.522462 -306.555653)
			(xy 342.461669 -306.5359) (xy 342.40383 -306.508683) (xy 342.349859 -306.474432) (xy 342.300606 -306.433687)
			(xy 342.256849 -306.38709) (xy 342.219276 -306.335375) (xy 342.188482 -306.27936) (xy 342.16495 -306.219927)
			(xy 342.149053 -306.158013) (xy 342.141042 -306.094595) (xy 342.14054 -306.062634) (xy 341.258652 -306.062634)
			(xy 341.258652 -306.078128) (xy 341.258993 -306.086877) (xy 341.264844 -306.103369) (xy 341.270082 -306.110386)
			(xy 341.291811 -306.137784) (xy 341.328366 -306.197395) (xy 341.356415 -306.261449) (xy 341.375429 -306.328741)
			(xy 341.385049 -306.398003) (xy 341.385652 -306.432966) (xy 341.385137 -306.466018) (xy 341.376563 -306.531564)
			(xy 341.359569 -306.595447) (xy 341.334441 -306.65659) (xy 341.301603 -306.713961) (xy 341.261608 -306.766594)
			(xy 341.215131 -306.813601) (xy 341.162955 -306.85419) (xy 341.10596 -306.887676) (xy 341.045106 -306.913496)
			(xy 340.98142 -306.931213) (xy 340.948772 -306.936394) (xy 340.93912 -306.937664) (xy 340.921848 -306.94757)
			(xy 340.866476 -307.018944) (xy 340.861142 -307.037994) (xy 340.862158 -307.047646) (xy 340.863117 -307.057588)
			(xy 340.864136 -307.077536) (xy 340.86419 -307.087524) (xy 340.863704 -307.114775) (xy 340.855948 -307.168723)
			(xy 340.840593 -307.221018) (xy 340.817951 -307.270595) (xy 340.788485 -307.316445) (xy 340.752794 -307.357636)
			(xy 340.711603 -307.393327) (xy 340.665753 -307.422793) (xy 340.616176 -307.445435) (xy 340.563881 -307.46079)
			(xy 340.509933 -307.468546) (xy 340.455431 -307.468546) (xy 340.401483 -307.46079) (xy 340.349188 -307.445435)
			(xy 340.299611 -307.422793) (xy 340.253761 -307.393327) (xy 340.21257 -307.357636) (xy 340.176879 -307.316445)
			(xy 340.147413 -307.270595) (xy 340.124771 -307.221018) (xy 340.109416 -307.168723) (xy 340.10166 -307.114775)
			(xy 340.101174 -307.087524) (xy 340.101665 -307.05915) (xy 340.110081 -307.003028) (xy 340.126717 -306.948772)
			(xy 340.151204 -306.897579) (xy 340.183005 -306.850577) (xy 340.221416 -306.808803) (xy 340.26559 -306.773179)
			(xy 340.314553 -306.744491) (xy 340.340696 -306.733448) (xy 340.350094 -306.729638) (xy 340.364064 -306.71643)
			(xy 340.397084 -306.642516) (xy 340.400681 -306.633455) (xy 340.401465 -306.613991) (xy 340.398608 -306.60467)
			(xy 340.389101 -306.577055) (xy 340.375772 -306.520189) (xy 340.369054 -306.462169) (xy 340.368636 -306.432966)
			(xy 340.369241 -306.398001) (xy 340.378835 -306.328732) (xy 340.397837 -306.261433) (xy 340.425887 -306.197376)
			(xy 340.462457 -306.13777) (xy 340.484206 -306.110386) (xy 340.489483 -306.103391) (xy 340.495326 -306.086885)
			(xy 340.495636 -306.078128) (xy 340.495636 -305.924204) (xy 340.495263 -305.915458) (xy 340.489432 -305.898967)
			(xy 340.484206 -305.891946) (xy 340.465259 -305.868195) (xy 340.432531 -305.817005) (xy 340.418928 -305.789838)
			(xy 340.41472 -305.781905) (xy 340.401843 -305.769408) (xy 340.393782 -305.765454) (xy 340.366096 -305.753008)
			(xy 340.357925 -305.749727) (xy 340.340376 -305.748441) (xy 340.331806 -305.750468) (xy 340.306845 -305.756971)
			(xy 340.255742 -305.763978) (xy 340.229952 -305.764438) (xy 340.202705 -305.763889) (xy 340.148767 -305.756127)
			(xy 340.096482 -305.740769) (xy 340.046915 -305.718127) (xy 340.001074 -305.688662) (xy 339.959893 -305.652973)
			(xy 339.924209 -305.611787) (xy 339.89475 -305.565943) (xy 339.872114 -305.516373) (xy 339.856763 -305.464086)
			(xy 339.849008 -305.410147) (xy 331.703678 -305.410147) (xy 331.70276 -305.414131) (xy 331.662996 -305.550858)
			(xy 331.615559 -305.685117) (xy 331.560603 -305.816476) (xy 331.498303 -305.944517) (xy 331.428859 -306.068827)
			(xy 331.352493 -306.18901) (xy 331.269451 -306.304679) (xy 331.179997 -306.415465) (xy 331.084419 -306.521013)
			(xy 330.983022 -306.620985) (xy 330.876132 -306.71506) (xy 330.764091 -306.802937) (xy 330.647258 -306.884335)
			(xy 330.526007 -306.958992) (xy 330.400726 -307.02667) (xy 330.271817 -307.087152) (xy 330.139693 -307.140243)
			(xy 330.004777 -307.185775) (xy 329.867501 -307.223601) (xy 329.728304 -307.253601) (xy 329.587634 -307.275677)
			(xy 329.44594 -307.289759) (xy 329.303676 -307.295802) (xy 329.161298 -307.293787) (xy 329.019262 -307.28372)
			(xy 328.878023 -307.265634) (xy 328.738033 -307.239586) (xy 328.599742 -307.20566) (xy 328.463591 -307.163964)
			(xy 328.330017 -307.114632) (xy 328.199448 -307.057823) (xy 328.072302 -306.993717) (xy 327.948987 -306.922521)
			(xy 327.829897 -306.844463) (xy 327.715414 -306.759791) (xy 327.605905 -306.668779) (xy 327.50172 -306.571717)
			(xy 327.403193 -306.468916) (xy 327.31064 -306.360705) (xy 327.224358 -306.247432) (xy 327.144621 -306.129459)
			(xy 327.071687 -306.007163) (xy 327.005789 -305.880937) (xy 326.947138 -305.751185) (xy 326.895921 -305.618323)
			(xy 326.852303 -305.482776) (xy 326.816423 -305.344978) (xy 326.788396 -305.205371) (xy 326.768313 -305.064403)
			(xy 326.756238 -304.922523) (xy 326.752208 -304.780188) (xy 322.337062 -304.780188) (xy 316.940549 -310.176629)
			(xy 332.667604 -310.176629) (xy 332.667604 -310.112707) (xy 332.675615 -310.049289) (xy 332.691512 -309.987375)
			(xy 332.715044 -309.927942) (xy 332.745838 -309.871927) (xy 332.783411 -309.820212) (xy 332.827168 -309.773615)
			(xy 332.876421 -309.73287) (xy 332.930392 -309.698619) (xy 332.988231 -309.671402) (xy 333.049024 -309.651649)
			(xy 333.111814 -309.639671) (xy 333.17561 -309.635658) (xy 333.239406 -309.639671) (xy 333.302196 -309.651649)
			(xy 333.362989 -309.671402) (xy 333.420828 -309.698619) (xy 333.474799 -309.73287) (xy 333.506735 -309.759289)
			(xy 334.460162 -309.759289) (xy 334.465371 -309.696417) (xy 334.478316 -309.634671) (xy 334.4988 -309.575002)
			(xy 334.526507 -309.518324) (xy 334.561012 -309.465509) (xy 334.601786 -309.417368) (xy 334.6482 -309.374639)
			(xy 334.699544 -309.337981) (xy 334.755028 -309.307954) (xy 334.8138 -309.285021) (xy 334.874957 -309.269535)
			(xy 334.93756 -309.261732) (xy 334.969104 -309.261256) (xy 335.004096 -309.261834) (xy 335.073421 -309.271427)
			(xy 335.140775 -309.290432) (xy 335.173066 -309.303928) (xy 335.184935 -309.308312) (xy 335.210115 -309.30619)
			(xy 335.221072 -309.299864) (xy 335.292192 -309.253382) (xy 335.302419 -309.245873) (xy 335.314551 -309.223628)
			(xy 335.315306 -309.210964) (xy 335.315306 -309.21071) (xy 335.315747 -309.179978) (xy 335.323155 -309.118961)
			(xy 335.337864 -309.059282) (xy 335.359659 -309.001811) (xy 335.388223 -308.947386) (xy 335.423139 -308.896802)
			(xy 335.463897 -308.850795) (xy 335.509905 -308.810036) (xy 335.56049 -308.775121) (xy 335.614915 -308.746557)
			(xy 335.672386 -308.724762) (xy 335.732065 -308.710054) (xy 335.793082 -308.702647) (xy 335.823814 -308.702202)
			(xy 335.824068 -308.702202) (xy 335.854441 -308.702636) (xy 335.914755 -308.709857) (xy 335.973777 -308.724223)
			(xy 336.002376 -308.73446) (xy 336.010708 -308.73723) (xy 336.028253 -308.737483) (xy 336.036666 -308.734968)
			(xy 336.06486 -308.725316) (xy 336.073047 -308.722122) (xy 336.08682 -308.71123) (xy 336.091784 -308.70398)
			(xy 336.10951 -308.676098) (xy 336.151114 -308.624769) (xy 336.199019 -308.579265) (xy 336.252418 -308.540353)
			(xy 336.310409 -308.50869) (xy 336.372014 -308.484809) (xy 336.436195 -308.469114) (xy 336.468974 -308.464966)
			(xy 336.477527 -308.463631) (xy 336.493109 -308.45612) (xy 336.499454 -308.450234) (xy 336.520536 -308.428898)
			(xy 336.526255 -308.422634) (xy 336.53352 -308.407317) (xy 336.53476 -308.398926) (xy 336.53864 -308.369149)
			(xy 336.554497 -308.311235) (xy 336.579231 -308.256519) (xy 336.612231 -308.206354) (xy 336.632042 -308.183788)
			(xy 336.638251 -308.176383) (xy 336.645087 -308.158322) (xy 336.644768 -308.139013) (xy 336.64144 -308.12994)
			(xy 336.606388 -308.045104) (xy 336.602255 -308.036402) (xy 336.588828 -308.022614) (xy 336.571277 -308.014719)
			(xy 336.561684 -308.013862) (xy 336.529231 -308.011815) (xy 336.465183 -308.00058) (xy 336.40309 -307.981274)
			(xy 336.343963 -307.954212) (xy 336.288767 -307.919836) (xy 336.238403 -307.878705) (xy 336.193691 -307.831491)
			(xy 336.155361 -307.778963) (xy 336.124038 -307.721979) (xy 336.100233 -307.661468) (xy 336.091784 -307.630068)
			(xy 336.088668 -307.619885) (xy 336.075625 -307.60309) (xy 336.056882 -307.593044) (xy 336.046318 -307.591714)
			(xy 336.014763 -307.588842) (xy 335.952666 -307.576231) (xy 335.892618 -307.556) (xy 335.835549 -307.528464)
			(xy 335.782345 -307.494049) (xy 335.73383 -307.453288) (xy 335.690757 -307.406815) (xy 335.653794 -307.355349)
			(xy 335.623512 -307.299689) (xy 335.600383 -307.240696) (xy 335.584764 -307.179287) (xy 335.576898 -307.116412)
			(xy 335.576418 -307.08473) (xy 335.576866 -307.053998) (xy 335.584272 -306.99298) (xy 335.598979 -306.933301)
			(xy 335.620772 -306.87583) (xy 335.649335 -306.821404) (xy 335.68425 -306.770819) (xy 335.725009 -306.724812)
			(xy 335.771016 -306.684053) (xy 335.821601 -306.649137) (xy 335.876026 -306.620574) (xy 335.933497 -306.59878)
			(xy 335.993176 -306.584072) (xy 336.054194 -306.576666) (xy 336.084926 -306.576222) (xy 336.115533 -306.57669)
			(xy 336.176303 -306.584063) (xy 336.235748 -306.598677) (xy 336.29301 -306.620319) (xy 336.34726 -306.648677)
			(xy 336.397715 -306.683341) (xy 336.443645 -306.723809) (xy 336.484387 -306.769497) (xy 336.519351 -306.819745)
			(xy 336.548031 -306.873825) (xy 336.570014 -306.930957) (xy 336.57794 -306.960524) (xy 336.581042 -306.970713)
			(xy 336.59409 -306.98751) (xy 336.61284 -306.997552) (xy 336.623406 -306.998878) (xy 336.644318 -307.000687)
			(xy 336.685773 -307.007296) (xy 336.70621 -307.012086) (xy 336.709004 -307.012594) (xy 336.719775 -307.014056)
			(xy 336.740851 -307.008829) (xy 336.757897 -306.995376) (xy 336.76788 -306.976092) (xy 336.769024 -306.954407)
			(xy 336.761124 -306.93418) (xy 336.753708 -306.926234) (xy 336.749898 -306.922932) (xy 336.724514 -306.902221)
			(xy 336.678772 -306.855319) (xy 336.639434 -306.802929) (xy 336.607153 -306.74592) (xy 336.582464 -306.685235)
			(xy 336.565776 -306.621882) (xy 336.557365 -306.556909) (xy 336.556858 -306.524152) (xy 336.55731 -306.493421)
			(xy 336.564724 -306.432408) (xy 336.579437 -306.372734) (xy 336.601234 -306.315268) (xy 336.6298 -306.260847)
			(xy 336.664715 -306.210267) (xy 336.705473 -306.164263) (xy 336.751478 -306.123507) (xy 336.802059 -306.088592)
			(xy 336.85648 -306.060029) (xy 336.913947 -306.038232) (xy 336.973622 -306.023521) (xy 337.034635 -306.01611)
			(xy 337.065366 -306.015644) (xy 337.096619 -306.016114) (xy 337.158653 -306.023783) (xy 337.219279 -306.038996)
			(xy 337.277584 -306.061525) (xy 337.332688 -306.09103) (xy 337.383761 -306.127066) (xy 337.430032 -306.16909)
			(xy 337.470804 -306.216468) (xy 337.48853 -306.242212) (xy 337.493803 -306.249464) (xy 337.508303 -306.259994)
			(xy 337.525543 -306.264886) (xy 337.534504 -306.264564) (xy 337.636612 -306.257198) (xy 337.659218 -306.241704)
			(xy 337.66506 -306.229258) (xy 337.679112 -306.200524) (xy 337.713341 -306.146488) (xy 337.754078 -306.097172)
			(xy 337.800679 -306.053356) (xy 337.852408 -306.015732) (xy 337.908448 -305.984893) (xy 337.967914 -305.961328)
			(xy 338.029866 -305.945409) (xy 338.093326 -305.937386) (xy 338.125308 -305.936904) (xy 338.156041 -305.93733)
			(xy 338.217058 -305.94474) (xy 338.276737 -305.959451) (xy 338.334208 -305.981248) (xy 338.388632 -306.009813)
			(xy 338.439217 -306.04473) (xy 338.485224 -306.08549) (xy 338.525982 -306.131499) (xy 338.560897 -306.182085)
			(xy 338.589461 -306.23651) (xy 338.611255 -306.293982) (xy 338.625964 -306.353662) (xy 338.633371 -306.414679)
			(xy 338.633816 -306.445412) (xy 338.63329 -306.47859) (xy 338.624658 -306.544382) (xy 338.607541 -306.608492)
			(xy 338.582231 -306.669831) (xy 338.549158 -306.727357) (xy 338.508884 -306.780093) (xy 338.462092 -306.827142)
			(xy 338.409578 -306.867705) (xy 338.352234 -306.901093) (xy 338.291035 -306.926739) (xy 338.22702 -306.944207)
			(xy 338.161276 -306.9532) (xy 338.128102 -306.95392) (xy 338.115629 -306.954663) (xy 338.093662 -306.966511)
			(xy 338.086192 -306.976526) (xy 338.032344 -307.057044) (xy 338.029804 -307.08219) (xy 338.03463 -307.093874)
			(xy 338.045381 -307.121376) (xy 338.061219 -307.178263) (xy 338.070372 -307.236601) (xy 338.071968 -307.266086)
			(xy 338.072743 -307.275619) (xy 338.080451 -307.293108) (xy 338.086954 -307.300122) (xy 338.12353 -307.336444)
			(xy 338.125308 -307.336444) (xy 338.152555 -307.337027) (xy 338.206495 -307.344783) (xy 338.258783 -307.360137)
			(xy 338.308353 -307.382776) (xy 338.354196 -307.412239) (xy 338.39538 -307.447926) (xy 338.431066 -307.48911)
			(xy 338.460528 -307.534955) (xy 338.464274 -307.543157) (xy 343.824808 -307.543157) (xy 343.824808 -307.479235)
			(xy 343.832819 -307.415817) (xy 343.848716 -307.353903) (xy 343.872248 -307.29447) (xy 343.903042 -307.238455)
			(xy 343.940615 -307.18674) (xy 343.984372 -307.140143) (xy 344.033625 -307.099398) (xy 344.087596 -307.065147)
			(xy 344.145435 -307.03793) (xy 344.206228 -307.018177) (xy 344.269018 -307.006199) (xy 344.332814 -307.002186)
			(xy 344.39661 -307.006199) (xy 344.4594 -307.018177) (xy 344.520193 -307.03793) (xy 344.578032 -307.065147)
			(xy 344.632003 -307.099398) (xy 344.681256 -307.140143) (xy 344.725013 -307.18674) (xy 344.762586 -307.238455)
			(xy 344.79338 -307.29447) (xy 344.816912 -307.353903) (xy 344.832809 -307.415817) (xy 344.84082 -307.479235)
			(xy 344.841322 -307.511196) (xy 344.84082 -307.543157) (xy 344.832809 -307.606575) (xy 344.816912 -307.668489)
			(xy 344.79338 -307.727922) (xy 344.762586 -307.783937) (xy 344.725013 -307.835652) (xy 344.681256 -307.882249)
			(xy 344.632003 -307.922994) (xy 344.578032 -307.957245) (xy 344.520193 -307.984462) (xy 344.4594 -308.004215)
			(xy 344.39661 -308.016193) (xy 344.332814 -308.020207) (xy 344.269018 -308.016193) (xy 344.206228 -308.004215)
			(xy 344.145435 -307.984462) (xy 344.087596 -307.957245) (xy 344.033625 -307.922994) (xy 343.984372 -307.882249)
			(xy 343.940615 -307.835652) (xy 343.903042 -307.783937) (xy 343.872248 -307.727922) (xy 343.848716 -307.668489)
			(xy 343.832819 -307.606575) (xy 343.824808 -307.543157) (xy 338.464274 -307.543157) (xy 338.483166 -307.584525)
			(xy 338.498519 -307.636812) (xy 338.506274 -307.690753) (xy 338.506274 -307.745247) (xy 338.498519 -307.799188)
			(xy 338.483166 -307.851475) (xy 338.460528 -307.901045) (xy 338.431066 -307.94689) (xy 338.39538 -307.988074)
			(xy 338.354196 -308.023761) (xy 338.308353 -308.053224) (xy 338.258783 -308.075863) (xy 338.206495 -308.091217)
			(xy 338.152555 -308.098973) (xy 338.125308 -308.09946) (xy 338.098454 -308.098958) (xy 338.045277 -308.091426)
			(xy 337.993681 -308.076512) (xy 337.944688 -308.054508) (xy 337.899264 -308.025851) (xy 337.858309 -307.991106)
			(xy 337.822631 -307.950961) (xy 337.792936 -307.906209) (xy 337.769811 -307.857734) (xy 337.761326 -307.832252)
			(xy 337.758161 -307.823418) (xy 337.746405 -307.808808) (xy 337.738466 -307.803804) (xy 337.711796 -307.788056)
			(xy 337.703331 -307.783555) (xy 337.684409 -307.780554) (xy 337.674966 -307.782214) (xy 337.647584 -307.788018)
			(xy 337.591956 -307.794251) (xy 337.563968 -307.79466) (xy 337.532396 -307.794194) (xy 337.469736 -307.786382)
			(xy 337.408527 -307.77087) (xy 337.34971 -307.747897) (xy 337.294191 -307.717816) (xy 337.242825 -307.681091)
			(xy 337.21929 -307.66004) (xy 337.209892 -307.651404) (xy 337.186016 -307.645054) (xy 337.079844 -307.66893)
			(xy 337.060794 -307.684932) (xy 337.056222 -307.696616) (xy 337.044755 -307.723791) (xy 337.016464 -307.775549)
			(xy 336.982372 -307.823684) (xy 336.942937 -307.867549) (xy 336.921094 -307.88737) (xy 336.914142 -307.89404)
			(xy 336.905375 -307.911176) (xy 336.903558 -307.930338) (xy 336.905854 -307.939694) (xy 336.931762 -308.027832)
			(xy 336.934847 -308.036921) (xy 336.946544 -308.052116) (xy 336.963006 -308.06195) (xy 336.972402 -308.0639)
			(xy 336.972656 -308.0639) (xy 336.999301 -308.068469) (xy 337.051011 -308.084241) (xy 337.099977 -308.107155)
			(xy 337.145217 -308.136752) (xy 337.185826 -308.17244) (xy 337.22099 -308.213504) (xy 337.250004 -308.25912)
			(xy 337.272288 -308.308376) (xy 337.287395 -308.360284) (xy 337.295022 -308.413805) (xy 337.29549 -308.440836)
			(xy 337.295021 -308.468432) (xy 337.28705 -308.523047) (xy 337.271295 -308.575943) (xy 337.248085 -308.626018)
			(xy 337.217902 -308.672227) (xy 337.181378 -308.713606) (xy 337.139274 -308.749292) (xy 337.092468 -308.77854)
			(xy 337.067398 -308.790086) (xy 337.059656 -308.793824) (xy 337.047054 -308.805499) (xy 337.04276 -308.812946)
			(xy 337.02879 -308.839362) (xy 337.025092 -308.847197) (xy 337.02262 -308.864332) (xy 337.023964 -308.87289)
			(xy 337.028378 -308.897031) (xy 337.033082 -308.945886) (xy 337.033362 -308.970426) (xy 337.032987 -309.00116)
			(xy 337.025574 -309.062181) (xy 337.01086 -309.121863) (xy 336.98906 -309.179336) (xy 336.96049 -309.233762)
			(xy 336.925568 -309.284348) (xy 336.908895 -309.303166) (xy 341.391494 -309.303166) (xy 341.392058 -309.26821)
			(xy 341.401624 -309.198956) (xy 341.420585 -309.131665) (xy 341.448584 -309.067605) (xy 341.485093 -309.007984)
			(xy 341.50681 -308.980586) (xy 341.512055 -308.973646) (xy 341.517896 -308.957274) (xy 341.51824 -308.948582)
			(xy 341.51824 -308.79415) (xy 341.517853 -308.785467) (xy 341.512013 -308.769108) (xy 341.50681 -308.762146)
			(xy 341.48512 -308.73473) (xy 341.448618 -308.675109) (xy 341.420621 -308.611053) (xy 341.401655 -308.543768)
			(xy 341.392077 -308.47452) (xy 341.391494 -308.439566) (xy 341.391924 -308.408834) (xy 341.399336 -308.347819)
			(xy 341.414049 -308.288142) (xy 341.435847 -308.230674) (xy 341.464413 -308.176252) (xy 341.499331 -308.12567)
			(xy 341.54009 -308.079665) (xy 341.586098 -308.038909) (xy 341.636683 -308.003995) (xy 341.691107 -307.975432)
			(xy 341.748577 -307.953638) (xy 341.808255 -307.93893) (xy 341.86927 -307.931521) (xy 341.900002 -307.931058)
			(xy 341.931057 -307.931519) (xy 341.992704 -307.939091) (xy 342.052965 -307.954134) (xy 342.08212 -307.96484)
			(xy 342.09101 -307.968142) (xy 342.109298 -307.968142) (xy 342.190578 -307.937408) (xy 342.204294 -307.924962)
			(xy 342.208612 -307.916834) (xy 342.221035 -307.893937) (xy 342.251095 -307.851394) (xy 342.286665 -307.813337)
			(xy 342.327083 -307.780476) (xy 342.371598 -307.753421) (xy 342.41938 -307.732677) (xy 342.469542 -307.718629)
			(xy 342.521148 -307.711538) (xy 342.547194 -307.711094) (xy 342.574447 -307.711553) (xy 342.628399 -307.719309)
			(xy 342.680698 -307.734665) (xy 342.730279 -307.757307) (xy 342.776133 -307.786775) (xy 342.817327 -307.822469)
			(xy 342.853021 -307.863662) (xy 342.88249 -307.909516) (xy 342.905133 -307.959096) (xy 342.920489 -308.011395)
			(xy 342.928247 -308.065347) (xy 342.928247 -308.119853) (xy 342.920489 -308.173805) (xy 342.905133 -308.226104)
			(xy 342.88249 -308.275684) (xy 342.853021 -308.321538) (xy 342.817327 -308.362731) (xy 342.776133 -308.398425)
			(xy 342.730279 -308.427893) (xy 342.680698 -308.450535) (xy 342.628399 -308.465891) (xy 342.574447 -308.473647)
			(xy 342.547194 -308.47411) (xy 342.536949 -308.474015) (xy 342.516491 -308.472873) (xy 342.5063 -308.471824)
			(xy 342.497024 -308.471242) (xy 342.479052 -308.475921) (xy 342.471248 -308.480968) (xy 342.408764 -308.525926)
			(xy 342.39835 -308.541674) (xy 342.396318 -308.550818) (xy 342.389409 -308.579675) (xy 342.369756 -308.635667)
			(xy 342.343732 -308.688996) (xy 342.311687 -308.738941) (xy 342.293194 -308.762146) (xy 342.287978 -308.769105)
			(xy 342.282119 -308.785462) (xy 342.281764 -308.79415) (xy 342.281764 -308.948582) (xy 342.282156 -308.957264)
			(xy 342.287995 -308.973622) (xy 342.293194 -308.980586) (xy 342.312082 -309.004341) (xy 342.344682 -309.055532)
			(xy 342.358218 -309.082694) (xy 342.362401 -309.090642) (xy 342.375295 -309.103131) (xy 342.383364 -309.107078)
			(xy 342.41105 -309.119524) (xy 342.419218 -309.122825) (xy 342.436776 -309.124131) (xy 342.44534 -309.122064)
			(xy 342.470303 -309.11557) (xy 342.521404 -309.108557) (xy 342.547194 -309.108094) (xy 342.574447 -309.108553)
			(xy 342.628399 -309.116309) (xy 342.680698 -309.131665) (xy 342.730279 -309.154307) (xy 342.776133 -309.183775)
			(xy 342.817327 -309.219469) (xy 342.853021 -309.260662) (xy 342.88249 -309.306516) (xy 342.905133 -309.356096)
			(xy 342.920489 -309.408395) (xy 342.928247 -309.462347) (xy 342.928247 -309.516853) (xy 342.920489 -309.570805)
			(xy 342.905133 -309.623104) (xy 342.88249 -309.672684) (xy 342.853021 -309.718538) (xy 342.817327 -309.759731)
			(xy 342.776133 -309.795425) (xy 342.730279 -309.824893) (xy 342.680698 -309.847535) (xy 342.628399 -309.862891)
			(xy 342.574447 -309.870647) (xy 342.547194 -309.87111) (xy 342.520745 -309.870648) (xy 342.468354 -309.863351)
			(xy 342.417474 -309.848884) (xy 342.369081 -309.827524) (xy 342.324104 -309.799682) (xy 342.283406 -309.765891)
			(xy 342.265254 -309.74665) (xy 342.259042 -309.740362) (xy 342.243456 -309.73205) (xy 342.234774 -309.730394)
			(xy 342.205056 -309.72633) (xy 342.196131 -309.725354) (xy 342.178563 -309.728992) (xy 342.170766 -309.733442)
			(xy 342.140214 -309.751945) (xy 342.075047 -309.781182) (xy 342.006431 -309.801013) (xy 341.935714 -309.811048)
			(xy 341.900002 -309.811674) (xy 341.869269 -309.81126) (xy 341.80825 -309.803851) (xy 341.74857 -309.789141)
			(xy 341.691097 -309.767344) (xy 341.636672 -309.738778) (xy 341.586086 -309.70386) (xy 341.540079 -309.663098)
			(xy 341.499321 -309.617088) (xy 341.464406 -309.566501) (xy 341.435843 -309.512073) (xy 341.41405 -309.4546)
			(xy 341.399343 -309.394918) (xy 341.391938 -309.333899) (xy 341.391494 -309.303166) (xy 336.908895 -309.303166)
			(xy 336.884804 -309.330355) (xy 336.838791 -309.371113) (xy 336.7882 -309.406027) (xy 336.73377 -309.434589)
			(xy 336.676294 -309.456382) (xy 336.61661 -309.471087) (xy 336.555588 -309.478491) (xy 336.524854 -309.478934)
			(xy 336.5246 -309.478934) (xy 336.494227 -309.478514) (xy 336.433912 -309.471288) (xy 336.37489 -309.456916)
			(xy 336.346292 -309.446676) (xy 336.33795 -309.443942) (xy 336.320415 -309.443668) (xy 336.312002 -309.446168)
			(xy 336.283808 -309.45582) (xy 336.275611 -309.458992) (xy 336.261843 -309.469899) (xy 336.256884 -309.477156)
			(xy 336.239492 -309.504503) (xy 336.198801 -309.554947) (xy 336.152028 -309.599811) (xy 336.099932 -309.638364)
			(xy 336.043358 -309.669983) (xy 335.983224 -309.694155) (xy 335.920505 -309.710487) (xy 335.856219 -309.718714)
			(xy 335.823814 -309.719218) (xy 335.788822 -309.718636) (xy 335.719498 -309.709045) (xy 335.652143 -309.690041)
			(xy 335.619852 -309.676546) (xy 335.607981 -309.672166) (xy 335.582801 -309.674282) (xy 335.571846 -309.68061)
			(xy 335.500726 -309.727092) (xy 335.490469 -309.734568) (xy 335.478352 -309.756838) (xy 335.477612 -309.76951)
			(xy 335.477612 -309.769764) (xy 335.47717 -309.801308) (xy 335.469371 -309.863911) (xy 335.453888 -309.92507)
			(xy 335.430959 -309.983843) (xy 335.400936 -310.039329) (xy 335.364281 -310.090675) (xy 335.321555 -310.137092)
			(xy 335.273417 -310.177868) (xy 335.220604 -310.212377) (xy 335.163928 -310.240088) (xy 335.104259 -310.260575)
			(xy 335.042515 -310.273525) (xy 334.979643 -310.278737) (xy 334.916609 -310.276133) (xy 334.854382 -310.265752)
			(xy 334.793916 -310.247753) (xy 334.736141 -310.222413) (xy 334.681945 -310.190121) (xy 334.632158 -310.151374)
			(xy 334.587547 -310.106766) (xy 334.548797 -310.056982) (xy 334.516502 -310.002787) (xy 334.491158 -309.945014)
			(xy 334.473156 -309.884549) (xy 334.46277 -309.822322) (xy 334.460162 -309.759289) (xy 333.506735 -309.759289)
			(xy 333.524052 -309.773615) (xy 333.567809 -309.820212) (xy 333.605382 -309.871927) (xy 333.636176 -309.927942)
			(xy 333.659708 -309.987375) (xy 333.675605 -310.049289) (xy 333.683616 -310.112707) (xy 333.684118 -310.144668)
			(xy 333.683616 -310.176629) (xy 333.675605 -310.240047) (xy 333.659708 -310.301961) (xy 333.636176 -310.361394)
			(xy 333.605382 -310.417409) (xy 333.597591 -310.428132) (xy 337.30514 -310.428132) (xy 337.309211 -310.37251)
			(xy 337.321337 -310.318073) (xy 337.34126 -310.265982) (xy 337.368556 -310.217347) (xy 337.402642 -310.173204)
			(xy 337.442791 -310.134495) (xy 337.488149 -310.102044) (xy 337.537749 -310.076543) (xy 337.590533 -310.058536)
			(xy 337.645376 -310.048406) (xy 337.70111 -310.046369) (xy 337.756547 -310.052469) (xy 337.810504 -310.066575)
			(xy 337.861833 -310.088387) (xy 337.909439 -310.117441) (xy 337.952307 -310.153116) (xy 337.989524 -310.194653)
			(xy 338.020297 -310.241166) (xy 338.043969 -310.291663) (xy 338.060037 -310.34507) (xy 338.068157 -310.400246)
			(xy 338.068665 -310.4281) (xy 338.321221 -310.4281) (xy 338.325235 -310.364311) (xy 338.33721 -310.301529)
			(xy 338.35696 -310.240742) (xy 338.384172 -310.18291) (xy 338.418418 -310.128944) (xy 338.459157 -310.079695)
			(xy 338.505747 -310.03594) (xy 338.557453 -309.99837) (xy 338.61346 -309.967575) (xy 338.672885 -309.944043)
			(xy 338.734791 -309.928144) (xy 338.798201 -309.920128) (xy 338.830158 -309.919624) (xy 338.860799 -309.920055)
			(xy 338.921636 -309.92743) (xy 338.981144 -309.942067) (xy 339.038462 -309.963751) (xy 339.092756 -309.99217)
			(xy 339.143239 -310.026911) (xy 339.18918 -310.067469) (xy 339.209888 -310.090058) (xy 339.210142 -310.090312)
			(xy 339.216542 -310.096765) (xy 339.232669 -310.105109) (xy 339.241638 -310.106568) (xy 339.318346 -310.115458)
			(xy 339.33638 -310.110886) (xy 339.344 -310.105552) (xy 339.368184 -310.089318) (xy 339.420443 -310.063598)
			(xy 339.476002 -310.046113) (xy 339.533571 -310.037267) (xy 339.562694 -310.036718) (xy 339.589949 -310.037128)
			(xy 339.643904 -310.044885) (xy 339.696207 -310.060242) (xy 339.745791 -310.082886) (xy 339.791648 -310.112355)
			(xy 339.832844 -310.148052) (xy 339.868541 -310.189247) (xy 339.898012 -310.235104) (xy 339.920656 -310.284688)
			(xy 339.936013 -310.33699) (xy 339.943771 -310.390945) (xy 339.943771 -310.445455) (xy 339.936013 -310.49941)
			(xy 339.920656 -310.551712) (xy 339.898012 -310.601296) (xy 339.868541 -310.647153) (xy 339.832844 -310.688348)
			(xy 339.791648 -310.724045) (xy 339.745791 -310.753514) (xy 339.696207 -310.776158) (xy 339.643904 -310.791515)
			(xy 339.589949 -310.799272) (xy 339.562694 -310.799734) (xy 339.534878 -310.799218) (xy 339.479835 -310.791143)
			(xy 339.426546 -310.775167) (xy 339.376141 -310.751626) (xy 339.352636 -310.736742) (xy 339.352382 -310.736488)
			(xy 339.344452 -310.731821) (xy 339.326483 -310.727922) (xy 339.31733 -310.728868) (xy 339.241384 -310.739536)
			(xy 339.225128 -310.74868) (xy 339.219032 -310.756046) (xy 339.198257 -310.779871) (xy 339.151827 -310.822768)
			(xy 339.100437 -310.859578) (xy 339.04488 -310.889732) (xy 338.986012 -310.912764) (xy 338.924743 -310.92832)
			(xy 338.862018 -310.936159) (xy 338.830412 -310.93664) (xy 338.830158 -310.93664) (xy 338.798201 -310.936072)
			(xy 338.734791 -310.928056) (xy 338.672885 -310.912157) (xy 338.61346 -310.888625) (xy 338.557453 -310.85783)
			(xy 338.505747 -310.82026) (xy 338.459157 -310.776505) (xy 338.418418 -310.727256) (xy 338.384172 -310.67329)
			(xy 338.35696 -310.615458) (xy 338.33721 -310.554671) (xy 338.325235 -310.491889) (xy 338.321221 -310.4281)
			(xy 338.068665 -310.4281) (xy 338.068666 -310.428132) (xy 338.068157 -310.456018) (xy 338.060037 -310.511194)
			(xy 338.043969 -310.564601) (xy 338.020297 -310.615098) (xy 337.989524 -310.661611) (xy 337.952307 -310.703148)
			(xy 337.909439 -310.738823) (xy 337.861833 -310.767877) (xy 337.810504 -310.789689) (xy 337.756547 -310.803795)
			(xy 337.70111 -310.809895) (xy 337.645376 -310.807858) (xy 337.590533 -310.797728) (xy 337.537749 -310.779721)
			(xy 337.488149 -310.75422) (xy 337.442791 -310.721769) (xy 337.402642 -310.68306) (xy 337.368556 -310.638917)
			(xy 337.34126 -310.590282) (xy 337.321337 -310.538191) (xy 337.309211 -310.483754) (xy 337.30514 -310.428132)
			(xy 333.597591 -310.428132) (xy 333.567809 -310.469124) (xy 333.524052 -310.515721) (xy 333.474799 -310.556466)
			(xy 333.420828 -310.590717) (xy 333.362989 -310.617934) (xy 333.302196 -310.637687) (xy 333.239406 -310.649665)
			(xy 333.17561 -310.653679) (xy 333.111814 -310.649665) (xy 333.049024 -310.637687) (xy 332.988231 -310.617934)
			(xy 332.930392 -310.590717) (xy 332.876421 -310.556466) (xy 332.827168 -310.515721) (xy 332.783411 -310.469124)
			(xy 332.745838 -310.417409) (xy 332.715044 -310.361394) (xy 332.691512 -310.301961) (xy 332.675615 -310.240047)
			(xy 332.667604 -310.176629) (xy 316.940549 -310.176629) (xy 311.867296 -315.249814) (xy 311.860739 -315.257062)
			(xy 311.853276 -315.275104) (xy 311.852818 -315.284866) (xy 311.852818 -316.323218) (xy 311.852292 -316.33306)
			(xy 311.84472 -316.351236) (xy 311.838086 -316.358524) (xy 308.06517 -320.13144) (xy 308.05793 -320.138147)
			(xy 308.039725 -320.14573) (xy 308.029864 -320.146172) (xy 271.751552 -320.146172) (xy 271.746659 -320.14606)
			(xy 271.737065 -320.144133) (xy 271.732502 -320.142362) (xy 271.723358 -320.138552) (xy 269.76832 -320.138552)
			(xy 269.764312 -320.13862) (xy 269.756398 -320.139897) (xy 269.752572 -320.141092) (xy 269.746989 -320.143095)
			(xy 269.736849 -320.149244) (xy 269.732506 -320.153284) (xy 268.939264 -320.946526) (xy 268.932701 -320.953771)
			(xy 268.925232 -320.971814) (xy 268.924786 -320.981578) (xy 268.924786 -321.815968) (xy 268.924682 -321.820863)
			(xy 268.92277 -321.830463) (xy 268.920976 -321.835018) (xy 268.91361 -321.852544) (xy 268.910308 -321.86626)
			(xy 268.910054 -321.87134) (xy 268.910054 -322.376292) (xy 315.288168 -322.376292) (xy 315.288168 -322.376038)
			(xy 315.288614 -322.345317) (xy 315.29602 -322.284322) (xy 315.310717 -322.224664) (xy 315.332491 -322.167209)
			(xy 315.361025 -322.112794) (xy 315.378084 -322.08724) (xy 315.383446 -322.078539) (xy 315.38752 -322.058532)
			(xy 315.383471 -322.03852) (xy 315.378084 -322.029836) (xy 315.36106 -322.00426) (xy 315.332525 -321.949849)
			(xy 315.310751 -321.892398) (xy 315.296055 -321.832742) (xy 315.288651 -321.771751) (xy 315.288647 -321.710312)
			(xy 315.296044 -321.649319) (xy 315.310732 -321.589662) (xy 315.332499 -321.532208) (xy 315.361027 -321.477794)
			(xy 315.378084 -321.45224) (xy 315.383446 -321.443539) (xy 315.38752 -321.423532) (xy 315.383471 -321.40352)
			(xy 315.378084 -321.394836) (xy 315.36106 -321.36926) (xy 315.332525 -321.314849) (xy 315.310751 -321.257398)
			(xy 315.296055 -321.197742) (xy 315.288651 -321.136751) (xy 315.288647 -321.075312) (xy 315.296044 -321.014319)
			(xy 315.310732 -320.954662) (xy 315.332499 -320.897208) (xy 315.361027 -320.842794) (xy 315.378084 -320.81724)
			(xy 315.383446 -320.808539) (xy 315.38752 -320.788532) (xy 315.383471 -320.76852) (xy 315.378084 -320.759836)
			(xy 315.361044 -320.73427) (xy 315.332508 -320.679859) (xy 315.310734 -320.622407) (xy 315.296037 -320.56275)
			(xy 315.288633 -320.501758) (xy 315.288168 -320.471038) (xy 315.288673 -320.440308) (xy 315.296077 -320.379294)
			(xy 315.310781 -320.319619) (xy 315.332572 -320.26215) (xy 315.36113 -320.207728) (xy 315.396041 -320.157144)
			(xy 315.436794 -320.111138) (xy 315.482796 -320.070379) (xy 315.533375 -320.035462) (xy 315.587794 -320.006897)
			(xy 315.645259 -319.9851) (xy 315.704933 -319.970388) (xy 315.765946 -319.962977) (xy 315.796676 -319.96253)
			(xy 315.817758 -319.963038) (xy 315.818012 -319.963038) (xy 315.828445 -319.962885) (xy 315.847853 -319.955289)
			(xy 315.855604 -319.948306) (xy 315.908944 -319.894966) (xy 315.915954 -319.887233) (xy 315.923549 -319.867812)
			(xy 315.923676 -319.857374) (xy 315.923676 -319.856866) (xy 315.923168 -319.836038) (xy 315.923673 -319.805308)
			(xy 315.931077 -319.744294) (xy 315.945781 -319.684619) (xy 315.967572 -319.62715) (xy 315.99613 -319.572728)
			(xy 316.031041 -319.522144) (xy 316.071794 -319.476138) (xy 316.117796 -319.435379) (xy 316.168375 -319.400462)
			(xy 316.222794 -319.371897) (xy 316.280259 -319.3501) (xy 316.339933 -319.335388) (xy 316.400946 -319.327977)
			(xy 316.431676 -319.32753) (xy 316.452758 -319.328038) (xy 316.453012 -319.328038) (xy 316.463445 -319.327885)
			(xy 316.482853 -319.320289) (xy 316.490604 -319.313306) (xy 316.543944 -319.259966) (xy 316.550954 -319.252233)
			(xy 316.558549 -319.232812) (xy 316.558676 -319.222374) (xy 316.558676 -319.221866) (xy 316.558168 -319.201038)
			(xy 316.55867 -319.169077) (xy 316.566681 -319.105659) (xy 316.582578 -319.043745) (xy 316.60611 -318.984312)
			(xy 316.636904 -318.928297) (xy 316.674477 -318.876582) (xy 316.718234 -318.829985) (xy 316.767487 -318.78924)
			(xy 316.821458 -318.754989) (xy 316.879297 -318.727772) (xy 316.94009 -318.708019) (xy 317.00288 -318.696041)
			(xy 317.066676 -318.692028) (xy 317.130472 -318.696041) (xy 317.193262 -318.708019) (xy 317.254055 -318.727772)
			(xy 317.311894 -318.754989) (xy 317.365865 -318.78924) (xy 317.415118 -318.829985) (xy 317.458875 -318.876582)
			(xy 317.496448 -318.928297) (xy 317.527242 -318.984312) (xy 317.550774 -319.043745) (xy 317.566671 -319.105659)
			(xy 317.574682 -319.169077) (xy 317.575184 -319.201038) (xy 317.574734 -319.231759) (xy 317.56733 -319.292754)
			(xy 317.552635 -319.352413) (xy 317.530861 -319.409868) (xy 317.502327 -319.464282) (xy 317.485268 -319.489836)
			(xy 317.479845 -319.498504) (xy 317.475796 -319.518532) (xy 317.47987 -319.538554) (xy 317.485268 -319.54724)
			(xy 317.502335 -319.572788) (xy 317.530867 -319.627204) (xy 317.552637 -319.684661) (xy 317.567327 -319.744321)
			(xy 317.574724 -319.805317) (xy 317.575184 -319.836038) (xy 317.574771 -319.864993) (xy 317.568177 -319.922527)
			(xy 317.555088 -319.978939) (xy 317.535675 -320.033498) (xy 317.51019 -320.085499) (xy 317.49492 -320.110104)
			(xy 317.489699 -320.119082) (xy 317.486334 -320.139561) (xy 317.491326 -320.159706) (xy 317.497206 -320.16827)
			(xy 317.516735 -320.194863) (xy 317.549473 -320.252146) (xy 317.574528 -320.313183) (xy 317.59148 -320.376946)
			(xy 317.600044 -320.442367) (xy 317.600584 -320.475356) (xy 317.600584 -320.47561) (xy 317.60012 -320.506331)
			(xy 317.59272 -320.567325) (xy 317.578027 -320.626984) (xy 317.556257 -320.684439) (xy 317.527726 -320.738854)
			(xy 317.510668 -320.764408) (xy 317.505269 -320.773089) (xy 317.501213 -320.793108) (xy 317.505275 -320.813126)
			(xy 317.510668 -320.821812) (xy 317.527734 -320.84736) (xy 317.556264 -320.901777) (xy 317.578032 -320.959233)
			(xy 317.592723 -321.018893) (xy 317.600121 -321.079887) (xy 317.60012 -321.141329) (xy 317.59272 -321.202324)
			(xy 317.578027 -321.261983) (xy 317.556257 -321.319438) (xy 317.527726 -321.373854) (xy 317.510668 -321.399408)
			(xy 317.505269 -321.408089) (xy 317.501213 -321.428108) (xy 317.505275 -321.448126) (xy 317.510668 -321.456812)
			(xy 317.527734 -321.48236) (xy 317.556264 -321.536777) (xy 317.578032 -321.594233) (xy 317.592723 -321.653893)
			(xy 317.600121 -321.714887) (xy 317.60012 -321.776329) (xy 317.59272 -321.837324) (xy 317.578027 -321.896983)
			(xy 317.556257 -321.954438) (xy 317.527726 -322.008854) (xy 317.510668 -322.034408) (xy 317.505269 -322.043089)
			(xy 317.501213 -322.063108) (xy 317.505275 -322.083126) (xy 317.510668 -322.091812) (xy 317.527723 -322.117368)
			(xy 317.556257 -322.171782) (xy 317.578029 -322.229236) (xy 317.592722 -322.288895) (xy 317.600122 -322.349889)
			(xy 317.600584 -322.38061) (xy 317.600584 -322.380864) (xy 317.600094 -322.413847) (xy 317.591586 -322.47926)
			(xy 317.574683 -322.543022) (xy 317.549668 -322.60406) (xy 317.516963 -322.661347) (xy 317.49746 -322.68795)
			(xy 317.491574 -322.696564) (xy 317.48665 -322.716818) (xy 317.49016 -322.737364) (xy 317.495428 -322.74637)
			(xy 317.511292 -322.771279) (xy 317.537742 -322.824084) (xy 317.557896 -322.879597) (xy 317.571482 -322.937071)
			(xy 317.578317 -322.995733) (xy 317.57874 -323.025262) (xy 317.57874 -323.025516) (xy 319.304924 -323.025516)
			(xy 319.304924 -323.025262) (xy 319.305426 -322.99228) (xy 319.313931 -322.926867) (xy 319.330832 -322.863104)
			(xy 319.355843 -322.802066) (xy 319.388546 -322.744779) (xy 319.408048 -322.718176) (xy 319.413912 -322.709549)
			(xy 319.418842 -322.689303) (xy 319.415342 -322.668762) (xy 319.41008 -322.659756) (xy 319.394228 -322.63484)
			(xy 319.367776 -322.582037) (xy 319.34762 -322.526526) (xy 319.334031 -322.469053) (xy 319.327192 -322.410393)
			(xy 319.326768 -322.380864) (xy 319.326768 -322.38061) (xy 319.32725 -322.34989) (xy 319.334648 -322.288897)
			(xy 319.349336 -322.229239) (xy 319.371102 -322.171783) (xy 319.399629 -322.117367) (xy 319.416684 -322.091812)
			(xy 319.42207 -322.083123) (xy 319.426136 -322.063108) (xy 319.422077 -322.043092) (xy 319.416684 -322.034408)
			(xy 319.399634 -322.008849) (xy 319.371101 -321.954435) (xy 319.349329 -321.896981) (xy 319.334635 -321.837322)
			(xy 319.327234 -321.776329) (xy 319.327233 -321.714888) (xy 319.334632 -321.653894) (xy 319.349324 -321.594235)
			(xy 319.371094 -321.53678) (xy 319.399626 -321.482366) (xy 319.416684 -321.456812) (xy 319.42207 -321.448123)
			(xy 319.426136 -321.428108) (xy 319.422077 -321.408092) (xy 319.416684 -321.399408) (xy 319.399634 -321.373849)
			(xy 319.371101 -321.319435) (xy 319.349329 -321.261981) (xy 319.334635 -321.202322) (xy 319.327234 -321.141329)
			(xy 319.327233 -321.079888) (xy 319.334632 -321.018894) (xy 319.349324 -320.959235) (xy 319.371094 -320.90178)
			(xy 319.399626 -320.847366) (xy 319.416684 -320.821812) (xy 319.42207 -320.813123) (xy 319.426136 -320.793108)
			(xy 319.422077 -320.773092) (xy 319.416684 -320.764408) (xy 319.399632 -320.73885) (xy 319.371098 -320.684437)
			(xy 319.349326 -320.626982) (xy 319.334632 -320.567324) (xy 319.327231 -320.506331) (xy 319.326768 -320.47561)
			(xy 319.326768 -320.475356) (xy 319.32723 -320.444416) (xy 319.334733 -320.382994) (xy 319.349636 -320.322936)
			(xy 319.371717 -320.265131) (xy 319.400651 -320.210433) (xy 319.417954 -320.18478) (xy 319.423426 -320.176024)
			(xy 319.427583 -320.15582) (xy 319.423442 -320.135613) (xy 319.417954 -320.126868) (xy 319.400641 -320.101222)
			(xy 319.371713 -320.04652) (xy 319.349634 -319.988713) (xy 319.334731 -319.928655) (xy 319.327225 -319.867232)
			(xy 319.326768 -319.836292) (xy 319.326768 -319.836038) (xy 319.327214 -319.805317) (xy 319.33462 -319.744322)
			(xy 319.349317 -319.684664) (xy 319.371091 -319.627209) (xy 319.399625 -319.572794) (xy 319.416684 -319.54724)
			(xy 319.422046 -319.538539) (xy 319.42612 -319.518532) (xy 319.422071 -319.49852) (xy 319.416684 -319.489836)
			(xy 319.39966 -319.46426) (xy 319.371125 -319.409849) (xy 319.349351 -319.352398) (xy 319.334655 -319.292742)
			(xy 319.327251 -319.231751) (xy 319.327247 -319.170312) (xy 319.334644 -319.109319) (xy 319.349332 -319.049662)
			(xy 319.371099 -318.992208) (xy 319.399627 -318.937794) (xy 319.416684 -318.91224) (xy 319.422046 -318.903539)
			(xy 319.42612 -318.883532) (xy 319.422071 -318.86352) (xy 319.416684 -318.854836) (xy 319.39966 -318.82926)
			(xy 319.371125 -318.774849) (xy 319.349351 -318.717398) (xy 319.334655 -318.657742) (xy 319.327251 -318.596751)
			(xy 319.327247 -318.535312) (xy 319.334644 -318.474319) (xy 319.349332 -318.414662) (xy 319.371099 -318.357208)
			(xy 319.399627 -318.302794) (xy 319.416684 -318.27724) (xy 319.422046 -318.268539) (xy 319.42612 -318.248532)
			(xy 319.422071 -318.22852) (xy 319.416684 -318.219836) (xy 319.39966 -318.19426) (xy 319.371125 -318.139849)
			(xy 319.349351 -318.082398) (xy 319.334655 -318.022742) (xy 319.327251 -317.961751) (xy 319.327247 -317.900312)
			(xy 319.334644 -317.839319) (xy 319.349332 -317.779662) (xy 319.371099 -317.722208) (xy 319.399627 -317.667794)
			(xy 319.416684 -317.64224) (xy 319.422046 -317.633539) (xy 319.42612 -317.613532) (xy 319.422071 -317.59352)
			(xy 319.416684 -317.584836) (xy 319.39966 -317.55926) (xy 319.371125 -317.504849) (xy 319.349351 -317.447398)
			(xy 319.334655 -317.387742) (xy 319.327251 -317.326751) (xy 319.327247 -317.265312) (xy 319.334644 -317.204319)
			(xy 319.349332 -317.144662) (xy 319.371099 -317.087208) (xy 319.399627 -317.032794) (xy 319.416684 -317.00724)
			(xy 319.422046 -316.998539) (xy 319.42612 -316.978532) (xy 319.422071 -316.95852) (xy 319.416684 -316.949836)
			(xy 319.399644 -316.92427) (xy 319.371108 -316.869859) (xy 319.349334 -316.812407) (xy 319.334637 -316.75275)
			(xy 319.327233 -316.691758) (xy 319.326768 -316.661038) (xy 319.327273 -316.630308) (xy 319.334677 -316.569294)
			(xy 319.349381 -316.509619) (xy 319.371172 -316.45215) (xy 319.39973 -316.397728) (xy 319.434641 -316.347144)
			(xy 319.475394 -316.301138) (xy 319.521396 -316.260379) (xy 319.571975 -316.225462) (xy 319.626394 -316.196897)
			(xy 319.683859 -316.1751) (xy 319.743533 -316.160388) (xy 319.804546 -316.152977) (xy 319.835276 -316.15253)
			(xy 319.865996 -316.153009) (xy 319.92699 -316.160405) (xy 319.986649 -316.175094) (xy 320.044104 -316.196861)
			(xy 320.09852 -316.22539) (xy 320.124074 -316.242446) (xy 320.132759 -316.247839) (xy 320.152776 -316.2519)
			(xy 320.172793 -316.247839) (xy 320.181478 -316.242446) (xy 320.207032 -316.225388) (xy 320.261447 -316.196857)
			(xy 320.318902 -316.175086) (xy 320.378561 -316.160394) (xy 320.439555 -316.152994) (xy 320.500997 -316.152994)
			(xy 320.561991 -316.160394) (xy 320.62165 -316.175086) (xy 320.679105 -316.196857) (xy 320.73352 -316.225388)
			(xy 320.759074 -316.242446) (xy 320.767759 -316.247839) (xy 320.787776 -316.2519) (xy 320.807793 -316.247839)
			(xy 320.816478 -316.242446) (xy 320.842037 -316.225395) (xy 320.89645 -316.196863) (xy 320.953904 -316.175091)
			(xy 321.013562 -316.160396) (xy 321.074556 -316.152994) (xy 321.105276 -316.15253) (xy 321.136009 -316.15296)
			(xy 321.197027 -316.160367) (xy 321.256708 -316.175075) (xy 321.31418 -316.19687) (xy 321.368606 -316.225434)
			(xy 321.419191 -316.260351) (xy 321.465199 -316.301111) (xy 321.505958 -316.34712) (xy 321.540873 -316.397706)
			(xy 321.569436 -316.452133) (xy 321.591229 -316.509606) (xy 321.605936 -316.569287) (xy 321.613341 -316.630305)
			(xy 321.613784 -316.661038) (xy 321.613334 -316.691759) (xy 321.60593 -316.752754) (xy 321.591235 -316.812413)
			(xy 321.569461 -316.869868) (xy 321.540927 -316.924282) (xy 321.523868 -316.949836) (xy 321.518445 -316.958504)
			(xy 321.514396 -316.978532) (xy 321.51847 -316.998554) (xy 321.523868 -317.00724) (xy 321.54096 -317.032772)
			(xy 321.569488 -317.087191) (xy 321.591254 -317.14465) (xy 321.605943 -317.204313) (xy 321.613339 -317.265309)
			(xy 321.613335 -317.326753) (xy 321.605931 -317.387749) (xy 321.591236 -317.447409) (xy 321.569462 -317.504866)
			(xy 321.540927 -317.559282) (xy 321.523868 -317.584836) (xy 321.518445 -317.593504) (xy 321.514396 -317.613532)
			(xy 321.51847 -317.633554) (xy 321.523868 -317.64224) (xy 321.54096 -317.667772) (xy 321.569488 -317.722191)
			(xy 321.591254 -317.77965) (xy 321.605943 -317.839313) (xy 321.613339 -317.900309) (xy 321.613335 -317.961753)
			(xy 321.605931 -318.022749) (xy 321.591236 -318.082409) (xy 321.569462 -318.139866) (xy 321.540927 -318.194282)
			(xy 321.523868 -318.219836) (xy 321.518445 -318.228504) (xy 321.514396 -318.248532) (xy 321.51847 -318.268554)
			(xy 321.523868 -318.27724) (xy 321.54096 -318.302772) (xy 321.569488 -318.357191) (xy 321.591254 -318.41465)
			(xy 321.605943 -318.474313) (xy 321.613339 -318.535309) (xy 321.613335 -318.596753) (xy 321.605931 -318.657749)
			(xy 321.591236 -318.717409) (xy 321.569462 -318.774866) (xy 321.540927 -318.829282) (xy 321.523868 -318.854836)
			(xy 321.518445 -318.863504) (xy 321.514396 -318.883532) (xy 321.51847 -318.903554) (xy 321.523868 -318.91224)
			(xy 321.54096 -318.937772) (xy 321.569488 -318.992191) (xy 321.591254 -319.04965) (xy 321.605943 -319.109313)
			(xy 321.613339 -319.170309) (xy 321.613335 -319.231753) (xy 321.605931 -319.292749) (xy 321.591236 -319.352409)
			(xy 321.569462 -319.409866) (xy 321.540927 -319.464282) (xy 321.523868 -319.489836) (xy 321.518445 -319.498504)
			(xy 321.514396 -319.518532) (xy 321.51847 -319.538554) (xy 321.523868 -319.54724) (xy 321.54096 -319.572772)
			(xy 321.569488 -319.627191) (xy 321.591254 -319.68465) (xy 321.605943 -319.744313) (xy 321.613339 -319.805309)
			(xy 321.613335 -319.866753) (xy 321.605931 -319.927749) (xy 321.591236 -319.987409) (xy 321.569462 -320.044866)
			(xy 321.540927 -320.099282) (xy 321.523868 -320.124836) (xy 321.518445 -320.133504) (xy 321.514396 -320.153532)
			(xy 321.51847 -320.173554) (xy 321.523868 -320.18224) (xy 321.54096 -320.207772) (xy 321.569488 -320.262191)
			(xy 321.591254 -320.31965) (xy 321.605943 -320.379313) (xy 321.613339 -320.440309) (xy 321.613335 -320.501753)
			(xy 321.605931 -320.562749) (xy 321.591236 -320.622409) (xy 321.569462 -320.679866) (xy 321.540927 -320.734282)
			(xy 321.523868 -320.759836) (xy 321.518445 -320.768504) (xy 321.514396 -320.788532) (xy 321.51847 -320.808554)
			(xy 321.523868 -320.81724) (xy 321.54096 -320.842772) (xy 321.569488 -320.897191) (xy 321.591254 -320.95465)
			(xy 321.605943 -321.014313) (xy 321.613339 -321.075309) (xy 321.613335 -321.136753) (xy 321.605931 -321.197749)
			(xy 321.591236 -321.257409) (xy 321.569462 -321.314866) (xy 321.540927 -321.369282) (xy 321.523868 -321.394836)
			(xy 321.518445 -321.403504) (xy 321.514396 -321.423532) (xy 321.51847 -321.443554) (xy 321.523868 -321.45224)
			(xy 321.54096 -321.477772) (xy 321.569488 -321.532191) (xy 321.591254 -321.58965) (xy 321.605943 -321.649313)
			(xy 321.613339 -321.710309) (xy 321.613335 -321.771753) (xy 321.605931 -321.832749) (xy 321.591236 -321.892409)
			(xy 321.569462 -321.949866) (xy 321.540927 -322.004282) (xy 321.523868 -322.029836) (xy 321.518445 -322.038504)
			(xy 321.514396 -322.058532) (xy 321.51847 -322.078554) (xy 321.523868 -322.08724) (xy 321.540935 -322.112788)
			(xy 321.569467 -322.167204) (xy 321.591237 -322.224661) (xy 321.605927 -322.284321) (xy 321.613324 -322.345317)
			(xy 321.613465 -322.354702) (xy 323.643752 -322.354702) (xy 323.643752 -322.354448) (xy 323.644188 -322.323726)
			(xy 323.651594 -322.262731) (xy 323.666293 -322.203072) (xy 323.688069 -322.145617) (xy 323.716607 -322.091203)
			(xy 323.733668 -322.06565) (xy 323.739023 -322.056944) (xy 323.743101 -322.03694) (xy 323.739054 -322.016929)
			(xy 323.733668 -322.008246) (xy 323.716653 -321.982664) (xy 323.688119 -321.928254) (xy 323.666345 -321.870804)
			(xy 323.651648 -321.811149) (xy 323.644244 -321.750159) (xy 323.644239 -321.68872) (xy 323.651634 -321.627729)
			(xy 323.666321 -321.568072) (xy 323.688086 -321.510618) (xy 323.716613 -321.456204) (xy 323.733668 -321.43065)
			(xy 323.739023 -321.421944) (xy 323.743101 -321.40194) (xy 323.739054 -321.381929) (xy 323.733668 -321.373246)
			(xy 323.716653 -321.347664) (xy 323.688119 -321.293254) (xy 323.666345 -321.235804) (xy 323.651648 -321.176149)
			(xy 323.644244 -321.115159) (xy 323.644239 -321.05372) (xy 323.651634 -320.992729) (xy 323.666321 -320.933072)
			(xy 323.688086 -320.875618) (xy 323.716613 -320.821204) (xy 323.733668 -320.79565) (xy 323.739023 -320.786944)
			(xy 323.743101 -320.76694) (xy 323.739054 -320.746929) (xy 323.733668 -320.738246) (xy 323.716653 -320.712664)
			(xy 323.688119 -320.658254) (xy 323.666345 -320.600804) (xy 323.651648 -320.541149) (xy 323.644244 -320.480159)
			(xy 323.644239 -320.41872) (xy 323.651634 -320.357729) (xy 323.666321 -320.298072) (xy 323.688086 -320.240618)
			(xy 323.716613 -320.186204) (xy 323.733668 -320.16065) (xy 323.739023 -320.151944) (xy 323.743101 -320.13194)
			(xy 323.739054 -320.111929) (xy 323.733668 -320.103246) (xy 323.716653 -320.077664) (xy 323.688119 -320.023254)
			(xy 323.666345 -319.965804) (xy 323.651648 -319.906149) (xy 323.644244 -319.845159) (xy 323.644239 -319.78372)
			(xy 323.651634 -319.722729) (xy 323.666321 -319.663072) (xy 323.688086 -319.605618) (xy 323.716613 -319.551204)
			(xy 323.733668 -319.52565) (xy 323.739023 -319.516944) (xy 323.743101 -319.49694) (xy 323.739054 -319.476929)
			(xy 323.733668 -319.468246) (xy 323.716653 -319.442664) (xy 323.688119 -319.388254) (xy 323.666345 -319.330804)
			(xy 323.651648 -319.271149) (xy 323.644244 -319.210159) (xy 323.644239 -319.14872) (xy 323.651634 -319.087729)
			(xy 323.666321 -319.028072) (xy 323.688086 -318.970618) (xy 323.716613 -318.916204) (xy 323.733668 -318.89065)
			(xy 323.739023 -318.881944) (xy 323.743101 -318.86194) (xy 323.739054 -318.841929) (xy 323.733668 -318.833246)
			(xy 323.716653 -318.807664) (xy 323.688119 -318.753254) (xy 323.666345 -318.695804) (xy 323.651648 -318.636149)
			(xy 323.644244 -318.575159) (xy 323.644239 -318.51372) (xy 323.651634 -318.452729) (xy 323.666321 -318.393072)
			(xy 323.688086 -318.335618) (xy 323.716613 -318.281204) (xy 323.733668 -318.25565) (xy 323.739023 -318.246944)
			(xy 323.743101 -318.22694) (xy 323.739054 -318.206929) (xy 323.733668 -318.198246) (xy 323.716653 -318.172664)
			(xy 323.688119 -318.118254) (xy 323.666345 -318.060804) (xy 323.651648 -318.001149) (xy 323.644244 -317.940159)
			(xy 323.644239 -317.87872) (xy 323.651634 -317.817729) (xy 323.666321 -317.758072) (xy 323.688086 -317.700618)
			(xy 323.716613 -317.646204) (xy 323.733668 -317.62065) (xy 323.739023 -317.611944) (xy 323.743101 -317.59194)
			(xy 323.739054 -317.571929) (xy 323.733668 -317.563246) (xy 323.716653 -317.537664) (xy 323.688119 -317.483254)
			(xy 323.666345 -317.425804) (xy 323.651648 -317.366149) (xy 323.644244 -317.305159) (xy 323.644239 -317.24372)
			(xy 323.651634 -317.182729) (xy 323.666321 -317.123072) (xy 323.688086 -317.065618) (xy 323.716613 -317.011204)
			(xy 323.733668 -316.98565) (xy 323.739023 -316.976944) (xy 323.743101 -316.95694) (xy 323.739054 -316.936929)
			(xy 323.733668 -316.928246) (xy 323.716587 -316.902707) (xy 323.688059 -316.848288) (xy 323.666293 -316.790829)
			(xy 323.651606 -316.731167) (xy 323.644211 -316.67017) (xy 323.643752 -316.639448) (xy 323.644283 -316.608718)
			(xy 323.651685 -316.547707) (xy 323.666388 -316.488032) (xy 323.688176 -316.430565) (xy 323.716733 -316.376143)
			(xy 323.751641 -316.32556) (xy 323.792392 -316.279554) (xy 323.838391 -316.238795) (xy 323.888968 -316.203878)
			(xy 323.943385 -316.175312) (xy 324.000848 -316.153514) (xy 324.06052 -316.138801) (xy 324.121531 -316.131388)
			(xy 324.15226 -316.13094) (xy 324.182982 -316.131374) (xy 324.243977 -316.138781) (xy 324.303636 -316.15348)
			(xy 324.361091 -316.175257) (xy 324.415505 -316.203795) (xy 324.441058 -316.220856) (xy 324.449743 -316.226249)
			(xy 324.46976 -316.23031) (xy 324.489777 -316.226249) (xy 324.498462 -316.220856) (xy 324.524016 -316.203798)
			(xy 324.578431 -316.175267) (xy 324.635886 -316.153496) (xy 324.695545 -316.138804) (xy 324.756539 -316.131404)
			(xy 324.817981 -316.131404) (xy 324.878975 -316.138804) (xy 324.938634 -316.153496) (xy 324.996089 -316.175267)
			(xy 325.050504 -316.203798) (xy 325.076058 -316.220856) (xy 325.084743 -316.226249) (xy 325.10476 -316.23031)
			(xy 325.124777 -316.226249) (xy 325.133462 -316.220856) (xy 325.159026 -316.203814) (xy 325.213438 -316.175279)
			(xy 325.270891 -316.153505) (xy 325.330547 -316.138809) (xy 325.39154 -316.131405) (xy 325.42226 -316.13094)
			(xy 325.452993 -316.131375) (xy 325.514012 -316.13878) (xy 325.573692 -316.153487) (xy 325.631165 -316.175281)
			(xy 325.685591 -316.203844) (xy 325.736178 -316.23876) (xy 325.782186 -316.27952) (xy 325.822944 -316.325529)
			(xy 325.85786 -316.376115) (xy 325.886422 -316.430542) (xy 325.908215 -316.488015) (xy 325.922921 -316.547696)
			(xy 325.930325 -316.608715) (xy 325.930768 -316.639448) (xy 325.930326 -316.670169) (xy 325.922921 -316.731164)
			(xy 325.908224 -316.790824) (xy 325.886448 -316.848278) (xy 325.857912 -316.902693) (xy 325.840852 -316.928246)
			(xy 325.835422 -316.93691) (xy 325.831377 -316.95694) (xy 325.835453 -316.976964) (xy 325.840852 -316.98565)
			(xy 325.857953 -317.011176) (xy 325.886482 -317.065596) (xy 325.908248 -317.123056) (xy 325.922936 -317.182719)
			(xy 325.930332 -317.243717) (xy 325.930327 -317.305162) (xy 325.922922 -317.366159) (xy 325.908225 -317.425819)
			(xy 325.886449 -317.483276) (xy 325.857913 -317.537692) (xy 325.840852 -317.563246) (xy 325.835422 -317.57191)
			(xy 325.831377 -317.59194) (xy 325.835453 -317.611964) (xy 325.840852 -317.62065) (xy 325.857953 -317.646176)
			(xy 325.886482 -317.700596) (xy 325.908248 -317.758056) (xy 325.922936 -317.817719) (xy 325.930332 -317.878717)
			(xy 325.930327 -317.940162) (xy 325.922922 -318.001159) (xy 325.908225 -318.060819) (xy 325.886449 -318.118276)
			(xy 325.857913 -318.172692) (xy 325.840852 -318.198246) (xy 325.835422 -318.20691) (xy 325.831377 -318.22694)
			(xy 325.835453 -318.246964) (xy 325.840852 -318.25565) (xy 325.857953 -318.281176) (xy 325.886482 -318.335596)
			(xy 325.908248 -318.393056) (xy 325.922936 -318.452719) (xy 325.930332 -318.513717) (xy 325.930327 -318.575162)
			(xy 325.922922 -318.636159) (xy 325.908225 -318.695819) (xy 325.886449 -318.753276) (xy 325.857913 -318.807692)
			(xy 325.840852 -318.833246) (xy 325.835422 -318.84191) (xy 325.831377 -318.86194) (xy 325.835453 -318.881964)
			(xy 325.840852 -318.89065) (xy 325.857953 -318.916176) (xy 325.886482 -318.970596) (xy 325.908248 -319.028056)
			(xy 325.922936 -319.087719) (xy 325.930332 -319.148717) (xy 325.930327 -319.210162) (xy 325.922922 -319.271159)
			(xy 325.908225 -319.330819) (xy 325.886449 -319.388276) (xy 325.857913 -319.442692) (xy 325.840852 -319.468246)
			(xy 325.835422 -319.47691) (xy 325.831377 -319.49694) (xy 325.835453 -319.516964) (xy 325.840852 -319.52565)
			(xy 325.857934 -319.551189) (xy 325.886461 -319.605608) (xy 325.908227 -319.663067) (xy 325.922914 -319.722729)
			(xy 325.930308 -319.783726) (xy 325.930768 -319.814448) (xy 325.930363 -319.843403) (xy 325.923767 -319.900937)
			(xy 325.910677 -319.957349) (xy 325.891262 -320.011909) (xy 325.865775 -320.063909) (xy 325.850504 -320.088514)
			(xy 325.845363 -320.097531) (xy 325.841973 -320.117985) (xy 325.846929 -320.138116) (xy 325.85279 -320.14668)
			(xy 325.872321 -320.173271) (xy 325.905059 -320.230555) (xy 325.930114 -320.291592) (xy 325.947066 -320.355356)
			(xy 325.955628 -320.420777) (xy 325.956168 -320.453766) (xy 325.956168 -320.45402) (xy 325.955712 -320.484741)
			(xy 325.94831 -320.545735) (xy 325.933616 -320.605394) (xy 325.911844 -320.662849) (xy 325.883311 -320.717264)
			(xy 325.866252 -320.742818) (xy 325.860845 -320.751495) (xy 325.856793 -320.771517) (xy 325.860858 -320.791536)
			(xy 325.866252 -320.800222) (xy 325.883328 -320.825764) (xy 325.911858 -320.880182) (xy 325.933626 -320.937639)
			(xy 325.948316 -320.997299) (xy 325.955714 -321.058295) (xy 325.955712 -321.119738) (xy 325.94831 -321.180733)
			(xy 325.933616 -321.240393) (xy 325.911844 -321.297849) (xy 325.883311 -321.352264) (xy 325.866252 -321.377818)
			(xy 325.860845 -321.386495) (xy 325.856793 -321.406517) (xy 325.860858 -321.426536) (xy 325.866252 -321.435222)
			(xy 325.883328 -321.460764) (xy 325.911858 -321.515182) (xy 325.933626 -321.572639) (xy 325.948316 -321.632299)
			(xy 325.955714 -321.693295) (xy 325.955712 -321.754738) (xy 325.94831 -321.815733) (xy 325.933616 -321.875393)
			(xy 325.911844 -321.932849) (xy 325.883311 -321.987264) (xy 325.866252 -322.012818) (xy 325.860845 -322.021495)
			(xy 325.856793 -322.041517) (xy 325.860858 -322.061536) (xy 325.866252 -322.070222) (xy 325.883321 -322.095769)
			(xy 325.911851 -322.150186) (xy 325.933619 -322.207643) (xy 325.948309 -322.267303) (xy 325.955707 -322.328299)
			(xy 325.956168 -322.35902) (xy 325.956168 -322.359274) (xy 325.955667 -322.392256) (xy 325.947159 -322.457669)
			(xy 325.930257 -322.52143) (xy 325.905246 -322.582468) (xy 325.872545 -322.639756) (xy 325.853044 -322.66636)
			(xy 325.84715 -322.674969) (xy 325.84223 -322.695226) (xy 325.845743 -322.715773) (xy 325.851012 -322.72478)
			(xy 325.866836 -322.749714) (xy 325.893293 -322.802511) (xy 325.913455 -322.858018) (xy 325.927051 -322.915487)
			(xy 325.933896 -322.974144) (xy 325.934324 -323.003672) (xy 325.934324 -323.003926) (xy 327.660508 -323.003926)
			(xy 327.660508 -323.003672) (xy 327.661019 -322.97069) (xy 327.669522 -322.905277) (xy 327.686421 -322.841515)
			(xy 327.711431 -322.780477) (xy 327.744131 -322.72319) (xy 327.763632 -322.696586) (xy 327.769489 -322.687954)
			(xy 327.774423 -322.667711) (xy 327.770925 -322.647171) (xy 327.765664 -322.638166) (xy 327.749814 -322.613248)
			(xy 327.723362 -322.560446) (xy 327.703206 -322.504935) (xy 327.689616 -322.447463) (xy 327.682777 -322.388803)
			(xy 327.682352 -322.359274) (xy 327.682352 -322.35902) (xy 327.682825 -322.3283) (xy 327.690222 -322.267306)
			(xy 327.704912 -322.207647) (xy 327.726681 -322.150191) (xy 327.755211 -322.095776) (xy 327.772268 -322.070222)
			(xy 327.777647 -322.061529) (xy 327.781717 -322.041517) (xy 327.77766 -322.021501) (xy 327.772268 -322.012818)
			(xy 327.755228 -321.987252) (xy 327.726695 -321.93284) (xy 327.704923 -321.875386) (xy 327.690229 -321.815729)
			(xy 327.682827 -321.754737) (xy 327.682825 -321.693296) (xy 327.690223 -321.632303) (xy 327.704913 -321.572645)
			(xy 327.726681 -321.51519) (xy 327.755211 -321.460776) (xy 327.772268 -321.435222) (xy 327.777647 -321.426529)
			(xy 327.781717 -321.406517) (xy 327.77766 -321.386501) (xy 327.772268 -321.377818) (xy 327.755228 -321.352252)
			(xy 327.726695 -321.29784) (xy 327.704923 -321.240386) (xy 327.690229 -321.180729) (xy 327.682827 -321.119737)
			(xy 327.682825 -321.058296) (xy 327.690223 -320.997303) (xy 327.704913 -320.937645) (xy 327.726681 -320.88019)
			(xy 327.755211 -320.825776) (xy 327.772268 -320.800222) (xy 327.777647 -320.791529) (xy 327.781717 -320.771517)
			(xy 327.77766 -320.751501) (xy 327.772268 -320.742818) (xy 327.755218 -320.717259) (xy 327.726685 -320.662845)
			(xy 327.704912 -320.605392) (xy 327.690218 -320.545734) (xy 327.682816 -320.48474) (xy 327.682352 -320.45402)
			(xy 327.682352 -320.453766) (xy 327.682804 -320.422826) (xy 327.690307 -320.361403) (xy 327.705211 -320.301344)
			(xy 327.727295 -320.243539) (xy 327.756233 -320.188842) (xy 327.773538 -320.16319) (xy 327.779003 -320.154429)
			(xy 327.783164 -320.134228) (xy 327.779026 -320.114022) (xy 327.773538 -320.105278) (xy 327.756228 -320.07963)
			(xy 327.727299 -320.024929) (xy 327.70522 -319.967122) (xy 327.690317 -319.907064) (xy 327.68281 -319.845642)
			(xy 327.682352 -319.814702) (xy 327.682352 -319.814448) (xy 327.682788 -319.783726) (xy 327.690194 -319.722731)
			(xy 327.704893 -319.663072) (xy 327.726669 -319.605617) (xy 327.755207 -319.551203) (xy 327.772268 -319.52565)
			(xy 327.777623 -319.516944) (xy 327.781701 -319.49694) (xy 327.777654 -319.476929) (xy 327.772268 -319.468246)
			(xy 327.755253 -319.442664) (xy 327.726719 -319.388254) (xy 327.704945 -319.330804) (xy 327.690248 -319.271149)
			(xy 327.682844 -319.210159) (xy 327.682839 -319.14872) (xy 327.690234 -319.087729) (xy 327.704921 -319.028072)
			(xy 327.726686 -318.970618) (xy 327.755213 -318.916204) (xy 327.772268 -318.89065) (xy 327.777623 -318.881944)
			(xy 327.781701 -318.86194) (xy 327.777654 -318.841929) (xy 327.772268 -318.833246) (xy 327.755253 -318.807664)
			(xy 327.726719 -318.753254) (xy 327.704945 -318.695804) (xy 327.690248 -318.636149) (xy 327.682844 -318.575159)
			(xy 327.682839 -318.51372) (xy 327.690234 -318.452729) (xy 327.704921 -318.393072) (xy 327.726686 -318.335618)
			(xy 327.755213 -318.281204) (xy 327.772268 -318.25565) (xy 327.777623 -318.246944) (xy 327.781701 -318.22694)
			(xy 327.777654 -318.206929) (xy 327.772268 -318.198246) (xy 327.755253 -318.172664) (xy 327.726719 -318.118254)
			(xy 327.704945 -318.060804) (xy 327.690248 -318.001149) (xy 327.682844 -317.940159) (xy 327.682839 -317.87872)
			(xy 327.690234 -317.817729) (xy 327.704921 -317.758072) (xy 327.726686 -317.700618) (xy 327.755213 -317.646204)
			(xy 327.772268 -317.62065) (xy 327.777623 -317.611944) (xy 327.781701 -317.59194) (xy 327.777654 -317.571929)
			(xy 327.772268 -317.563246) (xy 327.755253 -317.537664) (xy 327.726719 -317.483254) (xy 327.704945 -317.425804)
			(xy 327.690248 -317.366149) (xy 327.682844 -317.305159) (xy 327.682839 -317.24372) (xy 327.690234 -317.182729)
			(xy 327.704921 -317.123072) (xy 327.726686 -317.065618) (xy 327.755213 -317.011204) (xy 327.772268 -316.98565)
			(xy 327.777623 -316.976944) (xy 327.781701 -316.95694) (xy 327.777654 -316.936929) (xy 327.772268 -316.928246)
			(xy 327.755187 -316.902707) (xy 327.726659 -316.848288) (xy 327.704893 -316.790829) (xy 327.690206 -316.731167)
			(xy 327.682811 -316.67017) (xy 327.682352 -316.639448) (xy 327.682883 -316.608718) (xy 327.690285 -316.547707)
			(xy 327.704988 -316.488032) (xy 327.726776 -316.430565) (xy 327.755333 -316.376143) (xy 327.790241 -316.32556)
			(xy 327.830992 -316.279554) (xy 327.876991 -316.238795) (xy 327.927568 -316.203878) (xy 327.981985 -316.175312)
			(xy 328.039448 -316.153514) (xy 328.09912 -316.138801) (xy 328.160131 -316.131388) (xy 328.19086 -316.13094)
			(xy 328.221582 -316.131374) (xy 328.282577 -316.138781) (xy 328.342236 -316.15348) (xy 328.399691 -316.175257)
			(xy 328.454105 -316.203795) (xy 328.479658 -316.220856) (xy 328.488343 -316.226249) (xy 328.50836 -316.23031)
			(xy 328.528377 -316.226249) (xy 328.537062 -316.220856) (xy 328.562616 -316.203798) (xy 328.617031 -316.175267)
			(xy 328.674486 -316.153496) (xy 328.734145 -316.138804) (xy 328.795139 -316.131404) (xy 328.856581 -316.131404)
			(xy 328.917575 -316.138804) (xy 328.977234 -316.153496) (xy 329.034689 -316.175267) (xy 329.089104 -316.203798)
			(xy 329.114658 -316.220856) (xy 329.123343 -316.226249) (xy 329.14336 -316.23031) (xy 329.163377 -316.226249)
			(xy 329.172062 -316.220856) (xy 329.197626 -316.203814) (xy 329.252038 -316.175279) (xy 329.309491 -316.153505)
			(xy 329.369147 -316.138809) (xy 329.43014 -316.131405) (xy 329.46086 -316.13094) (xy 329.491593 -316.131375)
			(xy 329.552612 -316.13878) (xy 329.612292 -316.153487) (xy 329.669765 -316.175281) (xy 329.724191 -316.203844)
			(xy 329.774778 -316.23876) (xy 329.820786 -316.27952) (xy 329.861544 -316.325529) (xy 329.89646 -316.376115)
			(xy 329.925022 -316.430542) (xy 329.946815 -316.488015) (xy 329.961521 -316.547696) (xy 329.968925 -316.608715)
			(xy 329.969368 -316.639448) (xy 329.968926 -316.670169) (xy 329.961521 -316.731164) (xy 329.946824 -316.790824)
			(xy 329.925048 -316.848278) (xy 329.896512 -316.902693) (xy 329.879452 -316.928246) (xy 329.874022 -316.93691)
			(xy 329.869977 -316.95694) (xy 329.874053 -316.976964) (xy 329.879452 -316.98565) (xy 329.896553 -317.011176)
			(xy 329.925082 -317.065596) (xy 329.946848 -317.123056) (xy 329.961536 -317.182719) (xy 329.968932 -317.243717)
			(xy 329.968927 -317.305162) (xy 329.961522 -317.366159) (xy 329.946825 -317.425819) (xy 329.925049 -317.483276)
			(xy 329.896513 -317.537692) (xy 329.879452 -317.563246) (xy 329.874022 -317.57191) (xy 329.869977 -317.59194)
			(xy 329.874053 -317.611964) (xy 329.879452 -317.62065) (xy 329.896553 -317.646176) (xy 329.925082 -317.700596)
			(xy 329.946848 -317.758056) (xy 329.961536 -317.817719) (xy 329.968932 -317.878717) (xy 329.968927 -317.940162)
			(xy 329.961522 -318.001159) (xy 329.946825 -318.060819) (xy 329.925049 -318.118276) (xy 329.896513 -318.172692)
			(xy 329.879452 -318.198246) (xy 329.874022 -318.20691) (xy 329.869977 -318.22694) (xy 329.874053 -318.246964)
			(xy 329.879452 -318.25565) (xy 329.896553 -318.281176) (xy 329.925082 -318.335596) (xy 329.946848 -318.393056)
			(xy 329.961536 -318.452719) (xy 329.968932 -318.513717) (xy 329.968927 -318.575162) (xy 329.961522 -318.636159)
			(xy 329.946825 -318.695819) (xy 329.925049 -318.753276) (xy 329.896513 -318.807692) (xy 329.879452 -318.833246)
			(xy 329.874022 -318.84191) (xy 329.869977 -318.86194) (xy 329.874053 -318.881964) (xy 329.879452 -318.89065)
			(xy 329.896553 -318.916176) (xy 329.925082 -318.970596) (xy 329.946848 -319.028056) (xy 329.961536 -319.087719)
			(xy 329.968932 -319.148717) (xy 329.968927 -319.210162) (xy 329.961522 -319.271159) (xy 329.946825 -319.330819)
			(xy 329.925049 -319.388276) (xy 329.896513 -319.442692) (xy 329.879452 -319.468246) (xy 329.874022 -319.47691)
			(xy 329.869977 -319.49694) (xy 329.874053 -319.516964) (xy 329.879452 -319.52565) (xy 329.896553 -319.551176)
			(xy 329.925082 -319.605596) (xy 329.946848 -319.663056) (xy 329.961536 -319.722719) (xy 329.968932 -319.783717)
			(xy 329.968927 -319.845162) (xy 329.961522 -319.906159) (xy 329.946825 -319.965819) (xy 329.925049 -320.023276)
			(xy 329.896513 -320.077692) (xy 329.879452 -320.103246) (xy 329.874022 -320.11191) (xy 329.869977 -320.13194)
			(xy 329.874053 -320.151964) (xy 329.879452 -320.16065) (xy 329.896553 -320.186176) (xy 329.925082 -320.240596)
			(xy 329.946848 -320.298056) (xy 329.961536 -320.357719) (xy 329.968932 -320.418717) (xy 329.968927 -320.480162)
			(xy 329.961522 -320.541159) (xy 329.946825 -320.600819) (xy 329.925049 -320.658276) (xy 329.896513 -320.712692)
			(xy 329.879452 -320.738246) (xy 329.874022 -320.74691) (xy 329.869977 -320.76694) (xy 329.874053 -320.786964)
			(xy 329.879452 -320.79565) (xy 329.896553 -320.821176) (xy 329.925082 -320.875596) (xy 329.946848 -320.933056)
			(xy 329.961536 -320.992719) (xy 329.968932 -321.053717) (xy 329.968927 -321.115162) (xy 329.961522 -321.176159)
			(xy 329.946825 -321.235819) (xy 329.925049 -321.293276) (xy 329.896513 -321.347692) (xy 329.879452 -321.373246)
			(xy 329.874022 -321.38191) (xy 329.869977 -321.40194) (xy 329.874053 -321.421964) (xy 329.879452 -321.43065)
			(xy 329.896553 -321.456176) (xy 329.925082 -321.510596) (xy 329.946848 -321.568056) (xy 329.961536 -321.627719)
			(xy 329.968932 -321.688717) (xy 329.968927 -321.750162) (xy 329.961522 -321.811159) (xy 329.946825 -321.870819)
			(xy 329.925049 -321.928276) (xy 329.896513 -321.982692) (xy 329.879452 -322.008246) (xy 329.874022 -322.01691)
			(xy 329.869977 -322.03694) (xy 329.874053 -322.056964) (xy 329.879452 -322.06565) (xy 329.896534 -322.091189)
			(xy 329.925061 -322.145608) (xy 329.946827 -322.203067) (xy 329.961514 -322.262729) (xy 329.968908 -322.323726)
			(xy 329.969368 -322.354448) (xy 329.96885 -322.387693) (xy 329.960159 -322.453613) (xy 329.942946 -322.517837)
			(xy 329.917503 -322.579268) (xy 329.884267 -322.636855) (xy 329.864466 -322.663566) (xy 329.858536 -322.672276)
			(xy 329.853595 -322.692733) (xy 329.857279 -322.713453) (xy 329.862688 -322.722494) (xy 329.878819 -322.747589)
			(xy 329.905781 -322.800806) (xy 329.926324 -322.856816) (xy 329.940165 -322.914845) (xy 329.947114 -322.974097)
			(xy 329.947524 -323.003926) (xy 332.000352 -323.003926) (xy 332.000828 -322.973206) (xy 332.008225 -322.912212)
			(xy 332.022914 -322.852553) (xy 332.044682 -322.795098) (xy 332.073211 -322.740682) (xy 332.090268 -322.715128)
			(xy 332.095642 -322.706433) (xy 332.099714 -322.686422) (xy 332.095659 -322.666407) (xy 332.090268 -322.657724)
			(xy 332.073233 -322.632155) (xy 332.0447 -322.577743) (xy 332.022927 -322.52029) (xy 332.008233 -322.460633)
			(xy 332.000831 -322.399641) (xy 332.000828 -322.338201) (xy 332.008225 -322.277209) (xy 332.022915 -322.217551)
			(xy 332.044682 -322.160096) (xy 332.073211 -322.105682) (xy 332.090268 -322.080128) (xy 332.095642 -322.071433)
			(xy 332.099714 -322.051422) (xy 332.095659 -322.031407) (xy 332.090268 -322.022724) (xy 332.073233 -321.997155)
			(xy 332.0447 -321.942743) (xy 332.022927 -321.88529) (xy 332.008233 -321.825633) (xy 332.000831 -321.764641)
			(xy 332.000828 -321.703201) (xy 332.008225 -321.642209) (xy 332.022915 -321.582551) (xy 332.044682 -321.525096)
			(xy 332.073211 -321.470682) (xy 332.090268 -321.445128) (xy 332.095642 -321.436433) (xy 332.099714 -321.416422)
			(xy 332.095659 -321.396407) (xy 332.090268 -321.387724) (xy 332.073233 -321.362155) (xy 332.0447 -321.307743)
			(xy 332.022927 -321.25029) (xy 332.008233 -321.190633) (xy 332.000831 -321.129641) (xy 332.000828 -321.068201)
			(xy 332.008225 -321.007209) (xy 332.022915 -320.947551) (xy 332.044682 -320.890096) (xy 332.073211 -320.835682)
			(xy 332.090268 -320.810128) (xy 332.095642 -320.801433) (xy 332.099714 -320.781422) (xy 332.095659 -320.761407)
			(xy 332.090268 -320.752724) (xy 332.073221 -320.727163) (xy 332.044687 -320.67275) (xy 332.022914 -320.615297)
			(xy 332.008219 -320.555639) (xy 332.000816 -320.494646) (xy 332.000352 -320.463926) (xy 332.000352 -320.463672)
			(xy 332.000876 -320.432104) (xy 332.008729 -320.369459) (xy 332.024274 -320.308267) (xy 332.047272 -320.249468)
			(xy 332.077369 -320.193968) (xy 332.095348 -320.168016) (xy 332.101061 -320.159166) (xy 332.10535 -320.13856)
			(xy 332.101029 -320.117962) (xy 332.095348 -320.109088) (xy 332.07754 -320.08318) (xy 332.047729 -320.02783)
			(xy 332.024963 -319.969229) (xy 332.009588 -319.90827) (xy 332.001839 -319.845882) (xy 332.001368 -319.814448)
			(xy 332.001819 -319.783727) (xy 332.009224 -319.722733) (xy 332.02392 -319.663074) (xy 332.045693 -319.605619)
			(xy 332.074226 -319.551204) (xy 332.091284 -319.52565) (xy 332.096638 -319.516944) (xy 332.100715 -319.49694)
			(xy 332.096669 -319.47693) (xy 332.091284 -319.468246) (xy 332.074269 -319.442664) (xy 332.045733 -319.388255)
			(xy 332.023959 -319.330804) (xy 332.009262 -319.271149) (xy 332.001857 -319.210159) (xy 332.001853 -319.14872)
			(xy 332.009248 -319.087728) (xy 332.023935 -319.028071) (xy 332.045701 -318.970618) (xy 332.074228 -318.916204)
			(xy 332.091284 -318.89065) (xy 332.096638 -318.881944) (xy 332.100715 -318.86194) (xy 332.096669 -318.84193)
			(xy 332.091284 -318.833246) (xy 332.074269 -318.807664) (xy 332.045733 -318.753255) (xy 332.023959 -318.695804)
			(xy 332.009262 -318.636149) (xy 332.001857 -318.575159) (xy 332.001853 -318.51372) (xy 332.009248 -318.452728)
			(xy 332.023935 -318.393071) (xy 332.045701 -318.335618) (xy 332.074228 -318.281204) (xy 332.091284 -318.25565)
			(xy 332.096638 -318.246944) (xy 332.100715 -318.22694) (xy 332.096669 -318.20693) (xy 332.091284 -318.198246)
			(xy 332.074269 -318.172664) (xy 332.045733 -318.118255) (xy 332.023959 -318.060804) (xy 332.009262 -318.001149)
			(xy 332.001857 -317.940159) (xy 332.001853 -317.87872) (xy 332.009248 -317.817728) (xy 332.023935 -317.758071)
			(xy 332.045701 -317.700618) (xy 332.074228 -317.646204) (xy 332.091284 -317.62065) (xy 332.096638 -317.611944)
			(xy 332.100715 -317.59194) (xy 332.096669 -317.57193) (xy 332.091284 -317.563246) (xy 332.074269 -317.537664)
			(xy 332.045733 -317.483255) (xy 332.023959 -317.425804) (xy 332.009262 -317.366149) (xy 332.001857 -317.305159)
			(xy 332.001853 -317.24372) (xy 332.009248 -317.182728) (xy 332.023935 -317.123071) (xy 332.045701 -317.065618)
			(xy 332.074228 -317.011204) (xy 332.091284 -316.98565) (xy 332.096638 -316.976944) (xy 332.100715 -316.95694)
			(xy 332.096669 -316.93693) (xy 332.091284 -316.928246) (xy 332.074205 -316.902706) (xy 332.045676 -316.848287)
			(xy 332.023909 -316.790828) (xy 332.009222 -316.731166) (xy 332.001827 -316.67017) (xy 332.001368 -316.639448)
			(xy 332.001883 -316.608718) (xy 332.009285 -316.547705) (xy 332.023989 -316.488029) (xy 332.045778 -316.430561)
			(xy 332.074336 -316.376139) (xy 332.109245 -316.325555) (xy 332.149997 -316.279548) (xy 332.195998 -316.23879)
			(xy 332.246577 -316.203873) (xy 332.300995 -316.175307) (xy 332.358461 -316.15351) (xy 332.418134 -316.138798)
			(xy 332.479146 -316.131387) (xy 332.509876 -316.13094) (xy 332.540596 -316.131417) (xy 332.60159 -316.138814)
			(xy 332.661249 -316.153503) (xy 332.718704 -316.17527) (xy 332.77312 -316.203799) (xy 332.798674 -316.220856)
			(xy 332.807359 -316.226249) (xy 332.827376 -316.23031) (xy 332.847393 -316.226249) (xy 332.856078 -316.220856)
			(xy 332.881632 -316.203798) (xy 332.936047 -316.175267) (xy 332.993502 -316.153496) (xy 333.053161 -316.138804)
			(xy 333.114155 -316.131404) (xy 333.175597 -316.131404) (xy 333.236591 -316.138804) (xy 333.29625 -316.153496)
			(xy 333.353705 -316.175267) (xy 333.40812 -316.203798) (xy 333.433674 -316.220856) (xy 333.442359 -316.226249)
			(xy 333.462376 -316.23031) (xy 333.482393 -316.226249) (xy 333.491078 -316.220856) (xy 333.516638 -316.203807)
			(xy 333.571051 -316.175273) (xy 333.628505 -316.153501) (xy 333.688162 -316.138806) (xy 333.749156 -316.131404)
			(xy 333.779876 -316.13094) (xy 333.810609 -316.13136) (xy 333.871628 -316.138767) (xy 333.93131 -316.153476)
			(xy 333.988782 -316.175271) (xy 334.043209 -316.203836) (xy 334.093795 -316.238754) (xy 334.139803 -316.279514)
			(xy 334.180561 -316.325524) (xy 334.215476 -316.376112) (xy 334.244039 -316.43054) (xy 334.265832 -316.488013)
			(xy 334.280537 -316.547695) (xy 334.287941 -316.608715) (xy 334.288384 -316.639448) (xy 334.28794 -316.670169)
			(xy 334.280534 -316.731164) (xy 334.265837 -316.790823) (xy 334.244063 -316.848278) (xy 334.215528 -316.902692)
			(xy 334.198468 -316.928246) (xy 334.193036 -316.93691) (xy 334.188991 -316.95694) (xy 334.193068 -316.976964)
			(xy 334.198468 -316.98565) (xy 334.215569 -317.011176) (xy 334.244096 -317.065596) (xy 334.265862 -317.123057)
			(xy 334.28055 -317.18272) (xy 334.287945 -317.243717) (xy 334.28794 -317.305162) (xy 334.280535 -317.366158)
			(xy 334.265839 -317.425819) (xy 334.244064 -317.483276) (xy 334.215528 -317.537692) (xy 334.198468 -317.563246)
			(xy 334.193036 -317.57191) (xy 334.188991 -317.59194) (xy 334.193068 -317.611964) (xy 334.198468 -317.62065)
			(xy 334.215569 -317.646176) (xy 334.244096 -317.700596) (xy 334.265862 -317.758057) (xy 334.28055 -317.81772)
			(xy 334.287945 -317.878717) (xy 334.28794 -317.940162) (xy 334.280535 -318.001158) (xy 334.265839 -318.060819)
			(xy 334.244064 -318.118276) (xy 334.215528 -318.172692) (xy 334.198468 -318.198246) (xy 334.193036 -318.20691)
			(xy 334.188991 -318.22694) (xy 334.193068 -318.246964) (xy 334.198468 -318.25565) (xy 334.215569 -318.281176)
			(xy 334.244096 -318.335596) (xy 334.265862 -318.393057) (xy 334.28055 -318.45272) (xy 334.287945 -318.513717)
			(xy 334.28794 -318.575162) (xy 334.280535 -318.636158) (xy 334.265839 -318.695819) (xy 334.244064 -318.753276)
			(xy 334.215528 -318.807692) (xy 334.198468 -318.833246) (xy 334.193036 -318.84191) (xy 334.188991 -318.86194)
			(xy 334.193068 -318.881964) (xy 334.198468 -318.89065) (xy 334.215569 -318.916176) (xy 334.244096 -318.970596)
			(xy 334.265862 -319.028057) (xy 334.28055 -319.08772) (xy 334.287945 -319.148717) (xy 334.28794 -319.210162)
			(xy 334.280535 -319.271158) (xy 334.265839 -319.330819) (xy 334.244064 -319.388276) (xy 334.215528 -319.442692)
			(xy 334.198468 -319.468246) (xy 334.193036 -319.47691) (xy 334.188991 -319.49694) (xy 334.193068 -319.516964)
			(xy 334.198468 -319.52565) (xy 334.215539 -319.551195) (xy 334.244071 -319.605612) (xy 334.26584 -319.663069)
			(xy 334.280529 -319.72273) (xy 334.287924 -319.783727) (xy 334.288384 -319.814448) (xy 334.287976 -319.843403)
			(xy 334.28138 -319.900937) (xy 334.268291 -319.957349) (xy 334.248877 -320.011908) (xy 334.22339 -320.063909)
			(xy 334.20812 -320.088514) (xy 334.202977 -320.097531) (xy 334.199586 -320.117985) (xy 334.204544 -320.138116)
			(xy 334.210406 -320.14668) (xy 334.229939 -320.17327) (xy 334.262677 -320.230554) (xy 334.287731 -320.291591)
			(xy 334.304682 -320.355356) (xy 334.313244 -320.420777) (xy 334.313784 -320.453766) (xy 334.313784 -320.45402)
			(xy 334.313325 -320.484741) (xy 334.305923 -320.545735) (xy 334.29123 -320.605394) (xy 334.269458 -320.662849)
			(xy 334.240926 -320.717264) (xy 334.223868 -320.742818) (xy 334.21846 -320.751494) (xy 334.214407 -320.771517)
			(xy 334.218473 -320.791536) (xy 334.223868 -320.800222) (xy 334.240943 -320.825764) (xy 334.269472 -320.880182)
			(xy 334.29124 -320.937639) (xy 334.30593 -320.9973) (xy 334.313327 -321.058295) (xy 334.313326 -321.119738)
			(xy 334.305924 -321.180733) (xy 334.29123 -321.240392) (xy 334.269459 -321.297848) (xy 334.240926 -321.352264)
			(xy 334.223868 -321.377818) (xy 334.21846 -321.386494) (xy 334.214407 -321.406517) (xy 334.218473 -321.426536)
			(xy 334.223868 -321.435222) (xy 334.240943 -321.460764) (xy 334.269472 -321.515182) (xy 334.29124 -321.572639)
			(xy 334.30593 -321.6323) (xy 334.313327 -321.693295) (xy 334.313326 -321.754738) (xy 334.305924 -321.815733)
			(xy 334.29123 -321.875392) (xy 334.269459 -321.932848) (xy 334.240926 -321.987264) (xy 334.223868 -322.012818)
			(xy 334.21846 -322.021494) (xy 334.214407 -322.041517) (xy 334.218473 -322.061536) (xy 334.223868 -322.070222)
			(xy 334.240927 -322.095775) (xy 334.269461 -322.15019) (xy 334.291232 -322.207645) (xy 334.305924 -322.267304)
			(xy 334.313323 -322.328299) (xy 334.313784 -322.35902) (xy 334.313221 -322.392381) (xy 334.304503 -322.458531)
			(xy 334.28722 -322.522975) (xy 334.261667 -322.58461) (xy 334.228282 -322.642379) (xy 334.208374 -322.669154)
			(xy 334.20239 -322.677761) (xy 334.197265 -322.698065) (xy 334.200617 -322.718736) (xy 334.205834 -322.727828)
			(xy 334.221366 -322.752554) (xy 334.247257 -322.804895) (xy 334.266979 -322.859858) (xy 334.280272 -322.916719)
			(xy 334.286961 -322.974729) (xy 334.287368 -323.003926) (xy 336.038952 -323.003926) (xy 336.03942 -322.972584)
			(xy 336.047128 -322.910377) (xy 336.06242 -322.849588) (xy 336.085062 -322.791137) (xy 336.114712 -322.73591)
			(xy 336.132424 -322.710048) (xy 336.137984 -322.701224) (xy 336.142231 -322.680831) (xy 336.138009 -322.660434)
			(xy 336.132424 -322.651628) (xy 336.114873 -322.625849) (xy 336.085524 -322.57082) (xy 336.063127 -322.512614)
			(xy 336.048018 -322.452106) (xy 336.040424 -322.390203) (xy 336.039968 -322.35902) (xy 336.040455 -322.3283)
			(xy 336.047852 -322.267307) (xy 336.062539 -322.207649) (xy 336.084304 -322.150193) (xy 336.112829 -322.095777)
			(xy 336.129884 -322.070222) (xy 336.135262 -322.061529) (xy 336.13933 -322.041517) (xy 336.135275 -322.021502)
			(xy 336.129884 -322.012818) (xy 336.112843 -321.987253) (xy 336.084309 -321.93284) (xy 336.062537 -321.875387)
			(xy 336.047842 -321.81573) (xy 336.04044 -321.754737) (xy 336.040438 -321.693296) (xy 336.047836 -321.632303)
			(xy 336.062527 -321.572645) (xy 336.084296 -321.51519) (xy 336.112826 -321.460776) (xy 336.129884 -321.435222)
			(xy 336.135262 -321.426529) (xy 336.13933 -321.406517) (xy 336.135275 -321.386502) (xy 336.129884 -321.377818)
			(xy 336.112843 -321.352253) (xy 336.084309 -321.29784) (xy 336.062537 -321.240387) (xy 336.047842 -321.18073)
			(xy 336.04044 -321.119737) (xy 336.040438 -321.058296) (xy 336.047836 -320.997303) (xy 336.062527 -320.937645)
			(xy 336.084296 -320.88019) (xy 336.112826 -320.825776) (xy 336.129884 -320.800222) (xy 336.135262 -320.791529)
			(xy 336.13933 -320.771517) (xy 336.135275 -320.751502) (xy 336.129884 -320.742818) (xy 336.112836 -320.717257)
			(xy 336.084302 -320.662845) (xy 336.062529 -320.605391) (xy 336.047834 -320.545734) (xy 336.040432 -320.48474)
			(xy 336.039968 -320.45402) (xy 336.039968 -320.453766) (xy 336.040435 -320.422827) (xy 336.047937 -320.361404)
			(xy 336.062838 -320.301346) (xy 336.084919 -320.243541) (xy 336.113851 -320.188843) (xy 336.131154 -320.16319)
			(xy 336.136618 -320.154429) (xy 336.140777 -320.134228) (xy 336.13664 -320.114023) (xy 336.131154 -320.105278)
			(xy 336.113846 -320.079629) (xy 336.084916 -320.024928) (xy 336.062837 -319.967122) (xy 336.047933 -319.907064)
			(xy 336.040426 -319.845642) (xy 336.039968 -319.814702) (xy 336.039968 -319.814448) (xy 336.040419 -319.783727)
			(xy 336.047824 -319.722733) (xy 336.06252 -319.663074) (xy 336.084293 -319.605619) (xy 336.112826 -319.551204)
			(xy 336.129884 -319.52565) (xy 336.135238 -319.516944) (xy 336.139315 -319.49694) (xy 336.135269 -319.47693)
			(xy 336.129884 -319.468246) (xy 336.112869 -319.442664) (xy 336.084333 -319.388255) (xy 336.062559 -319.330804)
			(xy 336.047862 -319.271149) (xy 336.040457 -319.210159) (xy 336.040453 -319.14872) (xy 336.047848 -319.087728)
			(xy 336.062535 -319.028071) (xy 336.084301 -318.970618) (xy 336.112828 -318.916204) (xy 336.129884 -318.89065)
			(xy 336.135238 -318.881944) (xy 336.139315 -318.86194) (xy 336.135269 -318.84193) (xy 336.129884 -318.833246)
			(xy 336.112869 -318.807664) (xy 336.084333 -318.753255) (xy 336.062559 -318.695804) (xy 336.047862 -318.636149)
			(xy 336.040457 -318.575159) (xy 336.040453 -318.51372) (xy 336.047848 -318.452728) (xy 336.062535 -318.393071)
			(xy 336.084301 -318.335618) (xy 336.112828 -318.281204) (xy 336.129884 -318.25565) (xy 336.135238 -318.246944)
			(xy 336.139315 -318.22694) (xy 336.135269 -318.20693) (xy 336.129884 -318.198246) (xy 336.112869 -318.172664)
			(xy 336.084333 -318.118255) (xy 336.062559 -318.060804) (xy 336.047862 -318.001149) (xy 336.040457 -317.940159)
			(xy 336.040453 -317.87872) (xy 336.047848 -317.817728) (xy 336.062535 -317.758071) (xy 336.084301 -317.700618)
			(xy 336.112828 -317.646204) (xy 336.129884 -317.62065) (xy 336.135238 -317.611944) (xy 336.139315 -317.59194)
			(xy 336.135269 -317.57193) (xy 336.129884 -317.563246) (xy 336.112869 -317.537664) (xy 336.084333 -317.483255)
			(xy 336.062559 -317.425804) (xy 336.047862 -317.366149) (xy 336.040457 -317.305159) (xy 336.040453 -317.24372)
			(xy 336.047848 -317.182728) (xy 336.062535 -317.123071) (xy 336.084301 -317.065618) (xy 336.112828 -317.011204)
			(xy 336.129884 -316.98565) (xy 336.135238 -316.976944) (xy 336.139315 -316.95694) (xy 336.135269 -316.93693)
			(xy 336.129884 -316.928246) (xy 336.112805 -316.902706) (xy 336.084276 -316.848287) (xy 336.062509 -316.790828)
			(xy 336.047822 -316.731166) (xy 336.040427 -316.67017) (xy 336.039968 -316.639448) (xy 336.040483 -316.608718)
			(xy 336.047885 -316.547705) (xy 336.062589 -316.488029) (xy 336.084378 -316.430561) (xy 336.112936 -316.376139)
			(xy 336.147845 -316.325555) (xy 336.188597 -316.279548) (xy 336.234598 -316.23879) (xy 336.285177 -316.203873)
			(xy 336.339595 -316.175307) (xy 336.397061 -316.15351) (xy 336.456734 -316.138798) (xy 336.517746 -316.131387)
			(xy 336.548476 -316.13094) (xy 336.579196 -316.131417) (xy 336.64019 -316.138814) (xy 336.699849 -316.153503)
			(xy 336.757304 -316.17527) (xy 336.81172 -316.203799) (xy 336.837274 -316.220856) (xy 336.845959 -316.226249)
			(xy 336.865976 -316.23031) (xy 336.885993 -316.226249) (xy 336.894678 -316.220856) (xy 336.920232 -316.203798)
			(xy 336.974647 -316.175267) (xy 337.032102 -316.153496) (xy 337.091761 -316.138804) (xy 337.152755 -316.131404)
			(xy 337.214197 -316.131404) (xy 337.275191 -316.138804) (xy 337.33485 -316.153496) (xy 337.392305 -316.175267)
			(xy 337.44672 -316.203798) (xy 337.472274 -316.220856) (xy 337.480959 -316.226249) (xy 337.500976 -316.23031)
			(xy 337.520993 -316.226249) (xy 337.529678 -316.220856) (xy 337.555238 -316.203807) (xy 337.609651 -316.175273)
			(xy 337.667105 -316.153501) (xy 337.726762 -316.138806) (xy 337.787756 -316.131404) (xy 337.818476 -316.13094)
			(xy 337.849209 -316.13136) (xy 337.910228 -316.138767) (xy 337.96991 -316.153476) (xy 338.027382 -316.175271)
			(xy 338.081809 -316.203836) (xy 338.132395 -316.238754) (xy 338.178403 -316.279514) (xy 338.219161 -316.325524)
			(xy 338.254076 -316.376112) (xy 338.282639 -316.43054) (xy 338.304432 -316.488013) (xy 338.319137 -316.547695)
			(xy 338.326541 -316.608715) (xy 338.326984 -316.639448) (xy 338.32654 -316.670169) (xy 338.319134 -316.731164)
			(xy 338.304437 -316.790823) (xy 338.282663 -316.848278) (xy 338.254128 -316.902692) (xy 338.237068 -316.928246)
			(xy 338.231636 -316.93691) (xy 338.227591 -316.95694) (xy 338.231668 -316.976964) (xy 338.237068 -316.98565)
			(xy 338.254169 -317.011176) (xy 338.282696 -317.065596) (xy 338.304462 -317.123057) (xy 338.31915 -317.18272)
			(xy 338.326545 -317.243717) (xy 338.32654 -317.305162) (xy 338.319135 -317.366158) (xy 338.304439 -317.425819)
			(xy 338.282664 -317.483276) (xy 338.254128 -317.537692) (xy 338.237068 -317.563246) (xy 338.231636 -317.57191)
			(xy 338.227591 -317.59194) (xy 338.231668 -317.611964) (xy 338.237068 -317.62065) (xy 338.254169 -317.646176)
			(xy 338.282696 -317.700596) (xy 338.304462 -317.758057) (xy 338.31915 -317.81772) (xy 338.326545 -317.878717)
			(xy 338.32654 -317.940162) (xy 338.319135 -318.001158) (xy 338.304439 -318.060819) (xy 338.282664 -318.118276)
			(xy 338.254128 -318.172692) (xy 338.237068 -318.198246) (xy 338.231636 -318.20691) (xy 338.227591 -318.22694)
			(xy 338.231668 -318.246964) (xy 338.237068 -318.25565) (xy 338.254169 -318.281176) (xy 338.282696 -318.335596)
			(xy 338.304462 -318.393057) (xy 338.31915 -318.45272) (xy 338.326545 -318.513717) (xy 338.32654 -318.575162)
			(xy 338.319135 -318.636158) (xy 338.304439 -318.695819) (xy 338.282664 -318.753276) (xy 338.254128 -318.807692)
			(xy 338.237068 -318.833246) (xy 338.231636 -318.84191) (xy 338.227591 -318.86194) (xy 338.231668 -318.881964)
			(xy 338.237068 -318.89065) (xy 338.254169 -318.916176) (xy 338.282696 -318.970596) (xy 338.304462 -319.028057)
			(xy 338.31915 -319.08772) (xy 338.326545 -319.148717) (xy 338.32654 -319.210162) (xy 338.319135 -319.271158)
			(xy 338.304439 -319.330819) (xy 338.282664 -319.388276) (xy 338.254128 -319.442692) (xy 338.237068 -319.468246)
			(xy 338.231636 -319.47691) (xy 338.227591 -319.49694) (xy 338.231668 -319.516964) (xy 338.237068 -319.52565)
			(xy 338.254169 -319.551176) (xy 338.282696 -319.605596) (xy 338.304462 -319.663057) (xy 338.31915 -319.72272)
			(xy 338.326545 -319.783717) (xy 338.326541 -319.828926) (xy 340.255352 -319.828926) (xy 340.255828 -319.798206)
			(xy 340.263225 -319.737212) (xy 340.277914 -319.677553) (xy 340.299682 -319.620098) (xy 340.328211 -319.565682)
			(xy 340.345268 -319.540128) (xy 340.350642 -319.531433) (xy 340.354714 -319.511422) (xy 340.350659 -319.491407)
			(xy 340.345268 -319.482724) (xy 340.328233 -319.457155) (xy 340.2997 -319.402743) (xy 340.277927 -319.34529)
			(xy 340.263233 -319.285633) (xy 340.255831 -319.224641) (xy 340.255828 -319.163201) (xy 340.263225 -319.102209)
			(xy 340.277915 -319.042551) (xy 340.299682 -318.985096) (xy 340.328211 -318.930682) (xy 340.345268 -318.905128)
			(xy 340.350642 -318.896433) (xy 340.354714 -318.876422) (xy 340.350659 -318.856407) (xy 340.345268 -318.847724)
			(xy 340.328233 -318.822155) (xy 340.2997 -318.767743) (xy 340.277927 -318.71029) (xy 340.263233 -318.650633)
			(xy 340.255831 -318.589641) (xy 340.255828 -318.528201) (xy 340.263225 -318.467209) (xy 340.277915 -318.407551)
			(xy 340.299682 -318.350096) (xy 340.328211 -318.295682) (xy 340.345268 -318.270128) (xy 340.350642 -318.261433)
			(xy 340.354714 -318.241422) (xy 340.350659 -318.221407) (xy 340.345268 -318.212724) (xy 340.328233 -318.187155)
			(xy 340.2997 -318.132743) (xy 340.277927 -318.07529) (xy 340.263233 -318.015633) (xy 340.255831 -317.954641)
			(xy 340.255828 -317.893201) (xy 340.263225 -317.832209) (xy 340.277915 -317.772551) (xy 340.299682 -317.715096)
			(xy 340.328211 -317.660682) (xy 340.345268 -317.635128) (xy 340.350642 -317.626433) (xy 340.354714 -317.606422)
			(xy 340.350659 -317.586407) (xy 340.345268 -317.577724) (xy 340.328233 -317.552155) (xy 340.2997 -317.497743)
			(xy 340.277927 -317.44029) (xy 340.263233 -317.380633) (xy 340.255831 -317.319641) (xy 340.255828 -317.258201)
			(xy 340.263225 -317.197209) (xy 340.277915 -317.137551) (xy 340.299682 -317.080096) (xy 340.328211 -317.025682)
			(xy 340.345268 -317.000128) (xy 340.350642 -316.991433) (xy 340.354714 -316.971422) (xy 340.350659 -316.951407)
			(xy 340.345268 -316.942724) (xy 340.328221 -316.917163) (xy 340.299687 -316.86275) (xy 340.277914 -316.805297)
			(xy 340.263219 -316.745639) (xy 340.255816 -316.684646) (xy 340.255352 -316.653926) (xy 340.25588 -316.623197)
			(xy 340.263285 -316.562187) (xy 340.27799 -316.502514) (xy 340.29978 -316.445049) (xy 340.328337 -316.390629)
			(xy 340.363246 -316.340048) (xy 340.403997 -316.294044) (xy 340.449996 -316.253287) (xy 340.500573 -316.218371)
			(xy 340.554989 -316.189807) (xy 340.612451 -316.168009) (xy 340.672122 -316.153297) (xy 340.733131 -316.145884)
			(xy 340.76386 -316.145418) (xy 340.794581 -316.145856) (xy 340.855576 -316.153263) (xy 340.915236 -316.167961)
			(xy 340.97269 -316.189737) (xy 341.027105 -316.218274) (xy 341.052658 -316.235334) (xy 341.061343 -316.240727)
			(xy 341.08136 -316.244788) (xy 341.101377 -316.240727) (xy 341.110062 -316.235334) (xy 341.135616 -316.218276)
			(xy 341.190031 -316.189745) (xy 341.247486 -316.167974) (xy 341.307145 -316.153282) (xy 341.368139 -316.145882)
			(xy 341.429581 -316.145882) (xy 341.490575 -316.153282) (xy 341.550234 -316.167974) (xy 341.607689 -316.189745)
			(xy 341.662104 -316.218276) (xy 341.687658 -316.235334) (xy 341.696343 -316.240727) (xy 341.71636 -316.244788)
			(xy 341.736377 -316.240727) (xy 341.745062 -316.235334) (xy 341.770632 -316.218301) (xy 341.825042 -316.189763)
			(xy 341.882493 -316.167986) (xy 341.942148 -316.153288) (xy 342.00314 -316.145883) (xy 342.03386 -316.145418)
			(xy 342.064592 -316.145875) (xy 342.125609 -316.15328) (xy 342.185288 -316.167986) (xy 342.24276 -316.189779)
			(xy 342.297185 -316.21834) (xy 342.34777 -316.253255) (xy 342.393778 -316.294012) (xy 342.434537 -316.340019)
			(xy 342.469452 -316.390603) (xy 342.498016 -316.445028) (xy 342.51981 -316.502498) (xy 342.534518 -316.562177)
			(xy 342.541924 -316.623194) (xy 342.542368 -316.653926) (xy 342.541915 -316.684647) (xy 342.534512 -316.745642)
			(xy 342.519818 -316.805301) (xy 342.498045 -316.862756) (xy 342.469511 -316.91717) (xy 342.452452 -316.942724)
			(xy 342.44704 -316.951398) (xy 342.44299 -316.971422) (xy 342.447057 -316.991442) (xy 342.452452 -317.000128)
			(xy 342.469533 -317.025667) (xy 342.498063 -317.080085) (xy 342.519831 -317.137542) (xy 342.534521 -317.197204)
			(xy 342.541918 -317.2582) (xy 342.541915 -317.319643) (xy 342.534513 -317.380638) (xy 342.519818 -317.440298)
			(xy 342.498045 -317.497754) (xy 342.469511 -317.55217) (xy 342.452452 -317.577724) (xy 342.44704 -317.586398)
			(xy 342.44299 -317.606422) (xy 342.447057 -317.626442) (xy 342.452452 -317.635128) (xy 342.469533 -317.660667)
			(xy 342.498063 -317.715085) (xy 342.519831 -317.772542) (xy 342.534521 -317.832204) (xy 342.541918 -317.8932)
			(xy 342.541915 -317.954643) (xy 342.534513 -318.015638) (xy 342.519818 -318.075298) (xy 342.498045 -318.132754)
			(xy 342.469511 -318.18717) (xy 342.452452 -318.212724) (xy 342.44704 -318.221398) (xy 342.44299 -318.241422)
			(xy 342.447057 -318.261442) (xy 342.452452 -318.270128) (xy 342.469533 -318.295667) (xy 342.498063 -318.350085)
			(xy 342.519831 -318.407542) (xy 342.534521 -318.467204) (xy 342.541918 -318.5282) (xy 342.541915 -318.589643)
			(xy 342.534513 -318.650638) (xy 342.519818 -318.710298) (xy 342.498045 -318.767754) (xy 342.469511 -318.82217)
			(xy 342.452452 -318.847724) (xy 342.44704 -318.856398) (xy 342.44299 -318.876422) (xy 342.447057 -318.896442)
			(xy 342.452452 -318.905128) (xy 342.469533 -318.930667) (xy 342.498063 -318.985085) (xy 342.519831 -319.042542)
			(xy 342.534521 -319.102204) (xy 342.541918 -319.1632) (xy 342.541915 -319.224643) (xy 342.534513 -319.285638)
			(xy 342.519818 -319.345298) (xy 342.498045 -319.402754) (xy 342.469511 -319.45717) (xy 342.452452 -319.482724)
			(xy 342.44704 -319.491398) (xy 342.44299 -319.511422) (xy 342.447057 -319.531442) (xy 342.452452 -319.540128)
			(xy 342.469524 -319.565673) (xy 342.498053 -319.620091) (xy 342.519821 -319.677548) (xy 342.53451 -319.737209)
			(xy 342.541907 -319.798205) (xy 342.542368 -319.828926) (xy 342.541952 -319.857881) (xy 342.535358 -319.915415)
			(xy 342.522271 -319.971826) (xy 342.502859 -320.026386) (xy 342.477374 -320.078387) (xy 342.462104 -320.102992)
			(xy 342.456895 -320.111976) (xy 342.453528 -320.132451) (xy 342.458514 -320.152594) (xy 342.46439 -320.161158)
			(xy 342.483911 -320.187756) (xy 342.516651 -320.245038) (xy 342.541708 -320.306073) (xy 342.558662 -320.369836)
			(xy 342.567227 -320.435255) (xy 342.567768 -320.468244) (xy 342.567768 -320.468498) (xy 342.567301 -320.499219)
			(xy 342.559901 -320.560213) (xy 342.54521 -320.619872) (xy 342.52344 -320.677327) (xy 342.49491 -320.731742)
			(xy 342.477852 -320.757296) (xy 342.472465 -320.765983) (xy 342.468406 -320.785998) (xy 342.472463 -320.806014)
			(xy 342.477852 -320.8147) (xy 342.494908 -320.840255) (xy 342.523439 -320.89467) (xy 342.545209 -320.952125)
			(xy 342.559901 -321.011784) (xy 342.567301 -321.072778) (xy 342.567301 -321.134219) (xy 342.559901 -321.195213)
			(xy 342.54521 -321.254872) (xy 342.52344 -321.312327) (xy 342.49491 -321.366742) (xy 342.477852 -321.392296)
			(xy 342.472465 -321.400983) (xy 342.468406 -321.420998) (xy 342.472463 -321.441014) (xy 342.477852 -321.4497)
			(xy 342.494908 -321.475255) (xy 342.523439 -321.52967) (xy 342.545209 -321.587125) (xy 342.559901 -321.646784)
			(xy 342.567301 -321.707778) (xy 342.567301 -321.769219) (xy 342.559901 -321.830213) (xy 342.54521 -321.889872)
			(xy 342.52344 -321.947327) (xy 342.49491 -322.001742) (xy 342.477852 -322.027296) (xy 342.472465 -322.035983)
			(xy 342.468406 -322.055998) (xy 342.472463 -322.076014) (xy 342.477852 -322.0847) (xy 342.494912 -322.110253)
			(xy 342.523443 -322.164668) (xy 342.545213 -322.222124) (xy 342.559905 -322.281783) (xy 342.567305 -322.342777)
			(xy 342.567768 -322.373498) (xy 342.567273 -322.405369) (xy 342.559305 -322.46861) (xy 342.543505 -322.530363)
			(xy 342.520121 -322.589661) (xy 342.489519 -322.645576) (xy 342.471248 -322.671694) (xy 342.465459 -322.680619)
			(xy 342.461065 -322.70141) (xy 342.465467 -322.722199) (xy 342.471248 -322.73113) (xy 342.489567 -322.757219)
			(xy 342.520197 -322.813128) (xy 342.543587 -322.872431) (xy 342.559369 -322.934196) (xy 342.567296 -322.997451)
			(xy 342.567768 -323.029326) (xy 344.293952 -323.029326) (xy 344.294474 -322.997456) (xy 344.302438 -322.934216)
			(xy 344.318232 -322.872464) (xy 344.34161 -322.813166) (xy 344.372205 -322.75725) (xy 344.390472 -322.73113)
			(xy 344.396238 -322.722192) (xy 344.400637 -322.70141) (xy 344.396246 -322.680626) (xy 344.390472 -322.671694)
			(xy 344.372166 -322.645596) (xy 344.341534 -322.58969) (xy 344.318141 -322.530389) (xy 344.302355 -322.468626)
			(xy 344.294425 -322.405373) (xy 344.293952 -322.373498) (xy 344.294414 -322.342777) (xy 344.301814 -322.281783)
			(xy 344.316506 -322.222124) (xy 344.338277 -322.164669) (xy 344.36681 -322.110254) (xy 344.383868 -322.0847)
			(xy 344.389266 -322.076017) (xy 344.39333 -322.055998) (xy 344.389264 -322.03598) (xy 344.383868 -322.027296)
			(xy 344.366808 -322.001743) (xy 344.338276 -321.947328) (xy 344.316505 -321.889873) (xy 344.301813 -321.830214)
			(xy 344.294413 -321.769219) (xy 344.294414 -321.707778) (xy 344.301814 -321.646783) (xy 344.316506 -321.587124)
			(xy 344.338277 -321.529669) (xy 344.36681 -321.475254) (xy 344.383868 -321.4497) (xy 344.389266 -321.441017)
			(xy 344.39333 -321.420998) (xy 344.389264 -321.40098) (xy 344.383868 -321.392296) (xy 344.366808 -321.366743)
			(xy 344.338276 -321.312328) (xy 344.316505 -321.254873) (xy 344.301813 -321.195214) (xy 344.294413 -321.134219)
			(xy 344.294414 -321.072778) (xy 344.301814 -321.011783) (xy 344.316506 -320.952124) (xy 344.338277 -320.894669)
			(xy 344.36681 -320.840254) (xy 344.383868 -320.8147) (xy 344.389266 -320.806017) (xy 344.39333 -320.785998)
			(xy 344.389264 -320.76598) (xy 344.383868 -320.757296) (xy 344.366809 -320.731743) (xy 344.338277 -320.677328)
			(xy 344.316506 -320.619872) (xy 344.301814 -320.560213) (xy 344.294414 -320.499219) (xy 344.293952 -320.468498)
			(xy 344.293952 -320.468244) (xy 344.294393 -320.437304) (xy 344.301899 -320.37588) (xy 344.316805 -320.315821)
			(xy 344.338892 -320.258016) (xy 344.367832 -320.20332) (xy 344.385138 -320.177668) (xy 344.390622 -320.168918)
			(xy 344.394776 -320.14871) (xy 344.39063 -320.128501) (xy 344.385138 -320.119756) (xy 344.367818 -320.094114)
			(xy 344.338891 -320.039411) (xy 344.316814 -319.981603) (xy 344.301913 -319.921544) (xy 344.294408 -319.86012)
			(xy 344.293952 -319.82918) (xy 344.293952 -319.828926) (xy 344.294428 -319.798206) (xy 344.301825 -319.737212)
			(xy 344.316514 -319.677553) (xy 344.338282 -319.620098) (xy 344.366811 -319.565682) (xy 344.383868 -319.540128)
			(xy 344.389242 -319.531433) (xy 344.393314 -319.511422) (xy 344.389259 -319.491407) (xy 344.383868 -319.482724)
			(xy 344.366833 -319.457155) (xy 344.3383 -319.402743) (xy 344.316527 -319.34529) (xy 344.301833 -319.285633)
			(xy 344.294431 -319.224641) (xy 344.294428 -319.163201) (xy 344.301825 -319.102209) (xy 344.316515 -319.042551)
			(xy 344.338282 -318.985096) (xy 344.366811 -318.930682) (xy 344.383868 -318.905128) (xy 344.389242 -318.896433)
			(xy 344.393314 -318.876422) (xy 344.389259 -318.856407) (xy 344.383868 -318.847724) (xy 344.366833 -318.822155)
			(xy 344.3383 -318.767743) (xy 344.316527 -318.71029) (xy 344.301833 -318.650633) (xy 344.294431 -318.589641)
			(xy 344.294428 -318.528201) (xy 344.301825 -318.467209) (xy 344.316515 -318.407551) (xy 344.338282 -318.350096)
			(xy 344.366811 -318.295682) (xy 344.383868 -318.270128) (xy 344.389242 -318.261433) (xy 344.393314 -318.241422)
			(xy 344.389259 -318.221407) (xy 344.383868 -318.212724) (xy 344.366833 -318.187155) (xy 344.3383 -318.132743)
			(xy 344.316527 -318.07529) (xy 344.301833 -318.015633) (xy 344.294431 -317.954641) (xy 344.294428 -317.893201)
			(xy 344.301825 -317.832209) (xy 344.316515 -317.772551) (xy 344.338282 -317.715096) (xy 344.366811 -317.660682)
			(xy 344.383868 -317.635128) (xy 344.389242 -317.626433) (xy 344.393314 -317.606422) (xy 344.389259 -317.586407)
			(xy 344.383868 -317.577724) (xy 344.366833 -317.552155) (xy 344.3383 -317.497743) (xy 344.316527 -317.44029)
			(xy 344.301833 -317.380633) (xy 344.294431 -317.319641) (xy 344.294428 -317.258201) (xy 344.301825 -317.197209)
			(xy 344.316515 -317.137551) (xy 344.338282 -317.080096) (xy 344.366811 -317.025682) (xy 344.383868 -317.000128)
			(xy 344.389242 -316.991433) (xy 344.393314 -316.971422) (xy 344.389259 -316.951407) (xy 344.383868 -316.942724)
			(xy 344.366821 -316.917163) (xy 344.338287 -316.86275) (xy 344.316514 -316.805297) (xy 344.301819 -316.745639)
			(xy 344.294416 -316.684646) (xy 344.293952 -316.653926) (xy 344.29448 -316.623197) (xy 344.301885 -316.562187)
			(xy 344.31659 -316.502514) (xy 344.33838 -316.445049) (xy 344.366937 -316.390629) (xy 344.401846 -316.340048)
			(xy 344.442597 -316.294044) (xy 344.488596 -316.253287) (xy 344.539173 -316.218371) (xy 344.593589 -316.189807)
			(xy 344.651051 -316.168009) (xy 344.710722 -316.153297) (xy 344.771731 -316.145884) (xy 344.80246 -316.145418)
			(xy 344.833181 -316.145856) (xy 344.894176 -316.153263) (xy 344.953836 -316.167961) (xy 345.01129 -316.189737)
			(xy 345.065705 -316.218274) (xy 345.091258 -316.235334) (xy 345.099943 -316.240727) (xy 345.11996 -316.244788)
			(xy 345.139977 -316.240727) (xy 345.148662 -316.235334) (xy 345.174216 -316.218276) (xy 345.228631 -316.189745)
			(xy 345.286086 -316.167974) (xy 345.345745 -316.153282) (xy 345.406739 -316.145882) (xy 345.468181 -316.145882)
			(xy 345.529175 -316.153282) (xy 345.588834 -316.167974) (xy 345.646289 -316.189745) (xy 345.700704 -316.218276)
			(xy 345.726258 -316.235334) (xy 345.734943 -316.240727) (xy 345.75496 -316.244788) (xy 345.774977 -316.240727)
			(xy 345.783662 -316.235334) (xy 345.809232 -316.218301) (xy 345.863642 -316.189763) (xy 345.921093 -316.167986)
			(xy 345.980748 -316.153288) (xy 346.04174 -316.145883) (xy 346.07246 -316.145418) (xy 346.103192 -316.145875)
			(xy 346.164209 -316.15328) (xy 346.223888 -316.167986) (xy 346.28136 -316.189779) (xy 346.335785 -316.21834)
			(xy 346.38637 -316.253255) (xy 346.432378 -316.294012) (xy 346.473137 -316.340019) (xy 346.508052 -316.390603)
			(xy 346.536616 -316.445028) (xy 346.55841 -316.502498) (xy 346.573118 -316.562177) (xy 346.580524 -316.623194)
			(xy 346.580968 -316.653926) (xy 346.580515 -316.684647) (xy 346.573112 -316.745642) (xy 346.558418 -316.805301)
			(xy 346.536645 -316.862756) (xy 346.508111 -316.91717) (xy 346.491052 -316.942724) (xy 346.48564 -316.951398)
			(xy 346.48159 -316.971422) (xy 346.485657 -316.991442) (xy 346.491052 -317.000128) (xy 346.508133 -317.025667)
			(xy 346.536663 -317.080085) (xy 346.558431 -317.137542) (xy 346.573121 -317.197204) (xy 346.580518 -317.2582)
			(xy 346.580515 -317.319643) (xy 346.573113 -317.380638) (xy 346.558418 -317.440298) (xy 346.536645 -317.497754)
			(xy 346.508111 -317.55217) (xy 346.491052 -317.577724) (xy 346.48564 -317.586398) (xy 346.48159 -317.606422)
			(xy 346.485657 -317.626442) (xy 346.491052 -317.635128) (xy 346.508133 -317.660667) (xy 346.536663 -317.715085)
			(xy 346.558431 -317.772542) (xy 346.573121 -317.832204) (xy 346.580518 -317.8932) (xy 346.580515 -317.954643)
			(xy 346.573113 -318.015638) (xy 346.558418 -318.075298) (xy 346.536645 -318.132754) (xy 346.508111 -318.18717)
			(xy 346.491052 -318.212724) (xy 346.48564 -318.221398) (xy 346.48159 -318.241422) (xy 346.485657 -318.261442)
			(xy 346.491052 -318.270128) (xy 346.508133 -318.295667) (xy 346.536663 -318.350085) (xy 346.558431 -318.407542)
			(xy 346.573121 -318.467204) (xy 346.580518 -318.5282) (xy 346.580515 -318.589643) (xy 346.573113 -318.650638)
			(xy 346.558418 -318.710298) (xy 346.536645 -318.767754) (xy 346.508111 -318.82217) (xy 346.491052 -318.847724)
			(xy 346.48564 -318.856398) (xy 346.48159 -318.876422) (xy 346.485657 -318.896442) (xy 346.491052 -318.905128)
			(xy 346.508133 -318.930667) (xy 346.536663 -318.985085) (xy 346.558431 -319.042542) (xy 346.573121 -319.102204)
			(xy 346.580518 -319.1632) (xy 346.580515 -319.224643) (xy 346.573113 -319.285638) (xy 346.558418 -319.345298)
			(xy 346.536645 -319.402754) (xy 346.508111 -319.45717) (xy 346.491052 -319.482724) (xy 346.48564 -319.491398)
			(xy 346.48159 -319.511422) (xy 346.485657 -319.531442) (xy 346.491052 -319.540128) (xy 346.508124 -319.565673)
			(xy 346.536653 -319.620091) (xy 346.558421 -319.677548) (xy 346.57311 -319.737209) (xy 346.580507 -319.798205)
			(xy 346.580968 -319.828926) (xy 346.580449 -319.861059) (xy 346.572313 -319.924809) (xy 346.556211 -319.987027)
			(xy 346.532401 -320.04672) (xy 346.50126 -320.102939) (xy 346.48267 -320.129154) (xy 346.476707 -320.138103)
			(xy 346.472238 -320.159121) (xy 346.476724 -320.180136) (xy 346.48267 -320.189098) (xy 346.501282 -320.215299)
			(xy 346.53243 -320.271517) (xy 346.556243 -320.331214) (xy 346.57234 -320.393436) (xy 346.580464 -320.457191)
			(xy 346.580968 -320.489326) (xy 346.580515 -320.520047) (xy 346.573112 -320.581042) (xy 346.558418 -320.640701)
			(xy 346.536645 -320.698156) (xy 346.508111 -320.75257) (xy 346.491052 -320.778124) (xy 346.48564 -320.786798)
			(xy 346.48159 -320.806822) (xy 346.485657 -320.826842) (xy 346.491052 -320.835528) (xy 346.508133 -320.861067)
			(xy 346.536663 -320.915485) (xy 346.558431 -320.972942) (xy 346.573121 -321.032604) (xy 346.580518 -321.0936)
			(xy 346.580515 -321.155043) (xy 346.573113 -321.216038) (xy 346.558418 -321.275698) (xy 346.536645 -321.333154)
			(xy 346.508111 -321.38757) (xy 346.491052 -321.413124) (xy 346.48564 -321.421798) (xy 346.48159 -321.441822)
			(xy 346.485657 -321.461842) (xy 346.491052 -321.470528) (xy 346.508133 -321.496067) (xy 346.536663 -321.550485)
			(xy 346.558431 -321.607942) (xy 346.573121 -321.667604) (xy 346.580518 -321.7286) (xy 346.580515 -321.790043)
			(xy 346.573113 -321.851038) (xy 346.558418 -321.910698) (xy 346.536645 -321.968154) (xy 346.508111 -322.02257)
			(xy 346.491052 -322.048124) (xy 346.48564 -322.056798) (xy 346.48159 -322.076822) (xy 346.485657 -322.096842)
			(xy 346.491052 -322.105528) (xy 346.508133 -322.131067) (xy 346.536663 -322.185485) (xy 346.558431 -322.242942)
			(xy 346.573121 -322.302604) (xy 346.580518 -322.3636) (xy 346.580515 -322.425043) (xy 346.573113 -322.486038)
			(xy 346.558418 -322.545698) (xy 346.536645 -322.603154) (xy 346.508111 -322.65757) (xy 346.491052 -322.683124)
			(xy 346.48564 -322.691798) (xy 346.48159 -322.711822) (xy 346.485657 -322.731842) (xy 346.491052 -322.740528)
			(xy 346.508124 -322.766073) (xy 346.536653 -322.820491) (xy 346.558421 -322.877948) (xy 346.57311 -322.937609)
			(xy 346.580507 -322.998605) (xy 346.580968 -323.029326) (xy 346.580587 -323.06006) (xy 346.573174 -323.12108)
			(xy 346.558461 -323.180762) (xy 346.53666 -323.238234) (xy 346.508091 -323.29266) (xy 346.47317 -323.343246)
			(xy 346.432406 -323.389253) (xy 346.386394 -323.430011) (xy 346.335804 -323.464925) (xy 346.281374 -323.493487)
			(xy 346.223898 -323.51528) (xy 346.164215 -323.529986) (xy 346.103194 -323.537391) (xy 346.07246 -323.537834)
			(xy 346.041739 -323.537377) (xy 345.980745 -323.529973) (xy 345.921087 -323.515279) (xy 345.863632 -323.493507)
			(xy 345.809216 -323.464976) (xy 345.783662 -323.447918) (xy 345.774977 -323.442525) (xy 345.75496 -323.438464)
			(xy 345.734943 -323.442525) (xy 345.726258 -323.447918) (xy 345.700704 -323.464976) (xy 345.646289 -323.493507)
			(xy 345.588834 -323.515278) (xy 345.529175 -323.52997) (xy 345.468181 -323.53737) (xy 345.406739 -323.53737)
			(xy 345.345745 -323.52997) (xy 345.286086 -323.515278) (xy 345.228631 -323.493507) (xy 345.174216 -323.464976)
			(xy 345.148662 -323.447918) (xy 345.139977 -323.442525) (xy 345.11996 -323.438464) (xy 345.099943 -323.442525)
			(xy 345.091258 -323.447918) (xy 345.065714 -323.464992) (xy 345.011297 -323.493522) (xy 344.953839 -323.515289)
			(xy 344.894178 -323.529978) (xy 344.833181 -323.537374) (xy 344.80246 -323.537834) (xy 344.771729 -323.537382)
			(xy 344.710716 -323.529969) (xy 344.651041 -323.515257) (xy 344.593574 -323.49346) (xy 344.539154 -323.464895)
			(xy 344.488573 -323.429979) (xy 344.442569 -323.389222) (xy 344.401812 -323.343216) (xy 344.366898 -323.292634)
			(xy 344.338335 -323.238213) (xy 344.316539 -323.180746) (xy 344.301828 -323.12107) (xy 344.294417 -323.060057)
			(xy 344.293952 -323.029326) (xy 342.567768 -323.029326) (xy 342.567387 -323.06006) (xy 342.559974 -323.12108)
			(xy 342.545261 -323.180762) (xy 342.52346 -323.238234) (xy 342.494891 -323.29266) (xy 342.45997 -323.343246)
			(xy 342.419206 -323.389253) (xy 342.373194 -323.430011) (xy 342.322604 -323.464925) (xy 342.268174 -323.493487)
			(xy 342.210698 -323.51528) (xy 342.151015 -323.529986) (xy 342.089994 -323.537391) (xy 342.05926 -323.537834)
			(xy 342.028539 -323.537377) (xy 341.967545 -323.529973) (xy 341.907887 -323.515279) (xy 341.850432 -323.493507)
			(xy 341.796016 -323.464976) (xy 341.770462 -323.447918) (xy 341.761777 -323.442525) (xy 341.74176 -323.438464)
			(xy 341.721743 -323.442525) (xy 341.713058 -323.447918) (xy 341.687504 -323.464976) (xy 341.633089 -323.493507)
			(xy 341.575634 -323.515278) (xy 341.515975 -323.52997) (xy 341.454981 -323.53737) (xy 341.393539 -323.53737)
			(xy 341.332545 -323.52997) (xy 341.272886 -323.515278) (xy 341.215431 -323.493507) (xy 341.161016 -323.464976)
			(xy 341.135462 -323.447918) (xy 341.126777 -323.442525) (xy 341.10676 -323.438464) (xy 341.086743 -323.442525)
			(xy 341.078058 -323.447918) (xy 341.052514 -323.464992) (xy 340.998097 -323.493522) (xy 340.940639 -323.515289)
			(xy 340.880978 -323.529978) (xy 340.819981 -323.537374) (xy 340.78926 -323.537834) (xy 340.758529 -323.537382)
			(xy 340.697516 -323.529969) (xy 340.637841 -323.515257) (xy 340.580374 -323.49346) (xy 340.525954 -323.464895)
			(xy 340.475373 -323.429979) (xy 340.429369 -323.389222) (xy 340.388612 -323.343216) (xy 340.353698 -323.292634)
			(xy 340.325135 -323.238213) (xy 340.303339 -323.180746) (xy 340.288628 -323.12107) (xy 340.281217 -323.060057)
			(xy 340.280752 -323.029326) (xy 340.281228 -322.998606) (xy 340.288625 -322.937612) (xy 340.303314 -322.877953)
			(xy 340.325082 -322.820498) (xy 340.353611 -322.766082) (xy 340.370668 -322.740528) (xy 340.376042 -322.731833)
			(xy 340.380114 -322.711822) (xy 340.376059 -322.691807) (xy 340.370668 -322.683124) (xy 340.353633 -322.657555)
			(xy 340.3251 -322.603143) (xy 340.303327 -322.54569) (xy 340.288633 -322.486033) (xy 340.281231 -322.425041)
			(xy 340.281228 -322.363601) (xy 340.288625 -322.302609) (xy 340.303315 -322.242951) (xy 340.325082 -322.185496)
			(xy 340.353611 -322.131082) (xy 340.370668 -322.105528) (xy 340.376042 -322.096833) (xy 340.380114 -322.076822)
			(xy 340.376059 -322.056807) (xy 340.370668 -322.048124) (xy 340.353633 -322.022555) (xy 340.3251 -321.968143)
			(xy 340.303327 -321.91069) (xy 340.288633 -321.851033) (xy 340.281231 -321.790041) (xy 340.281228 -321.728601)
			(xy 340.288625 -321.667609) (xy 340.303315 -321.607951) (xy 340.325082 -321.550496) (xy 340.353611 -321.496082)
			(xy 340.370668 -321.470528) (xy 340.376042 -321.461833) (xy 340.380114 -321.441822) (xy 340.376059 -321.421807)
			(xy 340.370668 -321.413124) (xy 340.353633 -321.387555) (xy 340.3251 -321.333143) (xy 340.303327 -321.27569)
			(xy 340.288633 -321.216033) (xy 340.281231 -321.155041) (xy 340.281228 -321.093601) (xy 340.288625 -321.032609)
			(xy 340.303315 -320.972951) (xy 340.325082 -320.915496) (xy 340.353611 -320.861082) (xy 340.370668 -320.835528)
			(xy 340.376042 -320.826833) (xy 340.380114 -320.806822) (xy 340.376059 -320.786807) (xy 340.370668 -320.778124)
			(xy 340.353621 -320.752563) (xy 340.325087 -320.69815) (xy 340.303314 -320.640697) (xy 340.288619 -320.581039)
			(xy 340.281216 -320.520046) (xy 340.280752 -320.489326) (xy 340.280752 -320.488818) (xy 340.281238 -320.458675)
			(xy 340.288398 -320.398816) (xy 340.302584 -320.340222) (xy 340.323598 -320.283717) (xy 340.351144 -320.230091)
			(xy 340.36762 -320.204846) (xy 340.373175 -320.195636) (xy 340.376859 -320.17447) (xy 340.371602 -320.153639)
			(xy 340.365334 -320.144902) (xy 340.344594 -320.117824) (xy 340.309772 -320.059173) (xy 340.283092 -319.996399)
			(xy 340.265029 -319.930626) (xy 340.255907 -319.86303) (xy 340.255352 -319.828926) (xy 338.326541 -319.828926)
			(xy 338.32654 -319.845162) (xy 338.319135 -319.906158) (xy 338.304439 -319.965819) (xy 338.282664 -320.023276)
			(xy 338.254128 -320.077692) (xy 338.237068 -320.103246) (xy 338.231636 -320.11191) (xy 338.227591 -320.13194)
			(xy 338.231668 -320.151964) (xy 338.237068 -320.16065) (xy 338.254169 -320.186176) (xy 338.282696 -320.240596)
			(xy 338.304462 -320.298057) (xy 338.31915 -320.35772) (xy 338.326545 -320.418717) (xy 338.32654 -320.480162)
			(xy 338.319135 -320.541158) (xy 338.304439 -320.600819) (xy 338.282664 -320.658276) (xy 338.254128 -320.712692)
			(xy 338.237068 -320.738246) (xy 338.231636 -320.74691) (xy 338.227591 -320.76694) (xy 338.231668 -320.786964)
			(xy 338.237068 -320.79565) (xy 338.254169 -320.821176) (xy 338.282696 -320.875596) (xy 338.304462 -320.933057)
			(xy 338.31915 -320.99272) (xy 338.326545 -321.053717) (xy 338.32654 -321.115162) (xy 338.319135 -321.176158)
			(xy 338.304439 -321.235819) (xy 338.282664 -321.293276) (xy 338.254128 -321.347692) (xy 338.237068 -321.373246)
			(xy 338.231636 -321.38191) (xy 338.227591 -321.40194) (xy 338.231668 -321.421964) (xy 338.237068 -321.43065)
			(xy 338.254169 -321.456176) (xy 338.282696 -321.510596) (xy 338.304462 -321.568057) (xy 338.31915 -321.62772)
			(xy 338.326545 -321.688717) (xy 338.32654 -321.750162) (xy 338.319135 -321.811158) (xy 338.304439 -321.870819)
			(xy 338.282664 -321.928276) (xy 338.254128 -321.982692) (xy 338.237068 -322.008246) (xy 338.231636 -322.01691)
			(xy 338.227591 -322.03694) (xy 338.231668 -322.056964) (xy 338.237068 -322.06565) (xy 338.254139 -322.091195)
			(xy 338.282671 -322.145612) (xy 338.30444 -322.203069) (xy 338.319129 -322.26273) (xy 338.326524 -322.323727)
			(xy 338.326984 -322.354448) (xy 338.326984 -322.354702) (xy 338.326492 -322.386271) (xy 338.31863 -322.448917)
			(xy 338.303078 -322.510109) (xy 338.280073 -322.568907) (xy 338.24997 -322.624407) (xy 338.231988 -322.650358)
			(xy 338.226295 -322.65922) (xy 338.221995 -322.679818) (xy 338.226309 -322.700414) (xy 338.231988 -322.709286)
			(xy 338.249789 -322.735198) (xy 338.2796 -322.790548) (xy 338.302367 -322.849147) (xy 338.317744 -322.910105)
			(xy 338.325496 -322.972492) (xy 338.325968 -323.003926) (xy 338.325587 -323.03466) (xy 338.318174 -323.09568)
			(xy 338.303461 -323.155362) (xy 338.28166 -323.212834) (xy 338.253091 -323.26726) (xy 338.21817 -323.317846)
			(xy 338.177406 -323.363853) (xy 338.131394 -323.404611) (xy 338.080804 -323.439525) (xy 338.026374 -323.468087)
			(xy 337.968898 -323.48988) (xy 337.909215 -323.504586) (xy 337.848194 -323.511991) (xy 337.81746 -323.512434)
			(xy 337.786739 -323.511977) (xy 337.725745 -323.504573) (xy 337.666087 -323.489879) (xy 337.608632 -323.468107)
			(xy 337.554216 -323.439576) (xy 337.528662 -323.422518) (xy 337.519977 -323.417125) (xy 337.49996 -323.413064)
			(xy 337.479943 -323.417125) (xy 337.471258 -323.422518) (xy 337.445704 -323.439576) (xy 337.391289 -323.468107)
			(xy 337.333834 -323.489878) (xy 337.274175 -323.50457) (xy 337.213181 -323.51197) (xy 337.151739 -323.51197)
			(xy 337.090745 -323.50457) (xy 337.031086 -323.489878) (xy 336.973631 -323.468107) (xy 336.919216 -323.439576)
			(xy 336.893662 -323.422518) (xy 336.884977 -323.417125) (xy 336.86496 -323.413064) (xy 336.844943 -323.417125)
			(xy 336.836258 -323.422518) (xy 336.810714 -323.439592) (xy 336.756297 -323.468122) (xy 336.698839 -323.489889)
			(xy 336.639178 -323.504578) (xy 336.578181 -323.511974) (xy 336.54746 -323.512434) (xy 336.516729 -323.511982)
			(xy 336.455716 -323.504569) (xy 336.396041 -323.489857) (xy 336.338574 -323.46806) (xy 336.284154 -323.439495)
			(xy 336.233573 -323.404579) (xy 336.187569 -323.363822) (xy 336.146812 -323.317816) (xy 336.111898 -323.267234)
			(xy 336.083335 -323.212813) (xy 336.061539 -323.155346) (xy 336.046828 -323.09567) (xy 336.039417 -323.034657)
			(xy 336.038952 -323.003926) (xy 334.287368 -323.003926) (xy 334.286987 -323.03466) (xy 334.279574 -323.09568)
			(xy 334.264861 -323.155362) (xy 334.24306 -323.212834) (xy 334.214491 -323.26726) (xy 334.17957 -323.317846)
			(xy 334.138806 -323.363853) (xy 334.092794 -323.404611) (xy 334.042204 -323.439525) (xy 333.987774 -323.468087)
			(xy 333.930298 -323.48988) (xy 333.870615 -323.504586) (xy 333.809594 -323.511991) (xy 333.77886 -323.512434)
			(xy 333.748139 -323.511977) (xy 333.687145 -323.504573) (xy 333.627487 -323.489879) (xy 333.570032 -323.468107)
			(xy 333.515616 -323.439576) (xy 333.490062 -323.422518) (xy 333.481377 -323.417125) (xy 333.46136 -323.413064)
			(xy 333.441343 -323.417125) (xy 333.432658 -323.422518) (xy 333.407104 -323.439576) (xy 333.352689 -323.468107)
			(xy 333.295234 -323.489878) (xy 333.235575 -323.50457) (xy 333.174581 -323.51197) (xy 333.113139 -323.51197)
			(xy 333.052145 -323.50457) (xy 332.992486 -323.489878) (xy 332.935031 -323.468107) (xy 332.880616 -323.439576)
			(xy 332.855062 -323.422518) (xy 332.846377 -323.417125) (xy 332.82636 -323.413064) (xy 332.806343 -323.417125)
			(xy 332.797658 -323.422518) (xy 332.772114 -323.439592) (xy 332.717697 -323.468122) (xy 332.660239 -323.489889)
			(xy 332.600578 -323.504578) (xy 332.539581 -323.511974) (xy 332.50886 -323.512434) (xy 332.478129 -323.511982)
			(xy 332.417116 -323.504569) (xy 332.357441 -323.489857) (xy 332.299974 -323.46806) (xy 332.245554 -323.439495)
			(xy 332.194973 -323.404579) (xy 332.148969 -323.363822) (xy 332.108212 -323.317816) (xy 332.073298 -323.267234)
			(xy 332.044735 -323.212813) (xy 332.022939 -323.155346) (xy 332.008228 -323.09567) (xy 332.000817 -323.034657)
			(xy 332.000352 -323.003926) (xy 329.947524 -323.003926) (xy 329.947068 -323.034657) (xy 329.939657 -323.09567)
			(xy 329.924946 -323.155346) (xy 329.90315 -323.212813) (xy 329.874585 -323.267234) (xy 329.83967 -323.317815)
			(xy 329.798913 -323.36382) (xy 329.752908 -323.404576) (xy 329.702325 -323.439491) (xy 329.647904 -323.468054)
			(xy 329.590436 -323.489849) (xy 329.530761 -323.504559) (xy 329.469747 -323.511969) (xy 329.439016 -323.512434)
			(xy 329.408296 -323.511948) (xy 329.347303 -323.504552) (xy 329.287645 -323.489864) (xy 329.230189 -323.468099)
			(xy 329.175773 -323.439573) (xy 329.150218 -323.422518) (xy 329.141533 -323.417125) (xy 329.121516 -323.413064)
			(xy 329.101499 -323.417125) (xy 329.092814 -323.422518) (xy 329.06726 -323.439576) (xy 329.012845 -323.468107)
			(xy 328.95539 -323.489878) (xy 328.895731 -323.50457) (xy 328.834737 -323.51197) (xy 328.773295 -323.51197)
			(xy 328.712301 -323.50457) (xy 328.652642 -323.489878) (xy 328.595187 -323.468107) (xy 328.540772 -323.439576)
			(xy 328.515218 -323.422518) (xy 328.506533 -323.417125) (xy 328.486516 -323.413064) (xy 328.466499 -323.417125)
			(xy 328.457814 -323.422518) (xy 328.432255 -323.439568) (xy 328.377841 -323.468102) (xy 328.320388 -323.489874)
			(xy 328.26073 -323.504569) (xy 328.199736 -323.51197) (xy 328.169016 -323.512434) (xy 328.138286 -323.511929)
			(xy 328.077275 -323.504523) (xy 328.017601 -323.489817) (xy 327.960135 -323.468025) (xy 327.905714 -323.439466)
			(xy 327.855133 -323.404555) (xy 327.809128 -323.363801) (xy 327.768371 -323.3178) (xy 327.733456 -323.267222)
			(xy 327.704892 -323.212804) (xy 327.683096 -323.155339) (xy 327.668385 -323.095666) (xy 327.660974 -323.034656)
			(xy 327.660508 -323.003926) (xy 325.934324 -323.003926) (xy 325.933868 -323.034657) (xy 325.926457 -323.09567)
			(xy 325.911746 -323.155346) (xy 325.88995 -323.212813) (xy 325.861385 -323.267234) (xy 325.82647 -323.317815)
			(xy 325.785713 -323.36382) (xy 325.739708 -323.404576) (xy 325.689125 -323.439491) (xy 325.634704 -323.468054)
			(xy 325.577236 -323.489849) (xy 325.517561 -323.504559) (xy 325.456547 -323.511969) (xy 325.425816 -323.512434)
			(xy 325.395096 -323.511948) (xy 325.334103 -323.504552) (xy 325.274445 -323.489864) (xy 325.216989 -323.468099)
			(xy 325.162573 -323.439573) (xy 325.137018 -323.422518) (xy 325.128333 -323.417125) (xy 325.108316 -323.413064)
			(xy 325.088299 -323.417125) (xy 325.079614 -323.422518) (xy 325.05406 -323.439576) (xy 324.999645 -323.468107)
			(xy 324.94219 -323.489878) (xy 324.882531 -323.50457) (xy 324.821537 -323.51197) (xy 324.760095 -323.51197)
			(xy 324.699101 -323.50457) (xy 324.639442 -323.489878) (xy 324.581987 -323.468107) (xy 324.527572 -323.439576)
			(xy 324.502018 -323.422518) (xy 324.493333 -323.417125) (xy 324.473316 -323.413064) (xy 324.453299 -323.417125)
			(xy 324.444614 -323.422518) (xy 324.419055 -323.439568) (xy 324.364641 -323.468102) (xy 324.307188 -323.489874)
			(xy 324.24753 -323.504569) (xy 324.186536 -323.51197) (xy 324.155816 -323.512434) (xy 324.125086 -323.511929)
			(xy 324.064075 -323.504523) (xy 324.004401 -323.489817) (xy 323.946935 -323.468025) (xy 323.892514 -323.439466)
			(xy 323.841933 -323.404555) (xy 323.795928 -323.363801) (xy 323.755171 -323.3178) (xy 323.720256 -323.267222)
			(xy 323.691692 -323.212804) (xy 323.669896 -323.155339) (xy 323.655185 -323.095666) (xy 323.647774 -323.034656)
			(xy 323.647308 -323.003926) (xy 323.647793 -322.972712) (xy 323.655434 -322.910752) (xy 323.670594 -322.850191)
			(xy 323.693044 -322.791939) (xy 323.722447 -322.736868) (xy 323.740018 -322.711064) (xy 323.745739 -322.702158)
			(xy 323.749978 -322.681438) (xy 323.745528 -322.660763) (xy 323.739764 -322.651882) (xy 323.721586 -322.625842)
			(xy 323.691164 -322.570095) (xy 323.667914 -322.510997) (xy 323.652197 -322.449465) (xy 323.644258 -322.386455)
			(xy 323.643752 -322.354702) (xy 321.613465 -322.354702) (xy 321.613784 -322.376038) (xy 321.613257 -322.409283)
			(xy 321.604568 -322.475203) (xy 321.587356 -322.539426) (xy 321.561916 -322.600857) (xy 321.528682 -322.658445)
			(xy 321.508882 -322.685156) (xy 321.50296 -322.693871) (xy 321.498014 -322.714325) (xy 321.501695 -322.735044)
			(xy 321.507104 -322.744084) (xy 321.523233 -322.76918) (xy 321.550194 -322.822398) (xy 321.570738 -322.878406)
			(xy 321.58458 -322.936436) (xy 321.59153 -322.995687) (xy 321.59194 -323.025516) (xy 321.591459 -323.056246)
			(xy 321.584049 -323.117258) (xy 321.56934 -323.176932) (xy 321.547545 -323.234398) (xy 321.518983 -323.288818)
			(xy 321.48407 -323.339399) (xy 321.443315 -323.385404) (xy 321.397312 -323.42616) (xy 321.346732 -323.461075)
			(xy 321.292313 -323.489639) (xy 321.234847 -323.511435) (xy 321.175174 -323.526146) (xy 321.114162 -323.533558)
			(xy 321.083432 -323.534024) (xy 321.052712 -323.533532) (xy 320.99172 -323.526137) (xy 320.932061 -323.511451)
			(xy 320.874606 -323.489687) (xy 320.820189 -323.461162) (xy 320.794634 -323.444108) (xy 320.785949 -323.438715)
			(xy 320.765932 -323.434654) (xy 320.745915 -323.438715) (xy 320.73723 -323.444108) (xy 320.711676 -323.461166)
			(xy 320.657261 -323.489697) (xy 320.599806 -323.511468) (xy 320.540147 -323.52616) (xy 320.479153 -323.53356)
			(xy 320.417711 -323.53356) (xy 320.356717 -323.52616) (xy 320.297058 -323.511468) (xy 320.239603 -323.489697)
			(xy 320.185188 -323.461166) (xy 320.159634 -323.444108) (xy 320.150949 -323.438715) (xy 320.130932 -323.434654)
			(xy 320.110915 -323.438715) (xy 320.10223 -323.444108) (xy 320.076665 -323.461149) (xy 320.022254 -323.489685)
			(xy 319.964801 -323.51146) (xy 319.905145 -323.526156) (xy 319.844152 -323.53356) (xy 319.813432 -323.534024)
			(xy 319.782701 -323.533532) (xy 319.721687 -323.526128) (xy 319.662011 -323.511422) (xy 319.604542 -323.489631)
			(xy 319.550119 -323.461071) (xy 319.499535 -323.42616) (xy 319.453529 -323.385405) (xy 319.41277 -323.339403)
			(xy 319.377854 -323.288822) (xy 319.349289 -323.234402) (xy 319.327492 -323.176935) (xy 319.312781 -323.11726)
			(xy 319.305371 -323.056247) (xy 319.304924 -323.025516) (xy 317.57874 -323.025516) (xy 317.578259 -323.056246)
			(xy 317.570849 -323.117258) (xy 317.55614 -323.176932) (xy 317.534345 -323.234398) (xy 317.505783 -323.288818)
			(xy 317.47087 -323.339399) (xy 317.430115 -323.385404) (xy 317.384112 -323.42616) (xy 317.333532 -323.461075)
			(xy 317.279113 -323.489639) (xy 317.221647 -323.511435) (xy 317.161974 -323.526146) (xy 317.100962 -323.533558)
			(xy 317.070232 -323.534024) (xy 317.039512 -323.533532) (xy 316.97852 -323.526137) (xy 316.918861 -323.511451)
			(xy 316.861406 -323.489687) (xy 316.806989 -323.461162) (xy 316.781434 -323.444108) (xy 316.772749 -323.438715)
			(xy 316.752732 -323.434654) (xy 316.732715 -323.438715) (xy 316.72403 -323.444108) (xy 316.698476 -323.461166)
			(xy 316.644061 -323.489697) (xy 316.586606 -323.511468) (xy 316.526947 -323.52616) (xy 316.465953 -323.53356)
			(xy 316.404511 -323.53356) (xy 316.343517 -323.52616) (xy 316.283858 -323.511468) (xy 316.226403 -323.489697)
			(xy 316.171988 -323.461166) (xy 316.146434 -323.444108) (xy 316.137749 -323.438715) (xy 316.117732 -323.434654)
			(xy 316.097715 -323.438715) (xy 316.08903 -323.444108) (xy 316.063465 -323.461149) (xy 316.009054 -323.489685)
			(xy 315.951601 -323.51146) (xy 315.891945 -323.526156) (xy 315.830952 -323.53356) (xy 315.800232 -323.534024)
			(xy 315.769501 -323.533532) (xy 315.708487 -323.526128) (xy 315.648811 -323.511422) (xy 315.591342 -323.489631)
			(xy 315.536919 -323.461071) (xy 315.486335 -323.42616) (xy 315.440329 -323.385405) (xy 315.39957 -323.339403)
			(xy 315.364654 -323.288822) (xy 315.336089 -323.234402) (xy 315.314292 -323.176935) (xy 315.299581 -323.11726)
			(xy 315.292171 -323.056247) (xy 315.291724 -323.025516) (xy 315.292201 -322.994301) (xy 315.299844 -322.932341)
			(xy 315.315005 -322.871781) (xy 315.337457 -322.813528) (xy 315.366862 -322.758457) (xy 315.384434 -322.732654)
			(xy 315.390075 -322.723705) (xy 315.394338 -322.703013) (xy 315.389924 -322.682353) (xy 315.38418 -322.673472)
			(xy 315.365999 -322.647434) (xy 315.335577 -322.591687) (xy 315.312328 -322.532588) (xy 315.296612 -322.471055)
			(xy 315.288674 -322.408046) (xy 315.288168 -322.376292) (xy 268.910054 -322.376292) (xy 268.910054 -323.600318)
			(xy 268.910201 -323.606187) (xy 268.912891 -323.617612) (xy 268.915388 -323.622924) (xy 268.917166 -323.62648)
			(xy 268.929358 -323.646546) (xy 268.93774 -323.65696) (xy 268.942566 -323.661532) (xy 268.948408 -323.664834)
			(xy 268.986138 -323.685897) (xy 269.058161 -323.733653) (xy 269.125749 -323.787503) (xy 269.188387 -323.847037)
			(xy 269.245601 -323.911803) (xy 269.296953 -323.981308) (xy 269.342054 -324.055022) (xy 269.380561 -324.132386)
			(xy 269.41218 -324.212811) (xy 269.436672 -324.295685) (xy 269.44574 -324.337934) (xy 269.455012 -324.386682)
			(xy 269.464932 -324.48542) (xy 269.465552 -324.535) (xy 273.274584 -324.535) (xy 273.278575 -324.446139)
			(xy 273.290515 -324.357994) (xy 273.310309 -324.271274) (xy 273.337796 -324.186677) (xy 273.372755 -324.104885)
			(xy 273.414906 -324.026556) (xy 273.463908 -323.95232) (xy 273.519368 -323.882776) (xy 273.580838 -323.818483)
			(xy 273.647824 -323.759959) (xy 273.719786 -323.707675) (xy 273.796145 -323.662053) (xy 273.876287 -323.623458)
			(xy 273.959565 -323.592203) (xy 274.04531 -323.568539) (xy 274.132831 -323.552656) (xy 274.221423 -323.544683)
			(xy 274.265898 -323.544184) (xy 276.018498 -323.544184) (xy 276.062977 -323.544592) (xy 276.151578 -323.552566)
			(xy 276.239107 -323.56845) (xy 276.32486 -323.592116) (xy 276.408146 -323.623374) (xy 276.488295 -323.661972)
			(xy 276.564662 -323.707598) (xy 276.636631 -323.759887) (xy 276.703623 -323.818416) (xy 276.765099 -323.882715)
			(xy 276.820564 -323.952266) (xy 276.869571 -324.026508) (xy 276.911726 -324.104845) (xy 276.946689 -324.186644)
			(xy 276.974178 -324.271249) (xy 276.993974 -324.357977) (xy 277.005915 -324.446131) (xy 277.009906 -324.535)
			(xy 280.818384 -324.535) (xy 280.822375 -324.446139) (xy 280.834315 -324.357994) (xy 280.854109 -324.271274)
			(xy 280.881596 -324.186677) (xy 280.916555 -324.104885) (xy 280.958706 -324.026556) (xy 281.007708 -323.95232)
			(xy 281.063168 -323.882776) (xy 281.124638 -323.818483) (xy 281.191624 -323.759959) (xy 281.263586 -323.707675)
			(xy 281.339945 -323.662053) (xy 281.420087 -323.623458) (xy 281.503365 -323.592203) (xy 281.58911 -323.568539)
			(xy 281.676631 -323.552656) (xy 281.765223 -323.544683) (xy 281.809698 -323.544184) (xy 283.562298 -323.544184)
			(xy 283.606777 -323.544592) (xy 283.695378 -323.552566) (xy 283.782907 -323.56845) (xy 283.86866 -323.592116)
			(xy 283.951946 -323.623374) (xy 284.032095 -323.661972) (xy 284.108462 -323.707598) (xy 284.180431 -323.759887)
			(xy 284.247423 -323.818416) (xy 284.308899 -323.882715) (xy 284.364364 -323.952266) (xy 284.413371 -324.026508)
			(xy 284.455526 -324.104845) (xy 284.490489 -324.186644) (xy 284.517978 -324.271249) (xy 284.537774 -324.357977)
			(xy 284.549715 -324.446131) (xy 284.553706 -324.535) (xy 288.362484 -324.535) (xy 288.366475 -324.446142)
			(xy 288.378414 -324.357999) (xy 288.398206 -324.271281) (xy 288.425692 -324.186687) (xy 288.46065 -324.104897)
			(xy 288.502798 -324.026569) (xy 288.551798 -323.952335) (xy 288.607254 -323.882792) (xy 288.668721 -323.818499)
			(xy 288.735703 -323.759975) (xy 288.807662 -323.707691) (xy 288.884018 -323.662068) (xy 288.964155 -323.623472)
			(xy 289.04743 -323.592215) (xy 289.133171 -323.568548) (xy 289.220689 -323.552662) (xy 289.309278 -323.544685)
			(xy 289.353752 -323.544184) (xy 291.106352 -323.544184) (xy 291.150833 -323.54459) (xy 291.239436 -323.552561)
			(xy 291.326968 -323.568441) (xy 291.412725 -323.592105) (xy 291.496015 -323.623361) (xy 291.576167 -323.661957)
			(xy 291.652537 -323.707582) (xy 291.72451 -323.75987) (xy 291.791506 -323.8184) (xy 291.852985 -323.882699)
			(xy 291.908453 -323.952251) (xy 291.957463 -324.026494) (xy 291.99962 -324.104833) (xy 292.034585 -324.186635)
			(xy 292.062076 -324.271242) (xy 292.081873 -324.357972) (xy 292.093815 -324.446128) (xy 292.097806 -324.535)
			(xy 295.90647 -324.535) (xy 295.910461 -324.446138) (xy 295.922401 -324.357991) (xy 295.942195 -324.271269)
			(xy 295.969683 -324.18667) (xy 296.004643 -324.104876) (xy 296.046795 -324.026546) (xy 296.095799 -323.952309)
			(xy 296.151259 -323.882764) (xy 296.212731 -323.81847) (xy 296.279719 -323.759945) (xy 296.351682 -323.70766)
			(xy 296.428043 -323.662037) (xy 296.508187 -323.623443) (xy 296.591467 -323.592188) (xy 296.677213 -323.568524)
			(xy 296.764736 -323.552641) (xy 296.85333 -323.544668) (xy 296.897806 -323.544184) (xy 298.650406 -323.544184)
			(xy 298.694884 -323.544607) (xy 298.783483 -323.552582) (xy 298.87101 -323.568466) (xy 298.956761 -323.592132)
			(xy 299.040046 -323.62339) (xy 299.120193 -323.661987) (xy 299.196558 -323.707613) (xy 299.268525 -323.759901)
			(xy 299.335516 -323.818429) (xy 299.39699 -323.882727) (xy 299.452454 -323.952277) (xy 299.50146 -324.026518)
			(xy 299.543614 -324.104853) (xy 299.578576 -324.186651) (xy 299.606065 -324.271254) (xy 299.62586 -324.357981)
			(xy 299.6378 -324.446133) (xy 299.641792 -324.535) (xy 303.450584 -324.535) (xy 303.454575 -324.446141)
			(xy 303.466515 -324.357998) (xy 303.486307 -324.27128) (xy 303.513793 -324.186685) (xy 303.548751 -324.104895)
			(xy 303.590899 -324.026567) (xy 303.6399 -323.952332) (xy 303.695357 -323.882789) (xy 303.756824 -323.818496)
			(xy 303.823807 -323.759973) (xy 303.895766 -323.707688) (xy 303.972122 -323.662065) (xy 304.052261 -323.62347)
			(xy 304.135536 -323.592213) (xy 304.221278 -323.568546) (xy 304.308796 -323.552661) (xy 304.397386 -323.544684)
			(xy 304.44186 -323.544184) (xy 306.19446 -323.544184) (xy 306.23894 -323.544591) (xy 306.327543 -323.552562)
			(xy 306.415075 -323.568443) (xy 306.500831 -323.592107) (xy 306.58412 -323.623363) (xy 306.664272 -323.661959)
			(xy 306.740642 -323.707585) (xy 306.812614 -323.759873) (xy 306.879609 -323.818403) (xy 306.941088 -323.882702)
			(xy 306.996555 -323.952253) (xy 307.045564 -324.026497) (xy 307.087721 -324.104835) (xy 307.122686 -324.186636)
			(xy 307.150177 -324.271243) (xy 307.169973 -324.357973) (xy 307.181915 -324.446129) (xy 307.185906 -324.535)
			(xy 307.181915 -324.623871) (xy 307.169973 -324.712027) (xy 307.150177 -324.798757) (xy 307.122686 -324.883364)
			(xy 307.087721 -324.965165) (xy 307.045564 -325.043503) (xy 306.996555 -325.117747) (xy 306.941088 -325.187298)
			(xy 306.879609 -325.251597) (xy 306.812614 -325.310127) (xy 306.740642 -325.362415) (xy 306.664272 -325.408041)
			(xy 306.58412 -325.446637) (xy 306.500831 -325.477893) (xy 306.415075 -325.501557) (xy 306.327543 -325.517438)
			(xy 306.23894 -325.525409) (xy 306.19446 -325.525892) (xy 304.44186 -325.525892) (xy 304.397386 -325.525316)
			(xy 304.308796 -325.517339) (xy 304.221278 -325.501454) (xy 304.135536 -325.477787) (xy 304.052261 -325.44653)
			(xy 303.972122 -325.407935) (xy 303.895766 -325.362312) (xy 303.823807 -325.310027) (xy 303.756824 -325.251504)
			(xy 303.695357 -325.187211) (xy 303.6399 -325.117668) (xy 303.590899 -325.043433) (xy 303.548751 -324.965105)
			(xy 303.513793 -324.883315) (xy 303.486307 -324.79872) (xy 303.466515 -324.712002) (xy 303.454575 -324.623859)
			(xy 303.450584 -324.535) (xy 299.641792 -324.535) (xy 299.6378 -324.623867) (xy 299.62586 -324.712019)
			(xy 299.606065 -324.798746) (xy 299.578576 -324.883349) (xy 299.543614 -324.965147) (xy 299.50146 -325.043482)
			(xy 299.452454 -325.117723) (xy 299.39699 -325.187273) (xy 299.335516 -325.251571) (xy 299.268525 -325.310099)
			(xy 299.196558 -325.362387) (xy 299.120193 -325.408013) (xy 299.040046 -325.44661) (xy 298.956761 -325.477868)
			(xy 298.87101 -325.501534) (xy 298.783483 -325.517418) (xy 298.694884 -325.525393) (xy 298.650406 -325.525892)
			(xy 296.897806 -325.525892) (xy 296.85333 -325.525332) (xy 296.764736 -325.517359) (xy 296.677213 -325.501476)
			(xy 296.591467 -325.477812) (xy 296.508187 -325.446557) (xy 296.428043 -325.407963) (xy 296.351682 -325.36234)
			(xy 296.279719 -325.310055) (xy 296.212731 -325.25153) (xy 296.151259 -325.187236) (xy 296.095799 -325.117691)
			(xy 296.046795 -325.043454) (xy 296.004643 -324.965124) (xy 295.969683 -324.88333) (xy 295.942195 -324.798731)
			(xy 295.922401 -324.712009) (xy 295.910461 -324.623862) (xy 295.90647 -324.535) (xy 292.097806 -324.535)
			(xy 292.093815 -324.623872) (xy 292.081873 -324.712028) (xy 292.062076 -324.798758) (xy 292.034585 -324.883365)
			(xy 291.99962 -324.965167) (xy 291.957463 -325.043506) (xy 291.908453 -325.117749) (xy 291.852985 -325.187301)
			(xy 291.791506 -325.2516) (xy 291.72451 -325.31013) (xy 291.652537 -325.362418) (xy 291.576167 -325.408043)
			(xy 291.496015 -325.446639) (xy 291.412725 -325.477895) (xy 291.326968 -325.501559) (xy 291.239436 -325.517439)
			(xy 291.150833 -325.52541) (xy 291.106352 -325.525892) (xy 289.353752 -325.525892) (xy 289.309278 -325.525315)
			(xy 289.220689 -325.517338) (xy 289.133171 -325.501452) (xy 289.04743 -325.477785) (xy 288.964155 -325.446528)
			(xy 288.884018 -325.407932) (xy 288.807662 -325.362309) (xy 288.735703 -325.310025) (xy 288.668721 -325.251501)
			(xy 288.607254 -325.187208) (xy 288.551798 -325.117665) (xy 288.502798 -325.043431) (xy 288.46065 -324.965103)
			(xy 288.425692 -324.883313) (xy 288.398206 -324.798719) (xy 288.378414 -324.712001) (xy 288.366475 -324.623858)
			(xy 288.362484 -324.535) (xy 284.553706 -324.535) (xy 284.549715 -324.623869) (xy 284.537774 -324.712023)
			(xy 284.517978 -324.798751) (xy 284.490489 -324.883356) (xy 284.455526 -324.965155) (xy 284.413371 -325.043492)
			(xy 284.364364 -325.117734) (xy 284.308899 -325.187285) (xy 284.247423 -325.251584) (xy 284.180431 -325.310113)
			(xy 284.108462 -325.362402) (xy 284.032095 -325.408028) (xy 283.951946 -325.446626) (xy 283.86866 -325.477884)
			(xy 283.782907 -325.50155) (xy 283.695378 -325.517434) (xy 283.606777 -325.525408) (xy 283.562298 -325.525892)
			(xy 281.809698 -325.525892) (xy 281.765223 -325.525317) (xy 281.676631 -325.517344) (xy 281.58911 -325.501461)
			(xy 281.503365 -325.477797) (xy 281.420087 -325.446542) (xy 281.339945 -325.407947) (xy 281.263586 -325.362325)
			(xy 281.191624 -325.310041) (xy 281.124638 -325.251517) (xy 281.063168 -325.187224) (xy 281.007708 -325.11768)
			(xy 280.958706 -325.043444) (xy 280.916555 -324.965115) (xy 280.881596 -324.883323) (xy 280.854109 -324.798726)
			(xy 280.834315 -324.712006) (xy 280.822375 -324.623861) (xy 280.818384 -324.535) (xy 277.009906 -324.535)
			(xy 277.005915 -324.623869) (xy 276.993974 -324.712023) (xy 276.974178 -324.798751) (xy 276.946689 -324.883356)
			(xy 276.911726 -324.965155) (xy 276.869571 -325.043492) (xy 276.820564 -325.117734) (xy 276.765099 -325.187285)
			(xy 276.703623 -325.251584) (xy 276.636631 -325.310113) (xy 276.564662 -325.362402) (xy 276.488295 -325.408028)
			(xy 276.408146 -325.446626) (xy 276.32486 -325.477884) (xy 276.239107 -325.50155) (xy 276.151578 -325.517434)
			(xy 276.062977 -325.525408) (xy 276.018498 -325.525892) (xy 274.265898 -325.525892) (xy 274.221423 -325.525317)
			(xy 274.132831 -325.517344) (xy 274.04531 -325.501461) (xy 273.959565 -325.477797) (xy 273.876287 -325.446542)
			(xy 273.796145 -325.407947) (xy 273.719786 -325.362325) (xy 273.647824 -325.310041) (xy 273.580838 -325.251517)
			(xy 273.519368 -325.187224) (xy 273.463908 -325.11768) (xy 273.414906 -325.043444) (xy 273.372755 -324.965115)
			(xy 273.337796 -324.883323) (xy 273.310309 -324.798726) (xy 273.290515 -324.712006) (xy 273.278575 -324.623861)
			(xy 273.274584 -324.535) (xy 269.465552 -324.535) (xy 269.465552 -324.535038) (xy 269.464999 -324.582017)
			(xy 269.456101 -324.675551) (xy 269.438388 -324.767824) (xy 269.41202 -324.858005) (xy 269.377234 -324.945286)
			(xy 269.334341 -325.028881) (xy 269.283728 -325.10804) (xy 269.25524 -325.1454) (xy 269.229987 -325.177081)
			(xy 269.175066 -325.236652) (xy 269.115457 -325.291532) (xy 269.05156 -325.341353) (xy 268.983802 -325.385782)
			(xy 268.948408 -325.405496) (xy 268.945106 -325.407274) (xy 268.943074 -325.408798) (xy 268.934692 -325.41464)
			(xy 268.916404 -325.44512) (xy 268.913755 -325.450147) (xy 268.910555 -325.461049) (xy 268.910054 -325.46671)
			(xy 268.910054 -328.124349) (xy 316.369712 -328.124349) (xy 316.369712 -328.069851) (xy 316.377468 -328.015908)
			(xy 316.392822 -327.963618) (xy 316.415461 -327.914046) (xy 316.444924 -327.868199) (xy 316.480613 -327.827013)
			(xy 316.521799 -327.791324) (xy 316.567646 -327.761861) (xy 316.617218 -327.739222) (xy 316.669508 -327.723868)
			(xy 316.723451 -327.716112) (xy 316.7507 -327.715626) (xy 316.779438 -327.71617) (xy 316.836264 -327.72479)
			(xy 316.891153 -327.741837) (xy 316.942865 -327.766923) (xy 316.99023 -327.799483) (xy 317.011558 -327.81875)
			(xy 317.018416 -327.825354) (xy 317.03645 -327.832466) (xy 317.12535 -327.832466) (xy 317.143384 -327.825354)
			(xy 317.150242 -327.81875) (xy 317.171571 -327.799481) (xy 317.218932 -327.766914) (xy 317.270643 -327.741821)
			(xy 317.325534 -327.72477) (xy 317.382361 -327.716147) (xy 317.4111 -327.715626) (xy 317.438354 -327.716044)
			(xy 317.492306 -327.723801) (xy 317.544606 -327.739158) (xy 317.594187 -327.761801) (xy 317.640042 -327.79127)
			(xy 317.681236 -327.826964) (xy 317.71693 -327.868158) (xy 317.746399 -327.914013) (xy 317.769042 -327.963594)
			(xy 317.784399 -328.015894) (xy 317.792156 -328.069846) (xy 317.792156 -328.124349) (xy 319.011312 -328.124349)
			(xy 319.011312 -328.069851) (xy 319.019068 -328.015908) (xy 319.034422 -327.963618) (xy 319.057061 -327.914046)
			(xy 319.086524 -327.868199) (xy 319.122213 -327.827013) (xy 319.163399 -327.791324) (xy 319.209246 -327.761861)
			(xy 319.258818 -327.739222) (xy 319.311108 -327.723868) (xy 319.365051 -327.716112) (xy 319.3923 -327.715626)
			(xy 319.421038 -327.71617) (xy 319.477864 -327.72479) (xy 319.532753 -327.741837) (xy 319.584465 -327.766923)
			(xy 319.63183 -327.799483) (xy 319.653158 -327.81875) (xy 319.660016 -327.825354) (xy 319.67805 -327.832466)
			(xy 319.76695 -327.832466) (xy 319.784984 -327.825354) (xy 319.791842 -327.81875) (xy 319.813171 -327.799481)
			(xy 319.860532 -327.766914) (xy 319.912243 -327.741821) (xy 319.967134 -327.72477) (xy 320.023961 -327.716147)
			(xy 320.0527 -327.715626) (xy 320.079954 -327.716044) (xy 320.133906 -327.723801) (xy 320.186206 -327.739158)
			(xy 320.235787 -327.761801) (xy 320.281642 -327.79127) (xy 320.322836 -327.826964) (xy 320.35853 -327.868158)
			(xy 320.387999 -327.914013) (xy 320.410642 -327.963594) (xy 320.425999 -328.015894) (xy 320.433756 -328.069846)
			(xy 320.433756 -328.124354) (xy 320.425999 -328.178306) (xy 320.410642 -328.230606) (xy 320.387999 -328.280187)
			(xy 320.35853 -328.326042) (xy 320.322836 -328.367236) (xy 320.281642 -328.40293) (xy 320.235787 -328.432399)
			(xy 320.186206 -328.455042) (xy 320.133906 -328.470399) (xy 320.079954 -328.478156) (xy 320.0527 -328.478642)
			(xy 320.023962 -328.478107) (xy 319.967135 -328.469485) (xy 319.912245 -328.452437) (xy 319.860533 -328.427349)
			(xy 319.81317 -328.394787) (xy 319.791842 -328.375518) (xy 319.784984 -328.368914) (xy 319.76695 -328.361802)
			(xy 319.67805 -328.361802) (xy 319.660016 -328.368914) (xy 319.653158 -328.375518) (xy 319.631824 -328.394781)
			(xy 319.584465 -328.42735) (xy 319.532755 -328.452445) (xy 319.477865 -328.469497) (xy 319.421039 -328.478121)
			(xy 319.3923 -328.478642) (xy 319.365051 -328.478088) (xy 319.311108 -328.470332) (xy 319.258818 -328.454978)
			(xy 319.209246 -328.432339) (xy 319.163399 -328.402876) (xy 319.122213 -328.367187) (xy 319.086524 -328.326001)
			(xy 319.057061 -328.280154) (xy 319.034422 -328.230582) (xy 319.019068 -328.178292) (xy 319.011312 -328.124349)
			(xy 317.792156 -328.124349) (xy 317.792156 -328.124354) (xy 317.784399 -328.178306) (xy 317.769042 -328.230606)
			(xy 317.746399 -328.280187) (xy 317.71693 -328.326042) (xy 317.681236 -328.367236) (xy 317.640042 -328.40293)
			(xy 317.594187 -328.432399) (xy 317.544606 -328.455042) (xy 317.492306 -328.470399) (xy 317.438354 -328.478156)
			(xy 317.4111 -328.478642) (xy 317.382362 -328.478107) (xy 317.325535 -328.469485) (xy 317.270645 -328.452437)
			(xy 317.218933 -328.427349) (xy 317.17157 -328.394787) (xy 317.150242 -328.375518) (xy 317.143384 -328.368914)
			(xy 317.12535 -328.361802) (xy 317.03645 -328.361802) (xy 317.018416 -328.368914) (xy 317.011558 -328.375518)
			(xy 316.990224 -328.394781) (xy 316.942865 -328.42735) (xy 316.891155 -328.452445) (xy 316.836265 -328.469497)
			(xy 316.779439 -328.478121) (xy 316.7507 -328.478642) (xy 316.723451 -328.478088) (xy 316.669508 -328.470332)
			(xy 316.617218 -328.454978) (xy 316.567646 -328.432339) (xy 316.521799 -328.402876) (xy 316.480613 -328.367187)
			(xy 316.444924 -328.326001) (xy 316.415461 -328.280154) (xy 316.392822 -328.230582) (xy 316.377468 -328.178292)
			(xy 316.369712 -328.124349) (xy 268.910054 -328.124349) (xy 268.910054 -333.675736) (xy 268.910816 -333.680054)
			(xy 268.913308 -333.695811) (xy 268.91598 -333.727602) (xy 268.91615 -333.743554) (xy 268.91615 -333.744316)
			(xy 269.041116 -333.744316) (xy 269.045187 -333.688694) (xy 269.057313 -333.634257) (xy 269.077236 -333.582166)
			(xy 269.104532 -333.533531) (xy 269.138618 -333.489388) (xy 269.178767 -333.450679) (xy 269.224125 -333.418228)
			(xy 269.273725 -333.392727) (xy 269.326509 -333.37472) (xy 269.381352 -333.36459) (xy 269.437086 -333.362553)
			(xy 269.492523 -333.368653) (xy 269.54648 -333.382759) (xy 269.597809 -333.404571) (xy 269.645415 -333.433625)
			(xy 269.688283 -333.4693) (xy 269.7255 -333.510837) (xy 269.756273 -333.55735) (xy 269.779945 -333.607847)
			(xy 269.796013 -333.661254) (xy 269.804133 -333.71643) (xy 269.804642 -333.744316) (xy 269.804133 -333.772202)
			(xy 269.796013 -333.827378) (xy 269.779945 -333.880785) (xy 269.756273 -333.931282) (xy 269.7255 -333.977795)
			(xy 269.688283 -334.019332) (xy 269.645415 -334.055007) (xy 269.597809 -334.084061) (xy 269.54648 -334.105873)
			(xy 269.492523 -334.119979) (xy 269.437086 -334.126079) (xy 269.381352 -334.124042) (xy 269.326509 -334.113912)
			(xy 269.273725 -334.095905) (xy 269.224125 -334.070404) (xy 269.178767 -334.037953) (xy 269.138618 -333.999244)
			(xy 269.104532 -333.955101) (xy 269.077236 -333.906466) (xy 269.057313 -333.854375) (xy 269.045187 -333.799938)
			(xy 269.041116 -333.744316) (xy 268.91615 -333.744316) (xy 268.91615 -333.745078) (xy 268.915987 -333.76103)
			(xy 268.913313 -333.792822) (xy 268.910816 -333.808578) (xy 268.910054 -333.812896) (xy 268.910054 -335.567782)
			(xy 268.91107 -335.577434) (xy 268.912697 -335.584678) (xy 268.919539 -335.597847) (xy 268.924532 -335.603342)
			(xy 270.003524 -336.682334) (xy 270.009024 -336.687319) (xy 270.022191 -336.694159) (xy 270.029432 -336.695796)
			(xy 270.039084 -336.696812) (xy 302.885602 -336.696812) (xy 302.895501 -336.696292) (xy 302.913796 -336.688713)
			(xy 302.921162 -336.68208) (xy 302.935386 -336.668872) (xy 302.935386 -336.615024) (xy 302.934949 -336.60496)
			(xy 302.927213 -336.586377) (xy 302.9204 -336.578956) (xy 302.899467 -336.557338) (xy 302.863992 -336.508734)
			(xy 302.836585 -336.455165) (xy 302.817924 -336.397959) (xy 302.808473 -336.338532) (xy 302.807878 -336.308446)
			(xy 302.808353 -336.281077) (xy 302.816183 -336.226902) (xy 302.831676 -336.174403) (xy 302.854512 -336.124656)
			(xy 302.884223 -336.078683) (xy 302.901858 -336.057748) (xy 302.901858 -336.057494) (xy 302.902112 -336.057494)
			(xy 302.907695 -336.050407) (xy 302.913934 -336.03349) (xy 302.914304 -336.024474) (xy 302.914304 -335.957418)
			(xy 302.913948 -335.9484) (xy 302.907705 -335.93148) (xy 302.902112 -335.924398) (xy 302.901858 -335.924144)
			(xy 302.884217 -335.903213) (xy 302.854493 -335.857246) (xy 302.831654 -335.807499) (xy 302.816169 -335.754995)
			(xy 302.808357 -335.700816) (xy 302.807878 -335.673446) (xy 302.808338 -335.646191) (xy 302.816089 -335.592234)
			(xy 302.831441 -335.53993) (xy 302.854081 -335.490343) (xy 302.883547 -335.444483) (xy 302.919241 -335.403283)
			(xy 302.960435 -335.367583) (xy 303.00629 -335.33811) (xy 303.055873 -335.315462) (xy 303.108175 -335.300102)
			(xy 303.162131 -335.292342) (xy 303.189386 -335.291938) (xy 303.218125 -335.292458) (xy 303.274953 -335.301079)
			(xy 303.329845 -335.318129) (xy 303.381557 -335.343222) (xy 303.428919 -335.375789) (xy 303.450244 -335.395062)
			(xy 303.457102 -335.401666) (xy 303.475136 -335.408778) (xy 303.564036 -335.408778) (xy 303.58207 -335.401666)
			(xy 303.588928 -335.395062) (xy 303.610256 -335.375793) (xy 303.65762 -335.343231) (xy 303.709331 -335.318142)
			(xy 303.764221 -335.301093) (xy 303.821048 -335.29247) (xy 303.849786 -335.291938) (xy 303.877038 -335.2924)
			(xy 303.930988 -335.300156) (xy 303.983285 -335.315511) (xy 304.032864 -335.338154) (xy 304.078716 -335.367622)
			(xy 304.119906 -335.403316) (xy 304.155597 -335.44451) (xy 304.185062 -335.490364) (xy 304.2077 -335.539945)
			(xy 304.223051 -335.592243) (xy 304.230802 -335.646194) (xy 304.231294 -335.673446) (xy 304.230819 -335.700815)
			(xy 304.222989 -335.75499) (xy 304.207497 -335.807489) (xy 304.18466 -335.857236) (xy 304.154948 -335.903208)
			(xy 304.137314 -335.924144) (xy 304.137314 -335.924398) (xy 304.13706 -335.924398) (xy 304.131478 -335.931486)
			(xy 304.125241 -335.948403) (xy 304.124868 -335.957418) (xy 304.124868 -336.024474) (xy 304.125222 -336.033493)
			(xy 304.13146 -336.050417) (xy 304.13706 -336.057494) (xy 304.137314 -336.057748) (xy 304.154953 -336.078681)
			(xy 304.184672 -336.124648) (xy 304.207508 -336.174396) (xy 304.222991 -336.226899) (xy 304.230802 -336.281077)
			(xy 304.231294 -336.308446) (xy 304.23086 -336.334307) (xy 304.223863 -336.385555) (xy 304.210005 -336.435386)
			(xy 304.18954 -336.482888) (xy 304.162843 -336.527188) (xy 304.130404 -336.567473) (xy 304.111914 -336.58556)
			(xy 304.105077 -336.592713) (xy 304.096989 -336.61075) (xy 304.096166 -336.620612) (xy 304.094896 -336.652362)
			(xy 304.095058 -336.662184) (xy 304.101855 -336.680596) (xy 304.108104 -336.688176) (xy 304.11547 -336.696812)
			(xy 305.097434 -336.696812) (xy 305.106868 -336.696445) (xy 305.124464 -336.689635) (xy 305.138399 -336.676916)
			(xy 305.1429 -336.668618) (xy 305.18354 -336.587338) (xy 305.187419 -336.57871) (xy 305.189147 -336.559886)
			(xy 305.183923 -336.541718) (xy 305.17846 -336.533998) (xy 305.160351 -336.509009) (xy 305.131594 -336.454407)
			(xy 305.111994 -336.395891) (xy 305.102063 -336.334984) (xy 305.101498 -336.304128) (xy 305.101982 -336.276216)
			(xy 305.110113 -336.220987) (xy 305.126206 -336.167533) (xy 305.149917 -336.116995) (xy 305.18074 -336.070452)
			(xy 305.199034 -336.049366) (xy 305.205384 -336.042254) (xy 305.211988 -336.024982) (xy 305.211988 -335.947512)
			(xy 305.211588 -335.93823) (xy 305.204948 -335.920895) (xy 305.199034 -335.91373) (xy 305.180753 -335.892631)
			(xy 305.14992 -335.846094) (xy 305.126198 -335.79556) (xy 305.110093 -335.742108) (xy 305.101948 -335.68688)
			(xy 305.101498 -335.658968) (xy 305.101986 -335.631718) (xy 305.109746 -335.577774) (xy 305.125104 -335.525484)
			(xy 305.147747 -335.475911) (xy 305.177214 -335.430065) (xy 305.212906 -335.388879) (xy 305.254096 -335.353192)
			(xy 305.299944 -335.323729) (xy 305.34952 -335.301091) (xy 305.401812 -335.285738) (xy 305.455756 -335.277983)
			(xy 305.483006 -335.27746) (xy 305.510376 -335.277932) (xy 305.564552 -335.285758) (xy 305.617054 -335.301248)
			(xy 305.666803 -335.324083) (xy 305.712776 -335.353796) (xy 305.733704 -335.37144) (xy 305.733958 -335.37144)
			(xy 305.733958 -335.371694) (xy 305.741043 -335.377286) (xy 305.75796 -335.383543) (xy 305.766978 -335.383886)
			(xy 305.834034 -335.383886) (xy 305.843048 -335.383521) (xy 305.859956 -335.377263) (xy 305.867054 -335.371694)
			(xy 305.867308 -335.37144) (xy 305.876948 -335.363175) (xy 305.897159 -335.347796) (xy 305.907694 -335.340706)
			(xy 305.907948 -335.340452) (xy 305.918148 -335.332795) (xy 305.930036 -335.310267) (xy 305.930554 -335.297526)
			(xy 305.929284 -335.211674) (xy 305.928837 -335.203198) (xy 305.923065 -335.187246) (xy 305.912422 -335.174036)
			(xy 305.905408 -335.169256) (xy 305.905154 -335.169256) (xy 305.877891 -335.151838) (xy 305.827591 -335.111152)
			(xy 305.782862 -335.06441) (xy 305.744428 -335.01237) (xy 305.712909 -334.955871) (xy 305.688816 -334.89583)
			(xy 305.672539 -334.833215) (xy 305.664341 -334.769042) (xy 305.663854 -334.736694) (xy 305.664317 -334.705973)
			(xy 305.671718 -334.644979) (xy 305.686411 -334.585321) (xy 305.708182 -334.527866) (xy 305.736715 -334.473452)
			(xy 305.75377 -334.447896) (xy 305.759165 -334.439212) (xy 305.763227 -334.419195) (xy 305.759161 -334.399178)
			(xy 305.75377 -334.390492) (xy 305.736712 -334.364938) (xy 305.70818 -334.310523) (xy 305.68641 -334.253068)
			(xy 305.671719 -334.19341) (xy 305.664319 -334.132416) (xy 305.66432 -334.070974) (xy 305.67172 -334.009981)
			(xy 305.686413 -333.950322) (xy 305.708185 -333.892868) (xy 305.736717 -333.838453) (xy 305.75377 -333.812896)
			(xy 305.759165 -333.804212) (xy 305.763227 -333.784195) (xy 305.759161 -333.764178) (xy 305.75377 -333.755492)
			(xy 305.736712 -333.729938) (xy 305.70818 -333.675523) (xy 305.68641 -333.618068) (xy 305.671719 -333.55841)
			(xy 305.664319 -333.497416) (xy 305.66432 -333.435974) (xy 305.67172 -333.374981) (xy 305.686413 -333.315322)
			(xy 305.708185 -333.257868) (xy 305.736717 -333.203453) (xy 305.75377 -333.177896) (xy 305.759165 -333.169212)
			(xy 305.763227 -333.149195) (xy 305.759161 -333.129178) (xy 305.75377 -333.120492) (xy 305.736712 -333.094938)
			(xy 305.70818 -333.040523) (xy 305.68641 -332.983068) (xy 305.671719 -332.92341) (xy 305.664319 -332.862416)
			(xy 305.66432 -332.800974) (xy 305.67172 -332.739981) (xy 305.686413 -332.680322) (xy 305.708185 -332.622868)
			(xy 305.736717 -332.568453) (xy 305.75377 -332.542896) (xy 305.759165 -332.534212) (xy 305.763227 -332.514195)
			(xy 305.759161 -332.494178) (xy 305.75377 -332.485492) (xy 305.736712 -332.459938) (xy 305.70818 -332.405523)
			(xy 305.68641 -332.348068) (xy 305.671719 -332.28841) (xy 305.664319 -332.227416) (xy 305.66432 -332.165974)
			(xy 305.67172 -332.104981) (xy 305.686413 -332.045322) (xy 305.708185 -331.987868) (xy 305.736717 -331.933453)
			(xy 305.75377 -331.907896) (xy 305.759165 -331.899212) (xy 305.763227 -331.879195) (xy 305.759161 -331.859178)
			(xy 305.75377 -331.850492) (xy 305.736712 -331.824938) (xy 305.70818 -331.770523) (xy 305.68641 -331.713068)
			(xy 305.671719 -331.65341) (xy 305.664319 -331.592416) (xy 305.66432 -331.530974) (xy 305.67172 -331.469981)
			(xy 305.686413 -331.410322) (xy 305.708185 -331.352868) (xy 305.736717 -331.298453) (xy 305.75377 -331.272896)
			(xy 305.759165 -331.264212) (xy 305.763227 -331.244195) (xy 305.759161 -331.224178) (xy 305.75377 -331.215492)
			(xy 305.736712 -331.189938) (xy 305.70818 -331.135523) (xy 305.68641 -331.078068) (xy 305.671719 -331.01841)
			(xy 305.664319 -330.957416) (xy 305.66432 -330.895974) (xy 305.67172 -330.834981) (xy 305.686413 -330.775322)
			(xy 305.708185 -330.717868) (xy 305.736717 -330.663453) (xy 305.75377 -330.637896) (xy 305.759165 -330.629212)
			(xy 305.763227 -330.609195) (xy 305.759161 -330.589178) (xy 305.75377 -330.580492) (xy 305.736712 -330.554938)
			(xy 305.70818 -330.500523) (xy 305.68641 -330.443068) (xy 305.671719 -330.383409) (xy 305.664319 -330.322415)
			(xy 305.663854 -330.291694) (xy 305.664318 -330.260962) (xy 305.671727 -330.199947) (xy 305.686436 -330.14027)
			(xy 305.708231 -330.082801) (xy 305.736793 -330.028377) (xy 305.771707 -329.977793) (xy 305.812464 -329.931786)
			(xy 305.858468 -329.891027) (xy 305.90905 -329.85611) (xy 305.963471 -329.827544) (xy 306.020939 -329.805745)
			(xy 306.080616 -329.791033) (xy 306.14163 -329.78362) (xy 306.172362 -329.783186) (xy 306.203083 -329.783646)
			(xy 306.264079 -329.791043) (xy 306.32374 -329.805732) (xy 306.381197 -329.8275) (xy 306.435614 -329.856031)
			(xy 306.46116 -329.873102) (xy 306.469845 -329.878495) (xy 306.489862 -329.882556) (xy 306.509879 -329.878495)
			(xy 306.518564 -329.873102) (xy 306.544118 -329.856044) (xy 306.598533 -329.827513) (xy 306.655988 -329.805742)
			(xy 306.715647 -329.79105) (xy 306.776641 -329.78365) (xy 306.838083 -329.78365) (xy 306.899077 -329.79105)
			(xy 306.958736 -329.805742) (xy 307.016191 -329.827513) (xy 307.070606 -329.856044) (xy 307.09616 -329.873102)
			(xy 307.104845 -329.878495) (xy 307.124862 -329.882556) (xy 307.144879 -329.878495) (xy 307.153564 -329.873102)
			(xy 307.179118 -329.856044) (xy 307.233533 -329.827511) (xy 307.290988 -329.805739) (xy 307.350647 -329.791044)
			(xy 307.411641 -329.783641) (xy 307.442362 -329.783186) (xy 307.473096 -329.783629) (xy 307.534115 -329.791034)
			(xy 307.593798 -329.80574) (xy 307.651272 -329.827534) (xy 307.7057 -329.856096) (xy 307.756289 -329.891011)
			(xy 307.8023 -329.931769) (xy 307.843062 -329.977777) (xy 307.877981 -330.028362) (xy 307.906548 -330.082788)
			(xy 307.928346 -330.14026) (xy 307.943058 -330.199941) (xy 307.950468 -330.26096) (xy 307.95087 -330.291694)
			(xy 307.950408 -330.322415) (xy 307.943009 -330.38341) (xy 307.928318 -330.443069) (xy 307.906548 -330.500526)
			(xy 307.878018 -330.554942) (xy 307.860954 -330.580492) (xy 307.855563 -330.589178) (xy 307.851503 -330.609195)
			(xy 307.855559 -330.629213) (xy 307.860954 -330.637896) (xy 307.878012 -330.66345) (xy 307.906544 -330.717865)
			(xy 307.928314 -330.775321) (xy 307.943006 -330.83498) (xy 307.950407 -330.895974) (xy 307.950407 -330.957416)
			(xy 307.943008 -331.01841) (xy 307.928317 -331.07807) (xy 307.906548 -331.135526) (xy 307.878017 -331.189942)
			(xy 307.860954 -331.215492) (xy 307.855563 -331.224178) (xy 307.851503 -331.244195) (xy 307.855559 -331.264213)
			(xy 307.860954 -331.272896) (xy 307.878012 -331.29845) (xy 307.906544 -331.352865) (xy 307.928314 -331.410321)
			(xy 307.943006 -331.46998) (xy 307.950407 -331.530974) (xy 307.950407 -331.592416) (xy 307.943008 -331.65341)
			(xy 307.928317 -331.71307) (xy 307.906548 -331.770526) (xy 307.878017 -331.824942) (xy 307.860954 -331.850492)
			(xy 307.855563 -331.859178) (xy 307.851503 -331.879195) (xy 307.855559 -331.899213) (xy 307.860954 -331.907896)
			(xy 307.878012 -331.93345) (xy 307.906544 -331.987865) (xy 307.928314 -332.045321) (xy 307.943006 -332.10498)
			(xy 307.950407 -332.165974) (xy 307.950407 -332.227416) (xy 307.943008 -332.28841) (xy 307.928317 -332.34807)
			(xy 307.906548 -332.405526) (xy 307.878017 -332.459942) (xy 307.860954 -332.485492) (xy 307.855563 -332.494178)
			(xy 307.851503 -332.514195) (xy 307.855559 -332.534213) (xy 307.860954 -332.542896) (xy 307.878012 -332.56845)
			(xy 307.906544 -332.622865) (xy 307.928314 -332.680321) (xy 307.943006 -332.73998) (xy 307.950407 -332.800974)
			(xy 307.950407 -332.862416) (xy 307.943008 -332.92341) (xy 307.928317 -332.98307) (xy 307.906548 -333.040526)
			(xy 307.878017 -333.094942) (xy 307.860954 -333.120492) (xy 307.855563 -333.129178) (xy 307.851503 -333.149195)
			(xy 307.855559 -333.169213) (xy 307.860954 -333.177896) (xy 307.878012 -333.20345) (xy 307.906544 -333.257865)
			(xy 307.928314 -333.315321) (xy 307.943006 -333.37498) (xy 307.950407 -333.435974) (xy 307.950407 -333.497416)
			(xy 307.943008 -333.55841) (xy 307.928317 -333.61807) (xy 307.906548 -333.675526) (xy 307.878017 -333.729942)
			(xy 307.860954 -333.755492) (xy 307.855563 -333.764178) (xy 307.851503 -333.784195) (xy 307.855559 -333.804213)
			(xy 307.860954 -333.812896) (xy 307.878012 -333.83845) (xy 307.906544 -333.892865) (xy 307.928314 -333.950321)
			(xy 307.943006 -334.00998) (xy 307.950407 -334.070974) (xy 307.950407 -334.132416) (xy 307.943008 -334.19341)
			(xy 307.928317 -334.25307) (xy 307.906548 -334.310526) (xy 307.878017 -334.364942) (xy 307.860954 -334.390492)
			(xy 307.855563 -334.399178) (xy 307.851503 -334.419195) (xy 307.855559 -334.439213) (xy 307.860954 -334.447896)
			(xy 307.878012 -334.47345) (xy 307.906543 -334.527865) (xy 307.928314 -334.58532) (xy 307.943006 -334.644979)
			(xy 307.950407 -334.705973) (xy 307.95087 -334.736694) (xy 309.677054 -334.736694) (xy 309.677513 -334.705973)
			(xy 309.684914 -334.644979) (xy 309.699607 -334.58532) (xy 309.721378 -334.527864) (xy 309.749911 -334.47345)
			(xy 309.76697 -334.447896) (xy 309.772371 -334.439215) (xy 309.776434 -334.419195) (xy 309.772367 -334.399176)
			(xy 309.76697 -334.390492) (xy 309.749906 -334.364942) (xy 309.721374 -334.310526) (xy 309.699604 -334.25307)
			(xy 309.684912 -334.193411) (xy 309.677512 -334.132416) (xy 309.677513 -334.070974) (xy 309.684914 -334.009979)
			(xy 309.699607 -333.95032) (xy 309.721378 -333.892865) (xy 309.749911 -333.83845) (xy 309.76697 -333.812896)
			(xy 309.772371 -333.804215) (xy 309.776434 -333.784195) (xy 309.772367 -333.764176) (xy 309.76697 -333.755492)
			(xy 309.749906 -333.729942) (xy 309.721374 -333.675526) (xy 309.699604 -333.61807) (xy 309.684912 -333.558411)
			(xy 309.677512 -333.497416) (xy 309.677513 -333.435974) (xy 309.684914 -333.374979) (xy 309.699607 -333.31532)
			(xy 309.721378 -333.257865) (xy 309.749911 -333.20345) (xy 309.76697 -333.177896) (xy 309.772371 -333.169215)
			(xy 309.776434 -333.149195) (xy 309.772367 -333.129176) (xy 309.76697 -333.120492) (xy 309.749906 -333.094942)
			(xy 309.721374 -333.040526) (xy 309.699604 -332.98307) (xy 309.684912 -332.923411) (xy 309.677512 -332.862416)
			(xy 309.677513 -332.800974) (xy 309.684914 -332.739979) (xy 309.699607 -332.68032) (xy 309.721378 -332.622865)
			(xy 309.749911 -332.56845) (xy 309.76697 -332.542896) (xy 309.772371 -332.534215) (xy 309.776434 -332.514195)
			(xy 309.772367 -332.494176) (xy 309.76697 -332.485492) (xy 309.749906 -332.459942) (xy 309.721374 -332.405526)
			(xy 309.699604 -332.34807) (xy 309.684912 -332.288411) (xy 309.677512 -332.227416) (xy 309.677513 -332.165974)
			(xy 309.684914 -332.104979) (xy 309.699607 -332.04532) (xy 309.721378 -331.987865) (xy 309.749911 -331.93345)
			(xy 309.76697 -331.907896) (xy 309.772371 -331.899215) (xy 309.776434 -331.879195) (xy 309.772367 -331.859176)
			(xy 309.76697 -331.850492) (xy 309.749906 -331.824942) (xy 309.721374 -331.770526) (xy 309.699604 -331.71307)
			(xy 309.684912 -331.653411) (xy 309.677512 -331.592416) (xy 309.677513 -331.530974) (xy 309.684914 -331.469979)
			(xy 309.699607 -331.41032) (xy 309.721378 -331.352865) (xy 309.749911 -331.29845) (xy 309.76697 -331.272896)
			(xy 309.772371 -331.264215) (xy 309.776434 -331.244195) (xy 309.772367 -331.224176) (xy 309.76697 -331.215492)
			(xy 309.749906 -331.189942) (xy 309.721374 -331.135526) (xy 309.699604 -331.07807) (xy 309.684912 -331.018411)
			(xy 309.677512 -330.957416) (xy 309.677513 -330.895974) (xy 309.684914 -330.834979) (xy 309.699607 -330.77532)
			(xy 309.721378 -330.717865) (xy 309.749911 -330.66345) (xy 309.76697 -330.637896) (xy 309.772371 -330.629215)
			(xy 309.776434 -330.609195) (xy 309.772367 -330.589176) (xy 309.76697 -330.580492) (xy 309.749909 -330.55494)
			(xy 309.721378 -330.500524) (xy 309.699607 -330.443069) (xy 309.684916 -330.383409) (xy 309.677516 -330.322415)
			(xy 309.677054 -330.291694) (xy 309.67755 -330.260964) (xy 309.684959 -330.199953) (xy 309.699667 -330.14028)
			(xy 309.72146 -330.082814) (xy 309.750021 -330.028394) (xy 309.784933 -329.977813) (xy 309.825687 -329.931809)
			(xy 309.871688 -329.891052) (xy 309.922267 -329.856138) (xy 309.976685 -329.827573) (xy 310.034149 -329.805776)
			(xy 310.093822 -329.791065) (xy 310.154832 -329.783652) (xy 310.185562 -329.783186) (xy 310.216283 -329.783629)
			(xy 310.277278 -329.791035) (xy 310.336937 -329.805733) (xy 310.394392 -329.827507) (xy 310.448806 -329.856043)
			(xy 310.47436 -329.873102) (xy 310.483045 -329.878495) (xy 310.503062 -329.882556) (xy 310.523079 -329.878495)
			(xy 310.531764 -329.873102) (xy 310.557331 -329.856064) (xy 310.611742 -329.827528) (xy 310.669194 -329.805753)
			(xy 310.72885 -329.791056) (xy 310.789842 -329.783651) (xy 310.820562 -329.783186) (xy 310.851293 -329.783673)
			(xy 310.912308 -329.791078) (xy 310.971985 -329.805782) (xy 311.029454 -329.827574) (xy 311.083878 -329.856134)
			(xy 311.134462 -329.891046) (xy 311.180469 -329.9318) (xy 311.221227 -329.977804) (xy 311.256144 -330.028385)
			(xy 311.284708 -330.082806) (xy 311.306504 -330.140273) (xy 311.321215 -330.199949) (xy 311.328624 -330.260963)
			(xy 311.32907 -330.291694) (xy 311.328601 -330.322415) (xy 311.321202 -330.383408) (xy 311.306511 -330.443067)
			(xy 311.284742 -330.500523) (xy 311.256211 -330.554938) (xy 311.239154 -330.580492) (xy 311.23377 -330.589181)
			(xy 311.22971 -330.609195) (xy 311.233766 -330.62921) (xy 311.239154 -330.637896) (xy 311.256206 -330.663454)
			(xy 311.284737 -330.717868) (xy 311.306508 -330.775323) (xy 311.3212 -330.834981) (xy 311.3286 -330.895975)
			(xy 311.328601 -330.957415) (xy 311.321201 -331.018409) (xy 311.30651 -331.078068) (xy 311.284741 -331.135523)
			(xy 311.256211 -331.189938) (xy 311.239154 -331.215492) (xy 311.23377 -331.224181) (xy 311.22971 -331.244195)
			(xy 311.233766 -331.26421) (xy 311.239154 -331.272896) (xy 311.256206 -331.298454) (xy 311.284737 -331.352868)
			(xy 311.306508 -331.410323) (xy 311.3212 -331.469981) (xy 311.3286 -331.530975) (xy 311.328601 -331.592415)
			(xy 311.321201 -331.653409) (xy 311.30651 -331.713068) (xy 311.284741 -331.770523) (xy 311.256211 -331.824938)
			(xy 311.239154 -331.850492) (xy 311.23377 -331.859181) (xy 311.22971 -331.879195) (xy 311.233766 -331.89921)
			(xy 311.239154 -331.907896) (xy 311.256206 -331.933454) (xy 311.284737 -331.987868) (xy 311.306508 -332.045323)
			(xy 311.3212 -332.104981) (xy 311.3286 -332.165975) (xy 311.328601 -332.227415) (xy 311.321201 -332.288409)
			(xy 311.30651 -332.348068) (xy 311.284741 -332.405523) (xy 311.256211 -332.459938) (xy 311.239154 -332.485492)
			(xy 311.23377 -332.494181) (xy 311.22971 -332.514195) (xy 311.233766 -332.53421) (xy 311.239154 -332.542896)
			(xy 311.256206 -332.568454) (xy 311.284737 -332.622868) (xy 311.306508 -332.680323) (xy 311.3212 -332.739981)
			(xy 311.3286 -332.800975) (xy 311.328601 -332.862415) (xy 311.321201 -332.923409) (xy 311.30651 -332.983068)
			(xy 311.284741 -333.040523) (xy 311.256211 -333.094938) (xy 311.239154 -333.120492) (xy 311.23377 -333.129181)
			(xy 311.22971 -333.149195) (xy 311.233766 -333.16921) (xy 311.239154 -333.177896) (xy 311.256206 -333.203454)
			(xy 311.284737 -333.257868) (xy 311.306508 -333.315323) (xy 311.3212 -333.374981) (xy 311.3286 -333.435975)
			(xy 311.328601 -333.497415) (xy 311.321201 -333.558409) (xy 311.30651 -333.618068) (xy 311.284741 -333.675523)
			(xy 311.256211 -333.729938) (xy 311.239154 -333.755492) (xy 311.23377 -333.764181) (xy 311.22971 -333.784195)
			(xy 311.233766 -333.80421) (xy 311.239154 -333.812896) (xy 311.256206 -333.838454) (xy 311.284737 -333.892868)
			(xy 311.306508 -333.950323) (xy 311.3212 -334.009981) (xy 311.3286 -334.070975) (xy 311.328601 -334.132415)
			(xy 311.321201 -334.193409) (xy 311.30651 -334.253068) (xy 311.284741 -334.310523) (xy 311.256211 -334.364938)
			(xy 311.239154 -334.390492) (xy 311.23377 -334.399181) (xy 311.22971 -334.419195) (xy 311.233766 -334.43921)
			(xy 311.239154 -334.447896) (xy 311.256212 -334.47345) (xy 311.284744 -334.527865) (xy 311.306514 -334.58532)
			(xy 311.321207 -334.644979) (xy 311.328607 -334.705973) (xy 311.32907 -334.736694) (xy 311.328657 -334.767427)
			(xy 311.321248 -334.828446) (xy 311.306538 -334.888127) (xy 311.284741 -334.945599) (xy 311.256175 -335.000025)
			(xy 311.221257 -335.050611) (xy 311.180495 -335.096618) (xy 311.134485 -335.137377) (xy 311.083898 -335.172292)
			(xy 311.02947 -335.200854) (xy 310.971996 -335.222647) (xy 310.912315 -335.237354) (xy 310.851295 -335.244759)
			(xy 310.820562 -335.245202) (xy 310.789841 -335.244749) (xy 310.728847 -335.237346) (xy 310.669188 -335.22265)
			(xy 310.611733 -335.200878) (xy 310.557318 -335.172345) (xy 310.531764 -335.155286) (xy 310.523079 -335.149893)
			(xy 310.503062 -335.145832) (xy 310.483045 -335.149893) (xy 310.47436 -335.155286) (xy 310.448813 -335.172355)
			(xy 310.394397 -335.200887) (xy 310.33694 -335.222656) (xy 310.277279 -335.237345) (xy 310.216283 -335.244742)
			(xy 310.185562 -335.245202) (xy 310.15483 -335.24478) (xy 310.093814 -335.237367) (xy 310.034137 -335.222654)
			(xy 309.976669 -335.200855) (xy 309.922246 -335.172288) (xy 309.871664 -335.13737) (xy 309.825659 -335.09661)
			(xy 309.784903 -335.050601) (xy 309.749989 -335.000016) (xy 309.721427 -334.945591) (xy 309.699633 -334.888121)
			(xy 309.684925 -334.828442) (xy 309.677517 -334.767426) (xy 309.677054 -334.736694) (xy 307.95087 -334.736694)
			(xy 307.950425 -334.767426) (xy 307.943016 -334.82844) (xy 307.928307 -334.888117) (xy 307.906512 -334.945586)
			(xy 307.877948 -335.000009) (xy 307.843032 -335.050591) (xy 307.802273 -335.096595) (xy 307.756266 -335.137351)
			(xy 307.705681 -335.172264) (xy 307.651257 -335.200825) (xy 307.593787 -335.222617) (xy 307.534109 -335.237322)
			(xy 307.473094 -335.244727) (xy 307.442362 -335.245202) (xy 307.411642 -335.244737) (xy 307.35065 -335.237332)
			(xy 307.290994 -335.222635) (xy 307.233542 -335.200859) (xy 307.179132 -335.172322) (xy 307.153564 -335.155286)
			(xy 307.144879 -335.149893) (xy 307.124862 -335.145832) (xy 307.104845 -335.149893) (xy 307.09616 -335.155286)
			(xy 307.070606 -335.172344) (xy 307.016191 -335.200875) (xy 306.958736 -335.222646) (xy 306.899077 -335.237338)
			(xy 306.838083 -335.244738) (xy 306.776641 -335.244738) (xy 306.715647 -335.237338) (xy 306.655988 -335.222646)
			(xy 306.598533 -335.200875) (xy 306.544118 -335.172344) (xy 306.518564 -335.155286) (xy 306.509879 -335.149893)
			(xy 306.489862 -335.145832) (xy 306.469845 -335.149893) (xy 306.46116 -335.155286) (xy 306.443361 -335.167248)
			(xy 306.406101 -335.188487) (xy 306.386738 -335.197704) (xy 306.375054 -335.203292) (xy 306.35956 -335.223866)
			(xy 306.344828 -335.335118) (xy 306.354226 -335.358994) (xy 306.364132 -335.367376) (xy 306.384945 -335.385608)
			(xy 306.42161 -335.427047) (xy 306.451908 -335.473344) (xy 306.475207 -335.52353) (xy 306.491017 -335.576553)
			(xy 306.499009 -335.631303) (xy 306.499514 -335.658968) (xy 306.499038 -335.686336) (xy 306.491205 -335.74051)
			(xy 306.475711 -335.793008) (xy 306.452873 -335.842754) (xy 306.423161 -335.888724) (xy 306.405534 -335.909666)
			(xy 306.405534 -335.90992) (xy 306.40528 -335.90992) (xy 306.399699 -335.917008) (xy 306.393467 -335.933925)
			(xy 306.393088 -335.94294) (xy 306.393088 -336.009996) (xy 306.393447 -336.019013) (xy 306.399692 -336.035931)
			(xy 306.40528 -336.043016) (xy 306.405534 -336.04327) (xy 306.423176 -336.064202) (xy 306.452903 -336.110168)
			(xy 306.475748 -336.159914) (xy 306.491241 -336.212418) (xy 306.499063 -336.266597) (xy 306.499514 -336.293968)
			(xy 306.49909 -336.319676) (xy 306.492179 -336.370627) (xy 306.47849 -336.420188) (xy 306.458273 -336.467463)
			(xy 306.431893 -336.511597) (xy 306.416202 -336.531966) (xy 306.407058 -336.54365) (xy 306.403756 -336.572098)
			(xy 306.449984 -336.66811) (xy 306.454479 -336.67652) (xy 306.468446 -336.689482) (xy 306.486177 -336.696461)
			(xy 306.495704 -336.696812) (xy 310.092344 -336.696812) (xy 310.098694 -336.703162)
		)
		(stroke
			(width 0)
			(type solid)
		)
		(fill yes)
		(layer "In11.Cu")
		(net "PVDDIO_P0")
	)
	(gr_poly
		(pts
			(xy 441.5663 -341.784178) (xy 441.573904 -341.782663) (xy 441.587736 -341.775674) (xy 441.593478 -341.770462)
			(xy 442.349382 -341.014558) (xy 442.354581 -341.008809) (xy 442.36156 -340.994977) (xy 442.363098 -340.98738)
			(xy 442.36386 -340.978998) (xy 442.36386 -320.757042) (xy 442.363504 -320.748354) (xy 442.357646 -320.731997)
			(xy 442.35243 -320.725038) (xy 442.349128 -320.721228) (xy 441.768992 -320.141092) (xy 441.765262 -320.13757)
			(xy 441.756689 -320.131939) (xy 441.751974 -320.129916) (xy 441.743338 -320.12636) (xy 415.753042 -320.12636)
			(xy 415.742595 -320.126925) (xy 415.723453 -320.135317) (xy 415.715958 -320.142616) (xy 415.665158 -320.197734)
			(xy 415.661731 -320.201606) (xy 415.656351 -320.210436) (xy 415.65449 -320.21526) (xy 415.651188 -320.224658)
			(xy 415.65195 -320.235326) (xy 415.65322 -320.272918) (xy 415.652755 -320.303649) (xy 415.645345 -320.364661)
			(xy 415.630634 -320.424336) (xy 415.608839 -320.481803) (xy 415.580275 -320.536223) (xy 415.545361 -320.586805)
			(xy 415.504604 -320.632809) (xy 415.4586 -320.673565) (xy 415.408018 -320.708479) (xy 415.353597 -320.737041)
			(xy 415.29613 -320.758836) (xy 415.236455 -320.773546) (xy 415.175443 -320.780955) (xy 415.144712 -320.781426)
			(xy 415.113898 -320.780977) (xy 415.05272 -320.773537) (xy 414.992889 -320.758763) (xy 414.935279 -320.736872)
			(xy 414.880735 -320.708184) (xy 414.855152 -320.691002) (xy 414.852133 -320.689001) (xy 414.84563 -320.685811)
			(xy 414.842198 -320.684652) (xy 414.83534 -320.682366) (xy 414.827212 -320.682366) (xy 414.823204 -320.682435)
			(xy 414.815291 -320.683713) (xy 414.811464 -320.684906) (xy 414.805114 -320.686938) (xy 414.779462 -320.704657)
			(xy 414.724661 -320.734388) (xy 414.666638 -320.757199) (xy 414.606261 -320.772748) (xy 414.544437 -320.780801)
			(xy 414.482093 -320.781238) (xy 414.420162 -320.774053) (xy 414.359573 -320.759353) (xy 414.301235 -320.737358)
			(xy 414.246023 -320.708399) (xy 414.220152 -320.691002) (xy 414.217133 -320.689001) (xy 414.21063 -320.685811)
			(xy 414.207198 -320.684652) (xy 414.20034 -320.682366) (xy 414.192212 -320.682366) (xy 414.188204 -320.682435)
			(xy 414.180291 -320.683713) (xy 414.176464 -320.684906) (xy 414.170114 -320.686938) (xy 414.144462 -320.704657)
			(xy 414.089661 -320.734388) (xy 414.031638 -320.757199) (xy 413.971261 -320.772748) (xy 413.909437 -320.780801)
			(xy 413.847093 -320.781238) (xy 413.785162 -320.774053) (xy 413.724573 -320.759353) (xy 413.666235 -320.737358)
			(xy 413.611023 -320.708399) (xy 413.585152 -320.691002) (xy 413.582133 -320.689001) (xy 413.57563 -320.685811)
			(xy 413.572198 -320.684652) (xy 413.56534 -320.682366) (xy 413.557212 -320.682366) (xy 413.553204 -320.682435)
			(xy 413.545291 -320.683713) (xy 413.541464 -320.684906) (xy 413.535114 -320.686938) (xy 413.509165 -320.704849)
			(xy 413.45369 -320.73482) (xy 413.394938 -320.757709) (xy 413.333809 -320.773166) (xy 413.271239 -320.780956)
			(xy 413.239712 -320.781426) (xy 413.20898 -320.780963) (xy 413.147964 -320.773555) (xy 413.088286 -320.758848)
			(xy 413.030816 -320.737054) (xy 412.976392 -320.708492) (xy 412.925807 -320.673578) (xy 412.8798 -320.632821)
			(xy 412.839041 -320.586816) (xy 412.804124 -320.536234) (xy 412.775558 -320.481811) (xy 412.753761 -320.424342)
			(xy 412.73905 -320.364665) (xy 412.731639 -320.30365) (xy 412.731204 -320.272918) (xy 412.732474 -320.235326)
			(xy 412.733236 -320.224658) (xy 412.729934 -320.21526) (xy 412.72808 -320.210432) (xy 412.722701 -320.201601)
			(xy 412.719266 -320.197734) (xy 412.681928 -320.157348) (xy 412.68142 -320.15684) (xy 412.668466 -320.142616)
			(xy 412.660995 -320.135283) (xy 412.641838 -320.126894) (xy 412.631382 -320.12636) (xy 410.271722 -320.12636)
			(xy 410.261659 -320.125921) (xy 410.243079 -320.118183) (xy 410.235654 -320.111374) (xy 398.147032 -308.022752)
			(xy 398.143302 -308.019229) (xy 398.13473 -308.013596) (xy 398.130014 -308.011576) (xy 398.121378 -308.00802)
			(xy 396.677642 -308.00802) (xy 396.667576 -308.007587) (xy 396.648985 -307.99986) (xy 396.641574 -307.993034)
			(xy 393.148312 -304.499772) (xy 393.141962 -304.494438) (xy 393.134875 -304.489794) (xy 393.118624 -304.485028)
			(xy 393.101706 -304.485809) (xy 393.093702 -304.488596) (xy 393.004802 -304.529236) (xy 393.000662 -304.531303)
			(xy 392.993126 -304.536671) (xy 392.989816 -304.539904) (xy 392.982748 -304.547897) (xy 392.975245 -304.567845)
			(xy 392.975338 -304.578512) (xy 392.980519 -304.649021) (xy 392.98392 -304.790374) (xy 392.979376 -304.931696)
			(xy 392.966899 -305.072539) (xy 392.946529 -305.212458) (xy 392.918331 -305.351012) (xy 392.882393 -305.487763)
			(xy 392.838829 -305.62228) (xy 392.787778 -305.754136) (xy 392.729399 -305.882916) (xy 392.663878 -306.008213)
			(xy 392.591421 -306.129631) (xy 392.512257 -306.246787) (xy 392.426637 -306.359311) (xy 392.33483 -306.466846)
			(xy 392.237127 -306.569055) (xy 392.133836 -306.665612) (xy 392.025284 -306.756215) (xy 391.911813 -306.840576)
			(xy 391.793782 -306.918429) (xy 391.671564 -306.989528) (xy 391.545544 -307.053649) (xy 391.416122 -307.110589)
			(xy 391.283704 -307.160168) (xy 391.148711 -307.202229) (xy 391.011568 -307.23664) (xy 390.872708 -307.263293)
			(xy 390.73257 -307.282102) (xy 390.591597 -307.293008) (xy 390.450234 -307.295978) (xy 390.308927 -307.291001)
			(xy 390.168123 -307.278093) (xy 390.028266 -307.257296) (xy 389.889799 -307.228674) (xy 389.753158 -307.192318)
			(xy 389.618776 -307.148344) (xy 389.487076 -307.096889) (xy 389.358475 -307.038117) (xy 389.233379 -306.972213)
			(xy 389.112183 -306.899385) (xy 388.99527 -306.819863) (xy 388.883009 -306.733899) (xy 388.775754 -306.641764)
			(xy 388.673845 -306.543749) (xy 388.577604 -306.440164) (xy 388.487333 -306.331335) (xy 388.40332 -306.217607)
			(xy 388.325828 -306.099339) (xy 388.255103 -305.976903) (xy 388.222744 -305.914044) (xy 388.191453 -305.850997)
			(xy 388.135124 -305.721992) (xy 388.086098 -305.590039) (xy 388.04453 -305.45555) (xy 388.01055 -305.318946)
			(xy 387.984263 -305.180656) (xy 387.965752 -305.041112) (xy 387.955076 -304.900751) (xy 387.952267 -304.760012)
			(xy 387.957334 -304.619337) (xy 387.970262 -304.479165) (xy 387.99101 -304.339936) (xy 388.019512 -304.202086)
			(xy 388.055681 -304.066045) (xy 388.099402 -303.93224) (xy 388.150539 -303.801091) (xy 388.208931 -303.673006)
			(xy 388.274396 -303.548389) (xy 388.346729 -303.427628) (xy 388.425703 -303.311102) (xy 388.511071 -303.199176)
			(xy 388.602566 -303.092199) (xy 388.699901 -302.990508) (xy 388.802771 -302.89442) (xy 388.910855 -302.804237)
			(xy 389.023814 -302.72024) (xy 389.141295 -302.642693) (xy 389.262929 -302.571838) (xy 389.388335 -302.507898)
			(xy 389.517122 -302.451072) (xy 389.648886 -302.401538) (xy 389.783213 -302.359452) (xy 389.919685 -302.324945)
			(xy 390.057873 -302.298125) (xy 390.197345 -302.279077) (xy 390.337664 -302.267859) (xy 390.47839 -302.264508)
			(xy 390.619084 -302.269033) (xy 390.759304 -302.28142) (xy 390.898612 -302.301631) (xy 391.036572 -302.329602)
			(xy 391.172751 -302.365246) (xy 391.306723 -302.408451) (xy 391.438069 -302.459082) (xy 391.566377 -302.51698)
			(xy 391.691246 -302.581964) (xy 391.752074 -302.617378) (xy 391.757154 -302.620172) (xy 391.782808 -302.627284)
			(xy 391.789389 -302.627073) (xy 391.802119 -302.62373) (xy 391.807954 -302.62068) (xy 391.884916 -302.576992)
			(xy 391.892535 -302.572265) (xy 391.904113 -302.558588) (xy 391.91026 -302.541756) (xy 391.91057 -302.532796)
			(xy 391.91057 -295.416224) (xy 391.910062 -295.409112) (xy 391.908063 -295.398909) (xy 391.897176 -295.38122)
			(xy 391.88898 -295.374822) (xy 391.877804 -295.368726) (xy 391.820908 -295.347136) (xy 391.787888 -295.334436)
			(xy 391.779186 -295.331791) (xy 391.761014 -295.33215) (xy 391.744101 -295.338805) (xy 391.737088 -295.344596)
			(xy 391.733024 -295.34866) (xy 391.71549 -295.367612) (xy 391.675219 -295.399917) (xy 391.630088 -295.424986)
			(xy 391.581383 -295.442106) (xy 391.530491 -295.450788) (xy 391.504678 -295.451276) (xy 391.479427 -295.450753)
			(xy 391.429613 -295.442437) (xy 391.381847 -295.426036) (xy 391.337432 -295.401997) (xy 391.297579 -295.370976)
			(xy 391.263376 -295.333818) (xy 391.235754 -295.291538) (xy 391.215469 -295.245288) (xy 391.203071 -295.196331)
			(xy 391.198901 -295.146) (xy 391.203071 -295.095669) (xy 391.215469 -295.046712) (xy 391.235754 -295.000462)
			(xy 391.263376 -294.958182) (xy 391.297579 -294.921024) (xy 391.337432 -294.890003) (xy 391.381847 -294.865964)
			(xy 391.429613 -294.849563) (xy 391.479427 -294.841247) (xy 391.504678 -294.84066) (xy 391.517441 -294.840796)
			(xy 391.542876 -294.842956) (xy 391.555478 -294.844978) (xy 391.555478 -294.844724) (xy 391.580299 -294.849442)
			(xy 391.628054 -294.865929) (xy 391.672446 -294.890045) (xy 391.712269 -294.921134) (xy 391.746437 -294.958347)
			(xy 391.77402 -295.000673) (xy 391.794268 -295.046959) (xy 391.806628 -295.095944) (xy 391.809224 -295.121076)
			(xy 391.809224 -295.1226) (xy 391.810402 -295.131993) (xy 391.818745 -295.148969) (xy 391.82548 -295.15562)
			(xy 391.831068 -295.1607) (xy 391.848594 -295.167558) (xy 391.870946 -295.167558) (xy 391.882026 -295.164496)
			(xy 391.899997 -295.150195) (xy 391.909978 -295.129511) (xy 391.91057 -295.118028) (xy 391.91057 -294.970962)
			(xy 391.910218 -294.962273) (xy 391.904365 -294.945911) (xy 391.89914 -294.938958) (xy 391.895838 -294.935148)
			(xy 391.022586 -294.061642) (xy 391.018858 -294.058117) (xy 391.010286 -294.052482) (xy 391.005568 -294.050466)
			(xy 390.996932 -294.04691) (xy 390.45388 -294.04691) (xy 390.445152 -294.047263) (xy 390.428719 -294.053148)
			(xy 390.415249 -294.06425) (xy 390.410446 -294.071548) (xy 390.365996 -294.145208) (xy 390.36299 -294.150729)
			(xy 390.35953 -294.162809) (xy 390.359138 -294.169084) (xy 390.358884 -294.182292) (xy 390.36498 -294.193976)
			(xy 390.376026 -294.215995) (xy 390.391647 -294.262712) (xy 390.399555 -294.311332) (xy 390.400032 -294.335962)
			(xy 390.39951 -294.361217) (xy 390.391197 -294.411039) (xy 390.374796 -294.458813) (xy 390.350755 -294.503236)
			(xy 390.319731 -294.543096) (xy 390.282569 -294.577306) (xy 390.240283 -294.604932) (xy 390.194027 -294.625222)
			(xy 390.145062 -294.637622) (xy 390.094724 -294.641793) (xy 390.044386 -294.637622) (xy 389.995421 -294.625222)
			(xy 389.949165 -294.604932) (xy 389.906879 -294.577306) (xy 389.869717 -294.543096) (xy 389.838693 -294.503236)
			(xy 389.814652 -294.458813) (xy 389.798251 -294.411039) (xy 389.789938 -294.361217) (xy 389.789416 -294.335962)
			(xy 389.789416 -294.335708) (xy 389.789888 -294.311079) (xy 389.797805 -294.262461) (xy 389.813436 -294.215748)
			(xy 389.824468 -294.193722) (xy 389.82904 -294.181276) (xy 389.83031 -294.175688) (xy 389.83031 -294.169084)
			(xy 389.829943 -294.162892) (xy 389.826597 -294.150951) (xy 389.823706 -294.145462) (xy 389.779002 -294.071548)
			(xy 389.774187 -294.064269) (xy 389.760694 -294.053221) (xy 389.744286 -294.047312) (xy 389.735568 -294.04691)
			(xy 389.51408 -294.04691) (xy 389.505352 -294.047263) (xy 389.488919 -294.053148) (xy 389.475449 -294.06425)
			(xy 389.470646 -294.071548) (xy 389.426196 -294.145208) (xy 389.42319 -294.150729) (xy 389.41973 -294.162809)
			(xy 389.419338 -294.169084) (xy 389.419084 -294.182292) (xy 389.42518 -294.193976) (xy 389.436226 -294.215995)
			(xy 389.451847 -294.262712) (xy 389.459755 -294.311332) (xy 389.460232 -294.335962) (xy 389.45971 -294.361217)
			(xy 389.451397 -294.411039) (xy 389.434996 -294.458813) (xy 389.410955 -294.503236) (xy 389.379931 -294.543096)
			(xy 389.342769 -294.577306) (xy 389.300483 -294.604932) (xy 389.254227 -294.625222) (xy 389.205262 -294.637622)
			(xy 389.154924 -294.641793) (xy 389.104586 -294.637622) (xy 389.055621 -294.625222) (xy 389.009365 -294.604932)
			(xy 388.967079 -294.577306) (xy 388.929917 -294.543096) (xy 388.898893 -294.503236) (xy 388.874852 -294.458813)
			(xy 388.858451 -294.411039) (xy 388.850138 -294.361217) (xy 388.849616 -294.335962) (xy 388.849616 -294.335708)
			(xy 388.850088 -294.311079) (xy 388.858005 -294.262461) (xy 388.873636 -294.215748) (xy 388.884668 -294.193722)
			(xy 388.88924 -294.181276) (xy 388.89051 -294.175688) (xy 388.89051 -294.169084) (xy 388.890143 -294.162892)
			(xy 388.886797 -294.150951) (xy 388.883906 -294.145462) (xy 388.839202 -294.071548) (xy 388.834387 -294.064269)
			(xy 388.820894 -294.053221) (xy 388.804486 -294.047312) (xy 388.795768 -294.04691) (xy 388.574026 -294.04691)
			(xy 388.565294 -294.047256) (xy 388.548849 -294.053131) (xy 388.535367 -294.064229) (xy 388.530592 -294.071548)
			(xy 388.486142 -294.145208) (xy 388.483134 -294.150728) (xy 388.47967 -294.162809) (xy 388.479284 -294.169084)
			(xy 388.47903 -294.182292) (xy 388.485126 -294.193976) (xy 388.49617 -294.215995) (xy 388.511789 -294.262712)
			(xy 388.519696 -294.311333) (xy 388.520178 -294.335962) (xy 388.519735 -294.359956) (xy 388.512232 -294.407355)
			(xy 388.497407 -294.452995) (xy 388.475623 -294.495755) (xy 388.447418 -294.534579) (xy 388.413485 -294.568512)
			(xy 388.374661 -294.596719) (xy 388.331903 -294.618504) (xy 388.286262 -294.633331) (xy 388.238864 -294.640834)
			(xy 388.21487 -294.64127) (xy 388.191094 -294.640814) (xy 388.144118 -294.633439) (xy 388.098852 -294.61887)
			(xy 388.056392 -294.597462) (xy 388.017764 -294.569731) (xy 387.983901 -294.536347) (xy 387.955622 -294.498117)
			(xy 387.933611 -294.455967) (xy 387.9184 -294.410913) (xy 387.910356 -294.364047) (xy 387.909562 -294.34028)
			(xy 387.909562 -294.335454) (xy 387.910296 -294.305243) (xy 387.922193 -294.246002) (xy 387.933184 -294.217852)
			(xy 387.933438 -294.217344) (xy 387.933692 -294.216836) (xy 387.935973 -294.210628) (xy 387.93764 -294.197511)
			(xy 387.936994 -294.190928) (xy 387.936232 -294.184324) (xy 387.931152 -294.172132) (xy 387.896354 -294.12692)
			(xy 387.874002 -294.098218) (xy 387.873748 -294.097964) (xy 387.867931 -294.091217) (xy 387.85279 -294.081857)
			(xy 387.835362 -294.078236) (xy 387.826504 -294.079168) (xy 387.82625 -294.079168) (xy 387.805984 -294.081991)
			(xy 387.765176 -294.085039) (xy 387.744716 -294.085264) (xy 387.724319 -294.085045) (xy 387.683638 -294.081992)
			(xy 387.663436 -294.079168) (xy 387.64845 -294.079168) (xy 387.639065 -294.080885) (xy 387.622473 -294.090275)
			(xy 387.616192 -294.097456) (xy 387.562852 -294.166544) (xy 387.558919 -294.171964) (xy 387.553763 -294.184318)
			(xy 387.552692 -294.190928) (xy 387.550914 -294.20439) (xy 387.556248 -294.217344) (xy 387.556502 -294.217852)
			(xy 387.567454 -294.245815) (xy 387.579347 -294.304671) (xy 387.580124 -294.334692) (xy 387.580124 -294.34028)
			(xy 387.579337 -294.364049) (xy 387.571304 -294.41092) (xy 387.5561 -294.455979) (xy 387.534092 -294.498135)
			(xy 387.505813 -294.536369) (xy 387.471947 -294.569754) (xy 387.433313 -294.597483) (xy 387.390847 -294.618886)
			(xy 387.345575 -294.633445) (xy 387.298594 -294.640807) (xy 387.274816 -294.64127) (xy 387.250823 -294.640825)
			(xy 387.203428 -294.63332) (xy 387.157791 -294.618492) (xy 387.115035 -294.596707) (xy 387.076214 -294.568501)
			(xy 387.042284 -294.534569) (xy 387.014081 -294.495746) (xy 386.992299 -294.452989) (xy 386.977475 -294.407351)
			(xy 386.969973 -294.359955) (xy 386.969508 -294.335962) (xy 386.969999 -294.311014) (xy 386.978103 -294.261781)
			(xy 386.994104 -294.214521) (xy 387.017578 -294.170492) (xy 387.047899 -294.130867) (xy 387.065774 -294.113458)
			(xy 387.07314 -294.106346) (xy 387.077204 -294.096948) (xy 387.077712 -294.096186) (xy 387.077966 -294.09517)
			(xy 387.079377 -294.0915) (xy 387.081165 -294.083845) (xy 387.081522 -294.07993) (xy 387.082792 -294.003476)
			(xy 387.082037 -293.994309) (xy 387.074875 -293.977382) (xy 387.068822 -293.970456) (xy 386.933948 -293.835582)
			(xy 386.930216 -293.832063) (xy 386.921639 -293.82644) (xy 386.91693 -293.824406) (xy 386.908294 -293.82085)
			(xy 386.884672 -293.82085) (xy 386.87883 -293.822374) (xy 386.860768 -293.826553) (xy 386.823962 -293.831012)
			(xy 386.805424 -293.831264) (xy 386.804916 -293.831264) (xy 386.780923 -293.830819) (xy 386.733528 -293.823314)
			(xy 386.687891 -293.808486) (xy 386.645136 -293.786701) (xy 386.606316 -293.758495) (xy 386.572387 -293.724563)
			(xy 386.544184 -293.68574) (xy 386.522403 -293.642983) (xy 386.50758 -293.597344) (xy 386.500079 -293.549949)
			(xy 386.499608 -293.525956) (xy 386.499959 -293.5061) (xy 386.505184 -293.466731) (xy 386.510022 -293.44747)
			(xy 386.510784 -293.44493) (xy 386.511817 -293.43911) (xy 386.51144 -293.4273) (xy 386.510022 -293.421562)
			(xy 386.510022 -293.421308) (xy 386.508071 -293.414909) (xy 386.501391 -293.403326) (xy 386.496814 -293.398448)
			(xy 386.48513 -293.386764) (xy 386.48132 -293.383208) (xy 386.469128 -293.375842) (xy 386.285232 -293.300404)
			(xy 386.274056 -293.29761) (xy 386.269738 -293.297102) (xy 386.260272 -293.297027) (xy 386.242293 -293.302897)
			(xy 386.234686 -293.308532) (xy 386.231892 -293.311072) (xy 386.214366 -293.327836) (xy 386.164328 -293.375334)
			(xy 386.157908 -293.382843) (xy 386.150846 -293.401272) (xy 386.150612 -293.411148) (xy 386.150866 -293.418768)
			(xy 386.153406 -293.426388) (xy 386.161199 -293.45041) (xy 386.169629 -293.5002) (xy 386.17017 -293.525448)
			(xy 386.17017 -293.531036) (xy 386.169327 -293.554767) (xy 386.161203 -293.601551) (xy 386.145934 -293.646513)
			(xy 386.123888 -293.688569) (xy 386.095597 -293.726705) (xy 386.061743 -293.760001) (xy 386.023142 -293.787654)
			(xy 385.980726 -293.808998) (xy 385.935516 -293.823518) (xy 385.888604 -293.830863) (xy 385.864862 -293.831264)
			(xy 385.840872 -293.830815) (xy 385.793484 -293.823303) (xy 385.747854 -293.808471) (xy 385.705106 -293.786683)
			(xy 385.666293 -293.758476) (xy 385.632371 -293.724544) (xy 385.604174 -293.685724) (xy 385.582398 -293.64297)
			(xy 385.567578 -293.597336) (xy 385.560079 -293.549946) (xy 385.559554 -293.525956) (xy 385.560044 -293.501364)
			(xy 385.567921 -293.452814) (xy 385.583482 -293.406156) (xy 385.606323 -293.362597) (xy 385.635852 -293.323264)
			(xy 385.671307 -293.289175) (xy 385.711769 -293.261212) (xy 385.756191 -293.240098) (xy 385.803424 -293.226381)
			(xy 385.827778 -293.222934) (xy 385.828032 -293.222934) (xy 385.829556 -293.22268) (xy 385.83574 -293.221574)
			(xy 385.847308 -293.216686) (xy 385.852416 -293.213028) (xy 385.85267 -293.213028) (xy 385.857452 -293.209129)
			(xy 385.865165 -293.199503) (xy 385.86791 -293.193978) (xy 385.901946 -293.112444) (xy 385.90522 -293.103413)
			(xy 385.905492 -293.084218) (xy 385.902454 -293.075106) (xy 385.901027 -293.071432) (xy 385.897199 -293.064543)
			(xy 385.894834 -293.06139) (xy 385.876008 -293.036715) (xy 385.843334 -292.983944) (xy 385.816699 -292.927882)
			(xy 385.79643 -292.869217) (xy 385.782775 -292.80867) (xy 385.775903 -292.746984) (xy 385.775454 -292.71595)
			(xy 385.775708 -292.700202) (xy 385.775708 -292.699948) (xy 385.775962 -292.689534) (xy 385.77139 -292.678104)
			(xy 385.769409 -292.673743) (xy 385.764038 -292.665813) (xy 385.760722 -292.662356) (xy 385.2164 -292.118034)
			(xy 385.208966 -292.111318) (xy 385.190466 -292.103682) (xy 385.170452 -292.103682) (xy 385.151952 -292.111318)
			(xy 385.144518 -292.118034) (xy 385.143756 -292.118796) (xy 385.126377 -292.135966) (xy 385.087173 -292.165109)
			(xy 385.043832 -292.187646) (xy 384.997458 -292.203003) (xy 384.949233 -292.210789) (xy 384.924808 -292.211252)
			(xy 384.899546 -292.21076) (xy 384.849712 -292.202445) (xy 384.801925 -292.186041) (xy 384.757491 -292.161995)
			(xy 384.71762 -292.130964) (xy 384.683401 -292.093793) (xy 384.655767 -292.051496) (xy 384.635471 -292.005228)
			(xy 384.623068 -291.956251) (xy 384.618896 -291.9059) (xy 384.623068 -291.855549) (xy 384.635471 -291.806572)
			(xy 384.655767 -291.760304) (xy 384.683401 -291.718007) (xy 384.71762 -291.680836) (xy 384.757491 -291.649805)
			(xy 384.801925 -291.625759) (xy 384.849712 -291.609355) (xy 384.899546 -291.60104) (xy 384.924808 -291.600636)
			(xy 384.946843 -291.601039) (xy 384.99045 -291.60741) (xy 385.011676 -291.613336) (xy 385.014724 -291.614352)
			(xy 385.025085 -291.616095) (xy 385.045672 -291.612016) (xy 385.054602 -291.606478) (xy 385.122166 -291.555932)
			(xy 385.130378 -291.548377) (xy 385.139872 -291.528213) (xy 385.140454 -291.51707) (xy 385.140454 -291.285422)
			(xy 385.13893 -291.27323) (xy 385.134612 -291.25799) (xy 385.13131 -291.25037) (xy 385.130548 -291.248846)
			(xy 385.117618 -291.225459) (xy 385.099265 -291.175273) (xy 385.089942 -291.122656) (xy 385.0894 -291.095938)
			(xy 385.090014 -291.069227) (xy 385.099353 -291.016627) (xy 385.117684 -290.966447) (xy 385.130548 -290.94303)
			(xy 385.13131 -290.941506) (xy 385.134612 -290.933886) (xy 385.13893 -290.918646) (xy 385.140454 -290.906454)
			(xy 385.140454 -289.66541) (xy 385.13893 -289.653218) (xy 385.134612 -289.637978) (xy 385.13131 -289.630358)
			(xy 385.130548 -289.628834) (xy 385.117819 -289.605775) (xy 385.099619 -289.556353) (xy 385.09018 -289.50454)
			(xy 385.0894 -289.478212) (xy 385.0894 -289.47491) (xy 385.090034 -289.447401) (xy 385.09997 -289.393286)
			(xy 385.119417 -289.341817) (xy 385.133088 -289.317938) (xy 385.137152 -289.311334) (xy 385.138676 -289.305746)
			(xy 385.140454 -289.292284) (xy 385.140454 -289.241484) (xy 385.140979 -289.231641) (xy 385.148547 -289.213462)
			(xy 385.155186 -289.206178) (xy 385.364736 -288.996628) (xy 385.366514 -288.994596) (xy 385.366768 -288.994596)
			(xy 385.374706 -288.984686) (xy 385.38059 -288.960022) (xy 385.377944 -288.947606) (xy 385.374896 -288.935922)
			(xy 385.366348 -288.919986) (xy 385.351097 -288.887194) (xy 385.344416 -288.87039) (xy 385.344416 -288.870136)
			(xy 385.341725 -288.863933) (xy 385.333619 -288.853115) (xy 385.328414 -288.8488) (xy 385.323334 -288.844736)
			(xy 385.310634 -288.839402) (xy 385.272534 -288.834576) (xy 385.272026 -288.834576) (xy 385.225036 -288.828226)
			(xy 385.218317 -288.82783) (xy 385.205063 -288.830151) (xy 385.198874 -288.832798) (xy 385.197096 -288.83356)
			(xy 385.17576 -288.844482) (xy 385.167632 -288.851086) (xy 385.164076 -288.855404) (xy 385.149527 -288.873137)
			(xy 385.116012 -288.90445) (xy 385.078186 -288.930393) (xy 385.036903 -288.95038) (xy 384.993092 -288.963961)
			(xy 384.947742 -288.970829) (xy 384.924808 -288.971228) (xy 384.899548 -288.970736) (xy 384.849717 -288.962422)
			(xy 384.801935 -288.946019) (xy 384.757504 -288.921975) (xy 384.717636 -288.890946) (xy 384.68342 -288.853778)
			(xy 384.655788 -288.811485) (xy 384.635494 -288.765221) (xy 384.623092 -288.716247) (xy 384.61892 -288.6659)
			(xy 384.623092 -288.615553) (xy 384.635494 -288.566579) (xy 384.655788 -288.520315) (xy 384.68342 -288.478022)
			(xy 384.717636 -288.440854) (xy 384.757504 -288.409825) (xy 384.801935 -288.385781) (xy 384.849717 -288.369378)
			(xy 384.899548 -288.361064) (xy 384.924808 -288.360612) (xy 384.948319 -288.361038) (xy 384.994788 -288.368234)
			(xy 385.039603 -288.38247) (xy 385.081706 -288.40341) (xy 385.1201 -288.430557) (xy 385.153877 -288.463271)
			(xy 385.168394 -288.48177) (xy 385.170426 -288.484564) (xy 385.18084 -288.494978) (xy 385.191 -288.50082)
			(xy 385.196576 -288.503016) (xy 385.208378 -288.505068) (xy 385.214368 -288.504884) (xy 385.217924 -288.50463)
			(xy 385.30403 -288.4932) (xy 385.310712 -288.492064) (xy 385.323189 -288.486777) (xy 385.328668 -288.482786)
			(xy 385.334002 -288.478722) (xy 385.341876 -288.468054) (xy 385.344416 -288.46145) (xy 385.352339 -288.441743)
			(xy 385.370774 -288.403475) (xy 385.381246 -288.384996) (xy 385.514596 -288.15538) (xy 385.517739 -288.149503)
			(xy 385.521215 -288.136641) (xy 385.521454 -288.12998) (xy 385.521454 -287.522158) (xy 385.521313 -287.516575)
			(xy 385.518887 -287.505675) (xy 385.516628 -287.500568) (xy 385.510024 -287.486852) (xy 385.504944 -287.478216)
			(xy 385.495546 -287.465516) (xy 385.491736 -287.462214) (xy 385.46778 -287.440162) (xy 385.424636 -287.391391)
			(xy 385.387457 -287.337932) (xy 385.356749 -287.280513) (xy 385.344416 -287.250378) (xy 385.341876 -287.243774)
			(xy 385.334002 -287.233106) (xy 385.328414 -287.228788) (xy 385.322939 -287.224828) (xy 385.310451 -287.219678)
			(xy 385.303776 -287.218628) (xy 385.255008 -287.212024) (xy 385.2545 -287.212024) (xy 385.225036 -287.208214)
			(xy 385.218317 -287.207818) (xy 385.205063 -287.210139) (xy 385.198874 -287.212786) (xy 385.197096 -287.213548)
			(xy 385.17576 -287.22447) (xy 385.167632 -287.231074) (xy 385.164076 -287.235392) (xy 385.149528 -287.253126)
			(xy 385.116013 -287.28444) (xy 385.078187 -287.310384) (xy 385.036903 -287.330372) (xy 384.993092 -287.343953)
			(xy 384.947742 -287.350822) (xy 384.924808 -287.351216) (xy 384.899549 -287.350724) (xy 384.84972 -287.34241)
			(xy 384.80194 -287.326008) (xy 384.75751 -287.301965) (xy 384.717644 -287.270937) (xy 384.683429 -287.233771)
			(xy 384.655798 -287.191479) (xy 384.635505 -287.145217) (xy 384.623104 -287.096245) (xy 384.618932 -287.0459)
			(xy 384.623104 -286.995555) (xy 384.635505 -286.946583) (xy 384.655798 -286.900321) (xy 384.683429 -286.858029)
			(xy 384.717644 -286.820863) (xy 384.75751 -286.789835) (xy 384.80194 -286.765792) (xy 384.84972 -286.74939)
			(xy 384.899549 -286.741076) (xy 384.924808 -286.7406) (xy 384.948319 -286.741026) (xy 384.994788 -286.748222)
			(xy 385.039604 -286.762458) (xy 385.081707 -286.783397) (xy 385.120102 -286.810543) (xy 385.153881 -286.843256)
			(xy 385.168394 -286.861758) (xy 385.170426 -286.864552) (xy 385.18084 -286.874966) (xy 385.191 -286.880808)
			(xy 385.196576 -286.883004) (xy 385.208378 -286.885057) (xy 385.214368 -286.884872) (xy 385.217924 -286.884618)
			(xy 385.30403 -286.873188) (xy 385.310712 -286.872051) (xy 385.323188 -286.866764) (xy 385.328668 -286.862774)
			(xy 385.334002 -286.85871) (xy 385.341876 -286.848042) (xy 385.344416 -286.841438) (xy 385.352339 -286.821731)
			(xy 385.370775 -286.783463) (xy 385.381246 -286.764984) (xy 385.42722 -286.685482) (xy 385.43198 -286.674749)
			(xy 385.432133 -286.651299) (xy 385.427474 -286.640524) (xy 385.397248 -286.578294) (xy 385.395216 -286.573976)
			(xy 385.386072 -286.563054) (xy 385.381246 -286.55899) (xy 385.36753 -286.549084) (xy 385.358386 -286.54375)
			(xy 385.342384 -286.536892) (xy 385.341876 -286.536892) (xy 385.319917 -286.532613) (xy 385.277469 -286.518485)
			(xy 385.237535 -286.49832) (xy 385.200966 -286.47255) (xy 385.168544 -286.441724) (xy 385.154424 -286.42437)
			(xy 385.138479 -286.403115) (xy 385.113409 -286.356271) (xy 385.096811 -286.3058) (xy 385.092448 -286.27959)
			(xy 385.090924 -286.269176) (xy 385.089146 -286.23641) (xy 385.089146 -286.236156) (xy 385.089696 -286.210241)
			(xy 385.098448 -286.159155) (xy 385.115693 -286.110278) (xy 385.140937 -286.065011) (xy 385.173457 -286.024652)
			(xy 385.212319 -285.990358) (xy 385.25641 -285.963112) (xy 385.304466 -285.943695) (xy 385.329684 -285.937706)
			(xy 385.358132 -285.93288) (xy 385.358386 -285.93288) (xy 385.360926 -285.932626) (xy 385.369324 -285.930846)
			(xy 385.384324 -285.922519) (xy 385.395737 -285.90971) (xy 385.39928 -285.901892) (xy 385.432046 -285.822136)
			(xy 385.434413 -285.815816) (xy 385.436077 -285.802429) (xy 385.435348 -285.79572) (xy 385.43357 -285.782512)
			(xy 385.424934 -285.77159) (xy 385.406108 -285.746915) (xy 385.373434 -285.694144) (xy 385.346799 -285.638082)
			(xy 385.32653 -285.579417) (xy 385.312875 -285.51887) (xy 385.306003 -285.457184) (xy 385.305554 -285.42615)
			(xy 385.306142 -285.389345) (xy 385.315806 -285.316372) (xy 385.33496 -285.245297) (xy 385.363272 -285.17735)
			(xy 385.381246 -285.145226) (xy 385.42595 -285.068264) (xy 385.431646 -285.057162) (xy 385.432593 -285.032255)
			(xy 385.427728 -285.020766) (xy 385.391406 -284.946344) (xy 385.388463 -284.940837) (xy 385.380371 -284.931331)
			(xy 385.375404 -284.927548) (xy 385.365752 -284.920436) (xy 385.353052 -284.918658) (xy 385.328689 -284.914826)
			(xy 385.28155 -284.900334) (xy 385.237353 -284.878454) (xy 385.197247 -284.849754) (xy 385.162276 -284.814982)
			(xy 385.133348 -284.775041) (xy 385.111216 -284.730969) (xy 385.096455 -284.683914) (xy 385.092448 -284.659578)
			(xy 385.090924 -284.649164) (xy 385.089146 -284.616398) (xy 385.089146 -284.616144) (xy 385.089697 -284.59023)
			(xy 385.098451 -284.539145) (xy 385.115697 -284.49027) (xy 385.140942 -284.445004) (xy 385.173461 -284.404647)
			(xy 385.212323 -284.370355) (xy 385.256414 -284.34311) (xy 385.304469 -284.323694) (xy 385.329684 -284.317694)
			(xy 385.358132 -284.312868) (xy 385.358386 -284.312868) (xy 385.360926 -284.312614) (xy 385.369323 -284.310833)
			(xy 385.384322 -284.302506) (xy 385.395731 -284.289695) (xy 385.39928 -284.28188) (xy 385.432046 -284.202124)
			(xy 385.434424 -284.195805) (xy 385.436112 -284.182415) (xy 385.435348 -284.175708) (xy 385.43357 -284.1625)
			(xy 385.424934 -284.151578) (xy 385.400377 -284.119052) (xy 385.35995 -284.048287) (xy 385.344416 -284.010608)
			(xy 385.344416 -284.010354) (xy 385.341727 -284.004149) (xy 385.333623 -283.993329) (xy 385.328414 -283.989018)
			(xy 385.32308 -283.984954) (xy 385.310888 -283.97962) (xy 385.27228 -283.97454) (xy 385.225036 -283.968444)
			(xy 385.218317 -283.968068) (xy 385.205067 -283.970385) (xy 385.198874 -283.973016) (xy 385.197096 -283.973778)
			(xy 385.17576 -283.9847) (xy 385.167632 -283.991304) (xy 385.164076 -283.995622) (xy 385.149527 -284.013354)
			(xy 385.116011 -284.044666) (xy 385.078185 -284.070607) (xy 385.036901 -284.090593) (xy 384.993091 -284.104173)
			(xy 384.947741 -284.11104) (xy 384.924808 -284.111446) (xy 384.899547 -284.110954) (xy 384.849713 -284.102639)
			(xy 384.801928 -284.086236) (xy 384.757494 -284.06219) (xy 384.717624 -284.031159) (xy 384.683406 -283.993989)
			(xy 384.655772 -283.951694) (xy 384.635477 -283.905427) (xy 384.623074 -283.85645) (xy 384.618902 -283.8061)
			(xy 384.623074 -283.75575) (xy 384.635477 -283.706773) (xy 384.655772 -283.660506) (xy 384.683406 -283.618211)
			(xy 384.717624 -283.581041) (xy 384.757494 -283.55001) (xy 384.801928 -283.525964) (xy 384.849713 -283.509561)
			(xy 384.899547 -283.501246) (xy 384.924808 -283.50083) (xy 384.94832 -283.501256) (xy 384.99479 -283.508451)
			(xy 385.039609 -283.522684) (xy 385.081715 -283.54362) (xy 385.120114 -283.570763) (xy 385.153899 -283.603472)
			(xy 385.168394 -283.621988) (xy 385.170426 -283.624782) (xy 385.18084 -283.635196) (xy 385.191 -283.641038)
			(xy 385.196576 -283.643233) (xy 385.208378 -283.645285) (xy 385.214368 -283.645102) (xy 385.217924 -283.644848)
			(xy 385.30403 -283.633418) (xy 385.310712 -283.632282) (xy 385.32319 -283.626997) (xy 385.328668 -283.623004)
			(xy 385.334002 -283.61894) (xy 385.341876 -283.608272) (xy 385.344416 -283.601668) (xy 385.352338 -283.581961)
			(xy 385.370773 -283.543692) (xy 385.381246 -283.525214) (xy 385.514596 -283.295598) (xy 385.517741 -283.289721)
			(xy 385.521222 -283.276859) (xy 385.521454 -283.270198) (xy 385.521454 -282.662376) (xy 385.521304 -282.656795)
			(xy 385.518862 -282.645903) (xy 385.516628 -282.640786) (xy 385.510024 -282.62707) (xy 385.504944 -282.618434)
			(xy 385.495546 -282.605734) (xy 385.491736 -282.602432) (xy 385.467782 -282.580378) (xy 385.424645 -282.531603)
			(xy 385.387474 -282.478142) (xy 385.356774 -282.42072) (xy 385.344416 -282.390596) (xy 385.341876 -282.383992)
			(xy 385.334002 -282.373324) (xy 385.328414 -282.369006) (xy 385.322939 -282.365044) (xy 385.310452 -282.359893)
			(xy 385.303776 -282.358846) (xy 385.255008 -282.352242) (xy 385.2545 -282.352242) (xy 385.225036 -282.348432)
			(xy 385.218317 -282.348056) (xy 385.205067 -282.350372) (xy 385.198874 -282.353004) (xy 385.197096 -282.353766)
			(xy 385.17576 -282.364688) (xy 385.167632 -282.371292) (xy 385.164076 -282.37561) (xy 385.149527 -282.393343)
			(xy 385.116012 -282.424656) (xy 385.078186 -282.450598) (xy 385.036902 -282.470584) (xy 384.993092 -282.484165)
			(xy 384.947742 -282.491033) (xy 384.924808 -282.491434) (xy 384.899548 -282.490942) (xy 384.849716 -282.482628)
			(xy 384.801932 -282.466225) (xy 384.7575 -282.44218) (xy 384.717632 -282.411151) (xy 384.683415 -282.373982)
			(xy 384.655782 -282.331688) (xy 384.635488 -282.285423) (xy 384.623086 -282.236448) (xy 384.618914 -282.1861)
			(xy 384.623086 -282.135752) (xy 384.635488 -282.086777) (xy 384.655782 -282.040512) (xy 384.683415 -281.998218)
			(xy 384.717632 -281.961049) (xy 384.7575 -281.93002) (xy 384.801932 -281.905975) (xy 384.849716 -281.889572)
			(xy 384.899548 -281.881258) (xy 384.924808 -281.880818) (xy 384.94832 -281.881244) (xy 384.994791 -281.888438)
			(xy 385.039609 -281.902671) (xy 385.081716 -281.923607) (xy 385.120117 -281.950749) (xy 385.153902 -281.983457)
			(xy 385.168394 -282.001976) (xy 385.170426 -282.00477) (xy 385.18084 -282.015184) (xy 385.191 -282.021026)
			(xy 385.196576 -282.023221) (xy 385.208378 -282.025274) (xy 385.214368 -282.02509) (xy 385.217924 -282.024836)
			(xy 385.30403 -282.013406) (xy 385.310712 -282.01227) (xy 385.323189 -282.006984) (xy 385.328668 -282.002992)
			(xy 385.334002 -281.998928) (xy 385.341876 -281.98826) (xy 385.344416 -281.981656) (xy 385.352338 -281.961949)
			(xy 385.370774 -281.923681) (xy 385.381246 -281.905202) (xy 385.42595 -281.82824) (xy 385.43164 -281.817138)
			(xy 385.432576 -281.792236) (xy 385.427728 -281.780742) (xy 385.391406 -281.70632) (xy 385.388461 -281.700814)
			(xy 385.380367 -281.691313) (xy 385.375404 -281.687524) (xy 385.365752 -281.680412) (xy 385.353052 -281.678634)
			(xy 385.328687 -281.674803) (xy 385.281543 -281.660313) (xy 385.23734 -281.638434) (xy 385.197228 -281.609737)
			(xy 385.162249 -281.574967) (xy 385.133312 -281.535027) (xy 385.11117 -281.490956) (xy 385.096397 -281.4439)
			(xy 385.092448 -281.419554) (xy 385.090924 -281.40914) (xy 385.089146 -281.376374) (xy 385.089146 -281.37612)
			(xy 385.089699 -281.350207) (xy 385.098456 -281.299125) (xy 385.115704 -281.250253) (xy 385.14095 -281.204991)
			(xy 385.173471 -281.164637) (xy 385.212332 -281.130348) (xy 385.256422 -281.103106) (xy 385.304475 -281.083693)
			(xy 385.329684 -281.07767) (xy 385.358132 -281.072844) (xy 385.358386 -281.072844) (xy 385.360926 -281.07259)
			(xy 385.369322 -281.070808) (xy 385.384317 -281.062479) (xy 385.395722 -281.049666) (xy 385.39928 -281.041856)
			(xy 385.432046 -280.9621) (xy 385.434421 -280.955781) (xy 385.436102 -280.942392) (xy 385.435348 -280.935684)
			(xy 385.43357 -280.922476) (xy 385.424934 -280.911554) (xy 385.406105 -280.88688) (xy 385.373425 -280.83411)
			(xy 385.346784 -280.778048) (xy 385.326508 -280.719384) (xy 385.312846 -280.658836) (xy 385.305967 -280.597149)
			(xy 385.305554 -280.566114) (xy 385.306138 -280.529308) (xy 385.315794 -280.456331) (xy 385.334941 -280.385253)
			(xy 385.363247 -280.3173) (xy 385.381246 -280.28519) (xy 385.42595 -280.208228) (xy 385.431637 -280.197126)
			(xy 385.432568 -280.172227) (xy 385.427728 -280.16073) (xy 385.391406 -280.086308) (xy 385.38846 -280.080803)
			(xy 385.380365 -280.071303) (xy 385.375404 -280.067512) (xy 385.365752 -280.0604) (xy 385.353052 -280.058622)
			(xy 385.328687 -280.054791) (xy 385.281544 -280.0403) (xy 385.237342 -280.018422) (xy 385.197231 -279.989724)
			(xy 385.162253 -279.954953) (xy 385.133318 -279.915013) (xy 385.111177 -279.870943) (xy 385.096406 -279.823886)
			(xy 385.092448 -279.799542) (xy 385.090924 -279.789128) (xy 385.089146 -279.756362) (xy 385.089146 -279.756108)
			(xy 385.0897 -279.730195) (xy 385.098458 -279.679115) (xy 385.115708 -279.630245) (xy 385.140955 -279.584985)
			(xy 385.173475 -279.544633) (xy 385.212337 -279.510345) (xy 385.256426 -279.483104) (xy 385.304478 -279.463692)
			(xy 385.329684 -279.457658) (xy 385.358132 -279.452832) (xy 385.358386 -279.452832) (xy 385.360926 -279.452578)
			(xy 385.369321 -279.450796) (xy 385.384315 -279.442466) (xy 385.395717 -279.429651) (xy 385.39928 -279.421844)
			(xy 385.432046 -279.342088) (xy 385.434419 -279.335769) (xy 385.436098 -279.32238) (xy 385.435348 -279.315672)
			(xy 385.43357 -279.302464) (xy 385.424934 -279.291542) (xy 385.400379 -279.259015) (xy 385.359956 -279.188248)
			(xy 385.344416 -279.150572) (xy 385.344416 -279.150318) (xy 385.341723 -279.144116) (xy 385.333615 -279.133302)
			(xy 385.328414 -279.128982) (xy 385.32308 -279.124918) (xy 385.310888 -279.119584) (xy 385.27228 -279.114504)
			(xy 385.225036 -279.108408) (xy 385.218317 -279.108012) (xy 385.205063 -279.110333) (xy 385.198874 -279.11298)
			(xy 385.197096 -279.113742) (xy 385.17576 -279.124664) (xy 385.167632 -279.131268) (xy 385.164076 -279.135586)
			(xy 385.149525 -279.153315) (xy 385.116006 -279.18462) (xy 385.078179 -279.210556) (xy 385.036896 -279.230537)
			(xy 384.993088 -279.244114) (xy 384.94774 -279.25098) (xy 384.924808 -279.25141) (xy 384.89955 -279.250918)
			(xy 384.849722 -279.242604) (xy 384.801942 -279.226203) (xy 384.757514 -279.20216) (xy 384.717648 -279.171133)
			(xy 384.683434 -279.133967) (xy 384.655804 -279.091676) (xy 384.635511 -279.045415) (xy 384.62311 -278.996444)
			(xy 384.618938 -278.9461) (xy 384.62311 -278.895756) (xy 384.635511 -278.846785) (xy 384.655804 -278.800524)
			(xy 384.683434 -278.758233) (xy 384.717648 -278.721067) (xy 384.757514 -278.69004) (xy 384.801942 -278.665997)
			(xy 384.849722 -278.649596) (xy 384.89955 -278.641282) (xy 384.924808 -278.640794) (xy 384.948319 -278.64122)
			(xy 384.994788 -278.648416) (xy 385.039604 -278.662651) (xy 385.081708 -278.68359) (xy 385.120103 -278.710737)
			(xy 385.153882 -278.743449) (xy 385.168394 -278.761952) (xy 385.170426 -278.764746) (xy 385.18084 -278.77516)
			(xy 385.191 -278.781002) (xy 385.196575 -278.783198) (xy 385.208378 -278.785251) (xy 385.214368 -278.785066)
			(xy 385.217924 -278.784812) (xy 385.30403 -278.773382) (xy 385.310712 -278.772245) (xy 385.323187 -278.766957)
			(xy 385.328668 -278.762968) (xy 385.334002 -278.758904) (xy 385.341876 -278.748236) (xy 385.344416 -278.741632)
			(xy 385.352339 -278.721925) (xy 385.370776 -278.683658) (xy 385.381246 -278.665178) (xy 385.514596 -278.435562)
			(xy 385.517737 -278.429684) (xy 385.521209 -278.416822) (xy 385.521454 -278.410162) (xy 385.521454 -277.80234)
			(xy 385.521311 -277.796757) (xy 385.518881 -277.785859) (xy 385.516628 -277.78075) (xy 385.510024 -277.767034)
			(xy 385.504944 -277.758398) (xy 385.495546 -277.745698) (xy 385.491736 -277.742396) (xy 385.46778 -277.720343)
			(xy 385.424638 -277.671571) (xy 385.387461 -277.618113) (xy 385.356754 -277.560692) (xy 385.344416 -277.53056)
			(xy 385.341876 -277.523956) (xy 385.334002 -277.513288) (xy 385.328414 -277.50897) (xy 385.322941 -277.505004)
			(xy 385.310454 -277.499846) (xy 385.303776 -277.49881) (xy 385.255008 -277.492206) (xy 385.2545 -277.492206)
			(xy 385.225036 -277.488396) (xy 385.218318 -277.48802) (xy 385.205068 -277.490339) (xy 385.198874 -277.492968)
			(xy 385.197096 -277.49373) (xy 385.17576 -277.504652) (xy 385.167632 -277.511256) (xy 385.164076 -277.515574)
			(xy 385.149525 -277.533303) (xy 385.116007 -277.56461) (xy 385.07818 -277.590547) (xy 385.036897 -277.610529)
			(xy 384.993088 -277.624106) (xy 384.94774 -277.630973) (xy 384.924808 -277.631398) (xy 384.899551 -277.630906)
			(xy 384.849725 -277.622593) (xy 384.801947 -277.606192) (xy 384.75752 -277.58215) (xy 384.717657 -277.551124)
			(xy 384.683443 -277.51396) (xy 384.655814 -277.471671) (xy 384.635522 -277.425411) (xy 384.623122 -277.376442)
			(xy 384.61895 -277.3261) (xy 384.623122 -277.275758) (xy 384.635522 -277.226789) (xy 384.655814 -277.180529)
			(xy 384.683443 -277.13824) (xy 384.717657 -277.101076) (xy 384.75752 -277.07005) (xy 384.801947 -277.046008)
			(xy 384.849725 -277.029607) (xy 384.899551 -277.021294) (xy 384.924808 -277.020782) (xy 384.94832 -277.021208)
			(xy 384.994789 -277.028404) (xy 385.039605 -277.042639) (xy 385.081709 -277.063577) (xy 385.120105 -277.090723)
			(xy 385.153885 -277.123435) (xy 385.168394 -277.14194) (xy 385.170426 -277.144734) (xy 385.18084 -277.155148)
			(xy 385.191 -277.16099) (xy 385.196575 -277.163187) (xy 385.208378 -277.16524) (xy 385.214368 -277.165054)
			(xy 385.217924 -277.1648) (xy 385.30403 -277.15337) (xy 385.310712 -277.152233) (xy 385.323186 -277.146944)
			(xy 385.328668 -277.142956) (xy 385.334002 -277.138892) (xy 385.341876 -277.128224) (xy 385.344416 -277.12162)
			(xy 385.35234 -277.101914) (xy 385.370777 -277.063646) (xy 385.381246 -277.045166) (xy 385.42595 -276.968204)
			(xy 385.431632 -276.957102) (xy 385.432552 -276.932208) (xy 385.427728 -276.920706) (xy 385.391406 -276.846284)
			(xy 385.388459 -276.840781) (xy 385.38036 -276.831285) (xy 385.375404 -276.827488) (xy 385.365752 -276.820376)
			(xy 385.353052 -276.818598) (xy 385.328688 -276.814767) (xy 385.281546 -276.800276) (xy 385.237346 -276.778396)
			(xy 385.197237 -276.749698) (xy 385.162262 -276.714927) (xy 385.133329 -276.674986) (xy 385.111192 -276.630915)
			(xy 385.096425 -276.583859) (xy 385.092448 -276.559518) (xy 385.090924 -276.549104) (xy 385.089146 -276.516338)
			(xy 385.089146 -276.516084) (xy 385.089702 -276.490173) (xy 385.098463 -276.439096) (xy 385.115715 -276.390228)
			(xy 385.140964 -276.344972) (xy 385.173484 -276.304623) (xy 385.212346 -276.270338) (xy 385.256433 -276.2431)
			(xy 385.304484 -276.22369) (xy 385.329684 -276.217634) (xy 385.358132 -276.212808) (xy 385.358386 -276.212808)
			(xy 385.360926 -276.212554) (xy 385.369325 -276.210774) (xy 385.384329 -276.202451) (xy 385.395748 -276.189643)
			(xy 385.39928 -276.18182) (xy 385.432046 -276.102064) (xy 385.434416 -276.095745) (xy 385.436088 -276.082357)
			(xy 385.435348 -276.075648) (xy 385.43357 -276.06244) (xy 385.424934 -276.051518) (xy 385.406107 -276.026843)
			(xy 385.37343 -275.974073) (xy 385.346792 -275.918011) (xy 385.32652 -275.859346) (xy 385.312863 -275.798799)
			(xy 385.305987 -275.737112) (xy 385.305554 -275.706078) (xy 385.306141 -275.669272) (xy 385.315801 -275.596298)
			(xy 385.334951 -275.525221) (xy 385.363261 -275.457272) (xy 385.381246 -275.425154) (xy 385.42595 -275.348192)
			(xy 385.431629 -275.33709) (xy 385.432544 -275.312199) (xy 385.427728 -275.300694) (xy 385.391406 -275.226272)
			(xy 385.388466 -275.220763) (xy 385.380376 -275.211253) (xy 385.375404 -275.207476) (xy 385.365752 -275.200364)
			(xy 385.353052 -275.198586) (xy 385.328688 -275.194754) (xy 385.281547 -275.180263) (xy 385.237348 -275.158383)
			(xy 385.19724 -275.129684) (xy 385.162266 -275.094913) (xy 385.133335 -275.054972) (xy 385.111199 -275.010901)
			(xy 385.096434 -274.963845) (xy 385.092448 -274.939506) (xy 385.090924 -274.929092) (xy 385.089146 -274.896326)
			(xy 385.089146 -274.896072) (xy 385.089695 -274.870156) (xy 385.098445 -274.819068) (xy 385.115688 -274.770189)
			(xy 385.140931 -274.72492) (xy 385.17345 -274.684558) (xy 385.212313 -274.650262) (xy 385.256405 -274.623015)
			(xy 385.304462 -274.603597) (xy 385.329684 -274.597622) (xy 385.358132 -274.592796) (xy 385.358386 -274.592796)
			(xy 385.360926 -274.592542) (xy 385.369325 -274.590762) (xy 385.384327 -274.582437) (xy 385.395743 -274.569629)
			(xy 385.39928 -274.561808) (xy 385.432046 -274.482052) (xy 385.434415 -274.475733) (xy 385.436084 -274.462345)
			(xy 385.435348 -274.455636) (xy 385.43357 -274.442428) (xy 385.424934 -274.431506) (xy 385.40038 -274.398978)
			(xy 385.359962 -274.32821) (xy 385.344416 -274.290536) (xy 385.344416 -274.290282) (xy 385.34172 -274.284083)
			(xy 385.333607 -274.273274) (xy 385.328414 -274.268946) (xy 385.32308 -274.264882) (xy 385.310888 -274.259548)
			(xy 385.27228 -274.254468) (xy 385.225036 -274.248372) (xy 385.218318 -274.247996) (xy 385.205068 -274.250314)
			(xy 385.198874 -274.252944) (xy 385.197096 -274.253706) (xy 385.17576 -274.264628) (xy 385.167632 -274.271232)
			(xy 385.164076 -274.27555) (xy 385.149526 -274.293281) (xy 385.116009 -274.32459) (xy 385.078182 -274.350528)
			(xy 385.036899 -274.370512) (xy 384.993089 -274.384091) (xy 384.947741 -274.390958) (xy 384.924808 -274.391374)
			(xy 384.899553 -274.390882) (xy 384.849731 -274.382569) (xy 384.801957 -274.36617) (xy 384.757533 -274.34213)
			(xy 384.717673 -274.311106) (xy 384.683462 -274.273945) (xy 384.655835 -274.231659) (xy 384.635545 -274.185403)
			(xy 384.623145 -274.136438) (xy 384.618974 -274.0861) (xy 384.623145 -274.035762) (xy 384.635545 -273.986797)
			(xy 384.655835 -273.940541) (xy 384.683462 -273.898255) (xy 384.717673 -273.861094) (xy 384.757533 -273.83007)
			(xy 384.801957 -273.80603) (xy 384.849731 -273.789631) (xy 384.899553 -273.781318) (xy 384.924808 -273.780758)
			(xy 384.94832 -273.781184) (xy 384.99479 -273.788379) (xy 385.039607 -273.802614) (xy 385.081712 -273.823551)
			(xy 385.120109 -273.850695) (xy 385.153892 -273.883405) (xy 385.168394 -273.901916) (xy 385.170426 -273.90471)
			(xy 385.18084 -273.915124) (xy 385.191 -273.920966) (xy 385.196576 -273.92316) (xy 385.208379 -273.92521)
			(xy 385.214368 -273.92503) (xy 385.217924 -273.924776) (xy 385.30403 -273.913346) (xy 385.310713 -273.912211)
			(xy 385.323192 -273.906928) (xy 385.328668 -273.902932) (xy 385.334002 -273.898868) (xy 385.341876 -273.8882)
			(xy 385.344416 -273.881596) (xy 385.35234 -273.86189) (xy 385.370779 -273.823624) (xy 385.381246 -273.805142)
			(xy 385.514596 -273.575526) (xy 385.517733 -273.569647) (xy 385.521195 -273.556785) (xy 385.521454 -273.550126)
			(xy 385.521454 -272.942304) (xy 385.521307 -272.936722) (xy 385.518871 -272.925828) (xy 385.516628 -272.920714)
			(xy 385.510024 -272.906998) (xy 385.504944 -272.898362) (xy 385.495546 -272.885662) (xy 385.491736 -272.88236)
			(xy 385.467782 -272.860306) (xy 385.424642 -272.811533) (xy 385.387468 -272.758073) (xy 385.356765 -272.700652)
			(xy 385.344416 -272.670524) (xy 385.341876 -272.66392) (xy 385.334002 -272.653252) (xy 385.328414 -272.648934)
			(xy 385.32294 -272.64497) (xy 385.310453 -272.639816) (xy 385.303776 -272.638774) (xy 385.255008 -272.63217)
			(xy 385.2545 -272.63217) (xy 385.225036 -272.62836) (xy 385.218317 -272.627984) (xy 385.205068 -272.630301)
			(xy 385.198874 -272.632932) (xy 385.197096 -272.633694) (xy 385.17576 -272.644616) (xy 385.167632 -272.65122)
			(xy 385.164076 -272.655538) (xy 385.149526 -272.673269) (xy 385.11601 -272.704579) (xy 385.078183 -272.730519)
			(xy 385.0369 -272.750504) (xy 384.99309 -272.764083) (xy 384.947741 -272.77095) (xy 384.924808 -272.771362)
			(xy 384.899554 -272.77087) (xy 384.849734 -272.762558) (xy 384.801961 -272.746159) (xy 384.75754 -272.72212)
			(xy 384.717681 -272.691098) (xy 384.683472 -272.653938) (xy 384.655846 -272.611654) (xy 384.635556 -272.565399)
			(xy 384.623157 -272.516436) (xy 384.618986 -272.4661) (xy 384.623157 -272.415764) (xy 384.635556 -272.366801)
			(xy 384.655846 -272.320546) (xy 384.683472 -272.278262) (xy 384.717681 -272.241102) (xy 384.75754 -272.21008)
			(xy 384.801961 -272.186041) (xy 384.849734 -272.169642) (xy 384.899554 -272.16133) (xy 384.924808 -272.160746)
			(xy 384.94832 -272.161172) (xy 384.99479 -272.168367) (xy 385.039608 -272.182601) (xy 385.081713 -272.203537)
			(xy 385.120112 -272.230681) (xy 385.153895 -272.263391) (xy 385.168394 -272.281904) (xy 385.170426 -272.284698)
			(xy 385.18084 -272.295112) (xy 385.191 -272.300954) (xy 385.196576 -272.303148) (xy 385.208378 -272.305199)
			(xy 385.214368 -272.305018) (xy 385.217924 -272.304764) (xy 385.30403 -272.293334) (xy 385.310713 -272.292198)
			(xy 385.323191 -272.286915) (xy 385.328668 -272.28292) (xy 385.334002 -272.278856) (xy 385.341876 -272.268188)
			(xy 385.344416 -272.261584) (xy 385.352338 -272.241877) (xy 385.370771 -272.203607) (xy 385.381246 -272.18513)
			(xy 385.42595 -272.108168) (xy 385.431647 -272.097066) (xy 385.432595 -272.072158) (xy 385.427728 -272.06067)
			(xy 385.391406 -271.986248) (xy 385.388464 -271.980741) (xy 385.380372 -271.971235) (xy 385.375404 -271.967452)
			(xy 385.365752 -271.96034) (xy 385.353052 -271.958562) (xy 385.328689 -271.95473) (xy 385.281549 -271.940238)
			(xy 385.237352 -271.918358) (xy 385.197246 -271.889658) (xy 385.162275 -271.854886) (xy 385.133346 -271.814945)
			(xy 385.111214 -271.770874) (xy 385.096452 -271.723818) (xy 385.092448 -271.699482) (xy 385.090924 -271.689068)
			(xy 385.089146 -271.656302) (xy 385.089146 -271.656048) (xy 385.089697 -271.630133) (xy 385.09845 -271.579048)
			(xy 385.115696 -271.530172) (xy 385.14094 -271.484907) (xy 385.17346 -271.444549) (xy 385.212322 -271.410256)
			(xy 385.256413 -271.383011) (xy 385.304468 -271.363595) (xy 385.329684 -271.357598) (xy 385.358132 -271.352772)
			(xy 385.358386 -271.352772) (xy 385.360926 -271.352518) (xy 385.369323 -271.350737) (xy 385.384323 -271.342411)
			(xy 385.395733 -271.3296) (xy 385.39928 -271.321784) (xy 385.432046 -271.242028) (xy 385.434412 -271.235708)
			(xy 385.436074 -271.222322) (xy 385.435348 -271.215612) (xy 385.43357 -271.202404) (xy 385.424934 -271.191482)
			(xy 385.406108 -271.166807) (xy 385.373435 -271.114035) (xy 385.346801 -271.057973) (xy 385.326533 -270.999308)
			(xy 385.312879 -270.938761) (xy 385.306007 -270.877076) (xy 385.305554 -270.846042) (xy 385.306143 -270.809237)
			(xy 385.315807 -270.736264) (xy 385.334962 -270.66519) (xy 385.363275 -270.597243) (xy 385.381246 -270.565118)
			(xy 385.42595 -270.488156) (xy 385.431644 -270.477054) (xy 385.432587 -270.452149) (xy 385.427728 -270.440658)
			(xy 385.391406 -270.366236) (xy 385.388463 -270.360729) (xy 385.38037 -270.351225) (xy 385.375404 -270.34744)
			(xy 385.365752 -270.340328) (xy 385.353052 -270.33855) (xy 385.329003 -270.334767) (xy 385.282439 -270.320568)
			(xy 385.238719 -270.299157) (xy 385.198953 -270.271077) (xy 385.164148 -270.237041) (xy 385.135188 -270.197911)
			(xy 385.112807 -270.15468) (xy 385.097572 -270.108444) (xy 385.08987 -270.060377) (xy 385.0894 -270.036036)
			(xy 385.089867 -270.012056) (xy 385.097361 -269.964685) (xy 385.11217 -269.919068) (xy 385.133929 -269.876328)
			(xy 385.162104 -269.837516) (xy 385.196002 -269.803588) (xy 385.234787 -269.775377) (xy 385.277507 -269.753578)
			(xy 385.32311 -269.738727) (xy 385.370474 -269.731189) (xy 385.394454 -269.730728) (xy 385.394962 -269.730728)
			(xy 385.414266 -269.731236) (xy 385.424934 -269.731998) (xy 385.43484 -269.728442) (xy 385.439666 -269.726584)
			(xy 385.448491 -269.721198) (xy 385.452366 -269.717774) (xy 385.505452 -269.66799) (xy 385.512652 -269.660599)
			(xy 385.520923 -269.641718) (xy 385.521454 -269.631414) (xy 385.521454 -268.692884) (xy 385.521979 -268.683041)
			(xy 385.529547 -268.664862) (xy 385.536186 -268.657578) (xy 386.065522 -268.128242) (xy 386.072242 -268.121006)
			(xy 386.079855 -268.102802) (xy 386.080254 -268.092936) (xy 386.080254 -267.994892) (xy 386.080254 -267.991844)
			(xy 386.079021 -267.98072) (xy 386.068348 -267.961078) (xy 386.05968 -267.953998) (xy 385.996434 -267.907008)
			(xy 385.99364 -267.904976) (xy 385.985698 -267.900342) (xy 385.96772 -267.896549) (xy 385.958588 -267.89761)
			(xy 385.951476 -267.89888) (xy 385.948682 -267.899642) (xy 385.92822 -267.905085) (xy 385.886286 -267.910943)
			(xy 385.865116 -267.911326) (xy 385.864862 -267.911326) (xy 385.840872 -267.910853) (xy 385.793484 -267.903342)
			(xy 385.747854 -267.888511) (xy 385.705105 -267.866726) (xy 385.66629 -267.838522) (xy 385.632365 -267.804594)
			(xy 385.604164 -267.765778) (xy 385.582381 -267.723028) (xy 385.567553 -267.677396) (xy 385.560046 -267.630008)
			(xy 385.559554 -267.606018) (xy 385.560045 -267.581085) (xy 385.568131 -267.53188) (xy 385.584093 -267.484638)
			(xy 385.607507 -267.440611) (xy 385.637753 -267.400965) (xy 385.655566 -267.383514) (xy 385.658868 -267.380212)
			(xy 385.667504 -267.368528) (xy 385.672838 -267.359892) (xy 385.675632 -267.353542) (xy 385.677664 -267.348208)
			(xy 385.677664 -267.316712) (xy 385.675378 -267.309346) (xy 385.675124 -267.308584) (xy 385.674616 -267.30706)
			(xy 385.669282 -267.288264) (xy 385.669282 -267.287756) (xy 385.64693 -267.204698) (xy 385.644898 -267.197078)
			(xy 385.644898 -267.196824) (xy 385.643628 -267.192506) (xy 385.643628 -267.192252) (xy 385.632706 -267.151104)
			(xy 385.63042 -267.144246) (xy 385.627045 -267.137006) (xy 385.616546 -267.124976) (xy 385.609846 -267.120624)
			(xy 385.544822 -267.084556) (xy 385.540021 -267.082018) (xy 385.529644 -267.078822) (xy 385.524248 -267.078206)
			(xy 385.51358 -267.077444) (xy 385.506976 -267.079984) (xy 385.502912 -267.081508) (xy 385.477068 -267.090689)
			(xy 385.423142 -267.100662) (xy 385.395724 -267.10132) (xy 385.39039 -267.10132) (xy 385.366623 -267.10053)
			(xy 385.319755 -267.092494) (xy 385.2747 -267.077287) (xy 385.232549 -267.055278) (xy 385.19432 -267.026998)
			(xy 385.160939 -266.993133) (xy 385.133213 -266.9545) (xy 385.111813 -266.912036) (xy 385.097257 -266.866767)
			(xy 385.089897 -266.819788) (xy 385.0894 -266.796012) (xy 385.089891 -266.771111) (xy 385.097969 -266.721969)
			(xy 385.113914 -266.674789) (xy 385.137302 -266.630821) (xy 385.167515 -266.59123) (xy 385.203751 -266.557066)
			(xy 385.245049 -266.529234) (xy 385.290317 -266.508472) (xy 385.31419 -266.501372) (xy 385.314444 -266.501372)
			(xy 385.318044 -266.500352) (xy 385.324928 -266.497417) (xy 385.32816 -266.49553) (xy 385.331829 -266.493123)
			(xy 385.338347 -266.487251) (xy 385.341114 -266.483846) (xy 385.357878 -266.463018) (xy 385.362951 -266.456147)
			(xy 385.368641 -266.440054) (xy 385.369054 -266.431522) (xy 385.369054 -266.262104) (xy 385.367784 -266.25042)
			(xy 385.363974 -266.234672) (xy 385.362704 -266.232132) (xy 385.361434 -266.229338) (xy 385.348109 -266.200812)
			(xy 385.327218 -266.141414) (xy 385.31312 -266.080048) (xy 385.305992 -266.017488) (xy 385.305554 -265.986006)
			(xy 385.305968 -265.95662) (xy 385.312214 -265.898181) (xy 385.324564 -265.840721) (xy 385.342882 -265.784876)
			(xy 385.354576 -265.757914) (xy 385.359148 -265.748008) (xy 385.36499 -265.735054) (xy 385.366839 -265.730374)
			(xy 385.368894 -265.720525) (xy 385.369054 -265.715496) (xy 385.369054 -265.540744) (xy 385.368734 -265.532934)
			(xy 385.363955 -265.518061) (xy 385.359656 -265.511534) (xy 385.357878 -265.508994) (xy 385.341114 -265.488166)
			(xy 385.338336 -265.484771) (xy 385.331825 -265.478893) (xy 385.32816 -265.476482) (xy 385.324936 -265.474581)
			(xy 385.318048 -265.471653) (xy 385.314444 -265.47064) (xy 385.31419 -265.47064) (xy 385.290291 -265.463599)
			(xy 385.245002 -265.442843) (xy 385.203681 -265.415011) (xy 385.167425 -265.380843) (xy 385.137195 -265.341244)
			(xy 385.113791 -265.297264) (xy 385.097836 -265.250069) (xy 385.089751 -265.20091) (xy 385.089751 -265.15109)
			(xy 385.097836 -265.101931) (xy 385.113791 -265.054736) (xy 385.137195 -265.010756) (xy 385.167425 -264.971157)
			(xy 385.203681 -264.936989) (xy 385.245002 -264.909157) (xy 385.290291 -264.888401) (xy 385.31419 -264.88136)
			(xy 385.314444 -264.88136) (xy 385.318044 -264.88034) (xy 385.324928 -264.877404) (xy 385.32816 -264.875518)
			(xy 385.331828 -264.873111) (xy 385.338346 -264.867238) (xy 385.341114 -264.863834) (xy 385.357878 -264.843006)
			(xy 385.362963 -264.836139) (xy 385.368681 -264.820046) (xy 385.369054 -264.81151) (xy 385.369054 -264.642092)
			(xy 385.367784 -264.630662) (xy 385.363974 -264.614406) (xy 385.361434 -264.609326) (xy 385.34467 -264.570718)
			(xy 385.341876 -264.563606) (xy 385.33705 -264.55751) (xy 385.330603 -264.550068) (xy 385.313477 -264.540394)
			(xy 385.303776 -264.538714) (xy 385.224782 -264.5283) (xy 385.218691 -264.527929) (xy 385.206622 -264.529718)
			(xy 385.200906 -264.531856) (xy 385.197096 -264.533634) (xy 385.17576 -264.544556) (xy 385.167632 -264.55116)
			(xy 385.164076 -264.555478) (xy 385.149525 -264.573207) (xy 385.116007 -264.604514) (xy 385.07818 -264.63045)
			(xy 385.036897 -264.650432) (xy 384.993088 -264.664009) (xy 384.94774 -264.670875) (xy 384.924808 -264.671302)
			(xy 384.900815 -264.670856) (xy 384.853419 -264.663351) (xy 384.80778 -264.648523) (xy 384.765023 -264.626738)
			(xy 384.726201 -264.598532) (xy 384.692269 -264.5646) (xy 384.664063 -264.525778) (xy 384.642278 -264.483022)
			(xy 384.62745 -264.437383) (xy 384.619944 -264.389987) (xy 384.6195 -264.365994) (xy 384.620278 -264.335097)
			(xy 384.632694 -264.274563) (xy 384.644138 -264.245852) (xy 384.645916 -264.241534) (xy 384.64871 -264.228834)
			(xy 384.650033 -264.219263) (xy 384.646242 -264.200333) (xy 384.641344 -264.192004) (xy 384.596894 -264.123424)
			(xy 384.595116 -264.120884) (xy 384.594608 -264.120376) (xy 384.588504 -264.113029) (xy 384.572188 -264.103122)
			(xy 384.562858 -264.101072) (xy 384.554222 -264.10031) (xy 384.35534 -264.10031) (xy 384.346704 -264.101072)
			(xy 384.337366 -264.103094) (xy 384.321059 -264.113024) (xy 384.314954 -264.120376) (xy 384.314446 -264.120884)
			(xy 384.312668 -264.123424) (xy 384.268218 -264.192004) (xy 384.263312 -264.20033) (xy 384.259523 -264.219263)
			(xy 384.260852 -264.228834) (xy 384.263646 -264.241534) (xy 384.265424 -264.245852) (xy 384.276865 -264.274563)
			(xy 384.289271 -264.335098) (xy 384.290062 -264.365994) (xy 384.289616 -264.389986) (xy 384.28211 -264.43738)
			(xy 384.267281 -264.483015) (xy 384.245496 -264.525769) (xy 384.217289 -264.564588) (xy 384.183357 -264.598515)
			(xy 384.144535 -264.626717) (xy 384.101778 -264.648497) (xy 384.056141 -264.663319) (xy 384.008746 -264.670819)
			(xy 383.984754 -264.671302) (xy 383.960879 -264.670837) (xy 383.913713 -264.663396) (xy 383.868281 -264.648703)
			(xy 383.82569 -264.627116) (xy 383.786979 -264.599162) (xy 383.753092 -264.565522) (xy 383.724855 -264.527016)
			(xy 383.702957 -264.484584) (xy 383.687932 -264.43926) (xy 383.680146 -264.39215) (xy 383.679446 -264.36828)
			(xy 383.679446 -264.367772) (xy 383.679446 -264.365994) (xy 383.679571 -264.354004) (xy 383.681481 -264.3301)
			(xy 383.683256 -264.318242) (xy 383.68351 -264.31621) (xy 383.683764 -264.313162) (xy 383.68853 -264.288765)
			(xy 383.704919 -264.241837) (xy 383.728692 -264.198184) (xy 383.759224 -264.158959) (xy 383.795706 -264.125198)
			(xy 383.837175 -264.097793) (xy 383.882537 -264.077467) (xy 383.930591 -264.064758) (xy 383.95529 -264.061956)
			(xy 383.956052 -264.061956) (xy 383.963007 -264.060957) (xy 383.976018 -264.055667) (xy 383.981706 -264.051542)
			(xy 383.987548 -264.047224) (xy 383.99593 -264.035794) (xy 384.029458 -263.943338) (xy 384.031967 -263.934611)
			(xy 384.031337 -263.916475) (xy 384.024442 -263.899688) (xy 384.018536 -263.892792) (xy 384.017774 -263.89203)
			(xy 384.017266 -263.891522) (xy 383.884424 -263.75868) (xy 383.880695 -263.755156) (xy 383.872123 -263.749521)
			(xy 383.867406 -263.747504) (xy 383.858516 -263.743948) (xy 383.831846 -263.744456) (xy 383.784602 -263.745472)
			(xy 383.780284 -263.74598) (xy 383.776669 -263.746616) (xy 383.769655 -263.748779) (xy 383.766314 -263.750298)
			(xy 383.740406 -263.762236) (xy 383.733548 -263.769094) (xy 383.716196 -263.786204) (xy 383.677067 -263.815245)
			(xy 383.633828 -263.837712) (xy 383.587572 -263.853036) (xy 383.539471 -263.860829) (xy 383.515108 -263.861296)
			(xy 383.5146 -263.861296) (xy 383.497836 -263.861042) (xy 383.49682 -263.861042) (xy 383.472023 -263.859082)
			(xy 383.423504 -263.848133) (xy 383.3774 -263.829468) (xy 383.334928 -263.803581) (xy 383.297212 -263.771155)
			(xy 383.265247 -263.733047) (xy 383.239879 -263.690264) (xy 383.221776 -263.643936) (xy 383.211419 -263.595287)
			(xy 383.2098 -263.570466) (xy 383.209546 -263.563862) (xy 383.209546 -263.555988) (xy 383.210027 -263.531565)
			(xy 383.217805 -263.483341) (xy 383.233162 -263.43697) (xy 383.255704 -263.393636) (xy 383.284858 -263.354443)
			(xy 383.302002 -263.33704) (xy 383.308352 -263.33069) (xy 383.321306 -263.30275) (xy 383.322946 -263.298669)
			(xy 383.324983 -263.290114) (xy 383.32537 -263.285732) (xy 383.325878 -263.256522) (xy 383.325878 -263.256014)
			(xy 383.32664 -263.222994) (xy 383.326366 -263.212666) (xy 383.318635 -263.193526) (xy 383.311654 -263.18591)
			(xy 383.250186 -263.124442) (xy 383.246458 -263.120917) (xy 383.237886 -263.115282) (xy 383.233168 -263.113266)
			(xy 383.224532 -263.10971) (xy 371.876828 -263.10971) (xy 371.866991 -263.110247) (xy 371.848831 -263.117835)
			(xy 371.841522 -263.124442) (xy 371.587014 -263.37895) (xy 371.578643 -263.388284) (xy 371.571449 -263.412269)
			(xy 371.573298 -263.42467) (xy 371.57533 -263.435084) (xy 371.577362 -263.43991) (xy 371.587982 -263.467683)
			(xy 371.599493 -263.526009) (xy 371.600222 -263.555734) (xy 371.600222 -263.555988) (xy 372.868964 -263.555988)
			(xy 372.872924 -263.506934) (xy 372.884701 -263.45915) (xy 372.903992 -263.413874) (xy 372.930295 -263.372278)
			(xy 372.96293 -263.335441) (xy 373.001051 -263.304316) (xy 373.043672 -263.279709) (xy 373.089688 -263.262257)
			(xy 373.137907 -263.252413) (xy 373.187082 -263.250432) (xy 373.235937 -263.256364) (xy 373.283208 -263.270056)
			(xy 373.32767 -263.291154) (xy 373.368173 -263.31911) (xy 373.403666 -263.353202) (xy 373.433231 -263.392546)
			(xy 373.456102 -263.436123) (xy 373.471686 -263.482804) (xy 373.479581 -263.531381) (xy 373.480076 -263.555988)
			(xy 374.749072 -263.555988) (xy 374.753032 -263.506934) (xy 374.764809 -263.45915) (xy 374.7841 -263.413874)
			(xy 374.810403 -263.372278) (xy 374.843038 -263.335441) (xy 374.881159 -263.304316) (xy 374.92378 -263.279709)
			(xy 374.969796 -263.262257) (xy 375.018015 -263.252413) (xy 375.06719 -263.250432) (xy 375.116045 -263.256364)
			(xy 375.163316 -263.270056) (xy 375.207778 -263.291154) (xy 375.248281 -263.31911) (xy 375.283774 -263.353202)
			(xy 375.313339 -263.392546) (xy 375.33621 -263.436123) (xy 375.351794 -263.482804) (xy 375.359689 -263.531381)
			(xy 375.360184 -263.555988) (xy 375.678695 -263.555988) (xy 375.68279 -263.50526) (xy 375.694969 -263.455846)
			(xy 375.714917 -263.409026) (xy 375.742118 -263.366012) (xy 375.775866 -263.327918) (xy 375.815288 -263.295731)
			(xy 375.859362 -263.270285) (xy 375.906948 -263.252238) (xy 375.956812 -263.242058) (xy 376.007664 -263.240009)
			(xy 376.058185 -263.246143) (xy 376.107069 -263.260303) (xy 376.153048 -263.28212) (xy 376.194932 -263.31103)
			(xy 376.231636 -263.346285) (xy 376.262209 -263.386971) (xy 376.28586 -263.432034) (xy 376.301976 -263.480308)
			(xy 376.31014 -263.530542) (xy 376.310652 -263.555988) (xy 376.628926 -263.555988) (xy 376.632886 -263.506934)
			(xy 376.644663 -263.45915) (xy 376.663954 -263.413874) (xy 376.690257 -263.372278) (xy 376.722892 -263.335441)
			(xy 376.761013 -263.304316) (xy 376.803634 -263.279709) (xy 376.84965 -263.262257) (xy 376.897869 -263.252413)
			(xy 376.947044 -263.250432) (xy 376.995899 -263.256364) (xy 377.04317 -263.270056) (xy 377.087632 -263.291154)
			(xy 377.128135 -263.31911) (xy 377.163628 -263.353202) (xy 377.193193 -263.392546) (xy 377.216064 -263.436123)
			(xy 377.231648 -263.482804) (xy 377.239543 -263.531381) (xy 377.240038 -263.555988) (xy 377.558549 -263.555988)
			(xy 377.562644 -263.50526) (xy 377.574823 -263.455846) (xy 377.594771 -263.409026) (xy 377.621972 -263.366012)
			(xy 377.65572 -263.327918) (xy 377.695142 -263.295731) (xy 377.739216 -263.270285) (xy 377.786802 -263.252238)
			(xy 377.836666 -263.242058) (xy 377.887518 -263.240009) (xy 377.938039 -263.246143) (xy 377.986923 -263.260303)
			(xy 378.032902 -263.28212) (xy 378.074786 -263.31103) (xy 378.11149 -263.346285) (xy 378.142063 -263.386971)
			(xy 378.165714 -263.432034) (xy 378.18183 -263.480308) (xy 378.189994 -263.530542) (xy 378.190506 -263.555988)
			(xy 379.438657 -263.555988) (xy 379.442752 -263.50526) (xy 379.454931 -263.455846) (xy 379.474879 -263.409026)
			(xy 379.50208 -263.366012) (xy 379.535828 -263.327918) (xy 379.57525 -263.295731) (xy 379.619324 -263.270285)
			(xy 379.66691 -263.252238) (xy 379.716774 -263.242058) (xy 379.767626 -263.240009) (xy 379.818147 -263.246143)
			(xy 379.867031 -263.260303) (xy 379.91301 -263.28212) (xy 379.954894 -263.31103) (xy 379.991598 -263.346285)
			(xy 380.022171 -263.386971) (xy 380.045822 -263.432034) (xy 380.061938 -263.480308) (xy 380.070102 -263.530542)
			(xy 380.070614 -263.555988) (xy 380.378711 -263.555988) (xy 380.382806 -263.50526) (xy 380.394985 -263.455846)
			(xy 380.414933 -263.409026) (xy 380.442134 -263.366012) (xy 380.475882 -263.327918) (xy 380.515304 -263.295731)
			(xy 380.559378 -263.270285) (xy 380.606964 -263.252238) (xy 380.656828 -263.242058) (xy 380.70768 -263.240009)
			(xy 380.758201 -263.246143) (xy 380.807085 -263.260303) (xy 380.853064 -263.28212) (xy 380.894948 -263.31103)
			(xy 380.931652 -263.346285) (xy 380.962225 -263.386971) (xy 380.985876 -263.432034) (xy 381.001992 -263.480308)
			(xy 381.010156 -263.530542) (xy 381.010668 -263.555988) (xy 381.328942 -263.555988) (xy 381.332902 -263.506934)
			(xy 381.344679 -263.45915) (xy 381.36397 -263.413874) (xy 381.390273 -263.372278) (xy 381.422908 -263.335441)
			(xy 381.461029 -263.304316) (xy 381.50365 -263.279709) (xy 381.549666 -263.262257) (xy 381.597885 -263.252413)
			(xy 381.64706 -263.250432) (xy 381.695915 -263.256364) (xy 381.743186 -263.270056) (xy 381.787648 -263.291154)
			(xy 381.828151 -263.31911) (xy 381.863644 -263.353202) (xy 381.893209 -263.392546) (xy 381.91608 -263.436123)
			(xy 381.931664 -263.482804) (xy 381.939559 -263.531381) (xy 381.940054 -263.555988) (xy 382.268996 -263.555988)
			(xy 382.272956 -263.506934) (xy 382.284733 -263.45915) (xy 382.304024 -263.413874) (xy 382.330327 -263.372278)
			(xy 382.362962 -263.335441) (xy 382.401083 -263.304316) (xy 382.443704 -263.279709) (xy 382.48972 -263.262257)
			(xy 382.537939 -263.252413) (xy 382.587114 -263.250432) (xy 382.635969 -263.256364) (xy 382.68324 -263.270056)
			(xy 382.727702 -263.291154) (xy 382.768205 -263.31911) (xy 382.803698 -263.353202) (xy 382.833263 -263.392546)
			(xy 382.856134 -263.436123) (xy 382.871718 -263.482804) (xy 382.879613 -263.531381) (xy 382.880108 -263.555988)
			(xy 382.879613 -263.580595) (xy 382.871718 -263.629172) (xy 382.856134 -263.675853) (xy 382.833263 -263.71943)
			(xy 382.803698 -263.758774) (xy 382.768205 -263.792866) (xy 382.727702 -263.820822) (xy 382.68324 -263.84192)
			(xy 382.635969 -263.855612) (xy 382.587114 -263.861544) (xy 382.537939 -263.859563) (xy 382.48972 -263.849719)
			(xy 382.443704 -263.832267) (xy 382.401083 -263.80766) (xy 382.362962 -263.776535) (xy 382.330327 -263.739698)
			(xy 382.304024 -263.698102) (xy 382.284733 -263.652826) (xy 382.272956 -263.605042) (xy 382.268996 -263.555988)
			(xy 381.940054 -263.555988) (xy 381.939559 -263.580595) (xy 381.931664 -263.629172) (xy 381.91608 -263.675853)
			(xy 381.893209 -263.71943) (xy 381.863644 -263.758774) (xy 381.828151 -263.792866) (xy 381.787648 -263.820822)
			(xy 381.743186 -263.84192) (xy 381.695915 -263.855612) (xy 381.64706 -263.861544) (xy 381.597885 -263.859563)
			(xy 381.549666 -263.849719) (xy 381.50365 -263.832267) (xy 381.461029 -263.80766) (xy 381.422908 -263.776535)
			(xy 381.390273 -263.739698) (xy 381.36397 -263.698102) (xy 381.344679 -263.652826) (xy 381.332902 -263.605042)
			(xy 381.328942 -263.555988) (xy 381.010668 -263.555988) (xy 381.010156 -263.581434) (xy 381.001992 -263.631668)
			(xy 380.985876 -263.679942) (xy 380.962225 -263.725005) (xy 380.931652 -263.765691) (xy 380.894948 -263.800946)
			(xy 380.853064 -263.829856) (xy 380.807085 -263.851673) (xy 380.758201 -263.865833) (xy 380.70768 -263.871967)
			(xy 380.656828 -263.869918) (xy 380.606964 -263.859738) (xy 380.559378 -263.841691) (xy 380.515304 -263.816245)
			(xy 380.475882 -263.784058) (xy 380.442134 -263.745964) (xy 380.414933 -263.70295) (xy 380.394985 -263.65613)
			(xy 380.382806 -263.606716) (xy 380.378711 -263.555988) (xy 380.070614 -263.555988) (xy 380.070102 -263.581434)
			(xy 380.061938 -263.631668) (xy 380.045822 -263.679942) (xy 380.022171 -263.725005) (xy 379.991598 -263.765691)
			(xy 379.954894 -263.800946) (xy 379.91301 -263.829856) (xy 379.867031 -263.851673) (xy 379.818147 -263.865833)
			(xy 379.767626 -263.871967) (xy 379.716774 -263.869918) (xy 379.66691 -263.859738) (xy 379.619324 -263.841691)
			(xy 379.57525 -263.816245) (xy 379.535828 -263.784058) (xy 379.50208 -263.745964) (xy 379.474879 -263.70295)
			(xy 379.454931 -263.65613) (xy 379.442752 -263.606716) (xy 379.438657 -263.555988) (xy 378.190506 -263.555988)
			(xy 378.189994 -263.581434) (xy 378.18183 -263.631668) (xy 378.165714 -263.679942) (xy 378.142063 -263.725005)
			(xy 378.11149 -263.765691) (xy 378.074786 -263.800946) (xy 378.032902 -263.829856) (xy 377.986923 -263.851673)
			(xy 377.938039 -263.865833) (xy 377.887518 -263.871967) (xy 377.836666 -263.869918) (xy 377.786802 -263.859738)
			(xy 377.739216 -263.841691) (xy 377.695142 -263.816245) (xy 377.65572 -263.784058) (xy 377.621972 -263.745964)
			(xy 377.594771 -263.70295) (xy 377.574823 -263.65613) (xy 377.562644 -263.606716) (xy 377.558549 -263.555988)
			(xy 377.240038 -263.555988) (xy 377.239543 -263.580595) (xy 377.231648 -263.629172) (xy 377.216064 -263.675853)
			(xy 377.193193 -263.71943) (xy 377.163628 -263.758774) (xy 377.128135 -263.792866) (xy 377.087632 -263.820822)
			(xy 377.04317 -263.84192) (xy 376.995899 -263.855612) (xy 376.947044 -263.861544) (xy 376.897869 -263.859563)
			(xy 376.84965 -263.849719) (xy 376.803634 -263.832267) (xy 376.761013 -263.80766) (xy 376.722892 -263.776535)
			(xy 376.690257 -263.739698) (xy 376.663954 -263.698102) (xy 376.644663 -263.652826) (xy 376.632886 -263.605042)
			(xy 376.628926 -263.555988) (xy 376.310652 -263.555988) (xy 376.31014 -263.581434) (xy 376.301976 -263.631668)
			(xy 376.28586 -263.679942) (xy 376.262209 -263.725005) (xy 376.231636 -263.765691) (xy 376.194932 -263.800946)
			(xy 376.153048 -263.829856) (xy 376.107069 -263.851673) (xy 376.058185 -263.865833) (xy 376.007664 -263.871967)
			(xy 375.956812 -263.869918) (xy 375.906948 -263.859738) (xy 375.859362 -263.841691) (xy 375.815288 -263.816245)
			(xy 375.775866 -263.784058) (xy 375.742118 -263.745964) (xy 375.714917 -263.70295) (xy 375.694969 -263.65613)
			(xy 375.68279 -263.606716) (xy 375.678695 -263.555988) (xy 375.360184 -263.555988) (xy 375.359689 -263.580595)
			(xy 375.351794 -263.629172) (xy 375.33621 -263.675853) (xy 375.313339 -263.71943) (xy 375.283774 -263.758774)
			(xy 375.248281 -263.792866) (xy 375.207778 -263.820822) (xy 375.163316 -263.84192) (xy 375.116045 -263.855612)
			(xy 375.06719 -263.861544) (xy 375.018015 -263.859563) (xy 374.969796 -263.849719) (xy 374.92378 -263.832267)
			(xy 374.881159 -263.80766) (xy 374.843038 -263.776535) (xy 374.810403 -263.739698) (xy 374.7841 -263.698102)
			(xy 374.764809 -263.652826) (xy 374.753032 -263.605042) (xy 374.749072 -263.555988) (xy 373.480076 -263.555988)
			(xy 373.479581 -263.580595) (xy 373.471686 -263.629172) (xy 373.456102 -263.675853) (xy 373.433231 -263.71943)
			(xy 373.403666 -263.758774) (xy 373.368173 -263.792866) (xy 373.32767 -263.820822) (xy 373.283208 -263.84192)
			(xy 373.235937 -263.855612) (xy 373.187082 -263.861544) (xy 373.137907 -263.859563) (xy 373.089688 -263.849719)
			(xy 373.043672 -263.832267) (xy 373.001051 -263.80766) (xy 372.96293 -263.776535) (xy 372.930295 -263.739698)
			(xy 372.903992 -263.698102) (xy 372.884701 -263.652826) (xy 372.872924 -263.605042) (xy 372.868964 -263.555988)
			(xy 371.600222 -263.555988) (xy 371.5997 -263.581243) (xy 371.591387 -263.631065) (xy 371.574986 -263.678839)
			(xy 371.550945 -263.723262) (xy 371.519921 -263.763122) (xy 371.482759 -263.797332) (xy 371.440473 -263.824958)
			(xy 371.394217 -263.845248) (xy 371.345252 -263.857648) (xy 371.294914 -263.861819) (xy 371.244576 -263.857648)
			(xy 371.195611 -263.845248) (xy 371.149355 -263.824958) (xy 371.107069 -263.797332) (xy 371.069907 -263.763122)
			(xy 371.038883 -263.723262) (xy 371.014842 -263.678839) (xy 370.998441 -263.631065) (xy 370.990128 -263.581243)
			(xy 370.989606 -263.555988) (xy 370.99113 -263.525) (xy 370.992146 -263.514332) (xy 370.988844 -263.504172)
			(xy 370.986812 -263.499092) (xy 370.985134 -263.49544) (xy 370.980798 -263.488675) (xy 370.978176 -263.48563)
			(xy 370.927376 -263.429496) (xy 370.920029 -263.42269) (xy 370.901567 -263.414967) (xy 370.891562 -263.41451)
			(xy 370.175028 -263.41451) (xy 370.165191 -263.415047) (xy 370.147031 -263.422635) (xy 370.139722 -263.429242)
			(xy 369.610386 -263.958578) (xy 369.603149 -263.965294) (xy 369.584944 -263.972893) (xy 369.57508 -263.97331)
			(xy 369.22456 -263.97331) (xy 369.214421 -263.973758) (xy 369.195723 -263.981607) (xy 369.18151 -263.996071)
			(xy 369.177316 -264.005314) (xy 369.14328 -264.090658) (xy 369.140767 -264.097813) (xy 369.139594 -264.112924)
			(xy 369.140994 -264.120376) (xy 369.142518 -264.127742) (xy 369.150138 -264.141204) (xy 369.155726 -264.146284)
			(xy 369.173386 -264.163702) (xy 369.203386 -264.203202) (xy 369.226613 -264.247027) (xy 369.242458 -264.294029)
			(xy 369.250505 -264.342972) (xy 369.250942 -264.365994) (xy 370.518956 -264.365994) (xy 370.522916 -264.31694)
			(xy 370.534693 -264.269156) (xy 370.553984 -264.22388) (xy 370.580287 -264.182284) (xy 370.612922 -264.145447)
			(xy 370.651043 -264.114322) (xy 370.693664 -264.089715) (xy 370.73968 -264.072263) (xy 370.787899 -264.062419)
			(xy 370.837074 -264.060438) (xy 370.885929 -264.06637) (xy 370.9332 -264.080062) (xy 370.977662 -264.10116)
			(xy 371.018165 -264.129116) (xy 371.053658 -264.163208) (xy 371.083223 -264.202552) (xy 371.106094 -264.246129)
			(xy 371.121678 -264.29281) (xy 371.129573 -264.341387) (xy 371.130068 -264.365994) (xy 372.399064 -264.365994)
			(xy 372.403024 -264.31694) (xy 372.414801 -264.269156) (xy 372.434092 -264.22388) (xy 372.460395 -264.182284)
			(xy 372.49303 -264.145447) (xy 372.531151 -264.114322) (xy 372.573772 -264.089715) (xy 372.619788 -264.072263)
			(xy 372.668007 -264.062419) (xy 372.717182 -264.060438) (xy 372.766037 -264.06637) (xy 372.813308 -264.080062)
			(xy 372.85777 -264.10116) (xy 372.898273 -264.129116) (xy 372.933766 -264.163208) (xy 372.963331 -264.202552)
			(xy 372.986202 -264.246129) (xy 373.001786 -264.29281) (xy 373.009681 -264.341387) (xy 373.010176 -264.365994)
			(xy 374.278918 -264.365994) (xy 374.282878 -264.31694) (xy 374.294655 -264.269156) (xy 374.313946 -264.22388)
			(xy 374.340249 -264.182284) (xy 374.372884 -264.145447) (xy 374.411005 -264.114322) (xy 374.453626 -264.089715)
			(xy 374.499642 -264.072263) (xy 374.547861 -264.062419) (xy 374.597036 -264.060438) (xy 374.645891 -264.06637)
			(xy 374.693162 -264.080062) (xy 374.737624 -264.10116) (xy 374.778127 -264.129116) (xy 374.81362 -264.163208)
			(xy 374.843185 -264.202552) (xy 374.866056 -264.246129) (xy 374.88164 -264.29281) (xy 374.889535 -264.341387)
			(xy 374.89003 -264.365994) (xy 376.148595 -264.365994) (xy 376.15269 -264.315266) (xy 376.164869 -264.265852)
			(xy 376.184817 -264.219032) (xy 376.212018 -264.176018) (xy 376.245766 -264.137924) (xy 376.285188 -264.105737)
			(xy 376.329262 -264.080291) (xy 376.376848 -264.062244) (xy 376.426712 -264.052064) (xy 376.477564 -264.050015)
			(xy 376.528085 -264.056149) (xy 376.576969 -264.070309) (xy 376.622948 -264.092126) (xy 376.664832 -264.121036)
			(xy 376.701536 -264.156291) (xy 376.732109 -264.196977) (xy 376.75576 -264.24204) (xy 376.771876 -264.290314)
			(xy 376.78004 -264.340548) (xy 376.780552 -264.365994) (xy 377.088649 -264.365994) (xy 377.092744 -264.315266)
			(xy 377.104923 -264.265852) (xy 377.124871 -264.219032) (xy 377.152072 -264.176018) (xy 377.18582 -264.137924)
			(xy 377.225242 -264.105737) (xy 377.269316 -264.080291) (xy 377.316902 -264.062244) (xy 377.366766 -264.052064)
			(xy 377.417618 -264.050015) (xy 377.468139 -264.056149) (xy 377.517023 -264.070309) (xy 377.563002 -264.092126)
			(xy 377.604886 -264.121036) (xy 377.64159 -264.156291) (xy 377.672163 -264.196977) (xy 377.695814 -264.24204)
			(xy 377.71193 -264.290314) (xy 377.720094 -264.340548) (xy 377.720606 -264.365994) (xy 378.039134 -264.365994)
			(xy 378.043094 -264.31694) (xy 378.054871 -264.269156) (xy 378.074162 -264.22388) (xy 378.100465 -264.182284)
			(xy 378.1331 -264.145447) (xy 378.171221 -264.114322) (xy 378.213842 -264.089715) (xy 378.259858 -264.072263)
			(xy 378.308077 -264.062419) (xy 378.357252 -264.060438) (xy 378.406107 -264.06637) (xy 378.453378 -264.080062)
			(xy 378.49784 -264.10116) (xy 378.538343 -264.129116) (xy 378.573836 -264.163208) (xy 378.603401 -264.202552)
			(xy 378.626272 -264.246129) (xy 378.641856 -264.29281) (xy 378.649751 -264.341387) (xy 378.650246 -264.365994)
			(xy 378.968503 -264.365994) (xy 378.972598 -264.315266) (xy 378.984777 -264.265852) (xy 379.004725 -264.219032)
			(xy 379.031926 -264.176018) (xy 379.065674 -264.137924) (xy 379.105096 -264.105737) (xy 379.14917 -264.080291)
			(xy 379.196756 -264.062244) (xy 379.24662 -264.052064) (xy 379.297472 -264.050015) (xy 379.347993 -264.056149)
			(xy 379.396877 -264.070309) (xy 379.442856 -264.092126) (xy 379.48474 -264.121036) (xy 379.521444 -264.156291)
			(xy 379.552017 -264.196977) (xy 379.575668 -264.24204) (xy 379.591784 -264.290314) (xy 379.599948 -264.340548)
			(xy 379.60046 -264.365994) (xy 379.918988 -264.365994) (xy 379.922948 -264.31694) (xy 379.934725 -264.269156)
			(xy 379.954016 -264.22388) (xy 379.980319 -264.182284) (xy 380.012954 -264.145447) (xy 380.051075 -264.114322)
			(xy 380.093696 -264.089715) (xy 380.139712 -264.072263) (xy 380.187931 -264.062419) (xy 380.237106 -264.060438)
			(xy 380.285961 -264.06637) (xy 380.333232 -264.080062) (xy 380.377694 -264.10116) (xy 380.418197 -264.129116)
			(xy 380.45369 -264.163208) (xy 380.483255 -264.202552) (xy 380.506126 -264.246129) (xy 380.52171 -264.29281)
			(xy 380.529605 -264.341387) (xy 380.5301 -264.365994) (xy 380.848611 -264.365994) (xy 380.852706 -264.315266)
			(xy 380.864885 -264.265852) (xy 380.884833 -264.219032) (xy 380.912034 -264.176018) (xy 380.945782 -264.137924)
			(xy 380.985204 -264.105737) (xy 381.029278 -264.080291) (xy 381.076864 -264.062244) (xy 381.126728 -264.052064)
			(xy 381.17758 -264.050015) (xy 381.228101 -264.056149) (xy 381.276985 -264.070309) (xy 381.322964 -264.092126)
			(xy 381.364848 -264.121036) (xy 381.401552 -264.156291) (xy 381.432125 -264.196977) (xy 381.455776 -264.24204)
			(xy 381.471892 -264.290314) (xy 381.480056 -264.340548) (xy 381.480568 -264.365994) (xy 381.799096 -264.365994)
			(xy 381.803056 -264.31694) (xy 381.814833 -264.269156) (xy 381.834124 -264.22388) (xy 381.860427 -264.182284)
			(xy 381.893062 -264.145447) (xy 381.931183 -264.114322) (xy 381.973804 -264.089715) (xy 382.01982 -264.072263)
			(xy 382.068039 -264.062419) (xy 382.117214 -264.060438) (xy 382.166069 -264.06637) (xy 382.21334 -264.080062)
			(xy 382.257802 -264.10116) (xy 382.298305 -264.129116) (xy 382.333798 -264.163208) (xy 382.363363 -264.202552)
			(xy 382.386234 -264.246129) (xy 382.401818 -264.29281) (xy 382.409713 -264.341387) (xy 382.410208 -264.365994)
			(xy 382.738896 -264.365994) (xy 382.742856 -264.31694) (xy 382.754633 -264.269156) (xy 382.773924 -264.22388)
			(xy 382.800227 -264.182284) (xy 382.832862 -264.145447) (xy 382.870983 -264.114322) (xy 382.913604 -264.089715)
			(xy 382.95962 -264.072263) (xy 383.007839 -264.062419) (xy 383.057014 -264.060438) (xy 383.105869 -264.06637)
			(xy 383.15314 -264.080062) (xy 383.197602 -264.10116) (xy 383.238105 -264.129116) (xy 383.273598 -264.163208)
			(xy 383.303163 -264.202552) (xy 383.326034 -264.246129) (xy 383.341618 -264.29281) (xy 383.349513 -264.341387)
			(xy 383.350008 -264.365994) (xy 383.349513 -264.390601) (xy 383.341618 -264.439178) (xy 383.326034 -264.485859)
			(xy 383.303163 -264.529436) (xy 383.273598 -264.56878) (xy 383.238105 -264.602872) (xy 383.197602 -264.630828)
			(xy 383.15314 -264.651926) (xy 383.105869 -264.665618) (xy 383.057014 -264.67155) (xy 383.007839 -264.669569)
			(xy 382.95962 -264.659725) (xy 382.913604 -264.642273) (xy 382.870983 -264.617666) (xy 382.832862 -264.586541)
			(xy 382.800227 -264.549704) (xy 382.773924 -264.508108) (xy 382.754633 -264.462832) (xy 382.742856 -264.415048)
			(xy 382.738896 -264.365994) (xy 382.410208 -264.365994) (xy 382.409713 -264.390601) (xy 382.401818 -264.439178)
			(xy 382.386234 -264.485859) (xy 382.363363 -264.529436) (xy 382.333798 -264.56878) (xy 382.298305 -264.602872)
			(xy 382.257802 -264.630828) (xy 382.21334 -264.651926) (xy 382.166069 -264.665618) (xy 382.117214 -264.67155)
			(xy 382.068039 -264.669569) (xy 382.01982 -264.659725) (xy 381.973804 -264.642273) (xy 381.931183 -264.617666)
			(xy 381.893062 -264.586541) (xy 381.860427 -264.549704) (xy 381.834124 -264.508108) (xy 381.814833 -264.462832)
			(xy 381.803056 -264.415048) (xy 381.799096 -264.365994) (xy 381.480568 -264.365994) (xy 381.480056 -264.39144)
			(xy 381.471892 -264.441674) (xy 381.455776 -264.489948) (xy 381.432125 -264.535011) (xy 381.401552 -264.575697)
			(xy 381.364848 -264.610952) (xy 381.322964 -264.639862) (xy 381.276985 -264.661679) (xy 381.228101 -264.675839)
			(xy 381.17758 -264.681973) (xy 381.126728 -264.679924) (xy 381.076864 -264.669744) (xy 381.029278 -264.651697)
			(xy 380.985204 -264.626251) (xy 380.945782 -264.594064) (xy 380.912034 -264.55597) (xy 380.884833 -264.512956)
			(xy 380.864885 -264.466136) (xy 380.852706 -264.416722) (xy 380.848611 -264.365994) (xy 380.5301 -264.365994)
			(xy 380.529605 -264.390601) (xy 380.52171 -264.439178) (xy 380.506126 -264.485859) (xy 380.483255 -264.529436)
			(xy 380.45369 -264.56878) (xy 380.418197 -264.602872) (xy 380.377694 -264.630828) (xy 380.333232 -264.651926)
			(xy 380.285961 -264.665618) (xy 380.237106 -264.67155) (xy 380.187931 -264.669569) (xy 380.139712 -264.659725)
			(xy 380.093696 -264.642273) (xy 380.051075 -264.617666) (xy 380.012954 -264.586541) (xy 379.980319 -264.549704)
			(xy 379.954016 -264.508108) (xy 379.934725 -264.462832) (xy 379.922948 -264.415048) (xy 379.918988 -264.365994)
			(xy 379.60046 -264.365994) (xy 379.599948 -264.39144) (xy 379.591784 -264.441674) (xy 379.575668 -264.489948)
			(xy 379.552017 -264.535011) (xy 379.521444 -264.575697) (xy 379.48474 -264.610952) (xy 379.442856 -264.639862)
			(xy 379.396877 -264.661679) (xy 379.347993 -264.675839) (xy 379.297472 -264.681973) (xy 379.24662 -264.679924)
			(xy 379.196756 -264.669744) (xy 379.14917 -264.651697) (xy 379.105096 -264.626251) (xy 379.065674 -264.594064)
			(xy 379.031926 -264.55597) (xy 379.004725 -264.512956) (xy 378.984777 -264.466136) (xy 378.972598 -264.416722)
			(xy 378.968503 -264.365994) (xy 378.650246 -264.365994) (xy 378.649751 -264.390601) (xy 378.641856 -264.439178)
			(xy 378.626272 -264.485859) (xy 378.603401 -264.529436) (xy 378.573836 -264.56878) (xy 378.538343 -264.602872)
			(xy 378.49784 -264.630828) (xy 378.453378 -264.651926) (xy 378.406107 -264.665618) (xy 378.357252 -264.67155)
			(xy 378.308077 -264.669569) (xy 378.259858 -264.659725) (xy 378.213842 -264.642273) (xy 378.171221 -264.617666)
			(xy 378.1331 -264.586541) (xy 378.100465 -264.549704) (xy 378.074162 -264.508108) (xy 378.054871 -264.462832)
			(xy 378.043094 -264.415048) (xy 378.039134 -264.365994) (xy 377.720606 -264.365994) (xy 377.720094 -264.39144)
			(xy 377.71193 -264.441674) (xy 377.695814 -264.489948) (xy 377.672163 -264.535011) (xy 377.64159 -264.575697)
			(xy 377.604886 -264.610952) (xy 377.563002 -264.639862) (xy 377.517023 -264.661679) (xy 377.468139 -264.675839)
			(xy 377.417618 -264.681973) (xy 377.366766 -264.679924) (xy 377.316902 -264.669744) (xy 377.269316 -264.651697)
			(xy 377.225242 -264.626251) (xy 377.18582 -264.594064) (xy 377.152072 -264.55597) (xy 377.124871 -264.512956)
			(xy 377.104923 -264.466136) (xy 377.092744 -264.416722) (xy 377.088649 -264.365994) (xy 376.780552 -264.365994)
			(xy 376.78004 -264.39144) (xy 376.771876 -264.441674) (xy 376.75576 -264.489948) (xy 376.732109 -264.535011)
			(xy 376.701536 -264.575697) (xy 376.664832 -264.610952) (xy 376.622948 -264.639862) (xy 376.576969 -264.661679)
			(xy 376.528085 -264.675839) (xy 376.477564 -264.681973) (xy 376.426712 -264.679924) (xy 376.376848 -264.669744)
			(xy 376.329262 -264.651697) (xy 376.285188 -264.626251) (xy 376.245766 -264.594064) (xy 376.212018 -264.55597)
			(xy 376.184817 -264.512956) (xy 376.164869 -264.466136) (xy 376.15269 -264.416722) (xy 376.148595 -264.365994)
			(xy 374.89003 -264.365994) (xy 374.889535 -264.390601) (xy 374.88164 -264.439178) (xy 374.866056 -264.485859)
			(xy 374.843185 -264.529436) (xy 374.81362 -264.56878) (xy 374.778127 -264.602872) (xy 374.737624 -264.630828)
			(xy 374.693162 -264.651926) (xy 374.645891 -264.665618) (xy 374.597036 -264.67155) (xy 374.547861 -264.669569)
			(xy 374.499642 -264.659725) (xy 374.453626 -264.642273) (xy 374.411005 -264.617666) (xy 374.372884 -264.586541)
			(xy 374.340249 -264.549704) (xy 374.313946 -264.508108) (xy 374.294655 -264.462832) (xy 374.282878 -264.415048)
			(xy 374.278918 -264.365994) (xy 373.010176 -264.365994) (xy 373.009681 -264.390601) (xy 373.001786 -264.439178)
			(xy 372.986202 -264.485859) (xy 372.963331 -264.529436) (xy 372.933766 -264.56878) (xy 372.898273 -264.602872)
			(xy 372.85777 -264.630828) (xy 372.813308 -264.651926) (xy 372.766037 -264.665618) (xy 372.717182 -264.67155)
			(xy 372.668007 -264.669569) (xy 372.619788 -264.659725) (xy 372.573772 -264.642273) (xy 372.531151 -264.617666)
			(xy 372.49303 -264.586541) (xy 372.460395 -264.549704) (xy 372.434092 -264.508108) (xy 372.414801 -264.462832)
			(xy 372.403024 -264.415048) (xy 372.399064 -264.365994) (xy 371.130068 -264.365994) (xy 371.129573 -264.390601)
			(xy 371.121678 -264.439178) (xy 371.106094 -264.485859) (xy 371.083223 -264.529436) (xy 371.053658 -264.56878)
			(xy 371.018165 -264.602872) (xy 370.977662 -264.630828) (xy 370.9332 -264.651926) (xy 370.885929 -264.665618)
			(xy 370.837074 -264.67155) (xy 370.787899 -264.669569) (xy 370.73968 -264.659725) (xy 370.693664 -264.642273)
			(xy 370.651043 -264.617666) (xy 370.612922 -264.586541) (xy 370.580287 -264.549704) (xy 370.553984 -264.508108)
			(xy 370.534693 -264.462832) (xy 370.522916 -264.415048) (xy 370.518956 -264.365994) (xy 369.250942 -264.365994)
			(xy 369.250976 -264.367772) (xy 369.250976 -264.37717) (xy 369.250722 -264.380472) (xy 369.250722 -264.381234)
			(xy 369.249317 -264.40418) (xy 369.240473 -264.449292) (xy 369.224963 -264.492567) (xy 369.203139 -264.533027)
			(xy 369.175493 -264.569756) (xy 369.142652 -264.601924) (xy 369.12423 -264.615676) (xy 369.104613 -264.629254)
			(xy 369.062047 -264.650797) (xy 369.016648 -264.665457) (xy 368.969522 -264.672877) (xy 368.921814 -264.672877)
			(xy 368.874688 -264.665457) (xy 368.829289 -264.650797) (xy 368.786723 -264.629254) (xy 368.767106 -264.615676)
			(xy 368.748708 -264.601896) (xy 368.715875 -264.569726) (xy 368.688232 -264.533) (xy 368.666404 -264.492548)
			(xy 368.650882 -264.449281) (xy 368.642018 -264.404178) (xy 368.640614 -264.381234) (xy 368.640614 -264.380472)
			(xy 368.64036 -264.37717) (xy 368.64036 -264.367772) (xy 368.64084 -264.34297) (xy 368.648857 -264.294019)
			(xy 368.664691 -264.247012) (xy 368.687924 -264.203186) (xy 368.717944 -264.163699) (xy 368.73561 -264.146284)
			(xy 368.741198 -264.141204) (xy 368.748818 -264.127742) (xy 368.750342 -264.120376) (xy 368.751772 -264.112924)
			(xy 368.750614 -264.097801) (xy 368.748056 -264.090658) (xy 368.71402 -264.005314) (xy 368.709863 -263.996047)
			(xy 368.695647 -263.981564) (xy 368.676924 -263.973734) (xy 368.666776 -263.97331) (xy 367.346738 -263.97331)
			(xy 367.336602 -263.973762) (xy 367.317911 -263.981616) (xy 367.303704 -263.99608) (xy 367.299494 -264.005314)
			(xy 367.265458 -264.090658) (xy 367.262946 -264.097813) (xy 367.261773 -264.112924) (xy 367.263172 -264.120376)
			(xy 367.264696 -264.127742) (xy 367.272316 -264.141204) (xy 367.277904 -264.146284) (xy 367.295565 -264.163702)
			(xy 367.325567 -264.2032) (xy 367.348796 -264.247026) (xy 367.364642 -264.294028) (xy 367.372689 -264.342972)
			(xy 367.373154 -264.367772) (xy 367.373154 -264.37717) (xy 367.3729 -264.380472) (xy 367.3729 -264.381234)
			(xy 367.371495 -264.40418) (xy 367.36265 -264.449291) (xy 367.34714 -264.492566) (xy 367.325314 -264.533025)
			(xy 367.297668 -264.569752) (xy 367.264825 -264.601918) (xy 367.246408 -264.615676) (xy 367.226791 -264.629254)
			(xy 367.184225 -264.650797) (xy 367.138826 -264.665457) (xy 367.0917 -264.672877) (xy 367.043992 -264.672877)
			(xy 366.996866 -264.665457) (xy 366.951467 -264.650797) (xy 366.908901 -264.629254) (xy 366.889284 -264.615676)
			(xy 366.870887 -264.601895) (xy 366.838056 -264.569724) (xy 366.810415 -264.532998) (xy 366.788589 -264.492546)
			(xy 366.773069 -264.44928) (xy 366.764205 -264.404177) (xy 366.762792 -264.381234) (xy 366.762792 -264.380472)
			(xy 366.762538 -264.37717) (xy 366.762538 -264.367772) (xy 366.763018 -264.34297) (xy 366.771034 -264.294019)
			(xy 366.786867 -264.24701) (xy 366.810099 -264.203184) (xy 366.840118 -264.163695) (xy 366.857788 -264.146284)
			(xy 366.863376 -264.141204) (xy 366.870996 -264.127742) (xy 366.87252 -264.120376) (xy 366.873951 -264.112924)
			(xy 366.872792 -264.097801) (xy 366.870234 -264.090658) (xy 366.836198 -264.005314) (xy 366.83204 -263.996049)
			(xy 366.817822 -263.981573) (xy 366.799101 -263.97375) (xy 366.788954 -263.97331) (xy 365.466884 -263.97331)
			(xy 365.456742 -263.973754) (xy 365.438037 -263.981598) (xy 365.423816 -263.996061) (xy 365.41964 -264.005314)
			(xy 365.385604 -264.090658) (xy 365.383091 -264.097813) (xy 365.381917 -264.112924) (xy 365.383318 -264.120376)
			(xy 365.384842 -264.127742) (xy 365.392462 -264.141204) (xy 365.39805 -264.146284) (xy 365.415709 -264.163703)
			(xy 365.445707 -264.203203) (xy 365.468932 -264.247029) (xy 365.484775 -264.29403) (xy 365.492821 -264.342973)
			(xy 365.4933 -264.367772) (xy 365.4933 -264.37717) (xy 365.493046 -264.380472) (xy 365.493046 -264.381234)
			(xy 365.491382 -264.407118) (xy 365.48043 -264.45781) (xy 365.46107 -264.505924) (xy 365.433861 -264.550076)
			(xy 365.399584 -264.588996) (xy 365.359225 -264.621566) (xy 365.313943 -264.64685) (xy 365.26504 -264.66412)
			(xy 365.213923 -264.67288) (xy 365.187992 -264.673334) (xy 365.164 -264.672863) (xy 365.116608 -264.665356)
			(xy 365.070974 -264.650528) (xy 365.02822 -264.628745) (xy 364.9894 -264.600541) (xy 364.95547 -264.566613)
			(xy 364.927265 -264.527795) (xy 364.905479 -264.485043) (xy 364.890648 -264.439409) (xy 364.883139 -264.392018)
			(xy 364.882684 -264.368026) (xy 364.883188 -264.343048) (xy 364.89133 -264.293761) (xy 364.907384 -264.246455)
			(xy 364.930923 -264.202393) (xy 364.961319 -264.162748) (xy 364.997761 -264.128579) (xy 365.039278 -264.100797)
			(xy 365.084764 -264.080141) (xy 365.108744 -264.073132) (xy 365.108998 -264.073132) (xy 365.116941 -264.070659)
			(xy 365.130693 -264.061314) (xy 365.135922 -264.054844) (xy 365.141002 -264.04824) (xy 365.146336 -264.032746)
			(xy 365.146336 -264.02411) (xy 365.14585 -264.014098) (xy 365.138194 -263.995597) (xy 365.124042 -263.981432)
			(xy 365.105547 -263.973759) (xy 365.095536 -263.97331) (xy 365.095028 -263.97331) (xy 365.08519 -263.972774)
			(xy 365.067029 -263.965188) (xy 365.059722 -263.958578) (xy 364.289086 -263.187942) (xy 364.282365 -263.180707)
			(xy 364.274751 -263.162502) (xy 364.274354 -263.152636) (xy 364.274354 -262.127492) (xy 364.274006 -262.118801)
			(xy 364.26816 -262.102434) (xy 364.262924 -262.095488) (xy 364.259622 -262.091678) (xy 364.123986 -261.956042)
			(xy 364.120258 -261.952517) (xy 364.111686 -261.946882) (xy 364.106968 -261.944866) (xy 364.098332 -261.94131)
			(xy 353.854004 -261.94131) (xy 353.841999 -261.942023) (xy 353.820653 -261.953026) (xy 353.81311 -261.962392)
			(xy 353.782884 -262.003794) (xy 353.764596 -262.02894) (xy 353.761219 -262.033879) (xy 353.756596 -262.044911)
			(xy 353.755452 -262.050784) (xy 353.753674 -262.062468) (xy 353.757484 -262.074406) (xy 353.765274 -262.100126)
			(xy 353.77369 -262.153202) (xy 353.774248 -262.18007) (xy 353.773768 -262.205769) (xy 353.766107 -262.256593)
			(xy 353.750958 -262.305707) (xy 353.728657 -262.352015) (xy 353.699704 -262.394482) (xy 353.664744 -262.432159)
			(xy 353.62456 -262.464205) (xy 353.580048 -262.489904) (xy 353.532203 -262.508681) (xy 353.482094 -262.520119)
			(xy 353.43084 -262.52396) (xy 353.379586 -262.520119) (xy 353.329477 -262.508681) (xy 353.281632 -262.489904)
			(xy 353.23712 -262.464205) (xy 353.196936 -262.432159) (xy 353.161976 -262.394482) (xy 353.133023 -262.352015)
			(xy 353.110722 -262.305707) (xy 353.095573 -262.256593) (xy 353.087912 -262.205769) (xy 353.087432 -262.18007)
			(xy 353.087974 -262.153201) (xy 353.096401 -262.100126) (xy 353.104196 -262.074406) (xy 353.104196 -262.074152)
			(xy 353.105869 -262.068402) (xy 353.106775 -262.056464) (xy 353.105974 -262.05053) (xy 353.104196 -262.038846)
			(xy 353.078796 -262.003794) (xy 353.04857 -261.962392) (xy 353.041004 -261.953057) (xy 353.019669 -261.94207)
			(xy 353.007676 -261.94131) (xy 350.972628 -261.94131) (xy 350.96361 -261.941665) (xy 350.946688 -261.947906)
			(xy 350.939608 -261.953502) (xy 350.93275 -261.959344) (xy 350.924114 -261.974838) (xy 350.92259 -261.983982)
			(xy 350.9181 -262.008977) (xy 350.901928 -262.057114) (xy 350.878014 -262.101911) (xy 350.847017 -262.142133)
			(xy 350.809792 -262.176673) (xy 350.767366 -262.204578) (xy 350.720907 -262.225078) (xy 350.671697 -262.237608)
			(xy 350.621092 -262.241824) (xy 350.570487 -262.237608) (xy 350.521277 -262.225078) (xy 350.474818 -262.204578)
			(xy 350.432392 -262.176673) (xy 350.395167 -262.142133) (xy 350.36417 -262.101911) (xy 350.340256 -262.057114)
			(xy 350.324084 -262.008977) (xy 350.319594 -261.983982) (xy 350.319594 -261.983728) (xy 350.317747 -261.975044)
			(xy 350.309045 -261.959583) (xy 350.302576 -261.953502) (xy 350.295718 -261.94766) (xy 350.2787 -261.94131)
			(xy 350.032574 -261.94131) (xy 350.023559 -261.941674) (xy 350.00665 -261.947929) (xy 349.999554 -261.953502)
			(xy 349.992696 -261.959344) (xy 349.98406 -261.974838) (xy 349.982536 -261.983982) (xy 349.978304 -262.007589)
			(xy 349.963456 -262.053189) (xy 349.941661 -262.095908) (xy 349.913455 -262.134694) (xy 349.879533 -262.168593)
			(xy 349.840728 -262.196772) (xy 349.797994 -262.218537) (xy 349.752383 -262.233354) (xy 349.705017 -262.240857)
			(xy 349.681038 -262.241284) (xy 349.68053 -262.241284) (xy 349.658826 -262.240884) (xy 349.615862 -262.234699)
			(xy 349.574205 -262.222493) (xy 349.554292 -262.213852) (xy 349.54845 -262.211058) (xy 349.539265 -262.208235)
			(xy 349.520075 -262.208889) (xy 349.502449 -262.216506) (xy 349.495364 -262.222996) (xy 349.375476 -262.342884)
			(xy 349.368458 -262.350689) (xy 349.360864 -262.370233) (xy 349.360744 -262.38073) (xy 349.360744 -262.382254)
			(xy 349.360744 -262.383016) (xy 349.367094 -262.459978) (xy 349.368382 -262.469967) (xy 349.377525 -262.487891)
			(xy 349.384874 -262.494776) (xy 349.388176 -262.497316) (xy 349.407662 -262.511737) (xy 349.442235 -262.545716)
			(xy 349.470994 -262.584738) (xy 349.493215 -262.62782) (xy 349.508337 -262.673876) (xy 349.51598 -262.721744)
			(xy 349.516446 -262.745982) (xy 349.845388 -262.745982) (xy 349.849348 -262.696928) (xy 349.861125 -262.649144)
			(xy 349.880416 -262.603868) (xy 349.906719 -262.562272) (xy 349.939354 -262.525435) (xy 349.977475 -262.49431)
			(xy 350.020096 -262.469703) (xy 350.066112 -262.452251) (xy 350.114331 -262.442407) (xy 350.163506 -262.440426)
			(xy 350.212361 -262.446358) (xy 350.259632 -262.46005) (xy 350.304094 -262.481148) (xy 350.344597 -262.509104)
			(xy 350.38009 -262.543196) (xy 350.409655 -262.58254) (xy 350.432526 -262.626117) (xy 350.44811 -262.672798)
			(xy 350.456005 -262.721375) (xy 350.4565 -262.745982) (xy 350.456459 -262.748014) (xy 350.78214 -262.748014)
			(xy 350.7861 -262.69896) (xy 350.797877 -262.651176) (xy 350.817168 -262.6059) (xy 350.843471 -262.564304)
			(xy 350.876106 -262.527467) (xy 350.914227 -262.496342) (xy 350.956848 -262.471735) (xy 351.002864 -262.454283)
			(xy 351.051083 -262.444439) (xy 351.100258 -262.442458) (xy 351.149113 -262.44839) (xy 351.196384 -262.462082)
			(xy 351.240846 -262.48318) (xy 351.281349 -262.511136) (xy 351.316842 -262.545228) (xy 351.346407 -262.584572)
			(xy 351.369278 -262.628149) (xy 351.384862 -262.67483) (xy 351.392757 -262.723407) (xy 351.393252 -262.748014)
			(xy 351.722194 -262.748014) (xy 351.726154 -262.69896) (xy 351.737931 -262.651176) (xy 351.757222 -262.6059)
			(xy 351.783525 -262.564304) (xy 351.81616 -262.527467) (xy 351.854281 -262.496342) (xy 351.896902 -262.471735)
			(xy 351.942918 -262.454283) (xy 351.991137 -262.444439) (xy 352.040312 -262.442458) (xy 352.089167 -262.44839)
			(xy 352.136438 -262.462082) (xy 352.1809 -262.48318) (xy 352.221403 -262.511136) (xy 352.256896 -262.545228)
			(xy 352.286461 -262.584572) (xy 352.309332 -262.628149) (xy 352.324916 -262.67483) (xy 352.332811 -262.723407)
			(xy 352.333306 -262.748014) (xy 352.332811 -262.772621) (xy 352.324916 -262.821198) (xy 352.309332 -262.867879)
			(xy 352.286461 -262.911456) (xy 352.256896 -262.9508) (xy 352.221403 -262.984892) (xy 352.1809 -263.012848)
			(xy 352.136438 -263.033946) (xy 352.089167 -263.047638) (xy 352.040312 -263.05357) (xy 351.991137 -263.051589)
			(xy 351.942918 -263.041745) (xy 351.896902 -263.024293) (xy 351.854281 -262.999686) (xy 351.81616 -262.968561)
			(xy 351.783525 -262.931724) (xy 351.757222 -262.890128) (xy 351.737931 -262.844852) (xy 351.726154 -262.797068)
			(xy 351.722194 -262.748014) (xy 351.393252 -262.748014) (xy 351.392757 -262.772621) (xy 351.384862 -262.821198)
			(xy 351.369278 -262.867879) (xy 351.346407 -262.911456) (xy 351.316842 -262.9508) (xy 351.281349 -262.984892)
			(xy 351.240846 -263.012848) (xy 351.196384 -263.033946) (xy 351.149113 -263.047638) (xy 351.100258 -263.05357)
			(xy 351.051083 -263.051589) (xy 351.002864 -263.041745) (xy 350.956848 -263.024293) (xy 350.914227 -262.999686)
			(xy 350.876106 -262.968561) (xy 350.843471 -262.931724) (xy 350.817168 -262.890128) (xy 350.797877 -262.844852)
			(xy 350.7861 -262.797068) (xy 350.78214 -262.748014) (xy 350.456459 -262.748014) (xy 350.456005 -262.770589)
			(xy 350.44811 -262.819166) (xy 350.432526 -262.865847) (xy 350.409655 -262.909424) (xy 350.38009 -262.948768)
			(xy 350.344597 -262.98286) (xy 350.304094 -263.010816) (xy 350.259632 -263.031914) (xy 350.212361 -263.045606)
			(xy 350.163506 -263.051538) (xy 350.114331 -263.049557) (xy 350.066112 -263.039713) (xy 350.020096 -263.022261)
			(xy 349.977475 -262.997654) (xy 349.939354 -262.966529) (xy 349.906719 -262.929692) (xy 349.880416 -262.888096)
			(xy 349.861125 -262.84282) (xy 349.849348 -262.795036) (xy 349.845388 -262.745982) (xy 349.516446 -262.745982)
			(xy 349.515979 -262.769947) (xy 349.508493 -262.817289) (xy 349.493702 -262.86288) (xy 349.471969 -262.9056)
			(xy 349.443828 -262.9444) (xy 349.40997 -262.978326) (xy 349.371228 -263.006545) (xy 349.328552 -263.028365)
			(xy 349.282991 -263.043248) (xy 349.259398 -263.04748) (xy 349.250996 -263.049185) (xy 349.23594 -263.057363)
			(xy 349.229934 -263.063482) (xy 349.209868 -263.085834) (xy 349.203905 -263.09306) (xy 349.197137 -263.110513)
			(xy 349.19666 -263.11987) (xy 349.19666 -263.555988) (xy 349.375234 -263.555988) (xy 349.379194 -263.506934)
			(xy 349.390971 -263.45915) (xy 349.410262 -263.413874) (xy 349.436565 -263.372278) (xy 349.4692 -263.335441)
			(xy 349.507321 -263.304316) (xy 349.549942 -263.279709) (xy 349.595958 -263.262257) (xy 349.644177 -263.252413)
			(xy 349.693352 -263.250432) (xy 349.742207 -263.256364) (xy 349.789478 -263.270056) (xy 349.83394 -263.291154)
			(xy 349.874443 -263.31911) (xy 349.909936 -263.353202) (xy 349.939501 -263.392546) (xy 349.962372 -263.436123)
			(xy 349.977956 -263.482804) (xy 349.985851 -263.531381) (xy 349.986346 -263.555988) (xy 350.315288 -263.555988)
			(xy 350.319248 -263.506934) (xy 350.331025 -263.45915) (xy 350.350316 -263.413874) (xy 350.376619 -263.372278)
			(xy 350.409254 -263.335441) (xy 350.447375 -263.304316) (xy 350.489996 -263.279709) (xy 350.536012 -263.262257)
			(xy 350.584231 -263.252413) (xy 350.633406 -263.250432) (xy 350.682261 -263.256364) (xy 350.729532 -263.270056)
			(xy 350.773994 -263.291154) (xy 350.814497 -263.31911) (xy 350.84999 -263.353202) (xy 350.879555 -263.392546)
			(xy 350.902426 -263.436123) (xy 350.91801 -263.482804) (xy 350.925905 -263.531381) (xy 350.9264 -263.555988)
			(xy 350.925905 -263.580595) (xy 350.91801 -263.629172) (xy 350.902426 -263.675853) (xy 350.879555 -263.71943)
			(xy 350.84999 -263.758774) (xy 350.814497 -263.792866) (xy 350.773994 -263.820822) (xy 350.729532 -263.84192)
			(xy 350.714376 -263.84631) (xy 359.174291 -263.84631) (xy 359.178321 -263.793812) (xy 359.190318 -263.742544)
			(xy 359.210001 -263.693709) (xy 359.236907 -263.64845) (xy 359.270407 -263.607829) (xy 359.309715 -263.572798)
			(xy 359.35391 -263.544178) (xy 359.401955 -263.522639) (xy 359.452726 -263.508687) (xy 359.505031 -263.502649)
			(xy 359.557645 -263.504666) (xy 359.609335 -263.51469) (xy 359.658888 -263.532488) (xy 359.705144 -263.557641)
			(xy 359.747018 -263.58956) (xy 359.78353 -263.627498) (xy 359.813822 -263.670564) (xy 359.837185 -263.717749)
			(xy 359.853071 -263.767948) (xy 359.861108 -263.819984) (xy 359.861612 -263.84631) (xy 359.861108 -263.872636)
			(xy 359.853071 -263.924672) (xy 359.837185 -263.974871) (xy 359.813822 -264.022056) (xy 359.78353 -264.065122)
			(xy 359.747018 -264.10306) (xy 359.705144 -264.134979) (xy 359.658888 -264.160132) (xy 359.609335 -264.17793)
			(xy 359.557645 -264.187954) (xy 359.505031 -264.189971) (xy 359.452726 -264.183933) (xy 359.401955 -264.169981)
			(xy 359.35391 -264.148442) (xy 359.309715 -264.119822) (xy 359.270407 -264.084791) (xy 359.236907 -264.04417)
			(xy 359.210001 -263.998911) (xy 359.190318 -263.950076) (xy 359.178321 -263.898808) (xy 359.174291 -263.84631)
			(xy 350.714376 -263.84631) (xy 350.682261 -263.855612) (xy 350.633406 -263.861544) (xy 350.584231 -263.859563)
			(xy 350.536012 -263.849719) (xy 350.489996 -263.832267) (xy 350.447375 -263.80766) (xy 350.409254 -263.776535)
			(xy 350.376619 -263.739698) (xy 350.350316 -263.698102) (xy 350.331025 -263.652826) (xy 350.319248 -263.605042)
			(xy 350.315288 -263.555988) (xy 349.986346 -263.555988) (xy 349.985851 -263.580595) (xy 349.977956 -263.629172)
			(xy 349.962372 -263.675853) (xy 349.939501 -263.71943) (xy 349.909936 -263.758774) (xy 349.874443 -263.792866)
			(xy 349.83394 -263.820822) (xy 349.789478 -263.84192) (xy 349.742207 -263.855612) (xy 349.693352 -263.861544)
			(xy 349.644177 -263.859563) (xy 349.595958 -263.849719) (xy 349.549942 -263.832267) (xy 349.507321 -263.80766)
			(xy 349.4692 -263.776535) (xy 349.436565 -263.739698) (xy 349.410262 -263.698102) (xy 349.390971 -263.652826)
			(xy 349.379194 -263.605042) (xy 349.375234 -263.555988) (xy 349.19666 -263.555988) (xy 349.19666 -264.365994)
			(xy 349.845388 -264.365994) (xy 349.849348 -264.31694) (xy 349.861125 -264.269156) (xy 349.880416 -264.22388)
			(xy 349.906719 -264.182284) (xy 349.939354 -264.145447) (xy 349.977475 -264.114322) (xy 350.020096 -264.089715)
			(xy 350.066112 -264.072263) (xy 350.114331 -264.062419) (xy 350.163506 -264.060438) (xy 350.212361 -264.06637)
			(xy 350.259632 -264.080062) (xy 350.304094 -264.10116) (xy 350.344597 -264.129116) (xy 350.38009 -264.163208)
			(xy 350.409655 -264.202552) (xy 350.432526 -264.246129) (xy 350.44811 -264.29281) (xy 350.456005 -264.341387)
			(xy 350.4565 -264.365994) (xy 350.456459 -264.368026) (xy 351.722194 -264.368026) (xy 351.726154 -264.318972)
			(xy 351.737931 -264.271188) (xy 351.757222 -264.225912) (xy 351.783525 -264.184316) (xy 351.81616 -264.147479)
			(xy 351.854281 -264.116354) (xy 351.896902 -264.091747) (xy 351.942918 -264.074295) (xy 351.991137 -264.064451)
			(xy 352.040312 -264.06247) (xy 352.089167 -264.068402) (xy 352.136438 -264.082094) (xy 352.1809 -264.103192)
			(xy 352.221403 -264.131148) (xy 352.256896 -264.16524) (xy 352.286461 -264.204584) (xy 352.309332 -264.248161)
			(xy 352.324916 -264.294842) (xy 352.332811 -264.343419) (xy 352.333306 -264.368026) (xy 353.602302 -264.368026)
			(xy 353.606262 -264.318972) (xy 353.618039 -264.271188) (xy 353.63733 -264.225912) (xy 353.663633 -264.184316)
			(xy 353.696268 -264.147479) (xy 353.734389 -264.116354) (xy 353.77701 -264.091747) (xy 353.823026 -264.074295)
			(xy 353.871245 -264.064451) (xy 353.92042 -264.06247) (xy 353.969275 -264.068402) (xy 354.016546 -264.082094)
			(xy 354.061008 -264.103192) (xy 354.101511 -264.131148) (xy 354.137004 -264.16524) (xy 354.166569 -264.204584)
			(xy 354.18944 -264.248161) (xy 354.205024 -264.294842) (xy 354.212919 -264.343419) (xy 354.213414 -264.368026)
			(xy 355.482156 -264.368026) (xy 355.486116 -264.318972) (xy 355.497893 -264.271188) (xy 355.517184 -264.225912)
			(xy 355.543487 -264.184316) (xy 355.576122 -264.147479) (xy 355.614243 -264.116354) (xy 355.656864 -264.091747)
			(xy 355.70288 -264.074295) (xy 355.751099 -264.064451) (xy 355.800274 -264.06247) (xy 355.849129 -264.068402)
			(xy 355.8964 -264.082094) (xy 355.940862 -264.103192) (xy 355.981365 -264.131148) (xy 356.016858 -264.16524)
			(xy 356.046423 -264.204584) (xy 356.069294 -264.248161) (xy 356.084878 -264.294842) (xy 356.092773 -264.343419)
			(xy 356.093268 -264.368026) (xy 363.00208 -264.368026) (xy 363.00604 -264.318972) (xy 363.017817 -264.271188)
			(xy 363.037108 -264.225912) (xy 363.063411 -264.184316) (xy 363.096046 -264.147479) (xy 363.134167 -264.116354)
			(xy 363.176788 -264.091747) (xy 363.222804 -264.074295) (xy 363.271023 -264.064451) (xy 363.320198 -264.06247)
			(xy 363.369053 -264.068402) (xy 363.416324 -264.082094) (xy 363.460786 -264.103192) (xy 363.501289 -264.131148)
			(xy 363.536782 -264.16524) (xy 363.566347 -264.204584) (xy 363.589218 -264.248161) (xy 363.604802 -264.294842)
			(xy 363.612697 -264.343419) (xy 363.613192 -264.368026) (xy 363.612697 -264.392633) (xy 363.604802 -264.44121)
			(xy 363.589218 -264.487891) (xy 363.566347 -264.531468) (xy 363.536782 -264.570812) (xy 363.501289 -264.604904)
			(xy 363.460786 -264.63286) (xy 363.416324 -264.653958) (xy 363.369053 -264.66765) (xy 363.320198 -264.673582)
			(xy 363.271023 -264.671601) (xy 363.222804 -264.661757) (xy 363.176788 -264.644305) (xy 363.134167 -264.619698)
			(xy 363.096046 -264.588573) (xy 363.063411 -264.551736) (xy 363.037108 -264.51014) (xy 363.017817 -264.464864)
			(xy 363.00604 -264.41708) (xy 363.00208 -264.368026) (xy 356.093268 -264.368026) (xy 356.092773 -264.392633)
			(xy 356.084878 -264.44121) (xy 356.069294 -264.487891) (xy 356.046423 -264.531468) (xy 356.016858 -264.570812)
			(xy 355.981365 -264.604904) (xy 355.940862 -264.63286) (xy 355.8964 -264.653958) (xy 355.849129 -264.66765)
			(xy 355.800274 -264.673582) (xy 355.751099 -264.671601) (xy 355.70288 -264.661757) (xy 355.656864 -264.644305)
			(xy 355.614243 -264.619698) (xy 355.576122 -264.588573) (xy 355.543487 -264.551736) (xy 355.517184 -264.51014)
			(xy 355.497893 -264.464864) (xy 355.486116 -264.41708) (xy 355.482156 -264.368026) (xy 354.213414 -264.368026)
			(xy 354.212919 -264.392633) (xy 354.205024 -264.44121) (xy 354.18944 -264.487891) (xy 354.166569 -264.531468)
			(xy 354.137004 -264.570812) (xy 354.101511 -264.604904) (xy 354.061008 -264.63286) (xy 354.016546 -264.653958)
			(xy 353.969275 -264.66765) (xy 353.92042 -264.673582) (xy 353.871245 -264.671601) (xy 353.823026 -264.661757)
			(xy 353.77701 -264.644305) (xy 353.734389 -264.619698) (xy 353.696268 -264.588573) (xy 353.663633 -264.551736)
			(xy 353.63733 -264.51014) (xy 353.618039 -264.464864) (xy 353.606262 -264.41708) (xy 353.602302 -264.368026)
			(xy 352.333306 -264.368026) (xy 352.332811 -264.392633) (xy 352.324916 -264.44121) (xy 352.309332 -264.487891)
			(xy 352.286461 -264.531468) (xy 352.256896 -264.570812) (xy 352.221403 -264.604904) (xy 352.1809 -264.63286)
			(xy 352.136438 -264.653958) (xy 352.089167 -264.66765) (xy 352.040312 -264.673582) (xy 351.991137 -264.671601)
			(xy 351.942918 -264.661757) (xy 351.896902 -264.644305) (xy 351.854281 -264.619698) (xy 351.81616 -264.588573)
			(xy 351.783525 -264.551736) (xy 351.757222 -264.51014) (xy 351.737931 -264.464864) (xy 351.726154 -264.41708)
			(xy 351.722194 -264.368026) (xy 350.456459 -264.368026) (xy 350.456005 -264.390601) (xy 350.44811 -264.439178)
			(xy 350.432526 -264.485859) (xy 350.409655 -264.529436) (xy 350.38009 -264.56878) (xy 350.344597 -264.602872)
			(xy 350.304094 -264.630828) (xy 350.259632 -264.651926) (xy 350.212361 -264.665618) (xy 350.163506 -264.67155)
			(xy 350.114331 -264.669569) (xy 350.066112 -264.659725) (xy 350.020096 -264.642273) (xy 349.977475 -264.617666)
			(xy 349.939354 -264.586541) (xy 349.906719 -264.549704) (xy 349.880416 -264.508108) (xy 349.861125 -264.462832)
			(xy 349.849348 -264.415048) (xy 349.845388 -264.365994) (xy 349.19666 -264.365994) (xy 349.19666 -264.86231)
			(xy 359.174291 -264.86231) (xy 359.178321 -264.809812) (xy 359.190318 -264.758544) (xy 359.210001 -264.709709)
			(xy 359.236907 -264.66445) (xy 359.270407 -264.623829) (xy 359.309715 -264.588798) (xy 359.35391 -264.560178)
			(xy 359.401955 -264.538639) (xy 359.452726 -264.524687) (xy 359.505031 -264.518649) (xy 359.557645 -264.520666)
			(xy 359.609335 -264.53069) (xy 359.658888 -264.548488) (xy 359.705144 -264.573641) (xy 359.747018 -264.60556)
			(xy 359.78353 -264.643498) (xy 359.813822 -264.686564) (xy 359.837185 -264.733749) (xy 359.853071 -264.783948)
			(xy 359.861108 -264.835984) (xy 359.861612 -264.86231) (xy 359.861108 -264.888636) (xy 359.853071 -264.940672)
			(xy 359.837185 -264.990871) (xy 359.813822 -265.038056) (xy 359.78353 -265.081122) (xy 359.747018 -265.11906)
			(xy 359.705144 -265.150979) (xy 359.659131 -265.176) (xy 369.109002 -265.176) (xy 369.112962 -265.126946)
			(xy 369.124739 -265.079162) (xy 369.14403 -265.033886) (xy 369.170333 -264.99229) (xy 369.202968 -264.955453)
			(xy 369.241089 -264.924328) (xy 369.28371 -264.899721) (xy 369.329726 -264.882269) (xy 369.377945 -264.872425)
			(xy 369.42712 -264.870444) (xy 369.475975 -264.876376) (xy 369.523246 -264.890068) (xy 369.567708 -264.911166)
			(xy 369.608211 -264.939122) (xy 369.643704 -264.973214) (xy 369.673269 -265.012558) (xy 369.69614 -265.056135)
			(xy 369.711724 -265.102816) (xy 369.719619 -265.151393) (xy 369.720114 -265.176) (xy 370.98911 -265.176)
			(xy 370.99307 -265.126946) (xy 371.004847 -265.079162) (xy 371.024138 -265.033886) (xy 371.050441 -264.99229)
			(xy 371.083076 -264.955453) (xy 371.121197 -264.924328) (xy 371.163818 -264.899721) (xy 371.209834 -264.882269)
			(xy 371.258053 -264.872425) (xy 371.307228 -264.870444) (xy 371.356083 -264.876376) (xy 371.403354 -264.890068)
			(xy 371.447816 -264.911166) (xy 371.488319 -264.939122) (xy 371.523812 -264.973214) (xy 371.553377 -265.012558)
			(xy 371.576248 -265.056135) (xy 371.591832 -265.102816) (xy 371.599727 -265.151393) (xy 371.600222 -265.176)
			(xy 372.868964 -265.176) (xy 372.872924 -265.126946) (xy 372.884701 -265.079162) (xy 372.903992 -265.033886)
			(xy 372.930295 -264.99229) (xy 372.96293 -264.955453) (xy 373.001051 -264.924328) (xy 373.043672 -264.899721)
			(xy 373.089688 -264.882269) (xy 373.137907 -264.872425) (xy 373.187082 -264.870444) (xy 373.235937 -264.876376)
			(xy 373.283208 -264.890068) (xy 373.32767 -264.911166) (xy 373.368173 -264.939122) (xy 373.403666 -264.973214)
			(xy 373.433231 -265.012558) (xy 373.456102 -265.056135) (xy 373.471686 -265.102816) (xy 373.479581 -265.151393)
			(xy 373.480076 -265.176) (xy 374.749072 -265.176) (xy 374.753032 -265.126946) (xy 374.764809 -265.079162)
			(xy 374.7841 -265.033886) (xy 374.810403 -264.99229) (xy 374.843038 -264.955453) (xy 374.881159 -264.924328)
			(xy 374.92378 -264.899721) (xy 374.969796 -264.882269) (xy 375.018015 -264.872425) (xy 375.06719 -264.870444)
			(xy 375.116045 -264.876376) (xy 375.163316 -264.890068) (xy 375.207778 -264.911166) (xy 375.248281 -264.939122)
			(xy 375.283774 -264.973214) (xy 375.313339 -265.012558) (xy 375.33621 -265.056135) (xy 375.351794 -265.102816)
			(xy 375.359689 -265.151393) (xy 375.360184 -265.176) (xy 375.678695 -265.176) (xy 375.68279 -265.125272)
			(xy 375.694969 -265.075858) (xy 375.714917 -265.029038) (xy 375.742118 -264.986024) (xy 375.775866 -264.94793)
			(xy 375.815288 -264.915743) (xy 375.859362 -264.890297) (xy 375.906948 -264.87225) (xy 375.956812 -264.86207)
			(xy 376.007664 -264.860021) (xy 376.058185 -264.866155) (xy 376.107069 -264.880315) (xy 376.153048 -264.902132)
			(xy 376.194932 -264.931042) (xy 376.231636 -264.966297) (xy 376.262209 -265.006983) (xy 376.28586 -265.052046)
			(xy 376.301976 -265.10032) (xy 376.31014 -265.150554) (xy 376.310652 -265.176) (xy 376.628926 -265.176)
			(xy 376.632886 -265.126946) (xy 376.644663 -265.079162) (xy 376.663954 -265.033886) (xy 376.690257 -264.99229)
			(xy 376.722892 -264.955453) (xy 376.761013 -264.924328) (xy 376.803634 -264.899721) (xy 376.84965 -264.882269)
			(xy 376.897869 -264.872425) (xy 376.947044 -264.870444) (xy 376.995899 -264.876376) (xy 377.04317 -264.890068)
			(xy 377.087632 -264.911166) (xy 377.128135 -264.939122) (xy 377.163628 -264.973214) (xy 377.193193 -265.012558)
			(xy 377.216064 -265.056135) (xy 377.231648 -265.102816) (xy 377.239543 -265.151393) (xy 377.240038 -265.176)
			(xy 377.56898 -265.176) (xy 377.57294 -265.126946) (xy 377.584717 -265.079162) (xy 377.604008 -265.033886)
			(xy 377.630311 -264.99229) (xy 377.662946 -264.955453) (xy 377.701067 -264.924328) (xy 377.743688 -264.899721)
			(xy 377.789704 -264.882269) (xy 377.837923 -264.872425) (xy 377.887098 -264.870444) (xy 377.935953 -264.876376)
			(xy 377.983224 -264.890068) (xy 378.027686 -264.911166) (xy 378.068189 -264.939122) (xy 378.103682 -264.973214)
			(xy 378.133247 -265.012558) (xy 378.156118 -265.056135) (xy 378.171702 -265.102816) (xy 378.179597 -265.151393)
			(xy 378.180092 -265.176) (xy 378.509034 -265.176) (xy 378.512994 -265.126946) (xy 378.524771 -265.079162)
			(xy 378.544062 -265.033886) (xy 378.570365 -264.99229) (xy 378.603 -264.955453) (xy 378.641121 -264.924328)
			(xy 378.683742 -264.899721) (xy 378.729758 -264.882269) (xy 378.777977 -264.872425) (xy 378.827152 -264.870444)
			(xy 378.876007 -264.876376) (xy 378.923278 -264.890068) (xy 378.96774 -264.911166) (xy 379.008243 -264.939122)
			(xy 379.043736 -264.973214) (xy 379.073301 -265.012558) (xy 379.096172 -265.056135) (xy 379.111756 -265.102816)
			(xy 379.119651 -265.151393) (xy 379.120146 -265.176) (xy 379.438657 -265.176) (xy 379.442752 -265.125272)
			(xy 379.454931 -265.075858) (xy 379.474879 -265.029038) (xy 379.50208 -264.986024) (xy 379.535828 -264.94793)
			(xy 379.57525 -264.915743) (xy 379.619324 -264.890297) (xy 379.66691 -264.87225) (xy 379.716774 -264.86207)
			(xy 379.767626 -264.860021) (xy 379.818147 -264.866155) (xy 379.867031 -264.880315) (xy 379.91301 -264.902132)
			(xy 379.954894 -264.931042) (xy 379.991598 -264.966297) (xy 380.022171 -265.006983) (xy 380.045822 -265.052046)
			(xy 380.061938 -265.10032) (xy 380.070102 -265.150554) (xy 380.070614 -265.176) (xy 380.388888 -265.176)
			(xy 380.392848 -265.126946) (xy 380.404625 -265.079162) (xy 380.423916 -265.033886) (xy 380.450219 -264.99229)
			(xy 380.482854 -264.955453) (xy 380.520975 -264.924328) (xy 380.563596 -264.899721) (xy 380.609612 -264.882269)
			(xy 380.657831 -264.872425) (xy 380.707006 -264.870444) (xy 380.755861 -264.876376) (xy 380.803132 -264.890068)
			(xy 380.847594 -264.911166) (xy 380.888097 -264.939122) (xy 380.92359 -264.973214) (xy 380.953155 -265.012558)
			(xy 380.976026 -265.056135) (xy 380.99161 -265.102816) (xy 380.999505 -265.151393) (xy 381 -265.176)
			(xy 381.328942 -265.176) (xy 381.332902 -265.126946) (xy 381.344679 -265.079162) (xy 381.36397 -265.033886)
			(xy 381.390273 -264.99229) (xy 381.422908 -264.955453) (xy 381.461029 -264.924328) (xy 381.50365 -264.899721)
			(xy 381.549666 -264.882269) (xy 381.597885 -264.872425) (xy 381.64706 -264.870444) (xy 381.695915 -264.876376)
			(xy 381.743186 -264.890068) (xy 381.787648 -264.911166) (xy 381.828151 -264.939122) (xy 381.863644 -264.973214)
			(xy 381.893209 -265.012558) (xy 381.91608 -265.056135) (xy 381.931664 -265.102816) (xy 381.939559 -265.151393)
			(xy 381.940054 -265.176) (xy 382.268996 -265.176) (xy 382.272956 -265.126946) (xy 382.284733 -265.079162)
			(xy 382.304024 -265.033886) (xy 382.330327 -264.99229) (xy 382.362962 -264.955453) (xy 382.401083 -264.924328)
			(xy 382.443704 -264.899721) (xy 382.48972 -264.882269) (xy 382.537939 -264.872425) (xy 382.587114 -264.870444)
			(xy 382.635969 -264.876376) (xy 382.68324 -264.890068) (xy 382.727702 -264.911166) (xy 382.768205 -264.939122)
			(xy 382.803698 -264.973214) (xy 382.833263 -265.012558) (xy 382.856134 -265.056135) (xy 382.871718 -265.102816)
			(xy 382.879613 -265.151393) (xy 382.880108 -265.176) (xy 383.20905 -265.176) (xy 383.21301 -265.126946)
			(xy 383.224787 -265.079162) (xy 383.244078 -265.033886) (xy 383.270381 -264.99229) (xy 383.303016 -264.955453)
			(xy 383.341137 -264.924328) (xy 383.383758 -264.899721) (xy 383.429774 -264.882269) (xy 383.477993 -264.872425)
			(xy 383.527168 -264.870444) (xy 383.576023 -264.876376) (xy 383.623294 -264.890068) (xy 383.667756 -264.911166)
			(xy 383.708259 -264.939122) (xy 383.743752 -264.973214) (xy 383.773317 -265.012558) (xy 383.796188 -265.056135)
			(xy 383.811772 -265.102816) (xy 383.819667 -265.151393) (xy 383.820162 -265.176) (xy 384.149104 -265.176)
			(xy 384.153064 -265.126946) (xy 384.164841 -265.079162) (xy 384.184132 -265.033886) (xy 384.210435 -264.99229)
			(xy 384.24307 -264.955453) (xy 384.281191 -264.924328) (xy 384.323812 -264.899721) (xy 384.369828 -264.882269)
			(xy 384.418047 -264.872425) (xy 384.467222 -264.870444) (xy 384.516077 -264.876376) (xy 384.563348 -264.890068)
			(xy 384.60781 -264.911166) (xy 384.648313 -264.939122) (xy 384.683806 -264.973214) (xy 384.713371 -265.012558)
			(xy 384.736242 -265.056135) (xy 384.751826 -265.102816) (xy 384.759721 -265.151393) (xy 384.760216 -265.176)
			(xy 384.759721 -265.200607) (xy 384.751826 -265.249184) (xy 384.736242 -265.295865) (xy 384.713371 -265.339442)
			(xy 384.683806 -265.378786) (xy 384.648313 -265.412878) (xy 384.60781 -265.440834) (xy 384.563348 -265.461932)
			(xy 384.516077 -265.475624) (xy 384.467222 -265.481556) (xy 384.418047 -265.479575) (xy 384.369828 -265.469731)
			(xy 384.323812 -265.452279) (xy 384.281191 -265.427672) (xy 384.24307 -265.396547) (xy 384.210435 -265.35971)
			(xy 384.184132 -265.318114) (xy 384.164841 -265.272838) (xy 384.153064 -265.225054) (xy 384.149104 -265.176)
			(xy 383.820162 -265.176) (xy 383.819667 -265.200607) (xy 383.811772 -265.249184) (xy 383.796188 -265.295865)
			(xy 383.773317 -265.339442) (xy 383.743752 -265.378786) (xy 383.708259 -265.412878) (xy 383.667756 -265.440834)
			(xy 383.623294 -265.461932) (xy 383.576023 -265.475624) (xy 383.527168 -265.481556) (xy 383.477993 -265.479575)
			(xy 383.429774 -265.469731) (xy 383.383758 -265.452279) (xy 383.341137 -265.427672) (xy 383.303016 -265.396547)
			(xy 383.270381 -265.35971) (xy 383.244078 -265.318114) (xy 383.224787 -265.272838) (xy 383.21301 -265.225054)
			(xy 383.20905 -265.176) (xy 382.880108 -265.176) (xy 382.879613 -265.200607) (xy 382.871718 -265.249184)
			(xy 382.856134 -265.295865) (xy 382.833263 -265.339442) (xy 382.803698 -265.378786) (xy 382.768205 -265.412878)
			(xy 382.727702 -265.440834) (xy 382.68324 -265.461932) (xy 382.635969 -265.475624) (xy 382.587114 -265.481556)
			(xy 382.537939 -265.479575) (xy 382.48972 -265.469731) (xy 382.443704 -265.452279) (xy 382.401083 -265.427672)
			(xy 382.362962 -265.396547) (xy 382.330327 -265.35971) (xy 382.304024 -265.318114) (xy 382.284733 -265.272838)
			(xy 382.272956 -265.225054) (xy 382.268996 -265.176) (xy 381.940054 -265.176) (xy 381.939559 -265.200607)
			(xy 381.931664 -265.249184) (xy 381.91608 -265.295865) (xy 381.893209 -265.339442) (xy 381.863644 -265.378786)
			(xy 381.828151 -265.412878) (xy 381.787648 -265.440834) (xy 381.743186 -265.461932) (xy 381.695915 -265.475624)
			(xy 381.64706 -265.481556) (xy 381.597885 -265.479575) (xy 381.549666 -265.469731) (xy 381.50365 -265.452279)
			(xy 381.461029 -265.427672) (xy 381.422908 -265.396547) (xy 381.390273 -265.35971) (xy 381.36397 -265.318114)
			(xy 381.344679 -265.272838) (xy 381.332902 -265.225054) (xy 381.328942 -265.176) (xy 381 -265.176)
			(xy 380.999505 -265.200607) (xy 380.99161 -265.249184) (xy 380.976026 -265.295865) (xy 380.953155 -265.339442)
			(xy 380.92359 -265.378786) (xy 380.888097 -265.412878) (xy 380.847594 -265.440834) (xy 380.803132 -265.461932)
			(xy 380.755861 -265.475624) (xy 380.707006 -265.481556) (xy 380.657831 -265.479575) (xy 380.609612 -265.469731)
			(xy 380.563596 -265.452279) (xy 380.520975 -265.427672) (xy 380.482854 -265.396547) (xy 380.450219 -265.35971)
			(xy 380.423916 -265.318114) (xy 380.404625 -265.272838) (xy 380.392848 -265.225054) (xy 380.388888 -265.176)
			(xy 380.070614 -265.176) (xy 380.070102 -265.201446) (xy 380.061938 -265.25168) (xy 380.045822 -265.299954)
			(xy 380.022171 -265.345017) (xy 379.991598 -265.385703) (xy 379.954894 -265.420958) (xy 379.91301 -265.449868)
			(xy 379.867031 -265.471685) (xy 379.818147 -265.485845) (xy 379.767626 -265.491979) (xy 379.716774 -265.48993)
			(xy 379.66691 -265.47975) (xy 379.619324 -265.461703) (xy 379.57525 -265.436257) (xy 379.535828 -265.40407)
			(xy 379.50208 -265.365976) (xy 379.474879 -265.322962) (xy 379.454931 -265.276142) (xy 379.442752 -265.226728)
			(xy 379.438657 -265.176) (xy 379.120146 -265.176) (xy 379.119651 -265.200607) (xy 379.111756 -265.249184)
			(xy 379.096172 -265.295865) (xy 379.073301 -265.339442) (xy 379.043736 -265.378786) (xy 379.008243 -265.412878)
			(xy 378.96774 -265.440834) (xy 378.923278 -265.461932) (xy 378.876007 -265.475624) (xy 378.827152 -265.481556)
			(xy 378.777977 -265.479575) (xy 378.729758 -265.469731) (xy 378.683742 -265.452279) (xy 378.641121 -265.427672)
			(xy 378.603 -265.396547) (xy 378.570365 -265.35971) (xy 378.544062 -265.318114) (xy 378.524771 -265.272838)
			(xy 378.512994 -265.225054) (xy 378.509034 -265.176) (xy 378.180092 -265.176) (xy 378.179597 -265.200607)
			(xy 378.171702 -265.249184) (xy 378.156118 -265.295865) (xy 378.133247 -265.339442) (xy 378.103682 -265.378786)
			(xy 378.068189 -265.412878) (xy 378.027686 -265.440834) (xy 377.983224 -265.461932) (xy 377.935953 -265.475624)
			(xy 377.887098 -265.481556) (xy 377.837923 -265.479575) (xy 377.789704 -265.469731) (xy 377.743688 -265.452279)
			(xy 377.701067 -265.427672) (xy 377.662946 -265.396547) (xy 377.630311 -265.35971) (xy 377.604008 -265.318114)
			(xy 377.584717 -265.272838) (xy 377.57294 -265.225054) (xy 377.56898 -265.176) (xy 377.240038 -265.176)
			(xy 377.239543 -265.200607) (xy 377.231648 -265.249184) (xy 377.216064 -265.295865) (xy 377.193193 -265.339442)
			(xy 377.163628 -265.378786) (xy 377.128135 -265.412878) (xy 377.087632 -265.440834) (xy 377.04317 -265.461932)
			(xy 376.995899 -265.475624) (xy 376.947044 -265.481556) (xy 376.897869 -265.479575) (xy 376.84965 -265.469731)
			(xy 376.803634 -265.452279) (xy 376.761013 -265.427672) (xy 376.722892 -265.396547) (xy 376.690257 -265.35971)
			(xy 376.663954 -265.318114) (xy 376.644663 -265.272838) (xy 376.632886 -265.225054) (xy 376.628926 -265.176)
			(xy 376.310652 -265.176) (xy 376.31014 -265.201446) (xy 376.301976 -265.25168) (xy 376.28586 -265.299954)
			(xy 376.262209 -265.345017) (xy 376.231636 -265.385703) (xy 376.194932 -265.420958) (xy 376.153048 -265.449868)
			(xy 376.107069 -265.471685) (xy 376.058185 -265.485845) (xy 376.007664 -265.491979) (xy 375.956812 -265.48993)
			(xy 375.906948 -265.47975) (xy 375.859362 -265.461703) (xy 375.815288 -265.436257) (xy 375.775866 -265.40407)
			(xy 375.742118 -265.365976) (xy 375.714917 -265.322962) (xy 375.694969 -265.276142) (xy 375.68279 -265.226728)
			(xy 375.678695 -265.176) (xy 375.360184 -265.176) (xy 375.359689 -265.200607) (xy 375.351794 -265.249184)
			(xy 375.33621 -265.295865) (xy 375.313339 -265.339442) (xy 375.283774 -265.378786) (xy 375.248281 -265.412878)
			(xy 375.207778 -265.440834) (xy 375.163316 -265.461932) (xy 375.116045 -265.475624) (xy 375.06719 -265.481556)
			(xy 375.018015 -265.479575) (xy 374.969796 -265.469731) (xy 374.92378 -265.452279) (xy 374.881159 -265.427672)
			(xy 374.843038 -265.396547) (xy 374.810403 -265.35971) (xy 374.7841 -265.318114) (xy 374.764809 -265.272838)
			(xy 374.753032 -265.225054) (xy 374.749072 -265.176) (xy 373.480076 -265.176) (xy 373.479581 -265.200607)
			(xy 373.471686 -265.249184) (xy 373.456102 -265.295865) (xy 373.433231 -265.339442) (xy 373.403666 -265.378786)
			(xy 373.368173 -265.412878) (xy 373.32767 -265.440834) (xy 373.283208 -265.461932) (xy 373.235937 -265.475624)
			(xy 373.187082 -265.481556) (xy 373.137907 -265.479575) (xy 373.089688 -265.469731) (xy 373.043672 -265.452279)
			(xy 373.001051 -265.427672) (xy 372.96293 -265.396547) (xy 372.930295 -265.35971) (xy 372.903992 -265.318114)
			(xy 372.884701 -265.272838) (xy 372.872924 -265.225054) (xy 372.868964 -265.176) (xy 371.600222 -265.176)
			(xy 371.599727 -265.200607) (xy 371.591832 -265.249184) (xy 371.576248 -265.295865) (xy 371.553377 -265.339442)
			(xy 371.523812 -265.378786) (xy 371.488319 -265.412878) (xy 371.447816 -265.440834) (xy 371.403354 -265.461932)
			(xy 371.356083 -265.475624) (xy 371.307228 -265.481556) (xy 371.258053 -265.479575) (xy 371.209834 -265.469731)
			(xy 371.163818 -265.452279) (xy 371.121197 -265.427672) (xy 371.083076 -265.396547) (xy 371.050441 -265.35971)
			(xy 371.024138 -265.318114) (xy 371.004847 -265.272838) (xy 370.99307 -265.225054) (xy 370.98911 -265.176)
			(xy 369.720114 -265.176) (xy 369.719619 -265.200607) (xy 369.711724 -265.249184) (xy 369.69614 -265.295865)
			(xy 369.673269 -265.339442) (xy 369.643704 -265.378786) (xy 369.608211 -265.412878) (xy 369.567708 -265.440834)
			(xy 369.523246 -265.461932) (xy 369.475975 -265.475624) (xy 369.42712 -265.481556) (xy 369.377945 -265.479575)
			(xy 369.329726 -265.469731) (xy 369.28371 -265.452279) (xy 369.241089 -265.427672) (xy 369.202968 -265.396547)
			(xy 369.170333 -265.35971) (xy 369.14403 -265.318114) (xy 369.124739 -265.272838) (xy 369.112962 -265.225054)
			(xy 369.109002 -265.176) (xy 359.659131 -265.176) (xy 359.658888 -265.176132) (xy 359.609335 -265.19393)
			(xy 359.557645 -265.203954) (xy 359.505031 -265.205971) (xy 359.452726 -265.199933) (xy 359.401955 -265.185981)
			(xy 359.35391 -265.164442) (xy 359.309715 -265.135822) (xy 359.270407 -265.100791) (xy 359.236907 -265.06017)
			(xy 359.210001 -265.014911) (xy 359.190318 -264.966076) (xy 359.178321 -264.914808) (xy 359.174291 -264.86231)
			(xy 349.19666 -264.86231) (xy 349.19666 -265.176) (xy 349.375234 -265.176) (xy 349.379194 -265.126946)
			(xy 349.390971 -265.079162) (xy 349.410262 -265.033886) (xy 349.436565 -264.99229) (xy 349.4692 -264.955453)
			(xy 349.507321 -264.924328) (xy 349.549942 -264.899721) (xy 349.595958 -264.882269) (xy 349.644177 -264.872425)
			(xy 349.693352 -264.870444) (xy 349.742207 -264.876376) (xy 349.789478 -264.890068) (xy 349.83394 -264.911166)
			(xy 349.874443 -264.939122) (xy 349.909936 -264.973214) (xy 349.939501 -265.012558) (xy 349.962372 -265.056135)
			(xy 349.977956 -265.102816) (xy 349.985851 -265.151393) (xy 349.986346 -265.176) (xy 349.985851 -265.200607)
			(xy 349.977956 -265.249184) (xy 349.962372 -265.295865) (xy 349.939501 -265.339442) (xy 349.909936 -265.378786)
			(xy 349.874443 -265.412878) (xy 349.83394 -265.440834) (xy 349.789478 -265.461932) (xy 349.742207 -265.475624)
			(xy 349.693352 -265.481556) (xy 349.644177 -265.479575) (xy 349.595958 -265.469731) (xy 349.549942 -265.452279)
			(xy 349.507321 -265.427672) (xy 349.4692 -265.396547) (xy 349.436565 -265.35971) (xy 349.410262 -265.318114)
			(xy 349.390971 -265.272838) (xy 349.379194 -265.225054) (xy 349.375234 -265.176) (xy 349.19666 -265.176)
			(xy 349.19666 -266.038838) (xy 349.197422 -266.04722) (xy 349.19894 -266.054823) (xy 349.205933 -266.068651)
			(xy 349.211138 -266.074398) (xy 349.453454 -266.316714) (xy 349.457435 -266.320812) (xy 349.463596 -266.330431)
			(xy 349.465646 -266.335764) (xy 349.468548 -266.343164) (xy 349.478115 -266.355845) (xy 349.484442 -266.360656)
			(xy 349.490538 -266.364974) (xy 349.50527 -266.3698) (xy 349.858076 -266.3698) (xy 349.868318 -266.369327)
			(xy 349.887175 -266.361323) (xy 349.894652 -266.354306) (xy 349.897782 -266.350852) (xy 349.902894 -266.34306)
			(xy 349.904812 -266.338812) (xy 349.933006 -266.272772) (xy 349.941388 -266.253214) (xy 349.944109 -266.246183)
			(xy 349.945787 -266.231209) (xy 349.94469 -266.22375) (xy 349.943166 -266.216384) (xy 349.936562 -266.20343)
			(xy 349.931228 -266.197842) (xy 349.915314 -266.180656) (xy 349.888371 -266.142344) (xy 349.867591 -266.100368)
			(xy 349.853461 -266.055713) (xy 349.846312 -266.009425) (xy 349.845884 -265.986006) (xy 349.846406 -265.960751)
			(xy 349.854719 -265.910929) (xy 349.87112 -265.863155) (xy 349.895161 -265.818732) (xy 349.926185 -265.778872)
			(xy 349.963347 -265.744662) (xy 350.005633 -265.717036) (xy 350.051889 -265.696746) (xy 350.100854 -265.684346)
			(xy 350.151192 -265.680175) (xy 350.20153 -265.684346) (xy 350.250495 -265.696746) (xy 350.296751 -265.717036)
			(xy 350.339037 -265.744662) (xy 350.376199 -265.778872) (xy 350.407223 -265.818732) (xy 350.431264 -265.863155)
			(xy 350.447665 -265.910929) (xy 350.455978 -265.960751) (xy 350.4565 -265.986006) (xy 350.456052 -266.009424)
			(xy 350.448905 -266.05571) (xy 350.434778 -266.100365) (xy 350.414004 -266.142341) (xy 350.387069 -266.180655)
			(xy 350.371156 -266.197842) (xy 350.370902 -266.198096) (xy 350.366051 -266.203588) (xy 350.359354 -266.216613)
			(xy 350.357694 -266.22375) (xy 350.356424 -266.23137) (xy 350.357948 -266.246102) (xy 350.369378 -266.272772)
			(xy 350.397572 -266.338812) (xy 350.39945 -266.343082) (xy 350.404561 -266.350885) (xy 350.407732 -266.354306)
			(xy 350.415181 -266.361364) (xy 350.434056 -266.36937) (xy 350.444308 -266.3698) (xy 351.73793 -266.3698)
			(xy 351.748176 -266.369335) (xy 351.767045 -266.361344) (xy 351.774506 -266.354306) (xy 351.777638 -266.350854)
			(xy 351.782754 -266.343063) (xy 351.784666 -266.338812) (xy 351.81286 -266.272772) (xy 351.821242 -266.253214)
			(xy 351.823961 -266.246183) (xy 351.825636 -266.231209) (xy 351.824544 -266.22375) (xy 351.82302 -266.216384)
			(xy 351.816416 -266.20343) (xy 351.811082 -266.197842) (xy 351.79517 -266.180655) (xy 351.768231 -266.142341)
			(xy 351.747454 -266.100366) (xy 351.733326 -266.055711) (xy 351.726178 -266.009424) (xy 351.725738 -265.986006)
			(xy 351.72626 -265.960751) (xy 351.734573 -265.910929) (xy 351.750974 -265.863155) (xy 351.775015 -265.818732)
			(xy 351.806039 -265.778872) (xy 351.843201 -265.744662) (xy 351.885487 -265.717036) (xy 351.931743 -265.696746)
			(xy 351.980708 -265.684346) (xy 352.031046 -265.680175) (xy 352.081384 -265.684346) (xy 352.130349 -265.696746)
			(xy 352.176605 -265.717036) (xy 352.218891 -265.744662) (xy 352.256053 -265.778872) (xy 352.287077 -265.818732)
			(xy 352.311118 -265.863155) (xy 352.327519 -265.910929) (xy 352.335832 -265.960751) (xy 352.336354 -265.986006)
			(xy 352.335906 -266.009423) (xy 352.328758 -266.055709) (xy 352.31463 -266.100362) (xy 352.293853 -266.142336)
			(xy 352.266915 -266.180648) (xy 352.25101 -266.197842) (xy 352.250756 -266.198096) (xy 352.245909 -266.20359)
			(xy 352.239217 -266.216615) (xy 352.237548 -266.22375) (xy 352.236278 -266.23137) (xy 352.237802 -266.246102)
			(xy 352.249232 -266.272772) (xy 352.277426 -266.338812) (xy 352.279306 -266.343081) (xy 352.284421 -266.35088)
			(xy 352.287586 -266.354306) (xy 352.295038 -266.361356) (xy 352.313913 -266.369341) (xy 352.324162 -266.3698)
			(xy 353.618038 -266.3698) (xy 353.628283 -266.369334) (xy 353.647151 -266.36134) (xy 353.654614 -266.354306)
			(xy 353.657746 -266.350854) (xy 353.662861 -266.343062) (xy 353.664774 -266.338812) (xy 353.692968 -266.272772)
			(xy 353.70135 -266.253214) (xy 353.704069 -266.246183) (xy 353.705744 -266.231209) (xy 353.704652 -266.22375)
			(xy 353.703128 -266.216384) (xy 353.696524 -266.20343) (xy 353.69119 -266.197842) (xy 353.675277 -266.180655)
			(xy 353.648338 -266.142342) (xy 353.627561 -266.100366) (xy 353.613432 -266.055712) (xy 353.606284 -266.009424)
			(xy 353.605846 -265.986006) (xy 353.606368 -265.960751) (xy 353.614681 -265.910929) (xy 353.631082 -265.863155)
			(xy 353.655123 -265.818732) (xy 353.686147 -265.778872) (xy 353.723309 -265.744662) (xy 353.765595 -265.717036)
			(xy 353.811851 -265.696746) (xy 353.860816 -265.684346) (xy 353.911154 -265.680175) (xy 353.961492 -265.684346)
			(xy 354.010457 -265.696746) (xy 354.056713 -265.717036) (xy 354.098999 -265.744662) (xy 354.136161 -265.778872)
			(xy 354.167185 -265.818732) (xy 354.191226 -265.863155) (xy 354.207627 -265.910929) (xy 354.21594 -265.960751)
			(xy 354.216462 -265.986006) (xy 354.216014 -266.009423) (xy 354.208866 -266.05571) (xy 354.194738 -266.100363)
			(xy 354.173962 -266.142337) (xy 354.147024 -266.18065) (xy 354.131118 -266.197842) (xy 354.130864 -266.198096)
			(xy 354.126016 -266.20359) (xy 354.119324 -266.216615) (xy 354.117656 -266.22375) (xy 354.116386 -266.23137)
			(xy 354.11791 -266.246102) (xy 354.12934 -266.272772) (xy 354.157534 -266.338812) (xy 354.159414 -266.343081)
			(xy 354.164529 -266.350879) (xy 354.167694 -266.354306) (xy 354.175147 -266.361354) (xy 354.194022 -266.369337)
			(xy 354.20427 -266.3698) (xy 355.497892 -266.3698) (xy 355.508133 -266.369324) (xy 355.526985 -266.361316)
			(xy 355.534468 -266.354306) (xy 355.537597 -266.350852) (xy 355.542707 -266.343059) (xy 355.544628 -266.338812)
			(xy 355.572822 -266.272772) (xy 355.581204 -266.253214) (xy 355.583924 -266.246183) (xy 355.585601 -266.231209)
			(xy 355.584506 -266.22375) (xy 355.582982 -266.216384) (xy 355.576378 -266.20343) (xy 355.571044 -266.197842)
			(xy 355.555129 -266.180656) (xy 355.528185 -266.142344) (xy 355.507404 -266.100369) (xy 355.493273 -266.055714)
			(xy 355.486123 -266.009425) (xy 355.4857 -265.986006) (xy 355.486222 -265.960751) (xy 355.494535 -265.910929)
			(xy 355.510936 -265.863155) (xy 355.534977 -265.818732) (xy 355.566001 -265.778872) (xy 355.603163 -265.744662)
			(xy 355.645449 -265.717036) (xy 355.691705 -265.696746) (xy 355.74067 -265.684346) (xy 355.791008 -265.680175)
			(xy 355.841346 -265.684346) (xy 355.890311 -265.696746) (xy 355.936567 -265.717036) (xy 355.978853 -265.744662)
			(xy 356.016015 -265.778872) (xy 356.047039 -265.818732) (xy 356.07108 -265.863155) (xy 356.087481 -265.910929)
			(xy 356.095794 -265.960751) (xy 356.096316 -265.986006) (xy 356.095868 -266.009424) (xy 356.088721 -266.055711)
			(xy 356.074595 -266.100366) (xy 356.053822 -266.142342) (xy 356.026887 -266.180658) (xy 356.010972 -266.197842)
			(xy 356.010718 -266.198096) (xy 356.005866 -266.203587) (xy 355.999166 -266.216612) (xy 355.99751 -266.22375)
			(xy 355.99624 -266.23137) (xy 355.997764 -266.246102) (xy 356.009194 -266.272772) (xy 356.037388 -266.338812)
			(xy 356.039266 -266.343082) (xy 356.044378 -266.350883) (xy 356.047548 -266.354306) (xy 356.054998 -266.361362)
			(xy 356.073873 -266.369362) (xy 356.084124 -266.3698) (xy 357.378 -266.3698) (xy 357.388248 -266.369341)
			(xy 357.407126 -266.361357) (xy 357.414576 -266.354306) (xy 357.417705 -266.350852) (xy 357.422814 -266.343058)
			(xy 357.424736 -266.338812) (xy 357.45293 -266.272772) (xy 357.461312 -266.253214) (xy 357.464032 -266.246183)
			(xy 357.465709 -266.231209) (xy 357.464614 -266.22375) (xy 357.46309 -266.216384) (xy 357.456486 -266.20343)
			(xy 357.451152 -266.197842) (xy 357.435237 -266.180656) (xy 357.408292 -266.142345) (xy 357.38751 -266.100369)
			(xy 357.373379 -266.055714) (xy 357.366229 -266.009425) (xy 357.365808 -265.986006) (xy 357.36633 -265.960751)
			(xy 357.374643 -265.910929) (xy 357.391044 -265.863155) (xy 357.415085 -265.818732) (xy 357.446109 -265.778872)
			(xy 357.483271 -265.744662) (xy 357.525557 -265.717036) (xy 357.571813 -265.696746) (xy 357.620778 -265.684346)
			(xy 357.671116 -265.680175) (xy 357.721454 -265.684346) (xy 357.770419 -265.696746) (xy 357.816675 -265.717036)
			(xy 357.858961 -265.744662) (xy 357.896123 -265.778872) (xy 357.927147 -265.818732) (xy 357.951188 -265.863155)
			(xy 357.967589 -265.910929) (xy 357.975902 -265.960751) (xy 357.976424 -265.986006) (xy 361.118924 -265.986006)
			(xy 361.122884 -265.936952) (xy 361.134661 -265.889168) (xy 361.153952 -265.843892) (xy 361.180255 -265.802296)
			(xy 361.21289 -265.765459) (xy 361.251011 -265.734334) (xy 361.293632 -265.709727) (xy 361.339648 -265.692275)
			(xy 361.387867 -265.682431) (xy 361.437042 -265.68045) (xy 361.485897 -265.686382) (xy 361.533168 -265.700074)
			(xy 361.57763 -265.721172) (xy 361.618133 -265.749128) (xy 361.653626 -265.78322) (xy 361.683191 -265.822564)
			(xy 361.706062 -265.866141) (xy 361.721646 -265.912822) (xy 361.729541 -265.961399) (xy 361.730036 -265.986006)
			(xy 362.999032 -265.986006) (xy 363.002992 -265.936952) (xy 363.014769 -265.889168) (xy 363.03406 -265.843892)
			(xy 363.060363 -265.802296) (xy 363.092998 -265.765459) (xy 363.131119 -265.734334) (xy 363.17374 -265.709727)
			(xy 363.219756 -265.692275) (xy 363.267975 -265.682431) (xy 363.31715 -265.68045) (xy 363.366005 -265.686382)
			(xy 363.413276 -265.700074) (xy 363.457738 -265.721172) (xy 363.498241 -265.749128) (xy 363.533734 -265.78322)
			(xy 363.563299 -265.822564) (xy 363.58617 -265.866141) (xy 363.601754 -265.912822) (xy 363.609649 -265.961399)
			(xy 363.610144 -265.986006) (xy 364.878886 -265.986006) (xy 364.882846 -265.936952) (xy 364.894623 -265.889168)
			(xy 364.913914 -265.843892) (xy 364.940217 -265.802296) (xy 364.972852 -265.765459) (xy 365.010973 -265.734334)
			(xy 365.053594 -265.709727) (xy 365.09961 -265.692275) (xy 365.147829 -265.682431) (xy 365.197004 -265.68045)
			(xy 365.245859 -265.686382) (xy 365.29313 -265.700074) (xy 365.337592 -265.721172) (xy 365.378095 -265.749128)
			(xy 365.413588 -265.78322) (xy 365.443153 -265.822564) (xy 365.466024 -265.866141) (xy 365.481608 -265.912822)
			(xy 365.489503 -265.961399) (xy 365.489998 -265.986006) (xy 366.758994 -265.986006) (xy 366.762954 -265.936952)
			(xy 366.774731 -265.889168) (xy 366.794022 -265.843892) (xy 366.820325 -265.802296) (xy 366.85296 -265.765459)
			(xy 366.891081 -265.734334) (xy 366.933702 -265.709727) (xy 366.979718 -265.692275) (xy 367.027937 -265.682431)
			(xy 367.077112 -265.68045) (xy 367.125967 -265.686382) (xy 367.173238 -265.700074) (xy 367.2177 -265.721172)
			(xy 367.258203 -265.749128) (xy 367.293696 -265.78322) (xy 367.323261 -265.822564) (xy 367.346132 -265.866141)
			(xy 367.361716 -265.912822) (xy 367.369611 -265.961399) (xy 367.370106 -265.986006) (xy 368.639102 -265.986006)
			(xy 368.643062 -265.936952) (xy 368.654839 -265.889168) (xy 368.67413 -265.843892) (xy 368.700433 -265.802296)
			(xy 368.733068 -265.765459) (xy 368.771189 -265.734334) (xy 368.81381 -265.709727) (xy 368.859826 -265.692275)
			(xy 368.908045 -265.682431) (xy 368.95722 -265.68045) (xy 369.006075 -265.686382) (xy 369.053346 -265.700074)
			(xy 369.097808 -265.721172) (xy 369.138311 -265.749128) (xy 369.173804 -265.78322) (xy 369.203369 -265.822564)
			(xy 369.22624 -265.866141) (xy 369.241824 -265.912822) (xy 369.249719 -265.961399) (xy 369.250214 -265.986006)
			(xy 370.518956 -265.986006) (xy 370.522916 -265.936952) (xy 370.534693 -265.889168) (xy 370.553984 -265.843892)
			(xy 370.580287 -265.802296) (xy 370.612922 -265.765459) (xy 370.651043 -265.734334) (xy 370.693664 -265.709727)
			(xy 370.73968 -265.692275) (xy 370.787899 -265.682431) (xy 370.837074 -265.68045) (xy 370.885929 -265.686382)
			(xy 370.9332 -265.700074) (xy 370.977662 -265.721172) (xy 371.018165 -265.749128) (xy 371.053658 -265.78322)
			(xy 371.083223 -265.822564) (xy 371.106094 -265.866141) (xy 371.121678 -265.912822) (xy 371.129573 -265.961399)
			(xy 371.130068 -265.986006) (xy 372.399064 -265.986006) (xy 372.403024 -265.936952) (xy 372.414801 -265.889168)
			(xy 372.434092 -265.843892) (xy 372.460395 -265.802296) (xy 372.49303 -265.765459) (xy 372.531151 -265.734334)
			(xy 372.573772 -265.709727) (xy 372.619788 -265.692275) (xy 372.668007 -265.682431) (xy 372.717182 -265.68045)
			(xy 372.766037 -265.686382) (xy 372.813308 -265.700074) (xy 372.85777 -265.721172) (xy 372.898273 -265.749128)
			(xy 372.933766 -265.78322) (xy 372.963331 -265.822564) (xy 372.986202 -265.866141) (xy 373.001786 -265.912822)
			(xy 373.009681 -265.961399) (xy 373.010176 -265.986006) (xy 374.278918 -265.986006) (xy 374.282878 -265.936952)
			(xy 374.294655 -265.889168) (xy 374.313946 -265.843892) (xy 374.340249 -265.802296) (xy 374.372884 -265.765459)
			(xy 374.411005 -265.734334) (xy 374.453626 -265.709727) (xy 374.499642 -265.692275) (xy 374.547861 -265.682431)
			(xy 374.597036 -265.68045) (xy 374.645891 -265.686382) (xy 374.693162 -265.700074) (xy 374.737624 -265.721172)
			(xy 374.778127 -265.749128) (xy 374.81362 -265.78322) (xy 374.843185 -265.822564) (xy 374.866056 -265.866141)
			(xy 374.88164 -265.912822) (xy 374.889535 -265.961399) (xy 374.89003 -265.986006) (xy 376.148595 -265.986006)
			(xy 376.15269 -265.935278) (xy 376.164869 -265.885864) (xy 376.184817 -265.839044) (xy 376.212018 -265.79603)
			(xy 376.245766 -265.757936) (xy 376.285188 -265.725749) (xy 376.329262 -265.700303) (xy 376.376848 -265.682256)
			(xy 376.426712 -265.672076) (xy 376.477564 -265.670027) (xy 376.528085 -265.676161) (xy 376.576969 -265.690321)
			(xy 376.622948 -265.712138) (xy 376.664832 -265.741048) (xy 376.701536 -265.776303) (xy 376.732109 -265.816989)
			(xy 376.75576 -265.862052) (xy 376.771876 -265.910326) (xy 376.78004 -265.96056) (xy 376.780552 -265.986006)
			(xy 377.09908 -265.986006) (xy 377.10304 -265.936952) (xy 377.114817 -265.889168) (xy 377.134108 -265.843892)
			(xy 377.160411 -265.802296) (xy 377.193046 -265.765459) (xy 377.231167 -265.734334) (xy 377.273788 -265.709727)
			(xy 377.319804 -265.692275) (xy 377.368023 -265.682431) (xy 377.417198 -265.68045) (xy 377.466053 -265.686382)
			(xy 377.513324 -265.700074) (xy 377.557786 -265.721172) (xy 377.598289 -265.749128) (xy 377.633782 -265.78322)
			(xy 377.663347 -265.822564) (xy 377.686218 -265.866141) (xy 377.701802 -265.912822) (xy 377.709697 -265.961399)
			(xy 377.710192 -265.986006) (xy 378.968503 -265.986006) (xy 378.972598 -265.935278) (xy 378.984777 -265.885864)
			(xy 379.004725 -265.839044) (xy 379.031926 -265.79603) (xy 379.065674 -265.757936) (xy 379.105096 -265.725749)
			(xy 379.14917 -265.700303) (xy 379.196756 -265.682256) (xy 379.24662 -265.672076) (xy 379.297472 -265.670027)
			(xy 379.347993 -265.676161) (xy 379.396877 -265.690321) (xy 379.442856 -265.712138) (xy 379.48474 -265.741048)
			(xy 379.521444 -265.776303) (xy 379.552017 -265.816989) (xy 379.575668 -265.862052) (xy 379.591784 -265.910326)
			(xy 379.599948 -265.96056) (xy 379.60046 -265.986006) (xy 379.918988 -265.986006) (xy 379.922948 -265.936952)
			(xy 379.934725 -265.889168) (xy 379.954016 -265.843892) (xy 379.980319 -265.802296) (xy 380.012954 -265.765459)
			(xy 380.051075 -265.734334) (xy 380.093696 -265.709727) (xy 380.139712 -265.692275) (xy 380.187931 -265.682431)
			(xy 380.237106 -265.68045) (xy 380.285961 -265.686382) (xy 380.333232 -265.700074) (xy 380.377694 -265.721172)
			(xy 380.418197 -265.749128) (xy 380.45369 -265.78322) (xy 380.483255 -265.822564) (xy 380.506126 -265.866141)
			(xy 380.52171 -265.912822) (xy 380.529605 -265.961399) (xy 380.5301 -265.986006) (xy 380.859042 -265.986006)
			(xy 380.863002 -265.936952) (xy 380.874779 -265.889168) (xy 380.89407 -265.843892) (xy 380.920373 -265.802296)
			(xy 380.953008 -265.765459) (xy 380.991129 -265.734334) (xy 381.03375 -265.709727) (xy 381.079766 -265.692275)
			(xy 381.127985 -265.682431) (xy 381.17716 -265.68045) (xy 381.226015 -265.686382) (xy 381.273286 -265.700074)
			(xy 381.317748 -265.721172) (xy 381.358251 -265.749128) (xy 381.393744 -265.78322) (xy 381.423309 -265.822564)
			(xy 381.44618 -265.866141) (xy 381.461764 -265.912822) (xy 381.469659 -265.961399) (xy 381.470154 -265.986006)
			(xy 381.799096 -265.986006) (xy 381.803056 -265.936952) (xy 381.814833 -265.889168) (xy 381.834124 -265.843892)
			(xy 381.860427 -265.802296) (xy 381.893062 -265.765459) (xy 381.931183 -265.734334) (xy 381.973804 -265.709727)
			(xy 382.01982 -265.692275) (xy 382.068039 -265.682431) (xy 382.117214 -265.68045) (xy 382.166069 -265.686382)
			(xy 382.21334 -265.700074) (xy 382.257802 -265.721172) (xy 382.298305 -265.749128) (xy 382.333798 -265.78322)
			(xy 382.363363 -265.822564) (xy 382.386234 -265.866141) (xy 382.401818 -265.912822) (xy 382.409713 -265.961399)
			(xy 382.410208 -265.986006) (xy 382.738896 -265.986006) (xy 382.742856 -265.936952) (xy 382.754633 -265.889168)
			(xy 382.773924 -265.843892) (xy 382.800227 -265.802296) (xy 382.832862 -265.765459) (xy 382.870983 -265.734334)
			(xy 382.913604 -265.709727) (xy 382.95962 -265.692275) (xy 383.007839 -265.682431) (xy 383.057014 -265.68045)
			(xy 383.105869 -265.686382) (xy 383.15314 -265.700074) (xy 383.197602 -265.721172) (xy 383.238105 -265.749128)
			(xy 383.273598 -265.78322) (xy 383.303163 -265.822564) (xy 383.326034 -265.866141) (xy 383.341618 -265.912822)
			(xy 383.349513 -265.961399) (xy 383.350008 -265.986006) (xy 383.67895 -265.986006) (xy 383.68291 -265.936952)
			(xy 383.694687 -265.889168) (xy 383.713978 -265.843892) (xy 383.740281 -265.802296) (xy 383.772916 -265.765459)
			(xy 383.811037 -265.734334) (xy 383.853658 -265.709727) (xy 383.899674 -265.692275) (xy 383.947893 -265.682431)
			(xy 383.997068 -265.68045) (xy 384.045923 -265.686382) (xy 384.093194 -265.700074) (xy 384.137656 -265.721172)
			(xy 384.178159 -265.749128) (xy 384.213652 -265.78322) (xy 384.243217 -265.822564) (xy 384.266088 -265.866141)
			(xy 384.281672 -265.912822) (xy 384.289567 -265.961399) (xy 384.290062 -265.986006) (xy 384.289567 -266.010613)
			(xy 384.281672 -266.05919) (xy 384.266088 -266.105871) (xy 384.243217 -266.149448) (xy 384.213652 -266.188792)
			(xy 384.178159 -266.222884) (xy 384.137656 -266.25084) (xy 384.093194 -266.271938) (xy 384.045923 -266.28563)
			(xy 383.997068 -266.291562) (xy 383.947893 -266.289581) (xy 383.899674 -266.279737) (xy 383.853658 -266.262285)
			(xy 383.811037 -266.237678) (xy 383.772916 -266.206553) (xy 383.740281 -266.169716) (xy 383.713978 -266.12812)
			(xy 383.694687 -266.082844) (xy 383.68291 -266.03506) (xy 383.67895 -265.986006) (xy 383.350008 -265.986006)
			(xy 383.349513 -266.010613) (xy 383.341618 -266.05919) (xy 383.326034 -266.105871) (xy 383.303163 -266.149448)
			(xy 383.273598 -266.188792) (xy 383.238105 -266.222884) (xy 383.197602 -266.25084) (xy 383.15314 -266.271938)
			(xy 383.105869 -266.28563) (xy 383.057014 -266.291562) (xy 383.007839 -266.289581) (xy 382.95962 -266.279737)
			(xy 382.913604 -266.262285) (xy 382.870983 -266.237678) (xy 382.832862 -266.206553) (xy 382.800227 -266.169716)
			(xy 382.773924 -266.12812) (xy 382.754633 -266.082844) (xy 382.742856 -266.03506) (xy 382.738896 -265.986006)
			(xy 382.410208 -265.986006) (xy 382.409713 -266.010613) (xy 382.401818 -266.05919) (xy 382.386234 -266.105871)
			(xy 382.363363 -266.149448) (xy 382.333798 -266.188792) (xy 382.298305 -266.222884) (xy 382.257802 -266.25084)
			(xy 382.21334 -266.271938) (xy 382.166069 -266.28563) (xy 382.117214 -266.291562) (xy 382.068039 -266.289581)
			(xy 382.01982 -266.279737) (xy 381.973804 -266.262285) (xy 381.931183 -266.237678) (xy 381.893062 -266.206553)
			(xy 381.860427 -266.169716) (xy 381.834124 -266.12812) (xy 381.814833 -266.082844) (xy 381.803056 -266.03506)
			(xy 381.799096 -265.986006) (xy 381.470154 -265.986006) (xy 381.469659 -266.010613) (xy 381.461764 -266.05919)
			(xy 381.44618 -266.105871) (xy 381.423309 -266.149448) (xy 381.393744 -266.188792) (xy 381.358251 -266.222884)
			(xy 381.317748 -266.25084) (xy 381.273286 -266.271938) (xy 381.226015 -266.28563) (xy 381.17716 -266.291562)
			(xy 381.127985 -266.289581) (xy 381.079766 -266.279737) (xy 381.03375 -266.262285) (xy 380.991129 -266.237678)
			(xy 380.953008 -266.206553) (xy 380.920373 -266.169716) (xy 380.89407 -266.12812) (xy 380.874779 -266.082844)
			(xy 380.863002 -266.03506) (xy 380.859042 -265.986006) (xy 380.5301 -265.986006) (xy 380.529605 -266.010613)
			(xy 380.52171 -266.05919) (xy 380.506126 -266.105871) (xy 380.483255 -266.149448) (xy 380.45369 -266.188792)
			(xy 380.418197 -266.222884) (xy 380.377694 -266.25084) (xy 380.333232 -266.271938) (xy 380.285961 -266.28563)
			(xy 380.237106 -266.291562) (xy 380.187931 -266.289581) (xy 380.139712 -266.279737) (xy 380.093696 -266.262285)
			(xy 380.051075 -266.237678) (xy 380.012954 -266.206553) (xy 379.980319 -266.169716) (xy 379.954016 -266.12812)
			(xy 379.934725 -266.082844) (xy 379.922948 -266.03506) (xy 379.918988 -265.986006) (xy 379.60046 -265.986006)
			(xy 379.599948 -266.011452) (xy 379.591784 -266.061686) (xy 379.575668 -266.10996) (xy 379.552017 -266.155023)
			(xy 379.521444 -266.195709) (xy 379.48474 -266.230964) (xy 379.442856 -266.259874) (xy 379.396877 -266.281691)
			(xy 379.347993 -266.295851) (xy 379.297472 -266.301985) (xy 379.24662 -266.299936) (xy 379.196756 -266.289756)
			(xy 379.14917 -266.271709) (xy 379.105096 -266.246263) (xy 379.065674 -266.214076) (xy 379.031926 -266.175982)
			(xy 379.004725 -266.132968) (xy 378.984777 -266.086148) (xy 378.972598 -266.036734) (xy 378.968503 -265.986006)
			(xy 377.710192 -265.986006) (xy 377.709697 -266.010613) (xy 377.701802 -266.05919) (xy 377.686218 -266.105871)
			(xy 377.663347 -266.149448) (xy 377.633782 -266.188792) (xy 377.598289 -266.222884) (xy 377.557786 -266.25084)
			(xy 377.513324 -266.271938) (xy 377.466053 -266.28563) (xy 377.417198 -266.291562) (xy 377.368023 -266.289581)
			(xy 377.319804 -266.279737) (xy 377.273788 -266.262285) (xy 377.231167 -266.237678) (xy 377.193046 -266.206553)
			(xy 377.160411 -266.169716) (xy 377.134108 -266.12812) (xy 377.114817 -266.082844) (xy 377.10304 -266.03506)
			(xy 377.09908 -265.986006) (xy 376.780552 -265.986006) (xy 376.78004 -266.011452) (xy 376.771876 -266.061686)
			(xy 376.75576 -266.10996) (xy 376.732109 -266.155023) (xy 376.701536 -266.195709) (xy 376.664832 -266.230964)
			(xy 376.622948 -266.259874) (xy 376.576969 -266.281691) (xy 376.528085 -266.295851) (xy 376.477564 -266.301985)
			(xy 376.426712 -266.299936) (xy 376.376848 -266.289756) (xy 376.329262 -266.271709) (xy 376.285188 -266.246263)
			(xy 376.245766 -266.214076) (xy 376.212018 -266.175982) (xy 376.184817 -266.132968) (xy 376.164869 -266.086148)
			(xy 376.15269 -266.036734) (xy 376.148595 -265.986006) (xy 374.89003 -265.986006) (xy 374.889535 -266.010613)
			(xy 374.88164 -266.05919) (xy 374.866056 -266.105871) (xy 374.843185 -266.149448) (xy 374.81362 -266.188792)
			(xy 374.778127 -266.222884) (xy 374.737624 -266.25084) (xy 374.693162 -266.271938) (xy 374.645891 -266.28563)
			(xy 374.597036 -266.291562) (xy 374.547861 -266.289581) (xy 374.499642 -266.279737) (xy 374.453626 -266.262285)
			(xy 374.411005 -266.237678) (xy 374.372884 -266.206553) (xy 374.340249 -266.169716) (xy 374.313946 -266.12812)
			(xy 374.294655 -266.082844) (xy 374.282878 -266.03506) (xy 374.278918 -265.986006) (xy 373.010176 -265.986006)
			(xy 373.009681 -266.010613) (xy 373.001786 -266.05919) (xy 372.986202 -266.105871) (xy 372.963331 -266.149448)
			(xy 372.933766 -266.188792) (xy 372.898273 -266.222884) (xy 372.85777 -266.25084) (xy 372.813308 -266.271938)
			(xy 372.766037 -266.28563) (xy 372.717182 -266.291562) (xy 372.668007 -266.289581) (xy 372.619788 -266.279737)
			(xy 372.573772 -266.262285) (xy 372.531151 -266.237678) (xy 372.49303 -266.206553) (xy 372.460395 -266.169716)
			(xy 372.434092 -266.12812) (xy 372.414801 -266.082844) (xy 372.403024 -266.03506) (xy 372.399064 -265.986006)
			(xy 371.130068 -265.986006) (xy 371.129573 -266.010613) (xy 371.121678 -266.05919) (xy 371.106094 -266.105871)
			(xy 371.083223 -266.149448) (xy 371.053658 -266.188792) (xy 371.018165 -266.222884) (xy 370.977662 -266.25084)
			(xy 370.9332 -266.271938) (xy 370.885929 -266.28563) (xy 370.837074 -266.291562) (xy 370.787899 -266.289581)
			(xy 370.73968 -266.279737) (xy 370.693664 -266.262285) (xy 370.651043 -266.237678) (xy 370.612922 -266.206553)
			(xy 370.580287 -266.169716) (xy 370.553984 -266.12812) (xy 370.534693 -266.082844) (xy 370.522916 -266.03506)
			(xy 370.518956 -265.986006) (xy 369.250214 -265.986006) (xy 369.249719 -266.010613) (xy 369.241824 -266.05919)
			(xy 369.22624 -266.105871) (xy 369.203369 -266.149448) (xy 369.173804 -266.188792) (xy 369.138311 -266.222884)
			(xy 369.097808 -266.25084) (xy 369.053346 -266.271938) (xy 369.006075 -266.28563) (xy 368.95722 -266.291562)
			(xy 368.908045 -266.289581) (xy 368.859826 -266.279737) (xy 368.81381 -266.262285) (xy 368.771189 -266.237678)
			(xy 368.733068 -266.206553) (xy 368.700433 -266.169716) (xy 368.67413 -266.12812) (xy 368.654839 -266.082844)
			(xy 368.643062 -266.03506) (xy 368.639102 -265.986006) (xy 367.370106 -265.986006) (xy 367.369611 -266.010613)
			(xy 367.361716 -266.05919) (xy 367.346132 -266.105871) (xy 367.323261 -266.149448) (xy 367.293696 -266.188792)
			(xy 367.258203 -266.222884) (xy 367.2177 -266.25084) (xy 367.173238 -266.271938) (xy 367.125967 -266.28563)
			(xy 367.077112 -266.291562) (xy 367.027937 -266.289581) (xy 366.979718 -266.279737) (xy 366.933702 -266.262285)
			(xy 366.891081 -266.237678) (xy 366.85296 -266.206553) (xy 366.820325 -266.169716) (xy 366.794022 -266.12812)
			(xy 366.774731 -266.082844) (xy 366.762954 -266.03506) (xy 366.758994 -265.986006) (xy 365.489998 -265.986006)
			(xy 365.489503 -266.010613) (xy 365.481608 -266.05919) (xy 365.466024 -266.105871) (xy 365.443153 -266.149448)
			(xy 365.413588 -266.188792) (xy 365.378095 -266.222884) (xy 365.337592 -266.25084) (xy 365.29313 -266.271938)
			(xy 365.245859 -266.28563) (xy 365.197004 -266.291562) (xy 365.147829 -266.289581) (xy 365.09961 -266.279737)
			(xy 365.053594 -266.262285) (xy 365.010973 -266.237678) (xy 364.972852 -266.206553) (xy 364.940217 -266.169716)
			(xy 364.913914 -266.12812) (xy 364.894623 -266.082844) (xy 364.882846 -266.03506) (xy 364.878886 -265.986006)
			(xy 363.610144 -265.986006) (xy 363.609649 -266.010613) (xy 363.601754 -266.05919) (xy 363.58617 -266.105871)
			(xy 363.563299 -266.149448) (xy 363.533734 -266.188792) (xy 363.498241 -266.222884) (xy 363.457738 -266.25084)
			(xy 363.413276 -266.271938) (xy 363.366005 -266.28563) (xy 363.31715 -266.291562) (xy 363.267975 -266.289581)
			(xy 363.219756 -266.279737) (xy 363.17374 -266.262285) (xy 363.131119 -266.237678) (xy 363.092998 -266.206553)
			(xy 363.060363 -266.169716) (xy 363.03406 -266.12812) (xy 363.014769 -266.082844) (xy 363.002992 -266.03506)
			(xy 362.999032 -265.986006) (xy 361.730036 -265.986006) (xy 361.729541 -266.010613) (xy 361.721646 -266.05919)
			(xy 361.706062 -266.105871) (xy 361.683191 -266.149448) (xy 361.653626 -266.188792) (xy 361.618133 -266.222884)
			(xy 361.57763 -266.25084) (xy 361.533168 -266.271938) (xy 361.485897 -266.28563) (xy 361.437042 -266.291562)
			(xy 361.387867 -266.289581) (xy 361.339648 -266.279737) (xy 361.293632 -266.262285) (xy 361.251011 -266.237678)
			(xy 361.21289 -266.206553) (xy 361.180255 -266.169716) (xy 361.153952 -266.12812) (xy 361.134661 -266.082844)
			(xy 361.122884 -266.03506) (xy 361.118924 -265.986006) (xy 357.976424 -265.986006) (xy 357.975976 -266.009424)
			(xy 357.968829 -266.055711) (xy 357.954704 -266.100366) (xy 357.933931 -266.142343) (xy 357.906997 -266.180659)
			(xy 357.89108 -266.197842) (xy 357.890826 -266.198096) (xy 357.885981 -266.203591) (xy 357.879293 -266.216617)
			(xy 357.877618 -266.22375) (xy 357.876348 -266.23137) (xy 357.877872 -266.246102) (xy 357.889302 -266.272772)
			(xy 357.917496 -266.338812) (xy 357.919375 -266.343082) (xy 357.924487 -266.350883) (xy 357.927656 -266.354306)
			(xy 357.935107 -266.36136) (xy 357.953981 -266.369357) (xy 357.964232 -266.3698) (xy 358.848152 -266.3698)
			(xy 358.858218 -266.370233) (xy 358.876809 -266.37796) (xy 358.88422 -266.384786) (xy 359.555796 -267.056362)
			(xy 359.561542 -267.061568) (xy 359.575371 -267.068562) (xy 359.582974 -267.070078) (xy 359.591356 -267.07084)
			(xy 359.60685 -267.07084) (xy 359.615685 -267.070467) (xy 359.63232 -267.064504) (xy 359.639362 -267.059156)
			(xy 359.64622 -267.053568) (xy 359.65511 -267.038328) (xy 359.656634 -267.029184) (xy 359.661905 -267.003183)
			(xy 359.679387 -266.953097) (xy 359.704363 -266.906294) (xy 359.736238 -266.863888) (xy 359.774254 -266.826887)
			(xy 359.817507 -266.796172) (xy 359.864969 -266.772472) (xy 359.91551 -266.756352) (xy 359.967929 -266.748195)
			(xy 360.020979 -266.748195) (xy 360.073398 -266.756352) (xy 360.123939 -266.772472) (xy 360.171401 -266.796172)
			(xy 360.214654 -266.826887) (xy 360.25267 -266.863888) (xy 360.284545 -266.906294) (xy 360.309521 -266.953097)
			(xy 360.327003 -267.003183) (xy 360.332274 -267.029184) (xy 360.334226 -267.037915) (xy 360.343192 -267.05338)
			(xy 360.3498 -267.05941) (xy 360.356658 -267.064744) (xy 360.373168 -267.07084) (xy 361.526582 -267.07084)
			(xy 361.528868 -267.07084) (xy 361.539785 -267.069821) (xy 361.559266 -267.059811) (xy 361.56646 -267.051536)
			(xy 361.568746 -267.048234) (xy 361.601004 -266.997688) (xy 361.615482 -266.974828) (xy 361.619138 -266.968569)
			(xy 361.623129 -266.954642) (xy 361.623356 -266.947396) (xy 361.6198 -266.93114) (xy 361.616498 -266.921488)
			(xy 361.60803 -266.901841) (xy 361.596066 -266.860765) (xy 361.589974 -266.818418) (xy 361.589574 -266.797028)
			(xy 361.589574 -266.790932) (xy 361.590489 -266.765952) (xy 361.599449 -266.716778) (xy 361.616299 -266.66972)
			(xy 361.640587 -266.626034) (xy 361.671666 -266.586887) (xy 361.708706 -266.553325) (xy 361.750718 -266.526243)
			(xy 361.796579 -266.506366) (xy 361.845065 -266.494223) (xy 361.894882 -266.490139) (xy 361.944699 -266.494223)
			(xy 361.993185 -266.506366) (xy 362.039046 -266.526243) (xy 362.081058 -266.553325) (xy 362.118098 -266.586887)
			(xy 362.149177 -266.626034) (xy 362.173465 -266.66972) (xy 362.190315 -266.716778) (xy 362.199275 -266.765952)
			(xy 362.20019 -266.790932) (xy 362.20019 -266.79652) (xy 362.199786 -266.817993) (xy 362.193702 -266.860507)
			(xy 362.181741 -266.901754) (xy 362.173266 -266.921488) (xy 362.169964 -266.93114) (xy 362.166408 -266.947396)
			(xy 362.166633 -266.95464) (xy 362.170638 -266.968562) (xy 362.174282 -266.974828) (xy 362.18876 -266.997688)
			(xy 362.221018 -267.048234) (xy 362.223304 -267.051536) (xy 362.230503 -267.059802) (xy 362.249983 -267.069805)
			(xy 362.260896 -267.07084) (xy 362.466382 -267.07084) (xy 362.468668 -267.07084) (xy 362.479585 -267.069821)
			(xy 362.499066 -267.059811) (xy 362.50626 -267.051536) (xy 362.508546 -267.048234) (xy 362.540804 -266.997688)
			(xy 362.555282 -266.974828) (xy 362.558938 -266.968569) (xy 362.562929 -266.954642) (xy 362.563156 -266.947396)
			(xy 362.5596 -266.93114) (xy 362.556298 -266.921488) (xy 362.54783 -266.901841) (xy 362.535866 -266.860765)
			(xy 362.529774 -266.818418) (xy 362.529374 -266.797028) (xy 362.529374 -266.790932) (xy 362.530289 -266.765952)
			(xy 362.539249 -266.716778) (xy 362.556099 -266.66972) (xy 362.580387 -266.626034) (xy 362.611466 -266.586887)
			(xy 362.648506 -266.553325) (xy 362.690518 -266.526243) (xy 362.736379 -266.506366) (xy 362.784865 -266.494223)
			(xy 362.834682 -266.490139) (xy 362.884499 -266.494223) (xy 362.932985 -266.506366) (xy 362.978846 -266.526243)
			(xy 363.020858 -266.553325) (xy 363.057898 -266.586887) (xy 363.088977 -266.626034) (xy 363.113265 -266.66972)
			(xy 363.130115 -266.716778) (xy 363.139075 -266.765952) (xy 363.13999 -266.790932) (xy 363.13999 -266.79652)
			(xy 363.139586 -266.817993) (xy 363.133502 -266.860507) (xy 363.121541 -266.901754) (xy 363.113066 -266.921488)
			(xy 363.109764 -266.93114) (xy 363.106208 -266.947396) (xy 363.106433 -266.95464) (xy 363.110438 -266.968562)
			(xy 363.114082 -266.974828) (xy 363.12856 -266.997688) (xy 363.160818 -267.048234) (xy 363.163104 -267.051536)
			(xy 363.170303 -267.059802) (xy 363.189783 -267.069805) (xy 363.200696 -267.07084) (xy 363.406436 -267.07084)
			(xy 363.408722 -267.07084) (xy 363.419643 -267.06983) (xy 363.439139 -267.05983) (xy 363.446314 -267.051536)
			(xy 363.4486 -267.048234) (xy 363.480858 -266.997688) (xy 363.495336 -266.974828) (xy 363.498995 -266.96857)
			(xy 363.502989 -266.954642) (xy 363.50321 -266.947396) (xy 363.499654 -266.93114) (xy 363.496352 -266.921488)
			(xy 363.487885 -266.901841) (xy 363.475923 -266.860765) (xy 363.469831 -266.818418) (xy 363.469428 -266.797028)
			(xy 363.469428 -266.790932) (xy 363.470343 -266.765952) (xy 363.479303 -266.716778) (xy 363.496153 -266.66972)
			(xy 363.520441 -266.626034) (xy 363.55152 -266.586887) (xy 363.58856 -266.553325) (xy 363.630572 -266.526243)
			(xy 363.676433 -266.506366) (xy 363.724919 -266.494223) (xy 363.774736 -266.490139) (xy 363.824553 -266.494223)
			(xy 363.873039 -266.506366) (xy 363.9189 -266.526243) (xy 363.960912 -266.553325) (xy 363.997952 -266.586887)
			(xy 364.029031 -266.626034) (xy 364.053319 -266.66972) (xy 364.070169 -266.716778) (xy 364.079129 -266.765952)
			(xy 364.080044 -266.790932) (xy 364.080044 -266.79652) (xy 364.079639 -266.817993) (xy 364.073555 -266.860506)
			(xy 364.061593 -266.901753) (xy 364.05312 -266.921488) (xy 364.049818 -266.93114) (xy 364.046262 -266.947396)
			(xy 364.046487 -266.95464) (xy 364.050496 -266.96856) (xy 364.054136 -266.974828) (xy 364.068614 -266.997688)
			(xy 364.100872 -267.048234) (xy 364.103158 -267.051536) (xy 364.110354 -267.059809) (xy 364.129833 -267.069829)
			(xy 364.14075 -267.07084) (xy 365.286544 -267.07084) (xy 365.28883 -267.07084) (xy 365.299751 -267.069828)
			(xy 365.319244 -267.059827) (xy 365.326422 -267.051536) (xy 365.328708 -267.048234) (xy 365.360966 -266.997688)
			(xy 365.375444 -266.974828) (xy 365.379102 -266.96857) (xy 365.383096 -266.954642) (xy 365.383318 -266.947396)
			(xy 365.379762 -266.93114) (xy 365.37646 -266.921488) (xy 365.367993 -266.901841) (xy 365.356031 -266.860765)
			(xy 365.349939 -266.818418) (xy 365.349536 -266.797028) (xy 365.349536 -266.790932) (xy 365.350451 -266.765952)
			(xy 365.359411 -266.716778) (xy 365.376261 -266.66972) (xy 365.400549 -266.626034) (xy 365.431628 -266.586887)
			(xy 365.468668 -266.553325) (xy 365.51068 -266.526243) (xy 365.556541 -266.506366) (xy 365.605027 -266.494223)
			(xy 365.654844 -266.490139) (xy 365.704661 -266.494223) (xy 365.753147 -266.506366) (xy 365.799008 -266.526243)
			(xy 365.84102 -266.553325) (xy 365.87806 -266.586887) (xy 365.909139 -266.626034) (xy 365.933427 -266.66972)
			(xy 365.950277 -266.716778) (xy 365.959237 -266.765952) (xy 365.960152 -266.790932) (xy 365.960152 -266.79652)
			(xy 365.959748 -266.817993) (xy 365.953663 -266.860506) (xy 365.941701 -266.901754) (xy 365.933228 -266.921488)
			(xy 365.929926 -266.93114) (xy 365.92637 -266.947396) (xy 365.926595 -266.95464) (xy 365.930605 -266.968559)
			(xy 365.934244 -266.974828) (xy 365.948722 -266.997688) (xy 365.98098 -267.048234) (xy 365.983266 -267.051536)
			(xy 365.990463 -267.059808) (xy 366.009942 -267.069825) (xy 366.020858 -267.07084) (xy 366.226598 -267.07084)
			(xy 366.228884 -267.07084) (xy 366.239799 -267.069818) (xy 366.259275 -267.059804) (xy 366.266476 -267.051536)
			(xy 366.268762 -267.048234) (xy 366.30102 -266.997688) (xy 366.315498 -266.974828) (xy 366.319153 -266.968569)
			(xy 366.323143 -266.954641) (xy 366.323372 -266.947396) (xy 366.319816 -266.93114) (xy 366.316514 -266.921488)
			(xy 366.308046 -266.901841) (xy 366.296081 -266.860765) (xy 366.289988 -266.818418) (xy 366.28959 -266.797028)
			(xy 366.28959 -266.790932) (xy 366.290505 -266.765952) (xy 366.299465 -266.716778) (xy 366.316315 -266.66972)
			(xy 366.340603 -266.626034) (xy 366.371682 -266.586887) (xy 366.408722 -266.553325) (xy 366.450734 -266.526243)
			(xy 366.496595 -266.506366) (xy 366.545081 -266.494223) (xy 366.594898 -266.490139) (xy 366.644715 -266.494223)
			(xy 366.693201 -266.506366) (xy 366.739062 -266.526243) (xy 366.781074 -266.553325) (xy 366.818114 -266.586887)
			(xy 366.849193 -266.626034) (xy 366.873481 -266.66972) (xy 366.890331 -266.716778) (xy 366.899291 -266.765952)
			(xy 366.900206 -266.790932) (xy 366.900206 -266.79652) (xy 366.899802 -266.817993) (xy 366.893718 -266.860507)
			(xy 366.881758 -266.901755) (xy 366.873282 -266.921488) (xy 366.86998 -266.93114) (xy 366.866424 -266.947396)
			(xy 366.866649 -266.95464) (xy 366.870656 -266.968561) (xy 366.874298 -266.974828) (xy 366.888776 -266.997688)
			(xy 366.921034 -267.048234) (xy 366.92332 -267.051536) (xy 366.93052 -267.0598) (xy 366.950001 -267.069796)
			(xy 366.960912 -267.07084) (xy 367.166398 -267.07084) (xy 367.168684 -267.07084) (xy 367.179599 -267.069818)
			(xy 367.199075 -267.059804) (xy 367.206276 -267.051536) (xy 367.208562 -267.048234) (xy 367.24082 -266.997688)
			(xy 367.255298 -266.974828) (xy 367.258953 -266.968569) (xy 367.262943 -266.954641) (xy 367.263172 -266.947396)
			(xy 367.259616 -266.93114) (xy 367.256314 -266.921488) (xy 367.247846 -266.901841) (xy 367.235881 -266.860765)
			(xy 367.229788 -266.818418) (xy 367.22939 -266.797028) (xy 367.22939 -266.790932) (xy 367.230305 -266.765952)
			(xy 367.239265 -266.716778) (xy 367.256115 -266.66972) (xy 367.280403 -266.626034) (xy 367.311482 -266.586887)
			(xy 367.348522 -266.553325) (xy 367.390534 -266.526243) (xy 367.436395 -266.506366) (xy 367.484881 -266.494223)
			(xy 367.534698 -266.490139) (xy 367.584515 -266.494223) (xy 367.633001 -266.506366) (xy 367.678862 -266.526243)
			(xy 367.720874 -266.553325) (xy 367.757914 -266.586887) (xy 367.788993 -266.626034) (xy 367.813281 -266.66972)
			(xy 367.830131 -266.716778) (xy 367.839091 -266.765952) (xy 367.840006 -266.790932) (xy 367.840006 -266.79652)
			(xy 367.839602 -266.817993) (xy 367.833518 -266.860507) (xy 367.821558 -266.901755) (xy 367.813082 -266.921488)
			(xy 367.80978 -266.93114) (xy 367.806224 -266.947396) (xy 367.806449 -266.95464) (xy 367.810456 -266.968561)
			(xy 367.814098 -266.974828) (xy 367.828576 -266.997688) (xy 367.860834 -267.048234) (xy 367.86312 -267.051536)
			(xy 367.87032 -267.0598) (xy 367.889801 -267.069796) (xy 367.900712 -267.07084) (xy 369.046506 -267.07084)
			(xy 369.048792 -267.07084) (xy 369.059717 -267.069836) (xy 369.079221 -267.059843) (xy 369.086384 -267.051536)
			(xy 369.08867 -267.048234) (xy 369.120928 -266.997688) (xy 369.135406 -266.974828) (xy 369.139067 -266.968571)
			(xy 369.143063 -266.954642) (xy 369.14328 -266.947396) (xy 369.139724 -266.93114) (xy 369.136422 -266.921488)
			(xy 369.127953 -266.901841) (xy 369.115989 -266.860765) (xy 369.109895 -266.818419) (xy 369.109498 -266.797028)
			(xy 369.109498 -266.790932) (xy 369.110413 -266.765952) (xy 369.119373 -266.716778) (xy 369.136223 -266.66972)
			(xy 369.160511 -266.626034) (xy 369.19159 -266.586887) (xy 369.22863 -266.553325) (xy 369.270642 -266.526243)
			(xy 369.316503 -266.506366) (xy 369.364989 -266.494223) (xy 369.414806 -266.490139) (xy 369.464623 -266.494223)
			(xy 369.513109 -266.506366) (xy 369.55897 -266.526243) (xy 369.600982 -266.553325) (xy 369.638022 -266.586887)
			(xy 369.669101 -266.626034) (xy 369.693389 -266.66972) (xy 369.710239 -266.716778) (xy 369.719199 -266.765952)
			(xy 369.720114 -266.790932) (xy 369.720114 -266.79652) (xy 369.71971 -266.817993) (xy 369.713627 -266.860507)
			(xy 369.701667 -266.901755) (xy 369.69319 -266.921488) (xy 369.689888 -266.93114) (xy 369.686332 -266.947396)
			(xy 369.686557 -266.95464) (xy 369.690564 -266.968561) (xy 369.694206 -266.974828) (xy 369.708684 -266.997688)
			(xy 369.740942 -267.048234) (xy 369.743228 -267.051536) (xy 369.750428 -267.059798) (xy 369.76991 -267.069792)
			(xy 369.78082 -267.07084) (xy 369.98656 -267.07084) (xy 369.988846 -267.07084) (xy 369.999765 -267.069825)
			(xy 370.019253 -267.05982) (xy 370.026438 -267.051536) (xy 370.028724 -267.048234) (xy 370.060982 -266.997688)
			(xy 370.07546 -266.974828) (xy 370.079118 -266.96857) (xy 370.08311 -266.954642) (xy 370.083334 -266.947396)
			(xy 370.079778 -266.93114) (xy 370.076476 -266.921488) (xy 370.068009 -266.901841) (xy 370.056046 -266.860765)
			(xy 370.049953 -266.818418) (xy 370.049552 -266.797028) (xy 370.049552 -266.790932) (xy 370.050467 -266.765952)
			(xy 370.059427 -266.716778) (xy 370.076277 -266.66972) (xy 370.100565 -266.626034) (xy 370.131644 -266.586887)
			(xy 370.168684 -266.553325) (xy 370.210696 -266.526243) (xy 370.256557 -266.506366) (xy 370.305043 -266.494223)
			(xy 370.35486 -266.490139) (xy 370.404677 -266.494223) (xy 370.453163 -266.506366) (xy 370.499024 -266.526243)
			(xy 370.541036 -266.553325) (xy 370.578076 -266.586887) (xy 370.609155 -266.626034) (xy 370.633443 -266.66972)
			(xy 370.650293 -266.716778) (xy 370.659253 -266.765952) (xy 370.660168 -266.790932) (xy 370.660168 -266.79652)
			(xy 370.659764 -266.817993) (xy 370.65368 -266.860506) (xy 370.641718 -266.901754) (xy 370.633244 -266.921488)
			(xy 370.629942 -266.93114) (xy 370.626386 -266.947396) (xy 370.62661 -266.95464) (xy 370.630614 -266.968563)
			(xy 370.63426 -266.974828) (xy 370.648738 -266.997688) (xy 370.680996 -267.048234) (xy 370.683282 -267.051536)
			(xy 370.69048 -267.059806) (xy 370.709959 -267.069817) (xy 370.720874 -267.07084) (xy 370.926614 -267.07084)
			(xy 370.9289 -267.07084) (xy 370.939824 -267.069834) (xy 370.959326 -267.05984) (xy 370.966492 -267.051536)
			(xy 370.968778 -267.048234) (xy 371.001036 -266.997688) (xy 371.015514 -266.974828) (xy 371.019174 -266.96857)
			(xy 371.02317 -266.954642) (xy 371.023388 -266.947396) (xy 371.019832 -266.93114) (xy 371.01653 -266.921488)
			(xy 371.008061 -266.901841) (xy 370.996096 -266.860765) (xy 370.990003 -266.818419) (xy 370.989606 -266.797028)
			(xy 370.989606 -266.790932) (xy 370.990521 -266.765952) (xy 370.999481 -266.716778) (xy 371.016331 -266.66972)
			(xy 371.040619 -266.626034) (xy 371.071698 -266.586887) (xy 371.108738 -266.553325) (xy 371.15075 -266.526243)
			(xy 371.196611 -266.506366) (xy 371.245097 -266.494223) (xy 371.294914 -266.490139) (xy 371.344731 -266.494223)
			(xy 371.393217 -266.506366) (xy 371.439078 -266.526243) (xy 371.48109 -266.553325) (xy 371.51813 -266.586887)
			(xy 371.549209 -266.626034) (xy 371.573497 -266.66972) (xy 371.590347 -266.716778) (xy 371.599307 -266.765952)
			(xy 371.600222 -266.790932) (xy 371.600222 -266.79652) (xy 371.599818 -266.817993) (xy 371.593735 -266.860507)
			(xy 371.581775 -266.901755) (xy 371.573298 -266.921488) (xy 371.569996 -266.93114) (xy 371.56644 -266.947396)
			(xy 371.566665 -266.95464) (xy 371.570673 -266.968561) (xy 371.574314 -266.974828) (xy 371.588792 -266.997688)
			(xy 371.62105 -267.048234) (xy 371.623336 -267.051536) (xy 371.630537 -267.059797) (xy 371.650018 -267.069788)
			(xy 371.660928 -267.07084) (xy 372.806468 -267.07084) (xy 372.808754 -267.07084) (xy 372.819672 -267.069824)
			(xy 372.839158 -267.059817) (xy 372.846346 -267.051536) (xy 372.848632 -267.048234) (xy 372.88089 -266.997688)
			(xy 372.895368 -266.974828) (xy 372.899025 -266.96857) (xy 372.903017 -266.954642) (xy 372.903242 -266.947396)
			(xy 372.899686 -266.93114) (xy 372.896384 -266.921488) (xy 372.887916 -266.901841) (xy 372.875953 -266.860765)
			(xy 372.869861 -266.818418) (xy 372.86946 -266.797028) (xy 372.86946 -266.790932) (xy 372.870375 -266.765952)
			(xy 372.879335 -266.716778) (xy 372.896185 -266.66972) (xy 372.920473 -266.626034) (xy 372.951552 -266.586887)
			(xy 372.988592 -266.553325) (xy 373.030604 -266.526243) (xy 373.076465 -266.506366) (xy 373.124951 -266.494223)
			(xy 373.174768 -266.490139) (xy 373.224585 -266.494223) (xy 373.273071 -266.506366) (xy 373.318932 -266.526243)
			(xy 373.360944 -266.553325) (xy 373.397984 -266.586887) (xy 373.429063 -266.626034) (xy 373.453351 -266.66972)
			(xy 373.470201 -266.716778) (xy 373.479161 -266.765952) (xy 373.480076 -266.790932) (xy 373.480076 -266.79652)
			(xy 373.479672 -266.817993) (xy 373.473588 -266.860507) (xy 373.461626 -266.901754) (xy 373.453152 -266.921488)
			(xy 373.44985 -266.93114) (xy 373.446294 -266.947396) (xy 373.446519 -266.95464) (xy 373.450523 -266.968563)
			(xy 373.454168 -266.974828) (xy 373.468646 -266.997688) (xy 373.500904 -267.048234) (xy 373.50319 -267.051536)
			(xy 373.510388 -267.059804) (xy 373.529868 -267.069812) (xy 373.540782 -267.07084) (xy 373.746522 -267.07084)
			(xy 373.748808 -267.07084) (xy 373.759731 -267.069833) (xy 373.779231 -267.059836) (xy 373.7864 -267.051536)
			(xy 373.788686 -267.048234) (xy 373.820944 -266.997688) (xy 373.835422 -266.974828) (xy 373.839082 -266.96857)
			(xy 373.843077 -266.954642) (xy 373.843296 -266.947396) (xy 373.83974 -266.93114) (xy 373.836438 -266.921488)
			(xy 373.827969 -266.901841) (xy 373.816004 -266.860765) (xy 373.80991 -266.818419) (xy 373.809514 -266.797028)
			(xy 373.809514 -266.790932) (xy 373.810359 -266.767205) (xy 373.818488 -266.72043) (xy 373.833761 -266.675477)
			(xy 373.85581 -266.633432) (xy 373.884103 -266.595308) (xy 373.917958 -266.562024) (xy 373.956558 -266.534383)
			(xy 373.998972 -266.513052) (xy 374.044177 -266.498546) (xy 374.091084 -266.491213) (xy 374.114822 -266.490704)
			(xy 374.138812 -266.491176) (xy 374.1862 -266.498685) (xy 374.23183 -266.513515) (xy 374.274579 -266.5353)
			(xy 374.313394 -266.563504) (xy 374.347319 -266.597432) (xy 374.375518 -266.63625) (xy 374.397298 -266.679001)
			(xy 374.412123 -266.724633) (xy 374.419626 -266.772022) (xy 374.42013 -266.796012) (xy 374.749072 -266.796012)
			(xy 374.753032 -266.746958) (xy 374.764809 -266.699174) (xy 374.7841 -266.653898) (xy 374.810403 -266.612302)
			(xy 374.843038 -266.575465) (xy 374.881159 -266.54434) (xy 374.92378 -266.519733) (xy 374.969796 -266.502281)
			(xy 375.018015 -266.492437) (xy 375.06719 -266.490456) (xy 375.116045 -266.496388) (xy 375.163316 -266.51008)
			(xy 375.207778 -266.531178) (xy 375.248281 -266.559134) (xy 375.283774 -266.593226) (xy 375.313339 -266.63257)
			(xy 375.33621 -266.676147) (xy 375.351794 -266.722828) (xy 375.359689 -266.771405) (xy 375.360184 -266.796012)
			(xy 375.678695 -266.796012) (xy 375.68279 -266.745284) (xy 375.694969 -266.69587) (xy 375.714917 -266.64905)
			(xy 375.742118 -266.606036) (xy 375.775866 -266.567942) (xy 375.815288 -266.535755) (xy 375.859362 -266.510309)
			(xy 375.906948 -266.492262) (xy 375.956812 -266.482082) (xy 376.007664 -266.480033) (xy 376.058185 -266.486167)
			(xy 376.107069 -266.500327) (xy 376.153048 -266.522144) (xy 376.194932 -266.551054) (xy 376.231636 -266.586309)
			(xy 376.262209 -266.626995) (xy 376.28586 -266.672058) (xy 376.301976 -266.720332) (xy 376.31014 -266.770566)
			(xy 376.310652 -266.796012) (xy 376.628926 -266.796012) (xy 376.632886 -266.746958) (xy 376.644663 -266.699174)
			(xy 376.663954 -266.653898) (xy 376.690257 -266.612302) (xy 376.722892 -266.575465) (xy 376.761013 -266.54434)
			(xy 376.803634 -266.519733) (xy 376.84965 -266.502281) (xy 376.897869 -266.492437) (xy 376.947044 -266.490456)
			(xy 376.995899 -266.496388) (xy 377.04317 -266.51008) (xy 377.087632 -266.531178) (xy 377.128135 -266.559134)
			(xy 377.163628 -266.593226) (xy 377.193193 -266.63257) (xy 377.216064 -266.676147) (xy 377.231648 -266.722828)
			(xy 377.239543 -266.771405) (xy 377.240038 -266.796012) (xy 377.558549 -266.796012) (xy 377.562644 -266.745284)
			(xy 377.574823 -266.69587) (xy 377.594771 -266.64905) (xy 377.621972 -266.606036) (xy 377.65572 -266.567942)
			(xy 377.695142 -266.535755) (xy 377.739216 -266.510309) (xy 377.786802 -266.492262) (xy 377.836666 -266.482082)
			(xy 377.887518 -266.480033) (xy 377.938039 -266.486167) (xy 377.986923 -266.500327) (xy 378.032902 -266.522144)
			(xy 378.074786 -266.551054) (xy 378.11149 -266.586309) (xy 378.142063 -266.626995) (xy 378.165714 -266.672058)
			(xy 378.18183 -266.720332) (xy 378.189994 -266.770566) (xy 378.190506 -266.796012) (xy 378.509034 -266.796012)
			(xy 378.512994 -266.746958) (xy 378.524771 -266.699174) (xy 378.544062 -266.653898) (xy 378.570365 -266.612302)
			(xy 378.603 -266.575465) (xy 378.641121 -266.54434) (xy 378.683742 -266.519733) (xy 378.729758 -266.502281)
			(xy 378.777977 -266.492437) (xy 378.827152 -266.490456) (xy 378.876007 -266.496388) (xy 378.923278 -266.51008)
			(xy 378.96774 -266.531178) (xy 379.008243 -266.559134) (xy 379.043736 -266.593226) (xy 379.073301 -266.63257)
			(xy 379.096172 -266.676147) (xy 379.111756 -266.722828) (xy 379.119651 -266.771405) (xy 379.120146 -266.796012)
			(xy 379.438657 -266.796012) (xy 379.442752 -266.745284) (xy 379.454931 -266.69587) (xy 379.474879 -266.64905)
			(xy 379.50208 -266.606036) (xy 379.535828 -266.567942) (xy 379.57525 -266.535755) (xy 379.619324 -266.510309)
			(xy 379.66691 -266.492262) (xy 379.716774 -266.482082) (xy 379.767626 -266.480033) (xy 379.818147 -266.486167)
			(xy 379.867031 -266.500327) (xy 379.91301 -266.522144) (xy 379.954894 -266.551054) (xy 379.991598 -266.586309)
			(xy 380.022171 -266.626995) (xy 380.045822 -266.672058) (xy 380.061938 -266.720332) (xy 380.070102 -266.770566)
			(xy 380.070614 -266.796012) (xy 380.378711 -266.796012) (xy 380.382806 -266.745284) (xy 380.394985 -266.69587)
			(xy 380.414933 -266.64905) (xy 380.442134 -266.606036) (xy 380.475882 -266.567942) (xy 380.515304 -266.535755)
			(xy 380.559378 -266.510309) (xy 380.606964 -266.492262) (xy 380.656828 -266.482082) (xy 380.70768 -266.480033)
			(xy 380.758201 -266.486167) (xy 380.807085 -266.500327) (xy 380.853064 -266.522144) (xy 380.894948 -266.551054)
			(xy 380.931652 -266.586309) (xy 380.962225 -266.626995) (xy 380.985876 -266.672058) (xy 381.001992 -266.720332)
			(xy 381.010156 -266.770566) (xy 381.010668 -266.796012) (xy 381.328942 -266.796012) (xy 381.332902 -266.746958)
			(xy 381.344679 -266.699174) (xy 381.36397 -266.653898) (xy 381.390273 -266.612302) (xy 381.422908 -266.575465)
			(xy 381.461029 -266.54434) (xy 381.50365 -266.519733) (xy 381.549666 -266.502281) (xy 381.597885 -266.492437)
			(xy 381.64706 -266.490456) (xy 381.695915 -266.496388) (xy 381.743186 -266.51008) (xy 381.787648 -266.531178)
			(xy 381.828151 -266.559134) (xy 381.863644 -266.593226) (xy 381.893209 -266.63257) (xy 381.91608 -266.676147)
			(xy 381.931664 -266.722828) (xy 381.939559 -266.771405) (xy 381.940054 -266.796012) (xy 382.268996 -266.796012)
			(xy 382.272956 -266.746958) (xy 382.284733 -266.699174) (xy 382.304024 -266.653898) (xy 382.330327 -266.612302)
			(xy 382.362962 -266.575465) (xy 382.401083 -266.54434) (xy 382.443704 -266.519733) (xy 382.48972 -266.502281)
			(xy 382.537939 -266.492437) (xy 382.587114 -266.490456) (xy 382.635969 -266.496388) (xy 382.68324 -266.51008)
			(xy 382.727702 -266.531178) (xy 382.768205 -266.559134) (xy 382.803698 -266.593226) (xy 382.833263 -266.63257)
			(xy 382.856134 -266.676147) (xy 382.871718 -266.722828) (xy 382.879613 -266.771405) (xy 382.880108 -266.796012)
			(xy 383.20905 -266.796012) (xy 383.21301 -266.746958) (xy 383.224787 -266.699174) (xy 383.244078 -266.653898)
			(xy 383.270381 -266.612302) (xy 383.303016 -266.575465) (xy 383.341137 -266.54434) (xy 383.383758 -266.519733)
			(xy 383.429774 -266.502281) (xy 383.477993 -266.492437) (xy 383.527168 -266.490456) (xy 383.576023 -266.496388)
			(xy 383.623294 -266.51008) (xy 383.667756 -266.531178) (xy 383.708259 -266.559134) (xy 383.743752 -266.593226)
			(xy 383.773317 -266.63257) (xy 383.796188 -266.676147) (xy 383.811772 -266.722828) (xy 383.819667 -266.771405)
			(xy 383.820162 -266.796012) (xy 384.149104 -266.796012) (xy 384.153064 -266.746958) (xy 384.164841 -266.699174)
			(xy 384.184132 -266.653898) (xy 384.210435 -266.612302) (xy 384.24307 -266.575465) (xy 384.281191 -266.54434)
			(xy 384.323812 -266.519733) (xy 384.369828 -266.502281) (xy 384.418047 -266.492437) (xy 384.467222 -266.490456)
			(xy 384.516077 -266.496388) (xy 384.563348 -266.51008) (xy 384.60781 -266.531178) (xy 384.648313 -266.559134)
			(xy 384.683806 -266.593226) (xy 384.713371 -266.63257) (xy 384.736242 -266.676147) (xy 384.751826 -266.722828)
			(xy 384.759721 -266.771405) (xy 384.760216 -266.796012) (xy 384.759721 -266.820619) (xy 384.751826 -266.869196)
			(xy 384.736242 -266.915877) (xy 384.713371 -266.959454) (xy 384.683806 -266.998798) (xy 384.648313 -267.03289)
			(xy 384.60781 -267.060846) (xy 384.563348 -267.081944) (xy 384.516077 -267.095636) (xy 384.467222 -267.101568)
			(xy 384.418047 -267.099587) (xy 384.369828 -267.089743) (xy 384.323812 -267.072291) (xy 384.281191 -267.047684)
			(xy 384.24307 -267.016559) (xy 384.210435 -266.979722) (xy 384.184132 -266.938126) (xy 384.164841 -266.89285)
			(xy 384.153064 -266.845066) (xy 384.149104 -266.796012) (xy 383.820162 -266.796012) (xy 383.819667 -266.820619)
			(xy 383.811772 -266.869196) (xy 383.796188 -266.915877) (xy 383.773317 -266.959454) (xy 383.743752 -266.998798)
			(xy 383.708259 -267.03289) (xy 383.667756 -267.060846) (xy 383.623294 -267.081944) (xy 383.576023 -267.095636)
			(xy 383.527168 -267.101568) (xy 383.477993 -267.099587) (xy 383.429774 -267.089743) (xy 383.383758 -267.072291)
			(xy 383.341137 -267.047684) (xy 383.303016 -267.016559) (xy 383.270381 -266.979722) (xy 383.244078 -266.938126)
			(xy 383.224787 -266.89285) (xy 383.21301 -266.845066) (xy 383.20905 -266.796012) (xy 382.880108 -266.796012)
			(xy 382.879613 -266.820619) (xy 382.871718 -266.869196) (xy 382.856134 -266.915877) (xy 382.833263 -266.959454)
			(xy 382.803698 -266.998798) (xy 382.768205 -267.03289) (xy 382.727702 -267.060846) (xy 382.68324 -267.081944)
			(xy 382.635969 -267.095636) (xy 382.587114 -267.101568) (xy 382.537939 -267.099587) (xy 382.48972 -267.089743)
			(xy 382.443704 -267.072291) (xy 382.401083 -267.047684) (xy 382.362962 -267.016559) (xy 382.330327 -266.979722)
			(xy 382.304024 -266.938126) (xy 382.284733 -266.89285) (xy 382.272956 -266.845066) (xy 382.268996 -266.796012)
			(xy 381.940054 -266.796012) (xy 381.939559 -266.820619) (xy 381.931664 -266.869196) (xy 381.91608 -266.915877)
			(xy 381.893209 -266.959454) (xy 381.863644 -266.998798) (xy 381.828151 -267.03289) (xy 381.787648 -267.060846)
			(xy 381.743186 -267.081944) (xy 381.695915 -267.095636) (xy 381.64706 -267.101568) (xy 381.597885 -267.099587)
			(xy 381.549666 -267.089743) (xy 381.50365 -267.072291) (xy 381.461029 -267.047684) (xy 381.422908 -267.016559)
			(xy 381.390273 -266.979722) (xy 381.36397 -266.938126) (xy 381.344679 -266.89285) (xy 381.332902 -266.845066)
			(xy 381.328942 -266.796012) (xy 381.010668 -266.796012) (xy 381.010156 -266.821458) (xy 381.001992 -266.871692)
			(xy 380.985876 -266.919966) (xy 380.962225 -266.965029) (xy 380.931652 -267.005715) (xy 380.894948 -267.04097)
			(xy 380.853064 -267.06988) (xy 380.807085 -267.091697) (xy 380.758201 -267.105857) (xy 380.70768 -267.111991)
			(xy 380.656828 -267.109942) (xy 380.606964 -267.099762) (xy 380.559378 -267.081715) (xy 380.515304 -267.056269)
			(xy 380.475882 -267.024082) (xy 380.442134 -266.985988) (xy 380.414933 -266.942974) (xy 380.394985 -266.896154)
			(xy 380.382806 -266.84674) (xy 380.378711 -266.796012) (xy 380.070614 -266.796012) (xy 380.070102 -266.821458)
			(xy 380.061938 -266.871692) (xy 380.045822 -266.919966) (xy 380.022171 -266.965029) (xy 379.991598 -267.005715)
			(xy 379.954894 -267.04097) (xy 379.91301 -267.06988) (xy 379.867031 -267.091697) (xy 379.818147 -267.105857)
			(xy 379.767626 -267.111991) (xy 379.716774 -267.109942) (xy 379.66691 -267.099762) (xy 379.619324 -267.081715)
			(xy 379.57525 -267.056269) (xy 379.535828 -267.024082) (xy 379.50208 -266.985988) (xy 379.474879 -266.942974)
			(xy 379.454931 -266.896154) (xy 379.442752 -266.84674) (xy 379.438657 -266.796012) (xy 379.120146 -266.796012)
			(xy 379.119651 -266.820619) (xy 379.111756 -266.869196) (xy 379.096172 -266.915877) (xy 379.073301 -266.959454)
			(xy 379.043736 -266.998798) (xy 379.008243 -267.03289) (xy 378.96774 -267.060846) (xy 378.923278 -267.081944)
			(xy 378.876007 -267.095636) (xy 378.827152 -267.101568) (xy 378.777977 -267.099587) (xy 378.729758 -267.089743)
			(xy 378.683742 -267.072291) (xy 378.641121 -267.047684) (xy 378.603 -267.016559) (xy 378.570365 -266.979722)
			(xy 378.544062 -266.938126) (xy 378.524771 -266.89285) (xy 378.512994 -266.845066) (xy 378.509034 -266.796012)
			(xy 378.190506 -266.796012) (xy 378.189994 -266.821458) (xy 378.18183 -266.871692) (xy 378.165714 -266.919966)
			(xy 378.142063 -266.965029) (xy 378.11149 -267.005715) (xy 378.074786 -267.04097) (xy 378.032902 -267.06988)
			(xy 377.986923 -267.091697) (xy 377.938039 -267.105857) (xy 377.887518 -267.111991) (xy 377.836666 -267.109942)
			(xy 377.786802 -267.099762) (xy 377.739216 -267.081715) (xy 377.695142 -267.056269) (xy 377.65572 -267.024082)
			(xy 377.621972 -266.985988) (xy 377.594771 -266.942974) (xy 377.574823 -266.896154) (xy 377.562644 -266.84674)
			(xy 377.558549 -266.796012) (xy 377.240038 -266.796012) (xy 377.239543 -266.820619) (xy 377.231648 -266.869196)
			(xy 377.216064 -266.915877) (xy 377.193193 -266.959454) (xy 377.163628 -266.998798) (xy 377.128135 -267.03289)
			(xy 377.087632 -267.060846) (xy 377.04317 -267.081944) (xy 376.995899 -267.095636) (xy 376.947044 -267.101568)
			(xy 376.897869 -267.099587) (xy 376.84965 -267.089743) (xy 376.803634 -267.072291) (xy 376.761013 -267.047684)
			(xy 376.722892 -267.016559) (xy 376.690257 -266.979722) (xy 376.663954 -266.938126) (xy 376.644663 -266.89285)
			(xy 376.632886 -266.845066) (xy 376.628926 -266.796012) (xy 376.310652 -266.796012) (xy 376.31014 -266.821458)
			(xy 376.301976 -266.871692) (xy 376.28586 -266.919966) (xy 376.262209 -266.965029) (xy 376.231636 -267.005715)
			(xy 376.194932 -267.04097) (xy 376.153048 -267.06988) (xy 376.107069 -267.091697) (xy 376.058185 -267.105857)
			(xy 376.007664 -267.111991) (xy 375.956812 -267.109942) (xy 375.906948 -267.099762) (xy 375.859362 -267.081715)
			(xy 375.815288 -267.056269) (xy 375.775866 -267.024082) (xy 375.742118 -266.985988) (xy 375.714917 -266.942974)
			(xy 375.694969 -266.896154) (xy 375.68279 -266.84674) (xy 375.678695 -266.796012) (xy 375.360184 -266.796012)
			(xy 375.359689 -266.820619) (xy 375.351794 -266.869196) (xy 375.33621 -266.915877) (xy 375.313339 -266.959454)
			(xy 375.283774 -266.998798) (xy 375.248281 -267.03289) (xy 375.207778 -267.060846) (xy 375.163316 -267.081944)
			(xy 375.116045 -267.095636) (xy 375.06719 -267.101568) (xy 375.018015 -267.099587) (xy 374.969796 -267.089743)
			(xy 374.92378 -267.072291) (xy 374.881159 -267.047684) (xy 374.843038 -267.016559) (xy 374.810403 -266.979722)
			(xy 374.7841 -266.938126) (xy 374.764809 -266.89285) (xy 374.753032 -266.845066) (xy 374.749072 -266.796012)
			(xy 374.42013 -266.796012) (xy 374.419976 -266.808774) (xy 374.417814 -266.834207) (xy 374.415812 -266.846812)
			(xy 374.416066 -266.846812) (xy 374.411535 -266.871015) (xy 374.39571 -266.917642) (xy 374.372603 -266.961122)
			(xy 374.342816 -267.000329) (xy 374.30712 -267.034244) (xy 374.287034 -267.048488) (xy 374.286526 -267.048742)
			(xy 374.282043 -267.051984) (xy 374.274483 -267.060059) (xy 374.27154 -267.064744) (xy 374.266206 -267.073888)
			(xy 374.261888 -267.120116) (xy 374.257824 -267.163296) (xy 374.257392 -267.174423) (xy 374.264902 -267.195361)
			(xy 374.272302 -267.203682) (xy 374.391174 -267.322554) (xy 374.397023 -267.328004) (xy 374.411266 -267.33525)
			(xy 374.419114 -267.336778) (xy 374.426734 -267.338048) (xy 374.442228 -267.335762) (xy 374.449594 -267.332206)
			(xy 374.470723 -267.32228) (xy 374.515244 -267.308245) (xy 374.561382 -267.301147) (xy 374.584722 -267.30071)
			(xy 374.608712 -267.301182) (xy 374.6561 -267.308691) (xy 374.701729 -267.323521) (xy 374.744478 -267.345306)
			(xy 374.783292 -267.37351) (xy 374.817216 -267.407439) (xy 374.845415 -267.446256) (xy 374.867195 -267.489008)
			(xy 374.882018 -267.534639) (xy 374.889521 -267.582028) (xy 374.89003 -267.606018) (xy 376.159026 -267.606018)
			(xy 376.162986 -267.556964) (xy 376.174763 -267.50918) (xy 376.194054 -267.463904) (xy 376.220357 -267.422308)
			(xy 376.252992 -267.385471) (xy 376.291113 -267.354346) (xy 376.333734 -267.329739) (xy 376.37975 -267.312287)
			(xy 376.427969 -267.302443) (xy 376.477144 -267.300462) (xy 376.525999 -267.306394) (xy 376.57327 -267.320086)
			(xy 376.617732 -267.341184) (xy 376.658235 -267.36914) (xy 376.693728 -267.403232) (xy 376.723293 -267.442576)
			(xy 376.746164 -267.486153) (xy 376.761748 -267.532834) (xy 376.769643 -267.581411) (xy 376.770138 -267.606018)
			(xy 377.088649 -267.606018) (xy 377.092744 -267.55529) (xy 377.104923 -267.505876) (xy 377.124871 -267.459056)
			(xy 377.152072 -267.416042) (xy 377.18582 -267.377948) (xy 377.225242 -267.345761) (xy 377.269316 -267.320315)
			(xy 377.316902 -267.302268) (xy 377.366766 -267.292088) (xy 377.417618 -267.290039) (xy 377.468139 -267.296173)
			(xy 377.517023 -267.310333) (xy 377.563002 -267.33215) (xy 377.604886 -267.36106) (xy 377.64159 -267.396315)
			(xy 377.672163 -267.437001) (xy 377.695814 -267.482064) (xy 377.71193 -267.530338) (xy 377.720094 -267.580572)
			(xy 377.720606 -267.606018) (xy 378.039134 -267.606018) (xy 378.043094 -267.556964) (xy 378.054871 -267.50918)
			(xy 378.074162 -267.463904) (xy 378.100465 -267.422308) (xy 378.1331 -267.385471) (xy 378.171221 -267.354346)
			(xy 378.213842 -267.329739) (xy 378.259858 -267.312287) (xy 378.308077 -267.302443) (xy 378.357252 -267.300462)
			(xy 378.406107 -267.306394) (xy 378.453378 -267.320086) (xy 378.49784 -267.341184) (xy 378.538343 -267.36914)
			(xy 378.573836 -267.403232) (xy 378.603401 -267.442576) (xy 378.626272 -267.486153) (xy 378.641856 -267.532834)
			(xy 378.649751 -267.581411) (xy 378.650246 -267.606018) (xy 378.978934 -267.606018) (xy 378.982894 -267.556964)
			(xy 378.994671 -267.50918) (xy 379.013962 -267.463904) (xy 379.040265 -267.422308) (xy 379.0729 -267.385471)
			(xy 379.111021 -267.354346) (xy 379.153642 -267.329739) (xy 379.199658 -267.312287) (xy 379.247877 -267.302443)
			(xy 379.297052 -267.300462) (xy 379.345907 -267.306394) (xy 379.393178 -267.320086) (xy 379.43764 -267.341184)
			(xy 379.478143 -267.36914) (xy 379.513636 -267.403232) (xy 379.543201 -267.442576) (xy 379.566072 -267.486153)
			(xy 379.581656 -267.532834) (xy 379.589551 -267.581411) (xy 379.590046 -267.606018) (xy 379.918988 -267.606018)
			(xy 379.922948 -267.556964) (xy 379.934725 -267.50918) (xy 379.954016 -267.463904) (xy 379.980319 -267.422308)
			(xy 380.012954 -267.385471) (xy 380.051075 -267.354346) (xy 380.093696 -267.329739) (xy 380.139712 -267.312287)
			(xy 380.187931 -267.302443) (xy 380.237106 -267.300462) (xy 380.285961 -267.306394) (xy 380.333232 -267.320086)
			(xy 380.377694 -267.341184) (xy 380.418197 -267.36914) (xy 380.45369 -267.403232) (xy 380.483255 -267.442576)
			(xy 380.506126 -267.486153) (xy 380.52171 -267.532834) (xy 380.529605 -267.581411) (xy 380.5301 -267.606018)
			(xy 380.848611 -267.606018) (xy 380.852706 -267.55529) (xy 380.864885 -267.505876) (xy 380.884833 -267.459056)
			(xy 380.912034 -267.416042) (xy 380.945782 -267.377948) (xy 380.985204 -267.345761) (xy 381.029278 -267.320315)
			(xy 381.076864 -267.302268) (xy 381.126728 -267.292088) (xy 381.17758 -267.290039) (xy 381.228101 -267.296173)
			(xy 381.276985 -267.310333) (xy 381.322964 -267.33215) (xy 381.364848 -267.36106) (xy 381.401552 -267.396315)
			(xy 381.432125 -267.437001) (xy 381.455776 -267.482064) (xy 381.471892 -267.530338) (xy 381.480056 -267.580572)
			(xy 381.480568 -267.606018) (xy 381.799096 -267.606018) (xy 381.803056 -267.556964) (xy 381.814833 -267.50918)
			(xy 381.834124 -267.463904) (xy 381.860427 -267.422308) (xy 381.893062 -267.385471) (xy 381.931183 -267.354346)
			(xy 381.973804 -267.329739) (xy 382.01982 -267.312287) (xy 382.068039 -267.302443) (xy 382.117214 -267.300462)
			(xy 382.166069 -267.306394) (xy 382.21334 -267.320086) (xy 382.257802 -267.341184) (xy 382.298305 -267.36914)
			(xy 382.333798 -267.403232) (xy 382.363363 -267.442576) (xy 382.386234 -267.486153) (xy 382.401818 -267.532834)
			(xy 382.409713 -267.581411) (xy 382.410208 -267.606018) (xy 382.738896 -267.606018) (xy 382.742856 -267.556964)
			(xy 382.754633 -267.50918) (xy 382.773924 -267.463904) (xy 382.800227 -267.422308) (xy 382.832862 -267.385471)
			(xy 382.870983 -267.354346) (xy 382.913604 -267.329739) (xy 382.95962 -267.312287) (xy 383.007839 -267.302443)
			(xy 383.057014 -267.300462) (xy 383.105869 -267.306394) (xy 383.15314 -267.320086) (xy 383.197602 -267.341184)
			(xy 383.238105 -267.36914) (xy 383.273598 -267.403232) (xy 383.303163 -267.442576) (xy 383.326034 -267.486153)
			(xy 383.341618 -267.532834) (xy 383.349513 -267.581411) (xy 383.350008 -267.606018) (xy 383.67895 -267.606018)
			(xy 383.68291 -267.556964) (xy 383.694687 -267.50918) (xy 383.713978 -267.463904) (xy 383.740281 -267.422308)
			(xy 383.772916 -267.385471) (xy 383.811037 -267.354346) (xy 383.853658 -267.329739) (xy 383.899674 -267.312287)
			(xy 383.947893 -267.302443) (xy 383.997068 -267.300462) (xy 384.045923 -267.306394) (xy 384.093194 -267.320086)
			(xy 384.137656 -267.341184) (xy 384.178159 -267.36914) (xy 384.213652 -267.403232) (xy 384.243217 -267.442576)
			(xy 384.266088 -267.486153) (xy 384.281672 -267.532834) (xy 384.289567 -267.581411) (xy 384.290062 -267.606018)
			(xy 384.619004 -267.606018) (xy 384.622964 -267.556964) (xy 384.634741 -267.50918) (xy 384.654032 -267.463904)
			(xy 384.680335 -267.422308) (xy 384.71297 -267.385471) (xy 384.751091 -267.354346) (xy 384.793712 -267.329739)
			(xy 384.839728 -267.312287) (xy 384.887947 -267.302443) (xy 384.937122 -267.300462) (xy 384.985977 -267.306394)
			(xy 385.033248 -267.320086) (xy 385.07771 -267.341184) (xy 385.118213 -267.36914) (xy 385.153706 -267.403232)
			(xy 385.183271 -267.442576) (xy 385.206142 -267.486153) (xy 385.221726 -267.532834) (xy 385.229621 -267.581411)
			(xy 385.230116 -267.606018) (xy 385.229621 -267.630625) (xy 385.221726 -267.679202) (xy 385.206142 -267.725883)
			(xy 385.183271 -267.76946) (xy 385.153706 -267.808804) (xy 385.118213 -267.842896) (xy 385.07771 -267.870852)
			(xy 385.033248 -267.89195) (xy 384.985977 -267.905642) (xy 384.937122 -267.911574) (xy 384.887947 -267.909593)
			(xy 384.839728 -267.899749) (xy 384.793712 -267.882297) (xy 384.751091 -267.85769) (xy 384.71297 -267.826565)
			(xy 384.680335 -267.789728) (xy 384.654032 -267.748132) (xy 384.634741 -267.702856) (xy 384.622964 -267.655072)
			(xy 384.619004 -267.606018) (xy 384.290062 -267.606018) (xy 384.289567 -267.630625) (xy 384.281672 -267.679202)
			(xy 384.266088 -267.725883) (xy 384.243217 -267.76946) (xy 384.213652 -267.808804) (xy 384.178159 -267.842896)
			(xy 384.137656 -267.870852) (xy 384.093194 -267.89195) (xy 384.045923 -267.905642) (xy 383.997068 -267.911574)
			(xy 383.947893 -267.909593) (xy 383.899674 -267.899749) (xy 383.853658 -267.882297) (xy 383.811037 -267.85769)
			(xy 383.772916 -267.826565) (xy 383.740281 -267.789728) (xy 383.713978 -267.748132) (xy 383.694687 -267.702856)
			(xy 383.68291 -267.655072) (xy 383.67895 -267.606018) (xy 383.350008 -267.606018) (xy 383.349513 -267.630625)
			(xy 383.341618 -267.679202) (xy 383.326034 -267.725883) (xy 383.303163 -267.76946) (xy 383.273598 -267.808804)
			(xy 383.238105 -267.842896) (xy 383.197602 -267.870852) (xy 383.15314 -267.89195) (xy 383.105869 -267.905642)
			(xy 383.057014 -267.911574) (xy 383.007839 -267.909593) (xy 382.95962 -267.899749) (xy 382.913604 -267.882297)
			(xy 382.870983 -267.85769) (xy 382.832862 -267.826565) (xy 382.800227 -267.789728) (xy 382.773924 -267.748132)
			(xy 382.754633 -267.702856) (xy 382.742856 -267.655072) (xy 382.738896 -267.606018) (xy 382.410208 -267.606018)
			(xy 382.409713 -267.630625) (xy 382.401818 -267.679202) (xy 382.386234 -267.725883) (xy 382.363363 -267.76946)
			(xy 382.333798 -267.808804) (xy 382.298305 -267.842896) (xy 382.257802 -267.870852) (xy 382.21334 -267.89195)
			(xy 382.166069 -267.905642) (xy 382.117214 -267.911574) (xy 382.068039 -267.909593) (xy 382.01982 -267.899749)
			(xy 381.973804 -267.882297) (xy 381.931183 -267.85769) (xy 381.893062 -267.826565) (xy 381.860427 -267.789728)
			(xy 381.834124 -267.748132) (xy 381.814833 -267.702856) (xy 381.803056 -267.655072) (xy 381.799096 -267.606018)
			(xy 381.480568 -267.606018) (xy 381.480056 -267.631464) (xy 381.471892 -267.681698) (xy 381.455776 -267.729972)
			(xy 381.432125 -267.775035) (xy 381.401552 -267.815721) (xy 381.364848 -267.850976) (xy 381.322964 -267.879886)
			(xy 381.276985 -267.901703) (xy 381.228101 -267.915863) (xy 381.17758 -267.921997) (xy 381.126728 -267.919948)
			(xy 381.076864 -267.909768) (xy 381.029278 -267.891721) (xy 380.985204 -267.866275) (xy 380.945782 -267.834088)
			(xy 380.912034 -267.795994) (xy 380.884833 -267.75298) (xy 380.864885 -267.70616) (xy 380.852706 -267.656746)
			(xy 380.848611 -267.606018) (xy 380.5301 -267.606018) (xy 380.529605 -267.630625) (xy 380.52171 -267.679202)
			(xy 380.506126 -267.725883) (xy 380.483255 -267.76946) (xy 380.45369 -267.808804) (xy 380.418197 -267.842896)
			(xy 380.377694 -267.870852) (xy 380.333232 -267.89195) (xy 380.285961 -267.905642) (xy 380.237106 -267.911574)
			(xy 380.187931 -267.909593) (xy 380.139712 -267.899749) (xy 380.093696 -267.882297) (xy 380.051075 -267.85769)
			(xy 380.012954 -267.826565) (xy 379.980319 -267.789728) (xy 379.954016 -267.748132) (xy 379.934725 -267.702856)
			(xy 379.922948 -267.655072) (xy 379.918988 -267.606018) (xy 379.590046 -267.606018) (xy 379.589551 -267.630625)
			(xy 379.581656 -267.679202) (xy 379.566072 -267.725883) (xy 379.543201 -267.76946) (xy 379.513636 -267.808804)
			(xy 379.478143 -267.842896) (xy 379.43764 -267.870852) (xy 379.393178 -267.89195) (xy 379.345907 -267.905642)
			(xy 379.297052 -267.911574) (xy 379.247877 -267.909593) (xy 379.199658 -267.899749) (xy 379.153642 -267.882297)
			(xy 379.111021 -267.85769) (xy 379.0729 -267.826565) (xy 379.040265 -267.789728) (xy 379.013962 -267.748132)
			(xy 378.994671 -267.702856) (xy 378.982894 -267.655072) (xy 378.978934 -267.606018) (xy 378.650246 -267.606018)
			(xy 378.649751 -267.630625) (xy 378.641856 -267.679202) (xy 378.626272 -267.725883) (xy 378.603401 -267.76946)
			(xy 378.573836 -267.808804) (xy 378.538343 -267.842896) (xy 378.49784 -267.870852) (xy 378.453378 -267.89195)
			(xy 378.406107 -267.905642) (xy 378.357252 -267.911574) (xy 378.308077 -267.909593) (xy 378.259858 -267.899749)
			(xy 378.213842 -267.882297) (xy 378.171221 -267.85769) (xy 378.1331 -267.826565) (xy 378.100465 -267.789728)
			(xy 378.074162 -267.748132) (xy 378.054871 -267.702856) (xy 378.043094 -267.655072) (xy 378.039134 -267.606018)
			(xy 377.720606 -267.606018) (xy 377.720094 -267.631464) (xy 377.71193 -267.681698) (xy 377.695814 -267.729972)
			(xy 377.672163 -267.775035) (xy 377.64159 -267.815721) (xy 377.604886 -267.850976) (xy 377.563002 -267.879886)
			(xy 377.517023 -267.901703) (xy 377.468139 -267.915863) (xy 377.417618 -267.921997) (xy 377.366766 -267.919948)
			(xy 377.316902 -267.909768) (xy 377.269316 -267.891721) (xy 377.225242 -267.866275) (xy 377.18582 -267.834088)
			(xy 377.152072 -267.795994) (xy 377.124871 -267.75298) (xy 377.104923 -267.70616) (xy 377.092744 -267.656746)
			(xy 377.088649 -267.606018) (xy 376.770138 -267.606018) (xy 376.769643 -267.630625) (xy 376.761748 -267.679202)
			(xy 376.746164 -267.725883) (xy 376.723293 -267.76946) (xy 376.693728 -267.808804) (xy 376.658235 -267.842896)
			(xy 376.617732 -267.870852) (xy 376.57327 -267.89195) (xy 376.525999 -267.905642) (xy 376.477144 -267.911574)
			(xy 376.427969 -267.909593) (xy 376.37975 -267.899749) (xy 376.333734 -267.882297) (xy 376.291113 -267.85769)
			(xy 376.252992 -267.826565) (xy 376.220357 -267.789728) (xy 376.194054 -267.748132) (xy 376.174763 -267.702856)
			(xy 376.162986 -267.655072) (xy 376.159026 -267.606018) (xy 374.89003 -267.606018) (xy 374.889575 -267.629316)
			(xy 374.882469 -267.675368) (xy 374.868455 -267.719807) (xy 374.858534 -267.740892) (xy 374.858534 -267.7414)
			(xy 374.85828 -267.741654) (xy 374.855197 -267.748722) (xy 374.85299 -267.763977) (xy 374.853962 -267.771626)
			(xy 374.855232 -267.7795) (xy 374.862344 -267.793724) (xy 375.248932 -268.180312) (xy 375.25071 -268.181836)
			(xy 375.25198 -268.182852) (xy 375.254012 -268.184376) (xy 375.263415 -268.192681) (xy 375.280962 -268.210612)
			(xy 375.289064 -268.22019) (xy 375.290588 -268.221968) (xy 375.382536 -268.313916) (xy 375.389387 -268.321312)
			(xy 375.397125 -268.339911) (xy 375.397522 -268.349984) (xy 375.397522 -268.416024) (xy 375.689126 -268.416024)
			(xy 375.693086 -268.36697) (xy 375.704863 -268.319186) (xy 375.724154 -268.27391) (xy 375.750457 -268.232314)
			(xy 375.783092 -268.195477) (xy 375.821213 -268.164352) (xy 375.863834 -268.139745) (xy 375.90985 -268.122293)
			(xy 375.958069 -268.112449) (xy 376.007244 -268.110468) (xy 376.056099 -268.1164) (xy 376.10337 -268.130092)
			(xy 376.147832 -268.15119) (xy 376.188335 -268.179146) (xy 376.223828 -268.213238) (xy 376.253393 -268.252582)
			(xy 376.276264 -268.296159) (xy 376.291848 -268.34284) (xy 376.299743 -268.391417) (xy 376.300238 -268.416024)
			(xy 376.628926 -268.416024) (xy 376.632886 -268.36697) (xy 376.644663 -268.319186) (xy 376.663954 -268.27391)
			(xy 376.690257 -268.232314) (xy 376.722892 -268.195477) (xy 376.761013 -268.164352) (xy 376.803634 -268.139745)
			(xy 376.84965 -268.122293) (xy 376.897869 -268.112449) (xy 376.947044 -268.110468) (xy 376.995899 -268.1164)
			(xy 377.04317 -268.130092) (xy 377.087632 -268.15119) (xy 377.128135 -268.179146) (xy 377.163628 -268.213238)
			(xy 377.193193 -268.252582) (xy 377.216064 -268.296159) (xy 377.231648 -268.34284) (xy 377.239543 -268.391417)
			(xy 377.240038 -268.416024) (xy 377.56898 -268.416024) (xy 377.57294 -268.36697) (xy 377.584717 -268.319186)
			(xy 377.604008 -268.27391) (xy 377.630311 -268.232314) (xy 377.662946 -268.195477) (xy 377.701067 -268.164352)
			(xy 377.743688 -268.139745) (xy 377.789704 -268.122293) (xy 377.837923 -268.112449) (xy 377.887098 -268.110468)
			(xy 377.935953 -268.1164) (xy 377.983224 -268.130092) (xy 378.027686 -268.15119) (xy 378.068189 -268.179146)
			(xy 378.103682 -268.213238) (xy 378.133247 -268.252582) (xy 378.156118 -268.296159) (xy 378.171702 -268.34284)
			(xy 378.179597 -268.391417) (xy 378.180092 -268.416024) (xy 379.449088 -268.416024) (xy 379.453048 -268.36697)
			(xy 379.464825 -268.319186) (xy 379.484116 -268.27391) (xy 379.510419 -268.232314) (xy 379.543054 -268.195477)
			(xy 379.581175 -268.164352) (xy 379.623796 -268.139745) (xy 379.669812 -268.122293) (xy 379.718031 -268.112449)
			(xy 379.767206 -268.110468) (xy 379.816061 -268.1164) (xy 379.863332 -268.130092) (xy 379.907794 -268.15119)
			(xy 379.948297 -268.179146) (xy 379.98379 -268.213238) (xy 380.013355 -268.252582) (xy 380.036226 -268.296159)
			(xy 380.05181 -268.34284) (xy 380.059705 -268.391417) (xy 380.0602 -268.416024) (xy 380.388888 -268.416024)
			(xy 380.392848 -268.36697) (xy 380.404625 -268.319186) (xy 380.423916 -268.27391) (xy 380.450219 -268.232314)
			(xy 380.482854 -268.195477) (xy 380.520975 -268.164352) (xy 380.563596 -268.139745) (xy 380.609612 -268.122293)
			(xy 380.657831 -268.112449) (xy 380.707006 -268.110468) (xy 380.755861 -268.1164) (xy 380.803132 -268.130092)
			(xy 380.847594 -268.15119) (xy 380.888097 -268.179146) (xy 380.92359 -268.213238) (xy 380.953155 -268.252582)
			(xy 380.976026 -268.296159) (xy 380.99161 -268.34284) (xy 380.999505 -268.391417) (xy 381 -268.416024)
			(xy 381.328942 -268.416024) (xy 381.332902 -268.36697) (xy 381.344679 -268.319186) (xy 381.36397 -268.27391)
			(xy 381.390273 -268.232314) (xy 381.422908 -268.195477) (xy 381.461029 -268.164352) (xy 381.50365 -268.139745)
			(xy 381.549666 -268.122293) (xy 381.597885 -268.112449) (xy 381.64706 -268.110468) (xy 381.695915 -268.1164)
			(xy 381.743186 -268.130092) (xy 381.787648 -268.15119) (xy 381.828151 -268.179146) (xy 381.863644 -268.213238)
			(xy 381.893209 -268.252582) (xy 381.91608 -268.296159) (xy 381.931664 -268.34284) (xy 381.939559 -268.391417)
			(xy 381.940054 -268.416024) (xy 382.268996 -268.416024) (xy 382.272956 -268.36697) (xy 382.284733 -268.319186)
			(xy 382.304024 -268.27391) (xy 382.330327 -268.232314) (xy 382.362962 -268.195477) (xy 382.401083 -268.164352)
			(xy 382.443704 -268.139745) (xy 382.48972 -268.122293) (xy 382.537939 -268.112449) (xy 382.587114 -268.110468)
			(xy 382.635969 -268.1164) (xy 382.68324 -268.130092) (xy 382.727702 -268.15119) (xy 382.768205 -268.179146)
			(xy 382.803698 -268.213238) (xy 382.833263 -268.252582) (xy 382.856134 -268.296159) (xy 382.871718 -268.34284)
			(xy 382.879613 -268.391417) (xy 382.880108 -268.416024) (xy 383.20905 -268.416024) (xy 383.21301 -268.36697)
			(xy 383.224787 -268.319186) (xy 383.244078 -268.27391) (xy 383.270381 -268.232314) (xy 383.303016 -268.195477)
			(xy 383.341137 -268.164352) (xy 383.383758 -268.139745) (xy 383.429774 -268.122293) (xy 383.477993 -268.112449)
			(xy 383.527168 -268.110468) (xy 383.576023 -268.1164) (xy 383.623294 -268.130092) (xy 383.667756 -268.15119)
			(xy 383.708259 -268.179146) (xy 383.743752 -268.213238) (xy 383.773317 -268.252582) (xy 383.796188 -268.296159)
			(xy 383.811772 -268.34284) (xy 383.819667 -268.391417) (xy 383.820162 -268.416024) (xy 384.149104 -268.416024)
			(xy 384.153064 -268.36697) (xy 384.164841 -268.319186) (xy 384.184132 -268.27391) (xy 384.210435 -268.232314)
			(xy 384.24307 -268.195477) (xy 384.281191 -268.164352) (xy 384.323812 -268.139745) (xy 384.369828 -268.122293)
			(xy 384.418047 -268.112449) (xy 384.467222 -268.110468) (xy 384.516077 -268.1164) (xy 384.563348 -268.130092)
			(xy 384.60781 -268.15119) (xy 384.648313 -268.179146) (xy 384.683806 -268.213238) (xy 384.713371 -268.252582)
			(xy 384.736242 -268.296159) (xy 384.751826 -268.34284) (xy 384.759721 -268.391417) (xy 384.760216 -268.416024)
			(xy 384.759721 -268.440631) (xy 384.751826 -268.489208) (xy 384.736242 -268.535889) (xy 384.713371 -268.579466)
			(xy 384.683806 -268.61881) (xy 384.648313 -268.652902) (xy 384.60781 -268.680858) (xy 384.563348 -268.701956)
			(xy 384.516077 -268.715648) (xy 384.467222 -268.72158) (xy 384.418047 -268.719599) (xy 384.369828 -268.709755)
			(xy 384.323812 -268.692303) (xy 384.281191 -268.667696) (xy 384.24307 -268.636571) (xy 384.210435 -268.599734)
			(xy 384.184132 -268.558138) (xy 384.164841 -268.512862) (xy 384.153064 -268.465078) (xy 384.149104 -268.416024)
			(xy 383.820162 -268.416024) (xy 383.819667 -268.440631) (xy 383.811772 -268.489208) (xy 383.796188 -268.535889)
			(xy 383.773317 -268.579466) (xy 383.743752 -268.61881) (xy 383.708259 -268.652902) (xy 383.667756 -268.680858)
			(xy 383.623294 -268.701956) (xy 383.576023 -268.715648) (xy 383.527168 -268.72158) (xy 383.477993 -268.719599)
			(xy 383.429774 -268.709755) (xy 383.383758 -268.692303) (xy 383.341137 -268.667696) (xy 383.303016 -268.636571)
			(xy 383.270381 -268.599734) (xy 383.244078 -268.558138) (xy 383.224787 -268.512862) (xy 383.21301 -268.465078)
			(xy 383.20905 -268.416024) (xy 382.880108 -268.416024) (xy 382.879613 -268.440631) (xy 382.871718 -268.489208)
			(xy 382.856134 -268.535889) (xy 382.833263 -268.579466) (xy 382.803698 -268.61881) (xy 382.768205 -268.652902)
			(xy 382.727702 -268.680858) (xy 382.68324 -268.701956) (xy 382.635969 -268.715648) (xy 382.587114 -268.72158)
			(xy 382.537939 -268.719599) (xy 382.48972 -268.709755) (xy 382.443704 -268.692303) (xy 382.401083 -268.667696)
			(xy 382.362962 -268.636571) (xy 382.330327 -268.599734) (xy 382.304024 -268.558138) (xy 382.284733 -268.512862)
			(xy 382.272956 -268.465078) (xy 382.268996 -268.416024) (xy 381.940054 -268.416024) (xy 381.939559 -268.440631)
			(xy 381.931664 -268.489208) (xy 381.91608 -268.535889) (xy 381.893209 -268.579466) (xy 381.863644 -268.61881)
			(xy 381.828151 -268.652902) (xy 381.787648 -268.680858) (xy 381.743186 -268.701956) (xy 381.695915 -268.715648)
			(xy 381.64706 -268.72158) (xy 381.597885 -268.719599) (xy 381.549666 -268.709755) (xy 381.50365 -268.692303)
			(xy 381.461029 -268.667696) (xy 381.422908 -268.636571) (xy 381.390273 -268.599734) (xy 381.36397 -268.558138)
			(xy 381.344679 -268.512862) (xy 381.332902 -268.465078) (xy 381.328942 -268.416024) (xy 381 -268.416024)
			(xy 380.999505 -268.440631) (xy 380.99161 -268.489208) (xy 380.976026 -268.535889) (xy 380.953155 -268.579466)
			(xy 380.92359 -268.61881) (xy 380.888097 -268.652902) (xy 380.847594 -268.680858) (xy 380.803132 -268.701956)
			(xy 380.755861 -268.715648) (xy 380.707006 -268.72158) (xy 380.657831 -268.719599) (xy 380.609612 -268.709755)
			(xy 380.563596 -268.692303) (xy 380.520975 -268.667696) (xy 380.482854 -268.636571) (xy 380.450219 -268.599734)
			(xy 380.423916 -268.558138) (xy 380.404625 -268.512862) (xy 380.392848 -268.465078) (xy 380.388888 -268.416024)
			(xy 380.0602 -268.416024) (xy 380.059705 -268.440631) (xy 380.05181 -268.489208) (xy 380.036226 -268.535889)
			(xy 380.013355 -268.579466) (xy 379.98379 -268.61881) (xy 379.948297 -268.652902) (xy 379.907794 -268.680858)
			(xy 379.863332 -268.701956) (xy 379.816061 -268.715648) (xy 379.767206 -268.72158) (xy 379.718031 -268.719599)
			(xy 379.669812 -268.709755) (xy 379.623796 -268.692303) (xy 379.581175 -268.667696) (xy 379.543054 -268.636571)
			(xy 379.510419 -268.599734) (xy 379.484116 -268.558138) (xy 379.464825 -268.512862) (xy 379.453048 -268.465078)
			(xy 379.449088 -268.416024) (xy 378.180092 -268.416024) (xy 378.179597 -268.440631) (xy 378.171702 -268.489208)
			(xy 378.156118 -268.535889) (xy 378.133247 -268.579466) (xy 378.103682 -268.61881) (xy 378.068189 -268.652902)
			(xy 378.027686 -268.680858) (xy 377.983224 -268.701956) (xy 377.935953 -268.715648) (xy 377.887098 -268.72158)
			(xy 377.837923 -268.719599) (xy 377.789704 -268.709755) (xy 377.743688 -268.692303) (xy 377.701067 -268.667696)
			(xy 377.662946 -268.636571) (xy 377.630311 -268.599734) (xy 377.604008 -268.558138) (xy 377.584717 -268.512862)
			(xy 377.57294 -268.465078) (xy 377.56898 -268.416024) (xy 377.240038 -268.416024) (xy 377.239543 -268.440631)
			(xy 377.231648 -268.489208) (xy 377.216064 -268.535889) (xy 377.193193 -268.579466) (xy 377.163628 -268.61881)
			(xy 377.128135 -268.652902) (xy 377.087632 -268.680858) (xy 377.04317 -268.701956) (xy 376.995899 -268.715648)
			(xy 376.947044 -268.72158) (xy 376.897869 -268.719599) (xy 376.84965 -268.709755) (xy 376.803634 -268.692303)
			(xy 376.761013 -268.667696) (xy 376.722892 -268.636571) (xy 376.690257 -268.599734) (xy 376.663954 -268.558138)
			(xy 376.644663 -268.512862) (xy 376.632886 -268.465078) (xy 376.628926 -268.416024) (xy 376.300238 -268.416024)
			(xy 376.299743 -268.440631) (xy 376.291848 -268.489208) (xy 376.276264 -268.535889) (xy 376.253393 -268.579466)
			(xy 376.223828 -268.61881) (xy 376.188335 -268.652902) (xy 376.147832 -268.680858) (xy 376.10337 -268.701956)
			(xy 376.056099 -268.715648) (xy 376.007244 -268.72158) (xy 375.958069 -268.719599) (xy 375.90985 -268.709755)
			(xy 375.863834 -268.692303) (xy 375.821213 -268.667696) (xy 375.783092 -268.636571) (xy 375.750457 -268.599734)
			(xy 375.724154 -268.558138) (xy 375.704863 -268.512862) (xy 375.693086 -268.465078) (xy 375.689126 -268.416024)
			(xy 375.397522 -268.416024) (xy 375.397522 -268.820138) (xy 375.398067 -268.830496) (xy 375.406323 -268.849503)
			(xy 375.413524 -268.856968) (xy 375.46788 -268.907768) (xy 375.475246 -268.91488) (xy 375.494296 -268.921992)
			(xy 375.505218 -268.92123) (xy 375.524522 -268.920722) (xy 375.52503 -268.920722) (xy 375.55027 -268.921261)
			(xy 375.600058 -268.929604) (xy 375.647794 -268.946024) (xy 375.692179 -268.970073) (xy 375.732003 -269.001097)
			(xy 375.76618 -269.03825) (xy 375.793779 -269.080519) (xy 375.814048 -269.126752) (xy 375.826434 -269.175691)
			(xy 375.830601 -269.226) (xy 375.830599 -269.22603) (xy 376.159026 -269.22603) (xy 376.162986 -269.176976)
			(xy 376.174763 -269.129192) (xy 376.194054 -269.083916) (xy 376.220357 -269.04232) (xy 376.252992 -269.005483)
			(xy 376.291113 -268.974358) (xy 376.333734 -268.949751) (xy 376.37975 -268.932299) (xy 376.427969 -268.922455)
			(xy 376.477144 -268.920474) (xy 376.525999 -268.926406) (xy 376.57327 -268.940098) (xy 376.617732 -268.961196)
			(xy 376.658235 -268.989152) (xy 376.693728 -269.023244) (xy 376.723293 -269.062588) (xy 376.746164 -269.106165)
			(xy 376.761748 -269.152846) (xy 376.769643 -269.201423) (xy 376.770138 -269.22603) (xy 377.088649 -269.22603)
			(xy 377.092744 -269.175302) (xy 377.104923 -269.125888) (xy 377.124871 -269.079068) (xy 377.152072 -269.036054)
			(xy 377.18582 -268.99796) (xy 377.225242 -268.965773) (xy 377.269316 -268.940327) (xy 377.316902 -268.92228)
			(xy 377.366766 -268.9121) (xy 377.417618 -268.910051) (xy 377.468139 -268.916185) (xy 377.517023 -268.930345)
			(xy 377.563002 -268.952162) (xy 377.604886 -268.981072) (xy 377.64159 -269.016327) (xy 377.672163 -269.057013)
			(xy 377.695814 -269.102076) (xy 377.71193 -269.15035) (xy 377.720094 -269.200584) (xy 377.720606 -269.22603)
			(xy 378.039134 -269.22603) (xy 378.043094 -269.176976) (xy 378.054871 -269.129192) (xy 378.074162 -269.083916)
			(xy 378.100465 -269.04232) (xy 378.1331 -269.005483) (xy 378.171221 -268.974358) (xy 378.213842 -268.949751)
			(xy 378.259858 -268.932299) (xy 378.308077 -268.922455) (xy 378.357252 -268.920474) (xy 378.406107 -268.926406)
			(xy 378.453378 -268.940098) (xy 378.49784 -268.961196) (xy 378.538343 -268.989152) (xy 378.573836 -269.023244)
			(xy 378.603401 -269.062588) (xy 378.626272 -269.106165) (xy 378.641856 -269.152846) (xy 378.649751 -269.201423)
			(xy 378.650246 -269.22603) (xy 378.978934 -269.22603) (xy 378.982894 -269.176976) (xy 378.994671 -269.129192)
			(xy 379.013962 -269.083916) (xy 379.040265 -269.04232) (xy 379.0729 -269.005483) (xy 379.111021 -268.974358)
			(xy 379.153642 -268.949751) (xy 379.199658 -268.932299) (xy 379.247877 -268.922455) (xy 379.297052 -268.920474)
			(xy 379.345907 -268.926406) (xy 379.393178 -268.940098) (xy 379.43764 -268.961196) (xy 379.478143 -268.989152)
			(xy 379.513636 -269.023244) (xy 379.543201 -269.062588) (xy 379.566072 -269.106165) (xy 379.581656 -269.152846)
			(xy 379.589551 -269.201423) (xy 379.590046 -269.22603) (xy 379.918988 -269.22603) (xy 379.922948 -269.176976)
			(xy 379.934725 -269.129192) (xy 379.954016 -269.083916) (xy 379.980319 -269.04232) (xy 380.012954 -269.005483)
			(xy 380.051075 -268.974358) (xy 380.093696 -268.949751) (xy 380.139712 -268.932299) (xy 380.187931 -268.922455)
			(xy 380.237106 -268.920474) (xy 380.285961 -268.926406) (xy 380.333232 -268.940098) (xy 380.377694 -268.961196)
			(xy 380.418197 -268.989152) (xy 380.45369 -269.023244) (xy 380.483255 -269.062588) (xy 380.506126 -269.106165)
			(xy 380.52171 -269.152846) (xy 380.529605 -269.201423) (xy 380.5301 -269.22603) (xy 380.848611 -269.22603)
			(xy 380.852706 -269.175302) (xy 380.864885 -269.125888) (xy 380.884833 -269.079068) (xy 380.912034 -269.036054)
			(xy 380.945782 -268.99796) (xy 380.985204 -268.965773) (xy 381.029278 -268.940327) (xy 381.076864 -268.92228)
			(xy 381.126728 -268.9121) (xy 381.17758 -268.910051) (xy 381.228101 -268.916185) (xy 381.276985 -268.930345)
			(xy 381.322964 -268.952162) (xy 381.364848 -268.981072) (xy 381.401552 -269.016327) (xy 381.432125 -269.057013)
			(xy 381.455776 -269.102076) (xy 381.471892 -269.15035) (xy 381.480056 -269.200584) (xy 381.480568 -269.22603)
			(xy 381.799096 -269.22603) (xy 381.803056 -269.176976) (xy 381.814833 -269.129192) (xy 381.834124 -269.083916)
			(xy 381.860427 -269.04232) (xy 381.893062 -269.005483) (xy 381.931183 -268.974358) (xy 381.973804 -268.949751)
			(xy 382.01982 -268.932299) (xy 382.068039 -268.922455) (xy 382.117214 -268.920474) (xy 382.166069 -268.926406)
			(xy 382.21334 -268.940098) (xy 382.257802 -268.961196) (xy 382.298305 -268.989152) (xy 382.333798 -269.023244)
			(xy 382.363363 -269.062588) (xy 382.386234 -269.106165) (xy 382.401818 -269.152846) (xy 382.409713 -269.201423)
			(xy 382.410208 -269.22603) (xy 382.738896 -269.22603) (xy 382.742856 -269.176976) (xy 382.754633 -269.129192)
			(xy 382.773924 -269.083916) (xy 382.800227 -269.04232) (xy 382.832862 -269.005483) (xy 382.870983 -268.974358)
			(xy 382.913604 -268.949751) (xy 382.95962 -268.932299) (xy 383.007839 -268.922455) (xy 383.057014 -268.920474)
			(xy 383.105869 -268.926406) (xy 383.15314 -268.940098) (xy 383.197602 -268.961196) (xy 383.238105 -268.989152)
			(xy 383.273598 -269.023244) (xy 383.303163 -269.062588) (xy 383.326034 -269.106165) (xy 383.341618 -269.152846)
			(xy 383.349513 -269.201423) (xy 383.350008 -269.22603) (xy 383.67895 -269.22603) (xy 383.68291 -269.176976)
			(xy 383.694687 -269.129192) (xy 383.713978 -269.083916) (xy 383.740281 -269.04232) (xy 383.772916 -269.005483)
			(xy 383.811037 -268.974358) (xy 383.853658 -268.949751) (xy 383.899674 -268.932299) (xy 383.947893 -268.922455)
			(xy 383.997068 -268.920474) (xy 384.045923 -268.926406) (xy 384.093194 -268.940098) (xy 384.137656 -268.961196)
			(xy 384.178159 -268.989152) (xy 384.213652 -269.023244) (xy 384.243217 -269.062588) (xy 384.266088 -269.106165)
			(xy 384.281672 -269.152846) (xy 384.289567 -269.201423) (xy 384.290062 -269.22603) (xy 384.619004 -269.22603)
			(xy 384.622964 -269.176976) (xy 384.634741 -269.129192) (xy 384.654032 -269.083916) (xy 384.680335 -269.04232)
			(xy 384.71297 -269.005483) (xy 384.751091 -268.974358) (xy 384.793712 -268.949751) (xy 384.839728 -268.932299)
			(xy 384.887947 -268.922455) (xy 384.937122 -268.920474) (xy 384.985977 -268.926406) (xy 385.033248 -268.940098)
			(xy 385.07771 -268.961196) (xy 385.118213 -268.989152) (xy 385.153706 -269.023244) (xy 385.183271 -269.062588)
			(xy 385.206142 -269.106165) (xy 385.221726 -269.152846) (xy 385.229621 -269.201423) (xy 385.230116 -269.22603)
			(xy 385.229621 -269.250637) (xy 385.221726 -269.299214) (xy 385.206142 -269.345895) (xy 385.183271 -269.389472)
			(xy 385.153706 -269.428816) (xy 385.118213 -269.462908) (xy 385.07771 -269.490864) (xy 385.033248 -269.511962)
			(xy 384.985977 -269.525654) (xy 384.937122 -269.531586) (xy 384.887947 -269.529605) (xy 384.839728 -269.519761)
			(xy 384.793712 -269.502309) (xy 384.751091 -269.477702) (xy 384.71297 -269.446577) (xy 384.680335 -269.40974)
			(xy 384.654032 -269.368144) (xy 384.634741 -269.322868) (xy 384.622964 -269.275084) (xy 384.619004 -269.22603)
			(xy 384.290062 -269.22603) (xy 384.289567 -269.250637) (xy 384.281672 -269.299214) (xy 384.266088 -269.345895)
			(xy 384.243217 -269.389472) (xy 384.213652 -269.428816) (xy 384.178159 -269.462908) (xy 384.137656 -269.490864)
			(xy 384.093194 -269.511962) (xy 384.045923 -269.525654) (xy 383.997068 -269.531586) (xy 383.947893 -269.529605)
			(xy 383.899674 -269.519761) (xy 383.853658 -269.502309) (xy 383.811037 -269.477702) (xy 383.772916 -269.446577)
			(xy 383.740281 -269.40974) (xy 383.713978 -269.368144) (xy 383.694687 -269.322868) (xy 383.68291 -269.275084)
			(xy 383.67895 -269.22603) (xy 383.350008 -269.22603) (xy 383.349513 -269.250637) (xy 383.341618 -269.299214)
			(xy 383.326034 -269.345895) (xy 383.303163 -269.389472) (xy 383.273598 -269.428816) (xy 383.238105 -269.462908)
			(xy 383.197602 -269.490864) (xy 383.15314 -269.511962) (xy 383.105869 -269.525654) (xy 383.057014 -269.531586)
			(xy 383.007839 -269.529605) (xy 382.95962 -269.519761) (xy 382.913604 -269.502309) (xy 382.870983 -269.477702)
			(xy 382.832862 -269.446577) (xy 382.800227 -269.40974) (xy 382.773924 -269.368144) (xy 382.754633 -269.322868)
			(xy 382.742856 -269.275084) (xy 382.738896 -269.22603) (xy 382.410208 -269.22603) (xy 382.409713 -269.250637)
			(xy 382.401818 -269.299214) (xy 382.386234 -269.345895) (xy 382.363363 -269.389472) (xy 382.333798 -269.428816)
			(xy 382.298305 -269.462908) (xy 382.257802 -269.490864) (xy 382.21334 -269.511962) (xy 382.166069 -269.525654)
			(xy 382.117214 -269.531586) (xy 382.068039 -269.529605) (xy 382.01982 -269.519761) (xy 381.973804 -269.502309)
			(xy 381.931183 -269.477702) (xy 381.893062 -269.446577) (xy 381.860427 -269.40974) (xy 381.834124 -269.368144)
			(xy 381.814833 -269.322868) (xy 381.803056 -269.275084) (xy 381.799096 -269.22603) (xy 381.480568 -269.22603)
			(xy 381.480056 -269.251476) (xy 381.471892 -269.30171) (xy 381.455776 -269.349984) (xy 381.432125 -269.395047)
			(xy 381.401552 -269.435733) (xy 381.364848 -269.470988) (xy 381.322964 -269.499898) (xy 381.276985 -269.521715)
			(xy 381.228101 -269.535875) (xy 381.17758 -269.542009) (xy 381.126728 -269.53996) (xy 381.076864 -269.52978)
			(xy 381.029278 -269.511733) (xy 380.985204 -269.486287) (xy 380.945782 -269.4541) (xy 380.912034 -269.416006)
			(xy 380.884833 -269.372992) (xy 380.864885 -269.326172) (xy 380.852706 -269.276758) (xy 380.848611 -269.22603)
			(xy 380.5301 -269.22603) (xy 380.529605 -269.250637) (xy 380.52171 -269.299214) (xy 380.506126 -269.345895)
			(xy 380.483255 -269.389472) (xy 380.45369 -269.428816) (xy 380.418197 -269.462908) (xy 380.377694 -269.490864)
			(xy 380.333232 -269.511962) (xy 380.285961 -269.525654) (xy 380.237106 -269.531586) (xy 380.187931 -269.529605)
			(xy 380.139712 -269.519761) (xy 380.093696 -269.502309) (xy 380.051075 -269.477702) (xy 380.012954 -269.446577)
			(xy 379.980319 -269.40974) (xy 379.954016 -269.368144) (xy 379.934725 -269.322868) (xy 379.922948 -269.275084)
			(xy 379.918988 -269.22603) (xy 379.590046 -269.22603) (xy 379.589551 -269.250637) (xy 379.581656 -269.299214)
			(xy 379.566072 -269.345895) (xy 379.543201 -269.389472) (xy 379.513636 -269.428816) (xy 379.478143 -269.462908)
			(xy 379.43764 -269.490864) (xy 379.393178 -269.511962) (xy 379.345907 -269.525654) (xy 379.297052 -269.531586)
			(xy 379.247877 -269.529605) (xy 379.199658 -269.519761) (xy 379.153642 -269.502309) (xy 379.111021 -269.477702)
			(xy 379.0729 -269.446577) (xy 379.040265 -269.40974) (xy 379.013962 -269.368144) (xy 378.994671 -269.322868)
			(xy 378.982894 -269.275084) (xy 378.978934 -269.22603) (xy 378.650246 -269.22603) (xy 378.649751 -269.250637)
			(xy 378.641856 -269.299214) (xy 378.626272 -269.345895) (xy 378.603401 -269.389472) (xy 378.573836 -269.428816)
			(xy 378.538343 -269.462908) (xy 378.49784 -269.490864) (xy 378.453378 -269.511962) (xy 378.406107 -269.525654)
			(xy 378.357252 -269.531586) (xy 378.308077 -269.529605) (xy 378.259858 -269.519761) (xy 378.213842 -269.502309)
			(xy 378.171221 -269.477702) (xy 378.1331 -269.446577) (xy 378.100465 -269.40974) (xy 378.074162 -269.368144)
			(xy 378.054871 -269.322868) (xy 378.043094 -269.275084) (xy 378.039134 -269.22603) (xy 377.720606 -269.22603)
			(xy 377.720094 -269.251476) (xy 377.71193 -269.30171) (xy 377.695814 -269.349984) (xy 377.672163 -269.395047)
			(xy 377.64159 -269.435733) (xy 377.604886 -269.470988) (xy 377.563002 -269.499898) (xy 377.517023 -269.521715)
			(xy 377.468139 -269.535875) (xy 377.417618 -269.542009) (xy 377.366766 -269.53996) (xy 377.316902 -269.52978)
			(xy 377.269316 -269.511733) (xy 377.225242 -269.486287) (xy 377.18582 -269.4541) (xy 377.152072 -269.416006)
			(xy 377.124871 -269.372992) (xy 377.104923 -269.326172) (xy 377.092744 -269.276758) (xy 377.088649 -269.22603)
			(xy 376.770138 -269.22603) (xy 376.769643 -269.250637) (xy 376.761748 -269.299214) (xy 376.746164 -269.345895)
			(xy 376.723293 -269.389472) (xy 376.693728 -269.428816) (xy 376.658235 -269.462908) (xy 376.617732 -269.490864)
			(xy 376.57327 -269.511962) (xy 376.525999 -269.525654) (xy 376.477144 -269.531586) (xy 376.427969 -269.529605)
			(xy 376.37975 -269.519761) (xy 376.333734 -269.502309) (xy 376.291113 -269.477702) (xy 376.252992 -269.446577)
			(xy 376.220357 -269.40974) (xy 376.194054 -269.368144) (xy 376.174763 -269.322868) (xy 376.162986 -269.275084)
			(xy 376.159026 -269.22603) (xy 375.830599 -269.22603) (xy 375.826434 -269.276309) (xy 375.814048 -269.325248)
			(xy 375.793779 -269.371481) (xy 375.76618 -269.41375) (xy 375.732003 -269.450903) (xy 375.692179 -269.481927)
			(xy 375.647794 -269.505976) (xy 375.600058 -269.522396) (xy 375.55027 -269.530739) (xy 375.52503 -269.531338)
			(xy 375.524522 -269.531338) (xy 375.505218 -269.53083) (xy 375.494296 -269.530068) (xy 375.475246 -269.53718)
			(xy 375.46788 -269.544292) (xy 375.413524 -269.595092) (xy 375.406287 -269.602536) (xy 375.398011 -269.621553)
			(xy 375.397522 -269.631922) (xy 375.397522 -270.036036) (xy 375.678695 -270.036036) (xy 375.68279 -269.985308)
			(xy 375.694969 -269.935894) (xy 375.714917 -269.889074) (xy 375.742118 -269.84606) (xy 375.775866 -269.807966)
			(xy 375.815288 -269.775779) (xy 375.859362 -269.750333) (xy 375.906948 -269.732286) (xy 375.956812 -269.722106)
			(xy 376.007664 -269.720057) (xy 376.058185 -269.726191) (xy 376.107069 -269.740351) (xy 376.153048 -269.762168)
			(xy 376.194932 -269.791078) (xy 376.231636 -269.826333) (xy 376.262209 -269.867019) (xy 376.28586 -269.912082)
			(xy 376.301976 -269.960356) (xy 376.31014 -270.01059) (xy 376.310652 -270.036036) (xy 376.628926 -270.036036)
			(xy 376.632886 -269.986982) (xy 376.644663 -269.939198) (xy 376.663954 -269.893922) (xy 376.690257 -269.852326)
			(xy 376.722892 -269.815489) (xy 376.761013 -269.784364) (xy 376.803634 -269.759757) (xy 376.84965 -269.742305)
			(xy 376.897869 -269.732461) (xy 376.947044 -269.73048) (xy 376.995899 -269.736412) (xy 377.04317 -269.750104)
			(xy 377.087632 -269.771202) (xy 377.128135 -269.799158) (xy 377.163628 -269.83325) (xy 377.193193 -269.872594)
			(xy 377.216064 -269.916171) (xy 377.231648 -269.962852) (xy 377.239543 -270.011429) (xy 377.240038 -270.036036)
			(xy 377.558549 -270.036036) (xy 377.562644 -269.985308) (xy 377.574823 -269.935894) (xy 377.594771 -269.889074)
			(xy 377.621972 -269.84606) (xy 377.65572 -269.807966) (xy 377.695142 -269.775779) (xy 377.739216 -269.750333)
			(xy 377.786802 -269.732286) (xy 377.836666 -269.722106) (xy 377.887518 -269.720057) (xy 377.938039 -269.726191)
			(xy 377.986923 -269.740351) (xy 378.032902 -269.762168) (xy 378.074786 -269.791078) (xy 378.11149 -269.826333)
			(xy 378.142063 -269.867019) (xy 378.165714 -269.912082) (xy 378.18183 -269.960356) (xy 378.189994 -270.01059)
			(xy 378.190506 -270.036036) (xy 378.509034 -270.036036) (xy 378.512994 -269.986982) (xy 378.524771 -269.939198)
			(xy 378.544062 -269.893922) (xy 378.570365 -269.852326) (xy 378.603 -269.815489) (xy 378.641121 -269.784364)
			(xy 378.683742 -269.759757) (xy 378.729758 -269.742305) (xy 378.777977 -269.732461) (xy 378.827152 -269.73048)
			(xy 378.876007 -269.736412) (xy 378.923278 -269.750104) (xy 378.96774 -269.771202) (xy 379.008243 -269.799158)
			(xy 379.043736 -269.83325) (xy 379.073301 -269.872594) (xy 379.096172 -269.916171) (xy 379.111756 -269.962852)
			(xy 379.119651 -270.011429) (xy 379.120146 -270.036036) (xy 379.438657 -270.036036) (xy 379.442752 -269.985308)
			(xy 379.454931 -269.935894) (xy 379.474879 -269.889074) (xy 379.50208 -269.84606) (xy 379.535828 -269.807966)
			(xy 379.57525 -269.775779) (xy 379.619324 -269.750333) (xy 379.66691 -269.732286) (xy 379.716774 -269.722106)
			(xy 379.767626 -269.720057) (xy 379.818147 -269.726191) (xy 379.867031 -269.740351) (xy 379.91301 -269.762168)
			(xy 379.954894 -269.791078) (xy 379.991598 -269.826333) (xy 380.022171 -269.867019) (xy 380.045822 -269.912082)
			(xy 380.061938 -269.960356) (xy 380.070102 -270.01059) (xy 380.070614 -270.036036) (xy 380.378711 -270.036036)
			(xy 380.382806 -269.985308) (xy 380.394985 -269.935894) (xy 380.414933 -269.889074) (xy 380.442134 -269.84606)
			(xy 380.475882 -269.807966) (xy 380.515304 -269.775779) (xy 380.559378 -269.750333) (xy 380.606964 -269.732286)
			(xy 380.656828 -269.722106) (xy 380.70768 -269.720057) (xy 380.758201 -269.726191) (xy 380.807085 -269.740351)
			(xy 380.853064 -269.762168) (xy 380.894948 -269.791078) (xy 380.931652 -269.826333) (xy 380.962225 -269.867019)
			(xy 380.985876 -269.912082) (xy 381.001992 -269.960356) (xy 381.010156 -270.01059) (xy 381.010668 -270.036036)
			(xy 381.328942 -270.036036) (xy 381.332902 -269.986982) (xy 381.344679 -269.939198) (xy 381.36397 -269.893922)
			(xy 381.390273 -269.852326) (xy 381.422908 -269.815489) (xy 381.461029 -269.784364) (xy 381.50365 -269.759757)
			(xy 381.549666 -269.742305) (xy 381.597885 -269.732461) (xy 381.64706 -269.73048) (xy 381.695915 -269.736412)
			(xy 381.743186 -269.750104) (xy 381.787648 -269.771202) (xy 381.828151 -269.799158) (xy 381.863644 -269.83325)
			(xy 381.893209 -269.872594) (xy 381.91608 -269.916171) (xy 381.931664 -269.962852) (xy 381.939559 -270.011429)
			(xy 381.940054 -270.036036) (xy 382.268996 -270.036036) (xy 382.272956 -269.986982) (xy 382.284733 -269.939198)
			(xy 382.304024 -269.893922) (xy 382.330327 -269.852326) (xy 382.362962 -269.815489) (xy 382.401083 -269.784364)
			(xy 382.443704 -269.759757) (xy 382.48972 -269.742305) (xy 382.537939 -269.732461) (xy 382.587114 -269.73048)
			(xy 382.635969 -269.736412) (xy 382.68324 -269.750104) (xy 382.727702 -269.771202) (xy 382.768205 -269.799158)
			(xy 382.803698 -269.83325) (xy 382.833263 -269.872594) (xy 382.856134 -269.916171) (xy 382.871718 -269.962852)
			(xy 382.879613 -270.011429) (xy 382.880108 -270.036036) (xy 383.20905 -270.036036) (xy 383.21301 -269.986982)
			(xy 383.224787 -269.939198) (xy 383.244078 -269.893922) (xy 383.270381 -269.852326) (xy 383.303016 -269.815489)
			(xy 383.341137 -269.784364) (xy 383.383758 -269.759757) (xy 383.429774 -269.742305) (xy 383.477993 -269.732461)
			(xy 383.527168 -269.73048) (xy 383.576023 -269.736412) (xy 383.623294 -269.750104) (xy 383.667756 -269.771202)
			(xy 383.708259 -269.799158) (xy 383.743752 -269.83325) (xy 383.773317 -269.872594) (xy 383.796188 -269.916171)
			(xy 383.811772 -269.962852) (xy 383.819667 -270.011429) (xy 383.820162 -270.036036) (xy 384.149104 -270.036036)
			(xy 384.153064 -269.986982) (xy 384.164841 -269.939198) (xy 384.184132 -269.893922) (xy 384.210435 -269.852326)
			(xy 384.24307 -269.815489) (xy 384.281191 -269.784364) (xy 384.323812 -269.759757) (xy 384.369828 -269.742305)
			(xy 384.418047 -269.732461) (xy 384.467222 -269.73048) (xy 384.516077 -269.736412) (xy 384.563348 -269.750104)
			(xy 384.60781 -269.771202) (xy 384.648313 -269.799158) (xy 384.683806 -269.83325) (xy 384.713371 -269.872594)
			(xy 384.736242 -269.916171) (xy 384.751826 -269.962852) (xy 384.759721 -270.011429) (xy 384.760216 -270.036036)
			(xy 384.759721 -270.060643) (xy 384.751826 -270.10922) (xy 384.736242 -270.155901) (xy 384.713371 -270.199478)
			(xy 384.683806 -270.238822) (xy 384.648313 -270.272914) (xy 384.60781 -270.30087) (xy 384.563348 -270.321968)
			(xy 384.516077 -270.33566) (xy 384.467222 -270.341592) (xy 384.418047 -270.339611) (xy 384.369828 -270.329767)
			(xy 384.323812 -270.312315) (xy 384.281191 -270.287708) (xy 384.24307 -270.256583) (xy 384.210435 -270.219746)
			(xy 384.184132 -270.17815) (xy 384.164841 -270.132874) (xy 384.153064 -270.08509) (xy 384.149104 -270.036036)
			(xy 383.820162 -270.036036) (xy 383.819667 -270.060643) (xy 383.811772 -270.10922) (xy 383.796188 -270.155901)
			(xy 383.773317 -270.199478) (xy 383.743752 -270.238822) (xy 383.708259 -270.272914) (xy 383.667756 -270.30087)
			(xy 383.623294 -270.321968) (xy 383.576023 -270.33566) (xy 383.527168 -270.341592) (xy 383.477993 -270.339611)
			(xy 383.429774 -270.329767) (xy 383.383758 -270.312315) (xy 383.341137 -270.287708) (xy 383.303016 -270.256583)
			(xy 383.270381 -270.219746) (xy 383.244078 -270.17815) (xy 383.224787 -270.132874) (xy 383.21301 -270.08509)
			(xy 383.20905 -270.036036) (xy 382.880108 -270.036036) (xy 382.879613 -270.060643) (xy 382.871718 -270.10922)
			(xy 382.856134 -270.155901) (xy 382.833263 -270.199478) (xy 382.803698 -270.238822) (xy 382.768205 -270.272914)
			(xy 382.727702 -270.30087) (xy 382.68324 -270.321968) (xy 382.635969 -270.33566) (xy 382.587114 -270.341592)
			(xy 382.537939 -270.339611) (xy 382.48972 -270.329767) (xy 382.443704 -270.312315) (xy 382.401083 -270.287708)
			(xy 382.362962 -270.256583) (xy 382.330327 -270.219746) (xy 382.304024 -270.17815) (xy 382.284733 -270.132874)
			(xy 382.272956 -270.08509) (xy 382.268996 -270.036036) (xy 381.940054 -270.036036) (xy 381.939559 -270.060643)
			(xy 381.931664 -270.10922) (xy 381.91608 -270.155901) (xy 381.893209 -270.199478) (xy 381.863644 -270.238822)
			(xy 381.828151 -270.272914) (xy 381.787648 -270.30087) (xy 381.743186 -270.321968) (xy 381.695915 -270.33566)
			(xy 381.64706 -270.341592) (xy 381.597885 -270.339611) (xy 381.549666 -270.329767) (xy 381.50365 -270.312315)
			(xy 381.461029 -270.287708) (xy 381.422908 -270.256583) (xy 381.390273 -270.219746) (xy 381.36397 -270.17815)
			(xy 381.344679 -270.132874) (xy 381.332902 -270.08509) (xy 381.328942 -270.036036) (xy 381.010668 -270.036036)
			(xy 381.010156 -270.061482) (xy 381.001992 -270.111716) (xy 380.985876 -270.15999) (xy 380.962225 -270.205053)
			(xy 380.931652 -270.245739) (xy 380.894948 -270.280994) (xy 380.853064 -270.309904) (xy 380.807085 -270.331721)
			(xy 380.758201 -270.345881) (xy 380.70768 -270.352015) (xy 380.656828 -270.349966) (xy 380.606964 -270.339786)
			(xy 380.559378 -270.321739) (xy 380.515304 -270.296293) (xy 380.475882 -270.264106) (xy 380.442134 -270.226012)
			(xy 380.414933 -270.182998) (xy 380.394985 -270.136178) (xy 380.382806 -270.086764) (xy 380.378711 -270.036036)
			(xy 380.070614 -270.036036) (xy 380.070102 -270.061482) (xy 380.061938 -270.111716) (xy 380.045822 -270.15999)
			(xy 380.022171 -270.205053) (xy 379.991598 -270.245739) (xy 379.954894 -270.280994) (xy 379.91301 -270.309904)
			(xy 379.867031 -270.331721) (xy 379.818147 -270.345881) (xy 379.767626 -270.352015) (xy 379.716774 -270.349966)
			(xy 379.66691 -270.339786) (xy 379.619324 -270.321739) (xy 379.57525 -270.296293) (xy 379.535828 -270.264106)
			(xy 379.50208 -270.226012) (xy 379.474879 -270.182998) (xy 379.454931 -270.136178) (xy 379.442752 -270.086764)
			(xy 379.438657 -270.036036) (xy 379.120146 -270.036036) (xy 379.119651 -270.060643) (xy 379.111756 -270.10922)
			(xy 379.096172 -270.155901) (xy 379.073301 -270.199478) (xy 379.043736 -270.238822) (xy 379.008243 -270.272914)
			(xy 378.96774 -270.30087) (xy 378.923278 -270.321968) (xy 378.876007 -270.33566) (xy 378.827152 -270.341592)
			(xy 378.777977 -270.339611) (xy 378.729758 -270.329767) (xy 378.683742 -270.312315) (xy 378.641121 -270.287708)
			(xy 378.603 -270.256583) (xy 378.570365 -270.219746) (xy 378.544062 -270.17815) (xy 378.524771 -270.132874)
			(xy 378.512994 -270.08509) (xy 378.509034 -270.036036) (xy 378.190506 -270.036036) (xy 378.189994 -270.061482)
			(xy 378.18183 -270.111716) (xy 378.165714 -270.15999) (xy 378.142063 -270.205053) (xy 378.11149 -270.245739)
			(xy 378.074786 -270.280994) (xy 378.032902 -270.309904) (xy 377.986923 -270.331721) (xy 377.938039 -270.345881)
			(xy 377.887518 -270.352015) (xy 377.836666 -270.349966) (xy 377.786802 -270.339786) (xy 377.739216 -270.321739)
			(xy 377.695142 -270.296293) (xy 377.65572 -270.264106) (xy 377.621972 -270.226012) (xy 377.594771 -270.182998)
			(xy 377.574823 -270.136178) (xy 377.562644 -270.086764) (xy 377.558549 -270.036036) (xy 377.240038 -270.036036)
			(xy 377.239543 -270.060643) (xy 377.231648 -270.10922) (xy 377.216064 -270.155901) (xy 377.193193 -270.199478)
			(xy 377.163628 -270.238822) (xy 377.128135 -270.272914) (xy 377.087632 -270.30087) (xy 377.04317 -270.321968)
			(xy 376.995899 -270.33566) (xy 376.947044 -270.341592) (xy 376.897869 -270.339611) (xy 376.84965 -270.329767)
			(xy 376.803634 -270.312315) (xy 376.761013 -270.287708) (xy 376.722892 -270.256583) (xy 376.690257 -270.219746)
			(xy 376.663954 -270.17815) (xy 376.644663 -270.132874) (xy 376.632886 -270.08509) (xy 376.628926 -270.036036)
			(xy 376.310652 -270.036036) (xy 376.31014 -270.061482) (xy 376.301976 -270.111716) (xy 376.28586 -270.15999)
			(xy 376.262209 -270.205053) (xy 376.231636 -270.245739) (xy 376.194932 -270.280994) (xy 376.153048 -270.309904)
			(xy 376.107069 -270.331721) (xy 376.058185 -270.345881) (xy 376.007664 -270.352015) (xy 375.956812 -270.349966)
			(xy 375.906948 -270.339786) (xy 375.859362 -270.321739) (xy 375.815288 -270.296293) (xy 375.775866 -270.264106)
			(xy 375.742118 -270.226012) (xy 375.714917 -270.182998) (xy 375.694969 -270.136178) (xy 375.68279 -270.086764)
			(xy 375.678695 -270.036036) (xy 375.397522 -270.036036) (xy 375.397522 -270.59636) (xy 375.399554 -270.61033)
			(xy 375.401332 -270.61668) (xy 375.404888 -270.622776) (xy 375.405142 -270.62303) (xy 375.408405 -270.628937)
			(xy 375.411995 -270.64194) (xy 375.412254 -270.648684) (xy 375.412254 -270.846042) (xy 376.148595 -270.846042)
			(xy 376.15269 -270.795314) (xy 376.164869 -270.7459) (xy 376.184817 -270.69908) (xy 376.212018 -270.656066)
			(xy 376.245766 -270.617972) (xy 376.285188 -270.585785) (xy 376.329262 -270.560339) (xy 376.376848 -270.542292)
			(xy 376.426712 -270.532112) (xy 376.477564 -270.530063) (xy 376.528085 -270.536197) (xy 376.576969 -270.550357)
			(xy 376.622948 -270.572174) (xy 376.664832 -270.601084) (xy 376.701536 -270.636339) (xy 376.732109 -270.677025)
			(xy 376.75576 -270.722088) (xy 376.771876 -270.770362) (xy 376.78004 -270.820596) (xy 376.780552 -270.846042)
			(xy 377.088649 -270.846042) (xy 377.092744 -270.795314) (xy 377.104923 -270.7459) (xy 377.124871 -270.69908)
			(xy 377.152072 -270.656066) (xy 377.18582 -270.617972) (xy 377.225242 -270.585785) (xy 377.269316 -270.560339)
			(xy 377.316902 -270.542292) (xy 377.366766 -270.532112) (xy 377.417618 -270.530063) (xy 377.468139 -270.536197)
			(xy 377.517023 -270.550357) (xy 377.563002 -270.572174) (xy 377.604886 -270.601084) (xy 377.64159 -270.636339)
			(xy 377.672163 -270.677025) (xy 377.695814 -270.722088) (xy 377.71193 -270.770362) (xy 377.720094 -270.820596)
			(xy 377.720606 -270.846042) (xy 378.968503 -270.846042) (xy 378.972598 -270.795314) (xy 378.984777 -270.7459)
			(xy 379.004725 -270.69908) (xy 379.031926 -270.656066) (xy 379.065674 -270.617972) (xy 379.105096 -270.585785)
			(xy 379.14917 -270.560339) (xy 379.196756 -270.542292) (xy 379.24662 -270.532112) (xy 379.297472 -270.530063)
			(xy 379.347993 -270.536197) (xy 379.396877 -270.550357) (xy 379.442856 -270.572174) (xy 379.48474 -270.601084)
			(xy 379.521444 -270.636339) (xy 379.552017 -270.677025) (xy 379.575668 -270.722088) (xy 379.591784 -270.770362)
			(xy 379.599948 -270.820596) (xy 379.60046 -270.846042) (xy 379.918988 -270.846042) (xy 379.922948 -270.796988)
			(xy 379.934725 -270.749204) (xy 379.954016 -270.703928) (xy 379.980319 -270.662332) (xy 380.012954 -270.625495)
			(xy 380.051075 -270.59437) (xy 380.093696 -270.569763) (xy 380.139712 -270.552311) (xy 380.187931 -270.542467)
			(xy 380.237106 -270.540486) (xy 380.285961 -270.546418) (xy 380.333232 -270.56011) (xy 380.377694 -270.581208)
			(xy 380.418197 -270.609164) (xy 380.45369 -270.643256) (xy 380.483255 -270.6826) (xy 380.506126 -270.726177)
			(xy 380.52171 -270.772858) (xy 380.529605 -270.821435) (xy 380.5301 -270.846042) (xy 380.848611 -270.846042)
			(xy 380.852706 -270.795314) (xy 380.864885 -270.7459) (xy 380.884833 -270.69908) (xy 380.912034 -270.656066)
			(xy 380.945782 -270.617972) (xy 380.985204 -270.585785) (xy 381.029278 -270.560339) (xy 381.076864 -270.542292)
			(xy 381.126728 -270.532112) (xy 381.17758 -270.530063) (xy 381.228101 -270.536197) (xy 381.276985 -270.550357)
			(xy 381.322964 -270.572174) (xy 381.364848 -270.601084) (xy 381.401552 -270.636339) (xy 381.432125 -270.677025)
			(xy 381.455776 -270.722088) (xy 381.471892 -270.770362) (xy 381.480056 -270.820596) (xy 381.480568 -270.846042)
			(xy 381.799096 -270.846042) (xy 381.803056 -270.796988) (xy 381.814833 -270.749204) (xy 381.834124 -270.703928)
			(xy 381.860427 -270.662332) (xy 381.893062 -270.625495) (xy 381.931183 -270.59437) (xy 381.973804 -270.569763)
			(xy 382.01982 -270.552311) (xy 382.068039 -270.542467) (xy 382.117214 -270.540486) (xy 382.166069 -270.546418)
			(xy 382.21334 -270.56011) (xy 382.257802 -270.581208) (xy 382.298305 -270.609164) (xy 382.333798 -270.643256)
			(xy 382.363363 -270.6826) (xy 382.386234 -270.726177) (xy 382.401818 -270.772858) (xy 382.409713 -270.821435)
			(xy 382.410208 -270.846042) (xy 382.738896 -270.846042) (xy 382.742856 -270.796988) (xy 382.754633 -270.749204)
			(xy 382.773924 -270.703928) (xy 382.800227 -270.662332) (xy 382.832862 -270.625495) (xy 382.870983 -270.59437)
			(xy 382.913604 -270.569763) (xy 382.95962 -270.552311) (xy 383.007839 -270.542467) (xy 383.057014 -270.540486)
			(xy 383.105869 -270.546418) (xy 383.15314 -270.56011) (xy 383.197602 -270.581208) (xy 383.238105 -270.609164)
			(xy 383.273598 -270.643256) (xy 383.303163 -270.6826) (xy 383.326034 -270.726177) (xy 383.341618 -270.772858)
			(xy 383.349513 -270.821435) (xy 383.350008 -270.846042) (xy 383.67895 -270.846042) (xy 383.68291 -270.796988)
			(xy 383.694687 -270.749204) (xy 383.713978 -270.703928) (xy 383.740281 -270.662332) (xy 383.772916 -270.625495)
			(xy 383.811037 -270.59437) (xy 383.853658 -270.569763) (xy 383.899674 -270.552311) (xy 383.947893 -270.542467)
			(xy 383.997068 -270.540486) (xy 384.045923 -270.546418) (xy 384.093194 -270.56011) (xy 384.137656 -270.581208)
			(xy 384.178159 -270.609164) (xy 384.213652 -270.643256) (xy 384.243217 -270.6826) (xy 384.266088 -270.726177)
			(xy 384.281672 -270.772858) (xy 384.289567 -270.821435) (xy 384.290062 -270.846042) (xy 384.289567 -270.870649)
			(xy 384.281672 -270.919226) (xy 384.266088 -270.965907) (xy 384.243217 -271.009484) (xy 384.213652 -271.048828)
			(xy 384.178159 -271.08292) (xy 384.137656 -271.110876) (xy 384.093194 -271.131974) (xy 384.045923 -271.145666)
			(xy 383.997068 -271.151598) (xy 383.947893 -271.149617) (xy 383.899674 -271.139773) (xy 383.853658 -271.122321)
			(xy 383.811037 -271.097714) (xy 383.772916 -271.066589) (xy 383.740281 -271.029752) (xy 383.713978 -270.988156)
			(xy 383.694687 -270.94288) (xy 383.68291 -270.895096) (xy 383.67895 -270.846042) (xy 383.350008 -270.846042)
			(xy 383.349513 -270.870649) (xy 383.341618 -270.919226) (xy 383.326034 -270.965907) (xy 383.303163 -271.009484)
			(xy 383.273598 -271.048828) (xy 383.238105 -271.08292) (xy 383.197602 -271.110876) (xy 383.15314 -271.131974)
			(xy 383.105869 -271.145666) (xy 383.057014 -271.151598) (xy 383.007839 -271.149617) (xy 382.95962 -271.139773)
			(xy 382.913604 -271.122321) (xy 382.870983 -271.097714) (xy 382.832862 -271.066589) (xy 382.800227 -271.029752)
			(xy 382.773924 -270.988156) (xy 382.754633 -270.94288) (xy 382.742856 -270.895096) (xy 382.738896 -270.846042)
			(xy 382.410208 -270.846042) (xy 382.409713 -270.870649) (xy 382.401818 -270.919226) (xy 382.386234 -270.965907)
			(xy 382.363363 -271.009484) (xy 382.333798 -271.048828) (xy 382.298305 -271.08292) (xy 382.257802 -271.110876)
			(xy 382.21334 -271.131974) (xy 382.166069 -271.145666) (xy 382.117214 -271.151598) (xy 382.068039 -271.149617)
			(xy 382.01982 -271.139773) (xy 381.973804 -271.122321) (xy 381.931183 -271.097714) (xy 381.893062 -271.066589)
			(xy 381.860427 -271.029752) (xy 381.834124 -270.988156) (xy 381.814833 -270.94288) (xy 381.803056 -270.895096)
			(xy 381.799096 -270.846042) (xy 381.480568 -270.846042) (xy 381.480056 -270.871488) (xy 381.471892 -270.921722)
			(xy 381.455776 -270.969996) (xy 381.432125 -271.015059) (xy 381.401552 -271.055745) (xy 381.364848 -271.091)
			(xy 381.322964 -271.11991) (xy 381.276985 -271.141727) (xy 381.228101 -271.155887) (xy 381.17758 -271.162021)
			(xy 381.126728 -271.159972) (xy 381.076864 -271.149792) (xy 381.029278 -271.131745) (xy 380.985204 -271.106299)
			(xy 380.945782 -271.074112) (xy 380.912034 -271.036018) (xy 380.884833 -270.993004) (xy 380.864885 -270.946184)
			(xy 380.852706 -270.89677) (xy 380.848611 -270.846042) (xy 380.5301 -270.846042) (xy 380.529605 -270.870649)
			(xy 380.52171 -270.919226) (xy 380.506126 -270.965907) (xy 380.483255 -271.009484) (xy 380.45369 -271.048828)
			(xy 380.418197 -271.08292) (xy 380.377694 -271.110876) (xy 380.333232 -271.131974) (xy 380.285961 -271.145666)
			(xy 380.237106 -271.151598) (xy 380.187931 -271.149617) (xy 380.139712 -271.139773) (xy 380.093696 -271.122321)
			(xy 380.051075 -271.097714) (xy 380.012954 -271.066589) (xy 379.980319 -271.029752) (xy 379.954016 -270.988156)
			(xy 379.934725 -270.94288) (xy 379.922948 -270.895096) (xy 379.918988 -270.846042) (xy 379.60046 -270.846042)
			(xy 379.599948 -270.871488) (xy 379.591784 -270.921722) (xy 379.575668 -270.969996) (xy 379.552017 -271.015059)
			(xy 379.521444 -271.055745) (xy 379.48474 -271.091) (xy 379.442856 -271.11991) (xy 379.396877 -271.141727)
			(xy 379.347993 -271.155887) (xy 379.297472 -271.162021) (xy 379.24662 -271.159972) (xy 379.196756 -271.149792)
			(xy 379.14917 -271.131745) (xy 379.105096 -271.106299) (xy 379.065674 -271.074112) (xy 379.031926 -271.036018)
			(xy 379.004725 -270.993004) (xy 378.984777 -270.946184) (xy 378.972598 -270.89677) (xy 378.968503 -270.846042)
			(xy 377.720606 -270.846042) (xy 377.720094 -270.871488) (xy 377.71193 -270.921722) (xy 377.695814 -270.969996)
			(xy 377.672163 -271.015059) (xy 377.64159 -271.055745) (xy 377.604886 -271.091) (xy 377.563002 -271.11991)
			(xy 377.517023 -271.141727) (xy 377.468139 -271.155887) (xy 377.417618 -271.162021) (xy 377.366766 -271.159972)
			(xy 377.316902 -271.149792) (xy 377.269316 -271.131745) (xy 377.225242 -271.106299) (xy 377.18582 -271.074112)
			(xy 377.152072 -271.036018) (xy 377.124871 -270.993004) (xy 377.104923 -270.946184) (xy 377.092744 -270.89677)
			(xy 377.088649 -270.846042) (xy 376.780552 -270.846042) (xy 376.78004 -270.871488) (xy 376.771876 -270.921722)
			(xy 376.75576 -270.969996) (xy 376.732109 -271.015059) (xy 376.701536 -271.055745) (xy 376.664832 -271.091)
			(xy 376.622948 -271.11991) (xy 376.576969 -271.141727) (xy 376.528085 -271.155887) (xy 376.477564 -271.162021)
			(xy 376.426712 -271.159972) (xy 376.376848 -271.149792) (xy 376.329262 -271.131745) (xy 376.285188 -271.106299)
			(xy 376.245766 -271.074112) (xy 376.212018 -271.036018) (xy 376.184817 -270.993004) (xy 376.164869 -270.946184)
			(xy 376.15269 -270.89677) (xy 376.148595 -270.846042) (xy 375.412254 -270.846042) (xy 375.412254 -271.656048)
			(xy 375.678695 -271.656048) (xy 375.68279 -271.60532) (xy 375.694969 -271.555906) (xy 375.714917 -271.509086)
			(xy 375.742118 -271.466072) (xy 375.775866 -271.427978) (xy 375.815288 -271.395791) (xy 375.859362 -271.370345)
			(xy 375.906948 -271.352298) (xy 375.956812 -271.342118) (xy 376.007664 -271.340069) (xy 376.058185 -271.346203)
			(xy 376.107069 -271.360363) (xy 376.153048 -271.38218) (xy 376.194932 -271.41109) (xy 376.231636 -271.446345)
			(xy 376.262209 -271.487031) (xy 376.28586 -271.532094) (xy 376.301976 -271.580368) (xy 376.31014 -271.630602)
			(xy 376.310652 -271.656048) (xy 376.628926 -271.656048) (xy 376.632886 -271.606994) (xy 376.644663 -271.55921)
			(xy 376.663954 -271.513934) (xy 376.690257 -271.472338) (xy 376.722892 -271.435501) (xy 376.761013 -271.404376)
			(xy 376.803634 -271.379769) (xy 376.84965 -271.362317) (xy 376.897869 -271.352473) (xy 376.947044 -271.350492)
			(xy 376.995899 -271.356424) (xy 377.04317 -271.370116) (xy 377.087632 -271.391214) (xy 377.128135 -271.41917)
			(xy 377.163628 -271.453262) (xy 377.193193 -271.492606) (xy 377.216064 -271.536183) (xy 377.231648 -271.582864)
			(xy 377.239543 -271.631441) (xy 377.240038 -271.656048) (xy 377.558549 -271.656048) (xy 377.562644 -271.60532)
			(xy 377.574823 -271.555906) (xy 377.594771 -271.509086) (xy 377.621972 -271.466072) (xy 377.65572 -271.427978)
			(xy 377.695142 -271.395791) (xy 377.739216 -271.370345) (xy 377.786802 -271.352298) (xy 377.836666 -271.342118)
			(xy 377.887518 -271.340069) (xy 377.938039 -271.346203) (xy 377.986923 -271.360363) (xy 378.032902 -271.38218)
			(xy 378.074786 -271.41109) (xy 378.11149 -271.446345) (xy 378.142063 -271.487031) (xy 378.165714 -271.532094)
			(xy 378.18183 -271.580368) (xy 378.189994 -271.630602) (xy 378.190506 -271.656048) (xy 378.509034 -271.656048)
			(xy 378.512994 -271.606994) (xy 378.524771 -271.55921) (xy 378.544062 -271.513934) (xy 378.570365 -271.472338)
			(xy 378.603 -271.435501) (xy 378.641121 -271.404376) (xy 378.683742 -271.379769) (xy 378.729758 -271.362317)
			(xy 378.777977 -271.352473) (xy 378.827152 -271.350492) (xy 378.876007 -271.356424) (xy 378.923278 -271.370116)
			(xy 378.96774 -271.391214) (xy 379.008243 -271.41917) (xy 379.043736 -271.453262) (xy 379.073301 -271.492606)
			(xy 379.096172 -271.536183) (xy 379.111756 -271.582864) (xy 379.119651 -271.631441) (xy 379.120146 -271.656048)
			(xy 379.438657 -271.656048) (xy 379.442752 -271.60532) (xy 379.454931 -271.555906) (xy 379.474879 -271.509086)
			(xy 379.50208 -271.466072) (xy 379.535828 -271.427978) (xy 379.57525 -271.395791) (xy 379.619324 -271.370345)
			(xy 379.66691 -271.352298) (xy 379.716774 -271.342118) (xy 379.767626 -271.340069) (xy 379.818147 -271.346203)
			(xy 379.867031 -271.360363) (xy 379.91301 -271.38218) (xy 379.954894 -271.41109) (xy 379.991598 -271.446345)
			(xy 380.022171 -271.487031) (xy 380.045822 -271.532094) (xy 380.061938 -271.580368) (xy 380.070102 -271.630602)
			(xy 380.070614 -271.656048) (xy 380.378711 -271.656048) (xy 380.382806 -271.60532) (xy 380.394985 -271.555906)
			(xy 380.414933 -271.509086) (xy 380.442134 -271.466072) (xy 380.475882 -271.427978) (xy 380.515304 -271.395791)
			(xy 380.559378 -271.370345) (xy 380.606964 -271.352298) (xy 380.656828 -271.342118) (xy 380.70768 -271.340069)
			(xy 380.758201 -271.346203) (xy 380.807085 -271.360363) (xy 380.853064 -271.38218) (xy 380.894948 -271.41109)
			(xy 380.931652 -271.446345) (xy 380.962225 -271.487031) (xy 380.985876 -271.532094) (xy 381.001992 -271.580368)
			(xy 381.010156 -271.630602) (xy 381.010668 -271.656048) (xy 381.328942 -271.656048) (xy 381.332902 -271.606994)
			(xy 381.344679 -271.55921) (xy 381.36397 -271.513934) (xy 381.390273 -271.472338) (xy 381.422908 -271.435501)
			(xy 381.461029 -271.404376) (xy 381.50365 -271.379769) (xy 381.549666 -271.362317) (xy 381.597885 -271.352473)
			(xy 381.64706 -271.350492) (xy 381.695915 -271.356424) (xy 381.743186 -271.370116) (xy 381.787648 -271.391214)
			(xy 381.828151 -271.41917) (xy 381.863644 -271.453262) (xy 381.893209 -271.492606) (xy 381.91608 -271.536183)
			(xy 381.931664 -271.582864) (xy 381.939559 -271.631441) (xy 381.940054 -271.656048) (xy 382.268996 -271.656048)
			(xy 382.272956 -271.606994) (xy 382.284733 -271.55921) (xy 382.304024 -271.513934) (xy 382.330327 -271.472338)
			(xy 382.362962 -271.435501) (xy 382.401083 -271.404376) (xy 382.443704 -271.379769) (xy 382.48972 -271.362317)
			(xy 382.537939 -271.352473) (xy 382.587114 -271.350492) (xy 382.635969 -271.356424) (xy 382.68324 -271.370116)
			(xy 382.727702 -271.391214) (xy 382.768205 -271.41917) (xy 382.803698 -271.453262) (xy 382.833263 -271.492606)
			(xy 382.856134 -271.536183) (xy 382.871718 -271.582864) (xy 382.879613 -271.631441) (xy 382.880108 -271.656048)
			(xy 383.20905 -271.656048) (xy 383.21301 -271.606994) (xy 383.224787 -271.55921) (xy 383.244078 -271.513934)
			(xy 383.270381 -271.472338) (xy 383.303016 -271.435501) (xy 383.341137 -271.404376) (xy 383.383758 -271.379769)
			(xy 383.429774 -271.362317) (xy 383.477993 -271.352473) (xy 383.527168 -271.350492) (xy 383.576023 -271.356424)
			(xy 383.623294 -271.370116) (xy 383.667756 -271.391214) (xy 383.708259 -271.41917) (xy 383.743752 -271.453262)
			(xy 383.773317 -271.492606) (xy 383.796188 -271.536183) (xy 383.811772 -271.582864) (xy 383.819667 -271.631441)
			(xy 383.820162 -271.656048) (xy 384.149104 -271.656048) (xy 384.153064 -271.606994) (xy 384.164841 -271.55921)
			(xy 384.184132 -271.513934) (xy 384.210435 -271.472338) (xy 384.24307 -271.435501) (xy 384.281191 -271.404376)
			(xy 384.323812 -271.379769) (xy 384.369828 -271.362317) (xy 384.418047 -271.352473) (xy 384.467222 -271.350492)
			(xy 384.516077 -271.356424) (xy 384.563348 -271.370116) (xy 384.60781 -271.391214) (xy 384.648313 -271.41917)
			(xy 384.683806 -271.453262) (xy 384.713371 -271.492606) (xy 384.736242 -271.536183) (xy 384.751826 -271.582864)
			(xy 384.759721 -271.631441) (xy 384.760216 -271.656048) (xy 384.759721 -271.680655) (xy 384.751826 -271.729232)
			(xy 384.736242 -271.775913) (xy 384.713371 -271.81949) (xy 384.683806 -271.858834) (xy 384.648313 -271.892926)
			(xy 384.60781 -271.920882) (xy 384.563348 -271.94198) (xy 384.516077 -271.955672) (xy 384.467222 -271.961604)
			(xy 384.418047 -271.959623) (xy 384.369828 -271.949779) (xy 384.323812 -271.932327) (xy 384.281191 -271.90772)
			(xy 384.24307 -271.876595) (xy 384.210435 -271.839758) (xy 384.184132 -271.798162) (xy 384.164841 -271.752886)
			(xy 384.153064 -271.705102) (xy 384.149104 -271.656048) (xy 383.820162 -271.656048) (xy 383.819667 -271.680655)
			(xy 383.811772 -271.729232) (xy 383.796188 -271.775913) (xy 383.773317 -271.81949) (xy 383.743752 -271.858834)
			(xy 383.708259 -271.892926) (xy 383.667756 -271.920882) (xy 383.623294 -271.94198) (xy 383.576023 -271.955672)
			(xy 383.527168 -271.961604) (xy 383.477993 -271.959623) (xy 383.429774 -271.949779) (xy 383.383758 -271.932327)
			(xy 383.341137 -271.90772) (xy 383.303016 -271.876595) (xy 383.270381 -271.839758) (xy 383.244078 -271.798162)
			(xy 383.224787 -271.752886) (xy 383.21301 -271.705102) (xy 383.20905 -271.656048) (xy 382.880108 -271.656048)
			(xy 382.879613 -271.680655) (xy 382.871718 -271.729232) (xy 382.856134 -271.775913) (xy 382.833263 -271.81949)
			(xy 382.803698 -271.858834) (xy 382.768205 -271.892926) (xy 382.727702 -271.920882) (xy 382.68324 -271.94198)
			(xy 382.635969 -271.955672) (xy 382.587114 -271.961604) (xy 382.537939 -271.959623) (xy 382.48972 -271.949779)
			(xy 382.443704 -271.932327) (xy 382.401083 -271.90772) (xy 382.362962 -271.876595) (xy 382.330327 -271.839758)
			(xy 382.304024 -271.798162) (xy 382.284733 -271.752886) (xy 382.272956 -271.705102) (xy 382.268996 -271.656048)
			(xy 381.940054 -271.656048) (xy 381.939559 -271.680655) (xy 381.931664 -271.729232) (xy 381.91608 -271.775913)
			(xy 381.893209 -271.81949) (xy 381.863644 -271.858834) (xy 381.828151 -271.892926) (xy 381.787648 -271.920882)
			(xy 381.743186 -271.94198) (xy 381.695915 -271.955672) (xy 381.64706 -271.961604) (xy 381.597885 -271.959623)
			(xy 381.549666 -271.949779) (xy 381.50365 -271.932327) (xy 381.461029 -271.90772) (xy 381.422908 -271.876595)
			(xy 381.390273 -271.839758) (xy 381.36397 -271.798162) (xy 381.344679 -271.752886) (xy 381.332902 -271.705102)
			(xy 381.328942 -271.656048) (xy 381.010668 -271.656048) (xy 381.010156 -271.681494) (xy 381.001992 -271.731728)
			(xy 380.985876 -271.780002) (xy 380.962225 -271.825065) (xy 380.931652 -271.865751) (xy 380.894948 -271.901006)
			(xy 380.853064 -271.929916) (xy 380.807085 -271.951733) (xy 380.758201 -271.965893) (xy 380.70768 -271.972027)
			(xy 380.656828 -271.969978) (xy 380.606964 -271.959798) (xy 380.559378 -271.941751) (xy 380.515304 -271.916305)
			(xy 380.475882 -271.884118) (xy 380.442134 -271.846024) (xy 380.414933 -271.80301) (xy 380.394985 -271.75619)
			(xy 380.382806 -271.706776) (xy 380.378711 -271.656048) (xy 380.070614 -271.656048) (xy 380.070102 -271.681494)
			(xy 380.061938 -271.731728) (xy 380.045822 -271.780002) (xy 380.022171 -271.825065) (xy 379.991598 -271.865751)
			(xy 379.954894 -271.901006) (xy 379.91301 -271.929916) (xy 379.867031 -271.951733) (xy 379.818147 -271.965893)
			(xy 379.767626 -271.972027) (xy 379.716774 -271.969978) (xy 379.66691 -271.959798) (xy 379.619324 -271.941751)
			(xy 379.57525 -271.916305) (xy 379.535828 -271.884118) (xy 379.50208 -271.846024) (xy 379.474879 -271.80301)
			(xy 379.454931 -271.75619) (xy 379.442752 -271.706776) (xy 379.438657 -271.656048) (xy 379.120146 -271.656048)
			(xy 379.119651 -271.680655) (xy 379.111756 -271.729232) (xy 379.096172 -271.775913) (xy 379.073301 -271.81949)
			(xy 379.043736 -271.858834) (xy 379.008243 -271.892926) (xy 378.96774 -271.920882) (xy 378.923278 -271.94198)
			(xy 378.876007 -271.955672) (xy 378.827152 -271.961604) (xy 378.777977 -271.959623) (xy 378.729758 -271.949779)
			(xy 378.683742 -271.932327) (xy 378.641121 -271.90772) (xy 378.603 -271.876595) (xy 378.570365 -271.839758)
			(xy 378.544062 -271.798162) (xy 378.524771 -271.752886) (xy 378.512994 -271.705102) (xy 378.509034 -271.656048)
			(xy 378.190506 -271.656048) (xy 378.189994 -271.681494) (xy 378.18183 -271.731728) (xy 378.165714 -271.780002)
			(xy 378.142063 -271.825065) (xy 378.11149 -271.865751) (xy 378.074786 -271.901006) (xy 378.032902 -271.929916)
			(xy 377.986923 -271.951733) (xy 377.938039 -271.965893) (xy 377.887518 -271.972027) (xy 377.836666 -271.969978)
			(xy 377.786802 -271.959798) (xy 377.739216 -271.941751) (xy 377.695142 -271.916305) (xy 377.65572 -271.884118)
			(xy 377.621972 -271.846024) (xy 377.594771 -271.80301) (xy 377.574823 -271.75619) (xy 377.562644 -271.706776)
			(xy 377.558549 -271.656048) (xy 377.240038 -271.656048) (xy 377.239543 -271.680655) (xy 377.231648 -271.729232)
			(xy 377.216064 -271.775913) (xy 377.193193 -271.81949) (xy 377.163628 -271.858834) (xy 377.128135 -271.892926)
			(xy 377.087632 -271.920882) (xy 377.04317 -271.94198) (xy 376.995899 -271.955672) (xy 376.947044 -271.961604)
			(xy 376.897869 -271.959623) (xy 376.84965 -271.949779) (xy 376.803634 -271.932327) (xy 376.761013 -271.90772)
			(xy 376.722892 -271.876595) (xy 376.690257 -271.839758) (xy 376.663954 -271.798162) (xy 376.644663 -271.752886)
			(xy 376.632886 -271.705102) (xy 376.628926 -271.656048) (xy 376.310652 -271.656048) (xy 376.31014 -271.681494)
			(xy 376.301976 -271.731728) (xy 376.28586 -271.780002) (xy 376.262209 -271.825065) (xy 376.231636 -271.865751)
			(xy 376.194932 -271.901006) (xy 376.153048 -271.929916) (xy 376.107069 -271.951733) (xy 376.058185 -271.965893)
			(xy 376.007664 -271.972027) (xy 375.956812 -271.969978) (xy 375.906948 -271.959798) (xy 375.859362 -271.941751)
			(xy 375.815288 -271.916305) (xy 375.775866 -271.884118) (xy 375.742118 -271.846024) (xy 375.714917 -271.80301)
			(xy 375.694969 -271.75619) (xy 375.68279 -271.706776) (xy 375.678695 -271.656048) (xy 375.412254 -271.656048)
			(xy 375.412254 -271.955006) (xy 375.413016 -271.963388) (xy 375.41453 -271.970993) (xy 375.421516 -271.984828)
			(xy 375.426732 -271.990566) (xy 375.59996 -272.163794) (xy 375.60377 -272.167096) (xy 375.609358 -272.17116)
			(xy 375.614184 -272.173954) (xy 375.619772 -272.175986) (xy 375.642374 -272.183889) (xy 375.684983 -272.205724)
			(xy 375.723663 -272.23394) (xy 375.757466 -272.267847) (xy 375.785564 -272.306613) (xy 375.807269 -272.349288)
			(xy 375.82205 -272.394827) (xy 375.829543 -272.442115) (xy 375.830084 -272.466054) (xy 376.148595 -272.466054)
			(xy 376.15269 -272.415326) (xy 376.164869 -272.365912) (xy 376.184817 -272.319092) (xy 376.212018 -272.276078)
			(xy 376.245766 -272.237984) (xy 376.285188 -272.205797) (xy 376.329262 -272.180351) (xy 376.376848 -272.162304)
			(xy 376.426712 -272.152124) (xy 376.477564 -272.150075) (xy 376.528085 -272.156209) (xy 376.576969 -272.170369)
			(xy 376.622948 -272.192186) (xy 376.664832 -272.221096) (xy 376.701536 -272.256351) (xy 376.732109 -272.297037)
			(xy 376.75576 -272.3421) (xy 376.771876 -272.390374) (xy 376.78004 -272.440608) (xy 376.780552 -272.466054)
			(xy 377.088649 -272.466054) (xy 377.092744 -272.415326) (xy 377.104923 -272.365912) (xy 377.124871 -272.319092)
			(xy 377.152072 -272.276078) (xy 377.18582 -272.237984) (xy 377.225242 -272.205797) (xy 377.269316 -272.180351)
			(xy 377.316902 -272.162304) (xy 377.366766 -272.152124) (xy 377.417618 -272.150075) (xy 377.468139 -272.156209)
			(xy 377.517023 -272.170369) (xy 377.563002 -272.192186) (xy 377.604886 -272.221096) (xy 377.64159 -272.256351)
			(xy 377.672163 -272.297037) (xy 377.695814 -272.3421) (xy 377.71193 -272.390374) (xy 377.720094 -272.440608)
			(xy 377.720606 -272.466054) (xy 378.039134 -272.466054) (xy 378.043094 -272.417) (xy 378.054871 -272.369216)
			(xy 378.074162 -272.32394) (xy 378.100465 -272.282344) (xy 378.1331 -272.245507) (xy 378.171221 -272.214382)
			(xy 378.213842 -272.189775) (xy 378.259858 -272.172323) (xy 378.308077 -272.162479) (xy 378.357252 -272.160498)
			(xy 378.406107 -272.16643) (xy 378.453378 -272.180122) (xy 378.49784 -272.20122) (xy 378.538343 -272.229176)
			(xy 378.573836 -272.263268) (xy 378.603401 -272.302612) (xy 378.626272 -272.346189) (xy 378.641856 -272.39287)
			(xy 378.649751 -272.441447) (xy 378.650246 -272.466054) (xy 378.968503 -272.466054) (xy 378.972598 -272.415326)
			(xy 378.984777 -272.365912) (xy 379.004725 -272.319092) (xy 379.031926 -272.276078) (xy 379.065674 -272.237984)
			(xy 379.105096 -272.205797) (xy 379.14917 -272.180351) (xy 379.196756 -272.162304) (xy 379.24662 -272.152124)
			(xy 379.297472 -272.150075) (xy 379.347993 -272.156209) (xy 379.396877 -272.170369) (xy 379.442856 -272.192186)
			(xy 379.48474 -272.221096) (xy 379.521444 -272.256351) (xy 379.552017 -272.297037) (xy 379.575668 -272.3421)
			(xy 379.591784 -272.390374) (xy 379.599948 -272.440608) (xy 379.60046 -272.466054) (xy 379.918988 -272.466054)
			(xy 379.922948 -272.417) (xy 379.934725 -272.369216) (xy 379.954016 -272.32394) (xy 379.980319 -272.282344)
			(xy 380.012954 -272.245507) (xy 380.051075 -272.214382) (xy 380.093696 -272.189775) (xy 380.139712 -272.172323)
			(xy 380.187931 -272.162479) (xy 380.237106 -272.160498) (xy 380.285961 -272.16643) (xy 380.333232 -272.180122)
			(xy 380.377694 -272.20122) (xy 380.418197 -272.229176) (xy 380.45369 -272.263268) (xy 380.483255 -272.302612)
			(xy 380.506126 -272.346189) (xy 380.52171 -272.39287) (xy 380.529605 -272.441447) (xy 380.5301 -272.466054)
			(xy 380.848611 -272.466054) (xy 380.852706 -272.415326) (xy 380.864885 -272.365912) (xy 380.884833 -272.319092)
			(xy 380.912034 -272.276078) (xy 380.945782 -272.237984) (xy 380.985204 -272.205797) (xy 381.029278 -272.180351)
			(xy 381.076864 -272.162304) (xy 381.126728 -272.152124) (xy 381.17758 -272.150075) (xy 381.228101 -272.156209)
			(xy 381.276985 -272.170369) (xy 381.322964 -272.192186) (xy 381.364848 -272.221096) (xy 381.401552 -272.256351)
			(xy 381.432125 -272.297037) (xy 381.455776 -272.3421) (xy 381.471892 -272.390374) (xy 381.480056 -272.440608)
			(xy 381.480568 -272.466054) (xy 381.799096 -272.466054) (xy 381.803056 -272.417) (xy 381.814833 -272.369216)
			(xy 381.834124 -272.32394) (xy 381.860427 -272.282344) (xy 381.893062 -272.245507) (xy 381.931183 -272.214382)
			(xy 381.973804 -272.189775) (xy 382.01982 -272.172323) (xy 382.068039 -272.162479) (xy 382.117214 -272.160498)
			(xy 382.166069 -272.16643) (xy 382.21334 -272.180122) (xy 382.257802 -272.20122) (xy 382.298305 -272.229176)
			(xy 382.333798 -272.263268) (xy 382.363363 -272.302612) (xy 382.386234 -272.346189) (xy 382.401818 -272.39287)
			(xy 382.409713 -272.441447) (xy 382.410208 -272.466054) (xy 382.738896 -272.466054) (xy 382.742856 -272.417)
			(xy 382.754633 -272.369216) (xy 382.773924 -272.32394) (xy 382.800227 -272.282344) (xy 382.832862 -272.245507)
			(xy 382.870983 -272.214382) (xy 382.913604 -272.189775) (xy 382.95962 -272.172323) (xy 383.007839 -272.162479)
			(xy 383.057014 -272.160498) (xy 383.105869 -272.16643) (xy 383.15314 -272.180122) (xy 383.197602 -272.20122)
			(xy 383.238105 -272.229176) (xy 383.273598 -272.263268) (xy 383.303163 -272.302612) (xy 383.326034 -272.346189)
			(xy 383.341618 -272.39287) (xy 383.349513 -272.441447) (xy 383.350008 -272.466054) (xy 383.67895 -272.466054)
			(xy 383.68291 -272.417) (xy 383.694687 -272.369216) (xy 383.713978 -272.32394) (xy 383.740281 -272.282344)
			(xy 383.772916 -272.245507) (xy 383.811037 -272.214382) (xy 383.853658 -272.189775) (xy 383.899674 -272.172323)
			(xy 383.947893 -272.162479) (xy 383.997068 -272.160498) (xy 384.045923 -272.16643) (xy 384.093194 -272.180122)
			(xy 384.137656 -272.20122) (xy 384.178159 -272.229176) (xy 384.213652 -272.263268) (xy 384.243217 -272.302612)
			(xy 384.266088 -272.346189) (xy 384.281672 -272.39287) (xy 384.289567 -272.441447) (xy 384.290062 -272.466054)
			(xy 384.289567 -272.490661) (xy 384.281672 -272.539238) (xy 384.266088 -272.585919) (xy 384.243217 -272.629496)
			(xy 384.213652 -272.66884) (xy 384.178159 -272.702932) (xy 384.137656 -272.730888) (xy 384.093194 -272.751986)
			(xy 384.045923 -272.765678) (xy 383.997068 -272.77161) (xy 383.947893 -272.769629) (xy 383.899674 -272.759785)
			(xy 383.853658 -272.742333) (xy 383.811037 -272.717726) (xy 383.772916 -272.686601) (xy 383.740281 -272.649764)
			(xy 383.713978 -272.608168) (xy 383.694687 -272.562892) (xy 383.68291 -272.515108) (xy 383.67895 -272.466054)
			(xy 383.350008 -272.466054) (xy 383.349513 -272.490661) (xy 383.341618 -272.539238) (xy 383.326034 -272.585919)
			(xy 383.303163 -272.629496) (xy 383.273598 -272.66884) (xy 383.238105 -272.702932) (xy 383.197602 -272.730888)
			(xy 383.15314 -272.751986) (xy 383.105869 -272.765678) (xy 383.057014 -272.77161) (xy 383.007839 -272.769629)
			(xy 382.95962 -272.759785) (xy 382.913604 -272.742333) (xy 382.870983 -272.717726) (xy 382.832862 -272.686601)
			(xy 382.800227 -272.649764) (xy 382.773924 -272.608168) (xy 382.754633 -272.562892) (xy 382.742856 -272.515108)
			(xy 382.738896 -272.466054) (xy 382.410208 -272.466054) (xy 382.409713 -272.490661) (xy 382.401818 -272.539238)
			(xy 382.386234 -272.585919) (xy 382.363363 -272.629496) (xy 382.333798 -272.66884) (xy 382.298305 -272.702932)
			(xy 382.257802 -272.730888) (xy 382.21334 -272.751986) (xy 382.166069 -272.765678) (xy 382.117214 -272.77161)
			(xy 382.068039 -272.769629) (xy 382.01982 -272.759785) (xy 381.973804 -272.742333) (xy 381.931183 -272.717726)
			(xy 381.893062 -272.686601) (xy 381.860427 -272.649764) (xy 381.834124 -272.608168) (xy 381.814833 -272.562892)
			(xy 381.803056 -272.515108) (xy 381.799096 -272.466054) (xy 381.480568 -272.466054) (xy 381.480056 -272.4915)
			(xy 381.471892 -272.541734) (xy 381.455776 -272.590008) (xy 381.432125 -272.635071) (xy 381.401552 -272.675757)
			(xy 381.364848 -272.711012) (xy 381.322964 -272.739922) (xy 381.276985 -272.761739) (xy 381.228101 -272.775899)
			(xy 381.17758 -272.782033) (xy 381.126728 -272.779984) (xy 381.076864 -272.769804) (xy 381.029278 -272.751757)
			(xy 380.985204 -272.726311) (xy 380.945782 -272.694124) (xy 380.912034 -272.65603) (xy 380.884833 -272.613016)
			(xy 380.864885 -272.566196) (xy 380.852706 -272.516782) (xy 380.848611 -272.466054) (xy 380.5301 -272.466054)
			(xy 380.529605 -272.490661) (xy 380.52171 -272.539238) (xy 380.506126 -272.585919) (xy 380.483255 -272.629496)
			(xy 380.45369 -272.66884) (xy 380.418197 -272.702932) (xy 380.377694 -272.730888) (xy 380.333232 -272.751986)
			(xy 380.285961 -272.765678) (xy 380.237106 -272.77161) (xy 380.187931 -272.769629) (xy 380.139712 -272.759785)
			(xy 380.093696 -272.742333) (xy 380.051075 -272.717726) (xy 380.012954 -272.686601) (xy 379.980319 -272.649764)
			(xy 379.954016 -272.608168) (xy 379.934725 -272.562892) (xy 379.922948 -272.515108) (xy 379.918988 -272.466054)
			(xy 379.60046 -272.466054) (xy 379.599948 -272.4915) (xy 379.591784 -272.541734) (xy 379.575668 -272.590008)
			(xy 379.552017 -272.635071) (xy 379.521444 -272.675757) (xy 379.48474 -272.711012) (xy 379.442856 -272.739922)
			(xy 379.396877 -272.761739) (xy 379.347993 -272.775899) (xy 379.297472 -272.782033) (xy 379.24662 -272.779984)
			(xy 379.196756 -272.769804) (xy 379.14917 -272.751757) (xy 379.105096 -272.726311) (xy 379.065674 -272.694124)
			(xy 379.031926 -272.65603) (xy 379.004725 -272.613016) (xy 378.984777 -272.566196) (xy 378.972598 -272.516782)
			(xy 378.968503 -272.466054) (xy 378.650246 -272.466054) (xy 378.649751 -272.490661) (xy 378.641856 -272.539238)
			(xy 378.626272 -272.585919) (xy 378.603401 -272.629496) (xy 378.573836 -272.66884) (xy 378.538343 -272.702932)
			(xy 378.49784 -272.730888) (xy 378.453378 -272.751986) (xy 378.406107 -272.765678) (xy 378.357252 -272.77161)
			(xy 378.308077 -272.769629) (xy 378.259858 -272.759785) (xy 378.213842 -272.742333) (xy 378.171221 -272.717726)
			(xy 378.1331 -272.686601) (xy 378.100465 -272.649764) (xy 378.074162 -272.608168) (xy 378.054871 -272.562892)
			(xy 378.043094 -272.515108) (xy 378.039134 -272.466054) (xy 377.720606 -272.466054) (xy 377.720094 -272.4915)
			(xy 377.71193 -272.541734) (xy 377.695814 -272.590008) (xy 377.672163 -272.635071) (xy 377.64159 -272.675757)
			(xy 377.604886 -272.711012) (xy 377.563002 -272.739922) (xy 377.517023 -272.761739) (xy 377.468139 -272.775899)
			(xy 377.417618 -272.782033) (xy 377.366766 -272.779984) (xy 377.316902 -272.769804) (xy 377.269316 -272.751757)
			(xy 377.225242 -272.726311) (xy 377.18582 -272.694124) (xy 377.152072 -272.65603) (xy 377.124871 -272.613016)
			(xy 377.104923 -272.566196) (xy 377.092744 -272.516782) (xy 377.088649 -272.466054) (xy 376.780552 -272.466054)
			(xy 376.78004 -272.4915) (xy 376.771876 -272.541734) (xy 376.75576 -272.590008) (xy 376.732109 -272.635071)
			(xy 376.701536 -272.675757) (xy 376.664832 -272.711012) (xy 376.622948 -272.739922) (xy 376.576969 -272.761739)
			(xy 376.528085 -272.775899) (xy 376.477564 -272.782033) (xy 376.426712 -272.779984) (xy 376.376848 -272.769804)
			(xy 376.329262 -272.751757) (xy 376.285188 -272.726311) (xy 376.245766 -272.694124) (xy 376.212018 -272.65603)
			(xy 376.184817 -272.613016) (xy 376.164869 -272.566196) (xy 376.15269 -272.516782) (xy 376.148595 -272.466054)
			(xy 375.830084 -272.466054) (xy 375.829611 -272.49034) (xy 375.821917 -272.538298) (xy 375.806731 -272.584434)
			(xy 375.784435 -272.627586) (xy 375.755592 -272.666666) (xy 375.720929 -272.70069) (xy 375.681318 -272.7288)
			(xy 375.637759 -272.750288) (xy 375.614692 -272.7579) (xy 375.608088 -272.759932) (xy 375.603262 -272.76298)
			(xy 375.593864 -272.770346) (xy 375.54281 -272.8214) (xy 375.536093 -272.828636) (xy 375.528491 -272.846842)
			(xy 375.528078 -272.856706) (xy 375.528078 -273.27606) (xy 375.678695 -273.27606) (xy 375.68279 -273.225332)
			(xy 375.694969 -273.175918) (xy 375.714917 -273.129098) (xy 375.742118 -273.086084) (xy 375.775866 -273.04799)
			(xy 375.815288 -273.015803) (xy 375.859362 -272.990357) (xy 375.906948 -272.97231) (xy 375.956812 -272.96213)
			(xy 376.007664 -272.960081) (xy 376.058185 -272.966215) (xy 376.107069 -272.980375) (xy 376.153048 -273.002192)
			(xy 376.194932 -273.031102) (xy 376.231636 -273.066357) (xy 376.262209 -273.107043) (xy 376.28586 -273.152106)
			(xy 376.301976 -273.20038) (xy 376.31014 -273.250614) (xy 376.310652 -273.27606) (xy 376.628926 -273.27606)
			(xy 376.632886 -273.227006) (xy 376.644663 -273.179222) (xy 376.663954 -273.133946) (xy 376.690257 -273.09235)
			(xy 376.722892 -273.055513) (xy 376.761013 -273.024388) (xy 376.803634 -272.999781) (xy 376.84965 -272.982329)
			(xy 376.897869 -272.972485) (xy 376.947044 -272.970504) (xy 376.995899 -272.976436) (xy 377.04317 -272.990128)
			(xy 377.087632 -273.011226) (xy 377.128135 -273.039182) (xy 377.163628 -273.073274) (xy 377.193193 -273.112618)
			(xy 377.216064 -273.156195) (xy 377.231648 -273.202876) (xy 377.239543 -273.251453) (xy 377.240038 -273.27606)
			(xy 377.558549 -273.27606) (xy 377.562644 -273.225332) (xy 377.574823 -273.175918) (xy 377.594771 -273.129098)
			(xy 377.621972 -273.086084) (xy 377.65572 -273.04799) (xy 377.695142 -273.015803) (xy 377.739216 -272.990357)
			(xy 377.786802 -272.97231) (xy 377.836666 -272.96213) (xy 377.887518 -272.960081) (xy 377.938039 -272.966215)
			(xy 377.986923 -272.980375) (xy 378.032902 -273.002192) (xy 378.074786 -273.031102) (xy 378.11149 -273.066357)
			(xy 378.142063 -273.107043) (xy 378.165714 -273.152106) (xy 378.18183 -273.20038) (xy 378.189994 -273.250614)
			(xy 378.190506 -273.27606) (xy 379.438657 -273.27606) (xy 379.442752 -273.225332) (xy 379.454931 -273.175918)
			(xy 379.474879 -273.129098) (xy 379.50208 -273.086084) (xy 379.535828 -273.04799) (xy 379.57525 -273.015803)
			(xy 379.619324 -272.990357) (xy 379.66691 -272.97231) (xy 379.716774 -272.96213) (xy 379.767626 -272.960081)
			(xy 379.818147 -272.966215) (xy 379.867031 -272.980375) (xy 379.91301 -273.002192) (xy 379.954894 -273.031102)
			(xy 379.991598 -273.066357) (xy 380.022171 -273.107043) (xy 380.045822 -273.152106) (xy 380.061938 -273.20038)
			(xy 380.070102 -273.250614) (xy 380.070614 -273.27606) (xy 380.378711 -273.27606) (xy 380.382806 -273.225332)
			(xy 380.394985 -273.175918) (xy 380.414933 -273.129098) (xy 380.442134 -273.086084) (xy 380.475882 -273.04799)
			(xy 380.515304 -273.015803) (xy 380.559378 -272.990357) (xy 380.606964 -272.97231) (xy 380.656828 -272.96213)
			(xy 380.70768 -272.960081) (xy 380.758201 -272.966215) (xy 380.807085 -272.980375) (xy 380.853064 -273.002192)
			(xy 380.894948 -273.031102) (xy 380.931652 -273.066357) (xy 380.962225 -273.107043) (xy 380.985876 -273.152106)
			(xy 381.001992 -273.20038) (xy 381.010156 -273.250614) (xy 381.010668 -273.27606) (xy 381.328942 -273.27606)
			(xy 381.332902 -273.227006) (xy 381.344679 -273.179222) (xy 381.36397 -273.133946) (xy 381.390273 -273.09235)
			(xy 381.422908 -273.055513) (xy 381.461029 -273.024388) (xy 381.50365 -272.999781) (xy 381.549666 -272.982329)
			(xy 381.597885 -272.972485) (xy 381.64706 -272.970504) (xy 381.695915 -272.976436) (xy 381.743186 -272.990128)
			(xy 381.787648 -273.011226) (xy 381.828151 -273.039182) (xy 381.863644 -273.073274) (xy 381.893209 -273.112618)
			(xy 381.91608 -273.156195) (xy 381.931664 -273.202876) (xy 381.939559 -273.251453) (xy 381.940054 -273.27606)
			(xy 382.268996 -273.27606) (xy 382.272956 -273.227006) (xy 382.284733 -273.179222) (xy 382.304024 -273.133946)
			(xy 382.330327 -273.09235) (xy 382.362962 -273.055513) (xy 382.401083 -273.024388) (xy 382.443704 -272.999781)
			(xy 382.48972 -272.982329) (xy 382.537939 -272.972485) (xy 382.587114 -272.970504) (xy 382.635969 -272.976436)
			(xy 382.68324 -272.990128) (xy 382.727702 -273.011226) (xy 382.768205 -273.039182) (xy 382.803698 -273.073274)
			(xy 382.833263 -273.112618) (xy 382.856134 -273.156195) (xy 382.871718 -273.202876) (xy 382.879613 -273.251453)
			(xy 382.880108 -273.27606) (xy 383.20905 -273.27606) (xy 383.21301 -273.227006) (xy 383.224787 -273.179222)
			(xy 383.244078 -273.133946) (xy 383.270381 -273.09235) (xy 383.303016 -273.055513) (xy 383.341137 -273.024388)
			(xy 383.383758 -272.999781) (xy 383.429774 -272.982329) (xy 383.477993 -272.972485) (xy 383.527168 -272.970504)
			(xy 383.576023 -272.976436) (xy 383.623294 -272.990128) (xy 383.667756 -273.011226) (xy 383.708259 -273.039182)
			(xy 383.743752 -273.073274) (xy 383.773317 -273.112618) (xy 383.796188 -273.156195) (xy 383.811772 -273.202876)
			(xy 383.819667 -273.251453) (xy 383.820162 -273.27606) (xy 384.149104 -273.27606) (xy 384.153064 -273.227006)
			(xy 384.164841 -273.179222) (xy 384.184132 -273.133946) (xy 384.210435 -273.09235) (xy 384.24307 -273.055513)
			(xy 384.281191 -273.024388) (xy 384.323812 -272.999781) (xy 384.369828 -272.982329) (xy 384.418047 -272.972485)
			(xy 384.467222 -272.970504) (xy 384.516077 -272.976436) (xy 384.563348 -272.990128) (xy 384.60781 -273.011226)
			(xy 384.648313 -273.039182) (xy 384.683806 -273.073274) (xy 384.713371 -273.112618) (xy 384.736242 -273.156195)
			(xy 384.751826 -273.202876) (xy 384.759721 -273.251453) (xy 384.760216 -273.27606) (xy 384.759721 -273.300667)
			(xy 384.751826 -273.349244) (xy 384.736242 -273.395925) (xy 384.713371 -273.439502) (xy 384.683806 -273.478846)
			(xy 384.648313 -273.512938) (xy 384.60781 -273.540894) (xy 384.563348 -273.561992) (xy 384.516077 -273.575684)
			(xy 384.467222 -273.581616) (xy 384.418047 -273.579635) (xy 384.369828 -273.569791) (xy 384.323812 -273.552339)
			(xy 384.281191 -273.527732) (xy 384.24307 -273.496607) (xy 384.210435 -273.45977) (xy 384.184132 -273.418174)
			(xy 384.164841 -273.372898) (xy 384.153064 -273.325114) (xy 384.149104 -273.27606) (xy 383.820162 -273.27606)
			(xy 383.819667 -273.300667) (xy 383.811772 -273.349244) (xy 383.796188 -273.395925) (xy 383.773317 -273.439502)
			(xy 383.743752 -273.478846) (xy 383.708259 -273.512938) (xy 383.667756 -273.540894) (xy 383.623294 -273.561992)
			(xy 383.576023 -273.575684) (xy 383.527168 -273.581616) (xy 383.477993 -273.579635) (xy 383.429774 -273.569791)
			(xy 383.383758 -273.552339) (xy 383.341137 -273.527732) (xy 383.303016 -273.496607) (xy 383.270381 -273.45977)
			(xy 383.244078 -273.418174) (xy 383.224787 -273.372898) (xy 383.21301 -273.325114) (xy 383.20905 -273.27606)
			(xy 382.880108 -273.27606) (xy 382.879613 -273.300667) (xy 382.871718 -273.349244) (xy 382.856134 -273.395925)
			(xy 382.833263 -273.439502) (xy 382.803698 -273.478846) (xy 382.768205 -273.512938) (xy 382.727702 -273.540894)
			(xy 382.68324 -273.561992) (xy 382.635969 -273.575684) (xy 382.587114 -273.581616) (xy 382.537939 -273.579635)
			(xy 382.48972 -273.569791) (xy 382.443704 -273.552339) (xy 382.401083 -273.527732) (xy 382.362962 -273.496607)
			(xy 382.330327 -273.45977) (xy 382.304024 -273.418174) (xy 382.284733 -273.372898) (xy 382.272956 -273.325114)
			(xy 382.268996 -273.27606) (xy 381.940054 -273.27606) (xy 381.939559 -273.300667) (xy 381.931664 -273.349244)
			(xy 381.91608 -273.395925) (xy 381.893209 -273.439502) (xy 381.863644 -273.478846) (xy 381.828151 -273.512938)
			(xy 381.787648 -273.540894) (xy 381.743186 -273.561992) (xy 381.695915 -273.575684) (xy 381.64706 -273.581616)
			(xy 381.597885 -273.579635) (xy 381.549666 -273.569791) (xy 381.50365 -273.552339) (xy 381.461029 -273.527732)
			(xy 381.422908 -273.496607) (xy 381.390273 -273.45977) (xy 381.36397 -273.418174) (xy 381.344679 -273.372898)
			(xy 381.332902 -273.325114) (xy 381.328942 -273.27606) (xy 381.010668 -273.27606) (xy 381.010156 -273.301506)
			(xy 381.001992 -273.35174) (xy 380.985876 -273.400014) (xy 380.962225 -273.445077) (xy 380.931652 -273.485763)
			(xy 380.894948 -273.521018) (xy 380.853064 -273.549928) (xy 380.807085 -273.571745) (xy 380.758201 -273.585905)
			(xy 380.70768 -273.592039) (xy 380.656828 -273.58999) (xy 380.606964 -273.57981) (xy 380.559378 -273.561763)
			(xy 380.515304 -273.536317) (xy 380.475882 -273.50413) (xy 380.442134 -273.466036) (xy 380.414933 -273.423022)
			(xy 380.394985 -273.376202) (xy 380.382806 -273.326788) (xy 380.378711 -273.27606) (xy 380.070614 -273.27606)
			(xy 380.070102 -273.301506) (xy 380.061938 -273.35174) (xy 380.045822 -273.400014) (xy 380.022171 -273.445077)
			(xy 379.991598 -273.485763) (xy 379.954894 -273.521018) (xy 379.91301 -273.549928) (xy 379.867031 -273.571745)
			(xy 379.818147 -273.585905) (xy 379.767626 -273.592039) (xy 379.716774 -273.58999) (xy 379.66691 -273.57981)
			(xy 379.619324 -273.561763) (xy 379.57525 -273.536317) (xy 379.535828 -273.50413) (xy 379.50208 -273.466036)
			(xy 379.474879 -273.423022) (xy 379.454931 -273.376202) (xy 379.442752 -273.326788) (xy 379.438657 -273.27606)
			(xy 378.190506 -273.27606) (xy 378.189994 -273.301506) (xy 378.18183 -273.35174) (xy 378.165714 -273.400014)
			(xy 378.142063 -273.445077) (xy 378.11149 -273.485763) (xy 378.074786 -273.521018) (xy 378.032902 -273.549928)
			(xy 377.986923 -273.571745) (xy 377.938039 -273.585905) (xy 377.887518 -273.592039) (xy 377.836666 -273.58999)
			(xy 377.786802 -273.57981) (xy 377.739216 -273.561763) (xy 377.695142 -273.536317) (xy 377.65572 -273.50413)
			(xy 377.621972 -273.466036) (xy 377.594771 -273.423022) (xy 377.574823 -273.376202) (xy 377.562644 -273.326788)
			(xy 377.558549 -273.27606) (xy 377.240038 -273.27606) (xy 377.239543 -273.300667) (xy 377.231648 -273.349244)
			(xy 377.216064 -273.395925) (xy 377.193193 -273.439502) (xy 377.163628 -273.478846) (xy 377.128135 -273.512938)
			(xy 377.087632 -273.540894) (xy 377.04317 -273.561992) (xy 376.995899 -273.575684) (xy 376.947044 -273.581616)
			(xy 376.897869 -273.579635) (xy 376.84965 -273.569791) (xy 376.803634 -273.552339) (xy 376.761013 -273.527732)
			(xy 376.722892 -273.496607) (xy 376.690257 -273.45977) (xy 376.663954 -273.418174) (xy 376.644663 -273.372898)
			(xy 376.632886 -273.325114) (xy 376.628926 -273.27606) (xy 376.310652 -273.27606) (xy 376.31014 -273.301506)
			(xy 376.301976 -273.35174) (xy 376.28586 -273.400014) (xy 376.262209 -273.445077) (xy 376.231636 -273.485763)
			(xy 376.194932 -273.521018) (xy 376.153048 -273.549928) (xy 376.107069 -273.571745) (xy 376.058185 -273.585905)
			(xy 376.007664 -273.592039) (xy 375.956812 -273.58999) (xy 375.906948 -273.57981) (xy 375.859362 -273.561763)
			(xy 375.815288 -273.536317) (xy 375.775866 -273.50413) (xy 375.742118 -273.466036) (xy 375.714917 -273.423022)
			(xy 375.694969 -273.376202) (xy 375.68279 -273.326788) (xy 375.678695 -273.27606) (xy 375.528078 -273.27606)
			(xy 375.528078 -273.464274) (xy 375.528126 -273.467943) (xy 375.529151 -273.47521) (xy 375.53011 -273.478752)
			(xy 375.532904 -273.487896) (xy 375.534936 -273.493484) (xy 375.539 -273.503136) (xy 375.552505 -273.525471)
			(xy 375.577661 -273.57121) (xy 375.589292 -273.594576) (xy 375.592848 -273.601942) (xy 375.830846 -273.83994)
			(xy 375.837551 -273.847181) (xy 375.845129 -273.865386) (xy 375.845578 -273.875246) (xy 375.845578 -274.005548)
			(xy 375.846848 -274.011136) (xy 375.850893 -274.029604) (xy 375.855221 -274.067162) (xy 375.855484 -274.086066)
			(xy 376.148595 -274.086066) (xy 376.15269 -274.035338) (xy 376.164869 -273.985924) (xy 376.184817 -273.939104)
			(xy 376.212018 -273.89609) (xy 376.245766 -273.857996) (xy 376.285188 -273.825809) (xy 376.329262 -273.800363)
			(xy 376.376848 -273.782316) (xy 376.426712 -273.772136) (xy 376.477564 -273.770087) (xy 376.528085 -273.776221)
			(xy 376.576969 -273.790381) (xy 376.622948 -273.812198) (xy 376.664832 -273.841108) (xy 376.701536 -273.876363)
			(xy 376.732109 -273.917049) (xy 376.75576 -273.962112) (xy 376.771876 -274.010386) (xy 376.78004 -274.06062)
			(xy 376.780552 -274.086066) (xy 377.088649 -274.086066) (xy 377.092744 -274.035338) (xy 377.104923 -273.985924)
			(xy 377.124871 -273.939104) (xy 377.152072 -273.89609) (xy 377.18582 -273.857996) (xy 377.225242 -273.825809)
			(xy 377.269316 -273.800363) (xy 377.316902 -273.782316) (xy 377.366766 -273.772136) (xy 377.417618 -273.770087)
			(xy 377.468139 -273.776221) (xy 377.517023 -273.790381) (xy 377.563002 -273.812198) (xy 377.604886 -273.841108)
			(xy 377.64159 -273.876363) (xy 377.672163 -273.917049) (xy 377.695814 -273.962112) (xy 377.71193 -274.010386)
			(xy 377.720094 -274.06062) (xy 377.720606 -274.086066) (xy 378.039134 -274.086066) (xy 378.043094 -274.037012)
			(xy 378.054871 -273.989228) (xy 378.074162 -273.943952) (xy 378.100465 -273.902356) (xy 378.1331 -273.865519)
			(xy 378.171221 -273.834394) (xy 378.213842 -273.809787) (xy 378.259858 -273.792335) (xy 378.308077 -273.782491)
			(xy 378.357252 -273.78051) (xy 378.406107 -273.786442) (xy 378.453378 -273.800134) (xy 378.49784 -273.821232)
			(xy 378.538343 -273.849188) (xy 378.573836 -273.88328) (xy 378.603401 -273.922624) (xy 378.626272 -273.966201)
			(xy 378.641856 -274.012882) (xy 378.649751 -274.061459) (xy 378.650246 -274.086066) (xy 378.968503 -274.086066)
			(xy 378.972598 -274.035338) (xy 378.984777 -273.985924) (xy 379.004725 -273.939104) (xy 379.031926 -273.89609)
			(xy 379.065674 -273.857996) (xy 379.105096 -273.825809) (xy 379.14917 -273.800363) (xy 379.196756 -273.782316)
			(xy 379.24662 -273.772136) (xy 379.297472 -273.770087) (xy 379.347993 -273.776221) (xy 379.396877 -273.790381)
			(xy 379.442856 -273.812198) (xy 379.48474 -273.841108) (xy 379.521444 -273.876363) (xy 379.552017 -273.917049)
			(xy 379.575668 -273.962112) (xy 379.591784 -274.010386) (xy 379.599948 -274.06062) (xy 379.60046 -274.086066)
			(xy 379.918988 -274.086066) (xy 379.922948 -274.037012) (xy 379.934725 -273.989228) (xy 379.954016 -273.943952)
			(xy 379.980319 -273.902356) (xy 380.012954 -273.865519) (xy 380.051075 -273.834394) (xy 380.093696 -273.809787)
			(xy 380.139712 -273.792335) (xy 380.187931 -273.782491) (xy 380.237106 -273.78051) (xy 380.285961 -273.786442)
			(xy 380.333232 -273.800134) (xy 380.377694 -273.821232) (xy 380.418197 -273.849188) (xy 380.45369 -273.88328)
			(xy 380.483255 -273.922624) (xy 380.506126 -273.966201) (xy 380.52171 -274.012882) (xy 380.529605 -274.061459)
			(xy 380.5301 -274.086066) (xy 380.848611 -274.086066) (xy 380.852706 -274.035338) (xy 380.864885 -273.985924)
			(xy 380.884833 -273.939104) (xy 380.912034 -273.89609) (xy 380.945782 -273.857996) (xy 380.985204 -273.825809)
			(xy 381.029278 -273.800363) (xy 381.076864 -273.782316) (xy 381.126728 -273.772136) (xy 381.17758 -273.770087)
			(xy 381.228101 -273.776221) (xy 381.276985 -273.790381) (xy 381.322964 -273.812198) (xy 381.364848 -273.841108)
			(xy 381.401552 -273.876363) (xy 381.432125 -273.917049) (xy 381.455776 -273.962112) (xy 381.471892 -274.010386)
			(xy 381.480056 -274.06062) (xy 381.480568 -274.086066) (xy 381.799096 -274.086066) (xy 381.803056 -274.037012)
			(xy 381.814833 -273.989228) (xy 381.834124 -273.943952) (xy 381.860427 -273.902356) (xy 381.893062 -273.865519)
			(xy 381.931183 -273.834394) (xy 381.973804 -273.809787) (xy 382.01982 -273.792335) (xy 382.068039 -273.782491)
			(xy 382.117214 -273.78051) (xy 382.166069 -273.786442) (xy 382.21334 -273.800134) (xy 382.257802 -273.821232)
			(xy 382.298305 -273.849188) (xy 382.333798 -273.88328) (xy 382.363363 -273.922624) (xy 382.386234 -273.966201)
			(xy 382.401818 -274.012882) (xy 382.409713 -274.061459) (xy 382.410208 -274.086066) (xy 382.738896 -274.086066)
			(xy 382.742856 -274.037012) (xy 382.754633 -273.989228) (xy 382.773924 -273.943952) (xy 382.800227 -273.902356)
			(xy 382.832862 -273.865519) (xy 382.870983 -273.834394) (xy 382.913604 -273.809787) (xy 382.95962 -273.792335)
			(xy 383.007839 -273.782491) (xy 383.057014 -273.78051) (xy 383.105869 -273.786442) (xy 383.15314 -273.800134)
			(xy 383.197602 -273.821232) (xy 383.238105 -273.849188) (xy 383.273598 -273.88328) (xy 383.303163 -273.922624)
			(xy 383.326034 -273.966201) (xy 383.341618 -274.012882) (xy 383.349513 -274.061459) (xy 383.350008 -274.086066)
			(xy 383.67895 -274.086066) (xy 383.68291 -274.037012) (xy 383.694687 -273.989228) (xy 383.713978 -273.943952)
			(xy 383.740281 -273.902356) (xy 383.772916 -273.865519) (xy 383.811037 -273.834394) (xy 383.853658 -273.809787)
			(xy 383.899674 -273.792335) (xy 383.947893 -273.782491) (xy 383.997068 -273.78051) (xy 384.045923 -273.786442)
			(xy 384.093194 -273.800134) (xy 384.137656 -273.821232) (xy 384.178159 -273.849188) (xy 384.213652 -273.88328)
			(xy 384.243217 -273.922624) (xy 384.266088 -273.966201) (xy 384.281672 -274.012882) (xy 384.289567 -274.061459)
			(xy 384.290062 -274.086066) (xy 384.289567 -274.110673) (xy 384.281672 -274.15925) (xy 384.266088 -274.205931)
			(xy 384.243217 -274.249508) (xy 384.213652 -274.288852) (xy 384.178159 -274.322944) (xy 384.137656 -274.3509)
			(xy 384.093194 -274.371998) (xy 384.045923 -274.38569) (xy 383.997068 -274.391622) (xy 383.947893 -274.389641)
			(xy 383.899674 -274.379797) (xy 383.853658 -274.362345) (xy 383.811037 -274.337738) (xy 383.772916 -274.306613)
			(xy 383.740281 -274.269776) (xy 383.713978 -274.22818) (xy 383.694687 -274.182904) (xy 383.68291 -274.13512)
			(xy 383.67895 -274.086066) (xy 383.350008 -274.086066) (xy 383.349513 -274.110673) (xy 383.341618 -274.15925)
			(xy 383.326034 -274.205931) (xy 383.303163 -274.249508) (xy 383.273598 -274.288852) (xy 383.238105 -274.322944)
			(xy 383.197602 -274.3509) (xy 383.15314 -274.371998) (xy 383.105869 -274.38569) (xy 383.057014 -274.391622)
			(xy 383.007839 -274.389641) (xy 382.95962 -274.379797) (xy 382.913604 -274.362345) (xy 382.870983 -274.337738)
			(xy 382.832862 -274.306613) (xy 382.800227 -274.269776) (xy 382.773924 -274.22818) (xy 382.754633 -274.182904)
			(xy 382.742856 -274.13512) (xy 382.738896 -274.086066) (xy 382.410208 -274.086066) (xy 382.409713 -274.110673)
			(xy 382.401818 -274.15925) (xy 382.386234 -274.205931) (xy 382.363363 -274.249508) (xy 382.333798 -274.288852)
			(xy 382.298305 -274.322944) (xy 382.257802 -274.3509) (xy 382.21334 -274.371998) (xy 382.166069 -274.38569)
			(xy 382.117214 -274.391622) (xy 382.068039 -274.389641) (xy 382.01982 -274.379797) (xy 381.973804 -274.362345)
			(xy 381.931183 -274.337738) (xy 381.893062 -274.306613) (xy 381.860427 -274.269776) (xy 381.834124 -274.22818)
			(xy 381.814833 -274.182904) (xy 381.803056 -274.13512) (xy 381.799096 -274.086066) (xy 381.480568 -274.086066)
			(xy 381.480056 -274.111512) (xy 381.471892 -274.161746) (xy 381.455776 -274.21002) (xy 381.432125 -274.255083)
			(xy 381.401552 -274.295769) (xy 381.364848 -274.331024) (xy 381.322964 -274.359934) (xy 381.276985 -274.381751)
			(xy 381.228101 -274.395911) (xy 381.17758 -274.402045) (xy 381.126728 -274.399996) (xy 381.076864 -274.389816)
			(xy 381.029278 -274.371769) (xy 380.985204 -274.346323) (xy 380.945782 -274.314136) (xy 380.912034 -274.276042)
			(xy 380.884833 -274.233028) (xy 380.864885 -274.186208) (xy 380.852706 -274.136794) (xy 380.848611 -274.086066)
			(xy 380.5301 -274.086066) (xy 380.529605 -274.110673) (xy 380.52171 -274.15925) (xy 380.506126 -274.205931)
			(xy 380.483255 -274.249508) (xy 380.45369 -274.288852) (xy 380.418197 -274.322944) (xy 380.377694 -274.3509)
			(xy 380.333232 -274.371998) (xy 380.285961 -274.38569) (xy 380.237106 -274.391622) (xy 380.187931 -274.389641)
			(xy 380.139712 -274.379797) (xy 380.093696 -274.362345) (xy 380.051075 -274.337738) (xy 380.012954 -274.306613)
			(xy 379.980319 -274.269776) (xy 379.954016 -274.22818) (xy 379.934725 -274.182904) (xy 379.922948 -274.13512)
			(xy 379.918988 -274.086066) (xy 379.60046 -274.086066) (xy 379.599948 -274.111512) (xy 379.591784 -274.161746)
			(xy 379.575668 -274.21002) (xy 379.552017 -274.255083) (xy 379.521444 -274.295769) (xy 379.48474 -274.331024)
			(xy 379.442856 -274.359934) (xy 379.396877 -274.381751) (xy 379.347993 -274.395911) (xy 379.297472 -274.402045)
			(xy 379.24662 -274.399996) (xy 379.196756 -274.389816) (xy 379.14917 -274.371769) (xy 379.105096 -274.346323)
			(xy 379.065674 -274.314136) (xy 379.031926 -274.276042) (xy 379.004725 -274.233028) (xy 378.984777 -274.186208)
			(xy 378.972598 -274.136794) (xy 378.968503 -274.086066) (xy 378.650246 -274.086066) (xy 378.649751 -274.110673)
			(xy 378.641856 -274.15925) (xy 378.626272 -274.205931) (xy 378.603401 -274.249508) (xy 378.573836 -274.288852)
			(xy 378.538343 -274.322944) (xy 378.49784 -274.3509) (xy 378.453378 -274.371998) (xy 378.406107 -274.38569)
			(xy 378.357252 -274.391622) (xy 378.308077 -274.389641) (xy 378.259858 -274.379797) (xy 378.213842 -274.362345)
			(xy 378.171221 -274.337738) (xy 378.1331 -274.306613) (xy 378.100465 -274.269776) (xy 378.074162 -274.22818)
			(xy 378.054871 -274.182904) (xy 378.043094 -274.13512) (xy 378.039134 -274.086066) (xy 377.720606 -274.086066)
			(xy 377.720094 -274.111512) (xy 377.71193 -274.161746) (xy 377.695814 -274.21002) (xy 377.672163 -274.255083)
			(xy 377.64159 -274.295769) (xy 377.604886 -274.331024) (xy 377.563002 -274.359934) (xy 377.517023 -274.381751)
			(xy 377.468139 -274.395911) (xy 377.417618 -274.402045) (xy 377.366766 -274.399996) (xy 377.316902 -274.389816)
			(xy 377.269316 -274.371769) (xy 377.225242 -274.346323) (xy 377.18582 -274.314136) (xy 377.152072 -274.276042)
			(xy 377.124871 -274.233028) (xy 377.104923 -274.186208) (xy 377.092744 -274.136794) (xy 377.088649 -274.086066)
			(xy 376.780552 -274.086066) (xy 376.78004 -274.111512) (xy 376.771876 -274.161746) (xy 376.75576 -274.21002)
			(xy 376.732109 -274.255083) (xy 376.701536 -274.295769) (xy 376.664832 -274.331024) (xy 376.622948 -274.359934)
			(xy 376.576969 -274.381751) (xy 376.528085 -274.395911) (xy 376.477564 -274.402045) (xy 376.426712 -274.399996)
			(xy 376.376848 -274.389816) (xy 376.329262 -274.371769) (xy 376.285188 -274.346323) (xy 376.245766 -274.314136)
			(xy 376.212018 -274.276042) (xy 376.184817 -274.233028) (xy 376.164869 -274.186208) (xy 376.15269 -274.136794)
			(xy 376.148595 -274.086066) (xy 375.855484 -274.086066) (xy 375.855197 -274.104968) (xy 375.850868 -274.142524)
			(xy 375.846848 -274.160996) (xy 375.845578 -274.166584) (xy 375.845578 -274.273518) (xy 375.845051 -274.283359)
			(xy 375.837475 -274.301532) (xy 375.830846 -274.308824) (xy 375.622058 -274.517612) (xy 375.615708 -274.525232)
			(xy 375.608596 -274.5359) (xy 375.606818 -274.540218) (xy 375.593696 -274.569184) (xy 375.564595 -274.625734)
			(xy 375.548652 -274.653248) (xy 375.54535 -274.658836) (xy 375.539762 -274.678394) (xy 375.538238 -274.690586)
			(xy 375.538238 -274.896072) (xy 375.678695 -274.896072) (xy 375.68279 -274.845344) (xy 375.694969 -274.79593)
			(xy 375.714917 -274.74911) (xy 375.742118 -274.706096) (xy 375.775866 -274.668002) (xy 375.815288 -274.635815)
			(xy 375.859362 -274.610369) (xy 375.906948 -274.592322) (xy 375.956812 -274.582142) (xy 376.007664 -274.580093)
			(xy 376.058185 -274.586227) (xy 376.107069 -274.600387) (xy 376.153048 -274.622204) (xy 376.194932 -274.651114)
			(xy 376.231636 -274.686369) (xy 376.262209 -274.727055) (xy 376.28586 -274.772118) (xy 376.301976 -274.820392)
			(xy 376.31014 -274.870626) (xy 376.310652 -274.896072) (xy 376.628926 -274.896072) (xy 376.632886 -274.847018)
			(xy 376.644663 -274.799234) (xy 376.663954 -274.753958) (xy 376.690257 -274.712362) (xy 376.722892 -274.675525)
			(xy 376.761013 -274.6444) (xy 376.803634 -274.619793) (xy 376.84965 -274.602341) (xy 376.897869 -274.592497)
			(xy 376.947044 -274.590516) (xy 376.995899 -274.596448) (xy 377.04317 -274.61014) (xy 377.087632 -274.631238)
			(xy 377.128135 -274.659194) (xy 377.163628 -274.693286) (xy 377.193193 -274.73263) (xy 377.216064 -274.776207)
			(xy 377.231648 -274.822888) (xy 377.239543 -274.871465) (xy 377.240038 -274.896072) (xy 377.558549 -274.896072)
			(xy 377.562644 -274.845344) (xy 377.574823 -274.79593) (xy 377.594771 -274.74911) (xy 377.621972 -274.706096)
			(xy 377.65572 -274.668002) (xy 377.695142 -274.635815) (xy 377.739216 -274.610369) (xy 377.786802 -274.592322)
			(xy 377.836666 -274.582142) (xy 377.887518 -274.580093) (xy 377.938039 -274.586227) (xy 377.986923 -274.600387)
			(xy 378.032902 -274.622204) (xy 378.074786 -274.651114) (xy 378.11149 -274.686369) (xy 378.142063 -274.727055)
			(xy 378.165714 -274.772118) (xy 378.18183 -274.820392) (xy 378.189994 -274.870626) (xy 378.190506 -274.896072)
			(xy 378.509034 -274.896072) (xy 378.512994 -274.847018) (xy 378.524771 -274.799234) (xy 378.544062 -274.753958)
			(xy 378.570365 -274.712362) (xy 378.603 -274.675525) (xy 378.641121 -274.6444) (xy 378.683742 -274.619793)
			(xy 378.729758 -274.602341) (xy 378.777977 -274.592497) (xy 378.827152 -274.590516) (xy 378.876007 -274.596448)
			(xy 378.923278 -274.61014) (xy 378.96774 -274.631238) (xy 379.008243 -274.659194) (xy 379.043736 -274.693286)
			(xy 379.073301 -274.73263) (xy 379.096172 -274.776207) (xy 379.111756 -274.822888) (xy 379.119651 -274.871465)
			(xy 379.120146 -274.896072) (xy 379.438657 -274.896072) (xy 379.442752 -274.845344) (xy 379.454931 -274.79593)
			(xy 379.474879 -274.74911) (xy 379.50208 -274.706096) (xy 379.535828 -274.668002) (xy 379.57525 -274.635815)
			(xy 379.619324 -274.610369) (xy 379.66691 -274.592322) (xy 379.716774 -274.582142) (xy 379.767626 -274.580093)
			(xy 379.818147 -274.586227) (xy 379.867031 -274.600387) (xy 379.91301 -274.622204) (xy 379.954894 -274.651114)
			(xy 379.991598 -274.686369) (xy 380.022171 -274.727055) (xy 380.045822 -274.772118) (xy 380.061938 -274.820392)
			(xy 380.070102 -274.870626) (xy 380.070614 -274.896072) (xy 380.378711 -274.896072) (xy 380.382806 -274.845344)
			(xy 380.394985 -274.79593) (xy 380.414933 -274.74911) (xy 380.442134 -274.706096) (xy 380.475882 -274.668002)
			(xy 380.515304 -274.635815) (xy 380.559378 -274.610369) (xy 380.606964 -274.592322) (xy 380.656828 -274.582142)
			(xy 380.70768 -274.580093) (xy 380.758201 -274.586227) (xy 380.807085 -274.600387) (xy 380.853064 -274.622204)
			(xy 380.894948 -274.651114) (xy 380.931652 -274.686369) (xy 380.962225 -274.727055) (xy 380.985876 -274.772118)
			(xy 381.001992 -274.820392) (xy 381.010156 -274.870626) (xy 381.010668 -274.896072) (xy 381.328942 -274.896072)
			(xy 381.332902 -274.847018) (xy 381.344679 -274.799234) (xy 381.36397 -274.753958) (xy 381.390273 -274.712362)
			(xy 381.422908 -274.675525) (xy 381.461029 -274.6444) (xy 381.50365 -274.619793) (xy 381.549666 -274.602341)
			(xy 381.597885 -274.592497) (xy 381.64706 -274.590516) (xy 381.695915 -274.596448) (xy 381.743186 -274.61014)
			(xy 381.787648 -274.631238) (xy 381.828151 -274.659194) (xy 381.863644 -274.693286) (xy 381.893209 -274.73263)
			(xy 381.91608 -274.776207) (xy 381.931664 -274.822888) (xy 381.939559 -274.871465) (xy 381.940054 -274.896072)
			(xy 382.268996 -274.896072) (xy 382.272956 -274.847018) (xy 382.284733 -274.799234) (xy 382.304024 -274.753958)
			(xy 382.330327 -274.712362) (xy 382.362962 -274.675525) (xy 382.401083 -274.6444) (xy 382.443704 -274.619793)
			(xy 382.48972 -274.602341) (xy 382.537939 -274.592497) (xy 382.587114 -274.590516) (xy 382.635969 -274.596448)
			(xy 382.68324 -274.61014) (xy 382.727702 -274.631238) (xy 382.768205 -274.659194) (xy 382.803698 -274.693286)
			(xy 382.833263 -274.73263) (xy 382.856134 -274.776207) (xy 382.871718 -274.822888) (xy 382.879613 -274.871465)
			(xy 382.880108 -274.896072) (xy 383.20905 -274.896072) (xy 383.21301 -274.847018) (xy 383.224787 -274.799234)
			(xy 383.244078 -274.753958) (xy 383.270381 -274.712362) (xy 383.303016 -274.675525) (xy 383.341137 -274.6444)
			(xy 383.383758 -274.619793) (xy 383.429774 -274.602341) (xy 383.477993 -274.592497) (xy 383.527168 -274.590516)
			(xy 383.576023 -274.596448) (xy 383.623294 -274.61014) (xy 383.667756 -274.631238) (xy 383.708259 -274.659194)
			(xy 383.743752 -274.693286) (xy 383.773317 -274.73263) (xy 383.796188 -274.776207) (xy 383.811772 -274.822888)
			(xy 383.819667 -274.871465) (xy 383.820162 -274.896072) (xy 384.149104 -274.896072) (xy 384.153064 -274.847018)
			(xy 384.164841 -274.799234) (xy 384.184132 -274.753958) (xy 384.210435 -274.712362) (xy 384.24307 -274.675525)
			(xy 384.281191 -274.6444) (xy 384.323812 -274.619793) (xy 384.369828 -274.602341) (xy 384.418047 -274.592497)
			(xy 384.467222 -274.590516) (xy 384.516077 -274.596448) (xy 384.563348 -274.61014) (xy 384.60781 -274.631238)
			(xy 384.648313 -274.659194) (xy 384.683806 -274.693286) (xy 384.713371 -274.73263) (xy 384.736242 -274.776207)
			(xy 384.751826 -274.822888) (xy 384.759721 -274.871465) (xy 384.760216 -274.896072) (xy 384.759721 -274.920679)
			(xy 384.751826 -274.969256) (xy 384.736242 -275.015937) (xy 384.713371 -275.059514) (xy 384.683806 -275.098858)
			(xy 384.648313 -275.13295) (xy 384.60781 -275.160906) (xy 384.563348 -275.182004) (xy 384.516077 -275.195696)
			(xy 384.467222 -275.201628) (xy 384.418047 -275.199647) (xy 384.369828 -275.189803) (xy 384.323812 -275.172351)
			(xy 384.281191 -275.147744) (xy 384.24307 -275.116619) (xy 384.210435 -275.079782) (xy 384.184132 -275.038186)
			(xy 384.164841 -274.99291) (xy 384.153064 -274.945126) (xy 384.149104 -274.896072) (xy 383.820162 -274.896072)
			(xy 383.819667 -274.920679) (xy 383.811772 -274.969256) (xy 383.796188 -275.015937) (xy 383.773317 -275.059514)
			(xy 383.743752 -275.098858) (xy 383.708259 -275.13295) (xy 383.667756 -275.160906) (xy 383.623294 -275.182004)
			(xy 383.576023 -275.195696) (xy 383.527168 -275.201628) (xy 383.477993 -275.199647) (xy 383.429774 -275.189803)
			(xy 383.383758 -275.172351) (xy 383.341137 -275.147744) (xy 383.303016 -275.116619) (xy 383.270381 -275.079782)
			(xy 383.244078 -275.038186) (xy 383.224787 -274.99291) (xy 383.21301 -274.945126) (xy 383.20905 -274.896072)
			(xy 382.880108 -274.896072) (xy 382.879613 -274.920679) (xy 382.871718 -274.969256) (xy 382.856134 -275.015937)
			(xy 382.833263 -275.059514) (xy 382.803698 -275.098858) (xy 382.768205 -275.13295) (xy 382.727702 -275.160906)
			(xy 382.68324 -275.182004) (xy 382.635969 -275.195696) (xy 382.587114 -275.201628) (xy 382.537939 -275.199647)
			(xy 382.48972 -275.189803) (xy 382.443704 -275.172351) (xy 382.401083 -275.147744) (xy 382.362962 -275.116619)
			(xy 382.330327 -275.079782) (xy 382.304024 -275.038186) (xy 382.284733 -274.99291) (xy 382.272956 -274.945126)
			(xy 382.268996 -274.896072) (xy 381.940054 -274.896072) (xy 381.939559 -274.920679) (xy 381.931664 -274.969256)
			(xy 381.91608 -275.015937) (xy 381.893209 -275.059514) (xy 381.863644 -275.098858) (xy 381.828151 -275.13295)
			(xy 381.787648 -275.160906) (xy 381.743186 -275.182004) (xy 381.695915 -275.195696) (xy 381.64706 -275.201628)
			(xy 381.597885 -275.199647) (xy 381.549666 -275.189803) (xy 381.50365 -275.172351) (xy 381.461029 -275.147744)
			(xy 381.422908 -275.116619) (xy 381.390273 -275.079782) (xy 381.36397 -275.038186) (xy 381.344679 -274.99291)
			(xy 381.332902 -274.945126) (xy 381.328942 -274.896072) (xy 381.010668 -274.896072) (xy 381.010156 -274.921518)
			(xy 381.001992 -274.971752) (xy 380.985876 -275.020026) (xy 380.962225 -275.065089) (xy 380.931652 -275.105775)
			(xy 380.894948 -275.14103) (xy 380.853064 -275.16994) (xy 380.807085 -275.191757) (xy 380.758201 -275.205917)
			(xy 380.70768 -275.212051) (xy 380.656828 -275.210002) (xy 380.606964 -275.199822) (xy 380.559378 -275.181775)
			(xy 380.515304 -275.156329) (xy 380.475882 -275.124142) (xy 380.442134 -275.086048) (xy 380.414933 -275.043034)
			(xy 380.394985 -274.996214) (xy 380.382806 -274.9468) (xy 380.378711 -274.896072) (xy 380.070614 -274.896072)
			(xy 380.070102 -274.921518) (xy 380.061938 -274.971752) (xy 380.045822 -275.020026) (xy 380.022171 -275.065089)
			(xy 379.991598 -275.105775) (xy 379.954894 -275.14103) (xy 379.91301 -275.16994) (xy 379.867031 -275.191757)
			(xy 379.818147 -275.205917) (xy 379.767626 -275.212051) (xy 379.716774 -275.210002) (xy 379.66691 -275.199822)
			(xy 379.619324 -275.181775) (xy 379.57525 -275.156329) (xy 379.535828 -275.124142) (xy 379.50208 -275.086048)
			(xy 379.474879 -275.043034) (xy 379.454931 -274.996214) (xy 379.442752 -274.9468) (xy 379.438657 -274.896072)
			(xy 379.120146 -274.896072) (xy 379.119651 -274.920679) (xy 379.111756 -274.969256) (xy 379.096172 -275.015937)
			(xy 379.073301 -275.059514) (xy 379.043736 -275.098858) (xy 379.008243 -275.13295) (xy 378.96774 -275.160906)
			(xy 378.923278 -275.182004) (xy 378.876007 -275.195696) (xy 378.827152 -275.201628) (xy 378.777977 -275.199647)
			(xy 378.729758 -275.189803) (xy 378.683742 -275.172351) (xy 378.641121 -275.147744) (xy 378.603 -275.116619)
			(xy 378.570365 -275.079782) (xy 378.544062 -275.038186) (xy 378.524771 -274.99291) (xy 378.512994 -274.945126)
			(xy 378.509034 -274.896072) (xy 378.190506 -274.896072) (xy 378.189994 -274.921518) (xy 378.18183 -274.971752)
			(xy 378.165714 -275.020026) (xy 378.142063 -275.065089) (xy 378.11149 -275.105775) (xy 378.074786 -275.14103)
			(xy 378.032902 -275.16994) (xy 377.986923 -275.191757) (xy 377.938039 -275.205917) (xy 377.887518 -275.212051)
			(xy 377.836666 -275.210002) (xy 377.786802 -275.199822) (xy 377.739216 -275.181775) (xy 377.695142 -275.156329)
			(xy 377.65572 -275.124142) (xy 377.621972 -275.086048) (xy 377.594771 -275.043034) (xy 377.574823 -274.996214)
			(xy 377.562644 -274.9468) (xy 377.558549 -274.896072) (xy 377.240038 -274.896072) (xy 377.239543 -274.920679)
			(xy 377.231648 -274.969256) (xy 377.216064 -275.015937) (xy 377.193193 -275.059514) (xy 377.163628 -275.098858)
			(xy 377.128135 -275.13295) (xy 377.087632 -275.160906) (xy 377.04317 -275.182004) (xy 376.995899 -275.195696)
			(xy 376.947044 -275.201628) (xy 376.897869 -275.199647) (xy 376.84965 -275.189803) (xy 376.803634 -275.172351)
			(xy 376.761013 -275.147744) (xy 376.722892 -275.116619) (xy 376.690257 -275.079782) (xy 376.663954 -275.038186)
			(xy 376.644663 -274.99291) (xy 376.632886 -274.945126) (xy 376.628926 -274.896072) (xy 376.310652 -274.896072)
			(xy 376.31014 -274.921518) (xy 376.301976 -274.971752) (xy 376.28586 -275.020026) (xy 376.262209 -275.065089)
			(xy 376.231636 -275.105775) (xy 376.194932 -275.14103) (xy 376.153048 -275.16994) (xy 376.107069 -275.191757)
			(xy 376.058185 -275.205917) (xy 376.007664 -275.212051) (xy 375.956812 -275.210002) (xy 375.906948 -275.199822)
			(xy 375.859362 -275.181775) (xy 375.815288 -275.156329) (xy 375.775866 -275.124142) (xy 375.742118 -275.086048)
			(xy 375.714917 -275.043034) (xy 375.694969 -274.996214) (xy 375.68279 -274.9468) (xy 375.678695 -274.896072)
			(xy 375.538238 -274.896072) (xy 375.538238 -275.101558) (xy 375.539762 -275.11375) (xy 375.54535 -275.133308)
			(xy 375.548652 -275.138896) (xy 375.573012 -275.181414) (xy 375.615056 -275.269934) (xy 375.649197 -275.361793)
			(xy 375.662698 -275.408898) (xy 375.664043 -275.413389) (xy 375.668132 -275.421825) (xy 375.670826 -275.425662)
			(xy 375.686828 -275.446998) (xy 375.694194 -275.452078) (xy 375.70669 -275.460633) (xy 375.730106 -275.479841)
			(xy 375.74093 -275.490432) (xy 375.756725 -275.506815) (xy 375.783767 -275.543415) (xy 375.794778 -275.56333)
			(xy 375.798334 -275.570188) (xy 375.810526 -275.58238) (xy 375.817243 -275.589617) (xy 375.824846 -275.607822)
			(xy 375.825258 -275.617686) (xy 375.825258 -275.650452) (xy 375.82602 -275.654516) (xy 375.82799 -275.66725)
			(xy 375.830022 -275.692939) (xy 375.830084 -275.705824) (xy 375.830084 -275.706078) (xy 376.148595 -275.706078)
			(xy 376.15269 -275.65535) (xy 376.164869 -275.605936) (xy 376.184817 -275.559116) (xy 376.212018 -275.516102)
			(xy 376.245766 -275.478008) (xy 376.285188 -275.445821) (xy 376.329262 -275.420375) (xy 376.376848 -275.402328)
			(xy 376.426712 -275.392148) (xy 376.477564 -275.390099) (xy 376.528085 -275.396233) (xy 376.576969 -275.410393)
			(xy 376.622948 -275.43221) (xy 376.664832 -275.46112) (xy 376.701536 -275.496375) (xy 376.732109 -275.537061)
			(xy 376.75576 -275.582124) (xy 376.771876 -275.630398) (xy 376.78004 -275.680632) (xy 376.780552 -275.706078)
			(xy 377.088649 -275.706078) (xy 377.092744 -275.65535) (xy 377.104923 -275.605936) (xy 377.124871 -275.559116)
			(xy 377.152072 -275.516102) (xy 377.18582 -275.478008) (xy 377.225242 -275.445821) (xy 377.269316 -275.420375)
			(xy 377.316902 -275.402328) (xy 377.366766 -275.392148) (xy 377.417618 -275.390099) (xy 377.468139 -275.396233)
			(xy 377.517023 -275.410393) (xy 377.563002 -275.43221) (xy 377.604886 -275.46112) (xy 377.64159 -275.496375)
			(xy 377.672163 -275.537061) (xy 377.695814 -275.582124) (xy 377.71193 -275.630398) (xy 377.720094 -275.680632)
			(xy 377.720606 -275.706078) (xy 378.968503 -275.706078) (xy 378.972598 -275.65535) (xy 378.984777 -275.605936)
			(xy 379.004725 -275.559116) (xy 379.031926 -275.516102) (xy 379.065674 -275.478008) (xy 379.105096 -275.445821)
			(xy 379.14917 -275.420375) (xy 379.196756 -275.402328) (xy 379.24662 -275.392148) (xy 379.297472 -275.390099)
			(xy 379.347993 -275.396233) (xy 379.396877 -275.410393) (xy 379.442856 -275.43221) (xy 379.48474 -275.46112)
			(xy 379.521444 -275.496375) (xy 379.552017 -275.537061) (xy 379.575668 -275.582124) (xy 379.591784 -275.630398)
			(xy 379.599948 -275.680632) (xy 379.60046 -275.706078) (xy 379.918988 -275.706078) (xy 379.922948 -275.657024)
			(xy 379.934725 -275.60924) (xy 379.954016 -275.563964) (xy 379.980319 -275.522368) (xy 380.012954 -275.485531)
			(xy 380.051075 -275.454406) (xy 380.093696 -275.429799) (xy 380.139712 -275.412347) (xy 380.187931 -275.402503)
			(xy 380.237106 -275.400522) (xy 380.285961 -275.406454) (xy 380.333232 -275.420146) (xy 380.377694 -275.441244)
			(xy 380.418197 -275.4692) (xy 380.45369 -275.503292) (xy 380.483255 -275.542636) (xy 380.506126 -275.586213)
			(xy 380.52171 -275.632894) (xy 380.529605 -275.681471) (xy 380.5301 -275.706078) (xy 380.848611 -275.706078)
			(xy 380.852706 -275.65535) (xy 380.864885 -275.605936) (xy 380.884833 -275.559116) (xy 380.912034 -275.516102)
			(xy 380.945782 -275.478008) (xy 380.985204 -275.445821) (xy 381.029278 -275.420375) (xy 381.076864 -275.402328)
			(xy 381.126728 -275.392148) (xy 381.17758 -275.390099) (xy 381.228101 -275.396233) (xy 381.276985 -275.410393)
			(xy 381.322964 -275.43221) (xy 381.364848 -275.46112) (xy 381.401552 -275.496375) (xy 381.432125 -275.537061)
			(xy 381.455776 -275.582124) (xy 381.471892 -275.630398) (xy 381.480056 -275.680632) (xy 381.480568 -275.706078)
			(xy 381.799096 -275.706078) (xy 381.803056 -275.657024) (xy 381.814833 -275.60924) (xy 381.834124 -275.563964)
			(xy 381.860427 -275.522368) (xy 381.893062 -275.485531) (xy 381.931183 -275.454406) (xy 381.973804 -275.429799)
			(xy 382.01982 -275.412347) (xy 382.068039 -275.402503) (xy 382.117214 -275.400522) (xy 382.166069 -275.406454)
			(xy 382.21334 -275.420146) (xy 382.257802 -275.441244) (xy 382.298305 -275.4692) (xy 382.333798 -275.503292)
			(xy 382.363363 -275.542636) (xy 382.386234 -275.586213) (xy 382.401818 -275.632894) (xy 382.409713 -275.681471)
			(xy 382.410208 -275.706078) (xy 382.738896 -275.706078) (xy 382.742856 -275.657024) (xy 382.754633 -275.60924)
			(xy 382.773924 -275.563964) (xy 382.800227 -275.522368) (xy 382.832862 -275.485531) (xy 382.870983 -275.454406)
			(xy 382.913604 -275.429799) (xy 382.95962 -275.412347) (xy 383.007839 -275.402503) (xy 383.057014 -275.400522)
			(xy 383.105869 -275.406454) (xy 383.15314 -275.420146) (xy 383.197602 -275.441244) (xy 383.238105 -275.4692)
			(xy 383.273598 -275.503292) (xy 383.303163 -275.542636) (xy 383.326034 -275.586213) (xy 383.341618 -275.632894)
			(xy 383.349513 -275.681471) (xy 383.350008 -275.706078) (xy 383.67895 -275.706078) (xy 383.68291 -275.657024)
			(xy 383.694687 -275.60924) (xy 383.713978 -275.563964) (xy 383.740281 -275.522368) (xy 383.772916 -275.485531)
			(xy 383.811037 -275.454406) (xy 383.853658 -275.429799) (xy 383.899674 -275.412347) (xy 383.947893 -275.402503)
			(xy 383.997068 -275.400522) (xy 384.045923 -275.406454) (xy 384.093194 -275.420146) (xy 384.137656 -275.441244)
			(xy 384.178159 -275.4692) (xy 384.213652 -275.503292) (xy 384.243217 -275.542636) (xy 384.266088 -275.586213)
			(xy 384.281672 -275.632894) (xy 384.289567 -275.681471) (xy 384.290062 -275.706078) (xy 384.289567 -275.730685)
			(xy 384.281672 -275.779262) (xy 384.266088 -275.825943) (xy 384.243217 -275.86952) (xy 384.213652 -275.908864)
			(xy 384.178159 -275.942956) (xy 384.137656 -275.970912) (xy 384.093194 -275.99201) (xy 384.045923 -276.005702)
			(xy 383.997068 -276.011634) (xy 383.947893 -276.009653) (xy 383.899674 -275.999809) (xy 383.853658 -275.982357)
			(xy 383.811037 -275.95775) (xy 383.772916 -275.926625) (xy 383.740281 -275.889788) (xy 383.713978 -275.848192)
			(xy 383.694687 -275.802916) (xy 383.68291 -275.755132) (xy 383.67895 -275.706078) (xy 383.350008 -275.706078)
			(xy 383.349513 -275.730685) (xy 383.341618 -275.779262) (xy 383.326034 -275.825943) (xy 383.303163 -275.86952)
			(xy 383.273598 -275.908864) (xy 383.238105 -275.942956) (xy 383.197602 -275.970912) (xy 383.15314 -275.99201)
			(xy 383.105869 -276.005702) (xy 383.057014 -276.011634) (xy 383.007839 -276.009653) (xy 382.95962 -275.999809)
			(xy 382.913604 -275.982357) (xy 382.870983 -275.95775) (xy 382.832862 -275.926625) (xy 382.800227 -275.889788)
			(xy 382.773924 -275.848192) (xy 382.754633 -275.802916) (xy 382.742856 -275.755132) (xy 382.738896 -275.706078)
			(xy 382.410208 -275.706078) (xy 382.409713 -275.730685) (xy 382.401818 -275.779262) (xy 382.386234 -275.825943)
			(xy 382.363363 -275.86952) (xy 382.333798 -275.908864) (xy 382.298305 -275.942956) (xy 382.257802 -275.970912)
			(xy 382.21334 -275.99201) (xy 382.166069 -276.005702) (xy 382.117214 -276.011634) (xy 382.068039 -276.009653)
			(xy 382.01982 -275.999809) (xy 381.973804 -275.982357) (xy 381.931183 -275.95775) (xy 381.893062 -275.926625)
			(xy 381.860427 -275.889788) (xy 381.834124 -275.848192) (xy 381.814833 -275.802916) (xy 381.803056 -275.755132)
			(xy 381.799096 -275.706078) (xy 381.480568 -275.706078) (xy 381.480056 -275.731524) (xy 381.471892 -275.781758)
			(xy 381.455776 -275.830032) (xy 381.432125 -275.875095) (xy 381.401552 -275.915781) (xy 381.364848 -275.951036)
			(xy 381.322964 -275.979946) (xy 381.276985 -276.001763) (xy 381.228101 -276.015923) (xy 381.17758 -276.022057)
			(xy 381.126728 -276.020008) (xy 381.076864 -276.009828) (xy 381.029278 -275.991781) (xy 380.985204 -275.966335)
			(xy 380.945782 -275.934148) (xy 380.912034 -275.896054) (xy 380.884833 -275.85304) (xy 380.864885 -275.80622)
			(xy 380.852706 -275.756806) (xy 380.848611 -275.706078) (xy 380.5301 -275.706078) (xy 380.529605 -275.730685)
			(xy 380.52171 -275.779262) (xy 380.506126 -275.825943) (xy 380.483255 -275.86952) (xy 380.45369 -275.908864)
			(xy 380.418197 -275.942956) (xy 380.377694 -275.970912) (xy 380.333232 -275.99201) (xy 380.285961 -276.005702)
			(xy 380.237106 -276.011634) (xy 380.187931 -276.009653) (xy 380.139712 -275.999809) (xy 380.093696 -275.982357)
			(xy 380.051075 -275.95775) (xy 380.012954 -275.926625) (xy 379.980319 -275.889788) (xy 379.954016 -275.848192)
			(xy 379.934725 -275.802916) (xy 379.922948 -275.755132) (xy 379.918988 -275.706078) (xy 379.60046 -275.706078)
			(xy 379.599948 -275.731524) (xy 379.591784 -275.781758) (xy 379.575668 -275.830032) (xy 379.552017 -275.875095)
			(xy 379.521444 -275.915781) (xy 379.48474 -275.951036) (xy 379.442856 -275.979946) (xy 379.396877 -276.001763)
			(xy 379.347993 -276.015923) (xy 379.297472 -276.022057) (xy 379.24662 -276.020008) (xy 379.196756 -276.009828)
			(xy 379.14917 -275.991781) (xy 379.105096 -275.966335) (xy 379.065674 -275.934148) (xy 379.031926 -275.896054)
			(xy 379.004725 -275.85304) (xy 378.984777 -275.80622) (xy 378.972598 -275.756806) (xy 378.968503 -275.706078)
			(xy 377.720606 -275.706078) (xy 377.720094 -275.731524) (xy 377.71193 -275.781758) (xy 377.695814 -275.830032)
			(xy 377.672163 -275.875095) (xy 377.64159 -275.915781) (xy 377.604886 -275.951036) (xy 377.563002 -275.979946)
			(xy 377.517023 -276.001763) (xy 377.468139 -276.015923) (xy 377.417618 -276.022057) (xy 377.366766 -276.020008)
			(xy 377.316902 -276.009828) (xy 377.269316 -275.991781) (xy 377.225242 -275.966335) (xy 377.18582 -275.934148)
			(xy 377.152072 -275.896054) (xy 377.124871 -275.85304) (xy 377.104923 -275.80622) (xy 377.092744 -275.756806)
			(xy 377.088649 -275.706078) (xy 376.780552 -275.706078) (xy 376.78004 -275.731524) (xy 376.771876 -275.781758)
			(xy 376.75576 -275.830032) (xy 376.732109 -275.875095) (xy 376.701536 -275.915781) (xy 376.664832 -275.951036)
			(xy 376.622948 -275.979946) (xy 376.576969 -276.001763) (xy 376.528085 -276.015923) (xy 376.477564 -276.022057)
			(xy 376.426712 -276.020008) (xy 376.376848 -276.009828) (xy 376.329262 -275.991781) (xy 376.285188 -275.966335)
			(xy 376.245766 -275.934148) (xy 376.212018 -275.896054) (xy 376.184817 -275.85304) (xy 376.164869 -275.80622)
			(xy 376.15269 -275.756806) (xy 376.148595 -275.706078) (xy 375.830084 -275.706078) (xy 375.830084 -275.706332)
			(xy 375.830011 -275.719217) (xy 375.827977 -275.744905) (xy 375.82602 -275.75764) (xy 375.825258 -275.761704)
			(xy 375.825258 -275.838158) (xy 375.824726 -275.847998) (xy 375.817148 -275.866168) (xy 375.810526 -275.873464)
			(xy 375.664476 -276.019514) (xy 375.660321 -276.023951) (xy 375.654032 -276.034349) (xy 375.65203 -276.040088)
			(xy 375.639868 -276.077847) (xy 375.610904 -276.151706) (xy 375.576785 -276.223331) (xy 375.557542 -276.25802)
			(xy 375.554488 -276.263785) (xy 375.551143 -276.276391) (xy 375.550938 -276.282912) (xy 375.550938 -276.516084)
			(xy 375.678695 -276.516084) (xy 375.68279 -276.465356) (xy 375.694969 -276.415942) (xy 375.714917 -276.369122)
			(xy 375.742118 -276.326108) (xy 375.775866 -276.288014) (xy 375.815288 -276.255827) (xy 375.859362 -276.230381)
			(xy 375.906948 -276.212334) (xy 375.956812 -276.202154) (xy 376.007664 -276.200105) (xy 376.058185 -276.206239)
			(xy 376.107069 -276.220399) (xy 376.153048 -276.242216) (xy 376.194932 -276.271126) (xy 376.231636 -276.306381)
			(xy 376.262209 -276.347067) (xy 376.28586 -276.39213) (xy 376.301976 -276.440404) (xy 376.31014 -276.490638)
			(xy 376.310652 -276.516084) (xy 376.628926 -276.516084) (xy 376.632886 -276.46703) (xy 376.644663 -276.419246)
			(xy 376.663954 -276.37397) (xy 376.690257 -276.332374) (xy 376.722892 -276.295537) (xy 376.761013 -276.264412)
			(xy 376.803634 -276.239805) (xy 376.84965 -276.222353) (xy 376.897869 -276.212509) (xy 376.947044 -276.210528)
			(xy 376.995899 -276.21646) (xy 377.04317 -276.230152) (xy 377.087632 -276.25125) (xy 377.128135 -276.279206)
			(xy 377.163628 -276.313298) (xy 377.193193 -276.352642) (xy 377.216064 -276.396219) (xy 377.231648 -276.4429)
			(xy 377.239543 -276.491477) (xy 377.240038 -276.516084) (xy 377.558549 -276.516084) (xy 377.562644 -276.465356)
			(xy 377.574823 -276.415942) (xy 377.594771 -276.369122) (xy 377.621972 -276.326108) (xy 377.65572 -276.288014)
			(xy 377.695142 -276.255827) (xy 377.739216 -276.230381) (xy 377.786802 -276.212334) (xy 377.836666 -276.202154)
			(xy 377.887518 -276.200105) (xy 377.938039 -276.206239) (xy 377.986923 -276.220399) (xy 378.032902 -276.242216)
			(xy 378.074786 -276.271126) (xy 378.11149 -276.306381) (xy 378.142063 -276.347067) (xy 378.165714 -276.39213)
			(xy 378.18183 -276.440404) (xy 378.189994 -276.490638) (xy 378.190506 -276.516084) (xy 378.509034 -276.516084)
			(xy 378.512994 -276.46703) (xy 378.524771 -276.419246) (xy 378.544062 -276.37397) (xy 378.570365 -276.332374)
			(xy 378.603 -276.295537) (xy 378.641121 -276.264412) (xy 378.683742 -276.239805) (xy 378.729758 -276.222353)
			(xy 378.777977 -276.212509) (xy 378.827152 -276.210528) (xy 378.876007 -276.21646) (xy 378.923278 -276.230152)
			(xy 378.96774 -276.25125) (xy 379.008243 -276.279206) (xy 379.043736 -276.313298) (xy 379.073301 -276.352642)
			(xy 379.096172 -276.396219) (xy 379.111756 -276.4429) (xy 379.119651 -276.491477) (xy 379.120146 -276.516084)
			(xy 379.438657 -276.516084) (xy 379.442752 -276.465356) (xy 379.454931 -276.415942) (xy 379.474879 -276.369122)
			(xy 379.50208 -276.326108) (xy 379.535828 -276.288014) (xy 379.57525 -276.255827) (xy 379.619324 -276.230381)
			(xy 379.66691 -276.212334) (xy 379.716774 -276.202154) (xy 379.767626 -276.200105) (xy 379.818147 -276.206239)
			(xy 379.867031 -276.220399) (xy 379.91301 -276.242216) (xy 379.954894 -276.271126) (xy 379.991598 -276.306381)
			(xy 380.022171 -276.347067) (xy 380.045822 -276.39213) (xy 380.061938 -276.440404) (xy 380.070102 -276.490638)
			(xy 380.070614 -276.516084) (xy 380.378711 -276.516084) (xy 380.382806 -276.465356) (xy 380.394985 -276.415942)
			(xy 380.414933 -276.369122) (xy 380.442134 -276.326108) (xy 380.475882 -276.288014) (xy 380.515304 -276.255827)
			(xy 380.559378 -276.230381) (xy 380.606964 -276.212334) (xy 380.656828 -276.202154) (xy 380.70768 -276.200105)
			(xy 380.758201 -276.206239) (xy 380.807085 -276.220399) (xy 380.853064 -276.242216) (xy 380.894948 -276.271126)
			(xy 380.931652 -276.306381) (xy 380.962225 -276.347067) (xy 380.985876 -276.39213) (xy 381.001992 -276.440404)
			(xy 381.010156 -276.490638) (xy 381.010668 -276.516084) (xy 381.328942 -276.516084) (xy 381.332902 -276.46703)
			(xy 381.344679 -276.419246) (xy 381.36397 -276.37397) (xy 381.390273 -276.332374) (xy 381.422908 -276.295537)
			(xy 381.461029 -276.264412) (xy 381.50365 -276.239805) (xy 381.549666 -276.222353) (xy 381.597885 -276.212509)
			(xy 381.64706 -276.210528) (xy 381.695915 -276.21646) (xy 381.743186 -276.230152) (xy 381.787648 -276.25125)
			(xy 381.828151 -276.279206) (xy 381.863644 -276.313298) (xy 381.893209 -276.352642) (xy 381.91608 -276.396219)
			(xy 381.931664 -276.4429) (xy 381.939559 -276.491477) (xy 381.940054 -276.516084) (xy 382.268996 -276.516084)
			(xy 382.272956 -276.46703) (xy 382.284733 -276.419246) (xy 382.304024 -276.37397) (xy 382.330327 -276.332374)
			(xy 382.362962 -276.295537) (xy 382.401083 -276.264412) (xy 382.443704 -276.239805) (xy 382.48972 -276.222353)
			(xy 382.537939 -276.212509) (xy 382.587114 -276.210528) (xy 382.635969 -276.21646) (xy 382.68324 -276.230152)
			(xy 382.727702 -276.25125) (xy 382.768205 -276.279206) (xy 382.803698 -276.313298) (xy 382.833263 -276.352642)
			(xy 382.856134 -276.396219) (xy 382.871718 -276.4429) (xy 382.879613 -276.491477) (xy 382.880108 -276.516084)
			(xy 383.20905 -276.516084) (xy 383.21301 -276.46703) (xy 383.224787 -276.419246) (xy 383.244078 -276.37397)
			(xy 383.270381 -276.332374) (xy 383.303016 -276.295537) (xy 383.341137 -276.264412) (xy 383.383758 -276.239805)
			(xy 383.429774 -276.222353) (xy 383.477993 -276.212509) (xy 383.527168 -276.210528) (xy 383.576023 -276.21646)
			(xy 383.623294 -276.230152) (xy 383.667756 -276.25125) (xy 383.708259 -276.279206) (xy 383.743752 -276.313298)
			(xy 383.773317 -276.352642) (xy 383.796188 -276.396219) (xy 383.811772 -276.4429) (xy 383.819667 -276.491477)
			(xy 383.820162 -276.516084) (xy 384.149104 -276.516084) (xy 384.153064 -276.46703) (xy 384.164841 -276.419246)
			(xy 384.184132 -276.37397) (xy 384.210435 -276.332374) (xy 384.24307 -276.295537) (xy 384.281191 -276.264412)
			(xy 384.323812 -276.239805) (xy 384.369828 -276.222353) (xy 384.418047 -276.212509) (xy 384.467222 -276.210528)
			(xy 384.516077 -276.21646) (xy 384.563348 -276.230152) (xy 384.60781 -276.25125) (xy 384.648313 -276.279206)
			(xy 384.683806 -276.313298) (xy 384.713371 -276.352642) (xy 384.736242 -276.396219) (xy 384.751826 -276.4429)
			(xy 384.759721 -276.491477) (xy 384.760216 -276.516084) (xy 384.759721 -276.540691) (xy 384.751826 -276.589268)
			(xy 384.736242 -276.635949) (xy 384.713371 -276.679526) (xy 384.683806 -276.71887) (xy 384.648313 -276.752962)
			(xy 384.60781 -276.780918) (xy 384.563348 -276.802016) (xy 384.516077 -276.815708) (xy 384.467222 -276.82164)
			(xy 384.418047 -276.819659) (xy 384.369828 -276.809815) (xy 384.323812 -276.792363) (xy 384.281191 -276.767756)
			(xy 384.24307 -276.736631) (xy 384.210435 -276.699794) (xy 384.184132 -276.658198) (xy 384.164841 -276.612922)
			(xy 384.153064 -276.565138) (xy 384.149104 -276.516084) (xy 383.820162 -276.516084) (xy 383.819667 -276.540691)
			(xy 383.811772 -276.589268) (xy 383.796188 -276.635949) (xy 383.773317 -276.679526) (xy 383.743752 -276.71887)
			(xy 383.708259 -276.752962) (xy 383.667756 -276.780918) (xy 383.623294 -276.802016) (xy 383.576023 -276.815708)
			(xy 383.527168 -276.82164) (xy 383.477993 -276.819659) (xy 383.429774 -276.809815) (xy 383.383758 -276.792363)
			(xy 383.341137 -276.767756) (xy 383.303016 -276.736631) (xy 383.270381 -276.699794) (xy 383.244078 -276.658198)
			(xy 383.224787 -276.612922) (xy 383.21301 -276.565138) (xy 383.20905 -276.516084) (xy 382.880108 -276.516084)
			(xy 382.879613 -276.540691) (xy 382.871718 -276.589268) (xy 382.856134 -276.635949) (xy 382.833263 -276.679526)
			(xy 382.803698 -276.71887) (xy 382.768205 -276.752962) (xy 382.727702 -276.780918) (xy 382.68324 -276.802016)
			(xy 382.635969 -276.815708) (xy 382.587114 -276.82164) (xy 382.537939 -276.819659) (xy 382.48972 -276.809815)
			(xy 382.443704 -276.792363) (xy 382.401083 -276.767756) (xy 382.362962 -276.736631) (xy 382.330327 -276.699794)
			(xy 382.304024 -276.658198) (xy 382.284733 -276.612922) (xy 382.272956 -276.565138) (xy 382.268996 -276.516084)
			(xy 381.940054 -276.516084) (xy 381.939559 -276.540691) (xy 381.931664 -276.589268) (xy 381.91608 -276.635949)
			(xy 381.893209 -276.679526) (xy 381.863644 -276.71887) (xy 381.828151 -276.752962) (xy 381.787648 -276.780918)
			(xy 381.743186 -276.802016) (xy 381.695915 -276.815708) (xy 381.64706 -276.82164) (xy 381.597885 -276.819659)
			(xy 381.549666 -276.809815) (xy 381.50365 -276.792363) (xy 381.461029 -276.767756) (xy 381.422908 -276.736631)
			(xy 381.390273 -276.699794) (xy 381.36397 -276.658198) (xy 381.344679 -276.612922) (xy 381.332902 -276.565138)
			(xy 381.328942 -276.516084) (xy 381.010668 -276.516084) (xy 381.010156 -276.54153) (xy 381.001992 -276.591764)
			(xy 380.985876 -276.640038) (xy 380.962225 -276.685101) (xy 380.931652 -276.725787) (xy 380.894948 -276.761042)
			(xy 380.853064 -276.789952) (xy 380.807085 -276.811769) (xy 380.758201 -276.825929) (xy 380.70768 -276.832063)
			(xy 380.656828 -276.830014) (xy 380.606964 -276.819834) (xy 380.559378 -276.801787) (xy 380.515304 -276.776341)
			(xy 380.475882 -276.744154) (xy 380.442134 -276.70606) (xy 380.414933 -276.663046) (xy 380.394985 -276.616226)
			(xy 380.382806 -276.566812) (xy 380.378711 -276.516084) (xy 380.070614 -276.516084) (xy 380.070102 -276.54153)
			(xy 380.061938 -276.591764) (xy 380.045822 -276.640038) (xy 380.022171 -276.685101) (xy 379.991598 -276.725787)
			(xy 379.954894 -276.761042) (xy 379.91301 -276.789952) (xy 379.867031 -276.811769) (xy 379.818147 -276.825929)
			(xy 379.767626 -276.832063) (xy 379.716774 -276.830014) (xy 379.66691 -276.819834) (xy 379.619324 -276.801787)
			(xy 379.57525 -276.776341) (xy 379.535828 -276.744154) (xy 379.50208 -276.70606) (xy 379.474879 -276.663046)
			(xy 379.454931 -276.616226) (xy 379.442752 -276.566812) (xy 379.438657 -276.516084) (xy 379.120146 -276.516084)
			(xy 379.119651 -276.540691) (xy 379.111756 -276.589268) (xy 379.096172 -276.635949) (xy 379.073301 -276.679526)
			(xy 379.043736 -276.71887) (xy 379.008243 -276.752962) (xy 378.96774 -276.780918) (xy 378.923278 -276.802016)
			(xy 378.876007 -276.815708) (xy 378.827152 -276.82164) (xy 378.777977 -276.819659) (xy 378.729758 -276.809815)
			(xy 378.683742 -276.792363) (xy 378.641121 -276.767756) (xy 378.603 -276.736631) (xy 378.570365 -276.699794)
			(xy 378.544062 -276.658198) (xy 378.524771 -276.612922) (xy 378.512994 -276.565138) (xy 378.509034 -276.516084)
			(xy 378.190506 -276.516084) (xy 378.189994 -276.54153) (xy 378.18183 -276.591764) (xy 378.165714 -276.640038)
			(xy 378.142063 -276.685101) (xy 378.11149 -276.725787) (xy 378.074786 -276.761042) (xy 378.032902 -276.789952)
			(xy 377.986923 -276.811769) (xy 377.938039 -276.825929) (xy 377.887518 -276.832063) (xy 377.836666 -276.830014)
			(xy 377.786802 -276.819834) (xy 377.739216 -276.801787) (xy 377.695142 -276.776341) (xy 377.65572 -276.744154)
			(xy 377.621972 -276.70606) (xy 377.594771 -276.663046) (xy 377.574823 -276.616226) (xy 377.562644 -276.566812)
			(xy 377.558549 -276.516084) (xy 377.240038 -276.516084) (xy 377.239543 -276.540691) (xy 377.231648 -276.589268)
			(xy 377.216064 -276.635949) (xy 377.193193 -276.679526) (xy 377.163628 -276.71887) (xy 377.128135 -276.752962)
			(xy 377.087632 -276.780918) (xy 377.04317 -276.802016) (xy 376.995899 -276.815708) (xy 376.947044 -276.82164)
			(xy 376.897869 -276.819659) (xy 376.84965 -276.809815) (xy 376.803634 -276.792363) (xy 376.761013 -276.767756)
			(xy 376.722892 -276.736631) (xy 376.690257 -276.699794) (xy 376.663954 -276.658198) (xy 376.644663 -276.612922)
			(xy 376.632886 -276.565138) (xy 376.628926 -276.516084) (xy 376.310652 -276.516084) (xy 376.31014 -276.54153)
			(xy 376.301976 -276.591764) (xy 376.28586 -276.640038) (xy 376.262209 -276.685101) (xy 376.231636 -276.725787)
			(xy 376.194932 -276.761042) (xy 376.153048 -276.789952) (xy 376.107069 -276.811769) (xy 376.058185 -276.825929)
			(xy 376.007664 -276.832063) (xy 375.956812 -276.830014) (xy 375.906948 -276.819834) (xy 375.859362 -276.801787)
			(xy 375.815288 -276.776341) (xy 375.775866 -276.744154) (xy 375.742118 -276.70606) (xy 375.714917 -276.663046)
			(xy 375.694969 -276.616226) (xy 375.68279 -276.566812) (xy 375.678695 -276.516084) (xy 375.550938 -276.516084)
			(xy 375.550938 -276.749256) (xy 375.551172 -276.755772) (xy 375.554515 -276.768373) (xy 375.557542 -276.774148)
			(xy 375.577933 -276.8109) (xy 375.613786 -276.886927) (xy 375.62917 -276.92604) (xy 375.631202 -276.93112)
			(xy 375.639838 -276.944582) (xy 375.645934 -276.951948) (xy 375.777506 -277.08352) (xy 375.783276 -277.0897)
			(xy 375.790688 -277.104884) (xy 375.791984 -277.113238) (xy 375.792492 -277.118064) (xy 375.80062 -277.143464)
			(xy 375.804176 -277.149052) (xy 375.816373 -277.169055) (xy 375.835612 -277.211771) (xy 375.848619 -277.256778)
			(xy 375.855131 -277.303173) (xy 375.855476 -277.32609) (xy 376.148595 -277.32609) (xy 376.15269 -277.275362)
			(xy 376.164869 -277.225948) (xy 376.184817 -277.179128) (xy 376.212018 -277.136114) (xy 376.245766 -277.09802)
			(xy 376.285188 -277.065833) (xy 376.329262 -277.040387) (xy 376.376848 -277.02234) (xy 376.426712 -277.01216)
			(xy 376.477564 -277.010111) (xy 376.528085 -277.016245) (xy 376.576969 -277.030405) (xy 376.622948 -277.052222)
			(xy 376.664832 -277.081132) (xy 376.701536 -277.116387) (xy 376.732109 -277.157073) (xy 376.75576 -277.202136)
			(xy 376.771876 -277.25041) (xy 376.78004 -277.300644) (xy 376.780552 -277.32609) (xy 377.088649 -277.32609)
			(xy 377.092744 -277.275362) (xy 377.104923 -277.225948) (xy 377.124871 -277.179128) (xy 377.152072 -277.136114)
			(xy 377.18582 -277.09802) (xy 377.225242 -277.065833) (xy 377.269316 -277.040387) (xy 377.316902 -277.02234)
			(xy 377.366766 -277.01216) (xy 377.417618 -277.010111) (xy 377.468139 -277.016245) (xy 377.517023 -277.030405)
			(xy 377.563002 -277.052222) (xy 377.604886 -277.081132) (xy 377.64159 -277.116387) (xy 377.672163 -277.157073)
			(xy 377.695814 -277.202136) (xy 377.71193 -277.25041) (xy 377.720094 -277.300644) (xy 377.720606 -277.32609)
			(xy 378.039134 -277.32609) (xy 378.043094 -277.277036) (xy 378.054871 -277.229252) (xy 378.074162 -277.183976)
			(xy 378.100465 -277.14238) (xy 378.1331 -277.105543) (xy 378.171221 -277.074418) (xy 378.213842 -277.049811)
			(xy 378.259858 -277.032359) (xy 378.308077 -277.022515) (xy 378.357252 -277.020534) (xy 378.406107 -277.026466)
			(xy 378.453378 -277.040158) (xy 378.49784 -277.061256) (xy 378.538343 -277.089212) (xy 378.573836 -277.123304)
			(xy 378.603401 -277.162648) (xy 378.626272 -277.206225) (xy 378.641856 -277.252906) (xy 378.649751 -277.301483)
			(xy 378.650246 -277.32609) (xy 378.968503 -277.32609) (xy 378.972598 -277.275362) (xy 378.984777 -277.225948)
			(xy 379.004725 -277.179128) (xy 379.031926 -277.136114) (xy 379.065674 -277.09802) (xy 379.105096 -277.065833)
			(xy 379.14917 -277.040387) (xy 379.196756 -277.02234) (xy 379.24662 -277.01216) (xy 379.297472 -277.010111)
			(xy 379.347993 -277.016245) (xy 379.396877 -277.030405) (xy 379.442856 -277.052222) (xy 379.48474 -277.081132)
			(xy 379.521444 -277.116387) (xy 379.552017 -277.157073) (xy 379.575668 -277.202136) (xy 379.591784 -277.25041)
			(xy 379.599948 -277.300644) (xy 379.60046 -277.32609) (xy 379.918988 -277.32609) (xy 379.922948 -277.277036)
			(xy 379.934725 -277.229252) (xy 379.954016 -277.183976) (xy 379.980319 -277.14238) (xy 380.012954 -277.105543)
			(xy 380.051075 -277.074418) (xy 380.093696 -277.049811) (xy 380.139712 -277.032359) (xy 380.187931 -277.022515)
			(xy 380.237106 -277.020534) (xy 380.285961 -277.026466) (xy 380.333232 -277.040158) (xy 380.377694 -277.061256)
			(xy 380.418197 -277.089212) (xy 380.45369 -277.123304) (xy 380.483255 -277.162648) (xy 380.506126 -277.206225)
			(xy 380.52171 -277.252906) (xy 380.529605 -277.301483) (xy 380.5301 -277.32609) (xy 380.848611 -277.32609)
			(xy 380.852706 -277.275362) (xy 380.864885 -277.225948) (xy 380.884833 -277.179128) (xy 380.912034 -277.136114)
			(xy 380.945782 -277.09802) (xy 380.985204 -277.065833) (xy 381.029278 -277.040387) (xy 381.076864 -277.02234)
			(xy 381.126728 -277.01216) (xy 381.17758 -277.010111) (xy 381.228101 -277.016245) (xy 381.276985 -277.030405)
			(xy 381.322964 -277.052222) (xy 381.364848 -277.081132) (xy 381.401552 -277.116387) (xy 381.432125 -277.157073)
			(xy 381.455776 -277.202136) (xy 381.471892 -277.25041) (xy 381.480056 -277.300644) (xy 381.480568 -277.32609)
			(xy 381.799096 -277.32609) (xy 381.803056 -277.277036) (xy 381.814833 -277.229252) (xy 381.834124 -277.183976)
			(xy 381.860427 -277.14238) (xy 381.893062 -277.105543) (xy 381.931183 -277.074418) (xy 381.973804 -277.049811)
			(xy 382.01982 -277.032359) (xy 382.068039 -277.022515) (xy 382.117214 -277.020534) (xy 382.166069 -277.026466)
			(xy 382.21334 -277.040158) (xy 382.257802 -277.061256) (xy 382.298305 -277.089212) (xy 382.333798 -277.123304)
			(xy 382.363363 -277.162648) (xy 382.386234 -277.206225) (xy 382.401818 -277.252906) (xy 382.409713 -277.301483)
			(xy 382.410208 -277.32609) (xy 382.738896 -277.32609) (xy 382.742856 -277.277036) (xy 382.754633 -277.229252)
			(xy 382.773924 -277.183976) (xy 382.800227 -277.14238) (xy 382.832862 -277.105543) (xy 382.870983 -277.074418)
			(xy 382.913604 -277.049811) (xy 382.95962 -277.032359) (xy 383.007839 -277.022515) (xy 383.057014 -277.020534)
			(xy 383.105869 -277.026466) (xy 383.15314 -277.040158) (xy 383.197602 -277.061256) (xy 383.238105 -277.089212)
			(xy 383.273598 -277.123304) (xy 383.303163 -277.162648) (xy 383.326034 -277.206225) (xy 383.341618 -277.252906)
			(xy 383.349513 -277.301483) (xy 383.350008 -277.32609) (xy 383.67895 -277.32609) (xy 383.68291 -277.277036)
			(xy 383.694687 -277.229252) (xy 383.713978 -277.183976) (xy 383.740281 -277.14238) (xy 383.772916 -277.105543)
			(xy 383.811037 -277.074418) (xy 383.853658 -277.049811) (xy 383.899674 -277.032359) (xy 383.947893 -277.022515)
			(xy 383.997068 -277.020534) (xy 384.045923 -277.026466) (xy 384.093194 -277.040158) (xy 384.137656 -277.061256)
			(xy 384.178159 -277.089212) (xy 384.213652 -277.123304) (xy 384.243217 -277.162648) (xy 384.266088 -277.206225)
			(xy 384.281672 -277.252906) (xy 384.289567 -277.301483) (xy 384.290062 -277.32609) (xy 384.289567 -277.350697)
			(xy 384.281672 -277.399274) (xy 384.266088 -277.445955) (xy 384.243217 -277.489532) (xy 384.213652 -277.528876)
			(xy 384.178159 -277.562968) (xy 384.137656 -277.590924) (xy 384.093194 -277.612022) (xy 384.045923 -277.625714)
			(xy 383.997068 -277.631646) (xy 383.947893 -277.629665) (xy 383.899674 -277.619821) (xy 383.853658 -277.602369)
			(xy 383.811037 -277.577762) (xy 383.772916 -277.546637) (xy 383.740281 -277.5098) (xy 383.713978 -277.468204)
			(xy 383.694687 -277.422928) (xy 383.68291 -277.375144) (xy 383.67895 -277.32609) (xy 383.350008 -277.32609)
			(xy 383.349513 -277.350697) (xy 383.341618 -277.399274) (xy 383.326034 -277.445955) (xy 383.303163 -277.489532)
			(xy 383.273598 -277.528876) (xy 383.238105 -277.562968) (xy 383.197602 -277.590924) (xy 383.15314 -277.612022)
			(xy 383.105869 -277.625714) (xy 383.057014 -277.631646) (xy 383.007839 -277.629665) (xy 382.95962 -277.619821)
			(xy 382.913604 -277.602369) (xy 382.870983 -277.577762) (xy 382.832862 -277.546637) (xy 382.800227 -277.5098)
			(xy 382.773924 -277.468204) (xy 382.754633 -277.422928) (xy 382.742856 -277.375144) (xy 382.738896 -277.32609)
			(xy 382.410208 -277.32609) (xy 382.409713 -277.350697) (xy 382.401818 -277.399274) (xy 382.386234 -277.445955)
			(xy 382.363363 -277.489532) (xy 382.333798 -277.528876) (xy 382.298305 -277.562968) (xy 382.257802 -277.590924)
			(xy 382.21334 -277.612022) (xy 382.166069 -277.625714) (xy 382.117214 -277.631646) (xy 382.068039 -277.629665)
			(xy 382.01982 -277.619821) (xy 381.973804 -277.602369) (xy 381.931183 -277.577762) (xy 381.893062 -277.546637)
			(xy 381.860427 -277.5098) (xy 381.834124 -277.468204) (xy 381.814833 -277.422928) (xy 381.803056 -277.375144)
			(xy 381.799096 -277.32609) (xy 381.480568 -277.32609) (xy 381.480056 -277.351536) (xy 381.471892 -277.40177)
			(xy 381.455776 -277.450044) (xy 381.432125 -277.495107) (xy 381.401552 -277.535793) (xy 381.364848 -277.571048)
			(xy 381.322964 -277.599958) (xy 381.276985 -277.621775) (xy 381.228101 -277.635935) (xy 381.17758 -277.642069)
			(xy 381.126728 -277.64002) (xy 381.076864 -277.62984) (xy 381.029278 -277.611793) (xy 380.985204 -277.586347)
			(xy 380.945782 -277.55416) (xy 380.912034 -277.516066) (xy 380.884833 -277.473052) (xy 380.864885 -277.426232)
			(xy 380.852706 -277.376818) (xy 380.848611 -277.32609) (xy 380.5301 -277.32609) (xy 380.529605 -277.350697)
			(xy 380.52171 -277.399274) (xy 380.506126 -277.445955) (xy 380.483255 -277.489532) (xy 380.45369 -277.528876)
			(xy 380.418197 -277.562968) (xy 380.377694 -277.590924) (xy 380.333232 -277.612022) (xy 380.285961 -277.625714)
			(xy 380.237106 -277.631646) (xy 380.187931 -277.629665) (xy 380.139712 -277.619821) (xy 380.093696 -277.602369)
			(xy 380.051075 -277.577762) (xy 380.012954 -277.546637) (xy 379.980319 -277.5098) (xy 379.954016 -277.468204)
			(xy 379.934725 -277.422928) (xy 379.922948 -277.375144) (xy 379.918988 -277.32609) (xy 379.60046 -277.32609)
			(xy 379.599948 -277.351536) (xy 379.591784 -277.40177) (xy 379.575668 -277.450044) (xy 379.552017 -277.495107)
			(xy 379.521444 -277.535793) (xy 379.48474 -277.571048) (xy 379.442856 -277.599958) (xy 379.396877 -277.621775)
			(xy 379.347993 -277.635935) (xy 379.297472 -277.642069) (xy 379.24662 -277.64002) (xy 379.196756 -277.62984)
			(xy 379.14917 -277.611793) (xy 379.105096 -277.586347) (xy 379.065674 -277.55416) (xy 379.031926 -277.516066)
			(xy 379.004725 -277.473052) (xy 378.984777 -277.426232) (xy 378.972598 -277.376818) (xy 378.968503 -277.32609)
			(xy 378.650246 -277.32609) (xy 378.649751 -277.350697) (xy 378.641856 -277.399274) (xy 378.626272 -277.445955)
			(xy 378.603401 -277.489532) (xy 378.573836 -277.528876) (xy 378.538343 -277.562968) (xy 378.49784 -277.590924)
			(xy 378.453378 -277.612022) (xy 378.406107 -277.625714) (xy 378.357252 -277.631646) (xy 378.308077 -277.629665)
			(xy 378.259858 -277.619821) (xy 378.213842 -277.602369) (xy 378.171221 -277.577762) (xy 378.1331 -277.546637)
			(xy 378.100465 -277.5098) (xy 378.074162 -277.468204) (xy 378.054871 -277.422928) (xy 378.043094 -277.375144)
			(xy 378.039134 -277.32609) (xy 377.720606 -277.32609) (xy 377.720094 -277.351536) (xy 377.71193 -277.40177)
			(xy 377.695814 -277.450044) (xy 377.672163 -277.495107) (xy 377.64159 -277.535793) (xy 377.604886 -277.571048)
			(xy 377.563002 -277.599958) (xy 377.517023 -277.621775) (xy 377.468139 -277.635935) (xy 377.417618 -277.642069)
			(xy 377.366766 -277.64002) (xy 377.316902 -277.62984) (xy 377.269316 -277.611793) (xy 377.225242 -277.586347)
			(xy 377.18582 -277.55416) (xy 377.152072 -277.516066) (xy 377.124871 -277.473052) (xy 377.104923 -277.426232)
			(xy 377.092744 -277.376818) (xy 377.088649 -277.32609) (xy 376.780552 -277.32609) (xy 376.78004 -277.351536)
			(xy 376.771876 -277.40177) (xy 376.75576 -277.450044) (xy 376.732109 -277.495107) (xy 376.701536 -277.535793)
			(xy 376.664832 -277.571048) (xy 376.622948 -277.599958) (xy 376.576969 -277.621775) (xy 376.528085 -277.635935)
			(xy 376.477564 -277.642069) (xy 376.426712 -277.64002) (xy 376.376848 -277.62984) (xy 376.329262 -277.611793)
			(xy 376.285188 -277.586347) (xy 376.245766 -277.55416) (xy 376.212018 -277.516066) (xy 376.184817 -277.473052)
			(xy 376.164869 -277.426232) (xy 376.15269 -277.376818) (xy 376.148595 -277.32609) (xy 375.855476 -277.32609)
			(xy 375.855484 -277.326598) (xy 375.855484 -277.331932) (xy 375.854736 -277.354513) (xy 375.847825 -277.399162)
			(xy 375.834891 -277.442451) (xy 375.816173 -277.483572) (xy 375.80443 -277.502874) (xy 375.804176 -277.503128)
			(xy 375.800366 -277.509224) (xy 375.79427 -277.530052) (xy 375.793508 -277.533354) (xy 375.792238 -277.544276)
			(xy 375.792238 -277.743412) (xy 375.792238 -277.744936) (xy 375.792902 -277.753907) (xy 375.799654 -277.770568)
			(xy 375.805446 -277.777448) (xy 375.81205 -277.783798) (xy 375.879614 -277.835868) (xy 375.88952 -277.8379)
			(xy 375.90857 -277.832566) (xy 375.909078 -277.832566) (xy 375.930041 -277.827011) (xy 375.972993 -277.821016)
			(xy 375.994676 -277.820628) (xy 375.99493 -277.820628) (xy 376.019718 -277.821116) (xy 376.068684 -277.828876)
			(xy 376.115833 -277.8442) (xy 376.160005 -277.86671) (xy 376.200112 -277.895853) (xy 376.235167 -277.930911)
			(xy 376.264306 -277.97102) (xy 376.286812 -278.015194) (xy 376.302131 -278.062345) (xy 376.309886 -278.111312)
			(xy 376.309886 -278.136096) (xy 376.628926 -278.136096) (xy 376.632886 -278.087042) (xy 376.644663 -278.039258)
			(xy 376.663954 -277.993982) (xy 376.690257 -277.952386) (xy 376.722892 -277.915549) (xy 376.761013 -277.884424)
			(xy 376.803634 -277.859817) (xy 376.84965 -277.842365) (xy 376.897869 -277.832521) (xy 376.947044 -277.83054)
			(xy 376.995899 -277.836472) (xy 377.04317 -277.850164) (xy 377.087632 -277.871262) (xy 377.128135 -277.899218)
			(xy 377.163628 -277.93331) (xy 377.193193 -277.972654) (xy 377.216064 -278.016231) (xy 377.231648 -278.062912)
			(xy 377.239543 -278.111489) (xy 377.240038 -278.136096) (xy 377.558549 -278.136096) (xy 377.562644 -278.085368)
			(xy 377.574823 -278.035954) (xy 377.594771 -277.989134) (xy 377.621972 -277.94612) (xy 377.65572 -277.908026)
			(xy 377.695142 -277.875839) (xy 377.739216 -277.850393) (xy 377.786802 -277.832346) (xy 377.836666 -277.822166)
			(xy 377.887518 -277.820117) (xy 377.938039 -277.826251) (xy 377.986923 -277.840411) (xy 378.032902 -277.862228)
			(xy 378.074786 -277.891138) (xy 378.11149 -277.926393) (xy 378.142063 -277.967079) (xy 378.165714 -278.012142)
			(xy 378.18183 -278.060416) (xy 378.189994 -278.11065) (xy 378.190506 -278.136096) (xy 379.438657 -278.136096)
			(xy 379.442752 -278.085368) (xy 379.454931 -278.035954) (xy 379.474879 -277.989134) (xy 379.50208 -277.94612)
			(xy 379.535828 -277.908026) (xy 379.57525 -277.875839) (xy 379.619324 -277.850393) (xy 379.66691 -277.832346)
			(xy 379.716774 -277.822166) (xy 379.767626 -277.820117) (xy 379.818147 -277.826251) (xy 379.867031 -277.840411)
			(xy 379.91301 -277.862228) (xy 379.954894 -277.891138) (xy 379.991598 -277.926393) (xy 380.022171 -277.967079)
			(xy 380.045822 -278.012142) (xy 380.061938 -278.060416) (xy 380.070102 -278.11065) (xy 380.070614 -278.136096)
			(xy 380.378711 -278.136096) (xy 380.382806 -278.085368) (xy 380.394985 -278.035954) (xy 380.414933 -277.989134)
			(xy 380.442134 -277.94612) (xy 380.475882 -277.908026) (xy 380.515304 -277.875839) (xy 380.559378 -277.850393)
			(xy 380.606964 -277.832346) (xy 380.656828 -277.822166) (xy 380.70768 -277.820117) (xy 380.758201 -277.826251)
			(xy 380.807085 -277.840411) (xy 380.853064 -277.862228) (xy 380.894948 -277.891138) (xy 380.931652 -277.926393)
			(xy 380.962225 -277.967079) (xy 380.985876 -278.012142) (xy 381.001992 -278.060416) (xy 381.010156 -278.11065)
			(xy 381.010668 -278.136096) (xy 381.328942 -278.136096) (xy 381.332902 -278.087042) (xy 381.344679 -278.039258)
			(xy 381.36397 -277.993982) (xy 381.390273 -277.952386) (xy 381.422908 -277.915549) (xy 381.461029 -277.884424)
			(xy 381.50365 -277.859817) (xy 381.549666 -277.842365) (xy 381.597885 -277.832521) (xy 381.64706 -277.83054)
			(xy 381.695915 -277.836472) (xy 381.743186 -277.850164) (xy 381.787648 -277.871262) (xy 381.828151 -277.899218)
			(xy 381.863644 -277.93331) (xy 381.893209 -277.972654) (xy 381.91608 -278.016231) (xy 381.931664 -278.062912)
			(xy 381.939559 -278.111489) (xy 381.940054 -278.136096) (xy 382.268996 -278.136096) (xy 382.272956 -278.087042)
			(xy 382.284733 -278.039258) (xy 382.304024 -277.993982) (xy 382.330327 -277.952386) (xy 382.362962 -277.915549)
			(xy 382.401083 -277.884424) (xy 382.443704 -277.859817) (xy 382.48972 -277.842365) (xy 382.537939 -277.832521)
			(xy 382.587114 -277.83054) (xy 382.635969 -277.836472) (xy 382.68324 -277.850164) (xy 382.727702 -277.871262)
			(xy 382.768205 -277.899218) (xy 382.803698 -277.93331) (xy 382.833263 -277.972654) (xy 382.856134 -278.016231)
			(xy 382.871718 -278.062912) (xy 382.879613 -278.111489) (xy 382.880108 -278.136096) (xy 383.20905 -278.136096)
			(xy 383.21301 -278.087042) (xy 383.224787 -278.039258) (xy 383.244078 -277.993982) (xy 383.270381 -277.952386)
			(xy 383.303016 -277.915549) (xy 383.341137 -277.884424) (xy 383.383758 -277.859817) (xy 383.429774 -277.842365)
			(xy 383.477993 -277.832521) (xy 383.527168 -277.83054) (xy 383.576023 -277.836472) (xy 383.623294 -277.850164)
			(xy 383.667756 -277.871262) (xy 383.708259 -277.899218) (xy 383.743752 -277.93331) (xy 383.773317 -277.972654)
			(xy 383.796188 -278.016231) (xy 383.811772 -278.062912) (xy 383.819667 -278.111489) (xy 383.820162 -278.136096)
			(xy 384.149104 -278.136096) (xy 384.153064 -278.087042) (xy 384.164841 -278.039258) (xy 384.184132 -277.993982)
			(xy 384.210435 -277.952386) (xy 384.24307 -277.915549) (xy 384.281191 -277.884424) (xy 384.323812 -277.859817)
			(xy 384.369828 -277.842365) (xy 384.418047 -277.832521) (xy 384.467222 -277.83054) (xy 384.516077 -277.836472)
			(xy 384.563348 -277.850164) (xy 384.60781 -277.871262) (xy 384.648313 -277.899218) (xy 384.683806 -277.93331)
			(xy 384.713371 -277.972654) (xy 384.736242 -278.016231) (xy 384.751826 -278.062912) (xy 384.759721 -278.111489)
			(xy 384.760216 -278.136096) (xy 384.759721 -278.160703) (xy 384.751826 -278.20928) (xy 384.736242 -278.255961)
			(xy 384.713371 -278.299538) (xy 384.683806 -278.338882) (xy 384.648313 -278.372974) (xy 384.60781 -278.40093)
			(xy 384.563348 -278.422028) (xy 384.516077 -278.43572) (xy 384.467222 -278.441652) (xy 384.418047 -278.439671)
			(xy 384.369828 -278.429827) (xy 384.323812 -278.412375) (xy 384.281191 -278.387768) (xy 384.24307 -278.356643)
			(xy 384.210435 -278.319806) (xy 384.184132 -278.27821) (xy 384.164841 -278.232934) (xy 384.153064 -278.18515)
			(xy 384.149104 -278.136096) (xy 383.820162 -278.136096) (xy 383.819667 -278.160703) (xy 383.811772 -278.20928)
			(xy 383.796188 -278.255961) (xy 383.773317 -278.299538) (xy 383.743752 -278.338882) (xy 383.708259 -278.372974)
			(xy 383.667756 -278.40093) (xy 383.623294 -278.422028) (xy 383.576023 -278.43572) (xy 383.527168 -278.441652)
			(xy 383.477993 -278.439671) (xy 383.429774 -278.429827) (xy 383.383758 -278.412375) (xy 383.341137 -278.387768)
			(xy 383.303016 -278.356643) (xy 383.270381 -278.319806) (xy 383.244078 -278.27821) (xy 383.224787 -278.232934)
			(xy 383.21301 -278.18515) (xy 383.20905 -278.136096) (xy 382.880108 -278.136096) (xy 382.879613 -278.160703)
			(xy 382.871718 -278.20928) (xy 382.856134 -278.255961) (xy 382.833263 -278.299538) (xy 382.803698 -278.338882)
			(xy 382.768205 -278.372974) (xy 382.727702 -278.40093) (xy 382.68324 -278.422028) (xy 382.635969 -278.43572)
			(xy 382.587114 -278.441652) (xy 382.537939 -278.439671) (xy 382.48972 -278.429827) (xy 382.443704 -278.412375)
			(xy 382.401083 -278.387768) (xy 382.362962 -278.356643) (xy 382.330327 -278.319806) (xy 382.304024 -278.27821)
			(xy 382.284733 -278.232934) (xy 382.272956 -278.18515) (xy 382.268996 -278.136096) (xy 381.940054 -278.136096)
			(xy 381.939559 -278.160703) (xy 381.931664 -278.20928) (xy 381.91608 -278.255961) (xy 381.893209 -278.299538)
			(xy 381.863644 -278.338882) (xy 381.828151 -278.372974) (xy 381.787648 -278.40093) (xy 381.743186 -278.422028)
			(xy 381.695915 -278.43572) (xy 381.64706 -278.441652) (xy 381.597885 -278.439671) (xy 381.549666 -278.429827)
			(xy 381.50365 -278.412375) (xy 381.461029 -278.387768) (xy 381.422908 -278.356643) (xy 381.390273 -278.319806)
			(xy 381.36397 -278.27821) (xy 381.344679 -278.232934) (xy 381.332902 -278.18515) (xy 381.328942 -278.136096)
			(xy 381.010668 -278.136096) (xy 381.010156 -278.161542) (xy 381.001992 -278.211776) (xy 380.985876 -278.26005)
			(xy 380.962225 -278.305113) (xy 380.931652 -278.345799) (xy 380.894948 -278.381054) (xy 380.853064 -278.409964)
			(xy 380.807085 -278.431781) (xy 380.758201 -278.445941) (xy 380.70768 -278.452075) (xy 380.656828 -278.450026)
			(xy 380.606964 -278.439846) (xy 380.559378 -278.421799) (xy 380.515304 -278.396353) (xy 380.475882 -278.364166)
			(xy 380.442134 -278.326072) (xy 380.414933 -278.283058) (xy 380.394985 -278.236238) (xy 380.382806 -278.186824)
			(xy 380.378711 -278.136096) (xy 380.070614 -278.136096) (xy 380.070102 -278.161542) (xy 380.061938 -278.211776)
			(xy 380.045822 -278.26005) (xy 380.022171 -278.305113) (xy 379.991598 -278.345799) (xy 379.954894 -278.381054)
			(xy 379.91301 -278.409964) (xy 379.867031 -278.431781) (xy 379.818147 -278.445941) (xy 379.767626 -278.452075)
			(xy 379.716774 -278.450026) (xy 379.66691 -278.439846) (xy 379.619324 -278.421799) (xy 379.57525 -278.396353)
			(xy 379.535828 -278.364166) (xy 379.50208 -278.326072) (xy 379.474879 -278.283058) (xy 379.454931 -278.236238)
			(xy 379.442752 -278.186824) (xy 379.438657 -278.136096) (xy 378.190506 -278.136096) (xy 378.189994 -278.161542)
			(xy 378.18183 -278.211776) (xy 378.165714 -278.26005) (xy 378.142063 -278.305113) (xy 378.11149 -278.345799)
			(xy 378.074786 -278.381054) (xy 378.032902 -278.409964) (xy 377.986923 -278.431781) (xy 377.938039 -278.445941)
			(xy 377.887518 -278.452075) (xy 377.836666 -278.450026) (xy 377.786802 -278.439846) (xy 377.739216 -278.421799)
			(xy 377.695142 -278.396353) (xy 377.65572 -278.364166) (xy 377.621972 -278.326072) (xy 377.594771 -278.283058)
			(xy 377.574823 -278.236238) (xy 377.562644 -278.186824) (xy 377.558549 -278.136096) (xy 377.240038 -278.136096)
			(xy 377.239543 -278.160703) (xy 377.231648 -278.20928) (xy 377.216064 -278.255961) (xy 377.193193 -278.299538)
			(xy 377.163628 -278.338882) (xy 377.128135 -278.372974) (xy 377.087632 -278.40093) (xy 377.04317 -278.422028)
			(xy 376.995899 -278.43572) (xy 376.947044 -278.441652) (xy 376.897869 -278.439671) (xy 376.84965 -278.429827)
			(xy 376.803634 -278.412375) (xy 376.761013 -278.387768) (xy 376.722892 -278.356643) (xy 376.690257 -278.319806)
			(xy 376.663954 -278.27821) (xy 376.644663 -278.232934) (xy 376.632886 -278.18515) (xy 376.628926 -278.136096)
			(xy 376.309886 -278.136096) (xy 376.309886 -278.160888) (xy 376.302131 -278.209855) (xy 376.286812 -278.257006)
			(xy 376.264306 -278.30118) (xy 376.235167 -278.341289) (xy 376.200112 -278.376347) (xy 376.160005 -278.40549)
			(xy 376.115833 -278.428) (xy 376.068684 -278.443324) (xy 376.019718 -278.451084) (xy 375.99493 -278.451564)
			(xy 375.968387 -278.451059) (xy 375.916038 -278.442245) (xy 375.89079 -278.434038) (xy 375.879614 -278.436324)
			(xy 375.810272 -278.490172) (xy 375.80218 -278.497712) (xy 375.792839 -278.517734) (xy 375.792238 -278.52878)
			(xy 375.792238 -278.780748) (xy 375.793762 -278.793194) (xy 375.797572 -278.807926) (xy 375.79935 -278.812244)
			(xy 375.799858 -278.81326) (xy 375.810069 -278.835476) (xy 375.824105 -278.882308) (xy 375.827798 -278.906478)
			(xy 375.827798 -278.906986) (xy 375.829068 -278.915114) (xy 375.8438 -278.945848) (xy 375.844065 -278.946102)
			(xy 376.148595 -278.946102) (xy 376.15269 -278.895374) (xy 376.164869 -278.84596) (xy 376.184817 -278.79914)
			(xy 376.212018 -278.756126) (xy 376.245766 -278.718032) (xy 376.285188 -278.685845) (xy 376.329262 -278.660399)
			(xy 376.376848 -278.642352) (xy 376.426712 -278.632172) (xy 376.477564 -278.630123) (xy 376.528085 -278.636257)
			(xy 376.576969 -278.650417) (xy 376.622948 -278.672234) (xy 376.664832 -278.701144) (xy 376.701536 -278.736399)
			(xy 376.732109 -278.777085) (xy 376.75576 -278.822148) (xy 376.771876 -278.870422) (xy 376.78004 -278.920656)
			(xy 376.780552 -278.946102) (xy 377.088649 -278.946102) (xy 377.092744 -278.895374) (xy 377.104923 -278.84596)
			(xy 377.124871 -278.79914) (xy 377.152072 -278.756126) (xy 377.18582 -278.718032) (xy 377.225242 -278.685845)
			(xy 377.269316 -278.660399) (xy 377.316902 -278.642352) (xy 377.366766 -278.632172) (xy 377.417618 -278.630123)
			(xy 377.468139 -278.636257) (xy 377.517023 -278.650417) (xy 377.563002 -278.672234) (xy 377.604886 -278.701144)
			(xy 377.64159 -278.736399) (xy 377.672163 -278.777085) (xy 377.695814 -278.822148) (xy 377.71193 -278.870422)
			(xy 377.720094 -278.920656) (xy 377.720606 -278.946102) (xy 378.039134 -278.946102) (xy 378.043094 -278.897048)
			(xy 378.054871 -278.849264) (xy 378.074162 -278.803988) (xy 378.100465 -278.762392) (xy 378.1331 -278.725555)
			(xy 378.171221 -278.69443) (xy 378.213842 -278.669823) (xy 378.259858 -278.652371) (xy 378.308077 -278.642527)
			(xy 378.357252 -278.640546) (xy 378.406107 -278.646478) (xy 378.453378 -278.66017) (xy 378.49784 -278.681268)
			(xy 378.538343 -278.709224) (xy 378.573836 -278.743316) (xy 378.603401 -278.78266) (xy 378.626272 -278.826237)
			(xy 378.641856 -278.872918) (xy 378.649751 -278.921495) (xy 378.650246 -278.946102) (xy 378.968503 -278.946102)
			(xy 378.972598 -278.895374) (xy 378.984777 -278.84596) (xy 379.004725 -278.79914) (xy 379.031926 -278.756126)
			(xy 379.065674 -278.718032) (xy 379.105096 -278.685845) (xy 379.14917 -278.660399) (xy 379.196756 -278.642352)
			(xy 379.24662 -278.632172) (xy 379.297472 -278.630123) (xy 379.347993 -278.636257) (xy 379.396877 -278.650417)
			(xy 379.442856 -278.672234) (xy 379.48474 -278.701144) (xy 379.521444 -278.736399) (xy 379.552017 -278.777085)
			(xy 379.575668 -278.822148) (xy 379.591784 -278.870422) (xy 379.599948 -278.920656) (xy 379.60046 -278.946102)
			(xy 379.918988 -278.946102) (xy 379.922948 -278.897048) (xy 379.934725 -278.849264) (xy 379.954016 -278.803988)
			(xy 379.980319 -278.762392) (xy 380.012954 -278.725555) (xy 380.051075 -278.69443) (xy 380.093696 -278.669823)
			(xy 380.139712 -278.652371) (xy 380.187931 -278.642527) (xy 380.237106 -278.640546) (xy 380.285961 -278.646478)
			(xy 380.333232 -278.66017) (xy 380.377694 -278.681268) (xy 380.418197 -278.709224) (xy 380.45369 -278.743316)
			(xy 380.483255 -278.78266) (xy 380.506126 -278.826237) (xy 380.52171 -278.872918) (xy 380.529605 -278.921495)
			(xy 380.5301 -278.946102) (xy 380.848611 -278.946102) (xy 380.852706 -278.895374) (xy 380.864885 -278.84596)
			(xy 380.884833 -278.79914) (xy 380.912034 -278.756126) (xy 380.945782 -278.718032) (xy 380.985204 -278.685845)
			(xy 381.029278 -278.660399) (xy 381.076864 -278.642352) (xy 381.126728 -278.632172) (xy 381.17758 -278.630123)
			(xy 381.228101 -278.636257) (xy 381.276985 -278.650417) (xy 381.322964 -278.672234) (xy 381.364848 -278.701144)
			(xy 381.401552 -278.736399) (xy 381.432125 -278.777085) (xy 381.455776 -278.822148) (xy 381.471892 -278.870422)
			(xy 381.480056 -278.920656) (xy 381.480568 -278.946102) (xy 381.799096 -278.946102) (xy 381.803056 -278.897048)
			(xy 381.814833 -278.849264) (xy 381.834124 -278.803988) (xy 381.860427 -278.762392) (xy 381.893062 -278.725555)
			(xy 381.931183 -278.69443) (xy 381.973804 -278.669823) (xy 382.01982 -278.652371) (xy 382.068039 -278.642527)
			(xy 382.117214 -278.640546) (xy 382.166069 -278.646478) (xy 382.21334 -278.66017) (xy 382.257802 -278.681268)
			(xy 382.298305 -278.709224) (xy 382.333798 -278.743316) (xy 382.363363 -278.78266) (xy 382.386234 -278.826237)
			(xy 382.401818 -278.872918) (xy 382.409713 -278.921495) (xy 382.410208 -278.946102) (xy 382.738896 -278.946102)
			(xy 382.742856 -278.897048) (xy 382.754633 -278.849264) (xy 382.773924 -278.803988) (xy 382.800227 -278.762392)
			(xy 382.832862 -278.725555) (xy 382.870983 -278.69443) (xy 382.913604 -278.669823) (xy 382.95962 -278.652371)
			(xy 383.007839 -278.642527) (xy 383.057014 -278.640546) (xy 383.105869 -278.646478) (xy 383.15314 -278.66017)
			(xy 383.197602 -278.681268) (xy 383.238105 -278.709224) (xy 383.273598 -278.743316) (xy 383.303163 -278.78266)
			(xy 383.326034 -278.826237) (xy 383.341618 -278.872918) (xy 383.349513 -278.921495) (xy 383.350008 -278.946102)
			(xy 383.67895 -278.946102) (xy 383.68291 -278.897048) (xy 383.694687 -278.849264) (xy 383.713978 -278.803988)
			(xy 383.740281 -278.762392) (xy 383.772916 -278.725555) (xy 383.811037 -278.69443) (xy 383.853658 -278.669823)
			(xy 383.899674 -278.652371) (xy 383.947893 -278.642527) (xy 383.997068 -278.640546) (xy 384.045923 -278.646478)
			(xy 384.093194 -278.66017) (xy 384.137656 -278.681268) (xy 384.178159 -278.709224) (xy 384.213652 -278.743316)
			(xy 384.243217 -278.78266) (xy 384.266088 -278.826237) (xy 384.281672 -278.872918) (xy 384.289567 -278.921495)
			(xy 384.290062 -278.946102) (xy 384.289567 -278.970709) (xy 384.281672 -279.019286) (xy 384.266088 -279.065967)
			(xy 384.243217 -279.109544) (xy 384.213652 -279.148888) (xy 384.178159 -279.18298) (xy 384.137656 -279.210936)
			(xy 384.093194 -279.232034) (xy 384.045923 -279.245726) (xy 383.997068 -279.251658) (xy 383.947893 -279.249677)
			(xy 383.899674 -279.239833) (xy 383.853658 -279.222381) (xy 383.811037 -279.197774) (xy 383.772916 -279.166649)
			(xy 383.740281 -279.129812) (xy 383.713978 -279.088216) (xy 383.694687 -279.04294) (xy 383.68291 -278.995156)
			(xy 383.67895 -278.946102) (xy 383.350008 -278.946102) (xy 383.349513 -278.970709) (xy 383.341618 -279.019286)
			(xy 383.326034 -279.065967) (xy 383.303163 -279.109544) (xy 383.273598 -279.148888) (xy 383.238105 -279.18298)
			(xy 383.197602 -279.210936) (xy 383.15314 -279.232034) (xy 383.105869 -279.245726) (xy 383.057014 -279.251658)
			(xy 383.007839 -279.249677) (xy 382.95962 -279.239833) (xy 382.913604 -279.222381) (xy 382.870983 -279.197774)
			(xy 382.832862 -279.166649) (xy 382.800227 -279.129812) (xy 382.773924 -279.088216) (xy 382.754633 -279.04294)
			(xy 382.742856 -278.995156) (xy 382.738896 -278.946102) (xy 382.410208 -278.946102) (xy 382.409713 -278.970709)
			(xy 382.401818 -279.019286) (xy 382.386234 -279.065967) (xy 382.363363 -279.109544) (xy 382.333798 -279.148888)
			(xy 382.298305 -279.18298) (xy 382.257802 -279.210936) (xy 382.21334 -279.232034) (xy 382.166069 -279.245726)
			(xy 382.117214 -279.251658) (xy 382.068039 -279.249677) (xy 382.01982 -279.239833) (xy 381.973804 -279.222381)
			(xy 381.931183 -279.197774) (xy 381.893062 -279.166649) (xy 381.860427 -279.129812) (xy 381.834124 -279.088216)
			(xy 381.814833 -279.04294) (xy 381.803056 -278.995156) (xy 381.799096 -278.946102) (xy 381.480568 -278.946102)
			(xy 381.480056 -278.971548) (xy 381.471892 -279.021782) (xy 381.455776 -279.070056) (xy 381.432125 -279.115119)
			(xy 381.401552 -279.155805) (xy 381.364848 -279.19106) (xy 381.322964 -279.21997) (xy 381.276985 -279.241787)
			(xy 381.228101 -279.255947) (xy 381.17758 -279.262081) (xy 381.126728 -279.260032) (xy 381.076864 -279.249852)
			(xy 381.029278 -279.231805) (xy 380.985204 -279.206359) (xy 380.945782 -279.174172) (xy 380.912034 -279.136078)
			(xy 380.884833 -279.093064) (xy 380.864885 -279.046244) (xy 380.852706 -278.99683) (xy 380.848611 -278.946102)
			(xy 380.5301 -278.946102) (xy 380.529605 -278.970709) (xy 380.52171 -279.019286) (xy 380.506126 -279.065967)
			(xy 380.483255 -279.109544) (xy 380.45369 -279.148888) (xy 380.418197 -279.18298) (xy 380.377694 -279.210936)
			(xy 380.333232 -279.232034) (xy 380.285961 -279.245726) (xy 380.237106 -279.251658) (xy 380.187931 -279.249677)
			(xy 380.139712 -279.239833) (xy 380.093696 -279.222381) (xy 380.051075 -279.197774) (xy 380.012954 -279.166649)
			(xy 379.980319 -279.129812) (xy 379.954016 -279.088216) (xy 379.934725 -279.04294) (xy 379.922948 -278.995156)
			(xy 379.918988 -278.946102) (xy 379.60046 -278.946102) (xy 379.599948 -278.971548) (xy 379.591784 -279.021782)
			(xy 379.575668 -279.070056) (xy 379.552017 -279.115119) (xy 379.521444 -279.155805) (xy 379.48474 -279.19106)
			(xy 379.442856 -279.21997) (xy 379.396877 -279.241787) (xy 379.347993 -279.255947) (xy 379.297472 -279.262081)
			(xy 379.24662 -279.260032) (xy 379.196756 -279.249852) (xy 379.14917 -279.231805) (xy 379.105096 -279.206359)
			(xy 379.065674 -279.174172) (xy 379.031926 -279.136078) (xy 379.004725 -279.093064) (xy 378.984777 -279.046244)
			(xy 378.972598 -278.99683) (xy 378.968503 -278.946102) (xy 378.650246 -278.946102) (xy 378.649751 -278.970709)
			(xy 378.641856 -279.019286) (xy 378.626272 -279.065967) (xy 378.603401 -279.109544) (xy 378.573836 -279.148888)
			(xy 378.538343 -279.18298) (xy 378.49784 -279.210936) (xy 378.453378 -279.232034) (xy 378.406107 -279.245726)
			(xy 378.357252 -279.251658) (xy 378.308077 -279.249677) (xy 378.259858 -279.239833) (xy 378.213842 -279.222381)
			(xy 378.171221 -279.197774) (xy 378.1331 -279.166649) (xy 378.100465 -279.129812) (xy 378.074162 -279.088216)
			(xy 378.054871 -279.04294) (xy 378.043094 -278.995156) (xy 378.039134 -278.946102) (xy 377.720606 -278.946102)
			(xy 377.720094 -278.971548) (xy 377.71193 -279.021782) (xy 377.695814 -279.070056) (xy 377.672163 -279.115119)
			(xy 377.64159 -279.155805) (xy 377.604886 -279.19106) (xy 377.563002 -279.21997) (xy 377.517023 -279.241787)
			(xy 377.468139 -279.255947) (xy 377.417618 -279.262081) (xy 377.366766 -279.260032) (xy 377.316902 -279.249852)
			(xy 377.269316 -279.231805) (xy 377.225242 -279.206359) (xy 377.18582 -279.174172) (xy 377.152072 -279.136078)
			(xy 377.124871 -279.093064) (xy 377.104923 -279.046244) (xy 377.092744 -278.99683) (xy 377.088649 -278.946102)
			(xy 376.780552 -278.946102) (xy 376.78004 -278.971548) (xy 376.771876 -279.021782) (xy 376.75576 -279.070056)
			(xy 376.732109 -279.115119) (xy 376.701536 -279.155805) (xy 376.664832 -279.19106) (xy 376.622948 -279.21997)
			(xy 376.576969 -279.241787) (xy 376.528085 -279.255947) (xy 376.477564 -279.262081) (xy 376.426712 -279.260032)
			(xy 376.376848 -279.249852) (xy 376.329262 -279.231805) (xy 376.285188 -279.206359) (xy 376.245766 -279.174172)
			(xy 376.212018 -279.136078) (xy 376.184817 -279.093064) (xy 376.164869 -279.046244) (xy 376.15269 -278.99683)
			(xy 376.148595 -278.946102) (xy 375.844065 -278.946102) (xy 375.85015 -278.951944) (xy 375.884926 -278.98708)
			(xy 375.948882 -279.062474) (xy 376.006012 -279.143164) (xy 376.055879 -279.228532) (xy 376.07748 -279.273)
			(xy 376.09866 -279.31918) (xy 376.13364 -279.414574) (xy 376.14733 -279.4635) (xy 376.149616 -279.472136)
			(xy 376.154442 -279.478994) (xy 376.157278 -279.482916) (xy 376.164181 -279.489698) (xy 376.168158 -279.492456)
			(xy 376.189631 -279.50719) (xy 376.227885 -279.542523) (xy 376.259825 -279.583652) (xy 376.284586 -279.629462)
			(xy 376.301498 -279.678713) (xy 376.310103 -279.730072) (xy 376.310652 -279.756108) (xy 376.628926 -279.756108)
			(xy 376.632886 -279.707054) (xy 376.644663 -279.65927) (xy 376.663954 -279.613994) (xy 376.690257 -279.572398)
			(xy 376.722892 -279.535561) (xy 376.761013 -279.504436) (xy 376.803634 -279.479829) (xy 376.84965 -279.462377)
			(xy 376.897869 -279.452533) (xy 376.947044 -279.450552) (xy 376.995899 -279.456484) (xy 377.04317 -279.470176)
			(xy 377.087632 -279.491274) (xy 377.128135 -279.51923) (xy 377.163628 -279.553322) (xy 377.193193 -279.592666)
			(xy 377.216064 -279.636243) (xy 377.231648 -279.682924) (xy 377.239543 -279.731501) (xy 377.240038 -279.756108)
			(xy 377.558549 -279.756108) (xy 377.562644 -279.70538) (xy 377.574823 -279.655966) (xy 377.594771 -279.609146)
			(xy 377.621972 -279.566132) (xy 377.65572 -279.528038) (xy 377.695142 -279.495851) (xy 377.739216 -279.470405)
			(xy 377.786802 -279.452358) (xy 377.836666 -279.442178) (xy 377.887518 -279.440129) (xy 377.938039 -279.446263)
			(xy 377.986923 -279.460423) (xy 378.032902 -279.48224) (xy 378.074786 -279.51115) (xy 378.11149 -279.546405)
			(xy 378.142063 -279.587091) (xy 378.165714 -279.632154) (xy 378.18183 -279.680428) (xy 378.189994 -279.730662)
			(xy 378.190506 -279.756108) (xy 378.509034 -279.756108) (xy 378.512994 -279.707054) (xy 378.524771 -279.65927)
			(xy 378.544062 -279.613994) (xy 378.570365 -279.572398) (xy 378.603 -279.535561) (xy 378.641121 -279.504436)
			(xy 378.683742 -279.479829) (xy 378.729758 -279.462377) (xy 378.777977 -279.452533) (xy 378.827152 -279.450552)
			(xy 378.876007 -279.456484) (xy 378.923278 -279.470176) (xy 378.96774 -279.491274) (xy 379.008243 -279.51923)
			(xy 379.043736 -279.553322) (xy 379.073301 -279.592666) (xy 379.096172 -279.636243) (xy 379.111756 -279.682924)
			(xy 379.119651 -279.731501) (xy 379.120146 -279.756108) (xy 379.438657 -279.756108) (xy 379.442752 -279.70538)
			(xy 379.454931 -279.655966) (xy 379.474879 -279.609146) (xy 379.50208 -279.566132) (xy 379.535828 -279.528038)
			(xy 379.57525 -279.495851) (xy 379.619324 -279.470405) (xy 379.66691 -279.452358) (xy 379.716774 -279.442178)
			(xy 379.767626 -279.440129) (xy 379.818147 -279.446263) (xy 379.867031 -279.460423) (xy 379.91301 -279.48224)
			(xy 379.954894 -279.51115) (xy 379.991598 -279.546405) (xy 380.022171 -279.587091) (xy 380.045822 -279.632154)
			(xy 380.061938 -279.680428) (xy 380.070102 -279.730662) (xy 380.070614 -279.756108) (xy 380.378711 -279.756108)
			(xy 380.382806 -279.70538) (xy 380.394985 -279.655966) (xy 380.414933 -279.609146) (xy 380.442134 -279.566132)
			(xy 380.475882 -279.528038) (xy 380.515304 -279.495851) (xy 380.559378 -279.470405) (xy 380.606964 -279.452358)
			(xy 380.656828 -279.442178) (xy 380.70768 -279.440129) (xy 380.758201 -279.446263) (xy 380.807085 -279.460423)
			(xy 380.853064 -279.48224) (xy 380.894948 -279.51115) (xy 380.931652 -279.546405) (xy 380.962225 -279.587091)
			(xy 380.985876 -279.632154) (xy 381.001992 -279.680428) (xy 381.010156 -279.730662) (xy 381.010668 -279.756108)
			(xy 381.328942 -279.756108) (xy 381.332902 -279.707054) (xy 381.344679 -279.65927) (xy 381.36397 -279.613994)
			(xy 381.390273 -279.572398) (xy 381.422908 -279.535561) (xy 381.461029 -279.504436) (xy 381.50365 -279.479829)
			(xy 381.549666 -279.462377) (xy 381.597885 -279.452533) (xy 381.64706 -279.450552) (xy 381.695915 -279.456484)
			(xy 381.743186 -279.470176) (xy 381.787648 -279.491274) (xy 381.828151 -279.51923) (xy 381.863644 -279.553322)
			(xy 381.893209 -279.592666) (xy 381.91608 -279.636243) (xy 381.931664 -279.682924) (xy 381.939559 -279.731501)
			(xy 381.940054 -279.756108) (xy 382.268996 -279.756108) (xy 382.272956 -279.707054) (xy 382.284733 -279.65927)
			(xy 382.304024 -279.613994) (xy 382.330327 -279.572398) (xy 382.362962 -279.535561) (xy 382.401083 -279.504436)
			(xy 382.443704 -279.479829) (xy 382.48972 -279.462377) (xy 382.537939 -279.452533) (xy 382.587114 -279.450552)
			(xy 382.635969 -279.456484) (xy 382.68324 -279.470176) (xy 382.727702 -279.491274) (xy 382.768205 -279.51923)
			(xy 382.803698 -279.553322) (xy 382.833263 -279.592666) (xy 382.856134 -279.636243) (xy 382.871718 -279.682924)
			(xy 382.879613 -279.731501) (xy 382.880108 -279.756108) (xy 383.20905 -279.756108) (xy 383.21301 -279.707054)
			(xy 383.224787 -279.65927) (xy 383.244078 -279.613994) (xy 383.270381 -279.572398) (xy 383.303016 -279.535561)
			(xy 383.341137 -279.504436) (xy 383.383758 -279.479829) (xy 383.429774 -279.462377) (xy 383.477993 -279.452533)
			(xy 383.527168 -279.450552) (xy 383.576023 -279.456484) (xy 383.623294 -279.470176) (xy 383.667756 -279.491274)
			(xy 383.708259 -279.51923) (xy 383.743752 -279.553322) (xy 383.773317 -279.592666) (xy 383.796188 -279.636243)
			(xy 383.811772 -279.682924) (xy 383.819667 -279.731501) (xy 383.820162 -279.756108) (xy 384.149104 -279.756108)
			(xy 384.153064 -279.707054) (xy 384.164841 -279.65927) (xy 384.184132 -279.613994) (xy 384.210435 -279.572398)
			(xy 384.24307 -279.535561) (xy 384.281191 -279.504436) (xy 384.323812 -279.479829) (xy 384.369828 -279.462377)
			(xy 384.418047 -279.452533) (xy 384.467222 -279.450552) (xy 384.516077 -279.456484) (xy 384.563348 -279.470176)
			(xy 384.60781 -279.491274) (xy 384.648313 -279.51923) (xy 384.683806 -279.553322) (xy 384.713371 -279.592666)
			(xy 384.736242 -279.636243) (xy 384.751826 -279.682924) (xy 384.759721 -279.731501) (xy 384.760216 -279.756108)
			(xy 384.759721 -279.780715) (xy 384.751826 -279.829292) (xy 384.736242 -279.875973) (xy 384.713371 -279.91955)
			(xy 384.683806 -279.958894) (xy 384.648313 -279.992986) (xy 384.60781 -280.020942) (xy 384.563348 -280.04204)
			(xy 384.516077 -280.055732) (xy 384.467222 -280.061664) (xy 384.418047 -280.059683) (xy 384.369828 -280.049839)
			(xy 384.323812 -280.032387) (xy 384.281191 -280.00778) (xy 384.24307 -279.976655) (xy 384.210435 -279.939818)
			(xy 384.184132 -279.898222) (xy 384.164841 -279.852946) (xy 384.153064 -279.805162) (xy 384.149104 -279.756108)
			(xy 383.820162 -279.756108) (xy 383.819667 -279.780715) (xy 383.811772 -279.829292) (xy 383.796188 -279.875973)
			(xy 383.773317 -279.91955) (xy 383.743752 -279.958894) (xy 383.708259 -279.992986) (xy 383.667756 -280.020942)
			(xy 383.623294 -280.04204) (xy 383.576023 -280.055732) (xy 383.527168 -280.061664) (xy 383.477993 -280.059683)
			(xy 383.429774 -280.049839) (xy 383.383758 -280.032387) (xy 383.341137 -280.00778) (xy 383.303016 -279.976655)
			(xy 383.270381 -279.939818) (xy 383.244078 -279.898222) (xy 383.224787 -279.852946) (xy 383.21301 -279.805162)
			(xy 383.20905 -279.756108) (xy 382.880108 -279.756108) (xy 382.879613 -279.780715) (xy 382.871718 -279.829292)
			(xy 382.856134 -279.875973) (xy 382.833263 -279.91955) (xy 382.803698 -279.958894) (xy 382.768205 -279.992986)
			(xy 382.727702 -280.020942) (xy 382.68324 -280.04204) (xy 382.635969 -280.055732) (xy 382.587114 -280.061664)
			(xy 382.537939 -280.059683) (xy 382.48972 -280.049839) (xy 382.443704 -280.032387) (xy 382.401083 -280.00778)
			(xy 382.362962 -279.976655) (xy 382.330327 -279.939818) (xy 382.304024 -279.898222) (xy 382.284733 -279.852946)
			(xy 382.272956 -279.805162) (xy 382.268996 -279.756108) (xy 381.940054 -279.756108) (xy 381.939559 -279.780715)
			(xy 381.931664 -279.829292) (xy 381.91608 -279.875973) (xy 381.893209 -279.91955) (xy 381.863644 -279.958894)
			(xy 381.828151 -279.992986) (xy 381.787648 -280.020942) (xy 381.743186 -280.04204) (xy 381.695915 -280.055732)
			(xy 381.64706 -280.061664) (xy 381.597885 -280.059683) (xy 381.549666 -280.049839) (xy 381.50365 -280.032387)
			(xy 381.461029 -280.00778) (xy 381.422908 -279.976655) (xy 381.390273 -279.939818) (xy 381.36397 -279.898222)
			(xy 381.344679 -279.852946) (xy 381.332902 -279.805162) (xy 381.328942 -279.756108) (xy 381.010668 -279.756108)
			(xy 381.010156 -279.781554) (xy 381.001992 -279.831788) (xy 380.985876 -279.880062) (xy 380.962225 -279.925125)
			(xy 380.931652 -279.965811) (xy 380.894948 -280.001066) (xy 380.853064 -280.029976) (xy 380.807085 -280.051793)
			(xy 380.758201 -280.065953) (xy 380.70768 -280.072087) (xy 380.656828 -280.070038) (xy 380.606964 -280.059858)
			(xy 380.559378 -280.041811) (xy 380.515304 -280.016365) (xy 380.475882 -279.984178) (xy 380.442134 -279.946084)
			(xy 380.414933 -279.90307) (xy 380.394985 -279.85625) (xy 380.382806 -279.806836) (xy 380.378711 -279.756108)
			(xy 380.070614 -279.756108) (xy 380.070102 -279.781554) (xy 380.061938 -279.831788) (xy 380.045822 -279.880062)
			(xy 380.022171 -279.925125) (xy 379.991598 -279.965811) (xy 379.954894 -280.001066) (xy 379.91301 -280.029976)
			(xy 379.867031 -280.051793) (xy 379.818147 -280.065953) (xy 379.767626 -280.072087) (xy 379.716774 -280.070038)
			(xy 379.66691 -280.059858) (xy 379.619324 -280.041811) (xy 379.57525 -280.016365) (xy 379.535828 -279.984178)
			(xy 379.50208 -279.946084) (xy 379.474879 -279.90307) (xy 379.454931 -279.85625) (xy 379.442752 -279.806836)
			(xy 379.438657 -279.756108) (xy 379.120146 -279.756108) (xy 379.119651 -279.780715) (xy 379.111756 -279.829292)
			(xy 379.096172 -279.875973) (xy 379.073301 -279.91955) (xy 379.043736 -279.958894) (xy 379.008243 -279.992986)
			(xy 378.96774 -280.020942) (xy 378.923278 -280.04204) (xy 378.876007 -280.055732) (xy 378.827152 -280.061664)
			(xy 378.777977 -280.059683) (xy 378.729758 -280.049839) (xy 378.683742 -280.032387) (xy 378.641121 -280.00778)
			(xy 378.603 -279.976655) (xy 378.570365 -279.939818) (xy 378.544062 -279.898222) (xy 378.524771 -279.852946)
			(xy 378.512994 -279.805162) (xy 378.509034 -279.756108) (xy 378.190506 -279.756108) (xy 378.189994 -279.781554)
			(xy 378.18183 -279.831788) (xy 378.165714 -279.880062) (xy 378.142063 -279.925125) (xy 378.11149 -279.965811)
			(xy 378.074786 -280.001066) (xy 378.032902 -280.029976) (xy 377.986923 -280.051793) (xy 377.938039 -280.065953)
			(xy 377.887518 -280.072087) (xy 377.836666 -280.070038) (xy 377.786802 -280.059858) (xy 377.739216 -280.041811)
			(xy 377.695142 -280.016365) (xy 377.65572 -279.984178) (xy 377.621972 -279.946084) (xy 377.594771 -279.90307)
			(xy 377.574823 -279.85625) (xy 377.562644 -279.806836) (xy 377.558549 -279.756108) (xy 377.240038 -279.756108)
			(xy 377.239543 -279.780715) (xy 377.231648 -279.829292) (xy 377.216064 -279.875973) (xy 377.193193 -279.91955)
			(xy 377.163628 -279.958894) (xy 377.128135 -279.992986) (xy 377.087632 -280.020942) (xy 377.04317 -280.04204)
			(xy 376.995899 -280.055732) (xy 376.947044 -280.061664) (xy 376.897869 -280.059683) (xy 376.84965 -280.049839)
			(xy 376.803634 -280.032387) (xy 376.761013 -280.00778) (xy 376.722892 -279.976655) (xy 376.690257 -279.939818)
			(xy 376.663954 -279.898222) (xy 376.644663 -279.852946) (xy 376.632886 -279.805162) (xy 376.628926 -279.756108)
			(xy 376.310652 -279.756108) (xy 376.310101 -279.782146) (xy 376.301516 -279.833512) (xy 376.284614 -279.88277)
			(xy 376.259854 -279.928585) (xy 376.227907 -279.969712) (xy 376.18964 -280.005036) (xy 376.168158 -280.01976)
			(xy 376.164195 -280.022535) (xy 376.157297 -280.029316) (xy 376.154442 -280.033222) (xy 376.149616 -280.04008)
			(xy 376.14733 -280.048716) (xy 376.133868 -280.0968) (xy 376.0996 -280.190598) (xy 376.057198 -280.281009)
			(xy 376.006992 -280.367331) (xy 375.949372 -280.448892) (xy 375.884787 -280.525055) (xy 375.849642 -280.560526)
			(xy 375.844054 -280.566114) (xy 376.148595 -280.566114) (xy 376.15269 -280.515386) (xy 376.164869 -280.465972)
			(xy 376.184817 -280.419152) (xy 376.212018 -280.376138) (xy 376.245766 -280.338044) (xy 376.285188 -280.305857)
			(xy 376.329262 -280.280411) (xy 376.376848 -280.262364) (xy 376.426712 -280.252184) (xy 376.477564 -280.250135)
			(xy 376.528085 -280.256269) (xy 376.576969 -280.270429) (xy 376.622948 -280.292246) (xy 376.664832 -280.321156)
			(xy 376.701536 -280.356411) (xy 376.732109 -280.397097) (xy 376.75576 -280.44216) (xy 376.771876 -280.490434)
			(xy 376.78004 -280.540668) (xy 376.780552 -280.566114) (xy 377.088649 -280.566114) (xy 377.092744 -280.515386)
			(xy 377.104923 -280.465972) (xy 377.124871 -280.419152) (xy 377.152072 -280.376138) (xy 377.18582 -280.338044)
			(xy 377.225242 -280.305857) (xy 377.269316 -280.280411) (xy 377.316902 -280.262364) (xy 377.366766 -280.252184)
			(xy 377.417618 -280.250135) (xy 377.468139 -280.256269) (xy 377.517023 -280.270429) (xy 377.563002 -280.292246)
			(xy 377.604886 -280.321156) (xy 377.64159 -280.356411) (xy 377.672163 -280.397097) (xy 377.695814 -280.44216)
			(xy 377.71193 -280.490434) (xy 377.720094 -280.540668) (xy 377.720606 -280.566114) (xy 378.968503 -280.566114)
			(xy 378.972598 -280.515386) (xy 378.984777 -280.465972) (xy 379.004725 -280.419152) (xy 379.031926 -280.376138)
			(xy 379.065674 -280.338044) (xy 379.105096 -280.305857) (xy 379.14917 -280.280411) (xy 379.196756 -280.262364)
			(xy 379.24662 -280.252184) (xy 379.297472 -280.250135) (xy 379.347993 -280.256269) (xy 379.396877 -280.270429)
			(xy 379.442856 -280.292246) (xy 379.48474 -280.321156) (xy 379.521444 -280.356411) (xy 379.552017 -280.397097)
			(xy 379.575668 -280.44216) (xy 379.591784 -280.490434) (xy 379.599948 -280.540668) (xy 379.60046 -280.566114)
			(xy 379.918988 -280.566114) (xy 379.922948 -280.51706) (xy 379.934725 -280.469276) (xy 379.954016 -280.424)
			(xy 379.980319 -280.382404) (xy 380.012954 -280.345567) (xy 380.051075 -280.314442) (xy 380.093696 -280.289835)
			(xy 380.139712 -280.272383) (xy 380.187931 -280.262539) (xy 380.237106 -280.260558) (xy 380.285961 -280.26649)
			(xy 380.333232 -280.280182) (xy 380.377694 -280.30128) (xy 380.418197 -280.329236) (xy 380.45369 -280.363328)
			(xy 380.483255 -280.402672) (xy 380.506126 -280.446249) (xy 380.52171 -280.49293) (xy 380.529605 -280.541507)
			(xy 380.5301 -280.566114) (xy 380.848611 -280.566114) (xy 380.852706 -280.515386) (xy 380.864885 -280.465972)
			(xy 380.884833 -280.419152) (xy 380.912034 -280.376138) (xy 380.945782 -280.338044) (xy 380.985204 -280.305857)
			(xy 381.029278 -280.280411) (xy 381.076864 -280.262364) (xy 381.126728 -280.252184) (xy 381.17758 -280.250135)
			(xy 381.228101 -280.256269) (xy 381.276985 -280.270429) (xy 381.322964 -280.292246) (xy 381.364848 -280.321156)
			(xy 381.401552 -280.356411) (xy 381.432125 -280.397097) (xy 381.455776 -280.44216) (xy 381.471892 -280.490434)
			(xy 381.480056 -280.540668) (xy 381.480568 -280.566114) (xy 381.799096 -280.566114) (xy 381.803056 -280.51706)
			(xy 381.814833 -280.469276) (xy 381.834124 -280.424) (xy 381.860427 -280.382404) (xy 381.893062 -280.345567)
			(xy 381.931183 -280.314442) (xy 381.973804 -280.289835) (xy 382.01982 -280.272383) (xy 382.068039 -280.262539)
			(xy 382.117214 -280.260558) (xy 382.166069 -280.26649) (xy 382.21334 -280.280182) (xy 382.257802 -280.30128)
			(xy 382.298305 -280.329236) (xy 382.333798 -280.363328) (xy 382.363363 -280.402672) (xy 382.386234 -280.446249)
			(xy 382.401818 -280.49293) (xy 382.409713 -280.541507) (xy 382.410208 -280.566114) (xy 382.738896 -280.566114)
			(xy 382.742856 -280.51706) (xy 382.754633 -280.469276) (xy 382.773924 -280.424) (xy 382.800227 -280.382404)
			(xy 382.832862 -280.345567) (xy 382.870983 -280.314442) (xy 382.913604 -280.289835) (xy 382.95962 -280.272383)
			(xy 383.007839 -280.262539) (xy 383.057014 -280.260558) (xy 383.105869 -280.26649) (xy 383.15314 -280.280182)
			(xy 383.197602 -280.30128) (xy 383.238105 -280.329236) (xy 383.273598 -280.363328) (xy 383.303163 -280.402672)
			(xy 383.326034 -280.446249) (xy 383.341618 -280.49293) (xy 383.349513 -280.541507) (xy 383.350008 -280.566114)
			(xy 383.67895 -280.566114) (xy 383.68291 -280.51706) (xy 383.694687 -280.469276) (xy 383.713978 -280.424)
			(xy 383.740281 -280.382404) (xy 383.772916 -280.345567) (xy 383.811037 -280.314442) (xy 383.853658 -280.289835)
			(xy 383.899674 -280.272383) (xy 383.947893 -280.262539) (xy 383.997068 -280.260558) (xy 384.045923 -280.26649)
			(xy 384.093194 -280.280182) (xy 384.137656 -280.30128) (xy 384.178159 -280.329236) (xy 384.213652 -280.363328)
			(xy 384.243217 -280.402672) (xy 384.266088 -280.446249) (xy 384.281672 -280.49293) (xy 384.289567 -280.541507)
			(xy 384.290062 -280.566114) (xy 384.289567 -280.590721) (xy 384.281672 -280.639298) (xy 384.266088 -280.685979)
			(xy 384.243217 -280.729556) (xy 384.213652 -280.7689) (xy 384.178159 -280.802992) (xy 384.137656 -280.830948)
			(xy 384.093194 -280.852046) (xy 384.045923 -280.865738) (xy 383.997068 -280.87167) (xy 383.947893 -280.869689)
			(xy 383.899674 -280.859845) (xy 383.853658 -280.842393) (xy 383.811037 -280.817786) (xy 383.772916 -280.786661)
			(xy 383.740281 -280.749824) (xy 383.713978 -280.708228) (xy 383.694687 -280.662952) (xy 383.68291 -280.615168)
			(xy 383.67895 -280.566114) (xy 383.350008 -280.566114) (xy 383.349513 -280.590721) (xy 383.341618 -280.639298)
			(xy 383.326034 -280.685979) (xy 383.303163 -280.729556) (xy 383.273598 -280.7689) (xy 383.238105 -280.802992)
			(xy 383.197602 -280.830948) (xy 383.15314 -280.852046) (xy 383.105869 -280.865738) (xy 383.057014 -280.87167)
			(xy 383.007839 -280.869689) (xy 382.95962 -280.859845) (xy 382.913604 -280.842393) (xy 382.870983 -280.817786)
			(xy 382.832862 -280.786661) (xy 382.800227 -280.749824) (xy 382.773924 -280.708228) (xy 382.754633 -280.662952)
			(xy 382.742856 -280.615168) (xy 382.738896 -280.566114) (xy 382.410208 -280.566114) (xy 382.409713 -280.590721)
			(xy 382.401818 -280.639298) (xy 382.386234 -280.685979) (xy 382.363363 -280.729556) (xy 382.333798 -280.7689)
			(xy 382.298305 -280.802992) (xy 382.257802 -280.830948) (xy 382.21334 -280.852046) (xy 382.166069 -280.865738)
			(xy 382.117214 -280.87167) (xy 382.068039 -280.869689) (xy 382.01982 -280.859845) (xy 381.973804 -280.842393)
			(xy 381.931183 -280.817786) (xy 381.893062 -280.786661) (xy 381.860427 -280.749824) (xy 381.834124 -280.708228)
			(xy 381.814833 -280.662952) (xy 381.803056 -280.615168) (xy 381.799096 -280.566114) (xy 381.480568 -280.566114)
			(xy 381.480056 -280.59156) (xy 381.471892 -280.641794) (xy 381.455776 -280.690068) (xy 381.432125 -280.735131)
			(xy 381.401552 -280.775817) (xy 381.364848 -280.811072) (xy 381.322964 -280.839982) (xy 381.276985 -280.861799)
			(xy 381.228101 -280.875959) (xy 381.17758 -280.882093) (xy 381.126728 -280.880044) (xy 381.076864 -280.869864)
			(xy 381.029278 -280.851817) (xy 380.985204 -280.826371) (xy 380.945782 -280.794184) (xy 380.912034 -280.75609)
			(xy 380.884833 -280.713076) (xy 380.864885 -280.666256) (xy 380.852706 -280.616842) (xy 380.848611 -280.566114)
			(xy 380.5301 -280.566114) (xy 380.529605 -280.590721) (xy 380.52171 -280.639298) (xy 380.506126 -280.685979)
			(xy 380.483255 -280.729556) (xy 380.45369 -280.7689) (xy 380.418197 -280.802992) (xy 380.377694 -280.830948)
			(xy 380.333232 -280.852046) (xy 380.285961 -280.865738) (xy 380.237106 -280.87167) (xy 380.187931 -280.869689)
			(xy 380.139712 -280.859845) (xy 380.093696 -280.842393) (xy 380.051075 -280.817786) (xy 380.012954 -280.786661)
			(xy 379.980319 -280.749824) (xy 379.954016 -280.708228) (xy 379.934725 -280.662952) (xy 379.922948 -280.615168)
			(xy 379.918988 -280.566114) (xy 379.60046 -280.566114) (xy 379.599948 -280.59156) (xy 379.591784 -280.641794)
			(xy 379.575668 -280.690068) (xy 379.552017 -280.735131) (xy 379.521444 -280.775817) (xy 379.48474 -280.811072)
			(xy 379.442856 -280.839982) (xy 379.396877 -280.861799) (xy 379.347993 -280.875959) (xy 379.297472 -280.882093)
			(xy 379.24662 -280.880044) (xy 379.196756 -280.869864) (xy 379.14917 -280.851817) (xy 379.105096 -280.826371)
			(xy 379.065674 -280.794184) (xy 379.031926 -280.75609) (xy 379.004725 -280.713076) (xy 378.984777 -280.666256)
			(xy 378.972598 -280.616842) (xy 378.968503 -280.566114) (xy 377.720606 -280.566114) (xy 377.720094 -280.59156)
			(xy 377.71193 -280.641794) (xy 377.695814 -280.690068) (xy 377.672163 -280.735131) (xy 377.64159 -280.775817)
			(xy 377.604886 -280.811072) (xy 377.563002 -280.839982) (xy 377.517023 -280.861799) (xy 377.468139 -280.875959)
			(xy 377.417618 -280.882093) (xy 377.366766 -280.880044) (xy 377.316902 -280.869864) (xy 377.269316 -280.851817)
			(xy 377.225242 -280.826371) (xy 377.18582 -280.794184) (xy 377.152072 -280.75609) (xy 377.124871 -280.713076)
			(xy 377.104923 -280.666256) (xy 377.092744 -280.616842) (xy 377.088649 -280.566114) (xy 376.780552 -280.566114)
			(xy 376.78004 -280.59156) (xy 376.771876 -280.641794) (xy 376.75576 -280.690068) (xy 376.732109 -280.735131)
			(xy 376.701536 -280.775817) (xy 376.664832 -280.811072) (xy 376.622948 -280.839982) (xy 376.576969 -280.861799)
			(xy 376.528085 -280.875959) (xy 376.477564 -280.882093) (xy 376.426712 -280.880044) (xy 376.376848 -280.869864)
			(xy 376.329262 -280.851817) (xy 376.285188 -280.826371) (xy 376.245766 -280.794184) (xy 376.212018 -280.75609)
			(xy 376.184817 -280.713076) (xy 376.164869 -280.666256) (xy 376.15269 -280.616842) (xy 376.148595 -280.566114)
			(xy 375.844054 -280.566114) (xy 375.843546 -280.566622) (xy 375.828814 -280.597356) (xy 375.827544 -280.605484)
			(xy 375.827544 -280.605992) (xy 375.825531 -280.619872) (xy 375.819299 -280.647221) (xy 375.815098 -280.660602)
			(xy 375.812558 -280.668476) (xy 375.812558 -280.745438) (xy 375.81203 -280.755279) (xy 375.804457 -280.773454)
			(xy 375.797826 -280.780744) (xy 375.667524 -280.911046) (xy 375.663912 -280.914816) (xy 375.658153 -280.923521)
			(xy 375.656094 -280.928318) (xy 375.635774 -280.98369) (xy 375.620924 -281.020063) (xy 375.586853 -281.090864)
			(xy 375.567702 -281.125168) (xy 375.566432 -281.127454) (xy 375.563638 -281.134312) (xy 375.562479 -281.138147)
			(xy 375.561206 -281.146055) (xy 375.561098 -281.15006) (xy 375.561098 -281.37612) (xy 375.678695 -281.37612)
			(xy 375.68279 -281.325392) (xy 375.694969 -281.275978) (xy 375.714917 -281.229158) (xy 375.742118 -281.186144)
			(xy 375.775866 -281.14805) (xy 375.815288 -281.115863) (xy 375.859362 -281.090417) (xy 375.906948 -281.07237)
			(xy 375.956812 -281.06219) (xy 376.007664 -281.060141) (xy 376.058185 -281.066275) (xy 376.107069 -281.080435)
			(xy 376.153048 -281.102252) (xy 376.194932 -281.131162) (xy 376.231636 -281.166417) (xy 376.262209 -281.207103)
			(xy 376.28586 -281.252166) (xy 376.301976 -281.30044) (xy 376.31014 -281.350674) (xy 376.310652 -281.37612)
			(xy 376.628926 -281.37612) (xy 376.632886 -281.327066) (xy 376.644663 -281.279282) (xy 376.663954 -281.234006)
			(xy 376.690257 -281.19241) (xy 376.722892 -281.155573) (xy 376.761013 -281.124448) (xy 376.803634 -281.099841)
			(xy 376.84965 -281.082389) (xy 376.897869 -281.072545) (xy 376.947044 -281.070564) (xy 376.995899 -281.076496)
			(xy 377.04317 -281.090188) (xy 377.087632 -281.111286) (xy 377.128135 -281.139242) (xy 377.163628 -281.173334)
			(xy 377.193193 -281.212678) (xy 377.216064 -281.256255) (xy 377.231648 -281.302936) (xy 377.239543 -281.351513)
			(xy 377.240038 -281.37612) (xy 377.558549 -281.37612) (xy 377.562644 -281.325392) (xy 377.574823 -281.275978)
			(xy 377.594771 -281.229158) (xy 377.621972 -281.186144) (xy 377.65572 -281.14805) (xy 377.695142 -281.115863)
			(xy 377.739216 -281.090417) (xy 377.786802 -281.07237) (xy 377.836666 -281.06219) (xy 377.887518 -281.060141)
			(xy 377.938039 -281.066275) (xy 377.986923 -281.080435) (xy 378.032902 -281.102252) (xy 378.074786 -281.131162)
			(xy 378.11149 -281.166417) (xy 378.142063 -281.207103) (xy 378.165714 -281.252166) (xy 378.18183 -281.30044)
			(xy 378.189994 -281.350674) (xy 378.190506 -281.37612) (xy 378.509034 -281.37612) (xy 378.512994 -281.327066)
			(xy 378.524771 -281.279282) (xy 378.544062 -281.234006) (xy 378.570365 -281.19241) (xy 378.603 -281.155573)
			(xy 378.641121 -281.124448) (xy 378.683742 -281.099841) (xy 378.729758 -281.082389) (xy 378.777977 -281.072545)
			(xy 378.827152 -281.070564) (xy 378.876007 -281.076496) (xy 378.923278 -281.090188) (xy 378.96774 -281.111286)
			(xy 379.008243 -281.139242) (xy 379.043736 -281.173334) (xy 379.073301 -281.212678) (xy 379.096172 -281.256255)
			(xy 379.111756 -281.302936) (xy 379.119651 -281.351513) (xy 379.120146 -281.37612) (xy 379.438657 -281.37612)
			(xy 379.442752 -281.325392) (xy 379.454931 -281.275978) (xy 379.474879 -281.229158) (xy 379.50208 -281.186144)
			(xy 379.535828 -281.14805) (xy 379.57525 -281.115863) (xy 379.619324 -281.090417) (xy 379.66691 -281.07237)
			(xy 379.716774 -281.06219) (xy 379.767626 -281.060141) (xy 379.818147 -281.066275) (xy 379.867031 -281.080435)
			(xy 379.91301 -281.102252) (xy 379.954894 -281.131162) (xy 379.991598 -281.166417) (xy 380.022171 -281.207103)
			(xy 380.045822 -281.252166) (xy 380.061938 -281.30044) (xy 380.070102 -281.350674) (xy 380.070614 -281.37612)
			(xy 380.378711 -281.37612) (xy 380.382806 -281.325392) (xy 380.394985 -281.275978) (xy 380.414933 -281.229158)
			(xy 380.442134 -281.186144) (xy 380.475882 -281.14805) (xy 380.515304 -281.115863) (xy 380.559378 -281.090417)
			(xy 380.606964 -281.07237) (xy 380.656828 -281.06219) (xy 380.70768 -281.060141) (xy 380.758201 -281.066275)
			(xy 380.807085 -281.080435) (xy 380.853064 -281.102252) (xy 380.894948 -281.131162) (xy 380.931652 -281.166417)
			(xy 380.962225 -281.207103) (xy 380.985876 -281.252166) (xy 381.001992 -281.30044) (xy 381.010156 -281.350674)
			(xy 381.010668 -281.37612) (xy 381.328942 -281.37612) (xy 381.332902 -281.327066) (xy 381.344679 -281.279282)
			(xy 381.36397 -281.234006) (xy 381.390273 -281.19241) (xy 381.422908 -281.155573) (xy 381.461029 -281.124448)
			(xy 381.50365 -281.099841) (xy 381.549666 -281.082389) (xy 381.597885 -281.072545) (xy 381.64706 -281.070564)
			(xy 381.695915 -281.076496) (xy 381.743186 -281.090188) (xy 381.787648 -281.111286) (xy 381.828151 -281.139242)
			(xy 381.863644 -281.173334) (xy 381.893209 -281.212678) (xy 381.91608 -281.256255) (xy 381.931664 -281.302936)
			(xy 381.939559 -281.351513) (xy 381.940054 -281.37612) (xy 382.268996 -281.37612) (xy 382.272956 -281.327066)
			(xy 382.284733 -281.279282) (xy 382.304024 -281.234006) (xy 382.330327 -281.19241) (xy 382.362962 -281.155573)
			(xy 382.401083 -281.124448) (xy 382.443704 -281.099841) (xy 382.48972 -281.082389) (xy 382.537939 -281.072545)
			(xy 382.587114 -281.070564) (xy 382.635969 -281.076496) (xy 382.68324 -281.090188) (xy 382.727702 -281.111286)
			(xy 382.768205 -281.139242) (xy 382.803698 -281.173334) (xy 382.833263 -281.212678) (xy 382.856134 -281.256255)
			(xy 382.871718 -281.302936) (xy 382.879613 -281.351513) (xy 382.880108 -281.37612) (xy 383.20905 -281.37612)
			(xy 383.21301 -281.327066) (xy 383.224787 -281.279282) (xy 383.244078 -281.234006) (xy 383.270381 -281.19241)
			(xy 383.303016 -281.155573) (xy 383.341137 -281.124448) (xy 383.383758 -281.099841) (xy 383.429774 -281.082389)
			(xy 383.477993 -281.072545) (xy 383.527168 -281.070564) (xy 383.576023 -281.076496) (xy 383.623294 -281.090188)
			(xy 383.667756 -281.111286) (xy 383.708259 -281.139242) (xy 383.743752 -281.173334) (xy 383.773317 -281.212678)
			(xy 383.796188 -281.256255) (xy 383.811772 -281.302936) (xy 383.819667 -281.351513) (xy 383.820162 -281.37612)
			(xy 384.149104 -281.37612) (xy 384.153064 -281.327066) (xy 384.164841 -281.279282) (xy 384.184132 -281.234006)
			(xy 384.210435 -281.19241) (xy 384.24307 -281.155573) (xy 384.281191 -281.124448) (xy 384.323812 -281.099841)
			(xy 384.369828 -281.082389) (xy 384.418047 -281.072545) (xy 384.467222 -281.070564) (xy 384.516077 -281.076496)
			(xy 384.563348 -281.090188) (xy 384.60781 -281.111286) (xy 384.648313 -281.139242) (xy 384.683806 -281.173334)
			(xy 384.713371 -281.212678) (xy 384.736242 -281.256255) (xy 384.751826 -281.302936) (xy 384.759721 -281.351513)
			(xy 384.760216 -281.37612) (xy 384.759721 -281.400727) (xy 384.751826 -281.449304) (xy 384.736242 -281.495985)
			(xy 384.713371 -281.539562) (xy 384.683806 -281.578906) (xy 384.648313 -281.612998) (xy 384.60781 -281.640954)
			(xy 384.563348 -281.662052) (xy 384.516077 -281.675744) (xy 384.467222 -281.681676) (xy 384.418047 -281.679695)
			(xy 384.369828 -281.669851) (xy 384.323812 -281.652399) (xy 384.281191 -281.627792) (xy 384.24307 -281.596667)
			(xy 384.210435 -281.55983) (xy 384.184132 -281.518234) (xy 384.164841 -281.472958) (xy 384.153064 -281.425174)
			(xy 384.149104 -281.37612) (xy 383.820162 -281.37612) (xy 383.819667 -281.400727) (xy 383.811772 -281.449304)
			(xy 383.796188 -281.495985) (xy 383.773317 -281.539562) (xy 383.743752 -281.578906) (xy 383.708259 -281.612998)
			(xy 383.667756 -281.640954) (xy 383.623294 -281.662052) (xy 383.576023 -281.675744) (xy 383.527168 -281.681676)
			(xy 383.477993 -281.679695) (xy 383.429774 -281.669851) (xy 383.383758 -281.652399) (xy 383.341137 -281.627792)
			(xy 383.303016 -281.596667) (xy 383.270381 -281.55983) (xy 383.244078 -281.518234) (xy 383.224787 -281.472958)
			(xy 383.21301 -281.425174) (xy 383.20905 -281.37612) (xy 382.880108 -281.37612) (xy 382.879613 -281.400727)
			(xy 382.871718 -281.449304) (xy 382.856134 -281.495985) (xy 382.833263 -281.539562) (xy 382.803698 -281.578906)
			(xy 382.768205 -281.612998) (xy 382.727702 -281.640954) (xy 382.68324 -281.662052) (xy 382.635969 -281.675744)
			(xy 382.587114 -281.681676) (xy 382.537939 -281.679695) (xy 382.48972 -281.669851) (xy 382.443704 -281.652399)
			(xy 382.401083 -281.627792) (xy 382.362962 -281.596667) (xy 382.330327 -281.55983) (xy 382.304024 -281.518234)
			(xy 382.284733 -281.472958) (xy 382.272956 -281.425174) (xy 382.268996 -281.37612) (xy 381.940054 -281.37612)
			(xy 381.939559 -281.400727) (xy 381.931664 -281.449304) (xy 381.91608 -281.495985) (xy 381.893209 -281.539562)
			(xy 381.863644 -281.578906) (xy 381.828151 -281.612998) (xy 381.787648 -281.640954) (xy 381.743186 -281.662052)
			(xy 381.695915 -281.675744) (xy 381.64706 -281.681676) (xy 381.597885 -281.679695) (xy 381.549666 -281.669851)
			(xy 381.50365 -281.652399) (xy 381.461029 -281.627792) (xy 381.422908 -281.596667) (xy 381.390273 -281.55983)
			(xy 381.36397 -281.518234) (xy 381.344679 -281.472958) (xy 381.332902 -281.425174) (xy 381.328942 -281.37612)
			(xy 381.010668 -281.37612) (xy 381.010156 -281.401566) (xy 381.001992 -281.4518) (xy 380.985876 -281.500074)
			(xy 380.962225 -281.545137) (xy 380.931652 -281.585823) (xy 380.894948 -281.621078) (xy 380.853064 -281.649988)
			(xy 380.807085 -281.671805) (xy 380.758201 -281.685965) (xy 380.70768 -281.692099) (xy 380.656828 -281.69005)
			(xy 380.606964 -281.67987) (xy 380.559378 -281.661823) (xy 380.515304 -281.636377) (xy 380.475882 -281.60419)
			(xy 380.442134 -281.566096) (xy 380.414933 -281.523082) (xy 380.394985 -281.476262) (xy 380.382806 -281.426848)
			(xy 380.378711 -281.37612) (xy 380.070614 -281.37612) (xy 380.070102 -281.401566) (xy 380.061938 -281.4518)
			(xy 380.045822 -281.500074) (xy 380.022171 -281.545137) (xy 379.991598 -281.585823) (xy 379.954894 -281.621078)
			(xy 379.91301 -281.649988) (xy 379.867031 -281.671805) (xy 379.818147 -281.685965) (xy 379.767626 -281.692099)
			(xy 379.716774 -281.69005) (xy 379.66691 -281.67987) (xy 379.619324 -281.661823) (xy 379.57525 -281.636377)
			(xy 379.535828 -281.60419) (xy 379.50208 -281.566096) (xy 379.474879 -281.523082) (xy 379.454931 -281.476262)
			(xy 379.442752 -281.426848) (xy 379.438657 -281.37612) (xy 379.120146 -281.37612) (xy 379.119651 -281.400727)
			(xy 379.111756 -281.449304) (xy 379.096172 -281.495985) (xy 379.073301 -281.539562) (xy 379.043736 -281.578906)
			(xy 379.008243 -281.612998) (xy 378.96774 -281.640954) (xy 378.923278 -281.662052) (xy 378.876007 -281.675744)
			(xy 378.827152 -281.681676) (xy 378.777977 -281.679695) (xy 378.729758 -281.669851) (xy 378.683742 -281.652399)
			(xy 378.641121 -281.627792) (xy 378.603 -281.596667) (xy 378.570365 -281.55983) (xy 378.544062 -281.518234)
			(xy 378.524771 -281.472958) (xy 378.512994 -281.425174) (xy 378.509034 -281.37612) (xy 378.190506 -281.37612)
			(xy 378.189994 -281.401566) (xy 378.18183 -281.4518) (xy 378.165714 -281.500074) (xy 378.142063 -281.545137)
			(xy 378.11149 -281.585823) (xy 378.074786 -281.621078) (xy 378.032902 -281.649988) (xy 377.986923 -281.671805)
			(xy 377.938039 -281.685965) (xy 377.887518 -281.692099) (xy 377.836666 -281.69005) (xy 377.786802 -281.67987)
			(xy 377.739216 -281.661823) (xy 377.695142 -281.636377) (xy 377.65572 -281.60419) (xy 377.621972 -281.566096)
			(xy 377.594771 -281.523082) (xy 377.574823 -281.476262) (xy 377.562644 -281.426848) (xy 377.558549 -281.37612)
			(xy 377.240038 -281.37612) (xy 377.239543 -281.400727) (xy 377.231648 -281.449304) (xy 377.216064 -281.495985)
			(xy 377.193193 -281.539562) (xy 377.163628 -281.578906) (xy 377.128135 -281.612998) (xy 377.087632 -281.640954)
			(xy 377.04317 -281.662052) (xy 376.995899 -281.675744) (xy 376.947044 -281.681676) (xy 376.897869 -281.679695)
			(xy 376.84965 -281.669851) (xy 376.803634 -281.652399) (xy 376.761013 -281.627792) (xy 376.722892 -281.596667)
			(xy 376.690257 -281.55983) (xy 376.663954 -281.518234) (xy 376.644663 -281.472958) (xy 376.632886 -281.425174)
			(xy 376.628926 -281.37612) (xy 376.310652 -281.37612) (xy 376.31014 -281.401566) (xy 376.301976 -281.4518)
			(xy 376.28586 -281.500074) (xy 376.262209 -281.545137) (xy 376.231636 -281.585823) (xy 376.194932 -281.621078)
			(xy 376.153048 -281.649988) (xy 376.107069 -281.671805) (xy 376.058185 -281.685965) (xy 376.007664 -281.692099)
			(xy 375.956812 -281.69005) (xy 375.906948 -281.67987) (xy 375.859362 -281.661823) (xy 375.815288 -281.636377)
			(xy 375.775866 -281.60419) (xy 375.742118 -281.566096) (xy 375.714917 -281.523082) (xy 375.694969 -281.476262)
			(xy 375.68279 -281.426848) (xy 375.678695 -281.37612) (xy 375.561098 -281.37612) (xy 375.561098 -281.60218)
			(xy 375.561166 -281.606188) (xy 375.562441 -281.614102) (xy 375.563638 -281.617928) (xy 375.566432 -281.624786)
			(xy 375.567702 -281.627072) (xy 375.588003 -281.663514) (xy 375.623815 -281.738863) (xy 375.653975 -281.816646)
			(xy 375.666508 -281.856434) (xy 375.667016 -281.857704) (xy 375.667524 -281.859482) (xy 375.669556 -281.866086)
			(xy 375.67235 -281.870912) (xy 375.67997 -281.880564) (xy 375.711974 -281.912568) (xy 375.719594 -281.918918)
			(xy 375.740081 -281.93446) (xy 375.776442 -281.970821) (xy 375.791984 -281.991308) (xy 375.798334 -281.998928)
			(xy 375.810526 -282.01112) (xy 375.816368 -282.017401) (xy 375.823778 -282.032857) (xy 375.825004 -282.041346)
			(xy 375.825766 -282.04922) (xy 375.829322 -282.057094) (xy 375.841123 -282.086871) (xy 375.854293 -282.149546)
			(xy 375.855484 -282.181554) (xy 375.855484 -282.185364) (xy 375.855473 -282.186126) (xy 376.148595 -282.186126)
			(xy 376.15269 -282.135398) (xy 376.164869 -282.085984) (xy 376.184817 -282.039164) (xy 376.212018 -281.99615)
			(xy 376.245766 -281.958056) (xy 376.285188 -281.925869) (xy 376.329262 -281.900423) (xy 376.376848 -281.882376)
			(xy 376.426712 -281.872196) (xy 376.477564 -281.870147) (xy 376.528085 -281.876281) (xy 376.576969 -281.890441)
			(xy 376.622948 -281.912258) (xy 376.664832 -281.941168) (xy 376.701536 -281.976423) (xy 376.732109 -282.017109)
			(xy 376.75576 -282.062172) (xy 376.771876 -282.110446) (xy 376.78004 -282.16068) (xy 376.780552 -282.186126)
			(xy 377.088649 -282.186126) (xy 377.092744 -282.135398) (xy 377.104923 -282.085984) (xy 377.124871 -282.039164)
			(xy 377.152072 -281.99615) (xy 377.18582 -281.958056) (xy 377.225242 -281.925869) (xy 377.269316 -281.900423)
			(xy 377.316902 -281.882376) (xy 377.366766 -281.872196) (xy 377.417618 -281.870147) (xy 377.468139 -281.876281)
			(xy 377.517023 -281.890441) (xy 377.563002 -281.912258) (xy 377.604886 -281.941168) (xy 377.64159 -281.976423)
			(xy 377.672163 -282.017109) (xy 377.695814 -282.062172) (xy 377.71193 -282.110446) (xy 377.720094 -282.16068)
			(xy 377.720606 -282.186126) (xy 378.039134 -282.186126) (xy 378.043094 -282.137072) (xy 378.054871 -282.089288)
			(xy 378.074162 -282.044012) (xy 378.100465 -282.002416) (xy 378.1331 -281.965579) (xy 378.171221 -281.934454)
			(xy 378.213842 -281.909847) (xy 378.259858 -281.892395) (xy 378.308077 -281.882551) (xy 378.357252 -281.88057)
			(xy 378.406107 -281.886502) (xy 378.453378 -281.900194) (xy 378.49784 -281.921292) (xy 378.538343 -281.949248)
			(xy 378.573836 -281.98334) (xy 378.603401 -282.022684) (xy 378.626272 -282.066261) (xy 378.641856 -282.112942)
			(xy 378.649751 -282.161519) (xy 378.650246 -282.186126) (xy 378.968503 -282.186126) (xy 378.972598 -282.135398)
			(xy 378.984777 -282.085984) (xy 379.004725 -282.039164) (xy 379.031926 -281.99615) (xy 379.065674 -281.958056)
			(xy 379.105096 -281.925869) (xy 379.14917 -281.900423) (xy 379.196756 -281.882376) (xy 379.24662 -281.872196)
			(xy 379.297472 -281.870147) (xy 379.347993 -281.876281) (xy 379.396877 -281.890441) (xy 379.442856 -281.912258)
			(xy 379.48474 -281.941168) (xy 379.521444 -281.976423) (xy 379.552017 -282.017109) (xy 379.575668 -282.062172)
			(xy 379.591784 -282.110446) (xy 379.599948 -282.16068) (xy 379.60046 -282.186126) (xy 379.918988 -282.186126)
			(xy 379.922948 -282.137072) (xy 379.934725 -282.089288) (xy 379.954016 -282.044012) (xy 379.980319 -282.002416)
			(xy 380.012954 -281.965579) (xy 380.051075 -281.934454) (xy 380.093696 -281.909847) (xy 380.139712 -281.892395)
			(xy 380.187931 -281.882551) (xy 380.237106 -281.88057) (xy 380.285961 -281.886502) (xy 380.333232 -281.900194)
			(xy 380.377694 -281.921292) (xy 380.418197 -281.949248) (xy 380.45369 -281.98334) (xy 380.483255 -282.022684)
			(xy 380.506126 -282.066261) (xy 380.52171 -282.112942) (xy 380.529605 -282.161519) (xy 380.5301 -282.186126)
			(xy 380.848611 -282.186126) (xy 380.852706 -282.135398) (xy 380.864885 -282.085984) (xy 380.884833 -282.039164)
			(xy 380.912034 -281.99615) (xy 380.945782 -281.958056) (xy 380.985204 -281.925869) (xy 381.029278 -281.900423)
			(xy 381.076864 -281.882376) (xy 381.126728 -281.872196) (xy 381.17758 -281.870147) (xy 381.228101 -281.876281)
			(xy 381.276985 -281.890441) (xy 381.322964 -281.912258) (xy 381.364848 -281.941168) (xy 381.401552 -281.976423)
			(xy 381.432125 -282.017109) (xy 381.455776 -282.062172) (xy 381.471892 -282.110446) (xy 381.480056 -282.16068)
			(xy 381.480568 -282.186126) (xy 381.799096 -282.186126) (xy 381.803056 -282.137072) (xy 381.814833 -282.089288)
			(xy 381.834124 -282.044012) (xy 381.860427 -282.002416) (xy 381.893062 -281.965579) (xy 381.931183 -281.934454)
			(xy 381.973804 -281.909847) (xy 382.01982 -281.892395) (xy 382.068039 -281.882551) (xy 382.117214 -281.88057)
			(xy 382.166069 -281.886502) (xy 382.21334 -281.900194) (xy 382.257802 -281.921292) (xy 382.298305 -281.949248)
			(xy 382.333798 -281.98334) (xy 382.363363 -282.022684) (xy 382.386234 -282.066261) (xy 382.401818 -282.112942)
			(xy 382.409713 -282.161519) (xy 382.410208 -282.186126) (xy 382.738896 -282.186126) (xy 382.742856 -282.137072)
			(xy 382.754633 -282.089288) (xy 382.773924 -282.044012) (xy 382.800227 -282.002416) (xy 382.832862 -281.965579)
			(xy 382.870983 -281.934454) (xy 382.913604 -281.909847) (xy 382.95962 -281.892395) (xy 383.007839 -281.882551)
			(xy 383.057014 -281.88057) (xy 383.105869 -281.886502) (xy 383.15314 -281.900194) (xy 383.197602 -281.921292)
			(xy 383.238105 -281.949248) (xy 383.273598 -281.98334) (xy 383.303163 -282.022684) (xy 383.326034 -282.066261)
			(xy 383.341618 -282.112942) (xy 383.349513 -282.161519) (xy 383.350008 -282.186126) (xy 383.67895 -282.186126)
			(xy 383.68291 -282.137072) (xy 383.694687 -282.089288) (xy 383.713978 -282.044012) (xy 383.740281 -282.002416)
			(xy 383.772916 -281.965579) (xy 383.811037 -281.934454) (xy 383.853658 -281.909847) (xy 383.899674 -281.892395)
			(xy 383.947893 -281.882551) (xy 383.997068 -281.88057) (xy 384.045923 -281.886502) (xy 384.093194 -281.900194)
			(xy 384.137656 -281.921292) (xy 384.178159 -281.949248) (xy 384.213652 -281.98334) (xy 384.243217 -282.022684)
			(xy 384.266088 -282.066261) (xy 384.281672 -282.112942) (xy 384.289567 -282.161519) (xy 384.290062 -282.186126)
			(xy 384.289567 -282.210733) (xy 384.281672 -282.25931) (xy 384.266088 -282.305991) (xy 384.243217 -282.349568)
			(xy 384.213652 -282.388912) (xy 384.178159 -282.423004) (xy 384.137656 -282.45096) (xy 384.093194 -282.472058)
			(xy 384.045923 -282.48575) (xy 383.997068 -282.491682) (xy 383.947893 -282.489701) (xy 383.899674 -282.479857)
			(xy 383.853658 -282.462405) (xy 383.811037 -282.437798) (xy 383.772916 -282.406673) (xy 383.740281 -282.369836)
			(xy 383.713978 -282.32824) (xy 383.694687 -282.282964) (xy 383.68291 -282.23518) (xy 383.67895 -282.186126)
			(xy 383.350008 -282.186126) (xy 383.349513 -282.210733) (xy 383.341618 -282.25931) (xy 383.326034 -282.305991)
			(xy 383.303163 -282.349568) (xy 383.273598 -282.388912) (xy 383.238105 -282.423004) (xy 383.197602 -282.45096)
			(xy 383.15314 -282.472058) (xy 383.105869 -282.48575) (xy 383.057014 -282.491682) (xy 383.007839 -282.489701)
			(xy 382.95962 -282.479857) (xy 382.913604 -282.462405) (xy 382.870983 -282.437798) (xy 382.832862 -282.406673)
			(xy 382.800227 -282.369836) (xy 382.773924 -282.32824) (xy 382.754633 -282.282964) (xy 382.742856 -282.23518)
			(xy 382.738896 -282.186126) (xy 382.410208 -282.186126) (xy 382.409713 -282.210733) (xy 382.401818 -282.25931)
			(xy 382.386234 -282.305991) (xy 382.363363 -282.349568) (xy 382.333798 -282.388912) (xy 382.298305 -282.423004)
			(xy 382.257802 -282.45096) (xy 382.21334 -282.472058) (xy 382.166069 -282.48575) (xy 382.117214 -282.491682)
			(xy 382.068039 -282.489701) (xy 382.01982 -282.479857) (xy 381.973804 -282.462405) (xy 381.931183 -282.437798)
			(xy 381.893062 -282.406673) (xy 381.860427 -282.369836) (xy 381.834124 -282.32824) (xy 381.814833 -282.282964)
			(xy 381.803056 -282.23518) (xy 381.799096 -282.186126) (xy 381.480568 -282.186126) (xy 381.480056 -282.211572)
			(xy 381.471892 -282.261806) (xy 381.455776 -282.31008) (xy 381.432125 -282.355143) (xy 381.401552 -282.395829)
			(xy 381.364848 -282.431084) (xy 381.322964 -282.459994) (xy 381.276985 -282.481811) (xy 381.228101 -282.495971)
			(xy 381.17758 -282.502105) (xy 381.126728 -282.500056) (xy 381.076864 -282.489876) (xy 381.029278 -282.471829)
			(xy 380.985204 -282.446383) (xy 380.945782 -282.414196) (xy 380.912034 -282.376102) (xy 380.884833 -282.333088)
			(xy 380.864885 -282.286268) (xy 380.852706 -282.236854) (xy 380.848611 -282.186126) (xy 380.5301 -282.186126)
			(xy 380.529605 -282.210733) (xy 380.52171 -282.25931) (xy 380.506126 -282.305991) (xy 380.483255 -282.349568)
			(xy 380.45369 -282.388912) (xy 380.418197 -282.423004) (xy 380.377694 -282.45096) (xy 380.333232 -282.472058)
			(xy 380.285961 -282.48575) (xy 380.237106 -282.491682) (xy 380.187931 -282.489701) (xy 380.139712 -282.479857)
			(xy 380.093696 -282.462405) (xy 380.051075 -282.437798) (xy 380.012954 -282.406673) (xy 379.980319 -282.369836)
			(xy 379.954016 -282.32824) (xy 379.934725 -282.282964) (xy 379.922948 -282.23518) (xy 379.918988 -282.186126)
			(xy 379.60046 -282.186126) (xy 379.599948 -282.211572) (xy 379.591784 -282.261806) (xy 379.575668 -282.31008)
			(xy 379.552017 -282.355143) (xy 379.521444 -282.395829) (xy 379.48474 -282.431084) (xy 379.442856 -282.459994)
			(xy 379.396877 -282.481811) (xy 379.347993 -282.495971) (xy 379.297472 -282.502105) (xy 379.24662 -282.500056)
			(xy 379.196756 -282.489876) (xy 379.14917 -282.471829) (xy 379.105096 -282.446383) (xy 379.065674 -282.414196)
			(xy 379.031926 -282.376102) (xy 379.004725 -282.333088) (xy 378.984777 -282.286268) (xy 378.972598 -282.236854)
			(xy 378.968503 -282.186126) (xy 378.650246 -282.186126) (xy 378.649751 -282.210733) (xy 378.641856 -282.25931)
			(xy 378.626272 -282.305991) (xy 378.603401 -282.349568) (xy 378.573836 -282.388912) (xy 378.538343 -282.423004)
			(xy 378.49784 -282.45096) (xy 378.453378 -282.472058) (xy 378.406107 -282.48575) (xy 378.357252 -282.491682)
			(xy 378.308077 -282.489701) (xy 378.259858 -282.479857) (xy 378.213842 -282.462405) (xy 378.171221 -282.437798)
			(xy 378.1331 -282.406673) (xy 378.100465 -282.369836) (xy 378.074162 -282.32824) (xy 378.054871 -282.282964)
			(xy 378.043094 -282.23518) (xy 378.039134 -282.186126) (xy 377.720606 -282.186126) (xy 377.720094 -282.211572)
			(xy 377.71193 -282.261806) (xy 377.695814 -282.31008) (xy 377.672163 -282.355143) (xy 377.64159 -282.395829)
			(xy 377.604886 -282.431084) (xy 377.563002 -282.459994) (xy 377.517023 -282.481811) (xy 377.468139 -282.495971)
			(xy 377.417618 -282.502105) (xy 377.366766 -282.500056) (xy 377.316902 -282.489876) (xy 377.269316 -282.471829)
			(xy 377.225242 -282.446383) (xy 377.18582 -282.414196) (xy 377.152072 -282.376102) (xy 377.124871 -282.333088)
			(xy 377.104923 -282.286268) (xy 377.092744 -282.236854) (xy 377.088649 -282.186126) (xy 376.780552 -282.186126)
			(xy 376.78004 -282.211572) (xy 376.771876 -282.261806) (xy 376.75576 -282.31008) (xy 376.732109 -282.355143)
			(xy 376.701536 -282.395829) (xy 376.664832 -282.431084) (xy 376.622948 -282.459994) (xy 376.576969 -282.481811)
			(xy 376.528085 -282.495971) (xy 376.477564 -282.502105) (xy 376.426712 -282.500056) (xy 376.376848 -282.489876)
			(xy 376.329262 -282.471829) (xy 376.285188 -282.446383) (xy 376.245766 -282.414196) (xy 376.212018 -282.376102)
			(xy 376.184817 -282.333088) (xy 376.164869 -282.286268) (xy 376.15269 -282.236854) (xy 376.148595 -282.186126)
			(xy 375.855473 -282.186126) (xy 375.85517 -282.20759) (xy 375.849319 -282.251655) (xy 375.837637 -282.294543)
			(xy 375.829322 -282.315158) (xy 375.829322 -282.315412) (xy 375.825258 -282.33497) (xy 375.825258 -282.335478)
			(xy 375.824722 -282.345316) (xy 375.81714 -282.363481) (xy 375.810526 -282.370784) (xy 375.675906 -282.505404)
			(xy 375.668286 -282.515056) (xy 375.665492 -282.519882) (xy 375.66346 -282.525978) (xy 375.66346 -282.526232)
			(xy 375.657806 -282.543869) (xy 375.645485 -282.578801) (xy 375.638822 -282.596082) (xy 375.625326 -282.629879)
			(xy 375.594569 -282.695844) (xy 375.577354 -282.727908) (xy 375.574306 -282.733496) (xy 375.571258 -282.745434)
			(xy 375.571258 -282.996132) (xy 375.678695 -282.996132) (xy 375.68279 -282.945404) (xy 375.694969 -282.89599)
			(xy 375.714917 -282.84917) (xy 375.742118 -282.806156) (xy 375.775866 -282.768062) (xy 375.815288 -282.735875)
			(xy 375.859362 -282.710429) (xy 375.906948 -282.692382) (xy 375.956812 -282.682202) (xy 376.007664 -282.680153)
			(xy 376.058185 -282.686287) (xy 376.107069 -282.700447) (xy 376.153048 -282.722264) (xy 376.194932 -282.751174)
			(xy 376.231636 -282.786429) (xy 376.262209 -282.827115) (xy 376.28586 -282.872178) (xy 376.301976 -282.920452)
			(xy 376.31014 -282.970686) (xy 376.310652 -282.996132) (xy 376.628926 -282.996132) (xy 376.632886 -282.947078)
			(xy 376.644663 -282.899294) (xy 376.663954 -282.854018) (xy 376.690257 -282.812422) (xy 376.722892 -282.775585)
			(xy 376.761013 -282.74446) (xy 376.803634 -282.719853) (xy 376.84965 -282.702401) (xy 376.897869 -282.692557)
			(xy 376.947044 -282.690576) (xy 376.995899 -282.696508) (xy 377.04317 -282.7102) (xy 377.087632 -282.731298)
			(xy 377.128135 -282.759254) (xy 377.163628 -282.793346) (xy 377.193193 -282.83269) (xy 377.216064 -282.876267)
			(xy 377.231648 -282.922948) (xy 377.239543 -282.971525) (xy 377.240038 -282.996132) (xy 377.558549 -282.996132)
			(xy 377.562644 -282.945404) (xy 377.574823 -282.89599) (xy 377.594771 -282.84917) (xy 377.621972 -282.806156)
			(xy 377.65572 -282.768062) (xy 377.695142 -282.735875) (xy 377.739216 -282.710429) (xy 377.786802 -282.692382)
			(xy 377.836666 -282.682202) (xy 377.887518 -282.680153) (xy 377.938039 -282.686287) (xy 377.986923 -282.700447)
			(xy 378.032902 -282.722264) (xy 378.074786 -282.751174) (xy 378.11149 -282.786429) (xy 378.142063 -282.827115)
			(xy 378.165714 -282.872178) (xy 378.18183 -282.920452) (xy 378.189994 -282.970686) (xy 378.190506 -282.996132)
			(xy 379.438657 -282.996132) (xy 379.442752 -282.945404) (xy 379.454931 -282.89599) (xy 379.474879 -282.84917)
			(xy 379.50208 -282.806156) (xy 379.535828 -282.768062) (xy 379.57525 -282.735875) (xy 379.619324 -282.710429)
			(xy 379.66691 -282.692382) (xy 379.716774 -282.682202) (xy 379.767626 -282.680153) (xy 379.818147 -282.686287)
			(xy 379.867031 -282.700447) (xy 379.91301 -282.722264) (xy 379.954894 -282.751174) (xy 379.991598 -282.786429)
			(xy 380.022171 -282.827115) (xy 380.045822 -282.872178) (xy 380.061938 -282.920452) (xy 380.070102 -282.970686)
			(xy 380.070614 -282.996132) (xy 380.378711 -282.996132) (xy 380.382806 -282.945404) (xy 380.394985 -282.89599)
			(xy 380.414933 -282.84917) (xy 380.442134 -282.806156) (xy 380.475882 -282.768062) (xy 380.515304 -282.735875)
			(xy 380.559378 -282.710429) (xy 380.606964 -282.692382) (xy 380.656828 -282.682202) (xy 380.70768 -282.680153)
			(xy 380.758201 -282.686287) (xy 380.807085 -282.700447) (xy 380.853064 -282.722264) (xy 380.894948 -282.751174)
			(xy 380.931652 -282.786429) (xy 380.962225 -282.827115) (xy 380.985876 -282.872178) (xy 381.001992 -282.920452)
			(xy 381.010156 -282.970686) (xy 381.010668 -282.996132) (xy 381.328942 -282.996132) (xy 381.332902 -282.947078)
			(xy 381.344679 -282.899294) (xy 381.36397 -282.854018) (xy 381.390273 -282.812422) (xy 381.422908 -282.775585)
			(xy 381.461029 -282.74446) (xy 381.50365 -282.719853) (xy 381.549666 -282.702401) (xy 381.597885 -282.692557)
			(xy 381.64706 -282.690576) (xy 381.695915 -282.696508) (xy 381.743186 -282.7102) (xy 381.787648 -282.731298)
			(xy 381.828151 -282.759254) (xy 381.863644 -282.793346) (xy 381.893209 -282.83269) (xy 381.91608 -282.876267)
			(xy 381.931664 -282.922948) (xy 381.939559 -282.971525) (xy 381.940054 -282.996132) (xy 382.268996 -282.996132)
			(xy 382.272956 -282.947078) (xy 382.284733 -282.899294) (xy 382.304024 -282.854018) (xy 382.330327 -282.812422)
			(xy 382.362962 -282.775585) (xy 382.401083 -282.74446) (xy 382.443704 -282.719853) (xy 382.48972 -282.702401)
			(xy 382.537939 -282.692557) (xy 382.587114 -282.690576) (xy 382.635969 -282.696508) (xy 382.68324 -282.7102)
			(xy 382.727702 -282.731298) (xy 382.768205 -282.759254) (xy 382.803698 -282.793346) (xy 382.833263 -282.83269)
			(xy 382.856134 -282.876267) (xy 382.871718 -282.922948) (xy 382.879613 -282.971525) (xy 382.880108 -282.996132)
			(xy 383.20905 -282.996132) (xy 383.21301 -282.947078) (xy 383.224787 -282.899294) (xy 383.244078 -282.854018)
			(xy 383.270381 -282.812422) (xy 383.303016 -282.775585) (xy 383.341137 -282.74446) (xy 383.383758 -282.719853)
			(xy 383.429774 -282.702401) (xy 383.477993 -282.692557) (xy 383.527168 -282.690576) (xy 383.576023 -282.696508)
			(xy 383.623294 -282.7102) (xy 383.667756 -282.731298) (xy 383.708259 -282.759254) (xy 383.743752 -282.793346)
			(xy 383.773317 -282.83269) (xy 383.796188 -282.876267) (xy 383.811772 -282.922948) (xy 383.819667 -282.971525)
			(xy 383.820162 -282.996132) (xy 384.149104 -282.996132) (xy 384.153064 -282.947078) (xy 384.164841 -282.899294)
			(xy 384.184132 -282.854018) (xy 384.210435 -282.812422) (xy 384.24307 -282.775585) (xy 384.281191 -282.74446)
			(xy 384.323812 -282.719853) (xy 384.369828 -282.702401) (xy 384.418047 -282.692557) (xy 384.467222 -282.690576)
			(xy 384.516077 -282.696508) (xy 384.563348 -282.7102) (xy 384.60781 -282.731298) (xy 384.648313 -282.759254)
			(xy 384.683806 -282.793346) (xy 384.713371 -282.83269) (xy 384.736242 -282.876267) (xy 384.751826 -282.922948)
			(xy 384.759721 -282.971525) (xy 384.760216 -282.996132) (xy 384.759721 -283.020739) (xy 384.751826 -283.069316)
			(xy 384.736242 -283.115997) (xy 384.713371 -283.159574) (xy 384.683806 -283.198918) (xy 384.648313 -283.23301)
			(xy 384.60781 -283.260966) (xy 384.563348 -283.282064) (xy 384.516077 -283.295756) (xy 384.467222 -283.301688)
			(xy 384.418047 -283.299707) (xy 384.369828 -283.289863) (xy 384.323812 -283.272411) (xy 384.281191 -283.247804)
			(xy 384.24307 -283.216679) (xy 384.210435 -283.179842) (xy 384.184132 -283.138246) (xy 384.164841 -283.09297)
			(xy 384.153064 -283.045186) (xy 384.149104 -282.996132) (xy 383.820162 -282.996132) (xy 383.819667 -283.020739)
			(xy 383.811772 -283.069316) (xy 383.796188 -283.115997) (xy 383.773317 -283.159574) (xy 383.743752 -283.198918)
			(xy 383.708259 -283.23301) (xy 383.667756 -283.260966) (xy 383.623294 -283.282064) (xy 383.576023 -283.295756)
			(xy 383.527168 -283.301688) (xy 383.477993 -283.299707) (xy 383.429774 -283.289863) (xy 383.383758 -283.272411)
			(xy 383.341137 -283.247804) (xy 383.303016 -283.216679) (xy 383.270381 -283.179842) (xy 383.244078 -283.138246)
			(xy 383.224787 -283.09297) (xy 383.21301 -283.045186) (xy 383.20905 -282.996132) (xy 382.880108 -282.996132)
			(xy 382.879613 -283.020739) (xy 382.871718 -283.069316) (xy 382.856134 -283.115997) (xy 382.833263 -283.159574)
			(xy 382.803698 -283.198918) (xy 382.768205 -283.23301) (xy 382.727702 -283.260966) (xy 382.68324 -283.282064)
			(xy 382.635969 -283.295756) (xy 382.587114 -283.301688) (xy 382.537939 -283.299707) (xy 382.48972 -283.289863)
			(xy 382.443704 -283.272411) (xy 382.401083 -283.247804) (xy 382.362962 -283.216679) (xy 382.330327 -283.179842)
			(xy 382.304024 -283.138246) (xy 382.284733 -283.09297) (xy 382.272956 -283.045186) (xy 382.268996 -282.996132)
			(xy 381.940054 -282.996132) (xy 381.939559 -283.020739) (xy 381.931664 -283.069316) (xy 381.91608 -283.115997)
			(xy 381.893209 -283.159574) (xy 381.863644 -283.198918) (xy 381.828151 -283.23301) (xy 381.787648 -283.260966)
			(xy 381.743186 -283.282064) (xy 381.695915 -283.295756) (xy 381.64706 -283.301688) (xy 381.597885 -283.299707)
			(xy 381.549666 -283.289863) (xy 381.50365 -283.272411) (xy 381.461029 -283.247804) (xy 381.422908 -283.216679)
			(xy 381.390273 -283.179842) (xy 381.36397 -283.138246) (xy 381.344679 -283.09297) (xy 381.332902 -283.045186)
			(xy 381.328942 -282.996132) (xy 381.010668 -282.996132) (xy 381.010156 -283.021578) (xy 381.001992 -283.071812)
			(xy 380.985876 -283.120086) (xy 380.962225 -283.165149) (xy 380.931652 -283.205835) (xy 380.894948 -283.24109)
			(xy 380.853064 -283.27) (xy 380.807085 -283.291817) (xy 380.758201 -283.305977) (xy 380.70768 -283.312111)
			(xy 380.656828 -283.310062) (xy 380.606964 -283.299882) (xy 380.559378 -283.281835) (xy 380.515304 -283.256389)
			(xy 380.475882 -283.224202) (xy 380.442134 -283.186108) (xy 380.414933 -283.143094) (xy 380.394985 -283.096274)
			(xy 380.382806 -283.04686) (xy 380.378711 -282.996132) (xy 380.070614 -282.996132) (xy 380.070102 -283.021578)
			(xy 380.061938 -283.071812) (xy 380.045822 -283.120086) (xy 380.022171 -283.165149) (xy 379.991598 -283.205835)
			(xy 379.954894 -283.24109) (xy 379.91301 -283.27) (xy 379.867031 -283.291817) (xy 379.818147 -283.305977)
			(xy 379.767626 -283.312111) (xy 379.716774 -283.310062) (xy 379.66691 -283.299882) (xy 379.619324 -283.281835)
			(xy 379.57525 -283.256389) (xy 379.535828 -283.224202) (xy 379.50208 -283.186108) (xy 379.474879 -283.143094)
			(xy 379.454931 -283.096274) (xy 379.442752 -283.04686) (xy 379.438657 -282.996132) (xy 378.190506 -282.996132)
			(xy 378.189994 -283.021578) (xy 378.18183 -283.071812) (xy 378.165714 -283.120086) (xy 378.142063 -283.165149)
			(xy 378.11149 -283.205835) (xy 378.074786 -283.24109) (xy 378.032902 -283.27) (xy 377.986923 -283.291817)
			(xy 377.938039 -283.305977) (xy 377.887518 -283.312111) (xy 377.836666 -283.310062) (xy 377.786802 -283.299882)
			(xy 377.739216 -283.281835) (xy 377.695142 -283.256389) (xy 377.65572 -283.224202) (xy 377.621972 -283.186108)
			(xy 377.594771 -283.143094) (xy 377.574823 -283.096274) (xy 377.562644 -283.04686) (xy 377.558549 -282.996132)
			(xy 377.240038 -282.996132) (xy 377.239543 -283.020739) (xy 377.231648 -283.069316) (xy 377.216064 -283.115997)
			(xy 377.193193 -283.159574) (xy 377.163628 -283.198918) (xy 377.128135 -283.23301) (xy 377.087632 -283.260966)
			(xy 377.04317 -283.282064) (xy 376.995899 -283.295756) (xy 376.947044 -283.301688) (xy 376.897869 -283.299707)
			(xy 376.84965 -283.289863) (xy 376.803634 -283.272411) (xy 376.761013 -283.247804) (xy 376.722892 -283.216679)
			(xy 376.690257 -283.179842) (xy 376.663954 -283.138246) (xy 376.644663 -283.09297) (xy 376.632886 -283.045186)
			(xy 376.628926 -282.996132) (xy 376.310652 -282.996132) (xy 376.31014 -283.021578) (xy 376.301976 -283.071812)
			(xy 376.28586 -283.120086) (xy 376.262209 -283.165149) (xy 376.231636 -283.205835) (xy 376.194932 -283.24109)
			(xy 376.153048 -283.27) (xy 376.107069 -283.291817) (xy 376.058185 -283.305977) (xy 376.007664 -283.312111)
			(xy 375.956812 -283.310062) (xy 375.906948 -283.299882) (xy 375.859362 -283.281835) (xy 375.815288 -283.256389)
			(xy 375.775866 -283.224202) (xy 375.742118 -283.186108) (xy 375.714917 -283.143094) (xy 375.694969 -283.096274)
			(xy 375.68279 -283.04686) (xy 375.678695 -282.996132) (xy 375.571258 -282.996132) (xy 375.571258 -283.24683)
			(xy 375.574306 -283.258768) (xy 375.577354 -283.264356) (xy 375.59864 -283.304225) (xy 375.635513 -283.386748)
			(xy 375.651014 -283.429202) (xy 375.668794 -283.483812) (xy 375.670572 -283.489908) (xy 375.67362 -283.495242)
			(xy 375.681494 -283.505148) (xy 375.810526 -283.63418) (xy 375.817243 -283.641417) (xy 375.824846 -283.659622)
			(xy 375.825258 -283.669486) (xy 375.825258 -283.750512) (xy 375.82602 -283.754576) (xy 375.827992 -283.76731)
			(xy 375.830027 -283.792999) (xy 375.830084 -283.805884) (xy 375.830084 -283.806138) (xy 376.148595 -283.806138)
			(xy 376.15269 -283.75541) (xy 376.164869 -283.705996) (xy 376.184817 -283.659176) (xy 376.212018 -283.616162)
			(xy 376.245766 -283.578068) (xy 376.285188 -283.545881) (xy 376.329262 -283.520435) (xy 376.376848 -283.502388)
			(xy 376.426712 -283.492208) (xy 376.477564 -283.490159) (xy 376.528085 -283.496293) (xy 376.576969 -283.510453)
			(xy 376.622948 -283.53227) (xy 376.664832 -283.56118) (xy 376.701536 -283.596435) (xy 376.732109 -283.637121)
			(xy 376.75576 -283.682184) (xy 376.771876 -283.730458) (xy 376.78004 -283.780692) (xy 376.780552 -283.806138)
			(xy 377.088649 -283.806138) (xy 377.092744 -283.75541) (xy 377.104923 -283.705996) (xy 377.124871 -283.659176)
			(xy 377.152072 -283.616162) (xy 377.18582 -283.578068) (xy 377.225242 -283.545881) (xy 377.269316 -283.520435)
			(xy 377.316902 -283.502388) (xy 377.366766 -283.492208) (xy 377.417618 -283.490159) (xy 377.468139 -283.496293)
			(xy 377.517023 -283.510453) (xy 377.563002 -283.53227) (xy 377.604886 -283.56118) (xy 377.64159 -283.596435)
			(xy 377.672163 -283.637121) (xy 377.695814 -283.682184) (xy 377.71193 -283.730458) (xy 377.720094 -283.780692)
			(xy 377.720606 -283.806138) (xy 378.039134 -283.806138) (xy 378.043094 -283.757084) (xy 378.054871 -283.7093)
			(xy 378.074162 -283.664024) (xy 378.100465 -283.622428) (xy 378.1331 -283.585591) (xy 378.171221 -283.554466)
			(xy 378.213842 -283.529859) (xy 378.259858 -283.512407) (xy 378.308077 -283.502563) (xy 378.357252 -283.500582)
			(xy 378.406107 -283.506514) (xy 378.453378 -283.520206) (xy 378.49784 -283.541304) (xy 378.538343 -283.56926)
			(xy 378.573836 -283.603352) (xy 378.603401 -283.642696) (xy 378.626272 -283.686273) (xy 378.641856 -283.732954)
			(xy 378.649751 -283.781531) (xy 378.650246 -283.806138) (xy 378.968503 -283.806138) (xy 378.972598 -283.75541)
			(xy 378.984777 -283.705996) (xy 379.004725 -283.659176) (xy 379.031926 -283.616162) (xy 379.065674 -283.578068)
			(xy 379.105096 -283.545881) (xy 379.14917 -283.520435) (xy 379.196756 -283.502388) (xy 379.24662 -283.492208)
			(xy 379.297472 -283.490159) (xy 379.347993 -283.496293) (xy 379.396877 -283.510453) (xy 379.442856 -283.53227)
			(xy 379.48474 -283.56118) (xy 379.521444 -283.596435) (xy 379.552017 -283.637121) (xy 379.575668 -283.682184)
			(xy 379.591784 -283.730458) (xy 379.599948 -283.780692) (xy 379.60046 -283.806138) (xy 379.918988 -283.806138)
			(xy 379.922948 -283.757084) (xy 379.934725 -283.7093) (xy 379.954016 -283.664024) (xy 379.980319 -283.622428)
			(xy 380.012954 -283.585591) (xy 380.051075 -283.554466) (xy 380.093696 -283.529859) (xy 380.139712 -283.512407)
			(xy 380.187931 -283.502563) (xy 380.237106 -283.500582) (xy 380.285961 -283.506514) (xy 380.333232 -283.520206)
			(xy 380.377694 -283.541304) (xy 380.418197 -283.56926) (xy 380.45369 -283.603352) (xy 380.483255 -283.642696)
			(xy 380.506126 -283.686273) (xy 380.52171 -283.732954) (xy 380.529605 -283.781531) (xy 380.5301 -283.806138)
			(xy 380.848611 -283.806138) (xy 380.852706 -283.75541) (xy 380.864885 -283.705996) (xy 380.884833 -283.659176)
			(xy 380.912034 -283.616162) (xy 380.945782 -283.578068) (xy 380.985204 -283.545881) (xy 381.029278 -283.520435)
			(xy 381.076864 -283.502388) (xy 381.126728 -283.492208) (xy 381.17758 -283.490159) (xy 381.228101 -283.496293)
			(xy 381.276985 -283.510453) (xy 381.322964 -283.53227) (xy 381.364848 -283.56118) (xy 381.401552 -283.596435)
			(xy 381.432125 -283.637121) (xy 381.455776 -283.682184) (xy 381.471892 -283.730458) (xy 381.480056 -283.780692)
			(xy 381.480568 -283.806138) (xy 381.799096 -283.806138) (xy 381.803056 -283.757084) (xy 381.814833 -283.7093)
			(xy 381.834124 -283.664024) (xy 381.860427 -283.622428) (xy 381.893062 -283.585591) (xy 381.931183 -283.554466)
			(xy 381.973804 -283.529859) (xy 382.01982 -283.512407) (xy 382.068039 -283.502563) (xy 382.117214 -283.500582)
			(xy 382.166069 -283.506514) (xy 382.21334 -283.520206) (xy 382.257802 -283.541304) (xy 382.298305 -283.56926)
			(xy 382.333798 -283.603352) (xy 382.363363 -283.642696) (xy 382.386234 -283.686273) (xy 382.401818 -283.732954)
			(xy 382.409713 -283.781531) (xy 382.410208 -283.806138) (xy 382.738896 -283.806138) (xy 382.742856 -283.757084)
			(xy 382.754633 -283.7093) (xy 382.773924 -283.664024) (xy 382.800227 -283.622428) (xy 382.832862 -283.585591)
			(xy 382.870983 -283.554466) (xy 382.913604 -283.529859) (xy 382.95962 -283.512407) (xy 383.007839 -283.502563)
			(xy 383.057014 -283.500582) (xy 383.105869 -283.506514) (xy 383.15314 -283.520206) (xy 383.197602 -283.541304)
			(xy 383.238105 -283.56926) (xy 383.273598 -283.603352) (xy 383.303163 -283.642696) (xy 383.326034 -283.686273)
			(xy 383.341618 -283.732954) (xy 383.349513 -283.781531) (xy 383.350008 -283.806138) (xy 383.67895 -283.806138)
			(xy 383.68291 -283.757084) (xy 383.694687 -283.7093) (xy 383.713978 -283.664024) (xy 383.740281 -283.622428)
			(xy 383.772916 -283.585591) (xy 383.811037 -283.554466) (xy 383.853658 -283.529859) (xy 383.899674 -283.512407)
			(xy 383.947893 -283.502563) (xy 383.997068 -283.500582) (xy 384.045923 -283.506514) (xy 384.093194 -283.520206)
			(xy 384.137656 -283.541304) (xy 384.178159 -283.56926) (xy 384.213652 -283.603352) (xy 384.243217 -283.642696)
			(xy 384.266088 -283.686273) (xy 384.281672 -283.732954) (xy 384.289567 -283.781531) (xy 384.290062 -283.806138)
			(xy 384.289567 -283.830745) (xy 384.281672 -283.879322) (xy 384.266088 -283.926003) (xy 384.243217 -283.96958)
			(xy 384.213652 -284.008924) (xy 384.178159 -284.043016) (xy 384.137656 -284.070972) (xy 384.093194 -284.09207)
			(xy 384.045923 -284.105762) (xy 383.997068 -284.111694) (xy 383.947893 -284.109713) (xy 383.899674 -284.099869)
			(xy 383.853658 -284.082417) (xy 383.811037 -284.05781) (xy 383.772916 -284.026685) (xy 383.740281 -283.989848)
			(xy 383.713978 -283.948252) (xy 383.694687 -283.902976) (xy 383.68291 -283.855192) (xy 383.67895 -283.806138)
			(xy 383.350008 -283.806138) (xy 383.349513 -283.830745) (xy 383.341618 -283.879322) (xy 383.326034 -283.926003)
			(xy 383.303163 -283.96958) (xy 383.273598 -284.008924) (xy 383.238105 -284.043016) (xy 383.197602 -284.070972)
			(xy 383.15314 -284.09207) (xy 383.105869 -284.105762) (xy 383.057014 -284.111694) (xy 383.007839 -284.109713)
			(xy 382.95962 -284.099869) (xy 382.913604 -284.082417) (xy 382.870983 -284.05781) (xy 382.832862 -284.026685)
			(xy 382.800227 -283.989848) (xy 382.773924 -283.948252) (xy 382.754633 -283.902976) (xy 382.742856 -283.855192)
			(xy 382.738896 -283.806138) (xy 382.410208 -283.806138) (xy 382.409713 -283.830745) (xy 382.401818 -283.879322)
			(xy 382.386234 -283.926003) (xy 382.363363 -283.96958) (xy 382.333798 -284.008924) (xy 382.298305 -284.043016)
			(xy 382.257802 -284.070972) (xy 382.21334 -284.09207) (xy 382.166069 -284.105762) (xy 382.117214 -284.111694)
			(xy 382.068039 -284.109713) (xy 382.01982 -284.099869) (xy 381.973804 -284.082417) (xy 381.931183 -284.05781)
			(xy 381.893062 -284.026685) (xy 381.860427 -283.989848) (xy 381.834124 -283.948252) (xy 381.814833 -283.902976)
			(xy 381.803056 -283.855192) (xy 381.799096 -283.806138) (xy 381.480568 -283.806138) (xy 381.480056 -283.831584)
			(xy 381.471892 -283.881818) (xy 381.455776 -283.930092) (xy 381.432125 -283.975155) (xy 381.401552 -284.015841)
			(xy 381.364848 -284.051096) (xy 381.322964 -284.080006) (xy 381.276985 -284.101823) (xy 381.228101 -284.115983)
			(xy 381.17758 -284.122117) (xy 381.126728 -284.120068) (xy 381.076864 -284.109888) (xy 381.029278 -284.091841)
			(xy 380.985204 -284.066395) (xy 380.945782 -284.034208) (xy 380.912034 -283.996114) (xy 380.884833 -283.9531)
			(xy 380.864885 -283.90628) (xy 380.852706 -283.856866) (xy 380.848611 -283.806138) (xy 380.5301 -283.806138)
			(xy 380.529605 -283.830745) (xy 380.52171 -283.879322) (xy 380.506126 -283.926003) (xy 380.483255 -283.96958)
			(xy 380.45369 -284.008924) (xy 380.418197 -284.043016) (xy 380.377694 -284.070972) (xy 380.333232 -284.09207)
			(xy 380.285961 -284.105762) (xy 380.237106 -284.111694) (xy 380.187931 -284.109713) (xy 380.139712 -284.099869)
			(xy 380.093696 -284.082417) (xy 380.051075 -284.05781) (xy 380.012954 -284.026685) (xy 379.980319 -283.989848)
			(xy 379.954016 -283.948252) (xy 379.934725 -283.902976) (xy 379.922948 -283.855192) (xy 379.918988 -283.806138)
			(xy 379.60046 -283.806138) (xy 379.599948 -283.831584) (xy 379.591784 -283.881818) (xy 379.575668 -283.930092)
			(xy 379.552017 -283.975155) (xy 379.521444 -284.015841) (xy 379.48474 -284.051096) (xy 379.442856 -284.080006)
			(xy 379.396877 -284.101823) (xy 379.347993 -284.115983) (xy 379.297472 -284.122117) (xy 379.24662 -284.120068)
			(xy 379.196756 -284.109888) (xy 379.14917 -284.091841) (xy 379.105096 -284.066395) (xy 379.065674 -284.034208)
			(xy 379.031926 -283.996114) (xy 379.004725 -283.9531) (xy 378.984777 -283.90628) (xy 378.972598 -283.856866)
			(xy 378.968503 -283.806138) (xy 378.650246 -283.806138) (xy 378.649751 -283.830745) (xy 378.641856 -283.879322)
			(xy 378.626272 -283.926003) (xy 378.603401 -283.96958) (xy 378.573836 -284.008924) (xy 378.538343 -284.043016)
			(xy 378.49784 -284.070972) (xy 378.453378 -284.09207) (xy 378.406107 -284.105762) (xy 378.357252 -284.111694)
			(xy 378.308077 -284.109713) (xy 378.259858 -284.099869) (xy 378.213842 -284.082417) (xy 378.171221 -284.05781)
			(xy 378.1331 -284.026685) (xy 378.100465 -283.989848) (xy 378.074162 -283.948252) (xy 378.054871 -283.902976)
			(xy 378.043094 -283.855192) (xy 378.039134 -283.806138) (xy 377.720606 -283.806138) (xy 377.720094 -283.831584)
			(xy 377.71193 -283.881818) (xy 377.695814 -283.930092) (xy 377.672163 -283.975155) (xy 377.64159 -284.015841)
			(xy 377.604886 -284.051096) (xy 377.563002 -284.080006) (xy 377.517023 -284.101823) (xy 377.468139 -284.115983)
			(xy 377.417618 -284.122117) (xy 377.366766 -284.120068) (xy 377.316902 -284.109888) (xy 377.269316 -284.091841)
			(xy 377.225242 -284.066395) (xy 377.18582 -284.034208) (xy 377.152072 -283.996114) (xy 377.124871 -283.9531)
			(xy 377.104923 -283.90628) (xy 377.092744 -283.856866) (xy 377.088649 -283.806138) (xy 376.780552 -283.806138)
			(xy 376.78004 -283.831584) (xy 376.771876 -283.881818) (xy 376.75576 -283.930092) (xy 376.732109 -283.975155)
			(xy 376.701536 -284.015841) (xy 376.664832 -284.051096) (xy 376.622948 -284.080006) (xy 376.576969 -284.101823)
			(xy 376.528085 -284.115983) (xy 376.477564 -284.122117) (xy 376.426712 -284.120068) (xy 376.376848 -284.109888)
			(xy 376.329262 -284.091841) (xy 376.285188 -284.066395) (xy 376.245766 -284.034208) (xy 376.212018 -283.996114)
			(xy 376.184817 -283.9531) (xy 376.164869 -283.90628) (xy 376.15269 -283.856866) (xy 376.148595 -283.806138)
			(xy 375.830084 -283.806138) (xy 375.830084 -283.806392) (xy 375.830008 -283.819276) (xy 375.82797 -283.844964)
			(xy 375.82602 -283.8577) (xy 375.825258 -283.861764) (xy 375.825258 -283.955998) (xy 375.824719 -283.965834)
			(xy 375.817131 -283.983994) (xy 375.810526 -283.991304) (xy 375.675652 -284.126178) (xy 375.671488 -284.130534)
			(xy 375.665205 -284.140813) (xy 375.663206 -284.146498) (xy 375.663206 -284.146752) (xy 375.656166 -284.168676)
			(xy 375.640542 -284.211997) (xy 375.631964 -284.233366) (xy 375.615895 -284.271665) (xy 375.578903 -284.346037)
			(xy 375.55805 -284.381956) (xy 375.556526 -284.384242) (xy 375.553919 -284.389728) (xy 375.551094 -284.401538)
			(xy 375.550938 -284.40761) (xy 375.550938 -284.616144) (xy 375.678695 -284.616144) (xy 375.68279 -284.565416)
			(xy 375.694969 -284.516002) (xy 375.714917 -284.469182) (xy 375.742118 -284.426168) (xy 375.775866 -284.388074)
			(xy 375.815288 -284.355887) (xy 375.859362 -284.330441) (xy 375.906948 -284.312394) (xy 375.956812 -284.302214)
			(xy 376.007664 -284.300165) (xy 376.058185 -284.306299) (xy 376.107069 -284.320459) (xy 376.153048 -284.342276)
			(xy 376.194932 -284.371186) (xy 376.231636 -284.406441) (xy 376.262209 -284.447127) (xy 376.28586 -284.49219)
			(xy 376.301976 -284.540464) (xy 376.31014 -284.590698) (xy 376.310652 -284.616144) (xy 376.628926 -284.616144)
			(xy 376.632886 -284.56709) (xy 376.644663 -284.519306) (xy 376.663954 -284.47403) (xy 376.690257 -284.432434)
			(xy 376.722892 -284.395597) (xy 376.761013 -284.364472) (xy 376.803634 -284.339865) (xy 376.84965 -284.322413)
			(xy 376.897869 -284.312569) (xy 376.947044 -284.310588) (xy 376.995899 -284.31652) (xy 377.04317 -284.330212)
			(xy 377.087632 -284.35131) (xy 377.128135 -284.379266) (xy 377.163628 -284.413358) (xy 377.193193 -284.452702)
			(xy 377.216064 -284.496279) (xy 377.231648 -284.54296) (xy 377.239543 -284.591537) (xy 377.240038 -284.616144)
			(xy 377.558549 -284.616144) (xy 377.562644 -284.565416) (xy 377.574823 -284.516002) (xy 377.594771 -284.469182)
			(xy 377.621972 -284.426168) (xy 377.65572 -284.388074) (xy 377.695142 -284.355887) (xy 377.739216 -284.330441)
			(xy 377.786802 -284.312394) (xy 377.836666 -284.302214) (xy 377.887518 -284.300165) (xy 377.938039 -284.306299)
			(xy 377.986923 -284.320459) (xy 378.032902 -284.342276) (xy 378.074786 -284.371186) (xy 378.11149 -284.406441)
			(xy 378.142063 -284.447127) (xy 378.165714 -284.49219) (xy 378.18183 -284.540464) (xy 378.189994 -284.590698)
			(xy 378.190506 -284.616144) (xy 378.509034 -284.616144) (xy 378.512994 -284.56709) (xy 378.524771 -284.519306)
			(xy 378.544062 -284.47403) (xy 378.570365 -284.432434) (xy 378.603 -284.395597) (xy 378.641121 -284.364472)
			(xy 378.683742 -284.339865) (xy 378.729758 -284.322413) (xy 378.777977 -284.312569) (xy 378.827152 -284.310588)
			(xy 378.876007 -284.31652) (xy 378.923278 -284.330212) (xy 378.96774 -284.35131) (xy 379.008243 -284.379266)
			(xy 379.043736 -284.413358) (xy 379.073301 -284.452702) (xy 379.096172 -284.496279) (xy 379.111756 -284.54296)
			(xy 379.119651 -284.591537) (xy 379.120146 -284.616144) (xy 379.438657 -284.616144) (xy 379.442752 -284.565416)
			(xy 379.454931 -284.516002) (xy 379.474879 -284.469182) (xy 379.50208 -284.426168) (xy 379.535828 -284.388074)
			(xy 379.57525 -284.355887) (xy 379.619324 -284.330441) (xy 379.66691 -284.312394) (xy 379.716774 -284.302214)
			(xy 379.767626 -284.300165) (xy 379.818147 -284.306299) (xy 379.867031 -284.320459) (xy 379.91301 -284.342276)
			(xy 379.954894 -284.371186) (xy 379.991598 -284.406441) (xy 380.022171 -284.447127) (xy 380.045822 -284.49219)
			(xy 380.061938 -284.540464) (xy 380.070102 -284.590698) (xy 380.070614 -284.616144) (xy 380.378711 -284.616144)
			(xy 380.382806 -284.565416) (xy 380.394985 -284.516002) (xy 380.414933 -284.469182) (xy 380.442134 -284.426168)
			(xy 380.475882 -284.388074) (xy 380.515304 -284.355887) (xy 380.559378 -284.330441) (xy 380.606964 -284.312394)
			(xy 380.656828 -284.302214) (xy 380.70768 -284.300165) (xy 380.758201 -284.306299) (xy 380.807085 -284.320459)
			(xy 380.853064 -284.342276) (xy 380.894948 -284.371186) (xy 380.931652 -284.406441) (xy 380.962225 -284.447127)
			(xy 380.985876 -284.49219) (xy 381.001992 -284.540464) (xy 381.010156 -284.590698) (xy 381.010668 -284.616144)
			(xy 381.328942 -284.616144) (xy 381.332902 -284.56709) (xy 381.344679 -284.519306) (xy 381.36397 -284.47403)
			(xy 381.390273 -284.432434) (xy 381.422908 -284.395597) (xy 381.461029 -284.364472) (xy 381.50365 -284.339865)
			(xy 381.549666 -284.322413) (xy 381.597885 -284.312569) (xy 381.64706 -284.310588) (xy 381.695915 -284.31652)
			(xy 381.743186 -284.330212) (xy 381.787648 -284.35131) (xy 381.828151 -284.379266) (xy 381.863644 -284.413358)
			(xy 381.893209 -284.452702) (xy 381.91608 -284.496279) (xy 381.931664 -284.54296) (xy 381.939559 -284.591537)
			(xy 381.940054 -284.616144) (xy 382.268996 -284.616144) (xy 382.272956 -284.56709) (xy 382.284733 -284.519306)
			(xy 382.304024 -284.47403) (xy 382.330327 -284.432434) (xy 382.362962 -284.395597) (xy 382.401083 -284.364472)
			(xy 382.443704 -284.339865) (xy 382.48972 -284.322413) (xy 382.537939 -284.312569) (xy 382.587114 -284.310588)
			(xy 382.635969 -284.31652) (xy 382.68324 -284.330212) (xy 382.727702 -284.35131) (xy 382.768205 -284.379266)
			(xy 382.803698 -284.413358) (xy 382.833263 -284.452702) (xy 382.856134 -284.496279) (xy 382.871718 -284.54296)
			(xy 382.879613 -284.591537) (xy 382.880108 -284.616144) (xy 383.20905 -284.616144) (xy 383.21301 -284.56709)
			(xy 383.224787 -284.519306) (xy 383.244078 -284.47403) (xy 383.270381 -284.432434) (xy 383.303016 -284.395597)
			(xy 383.341137 -284.364472) (xy 383.383758 -284.339865) (xy 383.429774 -284.322413) (xy 383.477993 -284.312569)
			(xy 383.527168 -284.310588) (xy 383.576023 -284.31652) (xy 383.623294 -284.330212) (xy 383.667756 -284.35131)
			(xy 383.708259 -284.379266) (xy 383.743752 -284.413358) (xy 383.773317 -284.452702) (xy 383.796188 -284.496279)
			(xy 383.811772 -284.54296) (xy 383.819667 -284.591537) (xy 383.820162 -284.616144) (xy 384.149104 -284.616144)
			(xy 384.153064 -284.56709) (xy 384.164841 -284.519306) (xy 384.184132 -284.47403) (xy 384.210435 -284.432434)
			(xy 384.24307 -284.395597) (xy 384.281191 -284.364472) (xy 384.323812 -284.339865) (xy 384.369828 -284.322413)
			(xy 384.418047 -284.312569) (xy 384.467222 -284.310588) (xy 384.516077 -284.31652) (xy 384.563348 -284.330212)
			(xy 384.60781 -284.35131) (xy 384.648313 -284.379266) (xy 384.683806 -284.413358) (xy 384.713371 -284.452702)
			(xy 384.736242 -284.496279) (xy 384.751826 -284.54296) (xy 384.759721 -284.591537) (xy 384.760216 -284.616144)
			(xy 384.759721 -284.640751) (xy 384.751826 -284.689328) (xy 384.736242 -284.736009) (xy 384.713371 -284.779586)
			(xy 384.683806 -284.81893) (xy 384.648313 -284.853022) (xy 384.60781 -284.880978) (xy 384.563348 -284.902076)
			(xy 384.516077 -284.915768) (xy 384.467222 -284.9217) (xy 384.418047 -284.919719) (xy 384.369828 -284.909875)
			(xy 384.323812 -284.892423) (xy 384.281191 -284.867816) (xy 384.24307 -284.836691) (xy 384.210435 -284.799854)
			(xy 384.184132 -284.758258) (xy 384.164841 -284.712982) (xy 384.153064 -284.665198) (xy 384.149104 -284.616144)
			(xy 383.820162 -284.616144) (xy 383.819667 -284.640751) (xy 383.811772 -284.689328) (xy 383.796188 -284.736009)
			(xy 383.773317 -284.779586) (xy 383.743752 -284.81893) (xy 383.708259 -284.853022) (xy 383.667756 -284.880978)
			(xy 383.623294 -284.902076) (xy 383.576023 -284.915768) (xy 383.527168 -284.9217) (xy 383.477993 -284.919719)
			(xy 383.429774 -284.909875) (xy 383.383758 -284.892423) (xy 383.341137 -284.867816) (xy 383.303016 -284.836691)
			(xy 383.270381 -284.799854) (xy 383.244078 -284.758258) (xy 383.224787 -284.712982) (xy 383.21301 -284.665198)
			(xy 383.20905 -284.616144) (xy 382.880108 -284.616144) (xy 382.879613 -284.640751) (xy 382.871718 -284.689328)
			(xy 382.856134 -284.736009) (xy 382.833263 -284.779586) (xy 382.803698 -284.81893) (xy 382.768205 -284.853022)
			(xy 382.727702 -284.880978) (xy 382.68324 -284.902076) (xy 382.635969 -284.915768) (xy 382.587114 -284.9217)
			(xy 382.537939 -284.919719) (xy 382.48972 -284.909875) (xy 382.443704 -284.892423) (xy 382.401083 -284.867816)
			(xy 382.362962 -284.836691) (xy 382.330327 -284.799854) (xy 382.304024 -284.758258) (xy 382.284733 -284.712982)
			(xy 382.272956 -284.665198) (xy 382.268996 -284.616144) (xy 381.940054 -284.616144) (xy 381.939559 -284.640751)
			(xy 381.931664 -284.689328) (xy 381.91608 -284.736009) (xy 381.893209 -284.779586) (xy 381.863644 -284.81893)
			(xy 381.828151 -284.853022) (xy 381.787648 -284.880978) (xy 381.743186 -284.902076) (xy 381.695915 -284.915768)
			(xy 381.64706 -284.9217) (xy 381.597885 -284.919719) (xy 381.549666 -284.909875) (xy 381.50365 -284.892423)
			(xy 381.461029 -284.867816) (xy 381.422908 -284.836691) (xy 381.390273 -284.799854) (xy 381.36397 -284.758258)
			(xy 381.344679 -284.712982) (xy 381.332902 -284.665198) (xy 381.328942 -284.616144) (xy 381.010668 -284.616144)
			(xy 381.010156 -284.64159) (xy 381.001992 -284.691824) (xy 380.985876 -284.740098) (xy 380.962225 -284.785161)
			(xy 380.931652 -284.825847) (xy 380.894948 -284.861102) (xy 380.853064 -284.890012) (xy 380.807085 -284.911829)
			(xy 380.758201 -284.925989) (xy 380.70768 -284.932123) (xy 380.656828 -284.930074) (xy 380.606964 -284.919894)
			(xy 380.559378 -284.901847) (xy 380.515304 -284.876401) (xy 380.475882 -284.844214) (xy 380.442134 -284.80612)
			(xy 380.414933 -284.763106) (xy 380.394985 -284.716286) (xy 380.382806 -284.666872) (xy 380.378711 -284.616144)
			(xy 380.070614 -284.616144) (xy 380.070102 -284.64159) (xy 380.061938 -284.691824) (xy 380.045822 -284.740098)
			(xy 380.022171 -284.785161) (xy 379.991598 -284.825847) (xy 379.954894 -284.861102) (xy 379.91301 -284.890012)
			(xy 379.867031 -284.911829) (xy 379.818147 -284.925989) (xy 379.767626 -284.932123) (xy 379.716774 -284.930074)
			(xy 379.66691 -284.919894) (xy 379.619324 -284.901847) (xy 379.57525 -284.876401) (xy 379.535828 -284.844214)
			(xy 379.50208 -284.80612) (xy 379.474879 -284.763106) (xy 379.454931 -284.716286) (xy 379.442752 -284.666872)
			(xy 379.438657 -284.616144) (xy 379.120146 -284.616144) (xy 379.119651 -284.640751) (xy 379.111756 -284.689328)
			(xy 379.096172 -284.736009) (xy 379.073301 -284.779586) (xy 379.043736 -284.81893) (xy 379.008243 -284.853022)
			(xy 378.96774 -284.880978) (xy 378.923278 -284.902076) (xy 378.876007 -284.915768) (xy 378.827152 -284.9217)
			(xy 378.777977 -284.919719) (xy 378.729758 -284.909875) (xy 378.683742 -284.892423) (xy 378.641121 -284.867816)
			(xy 378.603 -284.836691) (xy 378.570365 -284.799854) (xy 378.544062 -284.758258) (xy 378.524771 -284.712982)
			(xy 378.512994 -284.665198) (xy 378.509034 -284.616144) (xy 378.190506 -284.616144) (xy 378.189994 -284.64159)
			(xy 378.18183 -284.691824) (xy 378.165714 -284.740098) (xy 378.142063 -284.785161) (xy 378.11149 -284.825847)
			(xy 378.074786 -284.861102) (xy 378.032902 -284.890012) (xy 377.986923 -284.911829) (xy 377.938039 -284.925989)
			(xy 377.887518 -284.932123) (xy 377.836666 -284.930074) (xy 377.786802 -284.919894) (xy 377.739216 -284.901847)
			(xy 377.695142 -284.876401) (xy 377.65572 -284.844214) (xy 377.621972 -284.80612) (xy 377.594771 -284.763106)
			(xy 377.574823 -284.716286) (xy 377.562644 -284.666872) (xy 377.558549 -284.616144) (xy 377.240038 -284.616144)
			(xy 377.239543 -284.640751) (xy 377.231648 -284.689328) (xy 377.216064 -284.736009) (xy 377.193193 -284.779586)
			(xy 377.163628 -284.81893) (xy 377.128135 -284.853022) (xy 377.087632 -284.880978) (xy 377.04317 -284.902076)
			(xy 376.995899 -284.915768) (xy 376.947044 -284.9217) (xy 376.897869 -284.919719) (xy 376.84965 -284.909875)
			(xy 376.803634 -284.892423) (xy 376.761013 -284.867816) (xy 376.722892 -284.836691) (xy 376.690257 -284.799854)
			(xy 376.663954 -284.758258) (xy 376.644663 -284.712982) (xy 376.632886 -284.665198) (xy 376.628926 -284.616144)
			(xy 376.310652 -284.616144) (xy 376.31014 -284.64159) (xy 376.301976 -284.691824) (xy 376.28586 -284.740098)
			(xy 376.262209 -284.785161) (xy 376.231636 -284.825847) (xy 376.194932 -284.861102) (xy 376.153048 -284.890012)
			(xy 376.107069 -284.911829) (xy 376.058185 -284.925989) (xy 376.007664 -284.932123) (xy 375.956812 -284.930074)
			(xy 375.906948 -284.919894) (xy 375.859362 -284.901847) (xy 375.815288 -284.876401) (xy 375.775866 -284.844214)
			(xy 375.742118 -284.80612) (xy 375.714917 -284.763106) (xy 375.694969 -284.716286) (xy 375.68279 -284.666872)
			(xy 375.678695 -284.616144) (xy 375.550938 -284.616144) (xy 375.550938 -284.824678) (xy 375.55108 -284.830752)
			(xy 375.553902 -284.842566) (xy 375.556526 -284.848046) (xy 375.55805 -284.850332) (xy 375.580682 -284.889471)
			(xy 375.620352 -284.970722) (xy 375.637298 -285.012638) (xy 375.643902 -285.02991) (xy 375.650673 -285.048071)
			(xy 375.663122 -285.084782) (xy 375.668794 -285.103316) (xy 375.671334 -285.11246) (xy 375.688606 -285.134558)
			(xy 375.691359 -285.138031) (xy 375.697872 -285.144039) (xy 375.70156 -285.146496) (xy 375.713492 -285.154207)
			(xy 375.73613 -285.171375) (xy 375.746772 -285.180786) (xy 375.767522 -285.200367) (xy 375.802643 -285.245323)
			(xy 375.816622 -285.270194) (xy 375.820178 -285.277052) (xy 375.841006 -285.29788) (xy 375.847725 -285.305116)
			(xy 375.855331 -285.323321) (xy 375.855738 -285.333186) (xy 375.855738 -285.42615) (xy 376.148595 -285.42615)
			(xy 376.15269 -285.375422) (xy 376.164869 -285.326008) (xy 376.184817 -285.279188) (xy 376.212018 -285.236174)
			(xy 376.245766 -285.19808) (xy 376.285188 -285.165893) (xy 376.329262 -285.140447) (xy 376.376848 -285.1224)
			(xy 376.426712 -285.11222) (xy 376.477564 -285.110171) (xy 376.528085 -285.116305) (xy 376.576969 -285.130465)
			(xy 376.622948 -285.152282) (xy 376.664832 -285.181192) (xy 376.701536 -285.216447) (xy 376.732109 -285.257133)
			(xy 376.75576 -285.302196) (xy 376.771876 -285.35047) (xy 376.78004 -285.400704) (xy 376.780552 -285.42615)
			(xy 377.088649 -285.42615) (xy 377.092744 -285.375422) (xy 377.104923 -285.326008) (xy 377.124871 -285.279188)
			(xy 377.152072 -285.236174) (xy 377.18582 -285.19808) (xy 377.225242 -285.165893) (xy 377.269316 -285.140447)
			(xy 377.316902 -285.1224) (xy 377.366766 -285.11222) (xy 377.417618 -285.110171) (xy 377.468139 -285.116305)
			(xy 377.517023 -285.130465) (xy 377.563002 -285.152282) (xy 377.604886 -285.181192) (xy 377.64159 -285.216447)
			(xy 377.672163 -285.257133) (xy 377.695814 -285.302196) (xy 377.71193 -285.35047) (xy 377.720094 -285.400704)
			(xy 377.720606 -285.42615) (xy 378.968503 -285.42615) (xy 378.972598 -285.375422) (xy 378.984777 -285.326008)
			(xy 379.004725 -285.279188) (xy 379.031926 -285.236174) (xy 379.065674 -285.19808) (xy 379.105096 -285.165893)
			(xy 379.14917 -285.140447) (xy 379.196756 -285.1224) (xy 379.24662 -285.11222) (xy 379.297472 -285.110171)
			(xy 379.347993 -285.116305) (xy 379.396877 -285.130465) (xy 379.442856 -285.152282) (xy 379.48474 -285.181192)
			(xy 379.521444 -285.216447) (xy 379.552017 -285.257133) (xy 379.575668 -285.302196) (xy 379.591784 -285.35047)
			(xy 379.599948 -285.400704) (xy 379.60046 -285.42615) (xy 379.918988 -285.42615) (xy 379.922948 -285.377096)
			(xy 379.934725 -285.329312) (xy 379.954016 -285.284036) (xy 379.980319 -285.24244) (xy 380.012954 -285.205603)
			(xy 380.051075 -285.174478) (xy 380.093696 -285.149871) (xy 380.139712 -285.132419) (xy 380.187931 -285.122575)
			(xy 380.237106 -285.120594) (xy 380.285961 -285.126526) (xy 380.333232 -285.140218) (xy 380.377694 -285.161316)
			(xy 380.418197 -285.189272) (xy 380.45369 -285.223364) (xy 380.483255 -285.262708) (xy 380.506126 -285.306285)
			(xy 380.52171 -285.352966) (xy 380.529605 -285.401543) (xy 380.5301 -285.42615) (xy 380.848611 -285.42615)
			(xy 380.852706 -285.375422) (xy 380.864885 -285.326008) (xy 380.884833 -285.279188) (xy 380.912034 -285.236174)
			(xy 380.945782 -285.19808) (xy 380.985204 -285.165893) (xy 381.029278 -285.140447) (xy 381.076864 -285.1224)
			(xy 381.126728 -285.11222) (xy 381.17758 -285.110171) (xy 381.228101 -285.116305) (xy 381.276985 -285.130465)
			(xy 381.322964 -285.152282) (xy 381.364848 -285.181192) (xy 381.401552 -285.216447) (xy 381.432125 -285.257133)
			(xy 381.455776 -285.302196) (xy 381.471892 -285.35047) (xy 381.480056 -285.400704) (xy 381.480568 -285.42615)
			(xy 381.799096 -285.42615) (xy 381.803056 -285.377096) (xy 381.814833 -285.329312) (xy 381.834124 -285.284036)
			(xy 381.860427 -285.24244) (xy 381.893062 -285.205603) (xy 381.931183 -285.174478) (xy 381.973804 -285.149871)
			(xy 382.01982 -285.132419) (xy 382.068039 -285.122575) (xy 382.117214 -285.120594) (xy 382.166069 -285.126526)
			(xy 382.21334 -285.140218) (xy 382.257802 -285.161316) (xy 382.298305 -285.189272) (xy 382.333798 -285.223364)
			(xy 382.363363 -285.262708) (xy 382.386234 -285.306285) (xy 382.401818 -285.352966) (xy 382.409713 -285.401543)
			(xy 382.410208 -285.42615) (xy 382.738896 -285.42615) (xy 382.742856 -285.377096) (xy 382.754633 -285.329312)
			(xy 382.773924 -285.284036) (xy 382.800227 -285.24244) (xy 382.832862 -285.205603) (xy 382.870983 -285.174478)
			(xy 382.913604 -285.149871) (xy 382.95962 -285.132419) (xy 383.007839 -285.122575) (xy 383.057014 -285.120594)
			(xy 383.105869 -285.126526) (xy 383.15314 -285.140218) (xy 383.197602 -285.161316) (xy 383.238105 -285.189272)
			(xy 383.273598 -285.223364) (xy 383.303163 -285.262708) (xy 383.326034 -285.306285) (xy 383.341618 -285.352966)
			(xy 383.349513 -285.401543) (xy 383.350008 -285.42615) (xy 383.67895 -285.42615) (xy 383.68291 -285.377096)
			(xy 383.694687 -285.329312) (xy 383.713978 -285.284036) (xy 383.740281 -285.24244) (xy 383.772916 -285.205603)
			(xy 383.811037 -285.174478) (xy 383.853658 -285.149871) (xy 383.899674 -285.132419) (xy 383.947893 -285.122575)
			(xy 383.997068 -285.120594) (xy 384.045923 -285.126526) (xy 384.093194 -285.140218) (xy 384.137656 -285.161316)
			(xy 384.178159 -285.189272) (xy 384.213652 -285.223364) (xy 384.243217 -285.262708) (xy 384.266088 -285.306285)
			(xy 384.281672 -285.352966) (xy 384.289567 -285.401543) (xy 384.290062 -285.42615) (xy 384.289567 -285.450757)
			(xy 384.281672 -285.499334) (xy 384.266088 -285.546015) (xy 384.243217 -285.589592) (xy 384.213652 -285.628936)
			(xy 384.178159 -285.663028) (xy 384.137656 -285.690984) (xy 384.093194 -285.712082) (xy 384.045923 -285.725774)
			(xy 383.997068 -285.731706) (xy 383.947893 -285.729725) (xy 383.899674 -285.719881) (xy 383.853658 -285.702429)
			(xy 383.811037 -285.677822) (xy 383.772916 -285.646697) (xy 383.740281 -285.60986) (xy 383.713978 -285.568264)
			(xy 383.694687 -285.522988) (xy 383.68291 -285.475204) (xy 383.67895 -285.42615) (xy 383.350008 -285.42615)
			(xy 383.349513 -285.450757) (xy 383.341618 -285.499334) (xy 383.326034 -285.546015) (xy 383.303163 -285.589592)
			(xy 383.273598 -285.628936) (xy 383.238105 -285.663028) (xy 383.197602 -285.690984) (xy 383.15314 -285.712082)
			(xy 383.105869 -285.725774) (xy 383.057014 -285.731706) (xy 383.007839 -285.729725) (xy 382.95962 -285.719881)
			(xy 382.913604 -285.702429) (xy 382.870983 -285.677822) (xy 382.832862 -285.646697) (xy 382.800227 -285.60986)
			(xy 382.773924 -285.568264) (xy 382.754633 -285.522988) (xy 382.742856 -285.475204) (xy 382.738896 -285.42615)
			(xy 382.410208 -285.42615) (xy 382.409713 -285.450757) (xy 382.401818 -285.499334) (xy 382.386234 -285.546015)
			(xy 382.363363 -285.589592) (xy 382.333798 -285.628936) (xy 382.298305 -285.663028) (xy 382.257802 -285.690984)
			(xy 382.21334 -285.712082) (xy 382.166069 -285.725774) (xy 382.117214 -285.731706) (xy 382.068039 -285.729725)
			(xy 382.01982 -285.719881) (xy 381.973804 -285.702429) (xy 381.931183 -285.677822) (xy 381.893062 -285.646697)
			(xy 381.860427 -285.60986) (xy 381.834124 -285.568264) (xy 381.814833 -285.522988) (xy 381.803056 -285.475204)
			(xy 381.799096 -285.42615) (xy 381.480568 -285.42615) (xy 381.480056 -285.451596) (xy 381.471892 -285.50183)
			(xy 381.455776 -285.550104) (xy 381.432125 -285.595167) (xy 381.401552 -285.635853) (xy 381.364848 -285.671108)
			(xy 381.322964 -285.700018) (xy 381.276985 -285.721835) (xy 381.228101 -285.735995) (xy 381.17758 -285.742129)
			(xy 381.126728 -285.74008) (xy 381.076864 -285.7299) (xy 381.029278 -285.711853) (xy 380.985204 -285.686407)
			(xy 380.945782 -285.65422) (xy 380.912034 -285.616126) (xy 380.884833 -285.573112) (xy 380.864885 -285.526292)
			(xy 380.852706 -285.476878) (xy 380.848611 -285.42615) (xy 380.5301 -285.42615) (xy 380.529605 -285.450757)
			(xy 380.52171 -285.499334) (xy 380.506126 -285.546015) (xy 380.483255 -285.589592) (xy 380.45369 -285.628936)
			(xy 380.418197 -285.663028) (xy 380.377694 -285.690984) (xy 380.333232 -285.712082) (xy 380.285961 -285.725774)
			(xy 380.237106 -285.731706) (xy 380.187931 -285.729725) (xy 380.139712 -285.719881) (xy 380.093696 -285.702429)
			(xy 380.051075 -285.677822) (xy 380.012954 -285.646697) (xy 379.980319 -285.60986) (xy 379.954016 -285.568264)
			(xy 379.934725 -285.522988) (xy 379.922948 -285.475204) (xy 379.918988 -285.42615) (xy 379.60046 -285.42615)
			(xy 379.599948 -285.451596) (xy 379.591784 -285.50183) (xy 379.575668 -285.550104) (xy 379.552017 -285.595167)
			(xy 379.521444 -285.635853) (xy 379.48474 -285.671108) (xy 379.442856 -285.700018) (xy 379.396877 -285.721835)
			(xy 379.347993 -285.735995) (xy 379.297472 -285.742129) (xy 379.24662 -285.74008) (xy 379.196756 -285.7299)
			(xy 379.14917 -285.711853) (xy 379.105096 -285.686407) (xy 379.065674 -285.65422) (xy 379.031926 -285.616126)
			(xy 379.004725 -285.573112) (xy 378.984777 -285.526292) (xy 378.972598 -285.476878) (xy 378.968503 -285.42615)
			(xy 377.720606 -285.42615) (xy 377.720094 -285.451596) (xy 377.71193 -285.50183) (xy 377.695814 -285.550104)
			(xy 377.672163 -285.595167) (xy 377.64159 -285.635853) (xy 377.604886 -285.671108) (xy 377.563002 -285.700018)
			(xy 377.517023 -285.721835) (xy 377.468139 -285.735995) (xy 377.417618 -285.742129) (xy 377.366766 -285.74008)
			(xy 377.316902 -285.7299) (xy 377.269316 -285.711853) (xy 377.225242 -285.686407) (xy 377.18582 -285.65422)
			(xy 377.152072 -285.616126) (xy 377.124871 -285.573112) (xy 377.104923 -285.526292) (xy 377.092744 -285.476878)
			(xy 377.088649 -285.42615) (xy 376.780552 -285.42615) (xy 376.78004 -285.451596) (xy 376.771876 -285.50183)
			(xy 376.75576 -285.550104) (xy 376.732109 -285.595167) (xy 376.701536 -285.635853) (xy 376.664832 -285.671108)
			(xy 376.622948 -285.700018) (xy 376.576969 -285.721835) (xy 376.528085 -285.735995) (xy 376.477564 -285.742129)
			(xy 376.426712 -285.74008) (xy 376.376848 -285.7299) (xy 376.329262 -285.711853) (xy 376.285188 -285.686407)
			(xy 376.245766 -285.65422) (xy 376.212018 -285.616126) (xy 376.184817 -285.573112) (xy 376.164869 -285.526292)
			(xy 376.15269 -285.476878) (xy 376.148595 -285.42615) (xy 375.855738 -285.42615) (xy 375.855738 -285.576518)
			(xy 375.855212 -285.58636) (xy 375.847643 -285.604539) (xy 375.841006 -285.611824) (xy 375.663714 -285.789116)
			(xy 375.65711 -285.797244) (xy 375.647966 -285.811722) (xy 375.646188 -285.816802) (xy 375.637746 -285.839301)
			(xy 375.619199 -285.88364) (xy 375.609104 -285.905448) (xy 375.604278 -285.915862) (xy 375.604278 -285.9532)
			(xy 375.604278 -285.953708) (xy 375.604984 -285.965423) (xy 375.61557 -285.986342) (xy 375.624598 -285.99384)
			(xy 375.629932 -285.99765) (xy 375.717054 -286.03321) (xy 375.724181 -286.035828) (xy 375.739303 -286.037119)
			(xy 375.746772 -286.03575) (xy 375.751852 -286.034734) (xy 375.766898 -286.017226) (xy 375.801236 -285.986372)
			(xy 375.839704 -285.960853) (xy 375.881481 -285.941214) (xy 375.925675 -285.927874) (xy 375.971341 -285.921119)
			(xy 375.994422 -285.920688) (xy 375.99493 -285.920688) (xy 376.019722 -285.921176) (xy 376.068694 -285.928937)
			(xy 376.115849 -285.944263) (xy 376.160026 -285.966776) (xy 376.200138 -285.995922) (xy 376.235197 -286.030985)
			(xy 376.26434 -286.071099) (xy 376.286849 -286.115279) (xy 376.30217 -286.162436) (xy 376.309926 -286.211408)
			(xy 376.309926 -286.236156) (xy 376.628926 -286.236156) (xy 376.632886 -286.187102) (xy 376.644663 -286.139318)
			(xy 376.663954 -286.094042) (xy 376.690257 -286.052446) (xy 376.722892 -286.015609) (xy 376.761013 -285.984484)
			(xy 376.803634 -285.959877) (xy 376.84965 -285.942425) (xy 376.897869 -285.932581) (xy 376.947044 -285.9306)
			(xy 376.995899 -285.936532) (xy 377.04317 -285.950224) (xy 377.087632 -285.971322) (xy 377.128135 -285.999278)
			(xy 377.163628 -286.03337) (xy 377.193193 -286.072714) (xy 377.216064 -286.116291) (xy 377.231648 -286.162972)
			(xy 377.239543 -286.211549) (xy 377.240038 -286.236156) (xy 377.558549 -286.236156) (xy 377.562644 -286.185428)
			(xy 377.574823 -286.136014) (xy 377.594771 -286.089194) (xy 377.621972 -286.04618) (xy 377.65572 -286.008086)
			(xy 377.695142 -285.975899) (xy 377.739216 -285.950453) (xy 377.786802 -285.932406) (xy 377.836666 -285.922226)
			(xy 377.887518 -285.920177) (xy 377.938039 -285.926311) (xy 377.986923 -285.940471) (xy 378.032902 -285.962288)
			(xy 378.074786 -285.991198) (xy 378.11149 -286.026453) (xy 378.142063 -286.067139) (xy 378.165714 -286.112202)
			(xy 378.18183 -286.160476) (xy 378.189994 -286.21071) (xy 378.190506 -286.236156) (xy 378.509034 -286.236156)
			(xy 378.512994 -286.187102) (xy 378.524771 -286.139318) (xy 378.544062 -286.094042) (xy 378.570365 -286.052446)
			(xy 378.603 -286.015609) (xy 378.641121 -285.984484) (xy 378.683742 -285.959877) (xy 378.729758 -285.942425)
			(xy 378.777977 -285.932581) (xy 378.827152 -285.9306) (xy 378.876007 -285.936532) (xy 378.923278 -285.950224)
			(xy 378.96774 -285.971322) (xy 379.008243 -285.999278) (xy 379.043736 -286.03337) (xy 379.073301 -286.072714)
			(xy 379.096172 -286.116291) (xy 379.111756 -286.162972) (xy 379.119651 -286.211549) (xy 379.120146 -286.236156)
			(xy 379.438657 -286.236156) (xy 379.442752 -286.185428) (xy 379.454931 -286.136014) (xy 379.474879 -286.089194)
			(xy 379.50208 -286.04618) (xy 379.535828 -286.008086) (xy 379.57525 -285.975899) (xy 379.619324 -285.950453)
			(xy 379.66691 -285.932406) (xy 379.716774 -285.922226) (xy 379.767626 -285.920177) (xy 379.818147 -285.926311)
			(xy 379.867031 -285.940471) (xy 379.91301 -285.962288) (xy 379.954894 -285.991198) (xy 379.991598 -286.026453)
			(xy 380.022171 -286.067139) (xy 380.045822 -286.112202) (xy 380.061938 -286.160476) (xy 380.070102 -286.21071)
			(xy 380.070614 -286.236156) (xy 380.378711 -286.236156) (xy 380.382806 -286.185428) (xy 380.394985 -286.136014)
			(xy 380.414933 -286.089194) (xy 380.442134 -286.04618) (xy 380.475882 -286.008086) (xy 380.515304 -285.975899)
			(xy 380.559378 -285.950453) (xy 380.606964 -285.932406) (xy 380.656828 -285.922226) (xy 380.70768 -285.920177)
			(xy 380.758201 -285.926311) (xy 380.807085 -285.940471) (xy 380.853064 -285.962288) (xy 380.894948 -285.991198)
			(xy 380.931652 -286.026453) (xy 380.962225 -286.067139) (xy 380.985876 -286.112202) (xy 381.001992 -286.160476)
			(xy 381.010156 -286.21071) (xy 381.010668 -286.236156) (xy 381.328942 -286.236156) (xy 381.332902 -286.187102)
			(xy 381.344679 -286.139318) (xy 381.36397 -286.094042) (xy 381.390273 -286.052446) (xy 381.422908 -286.015609)
			(xy 381.461029 -285.984484) (xy 381.50365 -285.959877) (xy 381.549666 -285.942425) (xy 381.597885 -285.932581)
			(xy 381.64706 -285.9306) (xy 381.695915 -285.936532) (xy 381.743186 -285.950224) (xy 381.787648 -285.971322)
			(xy 381.828151 -285.999278) (xy 381.863644 -286.03337) (xy 381.893209 -286.072714) (xy 381.91608 -286.116291)
			(xy 381.931664 -286.162972) (xy 381.939559 -286.211549) (xy 381.940054 -286.236156) (xy 382.268996 -286.236156)
			(xy 382.272956 -286.187102) (xy 382.284733 -286.139318) (xy 382.304024 -286.094042) (xy 382.330327 -286.052446)
			(xy 382.362962 -286.015609) (xy 382.401083 -285.984484) (xy 382.443704 -285.959877) (xy 382.48972 -285.942425)
			(xy 382.537939 -285.932581) (xy 382.587114 -285.9306) (xy 382.635969 -285.936532) (xy 382.68324 -285.950224)
			(xy 382.727702 -285.971322) (xy 382.768205 -285.999278) (xy 382.803698 -286.03337) (xy 382.833263 -286.072714)
			(xy 382.856134 -286.116291) (xy 382.871718 -286.162972) (xy 382.879613 -286.211549) (xy 382.880108 -286.236156)
			(xy 383.20905 -286.236156) (xy 383.21301 -286.187102) (xy 383.224787 -286.139318) (xy 383.244078 -286.094042)
			(xy 383.270381 -286.052446) (xy 383.303016 -286.015609) (xy 383.341137 -285.984484) (xy 383.383758 -285.959877)
			(xy 383.429774 -285.942425) (xy 383.477993 -285.932581) (xy 383.527168 -285.9306) (xy 383.576023 -285.936532)
			(xy 383.623294 -285.950224) (xy 383.667756 -285.971322) (xy 383.708259 -285.999278) (xy 383.743752 -286.03337)
			(xy 383.773317 -286.072714) (xy 383.796188 -286.116291) (xy 383.811772 -286.162972) (xy 383.819667 -286.211549)
			(xy 383.820162 -286.236156) (xy 384.149104 -286.236156) (xy 384.153064 -286.187102) (xy 384.164841 -286.139318)
			(xy 384.184132 -286.094042) (xy 384.210435 -286.052446) (xy 384.24307 -286.015609) (xy 384.281191 -285.984484)
			(xy 384.323812 -285.959877) (xy 384.369828 -285.942425) (xy 384.418047 -285.932581) (xy 384.467222 -285.9306)
			(xy 384.516077 -285.936532) (xy 384.563348 -285.950224) (xy 384.60781 -285.971322) (xy 384.648313 -285.999278)
			(xy 384.683806 -286.03337) (xy 384.713371 -286.072714) (xy 384.736242 -286.116291) (xy 384.751826 -286.162972)
			(xy 384.759721 -286.211549) (xy 384.760216 -286.236156) (xy 384.759721 -286.260763) (xy 384.751826 -286.30934)
			(xy 384.736242 -286.356021) (xy 384.713371 -286.399598) (xy 384.683806 -286.438942) (xy 384.648313 -286.473034)
			(xy 384.60781 -286.50099) (xy 384.563348 -286.522088) (xy 384.516077 -286.53578) (xy 384.467222 -286.541712)
			(xy 384.418047 -286.539731) (xy 384.369828 -286.529887) (xy 384.323812 -286.512435) (xy 384.281191 -286.487828)
			(xy 384.24307 -286.456703) (xy 384.210435 -286.419866) (xy 384.184132 -286.37827) (xy 384.164841 -286.332994)
			(xy 384.153064 -286.28521) (xy 384.149104 -286.236156) (xy 383.820162 -286.236156) (xy 383.819667 -286.260763)
			(xy 383.811772 -286.30934) (xy 383.796188 -286.356021) (xy 383.773317 -286.399598) (xy 383.743752 -286.438942)
			(xy 383.708259 -286.473034) (xy 383.667756 -286.50099) (xy 383.623294 -286.522088) (xy 383.576023 -286.53578)
			(xy 383.527168 -286.541712) (xy 383.477993 -286.539731) (xy 383.429774 -286.529887) (xy 383.383758 -286.512435)
			(xy 383.341137 -286.487828) (xy 383.303016 -286.456703) (xy 383.270381 -286.419866) (xy 383.244078 -286.37827)
			(xy 383.224787 -286.332994) (xy 383.21301 -286.28521) (xy 383.20905 -286.236156) (xy 382.880108 -286.236156)
			(xy 382.879613 -286.260763) (xy 382.871718 -286.30934) (xy 382.856134 -286.356021) (xy 382.833263 -286.399598)
			(xy 382.803698 -286.438942) (xy 382.768205 -286.473034) (xy 382.727702 -286.50099) (xy 382.68324 -286.522088)
			(xy 382.635969 -286.53578) (xy 382.587114 -286.541712) (xy 382.537939 -286.539731) (xy 382.48972 -286.529887)
			(xy 382.443704 -286.512435) (xy 382.401083 -286.487828) (xy 382.362962 -286.456703) (xy 382.330327 -286.419866)
			(xy 382.304024 -286.37827) (xy 382.284733 -286.332994) (xy 382.272956 -286.28521) (xy 382.268996 -286.236156)
			(xy 381.940054 -286.236156) (xy 381.939559 -286.260763) (xy 381.931664 -286.30934) (xy 381.91608 -286.356021)
			(xy 381.893209 -286.399598) (xy 381.863644 -286.438942) (xy 381.828151 -286.473034) (xy 381.787648 -286.50099)
			(xy 381.743186 -286.522088) (xy 381.695915 -286.53578) (xy 381.64706 -286.541712) (xy 381.597885 -286.539731)
			(xy 381.549666 -286.529887) (xy 381.50365 -286.512435) (xy 381.461029 -286.487828) (xy 381.422908 -286.456703)
			(xy 381.390273 -286.419866) (xy 381.36397 -286.37827) (xy 381.344679 -286.332994) (xy 381.332902 -286.28521)
			(xy 381.328942 -286.236156) (xy 381.010668 -286.236156) (xy 381.010156 -286.261602) (xy 381.001992 -286.311836)
			(xy 380.985876 -286.36011) (xy 380.962225 -286.405173) (xy 380.931652 -286.445859) (xy 380.894948 -286.481114)
			(xy 380.853064 -286.510024) (xy 380.807085 -286.531841) (xy 380.758201 -286.546001) (xy 380.70768 -286.552135)
			(xy 380.656828 -286.550086) (xy 380.606964 -286.539906) (xy 380.559378 -286.521859) (xy 380.515304 -286.496413)
			(xy 380.475882 -286.464226) (xy 380.442134 -286.426132) (xy 380.414933 -286.383118) (xy 380.394985 -286.336298)
			(xy 380.382806 -286.286884) (xy 380.378711 -286.236156) (xy 380.070614 -286.236156) (xy 380.070102 -286.261602)
			(xy 380.061938 -286.311836) (xy 380.045822 -286.36011) (xy 380.022171 -286.405173) (xy 379.991598 -286.445859)
			(xy 379.954894 -286.481114) (xy 379.91301 -286.510024) (xy 379.867031 -286.531841) (xy 379.818147 -286.546001)
			(xy 379.767626 -286.552135) (xy 379.716774 -286.550086) (xy 379.66691 -286.539906) (xy 379.619324 -286.521859)
			(xy 379.57525 -286.496413) (xy 379.535828 -286.464226) (xy 379.50208 -286.426132) (xy 379.474879 -286.383118)
			(xy 379.454931 -286.336298) (xy 379.442752 -286.286884) (xy 379.438657 -286.236156) (xy 379.120146 -286.236156)
			(xy 379.119651 -286.260763) (xy 379.111756 -286.30934) (xy 379.096172 -286.356021) (xy 379.073301 -286.399598)
			(xy 379.043736 -286.438942) (xy 379.008243 -286.473034) (xy 378.96774 -286.50099) (xy 378.923278 -286.522088)
			(xy 378.876007 -286.53578) (xy 378.827152 -286.541712) (xy 378.777977 -286.539731) (xy 378.729758 -286.529887)
			(xy 378.683742 -286.512435) (xy 378.641121 -286.487828) (xy 378.603 -286.456703) (xy 378.570365 -286.419866)
			(xy 378.544062 -286.37827) (xy 378.524771 -286.332994) (xy 378.512994 -286.28521) (xy 378.509034 -286.236156)
			(xy 378.190506 -286.236156) (xy 378.189994 -286.261602) (xy 378.18183 -286.311836) (xy 378.165714 -286.36011)
			(xy 378.142063 -286.405173) (xy 378.11149 -286.445859) (xy 378.074786 -286.481114) (xy 378.032902 -286.510024)
			(xy 377.986923 -286.531841) (xy 377.938039 -286.546001) (xy 377.887518 -286.552135) (xy 377.836666 -286.550086)
			(xy 377.786802 -286.539906) (xy 377.739216 -286.521859) (xy 377.695142 -286.496413) (xy 377.65572 -286.464226)
			(xy 377.621972 -286.426132) (xy 377.594771 -286.383118) (xy 377.574823 -286.336298) (xy 377.562644 -286.286884)
			(xy 377.558549 -286.236156) (xy 377.240038 -286.236156) (xy 377.239543 -286.260763) (xy 377.231648 -286.30934)
			(xy 377.216064 -286.356021) (xy 377.193193 -286.399598) (xy 377.163628 -286.438942) (xy 377.128135 -286.473034)
			(xy 377.087632 -286.50099) (xy 377.04317 -286.522088) (xy 376.995899 -286.53578) (xy 376.947044 -286.541712)
			(xy 376.897869 -286.539731) (xy 376.84965 -286.529887) (xy 376.803634 -286.512435) (xy 376.761013 -286.487828)
			(xy 376.722892 -286.456703) (xy 376.690257 -286.419866) (xy 376.663954 -286.37827) (xy 376.644663 -286.332994)
			(xy 376.632886 -286.28521) (xy 376.628926 -286.236156) (xy 376.309926 -286.236156) (xy 376.309926 -286.260992)
			(xy 376.30217 -286.309964) (xy 376.286849 -286.357121) (xy 376.26434 -286.401301) (xy 376.235197 -286.441415)
			(xy 376.200138 -286.476478) (xy 376.160026 -286.505624) (xy 376.115849 -286.528137) (xy 376.068694 -286.543463)
			(xy 376.019722 -286.551224) (xy 375.99493 -286.551624) (xy 375.969382 -286.551133) (xy 375.918952 -286.542904)
			(xy 375.870507 -286.526656) (xy 375.825313 -286.502815) (xy 375.784551 -286.472003) (xy 375.766584 -286.453834)
			(xy 375.752614 -286.439356) (xy 375.743617 -286.436391) (xy 375.724688 -286.436634) (xy 375.715784 -286.439864)
			(xy 375.71172 -286.441388) (xy 375.633488 -286.473138) (xy 375.625159 -286.477519) (xy 375.612155 -286.491101)
			(xy 375.604917 -286.508454) (xy 375.604278 -286.517842) (xy 375.604278 -286.54502) (xy 375.604443 -286.550538)
			(xy 375.606875 -286.561305) (xy 375.609104 -286.566356) (xy 375.609104 -286.56661) (xy 375.626677 -286.605142)
			(xy 375.656683 -286.684347) (xy 375.669048 -286.724852) (xy 375.669302 -286.725106) (xy 375.671334 -286.731964)
			(xy 375.674128 -286.73679) (xy 375.681748 -286.746442) (xy 375.787666 -286.85236) (xy 375.794392 -286.859593)
			(xy 375.802013 -286.877798) (xy 375.802398 -286.887666) (xy 375.802398 -286.902652) (xy 375.803414 -286.913066)
			(xy 375.806462 -286.92729) (xy 375.80697 -286.929068) (xy 375.816908 -286.954725) (xy 375.828413 -287.008524)
			(xy 375.82983 -287.036002) (xy 375.82983 -287.037018) (xy 375.830084 -287.043114) (xy 375.830084 -287.045908)
			(xy 376.148595 -287.045908) (xy 376.15269 -286.99518) (xy 376.164869 -286.945766) (xy 376.184817 -286.898946)
			(xy 376.212018 -286.855932) (xy 376.245766 -286.817838) (xy 376.285188 -286.785651) (xy 376.329262 -286.760205)
			(xy 376.376848 -286.742158) (xy 376.426712 -286.731978) (xy 376.477564 -286.729929) (xy 376.528085 -286.736063)
			(xy 376.576969 -286.750223) (xy 376.622948 -286.77204) (xy 376.664832 -286.80095) (xy 376.701536 -286.836205)
			(xy 376.732109 -286.876891) (xy 376.75576 -286.921954) (xy 376.771876 -286.970228) (xy 376.78004 -287.020462)
			(xy 376.780552 -287.045908) (xy 377.088649 -287.045908) (xy 377.092744 -286.99518) (xy 377.104923 -286.945766)
			(xy 377.124871 -286.898946) (xy 377.152072 -286.855932) (xy 377.18582 -286.817838) (xy 377.225242 -286.785651)
			(xy 377.269316 -286.760205) (xy 377.316902 -286.742158) (xy 377.366766 -286.731978) (xy 377.417618 -286.729929)
			(xy 377.468139 -286.736063) (xy 377.517023 -286.750223) (xy 377.563002 -286.77204) (xy 377.604886 -286.80095)
			(xy 377.64159 -286.836205) (xy 377.672163 -286.876891) (xy 377.695814 -286.921954) (xy 377.71193 -286.970228)
			(xy 377.720094 -287.020462) (xy 377.720606 -287.045908) (xy 377.720601 -287.046162) (xy 378.039134 -287.046162)
			(xy 378.043094 -286.997108) (xy 378.054871 -286.949324) (xy 378.074162 -286.904048) (xy 378.100465 -286.862452)
			(xy 378.1331 -286.825615) (xy 378.171221 -286.79449) (xy 378.213842 -286.769883) (xy 378.259858 -286.752431)
			(xy 378.308077 -286.742587) (xy 378.357252 -286.740606) (xy 378.406107 -286.746538) (xy 378.453378 -286.76023)
			(xy 378.49784 -286.781328) (xy 378.538343 -286.809284) (xy 378.573836 -286.843376) (xy 378.603401 -286.88272)
			(xy 378.626272 -286.926297) (xy 378.641856 -286.972978) (xy 378.649751 -287.021555) (xy 378.650241 -287.045908)
			(xy 378.968503 -287.045908) (xy 378.972598 -286.99518) (xy 378.984777 -286.945766) (xy 379.004725 -286.898946)
			(xy 379.031926 -286.855932) (xy 379.065674 -286.817838) (xy 379.105096 -286.785651) (xy 379.14917 -286.760205)
			(xy 379.196756 -286.742158) (xy 379.24662 -286.731978) (xy 379.297472 -286.729929) (xy 379.347993 -286.736063)
			(xy 379.396877 -286.750223) (xy 379.442856 -286.77204) (xy 379.48474 -286.80095) (xy 379.521444 -286.836205)
			(xy 379.552017 -286.876891) (xy 379.575668 -286.921954) (xy 379.591784 -286.970228) (xy 379.599948 -287.020462)
			(xy 379.60046 -287.045908) (xy 379.918988 -287.045908) (xy 379.922948 -286.996854) (xy 379.934725 -286.94907)
			(xy 379.954016 -286.903794) (xy 379.980319 -286.862198) (xy 380.012954 -286.825361) (xy 380.051075 -286.794236)
			(xy 380.093696 -286.769629) (xy 380.139712 -286.752177) (xy 380.187931 -286.742333) (xy 380.237106 -286.740352)
			(xy 380.285961 -286.746284) (xy 380.333232 -286.759976) (xy 380.377694 -286.781074) (xy 380.418197 -286.80903)
			(xy 380.45369 -286.843122) (xy 380.483255 -286.882466) (xy 380.506126 -286.926043) (xy 380.52171 -286.972724)
			(xy 380.529605 -287.021301) (xy 380.5301 -287.045908) (xy 380.848611 -287.045908) (xy 380.852706 -286.99518)
			(xy 380.864885 -286.945766) (xy 380.884833 -286.898946) (xy 380.912034 -286.855932) (xy 380.945782 -286.817838)
			(xy 380.985204 -286.785651) (xy 381.029278 -286.760205) (xy 381.076864 -286.742158) (xy 381.126728 -286.731978)
			(xy 381.17758 -286.729929) (xy 381.228101 -286.736063) (xy 381.276985 -286.750223) (xy 381.322964 -286.77204)
			(xy 381.364848 -286.80095) (xy 381.401552 -286.836205) (xy 381.432125 -286.876891) (xy 381.455776 -286.921954)
			(xy 381.471892 -286.970228) (xy 381.480056 -287.020462) (xy 381.480568 -287.045908) (xy 381.480563 -287.046162)
			(xy 381.799096 -287.046162) (xy 381.803056 -286.997108) (xy 381.814833 -286.949324) (xy 381.834124 -286.904048)
			(xy 381.860427 -286.862452) (xy 381.893062 -286.825615) (xy 381.931183 -286.79449) (xy 381.973804 -286.769883)
			(xy 382.01982 -286.752431) (xy 382.068039 -286.742587) (xy 382.117214 -286.740606) (xy 382.166069 -286.746538)
			(xy 382.21334 -286.76023) (xy 382.257802 -286.781328) (xy 382.298305 -286.809284) (xy 382.333798 -286.843376)
			(xy 382.363363 -286.88272) (xy 382.386234 -286.926297) (xy 382.401818 -286.972978) (xy 382.409713 -287.021555)
			(xy 382.410203 -287.045908) (xy 382.738896 -287.045908) (xy 382.742856 -286.996854) (xy 382.754633 -286.94907)
			(xy 382.773924 -286.903794) (xy 382.800227 -286.862198) (xy 382.832862 -286.825361) (xy 382.870983 -286.794236)
			(xy 382.913604 -286.769629) (xy 382.95962 -286.752177) (xy 383.007839 -286.742333) (xy 383.057014 -286.740352)
			(xy 383.105869 -286.746284) (xy 383.15314 -286.759976) (xy 383.197602 -286.781074) (xy 383.238105 -286.80903)
			(xy 383.273598 -286.843122) (xy 383.303163 -286.882466) (xy 383.326034 -286.926043) (xy 383.341618 -286.972724)
			(xy 383.349513 -287.021301) (xy 383.350008 -287.045908) (xy 383.67895 -287.045908) (xy 383.68291 -286.996854)
			(xy 383.694687 -286.94907) (xy 383.713978 -286.903794) (xy 383.740281 -286.862198) (xy 383.772916 -286.825361)
			(xy 383.811037 -286.794236) (xy 383.853658 -286.769629) (xy 383.899674 -286.752177) (xy 383.947893 -286.742333)
			(xy 383.997068 -286.740352) (xy 384.045923 -286.746284) (xy 384.093194 -286.759976) (xy 384.137656 -286.781074)
			(xy 384.178159 -286.80903) (xy 384.213652 -286.843122) (xy 384.243217 -286.882466) (xy 384.266088 -286.926043)
			(xy 384.281672 -286.972724) (xy 384.289567 -287.021301) (xy 384.290062 -287.045908) (xy 384.289567 -287.070515)
			(xy 384.281672 -287.119092) (xy 384.266088 -287.165773) (xy 384.243217 -287.20935) (xy 384.213652 -287.248694)
			(xy 384.178159 -287.282786) (xy 384.137656 -287.310742) (xy 384.093194 -287.33184) (xy 384.045923 -287.345532)
			(xy 383.997068 -287.351464) (xy 383.947893 -287.349483) (xy 383.899674 -287.339639) (xy 383.853658 -287.322187)
			(xy 383.811037 -287.29758) (xy 383.772916 -287.266455) (xy 383.740281 -287.229618) (xy 383.713978 -287.188022)
			(xy 383.694687 -287.142746) (xy 383.68291 -287.094962) (xy 383.67895 -287.045908) (xy 383.350008 -287.045908)
			(xy 383.349513 -287.070515) (xy 383.341618 -287.119092) (xy 383.326034 -287.165773) (xy 383.303163 -287.20935)
			(xy 383.273598 -287.248694) (xy 383.238105 -287.282786) (xy 383.197602 -287.310742) (xy 383.15314 -287.33184)
			(xy 383.105869 -287.345532) (xy 383.057014 -287.351464) (xy 383.007839 -287.349483) (xy 382.95962 -287.339639)
			(xy 382.913604 -287.322187) (xy 382.870983 -287.29758) (xy 382.832862 -287.266455) (xy 382.800227 -287.229618)
			(xy 382.773924 -287.188022) (xy 382.754633 -287.142746) (xy 382.742856 -287.094962) (xy 382.738896 -287.045908)
			(xy 382.410203 -287.045908) (xy 382.410208 -287.046162) (xy 382.409713 -287.070769) (xy 382.401818 -287.119346)
			(xy 382.386234 -287.166027) (xy 382.363363 -287.209604) (xy 382.333798 -287.248948) (xy 382.298305 -287.28304)
			(xy 382.257802 -287.310996) (xy 382.21334 -287.332094) (xy 382.166069 -287.345786) (xy 382.117214 -287.351718)
			(xy 382.068039 -287.349737) (xy 382.01982 -287.339893) (xy 381.973804 -287.322441) (xy 381.931183 -287.297834)
			(xy 381.893062 -287.266709) (xy 381.860427 -287.229872) (xy 381.834124 -287.188276) (xy 381.814833 -287.143)
			(xy 381.803056 -287.095216) (xy 381.799096 -287.046162) (xy 381.480563 -287.046162) (xy 381.480056 -287.071354)
			(xy 381.471892 -287.121588) (xy 381.455776 -287.169862) (xy 381.432125 -287.214925) (xy 381.401552 -287.255611)
			(xy 381.364848 -287.290866) (xy 381.322964 -287.319776) (xy 381.276985 -287.341593) (xy 381.228101 -287.355753)
			(xy 381.17758 -287.361887) (xy 381.126728 -287.359838) (xy 381.076864 -287.349658) (xy 381.029278 -287.331611)
			(xy 380.985204 -287.306165) (xy 380.945782 -287.273978) (xy 380.912034 -287.235884) (xy 380.884833 -287.19287)
			(xy 380.864885 -287.14605) (xy 380.852706 -287.096636) (xy 380.848611 -287.045908) (xy 380.5301 -287.045908)
			(xy 380.529605 -287.070515) (xy 380.52171 -287.119092) (xy 380.506126 -287.165773) (xy 380.483255 -287.20935)
			(xy 380.45369 -287.248694) (xy 380.418197 -287.282786) (xy 380.377694 -287.310742) (xy 380.333232 -287.33184)
			(xy 380.285961 -287.345532) (xy 380.237106 -287.351464) (xy 380.187931 -287.349483) (xy 380.139712 -287.339639)
			(xy 380.093696 -287.322187) (xy 380.051075 -287.29758) (xy 380.012954 -287.266455) (xy 379.980319 -287.229618)
			(xy 379.954016 -287.188022) (xy 379.934725 -287.142746) (xy 379.922948 -287.094962) (xy 379.918988 -287.045908)
			(xy 379.60046 -287.045908) (xy 379.599948 -287.071354) (xy 379.591784 -287.121588) (xy 379.575668 -287.169862)
			(xy 379.552017 -287.214925) (xy 379.521444 -287.255611) (xy 379.48474 -287.290866) (xy 379.442856 -287.319776)
			(xy 379.396877 -287.341593) (xy 379.347993 -287.355753) (xy 379.297472 -287.361887) (xy 379.24662 -287.359838)
			(xy 379.196756 -287.349658) (xy 379.14917 -287.331611) (xy 379.105096 -287.306165) (xy 379.065674 -287.273978)
			(xy 379.031926 -287.235884) (xy 379.004725 -287.19287) (xy 378.984777 -287.14605) (xy 378.972598 -287.096636)
			(xy 378.968503 -287.045908) (xy 378.650241 -287.045908) (xy 378.650246 -287.046162) (xy 378.649751 -287.070769)
			(xy 378.641856 -287.119346) (xy 378.626272 -287.166027) (xy 378.603401 -287.209604) (xy 378.573836 -287.248948)
			(xy 378.538343 -287.28304) (xy 378.49784 -287.310996) (xy 378.453378 -287.332094) (xy 378.406107 -287.345786)
			(xy 378.357252 -287.351718) (xy 378.308077 -287.349737) (xy 378.259858 -287.339893) (xy 378.213842 -287.322441)
			(xy 378.171221 -287.297834) (xy 378.1331 -287.266709) (xy 378.100465 -287.229872) (xy 378.074162 -287.188276)
			(xy 378.054871 -287.143) (xy 378.043094 -287.095216) (xy 378.039134 -287.046162) (xy 377.720601 -287.046162)
			(xy 377.720094 -287.071354) (xy 377.71193 -287.121588) (xy 377.695814 -287.169862) (xy 377.672163 -287.214925)
			(xy 377.64159 -287.255611) (xy 377.604886 -287.290866) (xy 377.563002 -287.319776) (xy 377.517023 -287.341593)
			(xy 377.468139 -287.355753) (xy 377.417618 -287.361887) (xy 377.366766 -287.359838) (xy 377.316902 -287.349658)
			(xy 377.269316 -287.331611) (xy 377.225242 -287.306165) (xy 377.18582 -287.273978) (xy 377.152072 -287.235884)
			(xy 377.124871 -287.19287) (xy 377.104923 -287.14605) (xy 377.092744 -287.096636) (xy 377.088649 -287.045908)
			(xy 376.780552 -287.045908) (xy 376.78004 -287.071354) (xy 376.771876 -287.121588) (xy 376.75576 -287.169862)
			(xy 376.732109 -287.214925) (xy 376.701536 -287.255611) (xy 376.664832 -287.290866) (xy 376.622948 -287.319776)
			(xy 376.576969 -287.341593) (xy 376.528085 -287.355753) (xy 376.477564 -287.361887) (xy 376.426712 -287.359838)
			(xy 376.376848 -287.349658) (xy 376.329262 -287.331611) (xy 376.285188 -287.306165) (xy 376.245766 -287.273978)
			(xy 376.212018 -287.235884) (xy 376.184817 -287.19287) (xy 376.164869 -287.14605) (xy 376.15269 -287.096636)
			(xy 376.148595 -287.045908) (xy 375.830084 -287.045908) (xy 375.829693 -287.068262) (xy 375.823173 -287.112493)
			(xy 375.810274 -287.1553) (xy 375.801128 -287.175702) (xy 375.799858 -287.178496) (xy 375.786922 -287.203885)
			(xy 375.753103 -287.249738) (xy 375.711365 -287.28852) (xy 375.68759 -287.304226) (xy 375.68505 -287.307782)
			(xy 375.670826 -287.36163) (xy 375.652792 -287.41751) (xy 375.649998 -287.425638) (xy 375.649998 -287.532572)
			(xy 375.650506 -287.53943) (xy 375.652742 -287.550789) (xy 375.665547 -287.570036) (xy 375.675144 -287.576514)
			(xy 375.676668 -287.577276) (xy 375.75363 -287.61563) (xy 375.760072 -287.618571) (xy 375.773993 -287.621141)
			(xy 375.781062 -287.62071) (xy 375.78538 -287.620202) (xy 375.802783 -287.605316) (xy 375.841076 -287.580202)
			(xy 375.882595 -287.560882) (xy 375.92647 -287.547761) (xy 375.971779 -287.541115) (xy 375.994676 -287.5407)
			(xy 375.99493 -287.5407) (xy 376.019721 -287.541188) (xy 376.068691 -287.548949) (xy 376.115844 -287.564274)
			(xy 376.16002 -287.586786) (xy 376.20013 -287.615932) (xy 376.235188 -287.650992) (xy 376.26433 -287.691106)
			(xy 376.286838 -287.735284) (xy 376.302158 -287.782438) (xy 376.309914 -287.831409) (xy 376.309914 -287.856168)
			(xy 376.628926 -287.856168) (xy 376.632886 -287.807114) (xy 376.644663 -287.75933) (xy 376.663954 -287.714054)
			(xy 376.690257 -287.672458) (xy 376.722892 -287.635621) (xy 376.761013 -287.604496) (xy 376.803634 -287.579889)
			(xy 376.84965 -287.562437) (xy 376.897869 -287.552593) (xy 376.947044 -287.550612) (xy 376.995899 -287.556544)
			(xy 377.04317 -287.570236) (xy 377.087632 -287.591334) (xy 377.128135 -287.61929) (xy 377.163628 -287.653382)
			(xy 377.193193 -287.692726) (xy 377.216064 -287.736303) (xy 377.231648 -287.782984) (xy 377.239543 -287.831561)
			(xy 377.240038 -287.856168) (xy 377.558549 -287.856168) (xy 377.562644 -287.80544) (xy 377.574823 -287.756026)
			(xy 377.594771 -287.709206) (xy 377.621972 -287.666192) (xy 377.65572 -287.628098) (xy 377.695142 -287.595911)
			(xy 377.739216 -287.570465) (xy 377.786802 -287.552418) (xy 377.836666 -287.542238) (xy 377.887518 -287.540189)
			(xy 377.938039 -287.546323) (xy 377.986923 -287.560483) (xy 378.032902 -287.5823) (xy 378.074786 -287.61121)
			(xy 378.11149 -287.646465) (xy 378.142063 -287.687151) (xy 378.165714 -287.732214) (xy 378.18183 -287.780488)
			(xy 378.189994 -287.830722) (xy 378.190506 -287.856168) (xy 379.438657 -287.856168) (xy 379.442752 -287.80544)
			(xy 379.454931 -287.756026) (xy 379.474879 -287.709206) (xy 379.50208 -287.666192) (xy 379.535828 -287.628098)
			(xy 379.57525 -287.595911) (xy 379.619324 -287.570465) (xy 379.66691 -287.552418) (xy 379.716774 -287.542238)
			(xy 379.767626 -287.540189) (xy 379.818147 -287.546323) (xy 379.867031 -287.560483) (xy 379.91301 -287.5823)
			(xy 379.954894 -287.61121) (xy 379.991598 -287.646465) (xy 380.022171 -287.687151) (xy 380.045822 -287.732214)
			(xy 380.061938 -287.780488) (xy 380.070102 -287.830722) (xy 380.070614 -287.856168) (xy 380.378711 -287.856168)
			(xy 380.382806 -287.80544) (xy 380.394985 -287.756026) (xy 380.414933 -287.709206) (xy 380.442134 -287.666192)
			(xy 380.475882 -287.628098) (xy 380.515304 -287.595911) (xy 380.559378 -287.570465) (xy 380.606964 -287.552418)
			(xy 380.656828 -287.542238) (xy 380.70768 -287.540189) (xy 380.758201 -287.546323) (xy 380.807085 -287.560483)
			(xy 380.853064 -287.5823) (xy 380.894948 -287.61121) (xy 380.931652 -287.646465) (xy 380.962225 -287.687151)
			(xy 380.985876 -287.732214) (xy 381.001992 -287.780488) (xy 381.010156 -287.830722) (xy 381.010668 -287.856168)
			(xy 381.328942 -287.856168) (xy 381.332902 -287.807114) (xy 381.344679 -287.75933) (xy 381.36397 -287.714054)
			(xy 381.390273 -287.672458) (xy 381.422908 -287.635621) (xy 381.461029 -287.604496) (xy 381.50365 -287.579889)
			(xy 381.549666 -287.562437) (xy 381.597885 -287.552593) (xy 381.64706 -287.550612) (xy 381.695915 -287.556544)
			(xy 381.743186 -287.570236) (xy 381.787648 -287.591334) (xy 381.828151 -287.61929) (xy 381.863644 -287.653382)
			(xy 381.893209 -287.692726) (xy 381.91608 -287.736303) (xy 381.931664 -287.782984) (xy 381.939559 -287.831561)
			(xy 381.940054 -287.856168) (xy 382.268996 -287.856168) (xy 382.272956 -287.807114) (xy 382.284733 -287.75933)
			(xy 382.304024 -287.714054) (xy 382.330327 -287.672458) (xy 382.362962 -287.635621) (xy 382.401083 -287.604496)
			(xy 382.443704 -287.579889) (xy 382.48972 -287.562437) (xy 382.537939 -287.552593) (xy 382.587114 -287.550612)
			(xy 382.635969 -287.556544) (xy 382.68324 -287.570236) (xy 382.727702 -287.591334) (xy 382.768205 -287.61929)
			(xy 382.803698 -287.653382) (xy 382.833263 -287.692726) (xy 382.856134 -287.736303) (xy 382.871718 -287.782984)
			(xy 382.879613 -287.831561) (xy 382.880108 -287.856168) (xy 383.20905 -287.856168) (xy 383.21301 -287.807114)
			(xy 383.224787 -287.75933) (xy 383.244078 -287.714054) (xy 383.270381 -287.672458) (xy 383.303016 -287.635621)
			(xy 383.341137 -287.604496) (xy 383.383758 -287.579889) (xy 383.429774 -287.562437) (xy 383.477993 -287.552593)
			(xy 383.527168 -287.550612) (xy 383.576023 -287.556544) (xy 383.623294 -287.570236) (xy 383.667756 -287.591334)
			(xy 383.708259 -287.61929) (xy 383.743752 -287.653382) (xy 383.773317 -287.692726) (xy 383.796188 -287.736303)
			(xy 383.811772 -287.782984) (xy 383.819667 -287.831561) (xy 383.820162 -287.856168) (xy 384.149104 -287.856168)
			(xy 384.153064 -287.807114) (xy 384.164841 -287.75933) (xy 384.184132 -287.714054) (xy 384.210435 -287.672458)
			(xy 384.24307 -287.635621) (xy 384.281191 -287.604496) (xy 384.323812 -287.579889) (xy 384.369828 -287.562437)
			(xy 384.418047 -287.552593) (xy 384.467222 -287.550612) (xy 384.516077 -287.556544) (xy 384.563348 -287.570236)
			(xy 384.60781 -287.591334) (xy 384.648313 -287.61929) (xy 384.683806 -287.653382) (xy 384.713371 -287.692726)
			(xy 384.736242 -287.736303) (xy 384.751826 -287.782984) (xy 384.759721 -287.831561) (xy 384.760216 -287.856168)
			(xy 384.759721 -287.880775) (xy 384.751826 -287.929352) (xy 384.736242 -287.976033) (xy 384.713371 -288.01961)
			(xy 384.683806 -288.058954) (xy 384.648313 -288.093046) (xy 384.60781 -288.121002) (xy 384.563348 -288.1421)
			(xy 384.516077 -288.155792) (xy 384.467222 -288.161724) (xy 384.418047 -288.159743) (xy 384.369828 -288.149899)
			(xy 384.323812 -288.132447) (xy 384.281191 -288.10784) (xy 384.24307 -288.076715) (xy 384.210435 -288.039878)
			(xy 384.184132 -287.998282) (xy 384.164841 -287.953006) (xy 384.153064 -287.905222) (xy 384.149104 -287.856168)
			(xy 383.820162 -287.856168) (xy 383.819667 -287.880775) (xy 383.811772 -287.929352) (xy 383.796188 -287.976033)
			(xy 383.773317 -288.01961) (xy 383.743752 -288.058954) (xy 383.708259 -288.093046) (xy 383.667756 -288.121002)
			(xy 383.623294 -288.1421) (xy 383.576023 -288.155792) (xy 383.527168 -288.161724) (xy 383.477993 -288.159743)
			(xy 383.429774 -288.149899) (xy 383.383758 -288.132447) (xy 383.341137 -288.10784) (xy 383.303016 -288.076715)
			(xy 383.270381 -288.039878) (xy 383.244078 -287.998282) (xy 383.224787 -287.953006) (xy 383.21301 -287.905222)
			(xy 383.20905 -287.856168) (xy 382.880108 -287.856168) (xy 382.879613 -287.880775) (xy 382.871718 -287.929352)
			(xy 382.856134 -287.976033) (xy 382.833263 -288.01961) (xy 382.803698 -288.058954) (xy 382.768205 -288.093046)
			(xy 382.727702 -288.121002) (xy 382.68324 -288.1421) (xy 382.635969 -288.155792) (xy 382.587114 -288.161724)
			(xy 382.537939 -288.159743) (xy 382.48972 -288.149899) (xy 382.443704 -288.132447) (xy 382.401083 -288.10784)
			(xy 382.362962 -288.076715) (xy 382.330327 -288.039878) (xy 382.304024 -287.998282) (xy 382.284733 -287.953006)
			(xy 382.272956 -287.905222) (xy 382.268996 -287.856168) (xy 381.940054 -287.856168) (xy 381.939559 -287.880775)
			(xy 381.931664 -287.929352) (xy 381.91608 -287.976033) (xy 381.893209 -288.01961) (xy 381.863644 -288.058954)
			(xy 381.828151 -288.093046) (xy 381.787648 -288.121002) (xy 381.743186 -288.1421) (xy 381.695915 -288.155792)
			(xy 381.64706 -288.161724) (xy 381.597885 -288.159743) (xy 381.549666 -288.149899) (xy 381.50365 -288.132447)
			(xy 381.461029 -288.10784) (xy 381.422908 -288.076715) (xy 381.390273 -288.039878) (xy 381.36397 -287.998282)
			(xy 381.344679 -287.953006) (xy 381.332902 -287.905222) (xy 381.328942 -287.856168) (xy 381.010668 -287.856168)
			(xy 381.010156 -287.881614) (xy 381.001992 -287.931848) (xy 380.985876 -287.980122) (xy 380.962225 -288.025185)
			(xy 380.931652 -288.065871) (xy 380.894948 -288.101126) (xy 380.853064 -288.130036) (xy 380.807085 -288.151853)
			(xy 380.758201 -288.166013) (xy 380.70768 -288.172147) (xy 380.656828 -288.170098) (xy 380.606964 -288.159918)
			(xy 380.559378 -288.141871) (xy 380.515304 -288.116425) (xy 380.475882 -288.084238) (xy 380.442134 -288.046144)
			(xy 380.414933 -288.00313) (xy 380.394985 -287.95631) (xy 380.382806 -287.906896) (xy 380.378711 -287.856168)
			(xy 380.070614 -287.856168) (xy 380.070102 -287.881614) (xy 380.061938 -287.931848) (xy 380.045822 -287.980122)
			(xy 380.022171 -288.025185) (xy 379.991598 -288.065871) (xy 379.954894 -288.101126) (xy 379.91301 -288.130036)
			(xy 379.867031 -288.151853) (xy 379.818147 -288.166013) (xy 379.767626 -288.172147) (xy 379.716774 -288.170098)
			(xy 379.66691 -288.159918) (xy 379.619324 -288.141871) (xy 379.57525 -288.116425) (xy 379.535828 -288.084238)
			(xy 379.50208 -288.046144) (xy 379.474879 -288.00313) (xy 379.454931 -287.95631) (xy 379.442752 -287.906896)
			(xy 379.438657 -287.856168) (xy 378.190506 -287.856168) (xy 378.189994 -287.881614) (xy 378.18183 -287.931848)
			(xy 378.165714 -287.980122) (xy 378.142063 -288.025185) (xy 378.11149 -288.065871) (xy 378.074786 -288.101126)
			(xy 378.032902 -288.130036) (xy 377.986923 -288.151853) (xy 377.938039 -288.166013) (xy 377.887518 -288.172147)
			(xy 377.836666 -288.170098) (xy 377.786802 -288.159918) (xy 377.739216 -288.141871) (xy 377.695142 -288.116425)
			(xy 377.65572 -288.084238) (xy 377.621972 -288.046144) (xy 377.594771 -288.00313) (xy 377.574823 -287.95631)
			(xy 377.562644 -287.906896) (xy 377.558549 -287.856168) (xy 377.240038 -287.856168) (xy 377.239543 -287.880775)
			(xy 377.231648 -287.929352) (xy 377.216064 -287.976033) (xy 377.193193 -288.01961) (xy 377.163628 -288.058954)
			(xy 377.128135 -288.093046) (xy 377.087632 -288.121002) (xy 377.04317 -288.1421) (xy 376.995899 -288.155792)
			(xy 376.947044 -288.161724) (xy 376.897869 -288.159743) (xy 376.84965 -288.149899) (xy 376.803634 -288.132447)
			(xy 376.761013 -288.10784) (xy 376.722892 -288.076715) (xy 376.690257 -288.039878) (xy 376.663954 -287.998282)
			(xy 376.644663 -287.953006) (xy 376.632886 -287.905222) (xy 376.628926 -287.856168) (xy 376.309914 -287.856168)
			(xy 376.309914 -287.880991) (xy 376.302158 -287.929962) (xy 376.286838 -287.977116) (xy 376.26433 -288.021294)
			(xy 376.235188 -288.061408) (xy 376.20013 -288.096468) (xy 376.16002 -288.125614) (xy 376.115844 -288.148126)
			(xy 376.068691 -288.163451) (xy 376.019721 -288.171212) (xy 375.99493 -288.171636) (xy 375.994422 -288.171636)
			(xy 375.968395 -288.171082) (xy 375.917051 -288.162504) (xy 375.867808 -288.145625) (xy 375.821998 -288.120902)
			(xy 375.801128 -288.105342) (xy 375.78538 -288.092896) (xy 375.777045 -288.091504) (xy 375.760298 -288.093699)
			(xy 375.752614 -288.097214) (xy 375.678192 -288.134298) (xy 375.677938 -288.134552) (xy 375.671729 -288.137852)
			(xy 375.661281 -288.147255) (xy 375.657364 -288.153094) (xy 375.653808 -288.158682) (xy 375.649998 -288.172398)
			(xy 375.649998 -288.286444) (xy 375.653046 -288.294826) (xy 375.658126 -288.309304) (xy 375.659904 -288.314638)
			(xy 375.669048 -288.32937) (xy 375.676414 -288.338768) (xy 375.841006 -288.50336) (xy 375.847728 -288.510595)
			(xy 375.855342 -288.5288) (xy 375.855738 -288.538666) (xy 375.855738 -288.66592) (xy 376.148595 -288.66592)
			(xy 376.15269 -288.615192) (xy 376.164869 -288.565778) (xy 376.184817 -288.518958) (xy 376.212018 -288.475944)
			(xy 376.245766 -288.43785) (xy 376.285188 -288.405663) (xy 376.329262 -288.380217) (xy 376.376848 -288.36217)
			(xy 376.426712 -288.35199) (xy 376.477564 -288.349941) (xy 376.528085 -288.356075) (xy 376.576969 -288.370235)
			(xy 376.622948 -288.392052) (xy 376.664832 -288.420962) (xy 376.701536 -288.456217) (xy 376.732109 -288.496903)
			(xy 376.75576 -288.541966) (xy 376.771876 -288.59024) (xy 376.78004 -288.640474) (xy 376.780552 -288.66592)
			(xy 377.088649 -288.66592) (xy 377.092744 -288.615192) (xy 377.104923 -288.565778) (xy 377.124871 -288.518958)
			(xy 377.152072 -288.475944) (xy 377.18582 -288.43785) (xy 377.225242 -288.405663) (xy 377.269316 -288.380217)
			(xy 377.316902 -288.36217) (xy 377.366766 -288.35199) (xy 377.417618 -288.349941) (xy 377.468139 -288.356075)
			(xy 377.517023 -288.370235) (xy 377.563002 -288.392052) (xy 377.604886 -288.420962) (xy 377.64159 -288.456217)
			(xy 377.672163 -288.496903) (xy 377.695814 -288.541966) (xy 377.71193 -288.59024) (xy 377.720094 -288.640474)
			(xy 377.720606 -288.66592) (xy 378.039134 -288.66592) (xy 378.043094 -288.616866) (xy 378.054871 -288.569082)
			(xy 378.074162 -288.523806) (xy 378.100465 -288.48221) (xy 378.1331 -288.445373) (xy 378.171221 -288.414248)
			(xy 378.213842 -288.389641) (xy 378.259858 -288.372189) (xy 378.308077 -288.362345) (xy 378.357252 -288.360364)
			(xy 378.406107 -288.366296) (xy 378.453378 -288.379988) (xy 378.49784 -288.401086) (xy 378.538343 -288.429042)
			(xy 378.573836 -288.463134) (xy 378.603401 -288.502478) (xy 378.626272 -288.546055) (xy 378.641856 -288.592736)
			(xy 378.649751 -288.641313) (xy 378.650246 -288.66592) (xy 378.968503 -288.66592) (xy 378.972598 -288.615192)
			(xy 378.984777 -288.565778) (xy 379.004725 -288.518958) (xy 379.031926 -288.475944) (xy 379.065674 -288.43785)
			(xy 379.105096 -288.405663) (xy 379.14917 -288.380217) (xy 379.196756 -288.36217) (xy 379.24662 -288.35199)
			(xy 379.297472 -288.349941) (xy 379.347993 -288.356075) (xy 379.396877 -288.370235) (xy 379.442856 -288.392052)
			(xy 379.48474 -288.420962) (xy 379.521444 -288.456217) (xy 379.552017 -288.496903) (xy 379.575668 -288.541966)
			(xy 379.591784 -288.59024) (xy 379.599948 -288.640474) (xy 379.60046 -288.66592) (xy 379.918988 -288.66592)
			(xy 379.922948 -288.616866) (xy 379.934725 -288.569082) (xy 379.954016 -288.523806) (xy 379.980319 -288.48221)
			(xy 380.012954 -288.445373) (xy 380.051075 -288.414248) (xy 380.093696 -288.389641) (xy 380.139712 -288.372189)
			(xy 380.187931 -288.362345) (xy 380.237106 -288.360364) (xy 380.285961 -288.366296) (xy 380.333232 -288.379988)
			(xy 380.377694 -288.401086) (xy 380.418197 -288.429042) (xy 380.45369 -288.463134) (xy 380.483255 -288.502478)
			(xy 380.506126 -288.546055) (xy 380.52171 -288.592736) (xy 380.529605 -288.641313) (xy 380.5301 -288.66592)
			(xy 380.848611 -288.66592) (xy 380.852706 -288.615192) (xy 380.864885 -288.565778) (xy 380.884833 -288.518958)
			(xy 380.912034 -288.475944) (xy 380.945782 -288.43785) (xy 380.985204 -288.405663) (xy 381.029278 -288.380217)
			(xy 381.076864 -288.36217) (xy 381.126728 -288.35199) (xy 381.17758 -288.349941) (xy 381.228101 -288.356075)
			(xy 381.276985 -288.370235) (xy 381.322964 -288.392052) (xy 381.364848 -288.420962) (xy 381.401552 -288.456217)
			(xy 381.432125 -288.496903) (xy 381.455776 -288.541966) (xy 381.471892 -288.59024) (xy 381.480056 -288.640474)
			(xy 381.480568 -288.66592) (xy 381.799096 -288.66592) (xy 381.803056 -288.616866) (xy 381.814833 -288.569082)
			(xy 381.834124 -288.523806) (xy 381.860427 -288.48221) (xy 381.893062 -288.445373) (xy 381.931183 -288.414248)
			(xy 381.973804 -288.389641) (xy 382.01982 -288.372189) (xy 382.068039 -288.362345) (xy 382.117214 -288.360364)
			(xy 382.166069 -288.366296) (xy 382.21334 -288.379988) (xy 382.257802 -288.401086) (xy 382.298305 -288.429042)
			(xy 382.333798 -288.463134) (xy 382.363363 -288.502478) (xy 382.386234 -288.546055) (xy 382.401818 -288.592736)
			(xy 382.409713 -288.641313) (xy 382.410208 -288.66592) (xy 382.738896 -288.66592) (xy 382.742856 -288.616866)
			(xy 382.754633 -288.569082) (xy 382.773924 -288.523806) (xy 382.800227 -288.48221) (xy 382.832862 -288.445373)
			(xy 382.870983 -288.414248) (xy 382.913604 -288.389641) (xy 382.95962 -288.372189) (xy 383.007839 -288.362345)
			(xy 383.057014 -288.360364) (xy 383.105869 -288.366296) (xy 383.15314 -288.379988) (xy 383.197602 -288.401086)
			(xy 383.238105 -288.429042) (xy 383.273598 -288.463134) (xy 383.303163 -288.502478) (xy 383.326034 -288.546055)
			(xy 383.341618 -288.592736) (xy 383.349513 -288.641313) (xy 383.350008 -288.66592) (xy 383.67895 -288.66592)
			(xy 383.68291 -288.616866) (xy 383.694687 -288.569082) (xy 383.713978 -288.523806) (xy 383.740281 -288.48221)
			(xy 383.772916 -288.445373) (xy 383.811037 -288.414248) (xy 383.853658 -288.389641) (xy 383.899674 -288.372189)
			(xy 383.947893 -288.362345) (xy 383.997068 -288.360364) (xy 384.045923 -288.366296) (xy 384.093194 -288.379988)
			(xy 384.137656 -288.401086) (xy 384.178159 -288.429042) (xy 384.213652 -288.463134) (xy 384.243217 -288.502478)
			(xy 384.266088 -288.546055) (xy 384.281672 -288.592736) (xy 384.289567 -288.641313) (xy 384.290062 -288.66592)
			(xy 384.289567 -288.690527) (xy 384.281672 -288.739104) (xy 384.266088 -288.785785) (xy 384.243217 -288.829362)
			(xy 384.213652 -288.868706) (xy 384.178159 -288.902798) (xy 384.137656 -288.930754) (xy 384.093194 -288.951852)
			(xy 384.045923 -288.965544) (xy 383.997068 -288.971476) (xy 383.947893 -288.969495) (xy 383.899674 -288.959651)
			(xy 383.853658 -288.942199) (xy 383.811037 -288.917592) (xy 383.772916 -288.886467) (xy 383.740281 -288.84963)
			(xy 383.713978 -288.808034) (xy 383.694687 -288.762758) (xy 383.68291 -288.714974) (xy 383.67895 -288.66592)
			(xy 383.350008 -288.66592) (xy 383.349513 -288.690527) (xy 383.341618 -288.739104) (xy 383.326034 -288.785785)
			(xy 383.303163 -288.829362) (xy 383.273598 -288.868706) (xy 383.238105 -288.902798) (xy 383.197602 -288.930754)
			(xy 383.15314 -288.951852) (xy 383.105869 -288.965544) (xy 383.057014 -288.971476) (xy 383.007839 -288.969495)
			(xy 382.95962 -288.959651) (xy 382.913604 -288.942199) (xy 382.870983 -288.917592) (xy 382.832862 -288.886467)
			(xy 382.800227 -288.84963) (xy 382.773924 -288.808034) (xy 382.754633 -288.762758) (xy 382.742856 -288.714974)
			(xy 382.738896 -288.66592) (xy 382.410208 -288.66592) (xy 382.409713 -288.690527) (xy 382.401818 -288.739104)
			(xy 382.386234 -288.785785) (xy 382.363363 -288.829362) (xy 382.333798 -288.868706) (xy 382.298305 -288.902798)
			(xy 382.257802 -288.930754) (xy 382.21334 -288.951852) (xy 382.166069 -288.965544) (xy 382.117214 -288.971476)
			(xy 382.068039 -288.969495) (xy 382.01982 -288.959651) (xy 381.973804 -288.942199) (xy 381.931183 -288.917592)
			(xy 381.893062 -288.886467) (xy 381.860427 -288.84963) (xy 381.834124 -288.808034) (xy 381.814833 -288.762758)
			(xy 381.803056 -288.714974) (xy 381.799096 -288.66592) (xy 381.480568 -288.66592) (xy 381.480056 -288.691366)
			(xy 381.471892 -288.7416) (xy 381.455776 -288.789874) (xy 381.432125 -288.834937) (xy 381.401552 -288.875623)
			(xy 381.364848 -288.910878) (xy 381.322964 -288.939788) (xy 381.276985 -288.961605) (xy 381.228101 -288.975765)
			(xy 381.17758 -288.981899) (xy 381.126728 -288.97985) (xy 381.076864 -288.96967) (xy 381.029278 -288.951623)
			(xy 380.985204 -288.926177) (xy 380.945782 -288.89399) (xy 380.912034 -288.855896) (xy 380.884833 -288.812882)
			(xy 380.864885 -288.766062) (xy 380.852706 -288.716648) (xy 380.848611 -288.66592) (xy 380.5301 -288.66592)
			(xy 380.529605 -288.690527) (xy 380.52171 -288.739104) (xy 380.506126 -288.785785) (xy 380.483255 -288.829362)
			(xy 380.45369 -288.868706) (xy 380.418197 -288.902798) (xy 380.377694 -288.930754) (xy 380.333232 -288.951852)
			(xy 380.285961 -288.965544) (xy 380.237106 -288.971476) (xy 380.187931 -288.969495) (xy 380.139712 -288.959651)
			(xy 380.093696 -288.942199) (xy 380.051075 -288.917592) (xy 380.012954 -288.886467) (xy 379.980319 -288.84963)
			(xy 379.954016 -288.808034) (xy 379.934725 -288.762758) (xy 379.922948 -288.714974) (xy 379.918988 -288.66592)
			(xy 379.60046 -288.66592) (xy 379.599948 -288.691366) (xy 379.591784 -288.7416) (xy 379.575668 -288.789874)
			(xy 379.552017 -288.834937) (xy 379.521444 -288.875623) (xy 379.48474 -288.910878) (xy 379.442856 -288.939788)
			(xy 379.396877 -288.961605) (xy 379.347993 -288.975765) (xy 379.297472 -288.981899) (xy 379.24662 -288.97985)
			(xy 379.196756 -288.96967) (xy 379.14917 -288.951623) (xy 379.105096 -288.926177) (xy 379.065674 -288.89399)
			(xy 379.031926 -288.855896) (xy 379.004725 -288.812882) (xy 378.984777 -288.766062) (xy 378.972598 -288.716648)
			(xy 378.968503 -288.66592) (xy 378.650246 -288.66592) (xy 378.649751 -288.690527) (xy 378.641856 -288.739104)
			(xy 378.626272 -288.785785) (xy 378.603401 -288.829362) (xy 378.573836 -288.868706) (xy 378.538343 -288.902798)
			(xy 378.49784 -288.930754) (xy 378.453378 -288.951852) (xy 378.406107 -288.965544) (xy 378.357252 -288.971476)
			(xy 378.308077 -288.969495) (xy 378.259858 -288.959651) (xy 378.213842 -288.942199) (xy 378.171221 -288.917592)
			(xy 378.1331 -288.886467) (xy 378.100465 -288.84963) (xy 378.074162 -288.808034) (xy 378.054871 -288.762758)
			(xy 378.043094 -288.714974) (xy 378.039134 -288.66592) (xy 377.720606 -288.66592) (xy 377.720094 -288.691366)
			(xy 377.71193 -288.7416) (xy 377.695814 -288.789874) (xy 377.672163 -288.834937) (xy 377.64159 -288.875623)
			(xy 377.604886 -288.910878) (xy 377.563002 -288.939788) (xy 377.517023 -288.961605) (xy 377.468139 -288.975765)
			(xy 377.417618 -288.981899) (xy 377.366766 -288.97985) (xy 377.316902 -288.96967) (xy 377.269316 -288.951623)
			(xy 377.225242 -288.926177) (xy 377.18582 -288.89399) (xy 377.152072 -288.855896) (xy 377.124871 -288.812882)
			(xy 377.104923 -288.766062) (xy 377.092744 -288.716648) (xy 377.088649 -288.66592) (xy 376.780552 -288.66592)
			(xy 376.78004 -288.691366) (xy 376.771876 -288.7416) (xy 376.75576 -288.789874) (xy 376.732109 -288.834937)
			(xy 376.701536 -288.875623) (xy 376.664832 -288.910878) (xy 376.622948 -288.939788) (xy 376.576969 -288.961605)
			(xy 376.528085 -288.975765) (xy 376.477564 -288.981899) (xy 376.426712 -288.97985) (xy 376.376848 -288.96967)
			(xy 376.329262 -288.951623) (xy 376.285188 -288.926177) (xy 376.245766 -288.89399) (xy 376.212018 -288.855896)
			(xy 376.184817 -288.812882) (xy 376.164869 -288.766062) (xy 376.15269 -288.716648) (xy 376.148595 -288.66592)
			(xy 375.855738 -288.66592) (xy 375.855738 -288.774378) (xy 375.855202 -288.784216) (xy 375.847617 -288.802378)
			(xy 375.841006 -288.809684) (xy 375.797318 -288.853372) (xy 375.794778 -288.856928) (xy 375.778078 -288.879511)
			(xy 375.73837 -288.919227) (xy 375.715784 -288.935922) (xy 375.713752 -288.937446) (xy 375.712482 -288.938208)
			(xy 375.680224 -288.970466) (xy 375.672858 -288.979864) (xy 375.66981 -288.98469) (xy 375.66854 -288.989008)
			(xy 375.667778 -288.991548) (xy 375.663968 -289.003994) (xy 375.663968 -289.004502) (xy 375.658634 -289.020758)
			(xy 375.642048 -289.069032) (xy 375.60135 -289.16265) (xy 375.577354 -289.207702) (xy 375.574306 -289.21329)
			(xy 375.571258 -289.225228) (xy 375.571258 -289.475926) (xy 375.678695 -289.475926) (xy 375.68279 -289.425198)
			(xy 375.694969 -289.375784) (xy 375.714917 -289.328964) (xy 375.742118 -289.28595) (xy 375.775866 -289.247856)
			(xy 375.815288 -289.215669) (xy 375.859362 -289.190223) (xy 375.906948 -289.172176) (xy 375.956812 -289.161996)
			(xy 376.007664 -289.159947) (xy 376.058185 -289.166081) (xy 376.107069 -289.180241) (xy 376.153048 -289.202058)
			(xy 376.194932 -289.230968) (xy 376.231636 -289.266223) (xy 376.262209 -289.306909) (xy 376.28586 -289.351972)
			(xy 376.301976 -289.400246) (xy 376.31014 -289.45048) (xy 376.310652 -289.475926) (xy 376.628926 -289.475926)
			(xy 376.632886 -289.426872) (xy 376.644663 -289.379088) (xy 376.663954 -289.333812) (xy 376.690257 -289.292216)
			(xy 376.722892 -289.255379) (xy 376.761013 -289.224254) (xy 376.803634 -289.199647) (xy 376.84965 -289.182195)
			(xy 376.897869 -289.172351) (xy 376.947044 -289.17037) (xy 376.995899 -289.176302) (xy 377.04317 -289.189994)
			(xy 377.087632 -289.211092) (xy 377.128135 -289.239048) (xy 377.163628 -289.27314) (xy 377.193193 -289.312484)
			(xy 377.216064 -289.356061) (xy 377.231648 -289.402742) (xy 377.239543 -289.451319) (xy 377.240038 -289.475926)
			(xy 377.558549 -289.475926) (xy 377.562644 -289.425198) (xy 377.574823 -289.375784) (xy 377.594771 -289.328964)
			(xy 377.621972 -289.28595) (xy 377.65572 -289.247856) (xy 377.695142 -289.215669) (xy 377.739216 -289.190223)
			(xy 377.786802 -289.172176) (xy 377.836666 -289.161996) (xy 377.887518 -289.159947) (xy 377.938039 -289.166081)
			(xy 377.986923 -289.180241) (xy 378.032902 -289.202058) (xy 378.074786 -289.230968) (xy 378.11149 -289.266223)
			(xy 378.142063 -289.306909) (xy 378.165714 -289.351972) (xy 378.18183 -289.400246) (xy 378.189994 -289.45048)
			(xy 378.190506 -289.475926) (xy 378.509034 -289.475926) (xy 378.512994 -289.426872) (xy 378.524771 -289.379088)
			(xy 378.544062 -289.333812) (xy 378.570365 -289.292216) (xy 378.603 -289.255379) (xy 378.641121 -289.224254)
			(xy 378.683742 -289.199647) (xy 378.729758 -289.182195) (xy 378.777977 -289.172351) (xy 378.827152 -289.17037)
			(xy 378.876007 -289.176302) (xy 378.923278 -289.189994) (xy 378.96774 -289.211092) (xy 379.008243 -289.239048)
			(xy 379.043736 -289.27314) (xy 379.073301 -289.312484) (xy 379.096172 -289.356061) (xy 379.111756 -289.402742)
			(xy 379.119651 -289.451319) (xy 379.120146 -289.475926) (xy 379.438657 -289.475926) (xy 379.442752 -289.425198)
			(xy 379.454931 -289.375784) (xy 379.474879 -289.328964) (xy 379.50208 -289.28595) (xy 379.535828 -289.247856)
			(xy 379.57525 -289.215669) (xy 379.619324 -289.190223) (xy 379.66691 -289.172176) (xy 379.716774 -289.161996)
			(xy 379.767626 -289.159947) (xy 379.818147 -289.166081) (xy 379.867031 -289.180241) (xy 379.91301 -289.202058)
			(xy 379.954894 -289.230968) (xy 379.991598 -289.266223) (xy 380.022171 -289.306909) (xy 380.045822 -289.351972)
			(xy 380.061938 -289.400246) (xy 380.070102 -289.45048) (xy 380.070614 -289.475926) (xy 380.378711 -289.475926)
			(xy 380.382806 -289.425198) (xy 380.394985 -289.375784) (xy 380.414933 -289.328964) (xy 380.442134 -289.28595)
			(xy 380.475882 -289.247856) (xy 380.515304 -289.215669) (xy 380.559378 -289.190223) (xy 380.606964 -289.172176)
			(xy 380.656828 -289.161996) (xy 380.70768 -289.159947) (xy 380.758201 -289.166081) (xy 380.807085 -289.180241)
			(xy 380.853064 -289.202058) (xy 380.894948 -289.230968) (xy 380.931652 -289.266223) (xy 380.962225 -289.306909)
			(xy 380.985876 -289.351972) (xy 381.001992 -289.400246) (xy 381.010156 -289.45048) (xy 381.010668 -289.475926)
			(xy 381.328942 -289.475926) (xy 381.332902 -289.426872) (xy 381.344679 -289.379088) (xy 381.36397 -289.333812)
			(xy 381.390273 -289.292216) (xy 381.422908 -289.255379) (xy 381.461029 -289.224254) (xy 381.50365 -289.199647)
			(xy 381.549666 -289.182195) (xy 381.597885 -289.172351) (xy 381.64706 -289.17037) (xy 381.695915 -289.176302)
			(xy 381.743186 -289.189994) (xy 381.787648 -289.211092) (xy 381.828151 -289.239048) (xy 381.863644 -289.27314)
			(xy 381.893209 -289.312484) (xy 381.91608 -289.356061) (xy 381.931664 -289.402742) (xy 381.939559 -289.451319)
			(xy 381.940054 -289.475926) (xy 382.268996 -289.475926) (xy 382.272956 -289.426872) (xy 382.284733 -289.379088)
			(xy 382.304024 -289.333812) (xy 382.330327 -289.292216) (xy 382.362962 -289.255379) (xy 382.401083 -289.224254)
			(xy 382.443704 -289.199647) (xy 382.48972 -289.182195) (xy 382.537939 -289.172351) (xy 382.587114 -289.17037)
			(xy 382.635969 -289.176302) (xy 382.68324 -289.189994) (xy 382.727702 -289.211092) (xy 382.768205 -289.239048)
			(xy 382.803698 -289.27314) (xy 382.833263 -289.312484) (xy 382.856134 -289.356061) (xy 382.871718 -289.402742)
			(xy 382.879613 -289.451319) (xy 382.880108 -289.475926) (xy 383.20905 -289.475926) (xy 383.21301 -289.426872)
			(xy 383.224787 -289.379088) (xy 383.244078 -289.333812) (xy 383.270381 -289.292216) (xy 383.303016 -289.255379)
			(xy 383.341137 -289.224254) (xy 383.383758 -289.199647) (xy 383.429774 -289.182195) (xy 383.477993 -289.172351)
			(xy 383.527168 -289.17037) (xy 383.576023 -289.176302) (xy 383.623294 -289.189994) (xy 383.667756 -289.211092)
			(xy 383.708259 -289.239048) (xy 383.743752 -289.27314) (xy 383.773317 -289.312484) (xy 383.796188 -289.356061)
			(xy 383.811772 -289.402742) (xy 383.819667 -289.451319) (xy 383.820162 -289.475926) (xy 384.149104 -289.475926)
			(xy 384.153064 -289.426872) (xy 384.164841 -289.379088) (xy 384.184132 -289.333812) (xy 384.210435 -289.292216)
			(xy 384.24307 -289.255379) (xy 384.281191 -289.224254) (xy 384.323812 -289.199647) (xy 384.369828 -289.182195)
			(xy 384.418047 -289.172351) (xy 384.467222 -289.17037) (xy 384.516077 -289.176302) (xy 384.563348 -289.189994)
			(xy 384.60781 -289.211092) (xy 384.648313 -289.239048) (xy 384.683806 -289.27314) (xy 384.713371 -289.312484)
			(xy 384.736242 -289.356061) (xy 384.751826 -289.402742) (xy 384.759721 -289.451319) (xy 384.760216 -289.475926)
			(xy 384.759721 -289.500533) (xy 384.751826 -289.54911) (xy 384.736242 -289.595791) (xy 384.713371 -289.639368)
			(xy 384.683806 -289.678712) (xy 384.648313 -289.712804) (xy 384.60781 -289.74076) (xy 384.563348 -289.761858)
			(xy 384.516077 -289.77555) (xy 384.467222 -289.781482) (xy 384.418047 -289.779501) (xy 384.369828 -289.769657)
			(xy 384.323812 -289.752205) (xy 384.281191 -289.727598) (xy 384.24307 -289.696473) (xy 384.210435 -289.659636)
			(xy 384.184132 -289.61804) (xy 384.164841 -289.572764) (xy 384.153064 -289.52498) (xy 384.149104 -289.475926)
			(xy 383.820162 -289.475926) (xy 383.819667 -289.500533) (xy 383.811772 -289.54911) (xy 383.796188 -289.595791)
			(xy 383.773317 -289.639368) (xy 383.743752 -289.678712) (xy 383.708259 -289.712804) (xy 383.667756 -289.74076)
			(xy 383.623294 -289.761858) (xy 383.576023 -289.77555) (xy 383.527168 -289.781482) (xy 383.477993 -289.779501)
			(xy 383.429774 -289.769657) (xy 383.383758 -289.752205) (xy 383.341137 -289.727598) (xy 383.303016 -289.696473)
			(xy 383.270381 -289.659636) (xy 383.244078 -289.61804) (xy 383.224787 -289.572764) (xy 383.21301 -289.52498)
			(xy 383.20905 -289.475926) (xy 382.880108 -289.475926) (xy 382.879613 -289.500533) (xy 382.871718 -289.54911)
			(xy 382.856134 -289.595791) (xy 382.833263 -289.639368) (xy 382.803698 -289.678712) (xy 382.768205 -289.712804)
			(xy 382.727702 -289.74076) (xy 382.68324 -289.761858) (xy 382.635969 -289.77555) (xy 382.587114 -289.781482)
			(xy 382.537939 -289.779501) (xy 382.48972 -289.769657) (xy 382.443704 -289.752205) (xy 382.401083 -289.727598)
			(xy 382.362962 -289.696473) (xy 382.330327 -289.659636) (xy 382.304024 -289.61804) (xy 382.284733 -289.572764)
			(xy 382.272956 -289.52498) (xy 382.268996 -289.475926) (xy 381.940054 -289.475926) (xy 381.939559 -289.500533)
			(xy 381.931664 -289.54911) (xy 381.91608 -289.595791) (xy 381.893209 -289.639368) (xy 381.863644 -289.678712)
			(xy 381.828151 -289.712804) (xy 381.787648 -289.74076) (xy 381.743186 -289.761858) (xy 381.695915 -289.77555)
			(xy 381.64706 -289.781482) (xy 381.597885 -289.779501) (xy 381.549666 -289.769657) (xy 381.50365 -289.752205)
			(xy 381.461029 -289.727598) (xy 381.422908 -289.696473) (xy 381.390273 -289.659636) (xy 381.36397 -289.61804)
			(xy 381.344679 -289.572764) (xy 381.332902 -289.52498) (xy 381.328942 -289.475926) (xy 381.010668 -289.475926)
			(xy 381.010156 -289.501372) (xy 381.001992 -289.551606) (xy 380.985876 -289.59988) (xy 380.962225 -289.644943)
			(xy 380.931652 -289.685629) (xy 380.894948 -289.720884) (xy 380.853064 -289.749794) (xy 380.807085 -289.771611)
			(xy 380.758201 -289.785771) (xy 380.70768 -289.791905) (xy 380.656828 -289.789856) (xy 380.606964 -289.779676)
			(xy 380.559378 -289.761629) (xy 380.515304 -289.736183) (xy 380.475882 -289.703996) (xy 380.442134 -289.665902)
			(xy 380.414933 -289.622888) (xy 380.394985 -289.576068) (xy 380.382806 -289.526654) (xy 380.378711 -289.475926)
			(xy 380.070614 -289.475926) (xy 380.070102 -289.501372) (xy 380.061938 -289.551606) (xy 380.045822 -289.59988)
			(xy 380.022171 -289.644943) (xy 379.991598 -289.685629) (xy 379.954894 -289.720884) (xy 379.91301 -289.749794)
			(xy 379.867031 -289.771611) (xy 379.818147 -289.785771) (xy 379.767626 -289.791905) (xy 379.716774 -289.789856)
			(xy 379.66691 -289.779676) (xy 379.619324 -289.761629) (xy 379.57525 -289.736183) (xy 379.535828 -289.703996)
			(xy 379.50208 -289.665902) (xy 379.474879 -289.622888) (xy 379.454931 -289.576068) (xy 379.442752 -289.526654)
			(xy 379.438657 -289.475926) (xy 379.120146 -289.475926) (xy 379.119651 -289.500533) (xy 379.111756 -289.54911)
			(xy 379.096172 -289.595791) (xy 379.073301 -289.639368) (xy 379.043736 -289.678712) (xy 379.008243 -289.712804)
			(xy 378.96774 -289.74076) (xy 378.923278 -289.761858) (xy 378.876007 -289.77555) (xy 378.827152 -289.781482)
			(xy 378.777977 -289.779501) (xy 378.729758 -289.769657) (xy 378.683742 -289.752205) (xy 378.641121 -289.727598)
			(xy 378.603 -289.696473) (xy 378.570365 -289.659636) (xy 378.544062 -289.61804) (xy 378.524771 -289.572764)
			(xy 378.512994 -289.52498) (xy 378.509034 -289.475926) (xy 378.190506 -289.475926) (xy 378.189994 -289.501372)
			(xy 378.18183 -289.551606) (xy 378.165714 -289.59988) (xy 378.142063 -289.644943) (xy 378.11149 -289.685629)
			(xy 378.074786 -289.720884) (xy 378.032902 -289.749794) (xy 377.986923 -289.771611) (xy 377.938039 -289.785771)
			(xy 377.887518 -289.791905) (xy 377.836666 -289.789856) (xy 377.786802 -289.779676) (xy 377.739216 -289.761629)
			(xy 377.695142 -289.736183) (xy 377.65572 -289.703996) (xy 377.621972 -289.665902) (xy 377.594771 -289.622888)
			(xy 377.574823 -289.576068) (xy 377.562644 -289.526654) (xy 377.558549 -289.475926) (xy 377.240038 -289.475926)
			(xy 377.239543 -289.500533) (xy 377.231648 -289.54911) (xy 377.216064 -289.595791) (xy 377.193193 -289.639368)
			(xy 377.163628 -289.678712) (xy 377.128135 -289.712804) (xy 377.087632 -289.74076) (xy 377.04317 -289.761858)
			(xy 376.995899 -289.77555) (xy 376.947044 -289.781482) (xy 376.897869 -289.779501) (xy 376.84965 -289.769657)
			(xy 376.803634 -289.752205) (xy 376.761013 -289.727598) (xy 376.722892 -289.696473) (xy 376.690257 -289.659636)
			(xy 376.663954 -289.61804) (xy 376.644663 -289.572764) (xy 376.632886 -289.52498) (xy 376.628926 -289.475926)
			(xy 376.310652 -289.475926) (xy 376.31014 -289.501372) (xy 376.301976 -289.551606) (xy 376.28586 -289.59988)
			(xy 376.262209 -289.644943) (xy 376.231636 -289.685629) (xy 376.194932 -289.720884) (xy 376.153048 -289.749794)
			(xy 376.107069 -289.771611) (xy 376.058185 -289.785771) (xy 376.007664 -289.791905) (xy 375.956812 -289.789856)
			(xy 375.906948 -289.779676) (xy 375.859362 -289.761629) (xy 375.815288 -289.736183) (xy 375.775866 -289.703996)
			(xy 375.742118 -289.665902) (xy 375.714917 -289.622888) (xy 375.694969 -289.576068) (xy 375.68279 -289.526654)
			(xy 375.678695 -289.475926) (xy 375.571258 -289.475926) (xy 375.571258 -289.726624) (xy 375.574306 -289.738562)
			(xy 375.577354 -289.74415) (xy 375.598931 -289.78457) (xy 375.63623 -289.868268) (xy 375.666625 -289.954713)
			(xy 375.6787 -289.998912) (xy 375.680986 -290.007548) (xy 375.690638 -290.021518) (xy 375.700544 -290.035742)
			(xy 375.707148 -290.040822) (xy 375.728732 -290.057629) (xy 375.766044 -290.097628) (xy 375.781316 -290.120324)
			(xy 375.785126 -290.12642) (xy 375.802398 -290.143692) (xy 375.802398 -290.157916) (xy 375.806462 -290.167314)
			(xy 375.817481 -290.195522) (xy 375.829376 -290.254894) (xy 375.830084 -290.28517) (xy 375.830084 -290.285932)
			(xy 376.148595 -290.285932) (xy 376.15269 -290.235204) (xy 376.164869 -290.18579) (xy 376.184817 -290.13897)
			(xy 376.212018 -290.095956) (xy 376.245766 -290.057862) (xy 376.285188 -290.025675) (xy 376.329262 -290.000229)
			(xy 376.376848 -289.982182) (xy 376.426712 -289.972002) (xy 376.477564 -289.969953) (xy 376.528085 -289.976087)
			(xy 376.576969 -289.990247) (xy 376.622948 -290.012064) (xy 376.664832 -290.040974) (xy 376.701536 -290.076229)
			(xy 376.732109 -290.116915) (xy 376.75576 -290.161978) (xy 376.771876 -290.210252) (xy 376.78004 -290.260486)
			(xy 376.780552 -290.285932) (xy 377.088649 -290.285932) (xy 377.092744 -290.235204) (xy 377.104923 -290.18579)
			(xy 377.124871 -290.13897) (xy 377.152072 -290.095956) (xy 377.18582 -290.057862) (xy 377.225242 -290.025675)
			(xy 377.269316 -290.000229) (xy 377.316902 -289.982182) (xy 377.366766 -289.972002) (xy 377.417618 -289.969953)
			(xy 377.468139 -289.976087) (xy 377.517023 -289.990247) (xy 377.563002 -290.012064) (xy 377.604886 -290.040974)
			(xy 377.64159 -290.076229) (xy 377.672163 -290.116915) (xy 377.695814 -290.161978) (xy 377.71193 -290.210252)
			(xy 377.720094 -290.260486) (xy 377.720606 -290.285932) (xy 378.968503 -290.285932) (xy 378.972598 -290.235204)
			(xy 378.984777 -290.18579) (xy 379.004725 -290.13897) (xy 379.031926 -290.095956) (xy 379.065674 -290.057862)
			(xy 379.105096 -290.025675) (xy 379.14917 -290.000229) (xy 379.196756 -289.982182) (xy 379.24662 -289.972002)
			(xy 379.297472 -289.969953) (xy 379.347993 -289.976087) (xy 379.396877 -289.990247) (xy 379.442856 -290.012064)
			(xy 379.48474 -290.040974) (xy 379.521444 -290.076229) (xy 379.552017 -290.116915) (xy 379.575668 -290.161978)
			(xy 379.591784 -290.210252) (xy 379.599948 -290.260486) (xy 379.60046 -290.285932) (xy 379.918988 -290.285932)
			(xy 379.922948 -290.236878) (xy 379.934725 -290.189094) (xy 379.954016 -290.143818) (xy 379.980319 -290.102222)
			(xy 380.012954 -290.065385) (xy 380.051075 -290.03426) (xy 380.093696 -290.009653) (xy 380.139712 -289.992201)
			(xy 380.187931 -289.982357) (xy 380.237106 -289.980376) (xy 380.285961 -289.986308) (xy 380.333232 -290)
			(xy 380.377694 -290.021098) (xy 380.418197 -290.049054) (xy 380.45369 -290.083146) (xy 380.483255 -290.12249)
			(xy 380.506126 -290.166067) (xy 380.52171 -290.212748) (xy 380.529605 -290.261325) (xy 380.5301 -290.285932)
			(xy 380.848611 -290.285932) (xy 380.852706 -290.235204) (xy 380.864885 -290.18579) (xy 380.884833 -290.13897)
			(xy 380.912034 -290.095956) (xy 380.945782 -290.057862) (xy 380.985204 -290.025675) (xy 381.029278 -290.000229)
			(xy 381.076864 -289.982182) (xy 381.126728 -289.972002) (xy 381.17758 -289.969953) (xy 381.228101 -289.976087)
			(xy 381.276985 -289.990247) (xy 381.322964 -290.012064) (xy 381.364848 -290.040974) (xy 381.401552 -290.076229)
			(xy 381.432125 -290.116915) (xy 381.455776 -290.161978) (xy 381.471892 -290.210252) (xy 381.480056 -290.260486)
			(xy 381.480568 -290.285932) (xy 381.799096 -290.285932) (xy 381.803056 -290.236878) (xy 381.814833 -290.189094)
			(xy 381.834124 -290.143818) (xy 381.860427 -290.102222) (xy 381.893062 -290.065385) (xy 381.931183 -290.03426)
			(xy 381.973804 -290.009653) (xy 382.01982 -289.992201) (xy 382.068039 -289.982357) (xy 382.117214 -289.980376)
			(xy 382.166069 -289.986308) (xy 382.21334 -290) (xy 382.257802 -290.021098) (xy 382.298305 -290.049054)
			(xy 382.333798 -290.083146) (xy 382.363363 -290.12249) (xy 382.386234 -290.166067) (xy 382.401818 -290.212748)
			(xy 382.409713 -290.261325) (xy 382.410208 -290.285932) (xy 382.738896 -290.285932) (xy 382.742856 -290.236878)
			(xy 382.754633 -290.189094) (xy 382.773924 -290.143818) (xy 382.800227 -290.102222) (xy 382.832862 -290.065385)
			(xy 382.870983 -290.03426) (xy 382.913604 -290.009653) (xy 382.95962 -289.992201) (xy 383.007839 -289.982357)
			(xy 383.057014 -289.980376) (xy 383.105869 -289.986308) (xy 383.15314 -290) (xy 383.197602 -290.021098)
			(xy 383.238105 -290.049054) (xy 383.273598 -290.083146) (xy 383.303163 -290.12249) (xy 383.326034 -290.166067)
			(xy 383.341618 -290.212748) (xy 383.349513 -290.261325) (xy 383.350008 -290.285932) (xy 383.67895 -290.285932)
			(xy 383.68291 -290.236878) (xy 383.694687 -290.189094) (xy 383.713978 -290.143818) (xy 383.740281 -290.102222)
			(xy 383.772916 -290.065385) (xy 383.811037 -290.03426) (xy 383.853658 -290.009653) (xy 383.899674 -289.992201)
			(xy 383.947893 -289.982357) (xy 383.997068 -289.980376) (xy 384.045923 -289.986308) (xy 384.093194 -290)
			(xy 384.137656 -290.021098) (xy 384.178159 -290.049054) (xy 384.213652 -290.083146) (xy 384.243217 -290.12249)
			(xy 384.266088 -290.166067) (xy 384.281672 -290.212748) (xy 384.289567 -290.261325) (xy 384.290062 -290.285932)
			(xy 384.289567 -290.310539) (xy 384.281672 -290.359116) (xy 384.266088 -290.405797) (xy 384.243217 -290.449374)
			(xy 384.213652 -290.488718) (xy 384.178159 -290.52281) (xy 384.137656 -290.550766) (xy 384.093194 -290.571864)
			(xy 384.045923 -290.585556) (xy 383.997068 -290.591488) (xy 383.947893 -290.589507) (xy 383.899674 -290.579663)
			(xy 383.853658 -290.562211) (xy 383.811037 -290.537604) (xy 383.772916 -290.506479) (xy 383.740281 -290.469642)
			(xy 383.713978 -290.428046) (xy 383.694687 -290.38277) (xy 383.68291 -290.334986) (xy 383.67895 -290.285932)
			(xy 383.350008 -290.285932) (xy 383.349513 -290.310539) (xy 383.341618 -290.359116) (xy 383.326034 -290.405797)
			(xy 383.303163 -290.449374) (xy 383.273598 -290.488718) (xy 383.238105 -290.52281) (xy 383.197602 -290.550766)
			(xy 383.15314 -290.571864) (xy 383.105869 -290.585556) (xy 383.057014 -290.591488) (xy 383.007839 -290.589507)
			(xy 382.95962 -290.579663) (xy 382.913604 -290.562211) (xy 382.870983 -290.537604) (xy 382.832862 -290.506479)
			(xy 382.800227 -290.469642) (xy 382.773924 -290.428046) (xy 382.754633 -290.38277) (xy 382.742856 -290.334986)
			(xy 382.738896 -290.285932) (xy 382.410208 -290.285932) (xy 382.409713 -290.310539) (xy 382.401818 -290.359116)
			(xy 382.386234 -290.405797) (xy 382.363363 -290.449374) (xy 382.333798 -290.488718) (xy 382.298305 -290.52281)
			(xy 382.257802 -290.550766) (xy 382.21334 -290.571864) (xy 382.166069 -290.585556) (xy 382.117214 -290.591488)
			(xy 382.068039 -290.589507) (xy 382.01982 -290.579663) (xy 381.973804 -290.562211) (xy 381.931183 -290.537604)
			(xy 381.893062 -290.506479) (xy 381.860427 -290.469642) (xy 381.834124 -290.428046) (xy 381.814833 -290.38277)
			(xy 381.803056 -290.334986) (xy 381.799096 -290.285932) (xy 381.480568 -290.285932) (xy 381.480056 -290.311378)
			(xy 381.471892 -290.361612) (xy 381.455776 -290.409886) (xy 381.432125 -290.454949) (xy 381.401552 -290.495635)
			(xy 381.364848 -290.53089) (xy 381.322964 -290.5598) (xy 381.276985 -290.581617) (xy 381.228101 -290.595777)
			(xy 381.17758 -290.601911) (xy 381.126728 -290.599862) (xy 381.076864 -290.589682) (xy 381.029278 -290.571635)
			(xy 380.985204 -290.546189) (xy 380.945782 -290.514002) (xy 380.912034 -290.475908) (xy 380.884833 -290.432894)
			(xy 380.864885 -290.386074) (xy 380.852706 -290.33666) (xy 380.848611 -290.285932) (xy 380.5301 -290.285932)
			(xy 380.529605 -290.310539) (xy 380.52171 -290.359116) (xy 380.506126 -290.405797) (xy 380.483255 -290.449374)
			(xy 380.45369 -290.488718) (xy 380.418197 -290.52281) (xy 380.377694 -290.550766) (xy 380.333232 -290.571864)
			(xy 380.285961 -290.585556) (xy 380.237106 -290.591488) (xy 380.187931 -290.589507) (xy 380.139712 -290.579663)
			(xy 380.093696 -290.562211) (xy 380.051075 -290.537604) (xy 380.012954 -290.506479) (xy 379.980319 -290.469642)
			(xy 379.954016 -290.428046) (xy 379.934725 -290.38277) (xy 379.922948 -290.334986) (xy 379.918988 -290.285932)
			(xy 379.60046 -290.285932) (xy 379.599948 -290.311378) (xy 379.591784 -290.361612) (xy 379.575668 -290.409886)
			(xy 379.552017 -290.454949) (xy 379.521444 -290.495635) (xy 379.48474 -290.53089) (xy 379.442856 -290.5598)
			(xy 379.396877 -290.581617) (xy 379.347993 -290.595777) (xy 379.297472 -290.601911) (xy 379.24662 -290.599862)
			(xy 379.196756 -290.589682) (xy 379.14917 -290.571635) (xy 379.105096 -290.546189) (xy 379.065674 -290.514002)
			(xy 379.031926 -290.475908) (xy 379.004725 -290.432894) (xy 378.984777 -290.386074) (xy 378.972598 -290.33666)
			(xy 378.968503 -290.285932) (xy 377.720606 -290.285932) (xy 377.720094 -290.311378) (xy 377.71193 -290.361612)
			(xy 377.695814 -290.409886) (xy 377.672163 -290.454949) (xy 377.64159 -290.495635) (xy 377.604886 -290.53089)
			(xy 377.563002 -290.5598) (xy 377.517023 -290.581617) (xy 377.468139 -290.595777) (xy 377.417618 -290.601911)
			(xy 377.366766 -290.599862) (xy 377.316902 -290.589682) (xy 377.269316 -290.571635) (xy 377.225242 -290.546189)
			(xy 377.18582 -290.514002) (xy 377.152072 -290.475908) (xy 377.124871 -290.432894) (xy 377.104923 -290.386074)
			(xy 377.092744 -290.33666) (xy 377.088649 -290.285932) (xy 376.780552 -290.285932) (xy 376.78004 -290.311378)
			(xy 376.771876 -290.361612) (xy 376.75576 -290.409886) (xy 376.732109 -290.454949) (xy 376.701536 -290.495635)
			(xy 376.664832 -290.53089) (xy 376.622948 -290.5598) (xy 376.576969 -290.581617) (xy 376.528085 -290.595777)
			(xy 376.477564 -290.601911) (xy 376.426712 -290.599862) (xy 376.376848 -290.589682) (xy 376.329262 -290.571635)
			(xy 376.285188 -290.546189) (xy 376.245766 -290.514002) (xy 376.212018 -290.475908) (xy 376.184817 -290.432894)
			(xy 376.164869 -290.386074) (xy 376.15269 -290.33666) (xy 376.148595 -290.285932) (xy 375.830084 -290.285932)
			(xy 375.829558 -290.311654) (xy 375.820947 -290.362371) (xy 375.803957 -290.410928) (xy 375.779069 -290.45595)
			(xy 375.746986 -290.496164) (xy 375.708618 -290.530431) (xy 375.687082 -290.544504) (xy 375.68505 -290.547298)
			(xy 375.67402 -290.59176) (xy 375.645699 -290.678888) (xy 375.610412 -290.763435) (xy 375.5898 -290.804346)
			(xy 375.58726 -290.809426) (xy 375.586752 -290.810188) (xy 375.583958 -290.821872) (xy 375.583958 -291.028628)
			(xy 375.58445 -291.038635) (xy 375.592113 -291.057124) (xy 375.606264 -291.071279) (xy 375.624751 -291.078947)
			(xy 375.634758 -291.079428) (xy 375.646563 -291.078815) (xy 375.667709 -291.068309) (xy 375.681994 -291.049509)
			(xy 375.684796 -291.038026) (xy 375.689684 -291.014196) (xy 375.70581 -290.968304) (xy 375.728788 -290.92543)
			(xy 375.758074 -290.88659) (xy 375.792974 -290.852705) (xy 375.832661 -290.824578) (xy 375.876194 -290.802875)
			(xy 375.922543 -290.788111) (xy 375.970608 -290.780635) (xy 375.99493 -290.780216) (xy 376.019735 -290.780705)
			(xy 376.068734 -290.78847) (xy 376.115915 -290.803804) (xy 376.160116 -290.826329) (xy 376.20025 -290.855492)
			(xy 376.235328 -290.890573) (xy 376.264486 -290.93071) (xy 376.287008 -290.974913) (xy 376.302337 -291.022095)
			(xy 376.310097 -291.071095) (xy 376.310097 -291.095938) (xy 376.628926 -291.095938) (xy 376.632886 -291.046884)
			(xy 376.644663 -290.9991) (xy 376.663954 -290.953824) (xy 376.690257 -290.912228) (xy 376.722892 -290.875391)
			(xy 376.761013 -290.844266) (xy 376.803634 -290.819659) (xy 376.84965 -290.802207) (xy 376.897869 -290.792363)
			(xy 376.947044 -290.790382) (xy 376.995899 -290.796314) (xy 377.04317 -290.810006) (xy 377.087632 -290.831104)
			(xy 377.128135 -290.85906) (xy 377.163628 -290.893152) (xy 377.193193 -290.932496) (xy 377.216064 -290.976073)
			(xy 377.231648 -291.022754) (xy 377.239543 -291.071331) (xy 377.240038 -291.095938) (xy 377.558549 -291.095938)
			(xy 377.562644 -291.04521) (xy 377.574823 -290.995796) (xy 377.594771 -290.948976) (xy 377.621972 -290.905962)
			(xy 377.65572 -290.867868) (xy 377.695142 -290.835681) (xy 377.739216 -290.810235) (xy 377.786802 -290.792188)
			(xy 377.836666 -290.782008) (xy 377.887518 -290.779959) (xy 377.938039 -290.786093) (xy 377.986923 -290.800253)
			(xy 378.032902 -290.82207) (xy 378.074786 -290.85098) (xy 378.11149 -290.886235) (xy 378.142063 -290.926921)
			(xy 378.165714 -290.971984) (xy 378.18183 -291.020258) (xy 378.189994 -291.070492) (xy 378.190506 -291.095938)
			(xy 378.509034 -291.095938) (xy 378.512994 -291.046884) (xy 378.524771 -290.9991) (xy 378.544062 -290.953824)
			(xy 378.570365 -290.912228) (xy 378.603 -290.875391) (xy 378.641121 -290.844266) (xy 378.683742 -290.819659)
			(xy 378.729758 -290.802207) (xy 378.777977 -290.792363) (xy 378.827152 -290.790382) (xy 378.876007 -290.796314)
			(xy 378.923278 -290.810006) (xy 378.96774 -290.831104) (xy 379.008243 -290.85906) (xy 379.043736 -290.893152)
			(xy 379.073301 -290.932496) (xy 379.096172 -290.976073) (xy 379.111756 -291.022754) (xy 379.119651 -291.071331)
			(xy 379.120146 -291.095938) (xy 379.438657 -291.095938) (xy 379.442752 -291.04521) (xy 379.454931 -290.995796)
			(xy 379.474879 -290.948976) (xy 379.50208 -290.905962) (xy 379.535828 -290.867868) (xy 379.57525 -290.835681)
			(xy 379.619324 -290.810235) (xy 379.66691 -290.792188) (xy 379.716774 -290.782008) (xy 379.767626 -290.779959)
			(xy 379.818147 -290.786093) (xy 379.867031 -290.800253) (xy 379.91301 -290.82207) (xy 379.954894 -290.85098)
			(xy 379.991598 -290.886235) (xy 380.022171 -290.926921) (xy 380.045822 -290.971984) (xy 380.061938 -291.020258)
			(xy 380.070102 -291.070492) (xy 380.070614 -291.095938) (xy 380.378711 -291.095938) (xy 380.382806 -291.04521)
			(xy 380.394985 -290.995796) (xy 380.414933 -290.948976) (xy 380.442134 -290.905962) (xy 380.475882 -290.867868)
			(xy 380.515304 -290.835681) (xy 380.559378 -290.810235) (xy 380.606964 -290.792188) (xy 380.656828 -290.782008)
			(xy 380.70768 -290.779959) (xy 380.758201 -290.786093) (xy 380.807085 -290.800253) (xy 380.853064 -290.82207)
			(xy 380.894948 -290.85098) (xy 380.931652 -290.886235) (xy 380.962225 -290.926921) (xy 380.985876 -290.971984)
			(xy 381.001992 -291.020258) (xy 381.010156 -291.070492) (xy 381.010668 -291.095938) (xy 381.328942 -291.095938)
			(xy 381.332902 -291.046884) (xy 381.344679 -290.9991) (xy 381.36397 -290.953824) (xy 381.390273 -290.912228)
			(xy 381.422908 -290.875391) (xy 381.461029 -290.844266) (xy 381.50365 -290.819659) (xy 381.549666 -290.802207)
			(xy 381.597885 -290.792363) (xy 381.64706 -290.790382) (xy 381.695915 -290.796314) (xy 381.743186 -290.810006)
			(xy 381.787648 -290.831104) (xy 381.828151 -290.85906) (xy 381.863644 -290.893152) (xy 381.893209 -290.932496)
			(xy 381.91608 -290.976073) (xy 381.931664 -291.022754) (xy 381.939559 -291.071331) (xy 381.940054 -291.095938)
			(xy 382.268996 -291.095938) (xy 382.272956 -291.046884) (xy 382.284733 -290.9991) (xy 382.304024 -290.953824)
			(xy 382.330327 -290.912228) (xy 382.362962 -290.875391) (xy 382.401083 -290.844266) (xy 382.443704 -290.819659)
			(xy 382.48972 -290.802207) (xy 382.537939 -290.792363) (xy 382.587114 -290.790382) (xy 382.635969 -290.796314)
			(xy 382.68324 -290.810006) (xy 382.727702 -290.831104) (xy 382.768205 -290.85906) (xy 382.803698 -290.893152)
			(xy 382.833263 -290.932496) (xy 382.856134 -290.976073) (xy 382.871718 -291.022754) (xy 382.879613 -291.071331)
			(xy 382.880108 -291.095938) (xy 383.20905 -291.095938) (xy 383.21301 -291.046884) (xy 383.224787 -290.9991)
			(xy 383.244078 -290.953824) (xy 383.270381 -290.912228) (xy 383.303016 -290.875391) (xy 383.341137 -290.844266)
			(xy 383.383758 -290.819659) (xy 383.429774 -290.802207) (xy 383.477993 -290.792363) (xy 383.527168 -290.790382)
			(xy 383.576023 -290.796314) (xy 383.623294 -290.810006) (xy 383.667756 -290.831104) (xy 383.708259 -290.85906)
			(xy 383.743752 -290.893152) (xy 383.773317 -290.932496) (xy 383.796188 -290.976073) (xy 383.811772 -291.022754)
			(xy 383.819667 -291.071331) (xy 383.820162 -291.095938) (xy 384.149104 -291.095938) (xy 384.153064 -291.046884)
			(xy 384.164841 -290.9991) (xy 384.184132 -290.953824) (xy 384.210435 -290.912228) (xy 384.24307 -290.875391)
			(xy 384.281191 -290.844266) (xy 384.323812 -290.819659) (xy 384.369828 -290.802207) (xy 384.418047 -290.792363)
			(xy 384.467222 -290.790382) (xy 384.516077 -290.796314) (xy 384.563348 -290.810006) (xy 384.60781 -290.831104)
			(xy 384.648313 -290.85906) (xy 384.683806 -290.893152) (xy 384.713371 -290.932496) (xy 384.736242 -290.976073)
			(xy 384.751826 -291.022754) (xy 384.759721 -291.071331) (xy 384.760216 -291.095938) (xy 384.759721 -291.120545)
			(xy 384.751826 -291.169122) (xy 384.736242 -291.215803) (xy 384.713371 -291.25938) (xy 384.683806 -291.298724)
			(xy 384.648313 -291.332816) (xy 384.60781 -291.360772) (xy 384.563348 -291.38187) (xy 384.516077 -291.395562)
			(xy 384.467222 -291.401494) (xy 384.418047 -291.399513) (xy 384.369828 -291.389669) (xy 384.323812 -291.372217)
			(xy 384.281191 -291.34761) (xy 384.24307 -291.316485) (xy 384.210435 -291.279648) (xy 384.184132 -291.238052)
			(xy 384.164841 -291.192776) (xy 384.153064 -291.144992) (xy 384.149104 -291.095938) (xy 383.820162 -291.095938)
			(xy 383.819667 -291.120545) (xy 383.811772 -291.169122) (xy 383.796188 -291.215803) (xy 383.773317 -291.25938)
			(xy 383.743752 -291.298724) (xy 383.708259 -291.332816) (xy 383.667756 -291.360772) (xy 383.623294 -291.38187)
			(xy 383.576023 -291.395562) (xy 383.527168 -291.401494) (xy 383.477993 -291.399513) (xy 383.429774 -291.389669)
			(xy 383.383758 -291.372217) (xy 383.341137 -291.34761) (xy 383.303016 -291.316485) (xy 383.270381 -291.279648)
			(xy 383.244078 -291.238052) (xy 383.224787 -291.192776) (xy 383.21301 -291.144992) (xy 383.20905 -291.095938)
			(xy 382.880108 -291.095938) (xy 382.879613 -291.120545) (xy 382.871718 -291.169122) (xy 382.856134 -291.215803)
			(xy 382.833263 -291.25938) (xy 382.803698 -291.298724) (xy 382.768205 -291.332816) (xy 382.727702 -291.360772)
			(xy 382.68324 -291.38187) (xy 382.635969 -291.395562) (xy 382.587114 -291.401494) (xy 382.537939 -291.399513)
			(xy 382.48972 -291.389669) (xy 382.443704 -291.372217) (xy 382.401083 -291.34761) (xy 382.362962 -291.316485)
			(xy 382.330327 -291.279648) (xy 382.304024 -291.238052) (xy 382.284733 -291.192776) (xy 382.272956 -291.144992)
			(xy 382.268996 -291.095938) (xy 381.940054 -291.095938) (xy 381.939559 -291.120545) (xy 381.931664 -291.169122)
			(xy 381.91608 -291.215803) (xy 381.893209 -291.25938) (xy 381.863644 -291.298724) (xy 381.828151 -291.332816)
			(xy 381.787648 -291.360772) (xy 381.743186 -291.38187) (xy 381.695915 -291.395562) (xy 381.64706 -291.401494)
			(xy 381.597885 -291.399513) (xy 381.549666 -291.389669) (xy 381.50365 -291.372217) (xy 381.461029 -291.34761)
			(xy 381.422908 -291.316485) (xy 381.390273 -291.279648) (xy 381.36397 -291.238052) (xy 381.344679 -291.192776)
			(xy 381.332902 -291.144992) (xy 381.328942 -291.095938) (xy 381.010668 -291.095938) (xy 381.010156 -291.121384)
			(xy 381.001992 -291.171618) (xy 380.985876 -291.219892) (xy 380.962225 -291.264955) (xy 380.931652 -291.305641)
			(xy 380.894948 -291.340896) (xy 380.853064 -291.369806) (xy 380.807085 -291.391623) (xy 380.758201 -291.405783)
			(xy 380.70768 -291.411917) (xy 380.656828 -291.409868) (xy 380.606964 -291.399688) (xy 380.559378 -291.381641)
			(xy 380.515304 -291.356195) (xy 380.475882 -291.324008) (xy 380.442134 -291.285914) (xy 380.414933 -291.2429)
			(xy 380.394985 -291.19608) (xy 380.382806 -291.146666) (xy 380.378711 -291.095938) (xy 380.070614 -291.095938)
			(xy 380.070102 -291.121384) (xy 380.061938 -291.171618) (xy 380.045822 -291.219892) (xy 380.022171 -291.264955)
			(xy 379.991598 -291.305641) (xy 379.954894 -291.340896) (xy 379.91301 -291.369806) (xy 379.867031 -291.391623)
			(xy 379.818147 -291.405783) (xy 379.767626 -291.411917) (xy 379.716774 -291.409868) (xy 379.66691 -291.399688)
			(xy 379.619324 -291.381641) (xy 379.57525 -291.356195) (xy 379.535828 -291.324008) (xy 379.50208 -291.285914)
			(xy 379.474879 -291.2429) (xy 379.454931 -291.19608) (xy 379.442752 -291.146666) (xy 379.438657 -291.095938)
			(xy 379.120146 -291.095938) (xy 379.119651 -291.120545) (xy 379.111756 -291.169122) (xy 379.096172 -291.215803)
			(xy 379.073301 -291.25938) (xy 379.043736 -291.298724) (xy 379.008243 -291.332816) (xy 378.96774 -291.360772)
			(xy 378.923278 -291.38187) (xy 378.876007 -291.395562) (xy 378.827152 -291.401494) (xy 378.777977 -291.399513)
			(xy 378.729758 -291.389669) (xy 378.683742 -291.372217) (xy 378.641121 -291.34761) (xy 378.603 -291.316485)
			(xy 378.570365 -291.279648) (xy 378.544062 -291.238052) (xy 378.524771 -291.192776) (xy 378.512994 -291.144992)
			(xy 378.509034 -291.095938) (xy 378.190506 -291.095938) (xy 378.189994 -291.121384) (xy 378.18183 -291.171618)
			(xy 378.165714 -291.219892) (xy 378.142063 -291.264955) (xy 378.11149 -291.305641) (xy 378.074786 -291.340896)
			(xy 378.032902 -291.369806) (xy 377.986923 -291.391623) (xy 377.938039 -291.405783) (xy 377.887518 -291.411917)
			(xy 377.836666 -291.409868) (xy 377.786802 -291.399688) (xy 377.739216 -291.381641) (xy 377.695142 -291.356195)
			(xy 377.65572 -291.324008) (xy 377.621972 -291.285914) (xy 377.594771 -291.2429) (xy 377.574823 -291.19608)
			(xy 377.562644 -291.146666) (xy 377.558549 -291.095938) (xy 377.240038 -291.095938) (xy 377.239543 -291.120545)
			(xy 377.231648 -291.169122) (xy 377.216064 -291.215803) (xy 377.193193 -291.25938) (xy 377.163628 -291.298724)
			(xy 377.128135 -291.332816) (xy 377.087632 -291.360772) (xy 377.04317 -291.38187) (xy 376.995899 -291.395562)
			(xy 376.947044 -291.401494) (xy 376.897869 -291.399513) (xy 376.84965 -291.389669) (xy 376.803634 -291.372217)
			(xy 376.761013 -291.34761) (xy 376.722892 -291.316485) (xy 376.690257 -291.279648) (xy 376.663954 -291.238052)
			(xy 376.644663 -291.192776) (xy 376.632886 -291.144992) (xy 376.628926 -291.095938) (xy 376.310097 -291.095938)
			(xy 376.310097 -291.120705) (xy 376.302337 -291.169705) (xy 376.287008 -291.216887) (xy 376.264486 -291.26109)
			(xy 376.235328 -291.301227) (xy 376.20025 -291.336308) (xy 376.160116 -291.365471) (xy 376.115915 -291.387996)
			(xy 376.068734 -291.40333) (xy 376.019735 -291.411095) (xy 375.99493 -291.41166) (xy 375.970607 -291.411212)
			(xy 375.922537 -291.403749) (xy 375.876183 -291.388995) (xy 375.832643 -291.3673) (xy 375.792949 -291.339179)
			(xy 375.758043 -291.305297) (xy 375.728752 -291.266458) (xy 375.70577 -291.223583) (xy 375.689642 -291.177689)
			(xy 375.684796 -291.15385) (xy 375.68124 -291.135562) (xy 375.6533 -291.112448) (xy 375.634758 -291.112448)
			(xy 375.624746 -291.112876) (xy 375.606252 -291.120555) (xy 375.592104 -291.134727) (xy 375.584458 -291.153235)
			(xy 375.583958 -291.163248) (xy 375.583958 -291.370004) (xy 375.586752 -291.381688) (xy 375.589546 -291.387276)
			(xy 375.5898 -291.38753) (xy 375.60833 -291.424255) (xy 375.640629 -291.499914) (xy 375.667335 -291.577724)
			(xy 375.678192 -291.6174) (xy 375.67997 -291.624258) (xy 375.683272 -291.629846) (xy 375.6914 -291.640514)
			(xy 375.703592 -291.652706) (xy 375.70918 -291.657532) (xy 375.727186 -291.671399) (xy 375.75932 -291.703535)
			(xy 375.773188 -291.72154) (xy 375.778014 -291.727128) (xy 375.797826 -291.74694) (xy 375.804533 -291.75418)
			(xy 375.812115 -291.772385) (xy 375.812558 -291.782246) (xy 375.812558 -291.792406) (xy 375.822274 -291.818673)
			(xy 375.83312 -291.873612) (xy 375.833569 -291.905944) (xy 376.148595 -291.905944) (xy 376.15269 -291.855216)
			(xy 376.164869 -291.805802) (xy 376.184817 -291.758982) (xy 376.212018 -291.715968) (xy 376.245766 -291.677874)
			(xy 376.285188 -291.645687) (xy 376.329262 -291.620241) (xy 376.376848 -291.602194) (xy 376.426712 -291.592014)
			(xy 376.477564 -291.589965) (xy 376.528085 -291.596099) (xy 376.576969 -291.610259) (xy 376.622948 -291.632076)
			(xy 376.664832 -291.660986) (xy 376.701536 -291.696241) (xy 376.732109 -291.736927) (xy 376.75576 -291.78199)
			(xy 376.771876 -291.830264) (xy 376.78004 -291.880498) (xy 376.780552 -291.905944) (xy 377.088649 -291.905944)
			(xy 377.092744 -291.855216) (xy 377.104923 -291.805802) (xy 377.124871 -291.758982) (xy 377.152072 -291.715968)
			(xy 377.18582 -291.677874) (xy 377.225242 -291.645687) (xy 377.269316 -291.620241) (xy 377.316902 -291.602194)
			(xy 377.366766 -291.592014) (xy 377.417618 -291.589965) (xy 377.468139 -291.596099) (xy 377.517023 -291.610259)
			(xy 377.563002 -291.632076) (xy 377.604886 -291.660986) (xy 377.64159 -291.696241) (xy 377.672163 -291.736927)
			(xy 377.695814 -291.78199) (xy 377.71193 -291.830264) (xy 377.720094 -291.880498) (xy 377.720606 -291.905944)
			(xy 378.039134 -291.905944) (xy 378.043094 -291.85689) (xy 378.054871 -291.809106) (xy 378.074162 -291.76383)
			(xy 378.100465 -291.722234) (xy 378.1331 -291.685397) (xy 378.171221 -291.654272) (xy 378.213842 -291.629665)
			(xy 378.259858 -291.612213) (xy 378.308077 -291.602369) (xy 378.357252 -291.600388) (xy 378.406107 -291.60632)
			(xy 378.453378 -291.620012) (xy 378.49784 -291.64111) (xy 378.538343 -291.669066) (xy 378.573836 -291.703158)
			(xy 378.603401 -291.742502) (xy 378.626272 -291.786079) (xy 378.641856 -291.83276) (xy 378.649751 -291.881337)
			(xy 378.650246 -291.905944) (xy 378.968503 -291.905944) (xy 378.972598 -291.855216) (xy 378.984777 -291.805802)
			(xy 379.004725 -291.758982) (xy 379.031926 -291.715968) (xy 379.065674 -291.677874) (xy 379.105096 -291.645687)
			(xy 379.14917 -291.620241) (xy 379.196756 -291.602194) (xy 379.24662 -291.592014) (xy 379.297472 -291.589965)
			(xy 379.347993 -291.596099) (xy 379.396877 -291.610259) (xy 379.442856 -291.632076) (xy 379.48474 -291.660986)
			(xy 379.521444 -291.696241) (xy 379.552017 -291.736927) (xy 379.575668 -291.78199) (xy 379.591784 -291.830264)
			(xy 379.599948 -291.880498) (xy 379.60046 -291.905944) (xy 379.918988 -291.905944) (xy 379.922948 -291.85689)
			(xy 379.934725 -291.809106) (xy 379.954016 -291.76383) (xy 379.980319 -291.722234) (xy 380.012954 -291.685397)
			(xy 380.051075 -291.654272) (xy 380.093696 -291.629665) (xy 380.139712 -291.612213) (xy 380.187931 -291.602369)
			(xy 380.237106 -291.600388) (xy 380.285961 -291.60632) (xy 380.333232 -291.620012) (xy 380.377694 -291.64111)
			(xy 380.418197 -291.669066) (xy 380.45369 -291.703158) (xy 380.483255 -291.742502) (xy 380.506126 -291.786079)
			(xy 380.52171 -291.83276) (xy 380.529605 -291.881337) (xy 380.5301 -291.905944) (xy 380.848611 -291.905944)
			(xy 380.852706 -291.855216) (xy 380.864885 -291.805802) (xy 380.884833 -291.758982) (xy 380.912034 -291.715968)
			(xy 380.945782 -291.677874) (xy 380.985204 -291.645687) (xy 381.029278 -291.620241) (xy 381.076864 -291.602194)
			(xy 381.126728 -291.592014) (xy 381.17758 -291.589965) (xy 381.228101 -291.596099) (xy 381.276985 -291.610259)
			(xy 381.322964 -291.632076) (xy 381.364848 -291.660986) (xy 381.401552 -291.696241) (xy 381.432125 -291.736927)
			(xy 381.455776 -291.78199) (xy 381.471892 -291.830264) (xy 381.480056 -291.880498) (xy 381.480568 -291.905944)
			(xy 381.799096 -291.905944) (xy 381.803056 -291.85689) (xy 381.814833 -291.809106) (xy 381.834124 -291.76383)
			(xy 381.860427 -291.722234) (xy 381.893062 -291.685397) (xy 381.931183 -291.654272) (xy 381.973804 -291.629665)
			(xy 382.01982 -291.612213) (xy 382.068039 -291.602369) (xy 382.117214 -291.600388) (xy 382.166069 -291.60632)
			(xy 382.21334 -291.620012) (xy 382.257802 -291.64111) (xy 382.298305 -291.669066) (xy 382.333798 -291.703158)
			(xy 382.363363 -291.742502) (xy 382.386234 -291.786079) (xy 382.401818 -291.83276) (xy 382.409713 -291.881337)
			(xy 382.410208 -291.905944) (xy 382.738896 -291.905944) (xy 382.742856 -291.85689) (xy 382.754633 -291.809106)
			(xy 382.773924 -291.76383) (xy 382.800227 -291.722234) (xy 382.832862 -291.685397) (xy 382.870983 -291.654272)
			(xy 382.913604 -291.629665) (xy 382.95962 -291.612213) (xy 383.007839 -291.602369) (xy 383.057014 -291.600388)
			(xy 383.105869 -291.60632) (xy 383.15314 -291.620012) (xy 383.197602 -291.64111) (xy 383.238105 -291.669066)
			(xy 383.273598 -291.703158) (xy 383.303163 -291.742502) (xy 383.326034 -291.786079) (xy 383.341618 -291.83276)
			(xy 383.349513 -291.881337) (xy 383.350008 -291.905944) (xy 383.67895 -291.905944) (xy 383.68291 -291.85689)
			(xy 383.694687 -291.809106) (xy 383.713978 -291.76383) (xy 383.740281 -291.722234) (xy 383.772916 -291.685397)
			(xy 383.811037 -291.654272) (xy 383.853658 -291.629665) (xy 383.899674 -291.612213) (xy 383.947893 -291.602369)
			(xy 383.997068 -291.600388) (xy 384.045923 -291.60632) (xy 384.093194 -291.620012) (xy 384.137656 -291.64111)
			(xy 384.178159 -291.669066) (xy 384.213652 -291.703158) (xy 384.243217 -291.742502) (xy 384.266088 -291.786079)
			(xy 384.281672 -291.83276) (xy 384.289567 -291.881337) (xy 384.290062 -291.905944) (xy 384.289567 -291.930551)
			(xy 384.281672 -291.979128) (xy 384.266088 -292.025809) (xy 384.243217 -292.069386) (xy 384.213652 -292.10873)
			(xy 384.178159 -292.142822) (xy 384.137656 -292.170778) (xy 384.093194 -292.191876) (xy 384.045923 -292.205568)
			(xy 383.997068 -292.2115) (xy 383.947893 -292.209519) (xy 383.899674 -292.199675) (xy 383.853658 -292.182223)
			(xy 383.811037 -292.157616) (xy 383.772916 -292.126491) (xy 383.740281 -292.089654) (xy 383.713978 -292.048058)
			(xy 383.694687 -292.002782) (xy 383.68291 -291.954998) (xy 383.67895 -291.905944) (xy 383.350008 -291.905944)
			(xy 383.349513 -291.930551) (xy 383.341618 -291.979128) (xy 383.326034 -292.025809) (xy 383.303163 -292.069386)
			(xy 383.273598 -292.10873) (xy 383.238105 -292.142822) (xy 383.197602 -292.170778) (xy 383.15314 -292.191876)
			(xy 383.105869 -292.205568) (xy 383.057014 -292.2115) (xy 383.007839 -292.209519) (xy 382.95962 -292.199675)
			(xy 382.913604 -292.182223) (xy 382.870983 -292.157616) (xy 382.832862 -292.126491) (xy 382.800227 -292.089654)
			(xy 382.773924 -292.048058) (xy 382.754633 -292.002782) (xy 382.742856 -291.954998) (xy 382.738896 -291.905944)
			(xy 382.410208 -291.905944) (xy 382.409713 -291.930551) (xy 382.401818 -291.979128) (xy 382.386234 -292.025809)
			(xy 382.363363 -292.069386) (xy 382.333798 -292.10873) (xy 382.298305 -292.142822) (xy 382.257802 -292.170778)
			(xy 382.21334 -292.191876) (xy 382.166069 -292.205568) (xy 382.117214 -292.2115) (xy 382.068039 -292.209519)
			(xy 382.01982 -292.199675) (xy 381.973804 -292.182223) (xy 381.931183 -292.157616) (xy 381.893062 -292.126491)
			(xy 381.860427 -292.089654) (xy 381.834124 -292.048058) (xy 381.814833 -292.002782) (xy 381.803056 -291.954998)
			(xy 381.799096 -291.905944) (xy 381.480568 -291.905944) (xy 381.480056 -291.93139) (xy 381.471892 -291.981624)
			(xy 381.455776 -292.029898) (xy 381.432125 -292.074961) (xy 381.401552 -292.115647) (xy 381.364848 -292.150902)
			(xy 381.322964 -292.179812) (xy 381.276985 -292.201629) (xy 381.228101 -292.215789) (xy 381.17758 -292.221923)
			(xy 381.126728 -292.219874) (xy 381.076864 -292.209694) (xy 381.029278 -292.191647) (xy 380.985204 -292.166201)
			(xy 380.945782 -292.134014) (xy 380.912034 -292.09592) (xy 380.884833 -292.052906) (xy 380.864885 -292.006086)
			(xy 380.852706 -291.956672) (xy 380.848611 -291.905944) (xy 380.5301 -291.905944) (xy 380.529605 -291.930551)
			(xy 380.52171 -291.979128) (xy 380.506126 -292.025809) (xy 380.483255 -292.069386) (xy 380.45369 -292.10873)
			(xy 380.418197 -292.142822) (xy 380.377694 -292.170778) (xy 380.333232 -292.191876) (xy 380.285961 -292.205568)
			(xy 380.237106 -292.2115) (xy 380.187931 -292.209519) (xy 380.139712 -292.199675) (xy 380.093696 -292.182223)
			(xy 380.051075 -292.157616) (xy 380.012954 -292.126491) (xy 379.980319 -292.089654) (xy 379.954016 -292.048058)
			(xy 379.934725 -292.002782) (xy 379.922948 -291.954998) (xy 379.918988 -291.905944) (xy 379.60046 -291.905944)
			(xy 379.599948 -291.93139) (xy 379.591784 -291.981624) (xy 379.575668 -292.029898) (xy 379.552017 -292.074961)
			(xy 379.521444 -292.115647) (xy 379.48474 -292.150902) (xy 379.442856 -292.179812) (xy 379.396877 -292.201629)
			(xy 379.347993 -292.215789) (xy 379.297472 -292.221923) (xy 379.24662 -292.219874) (xy 379.196756 -292.209694)
			(xy 379.14917 -292.191647) (xy 379.105096 -292.166201) (xy 379.065674 -292.134014) (xy 379.031926 -292.09592)
			(xy 379.004725 -292.052906) (xy 378.984777 -292.006086) (xy 378.972598 -291.956672) (xy 378.968503 -291.905944)
			(xy 378.650246 -291.905944) (xy 378.649751 -291.930551) (xy 378.641856 -291.979128) (xy 378.626272 -292.025809)
			(xy 378.603401 -292.069386) (xy 378.573836 -292.10873) (xy 378.538343 -292.142822) (xy 378.49784 -292.170778)
			(xy 378.453378 -292.191876) (xy 378.406107 -292.205568) (xy 378.357252 -292.2115) (xy 378.308077 -292.209519)
			(xy 378.259858 -292.199675) (xy 378.213842 -292.182223) (xy 378.171221 -292.157616) (xy 378.1331 -292.126491)
			(xy 378.100465 -292.089654) (xy 378.074162 -292.048058) (xy 378.054871 -292.002782) (xy 378.043094 -291.954998)
			(xy 378.039134 -291.905944) (xy 377.720606 -291.905944) (xy 377.720094 -291.93139) (xy 377.71193 -291.981624)
			(xy 377.695814 -292.029898) (xy 377.672163 -292.074961) (xy 377.64159 -292.115647) (xy 377.604886 -292.150902)
			(xy 377.563002 -292.179812) (xy 377.517023 -292.201629) (xy 377.468139 -292.215789) (xy 377.417618 -292.221923)
			(xy 377.366766 -292.219874) (xy 377.316902 -292.209694) (xy 377.269316 -292.191647) (xy 377.225242 -292.166201)
			(xy 377.18582 -292.134014) (xy 377.152072 -292.09592) (xy 377.124871 -292.052906) (xy 377.104923 -292.006086)
			(xy 377.092744 -291.956672) (xy 377.088649 -291.905944) (xy 376.780552 -291.905944) (xy 376.78004 -291.93139)
			(xy 376.771876 -291.981624) (xy 376.75576 -292.029898) (xy 376.732109 -292.074961) (xy 376.701536 -292.115647)
			(xy 376.664832 -292.150902) (xy 376.622948 -292.179812) (xy 376.576969 -292.201629) (xy 376.528085 -292.215789)
			(xy 376.477564 -292.221923) (xy 376.426712 -292.219874) (xy 376.376848 -292.209694) (xy 376.329262 -292.191647)
			(xy 376.285188 -292.166201) (xy 376.245766 -292.134014) (xy 376.212018 -292.09592) (xy 376.184817 -292.052906)
			(xy 376.164869 -292.006086) (xy 376.15269 -291.956672) (xy 376.148595 -291.905944) (xy 375.833569 -291.905944)
			(xy 375.833898 -291.929606) (xy 375.824585 -291.984826) (xy 375.815606 -292.011354) (xy 375.814179 -292.015594)
			(xy 375.812646 -292.024407) (xy 375.812558 -292.02888) (xy 375.812558 -292.071298) (xy 375.812019 -292.081134)
			(xy 375.804431 -292.099294) (xy 375.797826 -292.106604) (xy 375.678446 -292.225984) (xy 375.673874 -292.231318)
			(xy 375.67108 -292.235382) (xy 375.661936 -292.250622) (xy 375.660158 -292.25621) (xy 375.651536 -292.282265)
			(xy 375.632096 -292.333596) (xy 375.621296 -292.358826) (xy 375.616978 -292.368478) (xy 375.616978 -292.420548)
			(xy 375.617497 -292.430403) (xy 375.625027 -292.448625) (xy 375.638851 -292.462685) (xy 375.647712 -292.46703)
			(xy 375.727468 -292.50132) (xy 375.734373 -292.50401) (xy 375.74909 -292.505683) (xy 375.756424 -292.504622)
			(xy 375.76125 -292.50386) (xy 375.779327 -292.484701) (xy 375.820689 -292.452088) (xy 375.866893 -292.426799)
			(xy 375.916655 -292.409534) (xy 375.968594 -292.400774) (xy 375.99493 -292.400228) (xy 376.019734 -292.400717)
			(xy 376.068731 -292.408481) (xy 376.11591 -292.423815) (xy 376.16011 -292.446339) (xy 376.200242 -292.475501)
			(xy 376.235319 -292.510581) (xy 376.264476 -292.550716) (xy 376.286997 -292.594918) (xy 376.302326 -292.642098)
			(xy 376.310086 -292.691096) (xy 376.310086 -292.71595) (xy 376.628926 -292.71595) (xy 376.632886 -292.666896)
			(xy 376.644663 -292.619112) (xy 376.663954 -292.573836) (xy 376.690257 -292.53224) (xy 376.722892 -292.495403)
			(xy 376.761013 -292.464278) (xy 376.803634 -292.439671) (xy 376.84965 -292.422219) (xy 376.897869 -292.412375)
			(xy 376.947044 -292.410394) (xy 376.995899 -292.416326) (xy 377.04317 -292.430018) (xy 377.087632 -292.451116)
			(xy 377.128135 -292.479072) (xy 377.163628 -292.513164) (xy 377.193193 -292.552508) (xy 377.216064 -292.596085)
			(xy 377.231648 -292.642766) (xy 377.239543 -292.691343) (xy 377.240038 -292.71595) (xy 377.558549 -292.71595)
			(xy 377.562644 -292.665222) (xy 377.574823 -292.615808) (xy 377.594771 -292.568988) (xy 377.621972 -292.525974)
			(xy 377.65572 -292.48788) (xy 377.695142 -292.455693) (xy 377.739216 -292.430247) (xy 377.786802 -292.4122)
			(xy 377.836666 -292.40202) (xy 377.887518 -292.399971) (xy 377.938039 -292.406105) (xy 377.986923 -292.420265)
			(xy 378.032902 -292.442082) (xy 378.074786 -292.470992) (xy 378.11149 -292.506247) (xy 378.142063 -292.546933)
			(xy 378.165714 -292.591996) (xy 378.18183 -292.64027) (xy 378.189994 -292.690504) (xy 378.190506 -292.71595)
			(xy 379.438657 -292.71595) (xy 379.442752 -292.665222) (xy 379.454931 -292.615808) (xy 379.474879 -292.568988)
			(xy 379.50208 -292.525974) (xy 379.535828 -292.48788) (xy 379.57525 -292.455693) (xy 379.619324 -292.430247)
			(xy 379.66691 -292.4122) (xy 379.716774 -292.40202) (xy 379.767626 -292.399971) (xy 379.818147 -292.406105)
			(xy 379.867031 -292.420265) (xy 379.91301 -292.442082) (xy 379.954894 -292.470992) (xy 379.991598 -292.506247)
			(xy 380.022171 -292.546933) (xy 380.045822 -292.591996) (xy 380.061938 -292.64027) (xy 380.070102 -292.690504)
			(xy 380.070614 -292.71595) (xy 380.378711 -292.71595) (xy 380.382806 -292.665222) (xy 380.394985 -292.615808)
			(xy 380.414933 -292.568988) (xy 380.442134 -292.525974) (xy 380.475882 -292.48788) (xy 380.515304 -292.455693)
			(xy 380.559378 -292.430247) (xy 380.606964 -292.4122) (xy 380.656828 -292.40202) (xy 380.70768 -292.399971)
			(xy 380.758201 -292.406105) (xy 380.807085 -292.420265) (xy 380.853064 -292.442082) (xy 380.894948 -292.470992)
			(xy 380.931652 -292.506247) (xy 380.962225 -292.546933) (xy 380.985876 -292.591996) (xy 381.001992 -292.64027)
			(xy 381.010156 -292.690504) (xy 381.010668 -292.71595) (xy 381.328942 -292.71595) (xy 381.332902 -292.666896)
			(xy 381.344679 -292.619112) (xy 381.36397 -292.573836) (xy 381.390273 -292.53224) (xy 381.422908 -292.495403)
			(xy 381.461029 -292.464278) (xy 381.50365 -292.439671) (xy 381.549666 -292.422219) (xy 381.597885 -292.412375)
			(xy 381.64706 -292.410394) (xy 381.695915 -292.416326) (xy 381.743186 -292.430018) (xy 381.787648 -292.451116)
			(xy 381.828151 -292.479072) (xy 381.863644 -292.513164) (xy 381.893209 -292.552508) (xy 381.91608 -292.596085)
			(xy 381.931664 -292.642766) (xy 381.939559 -292.691343) (xy 381.940054 -292.71595) (xy 382.268996 -292.71595)
			(xy 382.272956 -292.666896) (xy 382.284733 -292.619112) (xy 382.304024 -292.573836) (xy 382.330327 -292.53224)
			(xy 382.362962 -292.495403) (xy 382.401083 -292.464278) (xy 382.443704 -292.439671) (xy 382.48972 -292.422219)
			(xy 382.537939 -292.412375) (xy 382.587114 -292.410394) (xy 382.635969 -292.416326) (xy 382.68324 -292.430018)
			(xy 382.727702 -292.451116) (xy 382.768205 -292.479072) (xy 382.803698 -292.513164) (xy 382.833263 -292.552508)
			(xy 382.856134 -292.596085) (xy 382.871718 -292.642766) (xy 382.879613 -292.691343) (xy 382.880108 -292.71595)
			(xy 383.20905 -292.71595) (xy 383.21301 -292.666896) (xy 383.224787 -292.619112) (xy 383.244078 -292.573836)
			(xy 383.270381 -292.53224) (xy 383.303016 -292.495403) (xy 383.341137 -292.464278) (xy 383.383758 -292.439671)
			(xy 383.429774 -292.422219) (xy 383.477993 -292.412375) (xy 383.527168 -292.410394) (xy 383.576023 -292.416326)
			(xy 383.623294 -292.430018) (xy 383.667756 -292.451116) (xy 383.708259 -292.479072) (xy 383.743752 -292.513164)
			(xy 383.773317 -292.552508) (xy 383.796188 -292.596085) (xy 383.811772 -292.642766) (xy 383.819667 -292.691343)
			(xy 383.820162 -292.71595) (xy 384.149104 -292.71595) (xy 384.153064 -292.666896) (xy 384.164841 -292.619112)
			(xy 384.184132 -292.573836) (xy 384.210435 -292.53224) (xy 384.24307 -292.495403) (xy 384.281191 -292.464278)
			(xy 384.323812 -292.439671) (xy 384.369828 -292.422219) (xy 384.418047 -292.412375) (xy 384.467222 -292.410394)
			(xy 384.516077 -292.416326) (xy 384.563348 -292.430018) (xy 384.60781 -292.451116) (xy 384.648313 -292.479072)
			(xy 384.683806 -292.513164) (xy 384.713371 -292.552508) (xy 384.736242 -292.596085) (xy 384.751826 -292.642766)
			(xy 384.759721 -292.691343) (xy 384.760216 -292.71595) (xy 384.759721 -292.740557) (xy 384.751826 -292.789134)
			(xy 384.736242 -292.835815) (xy 384.713371 -292.879392) (xy 384.683806 -292.918736) (xy 384.648313 -292.952828)
			(xy 384.60781 -292.980784) (xy 384.563348 -293.001882) (xy 384.516077 -293.015574) (xy 384.467222 -293.021506)
			(xy 384.418047 -293.019525) (xy 384.369828 -293.009681) (xy 384.323812 -292.992229) (xy 384.281191 -292.967622)
			(xy 384.24307 -292.936497) (xy 384.210435 -292.89966) (xy 384.184132 -292.858064) (xy 384.164841 -292.812788)
			(xy 384.153064 -292.765004) (xy 384.149104 -292.71595) (xy 383.820162 -292.71595) (xy 383.819667 -292.740557)
			(xy 383.811772 -292.789134) (xy 383.796188 -292.835815) (xy 383.773317 -292.879392) (xy 383.743752 -292.918736)
			(xy 383.708259 -292.952828) (xy 383.667756 -292.980784) (xy 383.623294 -293.001882) (xy 383.576023 -293.015574)
			(xy 383.527168 -293.021506) (xy 383.477993 -293.019525) (xy 383.429774 -293.009681) (xy 383.383758 -292.992229)
			(xy 383.341137 -292.967622) (xy 383.303016 -292.936497) (xy 383.270381 -292.89966) (xy 383.244078 -292.858064)
			(xy 383.224787 -292.812788) (xy 383.21301 -292.765004) (xy 383.20905 -292.71595) (xy 382.880108 -292.71595)
			(xy 382.879613 -292.740557) (xy 382.871718 -292.789134) (xy 382.856134 -292.835815) (xy 382.833263 -292.879392)
			(xy 382.803698 -292.918736) (xy 382.768205 -292.952828) (xy 382.727702 -292.980784) (xy 382.68324 -293.001882)
			(xy 382.635969 -293.015574) (xy 382.587114 -293.021506) (xy 382.537939 -293.019525) (xy 382.48972 -293.009681)
			(xy 382.443704 -292.992229) (xy 382.401083 -292.967622) (xy 382.362962 -292.936497) (xy 382.330327 -292.89966)
			(xy 382.304024 -292.858064) (xy 382.284733 -292.812788) (xy 382.272956 -292.765004) (xy 382.268996 -292.71595)
			(xy 381.940054 -292.71595) (xy 381.939559 -292.740557) (xy 381.931664 -292.789134) (xy 381.91608 -292.835815)
			(xy 381.893209 -292.879392) (xy 381.863644 -292.918736) (xy 381.828151 -292.952828) (xy 381.787648 -292.980784)
			(xy 381.743186 -293.001882) (xy 381.695915 -293.015574) (xy 381.64706 -293.021506) (xy 381.597885 -293.019525)
			(xy 381.549666 -293.009681) (xy 381.50365 -292.992229) (xy 381.461029 -292.967622) (xy 381.422908 -292.936497)
			(xy 381.390273 -292.89966) (xy 381.36397 -292.858064) (xy 381.344679 -292.812788) (xy 381.332902 -292.765004)
			(xy 381.328942 -292.71595) (xy 381.010668 -292.71595) (xy 381.010156 -292.741396) (xy 381.001992 -292.79163)
			(xy 380.985876 -292.839904) (xy 380.962225 -292.884967) (xy 380.931652 -292.925653) (xy 380.894948 -292.960908)
			(xy 380.853064 -292.989818) (xy 380.807085 -293.011635) (xy 380.758201 -293.025795) (xy 380.70768 -293.031929)
			(xy 380.656828 -293.02988) (xy 380.606964 -293.0197) (xy 380.559378 -293.001653) (xy 380.515304 -292.976207)
			(xy 380.475882 -292.94402) (xy 380.442134 -292.905926) (xy 380.414933 -292.862912) (xy 380.394985 -292.816092)
			(xy 380.382806 -292.766678) (xy 380.378711 -292.71595) (xy 380.070614 -292.71595) (xy 380.070102 -292.741396)
			(xy 380.061938 -292.79163) (xy 380.045822 -292.839904) (xy 380.022171 -292.884967) (xy 379.991598 -292.925653)
			(xy 379.954894 -292.960908) (xy 379.91301 -292.989818) (xy 379.867031 -293.011635) (xy 379.818147 -293.025795)
			(xy 379.767626 -293.031929) (xy 379.716774 -293.02988) (xy 379.66691 -293.0197) (xy 379.619324 -293.001653)
			(xy 379.57525 -292.976207) (xy 379.535828 -292.94402) (xy 379.50208 -292.905926) (xy 379.474879 -292.862912)
			(xy 379.454931 -292.816092) (xy 379.442752 -292.766678) (xy 379.438657 -292.71595) (xy 378.190506 -292.71595)
			(xy 378.189994 -292.741396) (xy 378.18183 -292.79163) (xy 378.165714 -292.839904) (xy 378.142063 -292.884967)
			(xy 378.11149 -292.925653) (xy 378.074786 -292.960908) (xy 378.032902 -292.989818) (xy 377.986923 -293.011635)
			(xy 377.938039 -293.025795) (xy 377.887518 -293.031929) (xy 377.836666 -293.02988) (xy 377.786802 -293.0197)
			(xy 377.739216 -293.001653) (xy 377.695142 -292.976207) (xy 377.65572 -292.94402) (xy 377.621972 -292.905926)
			(xy 377.594771 -292.862912) (xy 377.574823 -292.816092) (xy 377.562644 -292.766678) (xy 377.558549 -292.71595)
			(xy 377.240038 -292.71595) (xy 377.239543 -292.740557) (xy 377.231648 -292.789134) (xy 377.216064 -292.835815)
			(xy 377.193193 -292.879392) (xy 377.163628 -292.918736) (xy 377.128135 -292.952828) (xy 377.087632 -292.980784)
			(xy 377.04317 -293.001882) (xy 376.995899 -293.015574) (xy 376.947044 -293.021506) (xy 376.897869 -293.019525)
			(xy 376.84965 -293.009681) (xy 376.803634 -292.992229) (xy 376.761013 -292.967622) (xy 376.722892 -292.936497)
			(xy 376.690257 -292.89966) (xy 376.663954 -292.858064) (xy 376.644663 -292.812788) (xy 376.632886 -292.765004)
			(xy 376.628926 -292.71595) (xy 376.310086 -292.71595) (xy 376.310086 -292.740704) (xy 376.302326 -292.789702)
			(xy 376.286997 -292.836882) (xy 376.264476 -292.881084) (xy 376.235319 -292.921219) (xy 376.200242 -292.956299)
			(xy 376.16011 -292.985461) (xy 376.11591 -293.007985) (xy 376.068731 -293.023319) (xy 376.019734 -293.031083)
			(xy 375.99493 -293.031672) (xy 375.970715 -293.031232) (xy 375.922854 -293.02383) (xy 375.876688 -293.009197)
			(xy 375.833302 -292.987675) (xy 375.793718 -292.959772) (xy 375.775982 -292.94328) (xy 375.761758 -292.92931)
			(xy 375.749566 -292.927024) (xy 375.743573 -292.926795) (xy 375.73176 -292.928845) (xy 375.726198 -292.931088)
			(xy 375.647712 -292.96487) (xy 375.638825 -292.969182) (xy 375.624971 -292.983237) (xy 375.617458 -293.001486)
			(xy 375.616978 -293.011352) (xy 375.616978 -293.04869) (xy 375.61774 -293.056564) (xy 375.62028 -293.069264)
			(xy 375.623328 -293.078408) (xy 375.627392 -293.087806) (xy 375.810526 -293.27094) (xy 375.817233 -293.27818)
			(xy 375.824815 -293.296385) (xy 375.825258 -293.306246) (xy 375.825258 -293.47033) (xy 375.82602 -293.474394)
			(xy 375.827991 -293.487128) (xy 375.830024 -293.512817) (xy 375.830084 -293.525702) (xy 375.830084 -293.525956)
			(xy 376.148595 -293.525956) (xy 376.15269 -293.475228) (xy 376.164869 -293.425814) (xy 376.184817 -293.378994)
			(xy 376.212018 -293.33598) (xy 376.245766 -293.297886) (xy 376.285188 -293.265699) (xy 376.329262 -293.240253)
			(xy 376.376848 -293.222206) (xy 376.426712 -293.212026) (xy 376.477564 -293.209977) (xy 376.528085 -293.216111)
			(xy 376.576969 -293.230271) (xy 376.622948 -293.252088) (xy 376.664832 -293.280998) (xy 376.701536 -293.316253)
			(xy 376.732109 -293.356939) (xy 376.75576 -293.402002) (xy 376.771876 -293.450276) (xy 376.78004 -293.50051)
			(xy 376.780552 -293.525956) (xy 377.09908 -293.525956) (xy 377.10304 -293.476902) (xy 377.114817 -293.429118)
			(xy 377.134108 -293.383842) (xy 377.160411 -293.342246) (xy 377.193046 -293.305409) (xy 377.231167 -293.274284)
			(xy 377.273788 -293.249677) (xy 377.319804 -293.232225) (xy 377.368023 -293.222381) (xy 377.417198 -293.2204)
			(xy 377.466053 -293.226332) (xy 377.513324 -293.240024) (xy 377.557786 -293.261122) (xy 377.598289 -293.289078)
			(xy 377.633782 -293.32317) (xy 377.663347 -293.362514) (xy 377.686218 -293.406091) (xy 377.701802 -293.452772)
			(xy 377.709697 -293.501349) (xy 377.710192 -293.525956) (xy 378.039134 -293.525956) (xy 378.043094 -293.476902)
			(xy 378.054871 -293.429118) (xy 378.074162 -293.383842) (xy 378.100465 -293.342246) (xy 378.1331 -293.305409)
			(xy 378.171221 -293.274284) (xy 378.213842 -293.249677) (xy 378.259858 -293.232225) (xy 378.308077 -293.222381)
			(xy 378.357252 -293.2204) (xy 378.406107 -293.226332) (xy 378.453378 -293.240024) (xy 378.49784 -293.261122)
			(xy 378.538343 -293.289078) (xy 378.573836 -293.32317) (xy 378.603401 -293.362514) (xy 378.626272 -293.406091)
			(xy 378.641856 -293.452772) (xy 378.649751 -293.501349) (xy 378.650246 -293.525956) (xy 378.978934 -293.525956)
			(xy 378.982894 -293.476902) (xy 378.994671 -293.429118) (xy 379.013962 -293.383842) (xy 379.040265 -293.342246)
			(xy 379.0729 -293.305409) (xy 379.111021 -293.274284) (xy 379.153642 -293.249677) (xy 379.199658 -293.232225)
			(xy 379.247877 -293.222381) (xy 379.297052 -293.2204) (xy 379.345907 -293.226332) (xy 379.393178 -293.240024)
			(xy 379.43764 -293.261122) (xy 379.478143 -293.289078) (xy 379.513636 -293.32317) (xy 379.543201 -293.362514)
			(xy 379.566072 -293.406091) (xy 379.581656 -293.452772) (xy 379.589551 -293.501349) (xy 379.590046 -293.525956)
			(xy 379.918988 -293.525956) (xy 379.922948 -293.476902) (xy 379.934725 -293.429118) (xy 379.954016 -293.383842)
			(xy 379.980319 -293.342246) (xy 380.012954 -293.305409) (xy 380.051075 -293.274284) (xy 380.093696 -293.249677)
			(xy 380.139712 -293.232225) (xy 380.187931 -293.222381) (xy 380.237106 -293.2204) (xy 380.285961 -293.226332)
			(xy 380.333232 -293.240024) (xy 380.377694 -293.261122) (xy 380.418197 -293.289078) (xy 380.45369 -293.32317)
			(xy 380.483255 -293.362514) (xy 380.506126 -293.406091) (xy 380.52171 -293.452772) (xy 380.529605 -293.501349)
			(xy 380.5301 -293.525956) (xy 380.848611 -293.525956) (xy 380.852706 -293.475228) (xy 380.864885 -293.425814)
			(xy 380.884833 -293.378994) (xy 380.912034 -293.33598) (xy 380.945782 -293.297886) (xy 380.985204 -293.265699)
			(xy 381.029278 -293.240253) (xy 381.076864 -293.222206) (xy 381.126728 -293.212026) (xy 381.17758 -293.209977)
			(xy 381.228101 -293.216111) (xy 381.276985 -293.230271) (xy 381.322964 -293.252088) (xy 381.364848 -293.280998)
			(xy 381.401552 -293.316253) (xy 381.432125 -293.356939) (xy 381.455776 -293.402002) (xy 381.471892 -293.450276)
			(xy 381.480056 -293.50051) (xy 381.480568 -293.525956) (xy 381.799096 -293.525956) (xy 381.803056 -293.476902)
			(xy 381.814833 -293.429118) (xy 381.834124 -293.383842) (xy 381.860427 -293.342246) (xy 381.893062 -293.305409)
			(xy 381.931183 -293.274284) (xy 381.973804 -293.249677) (xy 382.01982 -293.232225) (xy 382.068039 -293.222381)
			(xy 382.117214 -293.2204) (xy 382.166069 -293.226332) (xy 382.21334 -293.240024) (xy 382.257802 -293.261122)
			(xy 382.298305 -293.289078) (xy 382.333798 -293.32317) (xy 382.363363 -293.362514) (xy 382.386234 -293.406091)
			(xy 382.401818 -293.452772) (xy 382.409713 -293.501349) (xy 382.410208 -293.525956) (xy 382.738896 -293.525956)
			(xy 382.742856 -293.476902) (xy 382.754633 -293.429118) (xy 382.773924 -293.383842) (xy 382.800227 -293.342246)
			(xy 382.832862 -293.305409) (xy 382.870983 -293.274284) (xy 382.913604 -293.249677) (xy 382.95962 -293.232225)
			(xy 383.007839 -293.222381) (xy 383.057014 -293.2204) (xy 383.105869 -293.226332) (xy 383.15314 -293.240024)
			(xy 383.197602 -293.261122) (xy 383.238105 -293.289078) (xy 383.273598 -293.32317) (xy 383.303163 -293.362514)
			(xy 383.326034 -293.406091) (xy 383.341618 -293.452772) (xy 383.349513 -293.501349) (xy 383.350008 -293.525956)
			(xy 383.67895 -293.525956) (xy 383.68291 -293.476902) (xy 383.694687 -293.429118) (xy 383.713978 -293.383842)
			(xy 383.740281 -293.342246) (xy 383.772916 -293.305409) (xy 383.811037 -293.274284) (xy 383.853658 -293.249677)
			(xy 383.899674 -293.232225) (xy 383.947893 -293.222381) (xy 383.997068 -293.2204) (xy 384.045923 -293.226332)
			(xy 384.093194 -293.240024) (xy 384.137656 -293.261122) (xy 384.178159 -293.289078) (xy 384.213652 -293.32317)
			(xy 384.243217 -293.362514) (xy 384.266088 -293.406091) (xy 384.281672 -293.452772) (xy 384.289567 -293.501349)
			(xy 384.290062 -293.525956) (xy 384.619004 -293.525956) (xy 384.622964 -293.476902) (xy 384.634741 -293.429118)
			(xy 384.654032 -293.383842) (xy 384.680335 -293.342246) (xy 384.71297 -293.305409) (xy 384.751091 -293.274284)
			(xy 384.793712 -293.249677) (xy 384.839728 -293.232225) (xy 384.887947 -293.222381) (xy 384.937122 -293.2204)
			(xy 384.985977 -293.226332) (xy 385.033248 -293.240024) (xy 385.07771 -293.261122) (xy 385.118213 -293.289078)
			(xy 385.153706 -293.32317) (xy 385.183271 -293.362514) (xy 385.206142 -293.406091) (xy 385.221726 -293.452772)
			(xy 385.229621 -293.501349) (xy 385.230116 -293.525956) (xy 385.229621 -293.550563) (xy 385.221726 -293.59914)
			(xy 385.206142 -293.645821) (xy 385.183271 -293.689398) (xy 385.153706 -293.728742) (xy 385.118213 -293.762834)
			(xy 385.07771 -293.79079) (xy 385.033248 -293.811888) (xy 384.985977 -293.82558) (xy 384.937122 -293.831512)
			(xy 384.887947 -293.829531) (xy 384.839728 -293.819687) (xy 384.793712 -293.802235) (xy 384.751091 -293.777628)
			(xy 384.71297 -293.746503) (xy 384.680335 -293.709666) (xy 384.654032 -293.66807) (xy 384.634741 -293.622794)
			(xy 384.622964 -293.57501) (xy 384.619004 -293.525956) (xy 384.290062 -293.525956) (xy 384.289567 -293.550563)
			(xy 384.281672 -293.59914) (xy 384.266088 -293.645821) (xy 384.243217 -293.689398) (xy 384.213652 -293.728742)
			(xy 384.178159 -293.762834) (xy 384.137656 -293.79079) (xy 384.093194 -293.811888) (xy 384.045923 -293.82558)
			(xy 383.997068 -293.831512) (xy 383.947893 -293.829531) (xy 383.899674 -293.819687) (xy 383.853658 -293.802235)
			(xy 383.811037 -293.777628) (xy 383.772916 -293.746503) (xy 383.740281 -293.709666) (xy 383.713978 -293.66807)
			(xy 383.694687 -293.622794) (xy 383.68291 -293.57501) (xy 383.67895 -293.525956) (xy 383.350008 -293.525956)
			(xy 383.349513 -293.550563) (xy 383.341618 -293.59914) (xy 383.326034 -293.645821) (xy 383.303163 -293.689398)
			(xy 383.273598 -293.728742) (xy 383.238105 -293.762834) (xy 383.197602 -293.79079) (xy 383.15314 -293.811888)
			(xy 383.105869 -293.82558) (xy 383.057014 -293.831512) (xy 383.007839 -293.829531) (xy 382.95962 -293.819687)
			(xy 382.913604 -293.802235) (xy 382.870983 -293.777628) (xy 382.832862 -293.746503) (xy 382.800227 -293.709666)
			(xy 382.773924 -293.66807) (xy 382.754633 -293.622794) (xy 382.742856 -293.57501) (xy 382.738896 -293.525956)
			(xy 382.410208 -293.525956) (xy 382.409713 -293.550563) (xy 382.401818 -293.59914) (xy 382.386234 -293.645821)
			(xy 382.363363 -293.689398) (xy 382.333798 -293.728742) (xy 382.298305 -293.762834) (xy 382.257802 -293.79079)
			(xy 382.21334 -293.811888) (xy 382.166069 -293.82558) (xy 382.117214 -293.831512) (xy 382.068039 -293.829531)
			(xy 382.01982 -293.819687) (xy 381.973804 -293.802235) (xy 381.931183 -293.777628) (xy 381.893062 -293.746503)
			(xy 381.860427 -293.709666) (xy 381.834124 -293.66807) (xy 381.814833 -293.622794) (xy 381.803056 -293.57501)
			(xy 381.799096 -293.525956) (xy 381.480568 -293.525956) (xy 381.480056 -293.551402) (xy 381.471892 -293.601636)
			(xy 381.455776 -293.64991) (xy 381.432125 -293.694973) (xy 381.401552 -293.735659) (xy 381.364848 -293.770914)
			(xy 381.322964 -293.799824) (xy 381.276985 -293.821641) (xy 381.228101 -293.835801) (xy 381.17758 -293.841935)
			(xy 381.126728 -293.839886) (xy 381.076864 -293.829706) (xy 381.029278 -293.811659) (xy 380.985204 -293.786213)
			(xy 380.945782 -293.754026) (xy 380.912034 -293.715932) (xy 380.884833 -293.672918) (xy 380.864885 -293.626098)
			(xy 380.852706 -293.576684) (xy 380.848611 -293.525956) (xy 380.5301 -293.525956) (xy 380.529605 -293.550563)
			(xy 380.52171 -293.59914) (xy 380.506126 -293.645821) (xy 380.483255 -293.689398) (xy 380.45369 -293.728742)
			(xy 380.418197 -293.762834) (xy 380.377694 -293.79079) (xy 380.333232 -293.811888) (xy 380.285961 -293.82558)
			(xy 380.237106 -293.831512) (xy 380.187931 -293.829531) (xy 380.139712 -293.819687) (xy 380.093696 -293.802235)
			(xy 380.051075 -293.777628) (xy 380.012954 -293.746503) (xy 379.980319 -293.709666) (xy 379.954016 -293.66807)
			(xy 379.934725 -293.622794) (xy 379.922948 -293.57501) (xy 379.918988 -293.525956) (xy 379.590046 -293.525956)
			(xy 379.589551 -293.550563) (xy 379.581656 -293.59914) (xy 379.566072 -293.645821) (xy 379.543201 -293.689398)
			(xy 379.513636 -293.728742) (xy 379.478143 -293.762834) (xy 379.43764 -293.79079) (xy 379.393178 -293.811888)
			(xy 379.345907 -293.82558) (xy 379.297052 -293.831512) (xy 379.247877 -293.829531) (xy 379.199658 -293.819687)
			(xy 379.153642 -293.802235) (xy 379.111021 -293.777628) (xy 379.0729 -293.746503) (xy 379.040265 -293.709666)
			(xy 379.013962 -293.66807) (xy 378.994671 -293.622794) (xy 378.982894 -293.57501) (xy 378.978934 -293.525956)
			(xy 378.650246 -293.525956) (xy 378.649751 -293.550563) (xy 378.641856 -293.59914) (xy 378.626272 -293.645821)
			(xy 378.603401 -293.689398) (xy 378.573836 -293.728742) (xy 378.538343 -293.762834) (xy 378.49784 -293.79079)
			(xy 378.453378 -293.811888) (xy 378.406107 -293.82558) (xy 378.357252 -293.831512) (xy 378.308077 -293.829531)
			(xy 378.259858 -293.819687) (xy 378.213842 -293.802235) (xy 378.171221 -293.777628) (xy 378.1331 -293.746503)
			(xy 378.100465 -293.709666) (xy 378.074162 -293.66807) (xy 378.054871 -293.622794) (xy 378.043094 -293.57501)
			(xy 378.039134 -293.525956) (xy 377.710192 -293.525956) (xy 377.709697 -293.550563) (xy 377.701802 -293.59914)
			(xy 377.686218 -293.645821) (xy 377.663347 -293.689398) (xy 377.633782 -293.728742) (xy 377.598289 -293.762834)
			(xy 377.557786 -293.79079) (xy 377.513324 -293.811888) (xy 377.466053 -293.82558) (xy 377.417198 -293.831512)
			(xy 377.368023 -293.829531) (xy 377.319804 -293.819687) (xy 377.273788 -293.802235) (xy 377.231167 -293.777628)
			(xy 377.193046 -293.746503) (xy 377.160411 -293.709666) (xy 377.134108 -293.66807) (xy 377.114817 -293.622794)
			(xy 377.10304 -293.57501) (xy 377.09908 -293.525956) (xy 376.780552 -293.525956) (xy 376.78004 -293.551402)
			(xy 376.771876 -293.601636) (xy 376.75576 -293.64991) (xy 376.732109 -293.694973) (xy 376.701536 -293.735659)
			(xy 376.664832 -293.770914) (xy 376.622948 -293.799824) (xy 376.576969 -293.821641) (xy 376.528085 -293.835801)
			(xy 376.477564 -293.841935) (xy 376.426712 -293.839886) (xy 376.376848 -293.829706) (xy 376.329262 -293.811659)
			(xy 376.285188 -293.786213) (xy 376.245766 -293.754026) (xy 376.212018 -293.715932) (xy 376.184817 -293.672918)
			(xy 376.164869 -293.626098) (xy 376.15269 -293.576684) (xy 376.148595 -293.525956) (xy 375.830084 -293.525956)
			(xy 375.830084 -293.52621) (xy 375.830012 -293.539095) (xy 375.82798 -293.564783) (xy 375.82602 -293.577518)
			(xy 375.825258 -293.581582) (xy 375.825258 -293.661338) (xy 375.82473 -293.671179) (xy 375.817157 -293.689354)
			(xy 375.810526 -293.696644) (xy 375.682002 -293.825168) (xy 375.674128 -293.835328) (xy 375.67108 -293.840662)
			(xy 375.669302 -293.846758) (xy 375.662698 -293.867586) (xy 375.662444 -293.868348) (xy 375.660158 -293.875968)
			(xy 375.660158 -294.005) (xy 375.660158 -294.005254) (xy 375.660519 -294.013758) (xy 375.666169 -294.029803)
			(xy 375.67676 -294.043114) (xy 375.68378 -294.047926) (xy 375.764552 -294.089582) (xy 375.773312 -294.093212)
			(xy 375.792212 -294.094532) (xy 375.801382 -294.092122) (xy 375.817384 -294.087296) (xy 375.824242 -294.082724)
			(xy 375.843223 -294.070417) (xy 375.884054 -294.050946) (xy 375.927316 -294.037732) (xy 375.972058 -294.031064)
			(xy 375.994676 -294.030654) (xy 376.005852 -294.030654) (xy 376.014488 -294.031162) (xy 376.03998 -294.033315)
			(xy 376.089772 -294.045048) (xy 376.13691 -294.06492) (xy 376.180074 -294.092374) (xy 376.218057 -294.126641)
			(xy 376.249794 -294.166761) (xy 376.274396 -294.211612) (xy 376.291176 -294.259937) (xy 376.299662 -294.310384)
			(xy 376.300238 -294.335962) (xy 376.628926 -294.335962) (xy 376.632886 -294.286908) (xy 376.644663 -294.239124)
			(xy 376.663954 -294.193848) (xy 376.690257 -294.152252) (xy 376.722892 -294.115415) (xy 376.761013 -294.08429)
			(xy 376.803634 -294.059683) (xy 376.84965 -294.042231) (xy 376.897869 -294.032387) (xy 376.947044 -294.030406)
			(xy 376.995899 -294.036338) (xy 377.04317 -294.05003) (xy 377.087632 -294.071128) (xy 377.128135 -294.099084)
			(xy 377.163628 -294.133176) (xy 377.193193 -294.17252) (xy 377.216064 -294.216097) (xy 377.231648 -294.262778)
			(xy 377.239543 -294.311355) (xy 377.240038 -294.335962) (xy 377.56898 -294.335962) (xy 377.57294 -294.286908)
			(xy 377.584717 -294.239124) (xy 377.604008 -294.193848) (xy 377.630311 -294.152252) (xy 377.662946 -294.115415)
			(xy 377.701067 -294.08429) (xy 377.743688 -294.059683) (xy 377.789704 -294.042231) (xy 377.837923 -294.032387)
			(xy 377.887098 -294.030406) (xy 377.935953 -294.036338) (xy 377.983224 -294.05003) (xy 378.027686 -294.071128)
			(xy 378.068189 -294.099084) (xy 378.103682 -294.133176) (xy 378.133247 -294.17252) (xy 378.156118 -294.216097)
			(xy 378.171702 -294.262778) (xy 378.179597 -294.311355) (xy 378.180092 -294.335962) (xy 378.509034 -294.335962)
			(xy 378.512994 -294.286908) (xy 378.524771 -294.239124) (xy 378.544062 -294.193848) (xy 378.570365 -294.152252)
			(xy 378.603 -294.115415) (xy 378.641121 -294.08429) (xy 378.683742 -294.059683) (xy 378.729758 -294.042231)
			(xy 378.777977 -294.032387) (xy 378.827152 -294.030406) (xy 378.876007 -294.036338) (xy 378.923278 -294.05003)
			(xy 378.96774 -294.071128) (xy 379.008243 -294.099084) (xy 379.043736 -294.133176) (xy 379.073301 -294.17252)
			(xy 379.096172 -294.216097) (xy 379.111756 -294.262778) (xy 379.119651 -294.311355) (xy 379.120146 -294.335962)
			(xy 380.389142 -294.335962) (xy 380.393102 -294.286908) (xy 380.404879 -294.239124) (xy 380.42417 -294.193848)
			(xy 380.450473 -294.152252) (xy 380.483108 -294.115415) (xy 380.521229 -294.08429) (xy 380.56385 -294.059683)
			(xy 380.609866 -294.042231) (xy 380.658085 -294.032387) (xy 380.70726 -294.030406) (xy 380.756115 -294.036338)
			(xy 380.803386 -294.05003) (xy 380.847848 -294.071128) (xy 380.888351 -294.099084) (xy 380.923844 -294.133176)
			(xy 380.953409 -294.17252) (xy 380.97628 -294.216097) (xy 380.991864 -294.262778) (xy 380.999759 -294.311355)
			(xy 381.000254 -294.335962) (xy 381.328942 -294.335962) (xy 381.332902 -294.286908) (xy 381.344679 -294.239124)
			(xy 381.36397 -294.193848) (xy 381.390273 -294.152252) (xy 381.422908 -294.115415) (xy 381.461029 -294.08429)
			(xy 381.50365 -294.059683) (xy 381.549666 -294.042231) (xy 381.597885 -294.032387) (xy 381.64706 -294.030406)
			(xy 381.695915 -294.036338) (xy 381.743186 -294.05003) (xy 381.787648 -294.071128) (xy 381.828151 -294.099084)
			(xy 381.863644 -294.133176) (xy 381.893209 -294.17252) (xy 381.91608 -294.216097) (xy 381.931664 -294.262778)
			(xy 381.939559 -294.311355) (xy 381.940054 -294.335962) (xy 382.268996 -294.335962) (xy 382.272956 -294.286908)
			(xy 382.284733 -294.239124) (xy 382.304024 -294.193848) (xy 382.330327 -294.152252) (xy 382.362962 -294.115415)
			(xy 382.401083 -294.08429) (xy 382.443704 -294.059683) (xy 382.48972 -294.042231) (xy 382.537939 -294.032387)
			(xy 382.587114 -294.030406) (xy 382.635969 -294.036338) (xy 382.68324 -294.05003) (xy 382.727702 -294.071128)
			(xy 382.768205 -294.099084) (xy 382.803698 -294.133176) (xy 382.833263 -294.17252) (xy 382.856134 -294.216097)
			(xy 382.871718 -294.262778) (xy 382.879613 -294.311355) (xy 382.880108 -294.335962) (xy 383.20905 -294.335962)
			(xy 383.21301 -294.286908) (xy 383.224787 -294.239124) (xy 383.244078 -294.193848) (xy 383.270381 -294.152252)
			(xy 383.303016 -294.115415) (xy 383.341137 -294.08429) (xy 383.383758 -294.059683) (xy 383.429774 -294.042231)
			(xy 383.477993 -294.032387) (xy 383.527168 -294.030406) (xy 383.576023 -294.036338) (xy 383.623294 -294.05003)
			(xy 383.667756 -294.071128) (xy 383.708259 -294.099084) (xy 383.743752 -294.133176) (xy 383.773317 -294.17252)
			(xy 383.796188 -294.216097) (xy 383.811772 -294.262778) (xy 383.819667 -294.311355) (xy 383.820162 -294.335962)
			(xy 384.149104 -294.335962) (xy 384.153064 -294.286908) (xy 384.164841 -294.239124) (xy 384.184132 -294.193848)
			(xy 384.210435 -294.152252) (xy 384.24307 -294.115415) (xy 384.281191 -294.08429) (xy 384.323812 -294.059683)
			(xy 384.369828 -294.042231) (xy 384.418047 -294.032387) (xy 384.467222 -294.030406) (xy 384.516077 -294.036338)
			(xy 384.563348 -294.05003) (xy 384.60781 -294.071128) (xy 384.648313 -294.099084) (xy 384.683806 -294.133176)
			(xy 384.713371 -294.17252) (xy 384.736242 -294.216097) (xy 384.751826 -294.262778) (xy 384.759721 -294.311355)
			(xy 384.760216 -294.335962) (xy 386.028958 -294.335962) (xy 386.032918 -294.286908) (xy 386.044695 -294.239124)
			(xy 386.063986 -294.193848) (xy 386.090289 -294.152252) (xy 386.122924 -294.115415) (xy 386.161045 -294.08429)
			(xy 386.203666 -294.059683) (xy 386.249682 -294.042231) (xy 386.297901 -294.032387) (xy 386.347076 -294.030406)
			(xy 386.395931 -294.036338) (xy 386.443202 -294.05003) (xy 386.487664 -294.071128) (xy 386.528167 -294.099084)
			(xy 386.56366 -294.133176) (xy 386.593225 -294.17252) (xy 386.616096 -294.216097) (xy 386.63168 -294.262778)
			(xy 386.639575 -294.311355) (xy 386.64007 -294.335962) (xy 386.639575 -294.360569) (xy 386.63168 -294.409146)
			(xy 386.616096 -294.455827) (xy 386.593225 -294.499404) (xy 386.56366 -294.538748) (xy 386.528167 -294.57284)
			(xy 386.487664 -294.600796) (xy 386.443202 -294.621894) (xy 386.395931 -294.635586) (xy 386.347076 -294.641518)
			(xy 386.297901 -294.639537) (xy 386.249682 -294.629693) (xy 386.203666 -294.612241) (xy 386.161045 -294.587634)
			(xy 386.122924 -294.556509) (xy 386.090289 -294.519672) (xy 386.063986 -294.478076) (xy 386.044695 -294.4328)
			(xy 386.032918 -294.385016) (xy 386.028958 -294.335962) (xy 384.760216 -294.335962) (xy 384.759721 -294.360569)
			(xy 384.751826 -294.409146) (xy 384.736242 -294.455827) (xy 384.713371 -294.499404) (xy 384.683806 -294.538748)
			(xy 384.648313 -294.57284) (xy 384.60781 -294.600796) (xy 384.563348 -294.621894) (xy 384.516077 -294.635586)
			(xy 384.467222 -294.641518) (xy 384.418047 -294.639537) (xy 384.369828 -294.629693) (xy 384.323812 -294.612241)
			(xy 384.281191 -294.587634) (xy 384.24307 -294.556509) (xy 384.210435 -294.519672) (xy 384.184132 -294.478076)
			(xy 384.164841 -294.4328) (xy 384.153064 -294.385016) (xy 384.149104 -294.335962) (xy 383.820162 -294.335962)
			(xy 383.819667 -294.360569) (xy 383.811772 -294.409146) (xy 383.796188 -294.455827) (xy 383.773317 -294.499404)
			(xy 383.743752 -294.538748) (xy 383.708259 -294.57284) (xy 383.667756 -294.600796) (xy 383.623294 -294.621894)
			(xy 383.576023 -294.635586) (xy 383.527168 -294.641518) (xy 383.477993 -294.639537) (xy 383.429774 -294.629693)
			(xy 383.383758 -294.612241) (xy 383.341137 -294.587634) (xy 383.303016 -294.556509) (xy 383.270381 -294.519672)
			(xy 383.244078 -294.478076) (xy 383.224787 -294.4328) (xy 383.21301 -294.385016) (xy 383.20905 -294.335962)
			(xy 382.880108 -294.335962) (xy 382.879613 -294.360569) (xy 382.871718 -294.409146) (xy 382.856134 -294.455827)
			(xy 382.833263 -294.499404) (xy 382.803698 -294.538748) (xy 382.768205 -294.57284) (xy 382.727702 -294.600796)
			(xy 382.68324 -294.621894) (xy 382.635969 -294.635586) (xy 382.587114 -294.641518) (xy 382.537939 -294.639537)
			(xy 382.48972 -294.629693) (xy 382.443704 -294.612241) (xy 382.401083 -294.587634) (xy 382.362962 -294.556509)
			(xy 382.330327 -294.519672) (xy 382.304024 -294.478076) (xy 382.284733 -294.4328) (xy 382.272956 -294.385016)
			(xy 382.268996 -294.335962) (xy 381.940054 -294.335962) (xy 381.939559 -294.360569) (xy 381.931664 -294.409146)
			(xy 381.91608 -294.455827) (xy 381.893209 -294.499404) (xy 381.863644 -294.538748) (xy 381.828151 -294.57284)
			(xy 381.787648 -294.600796) (xy 381.743186 -294.621894) (xy 381.695915 -294.635586) (xy 381.64706 -294.641518)
			(xy 381.597885 -294.639537) (xy 381.549666 -294.629693) (xy 381.50365 -294.612241) (xy 381.461029 -294.587634)
			(xy 381.422908 -294.556509) (xy 381.390273 -294.519672) (xy 381.36397 -294.478076) (xy 381.344679 -294.4328)
			(xy 381.332902 -294.385016) (xy 381.328942 -294.335962) (xy 381.000254 -294.335962) (xy 380.999759 -294.360569)
			(xy 380.991864 -294.409146) (xy 380.97628 -294.455827) (xy 380.953409 -294.499404) (xy 380.923844 -294.538748)
			(xy 380.888351 -294.57284) (xy 380.847848 -294.600796) (xy 380.803386 -294.621894) (xy 380.756115 -294.635586)
			(xy 380.70726 -294.641518) (xy 380.658085 -294.639537) (xy 380.609866 -294.629693) (xy 380.56385 -294.612241)
			(xy 380.521229 -294.587634) (xy 380.483108 -294.556509) (xy 380.450473 -294.519672) (xy 380.42417 -294.478076)
			(xy 380.404879 -294.4328) (xy 380.393102 -294.385016) (xy 380.389142 -294.335962) (xy 379.120146 -294.335962)
			(xy 379.119651 -294.360569) (xy 379.111756 -294.409146) (xy 379.096172 -294.455827) (xy 379.073301 -294.499404)
			(xy 379.043736 -294.538748) (xy 379.008243 -294.57284) (xy 378.96774 -294.600796) (xy 378.923278 -294.621894)
			(xy 378.876007 -294.635586) (xy 378.827152 -294.641518) (xy 378.777977 -294.639537) (xy 378.729758 -294.629693)
			(xy 378.683742 -294.612241) (xy 378.641121 -294.587634) (xy 378.603 -294.556509) (xy 378.570365 -294.519672)
			(xy 378.544062 -294.478076) (xy 378.524771 -294.4328) (xy 378.512994 -294.385016) (xy 378.509034 -294.335962)
			(xy 378.180092 -294.335962) (xy 378.179597 -294.360569) (xy 378.171702 -294.409146) (xy 378.156118 -294.455827)
			(xy 378.133247 -294.499404) (xy 378.103682 -294.538748) (xy 378.068189 -294.57284) (xy 378.027686 -294.600796)
			(xy 377.983224 -294.621894) (xy 377.935953 -294.635586) (xy 377.887098 -294.641518) (xy 377.837923 -294.639537)
			(xy 377.789704 -294.629693) (xy 377.743688 -294.612241) (xy 377.701067 -294.587634) (xy 377.662946 -294.556509)
			(xy 377.630311 -294.519672) (xy 377.604008 -294.478076) (xy 377.584717 -294.4328) (xy 377.57294 -294.385016)
			(xy 377.56898 -294.335962) (xy 377.240038 -294.335962) (xy 377.239543 -294.360569) (xy 377.231648 -294.409146)
			(xy 377.216064 -294.455827) (xy 377.193193 -294.499404) (xy 377.163628 -294.538748) (xy 377.128135 -294.57284)
			(xy 377.087632 -294.600796) (xy 377.04317 -294.621894) (xy 376.995899 -294.635586) (xy 376.947044 -294.641518)
			(xy 376.897869 -294.639537) (xy 376.84965 -294.629693) (xy 376.803634 -294.612241) (xy 376.761013 -294.587634)
			(xy 376.722892 -294.556509) (xy 376.690257 -294.519672) (xy 376.663954 -294.478076) (xy 376.644663 -294.4328)
			(xy 376.632886 -294.385016) (xy 376.628926 -294.335962) (xy 376.300238 -294.335962) (xy 376.299795 -294.359958)
			(xy 376.292293 -294.40736) (xy 376.277468 -294.453004) (xy 376.255685 -294.495768) (xy 376.227481 -294.534597)
			(xy 376.193549 -294.568537) (xy 376.154726 -294.59675) (xy 376.111967 -294.618542) (xy 376.066326 -294.633377)
			(xy 376.018926 -294.640889) (xy 375.99493 -294.64127) (xy 375.97588 -294.640762) (xy 375.975372 -294.640762)
			(xy 375.951515 -294.638702) (xy 375.904818 -294.628117) (xy 375.882408 -294.61968) (xy 375.867172 -294.613465)
			(xy 375.838023 -294.598192) (xy 375.824242 -294.5892) (xy 375.817384 -294.584628) (xy 375.801382 -294.579802)
			(xy 375.79179 -294.577273) (xy 375.772048 -294.578975) (xy 375.763028 -294.583104) (xy 375.687844 -294.621712)
			(xy 375.68759 -294.621712) (xy 375.68161 -294.625114) (xy 375.671572 -294.634515) (xy 375.667778 -294.640254)
			(xy 375.667778 -294.640508) (xy 375.664278 -294.646614) (xy 375.660419 -294.660144) (xy 375.660158 -294.667178)
			(xy 375.660158 -294.785288) (xy 375.660666 -294.792146) (xy 375.66219 -294.802306) (xy 375.662444 -294.80383)
			(xy 375.662698 -294.804084) (xy 375.679462 -294.86225) (xy 375.679462 -294.862758) (xy 375.681426 -294.869093)
			(xy 375.68812 -294.880538) (xy 375.69267 -294.885364) (xy 375.71299 -294.905684) (xy 375.714768 -294.906954)
			(xy 375.728068 -294.917853) (xy 375.752381 -294.94217) (xy 375.763282 -294.955468) (xy 375.767092 -294.959786)
			(xy 375.953274 -295.145968) (xy 377.09908 -295.145968) (xy 377.10304 -295.096914) (xy 377.114817 -295.04913)
			(xy 377.134108 -295.003854) (xy 377.160411 -294.962258) (xy 377.193046 -294.925421) (xy 377.231167 -294.894296)
			(xy 377.273788 -294.869689) (xy 377.319804 -294.852237) (xy 377.368023 -294.842393) (xy 377.417198 -294.840412)
			(xy 377.466053 -294.846344) (xy 377.513324 -294.860036) (xy 377.557786 -294.881134) (xy 377.598289 -294.90909)
			(xy 377.633782 -294.943182) (xy 377.663347 -294.982526) (xy 377.686218 -295.026103) (xy 377.701802 -295.072784)
			(xy 377.709697 -295.121361) (xy 377.710192 -295.145968) (xy 378.039134 -295.145968) (xy 378.043094 -295.096914)
			(xy 378.054871 -295.04913) (xy 378.074162 -295.003854) (xy 378.100465 -294.962258) (xy 378.1331 -294.925421)
			(xy 378.171221 -294.894296) (xy 378.213842 -294.869689) (xy 378.259858 -294.852237) (xy 378.308077 -294.842393)
			(xy 378.357252 -294.840412) (xy 378.406107 -294.846344) (xy 378.453378 -294.860036) (xy 378.49784 -294.881134)
			(xy 378.538343 -294.90909) (xy 378.573836 -294.943182) (xy 378.603401 -294.982526) (xy 378.626272 -295.026103)
			(xy 378.641856 -295.072784) (xy 378.649751 -295.121361) (xy 378.650246 -295.145968) (xy 378.978934 -295.145968)
			(xy 378.982894 -295.096914) (xy 378.994671 -295.04913) (xy 379.013962 -295.003854) (xy 379.040265 -294.962258)
			(xy 379.0729 -294.925421) (xy 379.111021 -294.894296) (xy 379.153642 -294.869689) (xy 379.199658 -294.852237)
			(xy 379.247877 -294.842393) (xy 379.297052 -294.840412) (xy 379.345907 -294.846344) (xy 379.393178 -294.860036)
			(xy 379.43764 -294.881134) (xy 379.478143 -294.90909) (xy 379.513636 -294.943182) (xy 379.543201 -294.982526)
			(xy 379.566072 -295.026103) (xy 379.581656 -295.072784) (xy 379.589551 -295.121361) (xy 379.590046 -295.145968)
			(xy 380.859042 -295.145968) (xy 380.863002 -295.096914) (xy 380.874779 -295.04913) (xy 380.89407 -295.003854)
			(xy 380.920373 -294.962258) (xy 380.953008 -294.925421) (xy 380.991129 -294.894296) (xy 381.03375 -294.869689)
			(xy 381.079766 -294.852237) (xy 381.127985 -294.842393) (xy 381.17716 -294.840412) (xy 381.226015 -294.846344)
			(xy 381.273286 -294.860036) (xy 381.317748 -294.881134) (xy 381.358251 -294.90909) (xy 381.393744 -294.943182)
			(xy 381.423309 -294.982526) (xy 381.44618 -295.026103) (xy 381.461764 -295.072784) (xy 381.469659 -295.121361)
			(xy 381.470154 -295.145968) (xy 381.799096 -295.145968) (xy 381.803056 -295.096914) (xy 381.814833 -295.04913)
			(xy 381.834124 -295.003854) (xy 381.860427 -294.962258) (xy 381.893062 -294.925421) (xy 381.931183 -294.894296)
			(xy 381.973804 -294.869689) (xy 382.01982 -294.852237) (xy 382.068039 -294.842393) (xy 382.117214 -294.840412)
			(xy 382.166069 -294.846344) (xy 382.21334 -294.860036) (xy 382.257802 -294.881134) (xy 382.298305 -294.90909)
			(xy 382.333798 -294.943182) (xy 382.363363 -294.982526) (xy 382.386234 -295.026103) (xy 382.401818 -295.072784)
			(xy 382.409713 -295.121361) (xy 382.410208 -295.145968) (xy 384.619004 -295.145968) (xy 384.622964 -295.096914)
			(xy 384.634741 -295.04913) (xy 384.654032 -295.003854) (xy 384.680335 -294.962258) (xy 384.71297 -294.925421)
			(xy 384.751091 -294.894296) (xy 384.793712 -294.869689) (xy 384.839728 -294.852237) (xy 384.887947 -294.842393)
			(xy 384.937122 -294.840412) (xy 384.985977 -294.846344) (xy 385.033248 -294.860036) (xy 385.07771 -294.881134)
			(xy 385.118213 -294.90909) (xy 385.153706 -294.943182) (xy 385.183271 -294.982526) (xy 385.206142 -295.026103)
			(xy 385.221726 -295.072784) (xy 385.229621 -295.121361) (xy 385.230116 -295.145968) (xy 385.559058 -295.145968)
			(xy 385.563018 -295.096914) (xy 385.574795 -295.04913) (xy 385.594086 -295.003854) (xy 385.620389 -294.962258)
			(xy 385.653024 -294.925421) (xy 385.691145 -294.894296) (xy 385.733766 -294.869689) (xy 385.779782 -294.852237)
			(xy 385.828001 -294.842393) (xy 385.877176 -294.840412) (xy 385.926031 -294.846344) (xy 385.973302 -294.860036)
			(xy 386.017764 -294.881134) (xy 386.058267 -294.90909) (xy 386.09376 -294.943182) (xy 386.123325 -294.982526)
			(xy 386.146196 -295.026103) (xy 386.16178 -295.072784) (xy 386.169675 -295.121361) (xy 386.17017 -295.145968)
			(xy 388.378966 -295.145968) (xy 388.382926 -295.096914) (xy 388.394703 -295.04913) (xy 388.413994 -295.003854)
			(xy 388.440297 -294.962258) (xy 388.472932 -294.925421) (xy 388.511053 -294.894296) (xy 388.553674 -294.869689)
			(xy 388.59969 -294.852237) (xy 388.647909 -294.842393) (xy 388.697084 -294.840412) (xy 388.745939 -294.846344)
			(xy 388.79321 -294.860036) (xy 388.837672 -294.881134) (xy 388.878175 -294.90909) (xy 388.913668 -294.943182)
			(xy 388.943233 -294.982526) (xy 388.966104 -295.026103) (xy 388.981688 -295.072784) (xy 388.989583 -295.121361)
			(xy 388.990078 -295.145968) (xy 389.31902 -295.145968) (xy 389.32298 -295.096914) (xy 389.334757 -295.04913)
			(xy 389.354048 -295.003854) (xy 389.380351 -294.962258) (xy 389.412986 -294.925421) (xy 389.451107 -294.894296)
			(xy 389.493728 -294.869689) (xy 389.539744 -294.852237) (xy 389.587963 -294.842393) (xy 389.637138 -294.840412)
			(xy 389.685993 -294.846344) (xy 389.733264 -294.860036) (xy 389.777726 -294.881134) (xy 389.818229 -294.90909)
			(xy 389.853722 -294.943182) (xy 389.883287 -294.982526) (xy 389.906158 -295.026103) (xy 389.921742 -295.072784)
			(xy 389.929637 -295.121361) (xy 389.930132 -295.145968) (xy 390.259074 -295.145968) (xy 390.263034 -295.096914)
			(xy 390.274811 -295.04913) (xy 390.294102 -295.003854) (xy 390.320405 -294.962258) (xy 390.35304 -294.925421)
			(xy 390.391161 -294.894296) (xy 390.433782 -294.869689) (xy 390.479798 -294.852237) (xy 390.528017 -294.842393)
			(xy 390.577192 -294.840412) (xy 390.626047 -294.846344) (xy 390.673318 -294.860036) (xy 390.71778 -294.881134)
			(xy 390.758283 -294.90909) (xy 390.793776 -294.943182) (xy 390.823341 -294.982526) (xy 390.846212 -295.026103)
			(xy 390.861796 -295.072784) (xy 390.869691 -295.121361) (xy 390.870186 -295.145968) (xy 390.869691 -295.170575)
			(xy 390.861796 -295.219152) (xy 390.846212 -295.265833) (xy 390.823341 -295.30941) (xy 390.793776 -295.348754)
			(xy 390.758283 -295.382846) (xy 390.71778 -295.410802) (xy 390.673318 -295.4319) (xy 390.626047 -295.445592)
			(xy 390.577192 -295.451524) (xy 390.528017 -295.449543) (xy 390.479798 -295.439699) (xy 390.433782 -295.422247)
			(xy 390.391161 -295.39764) (xy 390.35304 -295.366515) (xy 390.320405 -295.329678) (xy 390.294102 -295.288082)
			(xy 390.274811 -295.242806) (xy 390.263034 -295.195022) (xy 390.259074 -295.145968) (xy 389.930132 -295.145968)
			(xy 389.929637 -295.170575) (xy 389.921742 -295.219152) (xy 389.906158 -295.265833) (xy 389.883287 -295.30941)
			(xy 389.853722 -295.348754) (xy 389.818229 -295.382846) (xy 389.777726 -295.410802) (xy 389.733264 -295.4319)
			(xy 389.685993 -295.445592) (xy 389.637138 -295.451524) (xy 389.587963 -295.449543) (xy 389.539744 -295.439699)
			(xy 389.493728 -295.422247) (xy 389.451107 -295.39764) (xy 389.412986 -295.366515) (xy 389.380351 -295.329678)
			(xy 389.354048 -295.288082) (xy 389.334757 -295.242806) (xy 389.32298 -295.195022) (xy 389.31902 -295.145968)
			(xy 388.990078 -295.145968) (xy 388.989583 -295.170575) (xy 388.981688 -295.219152) (xy 388.966104 -295.265833)
			(xy 388.943233 -295.30941) (xy 388.913668 -295.348754) (xy 388.878175 -295.382846) (xy 388.837672 -295.410802)
			(xy 388.79321 -295.4319) (xy 388.745939 -295.445592) (xy 388.697084 -295.451524) (xy 388.647909 -295.449543)
			(xy 388.59969 -295.439699) (xy 388.553674 -295.422247) (xy 388.511053 -295.39764) (xy 388.472932 -295.366515)
			(xy 388.440297 -295.329678) (xy 388.413994 -295.288082) (xy 388.394703 -295.242806) (xy 388.382926 -295.195022)
			(xy 388.378966 -295.145968) (xy 386.17017 -295.145968) (xy 386.169675 -295.170575) (xy 386.16178 -295.219152)
			(xy 386.146196 -295.265833) (xy 386.123325 -295.30941) (xy 386.09376 -295.348754) (xy 386.058267 -295.382846)
			(xy 386.017764 -295.410802) (xy 385.973302 -295.4319) (xy 385.926031 -295.445592) (xy 385.877176 -295.451524)
			(xy 385.828001 -295.449543) (xy 385.779782 -295.439699) (xy 385.733766 -295.422247) (xy 385.691145 -295.39764)
			(xy 385.653024 -295.366515) (xy 385.620389 -295.329678) (xy 385.594086 -295.288082) (xy 385.574795 -295.242806)
			(xy 385.563018 -295.195022) (xy 385.559058 -295.145968) (xy 385.230116 -295.145968) (xy 385.229621 -295.170575)
			(xy 385.221726 -295.219152) (xy 385.206142 -295.265833) (xy 385.183271 -295.30941) (xy 385.153706 -295.348754)
			(xy 385.118213 -295.382846) (xy 385.07771 -295.410802) (xy 385.033248 -295.4319) (xy 384.985977 -295.445592)
			(xy 384.937122 -295.451524) (xy 384.887947 -295.449543) (xy 384.839728 -295.439699) (xy 384.793712 -295.422247)
			(xy 384.751091 -295.39764) (xy 384.71297 -295.366515) (xy 384.680335 -295.329678) (xy 384.654032 -295.288082)
			(xy 384.634741 -295.242806) (xy 384.622964 -295.195022) (xy 384.619004 -295.145968) (xy 382.410208 -295.145968)
			(xy 382.409713 -295.170575) (xy 382.401818 -295.219152) (xy 382.386234 -295.265833) (xy 382.363363 -295.30941)
			(xy 382.333798 -295.348754) (xy 382.298305 -295.382846) (xy 382.257802 -295.410802) (xy 382.21334 -295.4319)
			(xy 382.166069 -295.445592) (xy 382.117214 -295.451524) (xy 382.068039 -295.449543) (xy 382.01982 -295.439699)
			(xy 381.973804 -295.422247) (xy 381.931183 -295.39764) (xy 381.893062 -295.366515) (xy 381.860427 -295.329678)
			(xy 381.834124 -295.288082) (xy 381.814833 -295.242806) (xy 381.803056 -295.195022) (xy 381.799096 -295.145968)
			(xy 381.470154 -295.145968) (xy 381.469659 -295.170575) (xy 381.461764 -295.219152) (xy 381.44618 -295.265833)
			(xy 381.423309 -295.30941) (xy 381.393744 -295.348754) (xy 381.358251 -295.382846) (xy 381.317748 -295.410802)
			(xy 381.273286 -295.4319) (xy 381.226015 -295.445592) (xy 381.17716 -295.451524) (xy 381.127985 -295.449543)
			(xy 381.079766 -295.439699) (xy 381.03375 -295.422247) (xy 380.991129 -295.39764) (xy 380.953008 -295.366515)
			(xy 380.920373 -295.329678) (xy 380.89407 -295.288082) (xy 380.874779 -295.242806) (xy 380.863002 -295.195022)
			(xy 380.859042 -295.145968) (xy 379.590046 -295.145968) (xy 379.589551 -295.170575) (xy 379.581656 -295.219152)
			(xy 379.566072 -295.265833) (xy 379.543201 -295.30941) (xy 379.513636 -295.348754) (xy 379.478143 -295.382846)
			(xy 379.43764 -295.410802) (xy 379.393178 -295.4319) (xy 379.345907 -295.445592) (xy 379.297052 -295.451524)
			(xy 379.247877 -295.449543) (xy 379.199658 -295.439699) (xy 379.153642 -295.422247) (xy 379.111021 -295.39764)
			(xy 379.0729 -295.366515) (xy 379.040265 -295.329678) (xy 379.013962 -295.288082) (xy 378.994671 -295.242806)
			(xy 378.982894 -295.195022) (xy 378.978934 -295.145968) (xy 378.650246 -295.145968) (xy 378.649751 -295.170575)
			(xy 378.641856 -295.219152) (xy 378.626272 -295.265833) (xy 378.603401 -295.30941) (xy 378.573836 -295.348754)
			(xy 378.538343 -295.382846) (xy 378.49784 -295.410802) (xy 378.453378 -295.4319) (xy 378.406107 -295.445592)
			(xy 378.357252 -295.451524) (xy 378.308077 -295.449543) (xy 378.259858 -295.439699) (xy 378.213842 -295.422247)
			(xy 378.171221 -295.39764) (xy 378.1331 -295.366515) (xy 378.100465 -295.329678) (xy 378.074162 -295.288082)
			(xy 378.054871 -295.242806) (xy 378.043094 -295.195022) (xy 378.039134 -295.145968) (xy 377.710192 -295.145968)
			(xy 377.709697 -295.170575) (xy 377.701802 -295.219152) (xy 377.686218 -295.265833) (xy 377.663347 -295.30941)
			(xy 377.633782 -295.348754) (xy 377.598289 -295.382846) (xy 377.557786 -295.410802) (xy 377.513324 -295.4319)
			(xy 377.466053 -295.445592) (xy 377.417198 -295.451524) (xy 377.368023 -295.449543) (xy 377.319804 -295.439699)
			(xy 377.273788 -295.422247) (xy 377.231167 -295.39764) (xy 377.193046 -295.366515) (xy 377.160411 -295.329678)
			(xy 377.134108 -295.288082) (xy 377.114817 -295.242806) (xy 377.10304 -295.195022) (xy 377.09908 -295.145968)
			(xy 375.953274 -295.145968) (xy 376.218958 -295.411652) (xy 376.223991 -295.416999) (xy 376.230969 -295.42991)
			(xy 376.232674 -295.437052) (xy 376.233944 -295.443402) (xy 376.249692 -295.474898) (xy 376.256042 -295.480994)
			(xy 376.26671 -295.491662) (xy 376.267218 -295.49217) (xy 376.545094 -295.770046) (xy 376.567775 -295.793355)
			(xy 376.608345 -295.844189) (xy 376.642973 -295.899244) (xy 376.670329 -295.955974) (xy 377.56898 -295.955974)
			(xy 377.57294 -295.90692) (xy 377.584717 -295.859136) (xy 377.604008 -295.81386) (xy 377.630311 -295.772264)
			(xy 377.662946 -295.735427) (xy 377.701067 -295.704302) (xy 377.743688 -295.679695) (xy 377.789704 -295.662243)
			(xy 377.837923 -295.652399) (xy 377.887098 -295.650418) (xy 377.935953 -295.65635) (xy 377.983224 -295.670042)
			(xy 378.027686 -295.69114) (xy 378.068189 -295.719096) (xy 378.103682 -295.753188) (xy 378.133247 -295.792532)
			(xy 378.156118 -295.836109) (xy 378.171702 -295.88279) (xy 378.179597 -295.931367) (xy 378.180092 -295.955974)
			(xy 378.179597 -295.980581) (xy 378.177789 -295.991708) (xy 378.512342 -295.991708) (xy 378.515026 -295.942131)
			(xy 378.525696 -295.893641) (xy 378.54407 -295.847516) (xy 378.569664 -295.804972) (xy 378.601804 -295.767129)
			(xy 378.639644 -295.734984) (xy 378.682186 -295.709385) (xy 378.728308 -295.691006) (xy 378.776797 -295.680331)
			(xy 378.826374 -295.677641) (xy 378.875733 -295.683008) (xy 378.923573 -295.696289) (xy 378.968634 -295.717136)
			(xy 379.009729 -295.744998) (xy 379.045775 -295.779142) (xy 379.075822 -295.818668) (xy 379.099078 -295.862534)
			(xy 379.114931 -295.909585) (xy 379.122962 -295.958581) (xy 379.123448 -295.983406) (xy 379.123284 -295.998815)
			(xy 379.120228 -296.029481) (xy 379.117352 -296.04462) (xy 379.114812 -296.056812) (xy 379.12167 -296.080688)
			(xy 379.187964 -296.15003) (xy 379.19695 -296.158425) (xy 379.22017 -296.166395) (xy 379.232414 -296.16527)
			(xy 379.232668 -296.16527) (xy 379.246421 -296.163246) (xy 379.274139 -296.161086) (xy 379.28804 -296.160952)
			(xy 379.302005 -296.161073) (xy 379.32985 -296.163231) (xy 379.343666 -296.16527) (xy 379.355858 -296.167302)
			(xy 379.379734 -296.159428) (xy 379.446028 -296.090086) (xy 379.454112 -296.080682) (xy 379.460916 -296.056867)
			(xy 379.458982 -296.04462) (xy 379.45611 -296.02948) (xy 379.453054 -295.998815) (xy 379.452886 -295.983406)
			(xy 379.453408 -295.958151) (xy 379.461721 -295.908329) (xy 379.478122 -295.860555) (xy 379.502163 -295.816132)
			(xy 379.533187 -295.776272) (xy 379.570349 -295.742062) (xy 379.612635 -295.714436) (xy 379.658891 -295.694146)
			(xy 379.707856 -295.681746) (xy 379.758194 -295.677575) (xy 379.808532 -295.681746) (xy 379.857497 -295.694146)
			(xy 379.903753 -295.714436) (xy 379.946039 -295.742062) (xy 379.983201 -295.776272) (xy 380.014225 -295.816132)
			(xy 380.038266 -295.860555) (xy 380.054667 -295.908329) (xy 380.06298 -295.958151) (xy 380.063502 -295.983406)
			(xy 380.063339 -295.998815) (xy 380.060282 -296.029481) (xy 380.057406 -296.04462) (xy 380.054866 -296.056812)
			(xy 380.061724 -296.080688) (xy 380.128018 -296.15003) (xy 380.136981 -296.158454) (xy 380.160219 -296.166408)
			(xy 380.172468 -296.16527) (xy 380.172722 -296.16527) (xy 380.186413 -296.163261) (xy 380.214003 -296.161098)
			(xy 380.22784 -296.160952) (xy 380.241868 -296.161064) (xy 380.269841 -296.163223) (xy 380.28372 -296.16527)
			(xy 380.295912 -296.167302) (xy 380.319788 -296.159428) (xy 380.386082 -296.090086) (xy 380.394172 -296.080687)
			(xy 380.40097 -296.056868) (xy 380.399036 -296.04462) (xy 380.396163 -296.02948) (xy 380.393108 -295.998815)
			(xy 380.39294 -295.983406) (xy 380.393371 -295.958585) (xy 380.401401 -295.909598) (xy 380.41725 -295.862555)
			(xy 380.440501 -295.818695) (xy 380.470541 -295.779175) (xy 380.506579 -295.745035) (xy 380.547665 -295.717175)
			(xy 380.592717 -295.696329) (xy 380.640548 -295.683046) (xy 380.689898 -295.677676) (xy 380.739467 -295.68036)
			(xy 380.787948 -295.691028) (xy 380.834065 -295.709398) (xy 380.876603 -295.734988) (xy 380.91444 -295.767121)
			(xy 380.946581 -295.804953) (xy 380.972178 -295.847486) (xy 380.990556 -295.8936) (xy 381.001233 -295.942079)
			(xy 381.003926 -295.991648) (xy 381.003919 -295.991713) (xy 381.332233 -295.991713) (xy 381.334917 -295.942135)
			(xy 381.345586 -295.893643) (xy 381.36396 -295.847516) (xy 381.389555 -295.80497) (xy 381.421696 -295.767125)
			(xy 381.459536 -295.734979) (xy 381.502079 -295.709379) (xy 381.548203 -295.690998) (xy 381.596693 -295.680322)
			(xy 381.646271 -295.677632) (xy 381.695632 -295.682999) (xy 381.743474 -295.696281) (xy 381.788537 -295.717128)
			(xy 381.829633 -295.744991) (xy 381.86568 -295.779136) (xy 381.895728 -295.818663) (xy 381.918985 -295.86253)
			(xy 381.934839 -295.909583) (xy 381.942871 -295.95858) (xy 381.943356 -295.983406) (xy 381.943192 -295.998815)
			(xy 381.940136 -296.029481) (xy 381.93726 -296.04462) (xy 381.93472 -296.056812) (xy 381.941578 -296.080688)
			(xy 382.007872 -296.15003) (xy 382.016855 -296.158429) (xy 382.040077 -296.166397) (xy 382.052322 -296.16527)
			(xy 382.052576 -296.16527) (xy 382.066329 -296.163246) (xy 382.094047 -296.161086) (xy 382.107948 -296.160952)
			(xy 382.121913 -296.161072) (xy 382.149758 -296.16323) (xy 382.163574 -296.16527) (xy 382.175766 -296.167302)
			(xy 382.199642 -296.159428) (xy 382.265936 -296.090086) (xy 382.274021 -296.080683) (xy 382.280824 -296.056867)
			(xy 382.27889 -296.04462) (xy 382.276018 -296.02948) (xy 382.272962 -295.998815) (xy 382.272794 -295.983406)
			(xy 382.273316 -295.958151) (xy 382.281629 -295.908329) (xy 382.29803 -295.860555) (xy 382.322071 -295.816132)
			(xy 382.353095 -295.776272) (xy 382.390257 -295.742062) (xy 382.432543 -295.714436) (xy 382.478799 -295.694146)
			(xy 382.527764 -295.681746) (xy 382.578102 -295.677575) (xy 382.62844 -295.681746) (xy 382.677405 -295.694146)
			(xy 382.723661 -295.714436) (xy 382.765947 -295.742062) (xy 382.803109 -295.776272) (xy 382.834133 -295.816132)
			(xy 382.858174 -295.860555) (xy 382.874575 -295.908329) (xy 382.882888 -295.958151) (xy 382.88341 -295.983406)
			(xy 382.883246 -295.998815) (xy 382.88019 -296.029481) (xy 382.877314 -296.04462) (xy 382.874774 -296.056812)
			(xy 382.881632 -296.080688) (xy 382.947926 -296.15003) (xy 382.956885 -296.158459) (xy 382.980126 -296.16641)
			(xy 382.992376 -296.16527) (xy 382.99263 -296.16527) (xy 383.006384 -296.163251) (xy 383.034101 -296.161088)
			(xy 383.048002 -296.160952) (xy 383.061967 -296.161066) (xy 383.089813 -296.163228) (xy 383.103628 -296.16527)
			(xy 383.11582 -296.167302) (xy 383.139696 -296.159428) (xy 383.20599 -296.090086) (xy 383.214081 -296.080688)
			(xy 383.220878 -296.056868) (xy 383.218944 -296.04462) (xy 383.216072 -296.02948) (xy 383.213016 -295.998815)
			(xy 383.212848 -295.983406) (xy 383.213371 -295.958584) (xy 383.221402 -295.909593) (xy 383.237254 -295.862547)
			(xy 383.260507 -295.818686) (xy 383.290551 -295.779164) (xy 383.326593 -295.745024) (xy 383.367683 -295.717165)
			(xy 383.41274 -295.696321) (xy 383.460575 -295.683041) (xy 383.509929 -295.677675) (xy 383.5595 -295.680364)
			(xy 383.607983 -295.691039) (xy 383.654101 -295.709416) (xy 383.696638 -295.735013) (xy 383.734473 -295.767154)
			(xy 383.76661 -295.804993) (xy 383.792201 -295.847533) (xy 383.810573 -295.893653) (xy 383.821241 -295.942138)
			(xy 383.82199 -295.955974) (xy 388.84912 -295.955974) (xy 388.85308 -295.90692) (xy 388.864857 -295.859136)
			(xy 388.884148 -295.81386) (xy 388.910451 -295.772264) (xy 388.943086 -295.735427) (xy 388.981207 -295.704302)
			(xy 389.023828 -295.679695) (xy 389.069844 -295.662243) (xy 389.118063 -295.652399) (xy 389.167238 -295.650418)
			(xy 389.216093 -295.65635) (xy 389.263364 -295.670042) (xy 389.307826 -295.69114) (xy 389.348329 -295.719096)
			(xy 389.383822 -295.753188) (xy 389.413387 -295.792532) (xy 389.436258 -295.836109) (xy 389.451842 -295.88279)
			(xy 389.459737 -295.931367) (xy 389.460232 -295.955974) (xy 389.459737 -295.980581) (xy 389.451842 -296.029158)
			(xy 389.436258 -296.075839) (xy 389.413387 -296.119416) (xy 389.383822 -296.15876) (xy 389.348329 -296.192852)
			(xy 389.307826 -296.220808) (xy 389.263364 -296.241906) (xy 389.216093 -296.255598) (xy 389.167238 -296.26153)
			(xy 389.118063 -296.259549) (xy 389.069844 -296.249705) (xy 389.023828 -296.232253) (xy 388.981207 -296.207646)
			(xy 388.943086 -296.176521) (xy 388.910451 -296.139684) (xy 388.884148 -296.098088) (xy 388.864857 -296.052812)
			(xy 388.85308 -296.005028) (xy 388.84912 -295.955974) (xy 383.82199 -295.955974) (xy 383.823924 -295.99171)
			(xy 383.818552 -296.041062) (xy 383.805266 -296.088896) (xy 383.784416 -296.13395) (xy 383.756552 -296.175037)
			(xy 383.722407 -296.211075) (xy 383.682882 -296.241113) (xy 383.639018 -296.264362) (xy 383.59197 -296.280207)
			(xy 383.542978 -296.288232) (xy 383.518156 -296.288714) (xy 383.495042 -296.287952) (xy 383.482596 -296.286936)
			(xy 383.459736 -296.296842) (xy 383.39141 -296.38117) (xy 383.38633 -296.405554) (xy 383.389886 -296.417492)
			(xy 383.39653 -296.441846) (xy 383.403671 -296.49182) (xy 383.40411 -296.51706) (xy 383.403612 -296.543709)
			(xy 383.395669 -296.596413) (xy 383.379959 -296.647343) (xy 383.356833 -296.695364) (xy 383.326809 -296.739401)
			(xy 383.290557 -296.778472) (xy 383.248886 -296.811703) (xy 383.202728 -296.838352) (xy 383.153114 -296.857824)
			(xy 383.101152 -296.869684) (xy 383.048002 -296.873668) (xy 382.994852 -296.869684) (xy 382.94289 -296.857824)
			(xy 382.893276 -296.838352) (xy 382.847118 -296.811703) (xy 382.805447 -296.778472) (xy 382.769195 -296.739401)
			(xy 382.739171 -296.695364) (xy 382.716045 -296.647343) (xy 382.700335 -296.596413) (xy 382.692392 -296.543709)
			(xy 382.691894 -296.51706) (xy 382.69234 -296.49182) (xy 382.699482 -296.441848) (xy 382.706118 -296.417492)
			(xy 382.709674 -296.405554) (xy 382.704594 -296.38117) (xy 382.636268 -296.296842) (xy 382.613408 -296.286936)
			(xy 382.600962 -296.287952) (xy 382.578356 -296.288714) (xy 382.577848 -296.288714) (xy 382.554988 -296.287952)
			(xy 382.542542 -296.286936) (xy 382.519682 -296.296842) (xy 382.451356 -296.38117) (xy 382.446276 -296.405554)
			(xy 382.449832 -296.417492) (xy 382.456475 -296.441847) (xy 382.463617 -296.49182) (xy 382.464056 -296.51706)
			(xy 382.463558 -296.543709) (xy 382.455615 -296.596413) (xy 382.439905 -296.647343) (xy 382.416779 -296.695364)
			(xy 382.386755 -296.739401) (xy 382.350503 -296.778472) (xy 382.308832 -296.811703) (xy 382.262674 -296.838352)
			(xy 382.21306 -296.857824) (xy 382.161098 -296.869684) (xy 382.107948 -296.873668) (xy 382.054798 -296.869684)
			(xy 382.002836 -296.857824) (xy 381.953222 -296.838352) (xy 381.907064 -296.811703) (xy 381.865393 -296.778472)
			(xy 381.829141 -296.739401) (xy 381.799117 -296.695364) (xy 381.775991 -296.647343) (xy 381.760281 -296.596413)
			(xy 381.752338 -296.543709) (xy 381.75184 -296.51706) (xy 381.752284 -296.49182) (xy 381.759428 -296.441848)
			(xy 381.766064 -296.417492) (xy 381.76962 -296.405554) (xy 381.76454 -296.38117) (xy 381.696214 -296.296842)
			(xy 381.673354 -296.286936) (xy 381.660908 -296.287952) (xy 381.638048 -296.288714) (xy 381.613222 -296.288274)
			(xy 381.564224 -296.280249) (xy 381.517169 -296.264402) (xy 381.473298 -296.241151) (xy 381.433767 -296.211108)
			(xy 381.399617 -296.175066) (xy 381.371748 -296.133973) (xy 381.350895 -296.088913) (xy 381.337607 -296.041073)
			(xy 381.332233 -295.991713) (xy 381.003919 -295.991713) (xy 380.998564 -296.040998) (xy 380.98529 -296.088832)
			(xy 380.964451 -296.133888) (xy 380.936599 -296.174979) (xy 380.902465 -296.211023) (xy 380.86295 -296.24107)
			(xy 380.819095 -296.264328) (xy 380.772055 -296.280186) (xy 380.723069 -296.288224) (xy 380.698248 -296.288714)
			(xy 380.675134 -296.287952) (xy 380.662747 -296.287551) (xy 380.63998 -296.297273) (xy 380.6317 -296.306494)
			(xy 380.571248 -296.38117) (xy 380.566168 -296.405554) (xy 380.569724 -296.417492) (xy 380.576367 -296.441847)
			(xy 380.583509 -296.49182) (xy 380.583948 -296.51706) (xy 380.58345 -296.543709) (xy 380.575507 -296.596413)
			(xy 380.559797 -296.647343) (xy 380.536671 -296.695364) (xy 380.506647 -296.739401) (xy 380.470395 -296.778472)
			(xy 380.428724 -296.811703) (xy 380.382566 -296.838352) (xy 380.332952 -296.857824) (xy 380.28099 -296.869684)
			(xy 380.22784 -296.873668) (xy 380.17469 -296.869684) (xy 380.122728 -296.857824) (xy 380.073114 -296.838352)
			(xy 380.026956 -296.811703) (xy 379.985285 -296.778472) (xy 379.949033 -296.739401) (xy 379.919009 -296.695364)
			(xy 379.895883 -296.647343) (xy 379.880173 -296.596413) (xy 379.87223 -296.543709) (xy 379.871732 -296.51706)
			(xy 379.872177 -296.49182) (xy 379.87932 -296.441848) (xy 379.885956 -296.417492) (xy 379.889512 -296.405554)
			(xy 379.884432 -296.38117) (xy 379.816106 -296.296842) (xy 379.793246 -296.286936) (xy 379.7808 -296.287952)
			(xy 379.758448 -296.288714) (xy 379.75794 -296.288714) (xy 379.73508 -296.287952) (xy 379.722634 -296.286936)
			(xy 379.699774 -296.296842) (xy 379.631448 -296.38117) (xy 379.626368 -296.405554) (xy 379.629924 -296.417492)
			(xy 379.636567 -296.441847) (xy 379.643709 -296.49182) (xy 379.644148 -296.51706) (xy 379.64365 -296.543709)
			(xy 379.635707 -296.596413) (xy 379.619997 -296.647343) (xy 379.596871 -296.695364) (xy 379.566847 -296.739401)
			(xy 379.530595 -296.778472) (xy 379.488924 -296.811703) (xy 379.442766 -296.838352) (xy 379.393152 -296.857824)
			(xy 379.34119 -296.869684) (xy 379.28804 -296.873668) (xy 379.23489 -296.869684) (xy 379.182928 -296.857824)
			(xy 379.133314 -296.838352) (xy 379.087156 -296.811703) (xy 379.045485 -296.778472) (xy 379.009233 -296.739401)
			(xy 378.979209 -296.695364) (xy 378.956083 -296.647343) (xy 378.940373 -296.596413) (xy 378.93243 -296.543709)
			(xy 378.931932 -296.51706) (xy 378.932377 -296.49182) (xy 378.93952 -296.441848) (xy 378.946156 -296.417492)
			(xy 378.949712 -296.405554) (xy 378.944632 -296.38117) (xy 378.876306 -296.296842) (xy 378.853446 -296.286936)
			(xy 378.841 -296.287952) (xy 378.81814 -296.288714) (xy 378.793315 -296.288265) (xy 378.744318 -296.280239)
			(xy 378.697266 -296.264391) (xy 378.653397 -296.24114) (xy 378.613868 -296.211098) (xy 378.57972 -296.175056)
			(xy 378.551853 -296.133964) (xy 378.531001 -296.088905) (xy 378.517714 -296.041066) (xy 378.512342 -295.991708)
			(xy 378.177789 -295.991708) (xy 378.171702 -296.029158) (xy 378.156118 -296.075839) (xy 378.133247 -296.119416)
			(xy 378.103682 -296.15876) (xy 378.068189 -296.192852) (xy 378.027686 -296.220808) (xy 377.983224 -296.241906)
			(xy 377.935953 -296.255598) (xy 377.887098 -296.26153) (xy 377.837923 -296.259549) (xy 377.789704 -296.249705)
			(xy 377.743688 -296.232253) (xy 377.701067 -296.207646) (xy 377.662946 -296.176521) (xy 377.630311 -296.139684)
			(xy 377.604008 -296.098088) (xy 377.584717 -296.052812) (xy 377.57294 -296.005028) (xy 377.56898 -295.955974)
			(xy 376.670329 -295.955974) (xy 376.671223 -295.957828) (xy 376.692739 -296.019205) (xy 376.707253 -296.082604)
			(xy 376.714581 -296.147229) (xy 376.71502 -296.179748) (xy 376.71502 -296.522648) (xy 376.715274 -296.52849)
			(xy 376.71651 -296.536542) (xy 376.723386 -296.551301) (xy 376.728736 -296.557446) (xy 376.729752 -296.558462)
			(xy 377.253445 -297.081913) (xy 385.826756 -297.081913) (xy 385.826756 -297.017991) (xy 385.834767 -296.954573)
			(xy 385.850664 -296.892659) (xy 385.874196 -296.833226) (xy 385.90499 -296.777211) (xy 385.942563 -296.725496)
			(xy 385.98632 -296.678899) (xy 386.035573 -296.638154) (xy 386.089544 -296.603903) (xy 386.147383 -296.576686)
			(xy 386.208176 -296.556933) (xy 386.270966 -296.544955) (xy 386.334762 -296.540942) (xy 386.398558 -296.544955)
			(xy 386.461348 -296.556933) (xy 386.522141 -296.576686) (xy 386.57998 -296.603903) (xy 386.633951 -296.638154)
			(xy 386.683204 -296.678899) (xy 386.726961 -296.725496) (xy 386.764534 -296.777211) (xy 386.795328 -296.833226)
			(xy 386.81886 -296.892659) (xy 386.834757 -296.954573) (xy 386.842768 -297.017991) (xy 386.84327 -297.049952)
			(xy 386.842768 -297.081913) (xy 386.834757 -297.145331) (xy 386.81886 -297.207245) (xy 386.795328 -297.266678)
			(xy 386.764534 -297.322693) (xy 386.726961 -297.374408) (xy 386.683204 -297.421005) (xy 386.633951 -297.46175)
			(xy 386.57998 -297.496001) (xy 386.522141 -297.523218) (xy 386.461348 -297.542971) (xy 386.398558 -297.554949)
			(xy 386.334762 -297.558963) (xy 386.270966 -297.554949) (xy 386.208176 -297.542971) (xy 386.147383 -297.523218)
			(xy 386.089544 -297.496001) (xy 386.035573 -297.46175) (xy 385.98632 -297.421005) (xy 385.942563 -297.374408)
			(xy 385.90499 -297.322693) (xy 385.874196 -297.266678) (xy 385.850664 -297.207245) (xy 385.834767 -297.145331)
			(xy 385.826756 -297.081913) (xy 377.253445 -297.081913) (xy 377.278646 -297.107102) (xy 377.282939 -297.111688)
			(xy 377.289369 -297.122476) (xy 377.291346 -297.128438) (xy 377.292616 -297.132248) (xy 378.613924 -299.2882)
			(xy 378.617988 -299.294042) (xy 378.705539 -299.400722) (xy 379.192026 -299.400722) (xy 379.196097 -299.3451)
			(xy 379.208223 -299.290663) (xy 379.228146 -299.238572) (xy 379.255442 -299.189937) (xy 379.289528 -299.145794)
			(xy 379.329677 -299.107085) (xy 379.375035 -299.074634) (xy 379.424635 -299.049133) (xy 379.477419 -299.031126)
			(xy 379.532262 -299.020996) (xy 379.587996 -299.018959) (xy 379.643433 -299.025059) (xy 379.69739 -299.039165)
			(xy 379.748719 -299.060977) (xy 379.796325 -299.090031) (xy 379.839193 -299.125706) (xy 379.87641 -299.167243)
			(xy 379.907183 -299.213756) (xy 379.930855 -299.264253) (xy 379.935385 -299.27931) (xy 381.753362 -299.27931)
			(xy 381.757433 -299.223688) (xy 381.769559 -299.169251) (xy 381.789482 -299.11716) (xy 381.816778 -299.068525)
			(xy 381.850864 -299.024382) (xy 381.891013 -298.985673) (xy 381.936371 -298.953222) (xy 381.985971 -298.927721)
			(xy 382.038755 -298.909714) (xy 382.093598 -298.899584) (xy 382.149332 -298.897547) (xy 382.204769 -298.903647)
			(xy 382.258726 -298.917753) (xy 382.310055 -298.939565) (xy 382.357661 -298.968619) (xy 382.400529 -299.004294)
			(xy 382.437746 -299.045831) (xy 382.468519 -299.092344) (xy 382.492191 -299.142841) (xy 382.508259 -299.196248)
			(xy 382.516379 -299.251424) (xy 382.516888 -299.27931) (xy 384.039362 -299.27931) (xy 384.043433 -299.223688)
			(xy 384.055559 -299.169251) (xy 384.075482 -299.11716) (xy 384.102778 -299.068525) (xy 384.136864 -299.024382)
			(xy 384.177013 -298.985673) (xy 384.222371 -298.953222) (xy 384.271971 -298.927721) (xy 384.324755 -298.909714)
			(xy 384.379598 -298.899584) (xy 384.435332 -298.897547) (xy 384.490769 -298.903647) (xy 384.544726 -298.917753)
			(xy 384.596055 -298.939565) (xy 384.643661 -298.968619) (xy 384.686529 -299.004294) (xy 384.723746 -299.045831)
			(xy 384.754519 -299.092344) (xy 384.762249 -299.108833) (xy 387.935718 -299.108833) (xy 387.935718 -299.044911)
			(xy 387.943729 -298.981493) (xy 387.959626 -298.919579) (xy 387.983158 -298.860146) (xy 388.013952 -298.804131)
			(xy 388.051525 -298.752416) (xy 388.095282 -298.705819) (xy 388.144535 -298.665074) (xy 388.198506 -298.630823)
			(xy 388.256345 -298.603606) (xy 388.317138 -298.583853) (xy 388.379928 -298.571875) (xy 388.443724 -298.567862)
			(xy 388.50752 -298.571875) (xy 388.57031 -298.583853) (xy 388.631103 -298.603606) (xy 388.688942 -298.630823)
			(xy 388.742913 -298.665074) (xy 388.792166 -298.705819) (xy 388.835923 -298.752416) (xy 388.873496 -298.804131)
			(xy 388.90429 -298.860146) (xy 388.927822 -298.919579) (xy 388.943719 -298.981493) (xy 388.95173 -299.044911)
			(xy 388.952232 -299.076872) (xy 388.95173 -299.108833) (xy 388.943719 -299.172251) (xy 388.927822 -299.234165)
			(xy 388.90429 -299.293598) (xy 388.873496 -299.349613) (xy 388.835923 -299.401328) (xy 388.792166 -299.447925)
			(xy 388.742913 -299.48867) (xy 388.688942 -299.522921) (xy 388.631103 -299.550138) (xy 388.57031 -299.569891)
			(xy 388.50752 -299.581869) (xy 388.443724 -299.585883) (xy 388.379928 -299.581869) (xy 388.317138 -299.569891)
			(xy 388.256345 -299.550138) (xy 388.198506 -299.522921) (xy 388.144535 -299.48867) (xy 388.095282 -299.447925)
			(xy 388.051525 -299.401328) (xy 388.013952 -299.349613) (xy 387.983158 -299.293598) (xy 387.959626 -299.234165)
			(xy 387.943729 -299.172251) (xy 387.935718 -299.108833) (xy 384.762249 -299.108833) (xy 384.778191 -299.142841)
			(xy 384.794259 -299.196248) (xy 384.802379 -299.251424) (xy 384.802888 -299.27931) (xy 384.802379 -299.307196)
			(xy 384.794259 -299.362372) (xy 384.778191 -299.415779) (xy 384.754519 -299.466276) (xy 384.723746 -299.512789)
			(xy 384.686529 -299.554326) (xy 384.643661 -299.590001) (xy 384.596055 -299.619055) (xy 384.544726 -299.640867)
			(xy 384.490769 -299.654973) (xy 384.435332 -299.661073) (xy 384.379598 -299.659036) (xy 384.324755 -299.648906)
			(xy 384.271971 -299.630899) (xy 384.222371 -299.605398) (xy 384.177013 -299.572947) (xy 384.136864 -299.534238)
			(xy 384.102778 -299.490095) (xy 384.075482 -299.44146) (xy 384.055559 -299.389369) (xy 384.043433 -299.334932)
			(xy 384.039362 -299.27931) (xy 382.516888 -299.27931) (xy 382.516379 -299.307196) (xy 382.508259 -299.362372)
			(xy 382.492191 -299.415779) (xy 382.468519 -299.466276) (xy 382.437746 -299.512789) (xy 382.400529 -299.554326)
			(xy 382.357661 -299.590001) (xy 382.310055 -299.619055) (xy 382.258726 -299.640867) (xy 382.204769 -299.654973)
			(xy 382.149332 -299.661073) (xy 382.093598 -299.659036) (xy 382.038755 -299.648906) (xy 381.985971 -299.630899)
			(xy 381.936371 -299.605398) (xy 381.891013 -299.572947) (xy 381.850864 -299.534238) (xy 381.816778 -299.490095)
			(xy 381.789482 -299.44146) (xy 381.769559 -299.389369) (xy 381.757433 -299.334932) (xy 381.753362 -299.27931)
			(xy 379.935385 -299.27931) (xy 379.946923 -299.31766) (xy 379.955043 -299.372836) (xy 379.955552 -299.400722)
			(xy 379.955043 -299.428608) (xy 379.946923 -299.483784) (xy 379.930855 -299.537191) (xy 379.907183 -299.587688)
			(xy 379.87641 -299.634201) (xy 379.839193 -299.675738) (xy 379.796325 -299.711413) (xy 379.748719 -299.740467)
			(xy 379.69739 -299.762279) (xy 379.643433 -299.776385) (xy 379.587996 -299.782485) (xy 379.532262 -299.780448)
			(xy 379.477419 -299.770318) (xy 379.424635 -299.752311) (xy 379.375035 -299.72681) (xy 379.329677 -299.694359)
			(xy 379.289528 -299.65565) (xy 379.255442 -299.611507) (xy 379.228146 -299.562872) (xy 379.208223 -299.510781)
			(xy 379.196097 -299.456344) (xy 379.192026 -299.400722) (xy 378.705539 -299.400722) (xy 380.086311 -301.083175)
			(xy 386.695944 -301.083175) (xy 386.695944 -301.019253) (xy 386.703955 -300.955835) (xy 386.719852 -300.893921)
			(xy 386.743384 -300.834488) (xy 386.774178 -300.778473) (xy 386.811751 -300.726758) (xy 386.855508 -300.680161)
			(xy 386.904761 -300.639416) (xy 386.958732 -300.605165) (xy 387.016571 -300.577948) (xy 387.077364 -300.558195)
			(xy 387.140154 -300.546217) (xy 387.20395 -300.542204) (xy 387.267746 -300.546217) (xy 387.330536 -300.558195)
			(xy 387.391329 -300.577948) (xy 387.449168 -300.605165) (xy 387.503139 -300.639416) (xy 387.552392 -300.680161)
			(xy 387.596149 -300.726758) (xy 387.633722 -300.778473) (xy 387.664516 -300.834488) (xy 387.688048 -300.893921)
			(xy 387.703945 -300.955835) (xy 387.711956 -301.019253) (xy 387.712458 -301.051214) (xy 387.711956 -301.083175)
			(xy 387.703945 -301.146593) (xy 387.688048 -301.208507) (xy 387.664516 -301.26794) (xy 387.633722 -301.323955)
			(xy 387.596149 -301.37567) (xy 387.552392 -301.422267) (xy 387.503139 -301.463012) (xy 387.449168 -301.497263)
			(xy 387.391329 -301.52448) (xy 387.330536 -301.544233) (xy 387.267746 -301.556211) (xy 387.20395 -301.560225)
			(xy 387.140154 -301.556211) (xy 387.077364 -301.544233) (xy 387.016571 -301.52448) (xy 386.958732 -301.497263)
			(xy 386.904761 -301.463012) (xy 386.855508 -301.422267) (xy 386.811751 -301.37567) (xy 386.774178 -301.323955)
			(xy 386.743384 -301.26794) (xy 386.719852 -301.208507) (xy 386.703955 -301.146593) (xy 386.695944 -301.083175)
			(xy 380.086311 -301.083175) (xy 381.096693 -302.314313) (xy 385.881112 -302.314313) (xy 385.881112 -302.250391)
			(xy 385.889123 -302.186973) (xy 385.90502 -302.125059) (xy 385.928552 -302.065626) (xy 385.959346 -302.009611)
			(xy 385.996919 -301.957896) (xy 386.040676 -301.911299) (xy 386.089929 -301.870554) (xy 386.1439 -301.836303)
			(xy 386.201739 -301.809086) (xy 386.262532 -301.789333) (xy 386.325322 -301.777355) (xy 386.389118 -301.773342)
			(xy 386.452914 -301.777355) (xy 386.515704 -301.789333) (xy 386.576497 -301.809086) (xy 386.634336 -301.836303)
			(xy 386.688307 -301.870554) (xy 386.73756 -301.911299) (xy 386.781317 -301.957896) (xy 386.81889 -302.009611)
			(xy 386.849684 -302.065626) (xy 386.873216 -302.125059) (xy 386.889113 -302.186973) (xy 386.897124 -302.250391)
			(xy 386.897626 -302.282352) (xy 386.897124 -302.314313) (xy 386.889113 -302.377731) (xy 386.873216 -302.439645)
			(xy 386.849684 -302.499078) (xy 386.81889 -302.555093) (xy 386.781317 -302.606808) (xy 386.73756 -302.653405)
			(xy 386.688307 -302.69415) (xy 386.634336 -302.728401) (xy 386.576497 -302.755618) (xy 386.515704 -302.775371)
			(xy 386.452914 -302.787349) (xy 386.389118 -302.791363) (xy 386.325322 -302.787349) (xy 386.262532 -302.775371)
			(xy 386.201739 -302.755618) (xy 386.1439 -302.728401) (xy 386.089929 -302.69415) (xy 386.040676 -302.653405)
			(xy 385.996919 -302.606808) (xy 385.959346 -302.555093) (xy 385.928552 -302.499078) (xy 385.90502 -302.439645)
			(xy 385.889123 -302.377731) (xy 385.881112 -302.314313) (xy 381.096693 -302.314313) (xy 383.605278 -305.370992)
			(xy 383.605278 -305.3715) (xy 383.613152 -305.380898) (xy 383.613406 -305.381406) (xy 383.621534 -305.391312)
			(xy 383.624582 -305.395376) (xy 383.632456 -305.40706) (xy 383.632964 -305.408076) (xy 383.63906 -305.416712)
			(xy 386.083044 -309.074312) (xy 389.3345 -309.074312) (xy 389.338571 -309.01869) (xy 389.350697 -308.964253)
			(xy 389.37062 -308.912162) (xy 389.397916 -308.863527) (xy 389.432002 -308.819384) (xy 389.472151 -308.780675)
			(xy 389.517509 -308.748224) (xy 389.567109 -308.722723) (xy 389.619893 -308.704716) (xy 389.674736 -308.694586)
			(xy 389.73047 -308.692549) (xy 389.785907 -308.698649) (xy 389.839864 -308.712755) (xy 389.891193 -308.734567)
			(xy 389.938799 -308.763621) (xy 389.981667 -308.799296) (xy 390.018884 -308.840833) (xy 390.049657 -308.887346)
			(xy 390.073329 -308.937843) (xy 390.089397 -308.99125) (xy 390.097517 -309.046426) (xy 390.098026 -309.074312)
			(xy 390.097517 -309.102198) (xy 390.089397 -309.157374) (xy 390.079235 -309.191152) (xy 393.28674 -309.191152)
			(xy 393.290811 -309.13553) (xy 393.302937 -309.081093) (xy 393.32286 -309.029002) (xy 393.350156 -308.980367)
			(xy 393.384242 -308.936224) (xy 393.424391 -308.897515) (xy 393.469749 -308.865064) (xy 393.519349 -308.839563)
			(xy 393.572133 -308.821556) (xy 393.626976 -308.811426) (xy 393.68271 -308.809389) (xy 393.738147 -308.815489)
			(xy 393.792104 -308.829595) (xy 393.843433 -308.851407) (xy 393.891039 -308.880461) (xy 393.933907 -308.916136)
			(xy 393.971124 -308.957673) (xy 394.001897 -309.004186) (xy 394.025569 -309.054683) (xy 394.041637 -309.10809)
			(xy 394.049757 -309.163266) (xy 394.050266 -309.191152) (xy 394.049757 -309.219038) (xy 394.041637 -309.274214)
			(xy 394.025569 -309.327621) (xy 394.001897 -309.378118) (xy 393.971124 -309.424631) (xy 393.933907 -309.466168)
			(xy 393.891039 -309.501843) (xy 393.843433 -309.530897) (xy 393.792104 -309.552709) (xy 393.738147 -309.566815)
			(xy 393.68271 -309.572915) (xy 393.626976 -309.570878) (xy 393.572133 -309.560748) (xy 393.519349 -309.542741)
			(xy 393.469749 -309.51724) (xy 393.424391 -309.484789) (xy 393.384242 -309.44608) (xy 393.350156 -309.401937)
			(xy 393.32286 -309.353302) (xy 393.302937 -309.301211) (xy 393.290811 -309.246774) (xy 393.28674 -309.191152)
			(xy 390.079235 -309.191152) (xy 390.073329 -309.210781) (xy 390.049657 -309.261278) (xy 390.018884 -309.307791)
			(xy 389.981667 -309.349328) (xy 389.938799 -309.385003) (xy 389.891193 -309.414057) (xy 389.839864 -309.435869)
			(xy 389.785907 -309.449975) (xy 389.73047 -309.456075) (xy 389.674736 -309.454038) (xy 389.619893 -309.443908)
			(xy 389.567109 -309.425901) (xy 389.517509 -309.4004) (xy 389.472151 -309.367949) (xy 389.432002 -309.32924)
			(xy 389.397916 -309.285097) (xy 389.37062 -309.236462) (xy 389.350697 -309.184371) (xy 389.338571 -309.129934)
			(xy 389.3345 -309.074312) (xy 386.083044 -309.074312) (xy 386.84 -310.207152) (xy 393.28674 -310.207152)
			(xy 393.290811 -310.15153) (xy 393.302937 -310.097093) (xy 393.32286 -310.045002) (xy 393.350156 -309.996367)
			(xy 393.384242 -309.952224) (xy 393.424391 -309.913515) (xy 393.469749 -309.881064) (xy 393.519349 -309.855563)
			(xy 393.572133 -309.837556) (xy 393.626976 -309.827426) (xy 393.68271 -309.825389) (xy 393.738147 -309.831489)
			(xy 393.792104 -309.845595) (xy 393.843433 -309.867407) (xy 393.891039 -309.896461) (xy 393.933907 -309.932136)
			(xy 393.971124 -309.973673) (xy 394.001897 -310.020186) (xy 394.025569 -310.070683) (xy 394.041637 -310.12409)
			(xy 394.049757 -310.179266) (xy 394.050266 -310.207152) (xy 394.049757 -310.235038) (xy 394.041637 -310.290214)
			(xy 394.025569 -310.343621) (xy 394.001897 -310.394118) (xy 393.971124 -310.440631) (xy 393.933907 -310.482168)
			(xy 393.891039 -310.517843) (xy 393.843433 -310.546897) (xy 393.792104 -310.568709) (xy 393.738147 -310.582815)
			(xy 393.68271 -310.588915) (xy 393.626976 -310.586878) (xy 393.572133 -310.576748) (xy 393.519349 -310.558741)
			(xy 393.469749 -310.53324) (xy 393.424391 -310.500789) (xy 393.384242 -310.46208) (xy 393.350156 -310.417937)
			(xy 393.32286 -310.369302) (xy 393.302937 -310.317211) (xy 393.290811 -310.262774) (xy 393.28674 -310.207152)
			(xy 386.84 -310.207152) (xy 387.919427 -311.822592) (xy 388.54964 -311.822592) (xy 388.553711 -311.76697)
			(xy 388.565837 -311.712533) (xy 388.58576 -311.660442) (xy 388.613056 -311.611807) (xy 388.647142 -311.567664)
			(xy 388.687291 -311.528955) (xy 388.732649 -311.496504) (xy 388.782249 -311.471003) (xy 388.835033 -311.452996)
			(xy 388.889876 -311.442866) (xy 388.94561 -311.440829) (xy 389.001047 -311.446929) (xy 389.055004 -311.461035)
			(xy 389.106333 -311.482847) (xy 389.153939 -311.511901) (xy 389.196807 -311.547576) (xy 389.234024 -311.589113)
			(xy 389.264797 -311.635626) (xy 389.288469 -311.686123) (xy 389.304537 -311.73953) (xy 389.312657 -311.794706)
			(xy 389.313166 -311.822592) (xy 390.83564 -311.822592) (xy 390.839711 -311.76697) (xy 390.851837 -311.712533)
			(xy 390.87176 -311.660442) (xy 390.899056 -311.611807) (xy 390.933142 -311.567664) (xy 390.973291 -311.528955)
			(xy 391.018649 -311.496504) (xy 391.068249 -311.471003) (xy 391.121033 -311.452996) (xy 391.175876 -311.442866)
			(xy 391.23161 -311.440829) (xy 391.287047 -311.446929) (xy 391.341004 -311.461035) (xy 391.392333 -311.482847)
			(xy 391.439939 -311.511901) (xy 391.482807 -311.547576) (xy 391.520024 -311.589113) (xy 391.550797 -311.635626)
			(xy 391.574469 -311.686123) (xy 391.590537 -311.73953) (xy 391.598657 -311.794706) (xy 391.599166 -311.822592)
			(xy 391.598657 -311.850478) (xy 391.590537 -311.905654) (xy 391.574469 -311.959061) (xy 391.550797 -312.009558)
			(xy 391.520024 -312.056071) (xy 391.482807 -312.097608) (xy 391.439939 -312.133283) (xy 391.392333 -312.162337)
			(xy 391.341004 -312.184149) (xy 391.287047 -312.198255) (xy 391.23161 -312.204355) (xy 391.175876 -312.202318)
			(xy 391.121033 -312.192188) (xy 391.068249 -312.174181) (xy 391.018649 -312.14868) (xy 390.973291 -312.116229)
			(xy 390.933142 -312.07752) (xy 390.899056 -312.033377) (xy 390.87176 -311.984742) (xy 390.851837 -311.932651)
			(xy 390.839711 -311.878214) (xy 390.83564 -311.822592) (xy 389.313166 -311.822592) (xy 389.312657 -311.850478)
			(xy 389.304537 -311.905654) (xy 389.288469 -311.959061) (xy 389.264797 -312.009558) (xy 389.234024 -312.056071)
			(xy 389.196807 -312.097608) (xy 389.153939 -312.133283) (xy 389.106333 -312.162337) (xy 389.055004 -312.184149)
			(xy 389.001047 -312.198255) (xy 388.94561 -312.204355) (xy 388.889876 -312.202318) (xy 388.835033 -312.192188)
			(xy 388.782249 -312.174181) (xy 388.732649 -312.14868) (xy 388.687291 -312.116229) (xy 388.647142 -312.07752)
			(xy 388.613056 -312.033377) (xy 388.58576 -311.984742) (xy 388.565837 -311.932651) (xy 388.553711 -311.878214)
			(xy 388.54964 -311.822592) (xy 387.919427 -311.822592) (xy 388.67842 -312.95848) (xy 388.679944 -312.960766)
			(xy 388.68922 -312.972322) (xy 388.713024 -312.989949) (xy 388.740888 -312.999995) (xy 388.770463 -313.001616)
			(xy 388.799258 -312.994674) (xy 388.824846 -312.979755) (xy 388.845071 -312.958115) (xy 388.858228 -312.931578)
			(xy 388.8613 -312.917078) (xy 388.86627 -312.890772) (xy 388.8826 -312.839789) (xy 388.905887 -312.791584)
			(xy 388.935674 -312.747102) (xy 388.971379 -312.707213) (xy 389.012302 -312.672698) (xy 389.057642 -312.644233)
			(xy 389.106512 -312.622376) (xy 389.157954 -312.607554) (xy 389.210961 -312.600057) (xy 389.237728 -312.599578)
			(xy 389.264997 -312.600043) (xy 389.318978 -312.607809) (xy 389.371305 -312.623178) (xy 389.420912 -312.645838)
			(xy 389.46679 -312.675327) (xy 389.508003 -312.711045) (xy 389.543714 -312.752265) (xy 389.573195 -312.798147)
			(xy 389.595846 -312.847758) (xy 389.611205 -312.900088) (xy 389.618961 -312.954071) (xy 389.61949 -312.98134)
			(xy 389.618991 -313.009909) (xy 389.610477 -313.06641) (xy 389.593618 -313.121005) (xy 389.581644 -313.146948)
			(xy 389.575928 -313.159851) (xy 389.57109 -313.187643) (xy 389.574037 -313.215699) (xy 389.584545 -313.24188)
			(xy 389.601811 -313.264189) (xy 389.62452 -313.280926) (xy 389.650941 -313.290814) (xy 389.664956 -313.29249)
			(xy 389.705088 -313.296046) (xy 389.710676 -313.2963) (xy 389.719566 -313.295538) (xy 389.721852 -313.29503)
			(xy 389.781699 -313.284651) (xy 389.902311 -313.270183) (xy 390.023572 -313.262952) (xy 390.08431 -313.262518)
			(xy 390.084564 -313.262518) (xy 390.148643 -313.263015) (xy 390.276547 -313.271087) (xy 390.403688 -313.287202)
			(xy 390.529561 -313.311295) (xy 390.653666 -313.343271) (xy 390.77551 -313.383003) (xy 390.894609 -313.430333)
			(xy 391.010489 -313.485072) (xy 391.12269 -313.547004) (xy 391.230766 -313.615881) (xy 391.245316 -313.6265)
			(xy 392.774368 -313.6265) (xy 392.778383 -313.562698) (xy 392.790362 -313.499903) (xy 392.810118 -313.439104)
			(xy 392.837338 -313.381261) (xy 392.871594 -313.327286) (xy 392.912345 -313.27803) (xy 392.958948 -313.23427)
			(xy 393.010669 -313.196697) (xy 393.066691 -313.165902) (xy 393.126131 -313.142372) (xy 393.188052 -313.126478)
			(xy 393.251476 -313.118471) (xy 393.28344 -313.117992) (xy 393.324334 -313.119516) (xy 393.327262 -313.087957)
			(xy 393.339842 -313.025838) (xy 393.360047 -312.965765) (xy 393.387563 -312.90867) (xy 393.421963 -312.855438)
			(xy 393.462714 -312.806896) (xy 393.509184 -312.763797) (xy 393.560651 -312.726808) (xy 393.616317 -312.696505)
			(xy 393.675318 -312.673357) (xy 393.73674 -312.657723) (xy 393.799628 -312.649846) (xy 393.831318 -312.649362)
			(xy 393.863276 -312.649925) (xy 393.926689 -312.657938) (xy 393.988597 -312.673835) (xy 394.048025 -312.697366)
			(xy 394.104035 -312.72816) (xy 394.155744 -312.76573) (xy 394.202337 -312.809485) (xy 394.243078 -312.858735)
			(xy 394.277326 -312.912702) (xy 394.30454 -312.970536) (xy 394.324291 -313.031324) (xy 394.336267 -313.094109)
			(xy 394.340281 -313.1579) (xy 394.336267 -313.221691) (xy 394.324291 -313.284476) (xy 394.30454 -313.345264)
			(xy 394.277326 -313.403098) (xy 394.243078 -313.457065) (xy 394.202337 -313.506315) (xy 394.155744 -313.55007)
			(xy 394.104035 -313.58764) (xy 394.048025 -313.618434) (xy 393.988597 -313.641965) (xy 393.926689 -313.657862)
			(xy 393.863276 -313.665875) (xy 393.831318 -313.666378) (xy 393.790424 -313.664854) (xy 393.787721 -313.694949)
			(xy 393.776075 -313.754243) (xy 393.757468 -313.811733) (xy 393.745212 -313.839352) (xy 393.741684 -313.848163)
			(xy 393.740686 -313.867102) (xy 393.746602 -313.885121) (xy 393.752324 -313.892692) (xy 393.787893 -313.935872)
			(xy 394.732762 -313.935872) (xy 394.736833 -313.88025) (xy 394.748959 -313.825813) (xy 394.768882 -313.773722)
			(xy 394.796178 -313.725087) (xy 394.830264 -313.680944) (xy 394.870413 -313.642235) (xy 394.915771 -313.609784)
			(xy 394.965371 -313.584283) (xy 395.018155 -313.566276) (xy 395.072998 -313.556146) (xy 395.128732 -313.554109)
			(xy 395.184169 -313.560209) (xy 395.238126 -313.574315) (xy 395.289455 -313.596127) (xy 395.337061 -313.625181)
			(xy 395.379929 -313.660856) (xy 395.417146 -313.702393) (xy 395.447919 -313.748906) (xy 395.471591 -313.799403)
			(xy 395.487659 -313.85281) (xy 395.495779 -313.907986) (xy 395.496288 -313.935872) (xy 395.495779 -313.963758)
			(xy 395.487659 -314.018934) (xy 395.471591 -314.072341) (xy 395.447919 -314.122838) (xy 395.417146 -314.169351)
			(xy 395.379929 -314.210888) (xy 395.337061 -314.246563) (xy 395.289455 -314.275617) (xy 395.238126 -314.297429)
			(xy 395.184169 -314.311535) (xy 395.128732 -314.317635) (xy 395.072998 -314.315598) (xy 395.018155 -314.305468)
			(xy 394.965371 -314.287461) (xy 394.915771 -314.26196) (xy 394.870413 -314.229509) (xy 394.830264 -314.1908)
			(xy 394.796178 -314.146657) (xy 394.768882 -314.098022) (xy 394.748959 -314.045931) (xy 394.736833 -313.991494)
			(xy 394.732762 -313.935872) (xy 393.787893 -313.935872) (xy 393.81049 -313.963304) (xy 393.81686 -313.970419)
			(xy 393.833526 -313.979713) (xy 393.852441 -313.982233) (xy 393.861798 -313.980322) (xy 393.891371 -313.973554)
			(xy 393.951605 -313.966297) (xy 393.98194 -313.965844) (xy 393.982702 -313.965844) (xy 394.014244 -313.96637)
			(xy 394.076842 -313.974173) (xy 394.137995 -313.98966) (xy 394.196762 -314.012591) (xy 394.252241 -314.042616)
			(xy 394.303581 -314.079273) (xy 394.349992 -314.121999) (xy 394.390761 -314.170138) (xy 394.425263 -314.222949)
			(xy 394.452968 -314.279623) (xy 394.473449 -314.339289) (xy 394.486393 -314.40103) (xy 394.4916 -314.463898)
			(xy 394.488991 -314.526927) (xy 394.478606 -314.589149) (xy 394.460603 -314.649609) (xy 394.435261 -314.707377)
			(xy 394.402967 -314.761568) (xy 394.364218 -314.811347) (xy 394.31961 -314.855951) (xy 394.269826 -314.894695)
			(xy 394.215633 -314.926984) (xy 394.157862 -314.952321) (xy 394.0974 -314.970317) (xy 394.035177 -314.980696)
			(xy 393.972147 -314.983299) (xy 393.90928 -314.978086) (xy 393.847541 -314.965136) (xy 393.787877 -314.944649)
			(xy 393.731206 -314.916939) (xy 393.678398 -314.882431) (xy 393.630263 -314.841657) (xy 393.587542 -314.795242)
			(xy 393.55089 -314.743899) (xy 393.52087 -314.688417) (xy 393.497944 -314.629647) (xy 393.482464 -314.568493)
			(xy 393.474667 -314.505894) (xy 393.474194 -314.474352) (xy 393.474857 -314.437732) (xy 393.485384 -314.365252)
			(xy 393.506184 -314.295027) (xy 393.52093 -314.2615) (xy 393.524509 -314.252705) (xy 393.525494 -314.233753)
			(xy 393.519554 -314.215729) (xy 393.513818 -314.20816) (xy 393.455652 -314.137548) (xy 393.449263 -314.130453)
			(xy 393.432605 -314.121159) (xy 393.413699 -314.118629) (xy 393.404344 -314.12053) (xy 393.374769 -314.127291)
			(xy 393.314536 -314.134552) (xy 393.284202 -314.135008) (xy 393.28344 -314.135008) (xy 393.251476 -314.134529)
			(xy 393.188052 -314.126522) (xy 393.126131 -314.110628) (xy 393.066691 -314.087098) (xy 393.010669 -314.056303)
			(xy 392.958948 -314.01873) (xy 392.912345 -313.97497) (xy 392.871594 -313.925714) (xy 392.837338 -313.871739)
			(xy 392.810118 -313.813896) (xy 392.790362 -313.753097) (xy 392.778383 -313.690302) (xy 392.774368 -313.6265)
			(xy 391.245316 -313.6265) (xy 391.334287 -313.691431) (xy 391.432843 -313.773354) (xy 391.526042 -313.861323)
			(xy 391.613513 -313.954989) (xy 391.694909 -314.053981) (xy 391.769906 -314.157904) (xy 391.838206 -314.266345)
			(xy 391.899539 -314.378875) (xy 391.953659 -314.495045) (xy 392.000353 -314.614394) (xy 392.039435 -314.736448)
			(xy 392.055604 -314.798456) (xy 392.058959 -314.809509) (xy 392.073798 -314.827181) (xy 392.094855 -314.836619)
			(xy 392.106404 -314.83681) (xy 392.117326 -314.836556) (xy 392.118088 -314.836556) (xy 392.145344 -314.837018)
			(xy 392.199301 -314.844774) (xy 392.251606 -314.860131) (xy 392.301192 -314.882775) (xy 392.347051 -314.912245)
			(xy 392.388249 -314.947942) (xy 392.423947 -314.989139) (xy 392.453419 -315.034997) (xy 392.476065 -315.084583)
			(xy 392.491423 -315.136887) (xy 392.499181 -315.190844) (xy 392.499181 -315.245356) (xy 392.491423 -315.299313)
			(xy 392.476065 -315.351617) (xy 392.453419 -315.401203) (xy 392.423947 -315.447061) (xy 392.388249 -315.488258)
			(xy 392.347051 -315.523955) (xy 392.301192 -315.553425) (xy 392.251606 -315.576069) (xy 392.199301 -315.591426)
			(xy 392.145344 -315.599182) (xy 392.118088 -315.599572) (xy 392.097514 -315.599064) (xy 392.092851 -315.611561)
			(xy 392.089528 -315.638019) (xy 392.093171 -315.664434) (xy 392.103531 -315.689004) (xy 392.119902 -315.710053)
			(xy 392.141166 -315.726144) (xy 392.165871 -315.736178) (xy 392.179048 -315.738256) (xy 392.216882 -315.743591)
			(xy 392.290476 -315.764124) (xy 392.325606 -315.77915) (xy 392.335071 -315.782853) (xy 392.355375 -315.783246)
			(xy 392.364976 -315.779912) (xy 392.394845 -315.768663) (xy 392.45668 -315.752841) (xy 392.520007 -315.744863)
			(xy 392.55192 -315.744352) (xy 392.582651 -315.744817) (xy 392.643665 -315.752227) (xy 392.703341 -315.766937)
			(xy 392.760809 -315.788733) (xy 392.815231 -315.817296) (xy 392.865814 -315.85221) (xy 392.911819 -315.892966)
			(xy 392.952578 -315.938971) (xy 392.987494 -315.989552) (xy 393.016059 -316.043973) (xy 393.037857 -316.10144)
			(xy 393.052569 -316.161115) (xy 393.059982 -316.222129) (xy 393.060428 -316.25286) (xy 393.059888 -316.286044)
			(xy 393.05125 -316.351847) (xy 393.034128 -316.415968) (xy 393.008813 -316.477317) (xy 392.975735 -316.534854)
			(xy 392.935455 -316.587601) (xy 392.888659 -316.634662) (xy 392.83614 -316.675238) (xy 392.77879 -316.70864)
			(xy 392.717584 -316.7343) (xy 392.653561 -316.751783) (xy 392.620754 -316.756796) (xy 392.609832 -316.75832)
			(xy 392.590782 -316.770258) (xy 392.537188 -316.855348) (xy 392.534394 -316.8777) (xy 392.53795 -316.888368)
			(xy 392.549339 -316.926217) (xy 392.561587 -317.004298) (xy 392.562334 -317.043816) (xy 392.562334 -317.04407)
			(xy 392.56189 -317.074804) (xy 392.554485 -317.135824) (xy 392.539778 -317.195506) (xy 392.517984 -317.252981)
			(xy 392.489422 -317.307409) (xy 392.454507 -317.357998) (xy 392.413749 -317.40401) (xy 392.367742 -317.444773)
			(xy 392.317157 -317.479693) (xy 392.262732 -317.508261) (xy 392.20526 -317.530061) (xy 392.145579 -317.544774)
			(xy 392.08456 -317.552187) (xy 392.053826 -317.552578) (xy 392.053572 -317.552578) (xy 392.022668 -317.552117)
			(xy 391.961315 -317.544621) (xy 391.90132 -317.529754) (xy 391.843566 -317.507736) (xy 391.788901 -317.47889)
			(xy 391.76325 -317.461646) (xy 391.754173 -317.455849) (xy 391.733048 -317.451765) (xy 391.712108 -317.456713)
			(xy 391.703306 -317.462916) (xy 391.677228 -317.482389) (xy 391.621052 -317.515258) (xy 391.561142 -317.540693)
			(xy 391.498478 -317.558278) (xy 391.434082 -317.567728) (xy 391.401554 -317.568834) (xy 391.387997 -317.569485)
			(xy 391.361947 -317.577072) (xy 391.338824 -317.591267) (xy 391.32027 -317.611063) (xy 391.3076 -317.635055)
			(xy 391.301713 -317.661541) (xy 391.303027 -317.688641) (xy 391.306812 -317.701676) (xy 391.308336 -317.705486)
			(xy 391.364403 -317.840868) (xy 394.547852 -317.840868) (xy 394.547852 -315.041534) (xy 394.548281 -315.031465)
			(xy 394.555998 -315.012866) (xy 394.562838 -315.005466) (xy 394.821156 -314.746894) (xy 394.828577 -314.74008)
			(xy 394.84716 -314.732345) (xy 394.857224 -314.731908) (xy 403.17547 -314.731908) (xy 403.185538 -314.732347)
			(xy 403.204136 -314.740058) (xy 403.211538 -314.746894) (xy 404.383494 -315.91885) (xy 404.390304 -315.926274)
			(xy 404.398041 -315.944855) (xy 404.39848 -315.954918) (xy 404.39848 -318.283336) (xy 404.398079 -318.293408)
			(xy 404.390342 -318.312006) (xy 404.383494 -318.319404) (xy 403.830536 -318.872362) (xy 403.823113 -318.879173)
			(xy 403.804532 -318.886911) (xy 403.794468 -318.887348) (xy 395.594078 -318.887348) (xy 395.584006 -318.886948)
			(xy 395.565407 -318.879211) (xy 395.55801 -318.872362) (xy 394.562838 -317.876936) (xy 394.556027 -317.869513)
			(xy 394.548289 -317.850932) (xy 394.547852 -317.840868) (xy 391.364403 -317.840868) (xy 391.412476 -317.956946)
			(xy 391.413238 -317.958724) (xy 391.419914 -317.972036) (xy 391.439601 -317.99436) (xy 391.464892 -318.010055)
			(xy 391.493635 -318.017788) (xy 391.523387 -318.016901) (xy 391.551618 -318.007469) (xy 391.564114 -317.999364)
			(xy 391.589964 -317.981696) (xy 391.645155 -317.952124) (xy 391.703558 -317.929547) (xy 391.764289 -317.914305)
			(xy 391.826431 -317.906628) (xy 391.857738 -317.906146) (xy 391.889308 -317.906625) (xy 391.951963 -317.914441)
			(xy 392.01317 -317.92995) (xy 392.071987 -317.952912) (xy 392.127512 -317.982974) (xy 392.17889 -318.019676)
			(xy 392.225333 -318.062452) (xy 392.246104 -318.086232) (xy 392.251438 -318.092328) (xy 392.272774 -318.102488)
			(xy 392.28131 -318.106166) (xy 392.299813 -318.10774) (xy 392.308842 -318.105536) (xy 392.317224 -318.102996)
			(xy 392.323066 -318.09944) (xy 392.353182 -318.081679) (xy 392.417245 -318.053671) (xy 392.484536 -318.03469)
			(xy 392.553792 -318.025092) (xy 392.58875 -318.02451) (xy 392.589258 -318.02451) (xy 392.62124 -318.024988)
			(xy 392.6847 -318.033) (xy 392.746655 -318.048903) (xy 392.806128 -318.072446) (xy 392.862181 -318.103258)
			(xy 392.913931 -318.140852) (xy 392.96056 -318.184636) (xy 393.001334 -318.233919) (xy 393.035609 -318.287924)
			(xy 393.062844 -318.3458) (xy 393.082611 -318.406632) (xy 393.094597 -318.469463) (xy 393.098614 -318.5333)
			(xy 393.094597 -318.597137) (xy 393.082611 -318.659968) (xy 393.062844 -318.7208) (xy 393.035609 -318.778676)
			(xy 393.001334 -318.832681) (xy 392.96056 -318.881964) (xy 392.913931 -318.925748) (xy 392.862181 -318.963342)
			(xy 392.806128 -318.994154) (xy 392.746655 -319.017697) (xy 392.6847 -319.0336) (xy 392.62124 -319.041612)
			(xy 392.589258 -319.042034) (xy 392.559453 -319.041616) (xy 392.500251 -319.034658) (xy 392.442269 -319.02082)
			(xy 392.386306 -319.000291) (xy 392.333129 -318.973354) (xy 392.30808 -318.957198) (xy 392.295669 -318.949603)
			(xy 392.26788 -318.941026) (xy 392.238801 -318.940612) (xy 392.210779 -318.948396) (xy 392.186079 -318.963748)
			(xy 392.166695 -318.985429) (xy 392.159998 -318.998346) (xy 392.1506 -319.017142) (xy 392.150092 -319.018158)
			(xy 392.142726 -319.03289) (xy 392.14097 -319.037457) (xy 392.13905 -319.047049) (xy 392.138916 -319.05194)
			(xy 392.180826 -319.09512) (xy 392.19759 -319.102994) (xy 392.20521 -319.103502) (xy 392.237432 -319.106202)
			(xy 392.300868 -319.118735) (xy 392.362205 -319.139201) (xy 392.420457 -319.167271) (xy 392.474684 -319.202493)
			(xy 392.524013 -319.244299) (xy 392.56765 -319.292017) (xy 392.586718 -319.318132) (xy 392.594796 -319.328883)
			(xy 392.615476 -319.34606) (xy 392.639918 -319.357253) (xy 392.666433 -319.361689) (xy 392.693187 -319.35906)
			(xy 392.718332 -319.34955) (xy 392.729466 -319.342008) (xy 392.754068 -319.324856) (xy 392.807499 -319.297623)
			(xy 392.864532 -319.279084) (xy 392.923763 -319.269695) (xy 392.953748 -319.26911) (xy 392.981017 -319.2696)
			(xy 393.034999 -319.277368) (xy 393.087327 -319.292738) (xy 393.136935 -319.315399) (xy 393.182813 -319.344888)
			(xy 393.224028 -319.380606) (xy 393.259741 -319.421825) (xy 393.289224 -319.467707) (xy 393.311879 -319.517318)
			(xy 393.327243 -319.569647) (xy 393.335004 -319.623631) (xy 393.335004 -319.678169) (xy 393.327243 -319.732153)
			(xy 393.311879 -319.784482) (xy 393.289224 -319.834093) (xy 393.259741 -319.879975) (xy 393.224028 -319.921194)
			(xy 393.182813 -319.956912) (xy 393.136935 -319.986401) (xy 393.087327 -320.009062) (xy 393.034999 -320.024432)
			(xy 392.981017 -320.0322) (xy 392.953748 -320.032634) (xy 392.95324 -320.032634) (xy 392.943216 -320.033047)
			(xy 392.924691 -320.040711) (xy 392.910515 -320.054886) (xy 392.902848 -320.07341) (xy 392.90244 -320.083434)
			(xy 392.90244 -320.086736) (xy 392.902948 -320.091054) (xy 392.90371 -320.09461) (xy 392.909503 -320.122123)
			(xy 392.915738 -320.178003) (xy 392.916156 -320.206116) (xy 392.915716 -320.236445) (xy 392.908503 -320.296673)
			(xy 392.89418 -320.355617) (xy 392.872952 -320.41244) (xy 392.845119 -320.466336) (xy 392.811076 -320.51654)
			(xy 392.771305 -320.562342) (xy 392.726372 -320.60309) (xy 392.676912 -320.638208) (xy 392.623629 -320.667196)
			(xy 392.595608 -320.67881) (xy 392.595354 -320.67881) (xy 392.594846 -320.679064) (xy 392.586191 -320.683072)
			(xy 392.572462 -320.696291) (xy 392.564522 -320.713618) (xy 392.563473 -320.732648) (xy 392.566144 -320.741802)
			(xy 392.747653 -321.179952) (xy 394.285976 -321.179952) (xy 394.290047 -321.12433) (xy 394.302173 -321.069893)
			(xy 394.322096 -321.017802) (xy 394.349392 -320.969167) (xy 394.383478 -320.925024) (xy 394.423627 -320.886315)
			(xy 394.468985 -320.853864) (xy 394.518585 -320.828363) (xy 394.571369 -320.810356) (xy 394.626212 -320.800226)
			(xy 394.681946 -320.798189) (xy 394.737383 -320.804289) (xy 394.79134 -320.818395) (xy 394.842669 -320.840207)
			(xy 394.890275 -320.869261) (xy 394.933143 -320.904936) (xy 394.97036 -320.946473) (xy 395.001133 -320.992986)
			(xy 395.024805 -321.043483) (xy 395.040873 -321.09689) (xy 395.048993 -321.152066) (xy 395.049502 -321.179952)
			(xy 395.048993 -321.207838) (xy 395.040873 -321.263014) (xy 395.024805 -321.316421) (xy 395.001133 -321.366918)
			(xy 394.97036 -321.413431) (xy 394.933143 -321.454968) (xy 394.890275 -321.490643) (xy 394.842669 -321.519697)
			(xy 394.79134 -321.541509) (xy 394.737383 -321.555615) (xy 394.681946 -321.561715) (xy 394.626212 -321.559678)
			(xy 394.571369 -321.549548) (xy 394.518585 -321.531541) (xy 394.468985 -321.50604) (xy 394.423627 -321.473589)
			(xy 394.383478 -321.43488) (xy 394.349392 -321.390737) (xy 394.322096 -321.342102) (xy 394.302173 -321.290011)
			(xy 394.290047 -321.235574) (xy 394.285976 -321.179952) (xy 392.747653 -321.179952) (xy 392.960098 -321.692778)
			(xy 392.962384 -321.69862) (xy 392.97991 -321.740784) (xy 392.982704 -321.750182) (xy 392.982704 -321.750436)
			(xy 392.99007 -321.78752) (xy 392.990324 -321.788028) (xy 392.993118 -321.80149) (xy 393.13219 -322.5008)
			(xy 394.382741 -322.5008) (xy 394.386755 -322.437001) (xy 394.398733 -322.374207) (xy 394.418486 -322.31341)
			(xy 394.445703 -322.255568) (xy 394.479955 -322.201593) (xy 394.520701 -322.152336) (xy 394.5673 -322.108575)
			(xy 394.619015 -322.070998) (xy 394.675032 -322.040199) (xy 394.734468 -322.016664) (xy 394.796384 -322.000763)
			(xy 394.859805 -321.992747) (xy 394.891768 -321.992244) (xy 394.922778 -321.992715) (xy 394.984333 -322.000308)
			(xy 395.04451 -322.015325) (xy 395.102415 -322.037543) (xy 395.13002 -322.05168) (xy 395.138032 -322.055468)
			(xy 395.155566 -322.057944) (xy 395.16431 -322.056506) (xy 395.19352 -322.05041) (xy 395.20209 -322.04824)
			(xy 395.217162 -322.039028) (xy 395.222984 -322.032376) (xy 395.243742 -322.0073) (xy 395.290571 -321.962081)
			(xy 395.342788 -321.923209) (xy 395.399539 -321.89132) (xy 395.459897 -321.866934) (xy 395.522873 -321.850451)
			(xy 395.587437 -321.842141) (xy 395.619986 -321.841622) (xy 395.651951 -321.842042) (xy 395.715376 -321.850053)
			(xy 395.777298 -321.86595) (xy 395.836739 -321.889483) (xy 395.892761 -321.92028) (xy 395.944482 -321.957856)
			(xy 395.991085 -322.001619) (xy 396.031836 -322.050877) (xy 396.066092 -322.104854) (xy 396.093312 -322.162699)
			(xy 396.113068 -322.223499) (xy 396.125047 -322.286297) (xy 396.129062 -322.3501) (xy 396.125047 -322.413903)
			(xy 396.113068 -322.476701) (xy 396.093312 -322.537501) (xy 396.070106 -322.586815) (xy 396.221452 -322.586815)
			(xy 396.221452 -322.522893) (xy 396.229463 -322.459475) (xy 396.24536 -322.397561) (xy 396.268892 -322.338128)
			(xy 396.299686 -322.282113) (xy 396.337259 -322.230398) (xy 396.381016 -322.183801) (xy 396.430269 -322.143056)
			(xy 396.48424 -322.108805) (xy 396.542079 -322.081588) (xy 396.602872 -322.061835) (xy 396.665662 -322.049857)
			(xy 396.729458 -322.045844) (xy 396.793254 -322.049857) (xy 396.856044 -322.061835) (xy 396.916837 -322.081588)
			(xy 396.974676 -322.108805) (xy 397.028647 -322.143056) (xy 397.0779 -322.183801) (xy 397.121657 -322.230398)
			(xy 397.15923 -322.282113) (xy 397.190024 -322.338128) (xy 397.213556 -322.397561) (xy 397.229453 -322.459475)
			(xy 397.237464 -322.522893) (xy 397.237966 -322.554854) (xy 397.237464 -322.586815) (xy 397.229453 -322.650233)
			(xy 397.213556 -322.712147) (xy 397.190024 -322.77158) (xy 397.15923 -322.827595) (xy 397.121657 -322.87931)
			(xy 397.0779 -322.925907) (xy 397.028647 -322.966652) (xy 397.022812 -322.970355) (xy 397.697192 -322.970355)
			(xy 397.697192 -322.906433) (xy 397.705203 -322.843015) (xy 397.7211 -322.781101) (xy 397.744632 -322.721668)
			(xy 397.775426 -322.665653) (xy 397.812999 -322.613938) (xy 397.856756 -322.567341) (xy 397.906009 -322.526596)
			(xy 397.95998 -322.492345) (xy 398.017819 -322.465128) (xy 398.078612 -322.445375) (xy 398.141402 -322.433397)
			(xy 398.205198 -322.429384) (xy 398.268994 -322.433397) (xy 398.331784 -322.445375) (xy 398.392577 -322.465128)
			(xy 398.450416 -322.492345) (xy 398.504387 -322.526596) (xy 398.55364 -322.567341) (xy 398.597397 -322.613938)
			(xy 398.63497 -322.665653) (xy 398.665764 -322.721668) (xy 398.689296 -322.781101) (xy 398.69877 -322.818)
			(xy 400.068587 -322.818) (xy 400.072601 -322.754207) (xy 400.084577 -322.69142) (xy 400.104328 -322.630629)
			(xy 400.131542 -322.572793) (xy 400.16579 -322.518824) (xy 400.206532 -322.469572) (xy 400.253125 -322.425814)
			(xy 400.304835 -322.388241) (xy 400.360846 -322.357445) (xy 400.420274 -322.333911) (xy 400.482184 -322.31801)
			(xy 400.545599 -322.309994) (xy 400.577558 -322.30949) (xy 400.607225 -322.309885) (xy 400.666157 -322.316787)
			(xy 400.723884 -322.330501) (xy 400.779623 -322.350842) (xy 400.832615 -322.377532) (xy 400.88214 -322.410209)
			(xy 400.927525 -322.448429) (xy 400.948144 -322.469764) (xy 400.955256 -322.477384) (xy 400.97456 -322.485766)
			(xy 401.069556 -322.485766) (xy 401.08886 -322.477384) (xy 401.095972 -322.469764) (xy 401.116606 -322.448446)
			(xy 401.161993 -322.410234) (xy 401.211518 -322.377563) (xy 401.264508 -322.350876) (xy 401.320243 -322.330536)
			(xy 401.377966 -322.316818) (xy 401.436893 -322.30991) (xy 401.466558 -322.30949) (xy 401.498939 -322.309993)
			(xy 401.563177 -322.318216) (xy 401.62585 -322.334532) (xy 401.685943 -322.358679) (xy 401.74248 -322.390264)
			(xy 401.794548 -322.428776) (xy 401.8413 -322.47359) (xy 401.862036 -322.498466) (xy 401.86864 -322.506594)
			(xy 401.887182 -322.516246) (xy 401.982178 -322.523612) (xy 402.00199 -322.5165) (xy 402.00961 -322.509388)
			(xy 402.033129 -322.488499) (xy 402.084399 -322.452051) (xy 402.139772 -322.422202) (xy 402.198402 -322.399407)
			(xy 402.259394 -322.384013) (xy 402.321819 -322.376255) (xy 402.353272 -322.375784) (xy 402.384511 -322.3763)
			(xy 402.446515 -322.383972) (xy 402.507113 -322.399181) (xy 402.565392 -322.421697) (xy 402.620475 -322.451181)
			(xy 402.671532 -322.48719) (xy 402.717794 -322.52918) (xy 402.758566 -322.57652) (xy 402.793233 -322.628498)
			(xy 402.807678 -322.6562) (xy 402.812105 -322.664187) (xy 402.825524 -322.676554) (xy 402.83384 -322.68033)
			(xy 402.904452 -322.709032) (xy 402.922994 -322.70954) (xy 402.93163 -322.706492) (xy 402.951648 -322.699892)
			(xy 402.992761 -322.690598) (xy 403.013672 -322.68795) (xy 403.02561 -322.68668) (xy 403.04593 -322.673472)
			(xy 403.09292 -322.5927) (xy 403.098404 -322.582066) (xy 403.099847 -322.55821) (xy 403.095714 -322.54698)
			(xy 403.08279 -322.5153) (xy 403.064598 -322.449344) (xy 403.055396 -322.381546) (xy 403.05482 -322.347336)
			(xy 403.05482 -322.347082) (xy 403.055322 -322.315121) (xy 403.063333 -322.251703) (xy 403.07923 -322.189789)
			(xy 403.102762 -322.130356) (xy 403.133556 -322.074341) (xy 403.171129 -322.022626) (xy 403.214886 -321.976029)
			(xy 403.264139 -321.935284) (xy 403.31811 -321.901033) (xy 403.375949 -321.873816) (xy 403.436742 -321.854063)
			(xy 403.499532 -321.842085) (xy 403.563328 -321.838072) (xy 403.627124 -321.842085) (xy 403.689914 -321.854063)
			(xy 403.750707 -321.873816) (xy 403.808546 -321.901033) (xy 403.862517 -321.935284) (xy 403.91177 -321.976029)
			(xy 403.955527 -322.022626) (xy 403.9931 -322.074341) (xy 404.023894 -322.130356) (xy 404.047426 -322.189789)
			(xy 404.063323 -322.251703) (xy 404.071334 -322.315121) (xy 404.071836 -322.347082) (xy 404.071836 -322.351908)
			(xy 404.072148 -322.36114) (xy 404.078534 -322.378458) (xy 404.084282 -322.38569) (xy 404.104348 -322.408804)
			(xy 404.110706 -322.415512) (xy 404.126993 -322.424225) (xy 404.136098 -322.425822) (xy 404.169096 -322.430673)
			(xy 404.233526 -322.447911) (xy 404.29515 -322.473422) (xy 404.352911 -322.50677) (xy 404.379684 -322.52666)
			(xy 404.388401 -322.532687) (xy 404.408969 -322.537689) (xy 404.429801 -322.533928) (xy 404.438866 -322.528438)
			(xy 404.464118 -322.511985) (xy 404.517756 -322.484498) (xy 404.574265 -322.463537) (xy 404.632854 -322.449396)
			(xy 404.692702 -322.442272) (xy 404.722838 -322.441824) (xy 404.757536 -322.442404) (xy 404.826287 -322.451839)
			(xy 404.893115 -322.470541) (xy 404.956776 -322.498164) (xy 405.016086 -322.534193) (xy 405.043386 -322.555616)
			(xy 405.0503 -322.560774) (xy 405.066521 -322.566615) (xy 405.075136 -322.567046) (xy 405.1046 -322.567046)
			(xy 405.113245 -322.56677) (xy 405.129605 -322.561204) (xy 405.136604 -322.556124) (xy 405.163715 -322.535254)
			(xy 405.222458 -322.500177) (xy 405.285377 -322.473301) (xy 405.351332 -322.455111) (xy 405.419133 -322.445935)
			(xy 405.453342 -322.44538) (xy 405.487001 -322.44592) (xy 405.553728 -322.454829) (xy 405.618693 -322.472473)
			(xy 405.649938 -322.485004) (xy 405.660538 -322.48882) (xy 405.683015 -322.487884) (xy 405.702916 -322.477394)
			(xy 405.710136 -322.468748) (xy 405.715216 -322.462144) (xy 405.721121 -322.453908) (xy 405.726507 -322.434393)
			(xy 405.72563 -322.424298) (xy 405.721566 -322.392802) (xy 405.719846 -322.382876) (xy 405.709759 -322.365456)
			(xy 405.702008 -322.35902) (xy 405.675808 -322.338333) (xy 405.628504 -322.291231) (xy 405.587772 -322.238343)
			(xy 405.554311 -322.180579) (xy 405.528699 -322.118933) (xy 405.511375 -322.054465) (xy 405.502637 -321.988284)
			(xy 405.50211 -321.954906) (xy 405.502612 -321.922945) (xy 405.510623 -321.859527) (xy 405.52652 -321.797613)
			(xy 405.550052 -321.73818) (xy 405.580846 -321.682165) (xy 405.618419 -321.63045) (xy 405.662176 -321.583853)
			(xy 405.711429 -321.543108) (xy 405.7654 -321.508857) (xy 405.823239 -321.48164) (xy 405.884032 -321.461887)
			(xy 405.946822 -321.449909) (xy 406.010618 -321.445896) (xy 406.074414 -321.449909) (xy 406.137204 -321.461887)
			(xy 406.197997 -321.48164) (xy 406.255836 -321.508857) (xy 406.309807 -321.543108) (xy 406.35906 -321.583853)
			(xy 406.402817 -321.63045) (xy 406.44039 -321.682165) (xy 406.471184 -321.73818) (xy 406.494716 -321.797613)
			(xy 406.510613 -321.859527) (xy 406.518624 -321.922945) (xy 406.519126 -321.954906) (xy 406.518627 -321.986247)
			(xy 406.510926 -322.048453) (xy 406.495643 -322.109242) (xy 406.473007 -322.167694) (xy 406.443363 -322.222922)
			(xy 406.425654 -322.248784) (xy 406.420066 -322.256404) (xy 406.415494 -322.274946) (xy 406.426924 -322.362322)
			(xy 406.436068 -322.379086) (xy 406.44318 -322.385182) (xy 406.465954 -322.404863) (xy 406.507201 -322.448702)
			(xy 406.542981 -322.497108) (xy 406.572791 -322.549401) (xy 406.584912 -322.576952) (xy 406.5905 -322.590414)
			(xy 406.615138 -322.607432) (xy 406.722326 -322.610988) (xy 406.731963 -322.610888) (xy 406.750093 -322.604395)
			(xy 406.764562 -322.591685) (xy 406.769316 -322.583302) (xy 406.769316 -322.583048) (xy 406.786954 -322.549011)
			(xy 406.828028 -322.484278) (xy 406.875392 -322.423994) (xy 406.928566 -322.368767) (xy 406.987014 -322.319155)
			(xy 407.050145 -322.27566) (xy 407.117323 -322.23872) (xy 407.187869 -322.208707) (xy 407.261071 -322.185926)
			(xy 407.336189 -322.170607) (xy 407.412466 -322.162903) (xy 407.450798 -322.162424) (xy 407.48987 -322.162926)
			(xy 407.567605 -322.170923) (xy 407.644112 -322.186833) (xy 407.71859 -322.21049) (xy 407.790256 -322.241645)
			(xy 407.858357 -322.27997) (xy 407.922178 -322.325063) (xy 407.95194 -322.350384) (xy 407.958832 -322.355915)
			(xy 407.975311 -322.362274) (xy 407.992969 -322.362711) (xy 408.00147 -322.36029) (xy 408.04092 -322.347487)
			(xy 408.121898 -322.329534) (xy 408.204346 -322.320479) (xy 408.245818 -322.319904) (xy 408.284463 -322.32037)
			(xy 408.361357 -322.328191) (xy 408.437065 -322.343751) (xy 408.51081 -322.366891) (xy 408.581837 -322.397372)
			(xy 408.649415 -322.434882) (xy 408.712851 -322.479037) (xy 408.771495 -322.529382) (xy 408.824745 -322.585402)
			(xy 408.872055 -322.646522) (xy 408.912938 -322.712115) (xy 408.946976 -322.781507) (xy 408.973819 -322.853986)
			(xy 408.993192 -322.928809) (xy 409.004895 -323.005209) (xy 409.00881 -323.0824) (xy 409.004895 -323.159591)
			(xy 408.993192 -323.235991) (xy 408.973819 -323.310814) (xy 408.946976 -323.383293) (xy 408.912938 -323.452685)
			(xy 408.872055 -323.518278) (xy 408.824745 -323.579398) (xy 408.771495 -323.635418) (xy 408.712851 -323.685763)
			(xy 408.649415 -323.729918) (xy 408.581837 -323.767428) (xy 408.51081 -323.797909) (xy 408.437065 -323.821049)
			(xy 408.361357 -323.836609) (xy 408.284463 -323.84443) (xy 408.245818 -323.84492) (xy 408.206746 -323.844398)
			(xy 408.129013 -323.836403) (xy 408.052506 -323.820495) (xy 407.978028 -323.796841) (xy 407.906363 -323.76569)
			(xy 407.838261 -323.727368) (xy 407.774438 -323.682279) (xy 407.744676 -323.65696) (xy 407.737773 -323.651443)
			(xy 407.721301 -323.645076) (xy 407.703646 -323.644634) (xy 407.695146 -323.647054) (xy 407.655695 -323.659855)
			(xy 407.574718 -323.677808) (xy 407.49227 -323.686865) (xy 407.450798 -323.68744) (xy 407.411769 -323.686989)
			(xy 407.334117 -323.679033) (xy 407.257684 -323.663183) (xy 407.183272 -323.639606) (xy 407.111658 -323.608548)
			(xy 407.043593 -323.570335) (xy 406.979789 -323.525366) (xy 406.920914 -323.474113) (xy 406.867585 -323.417112)
			(xy 406.82036 -323.35496) (xy 406.779733 -323.288308) (xy 406.746129 -323.217853) (xy 406.719902 -323.144332)
			(xy 406.710134 -323.106542) (xy 406.706578 -323.092064) (xy 406.685242 -323.071744) (xy 406.580086 -323.05117)
			(xy 406.570466 -323.049728) (xy 406.551372 -323.053332) (xy 406.535013 -323.063821) (xy 406.529032 -323.07149)
			(xy 406.51107 -323.095661) (xy 406.470388 -323.140062) (xy 406.424744 -323.179346) (xy 406.374778 -323.21296)
			(xy 406.32119 -323.240434) (xy 406.264731 -323.261383) (xy 406.206191 -323.275514) (xy 406.146392 -323.282628)
			(xy 406.116282 -323.283072) (xy 406.082666 -323.282497) (xy 406.016027 -323.273586) (xy 405.951145 -323.255961)
			(xy 405.91994 -323.243448) (xy 405.90935 -323.239592) (xy 405.886862 -323.240537) (xy 405.866958 -323.251047)
			(xy 405.859742 -323.259704) (xy 405.839056 -323.286235) (xy 405.791853 -323.334172) (xy 405.738745 -323.37547)
			(xy 405.680658 -323.409409) (xy 405.618605 -323.435396) (xy 405.553668 -323.452979) (xy 405.48698 -323.461851)
			(xy 405.453342 -323.462396) (xy 405.418644 -323.461824) (xy 405.349893 -323.452386) (xy 405.283065 -323.433682)
			(xy 405.219404 -323.406058) (xy 405.160094 -323.370028) (xy 405.132794 -323.348604) (xy 405.125884 -323.34344)
			(xy 405.10966 -323.337603) (xy 405.101044 -323.337174) (xy 405.07158 -323.337174) (xy 405.062934 -323.337436)
			(xy 405.046573 -323.343012) (xy 405.039576 -323.348096) (xy 405.012474 -323.368978) (xy 404.953728 -323.404052)
			(xy 404.890807 -323.430926) (xy 404.82485 -323.449114) (xy 404.757048 -323.458286) (xy 404.722838 -323.45884)
			(xy 404.689534 -323.458306) (xy 404.623498 -323.449604) (xy 404.559162 -323.432357) (xy 404.497628 -323.406859)
			(xy 404.439948 -323.373548) (xy 404.413212 -323.353684) (xy 404.404469 -323.347623) (xy 404.383806 -323.342638)
			(xy 404.362887 -323.346408) (xy 404.353776 -323.351906) (xy 404.328549 -323.368356) (xy 404.27497 -323.395858)
			(xy 404.218514 -323.416829) (xy 404.159974 -323.430974) (xy 404.100171 -323.438094) (xy 404.070058 -323.43852)
			(xy 404.039327 -323.438084) (xy 403.978312 -323.430671) (xy 403.918636 -323.415958) (xy 403.861169 -323.394159)
			(xy 403.806747 -323.365593) (xy 403.756166 -323.330676) (xy 403.710161 -323.289917) (xy 403.669405 -323.243911)
			(xy 403.634491 -323.193327) (xy 403.605928 -323.138904) (xy 403.584133 -323.081435) (xy 403.569424 -323.021758)
			(xy 403.562014 -322.960743) (xy 403.56155 -322.930012) (xy 403.56155 -322.925186) (xy 403.561244 -322.915953)
			(xy 403.554854 -322.898635) (xy 403.549104 -322.891404) (xy 403.529038 -322.86829) (xy 403.522612 -322.861567)
			(xy 403.5062 -322.852847) (xy 403.497034 -322.851272) (xy 403.490684 -322.850256) (xy 403.48197 -322.849417)
			(xy 403.464851 -322.853026) (xy 403.449952 -322.862196) (xy 403.444202 -322.868798) (xy 403.424644 -322.892674)
			(xy 403.419479 -322.899603) (xy 403.413756 -322.915902) (xy 403.413735 -322.933176) (xy 403.416262 -322.941442)
			(xy 403.426221 -322.971916) (xy 403.436944 -323.035119) (xy 403.437598 -323.067172) (xy 403.437119 -323.094425)
			(xy 403.429365 -323.148375) (xy 403.414012 -323.200674) (xy 403.391372 -323.250254) (xy 403.361906 -323.296108)
			(xy 403.326214 -323.337301) (xy 403.285023 -323.372995) (xy 403.23917 -323.402464) (xy 403.189591 -323.425106)
			(xy 403.137293 -323.440461) (xy 403.083343 -323.448217) (xy 403.05609 -323.44868) (xy 403.029324 -323.448243)
			(xy 402.976317 -323.44077) (xy 402.924875 -323.425958) (xy 402.87601 -323.404098) (xy 402.830682 -323.37562)
			(xy 402.789782 -323.341083) (xy 402.77161 -323.321426) (xy 402.76526 -323.314314) (xy 402.749258 -323.305932)
			(xy 402.664422 -323.295518) (xy 402.646388 -323.299836) (xy 402.638768 -323.30517) (xy 402.61345 -323.321811)
			(xy 402.559608 -323.349598) (xy 402.50285 -323.3708) (xy 402.443977 -323.385116) (xy 402.38382 -323.392345)
			(xy 402.353526 -323.3928) (xy 402.353272 -323.3928) (xy 402.320891 -323.392279) (xy 402.256654 -323.38406)
			(xy 402.193981 -323.367747) (xy 402.133889 -323.343604) (xy 402.077351 -323.312021) (xy 402.025283 -323.273512)
			(xy 401.97853 -323.228699) (xy 401.957794 -323.203824) (xy 401.95119 -323.195696) (xy 401.932648 -323.186044)
			(xy 401.837652 -323.178678) (xy 401.81784 -323.18579) (xy 401.81022 -323.192902) (xy 401.786687 -323.213775)
			(xy 401.73542 -323.250225) (xy 401.680051 -323.280076) (xy 401.621423 -323.302875) (xy 401.560433 -323.318272)
			(xy 401.49801 -323.326033) (xy 401.466558 -323.326506) (xy 401.436891 -323.326101) (xy 401.37796 -323.319201)
			(xy 401.320233 -323.305488) (xy 401.264494 -323.285149) (xy 401.211502 -323.258461) (xy 401.161976 -323.225785)
			(xy 401.116591 -323.187566) (xy 401.095972 -323.166232) (xy 401.08886 -323.158612) (xy 401.069556 -323.15023)
			(xy 400.97456 -323.15023) (xy 400.955256 -323.158612) (xy 400.948144 -323.166232) (xy 400.927501 -323.187541)
			(xy 400.882116 -323.225754) (xy 400.832593 -323.258426) (xy 400.779604 -323.285114) (xy 400.723871 -323.305456)
			(xy 400.666149 -323.319175) (xy 400.607223 -323.326085) (xy 400.577558 -323.326506) (xy 400.545599 -323.326006)
			(xy 400.482184 -323.31799) (xy 400.420274 -323.302089) (xy 400.360846 -323.278555) (xy 400.304835 -323.247759)
			(xy 400.253125 -323.210186) (xy 400.206532 -323.166428) (xy 400.16579 -323.117176) (xy 400.131542 -323.063207)
			(xy 400.104328 -323.005371) (xy 400.084577 -322.94458) (xy 400.072601 -322.881793) (xy 400.068587 -322.818)
			(xy 398.69877 -322.818) (xy 398.705193 -322.843015) (xy 398.713204 -322.906433) (xy 398.713706 -322.938394)
			(xy 398.713204 -322.970355) (xy 398.705193 -323.033773) (xy 398.689296 -323.095687) (xy 398.665764 -323.15512)
			(xy 398.63497 -323.211135) (xy 398.597397 -323.26285) (xy 398.55364 -323.309447) (xy 398.504387 -323.350192)
			(xy 398.450416 -323.384443) (xy 398.392577 -323.41166) (xy 398.331784 -323.431413) (xy 398.268994 -323.443391)
			(xy 398.205198 -323.447405) (xy 398.141402 -323.443391) (xy 398.078612 -323.431413) (xy 398.017819 -323.41166)
			(xy 397.95998 -323.384443) (xy 397.906009 -323.350192) (xy 397.856756 -323.309447) (xy 397.812999 -323.26285)
			(xy 397.775426 -323.211135) (xy 397.744632 -323.15512) (xy 397.7211 -323.095687) (xy 397.705203 -323.033773)
			(xy 397.697192 -322.970355) (xy 397.022812 -322.970355) (xy 396.974676 -323.000903) (xy 396.916837 -323.02812)
			(xy 396.856044 -323.047873) (xy 396.793254 -323.059851) (xy 396.729458 -323.063865) (xy 396.665662 -323.059851)
			(xy 396.602872 -323.047873) (xy 396.542079 -323.02812) (xy 396.48424 -323.000903) (xy 396.430269 -322.966652)
			(xy 396.381016 -322.925907) (xy 396.337259 -322.87931) (xy 396.299686 -322.827595) (xy 396.268892 -322.77158)
			(xy 396.24536 -322.712147) (xy 396.229463 -322.650233) (xy 396.221452 -322.586815) (xy 396.070106 -322.586815)
			(xy 396.066092 -322.595346) (xy 396.031836 -322.649323) (xy 395.991085 -322.698581) (xy 395.944482 -322.742344)
			(xy 395.892761 -322.77992) (xy 395.836739 -322.810717) (xy 395.777298 -322.83425) (xy 395.715376 -322.850147)
			(xy 395.651951 -322.858158) (xy 395.619986 -322.858638) (xy 395.588976 -322.858147) (xy 395.527422 -322.85056)
			(xy 395.467245 -322.835549) (xy 395.409339 -322.813337) (xy 395.381734 -322.799202) (xy 395.373731 -322.795391)
			(xy 395.35619 -322.79293) (xy 395.347444 -322.794376) (xy 395.318234 -322.800472) (xy 395.309659 -322.802628)
			(xy 395.29459 -322.81185) (xy 395.28877 -322.818506) (xy 395.268034 -322.843601) (xy 395.221202 -322.888819)
			(xy 395.168981 -322.92769) (xy 395.112226 -322.959577) (xy 395.051865 -322.98396) (xy 394.988885 -323.000439)
			(xy 394.924318 -323.008744) (xy 394.891768 -323.00926) (xy 394.859805 -323.008853) (xy 394.796384 -323.000837)
			(xy 394.734468 -322.984936) (xy 394.675032 -322.961401) (xy 394.619015 -322.930602) (xy 394.5673 -322.893025)
			(xy 394.520701 -322.849264) (xy 394.479955 -322.800007) (xy 394.445703 -322.746032) (xy 394.418486 -322.68819)
			(xy 394.398733 -322.627393) (xy 394.386755 -322.564599) (xy 394.382741 -322.5008) (xy 393.13219 -322.5008)
			(xy 393.590585 -324.8058) (xy 394.302791 -324.8058) (xy 394.306805 -324.742008) (xy 394.318781 -324.679221)
			(xy 394.338532 -324.618431) (xy 394.365746 -324.560595) (xy 394.399994 -324.506626) (xy 394.440735 -324.457374)
			(xy 394.487328 -324.413617) (xy 394.539037 -324.376044) (xy 394.595047 -324.345248) (xy 394.654476 -324.321715)
			(xy 394.716385 -324.305814) (xy 394.779799 -324.297798) (xy 394.811758 -324.297294) (xy 394.843961 -324.297763)
			(xy 394.907855 -324.30588) (xy 394.970211 -324.322) (xy 395.030032 -324.345867) (xy 395.08636 -324.377098)
			(xy 395.138293 -324.415193) (xy 395.184998 -324.459542) (xy 395.225729 -324.509434) (xy 395.259832 -324.564071)
			(xy 395.286762 -324.622577) (xy 395.296898 -324.653148) (xy 395.299946 -324.663054) (xy 395.313408 -324.679056)
			(xy 395.398752 -324.720458) (xy 395.419326 -324.721474) (xy 395.429232 -324.717664) (xy 395.457793 -324.70745)
			(xy 395.516732 -324.693105) (xy 395.576957 -324.685862) (xy 395.607286 -324.685406) (xy 395.60754 -324.685406)
			(xy 395.634722 -324.685758) (xy 395.688777 -324.691557) (xy 395.741905 -324.703085) (xy 395.767814 -324.711314)
			(xy 395.776796 -324.713898) (xy 395.795452 -324.71299) (xy 395.804136 -324.709536) (xy 395.866366 -324.682612)
			(xy 395.874751 -324.678455) (xy 395.888043 -324.665305) (xy 395.892274 -324.656958) (xy 395.906101 -324.627702)
			(xy 395.940086 -324.572635) (xy 395.980783 -324.522325) (xy 396.027535 -324.477586) (xy 396.079586 -324.439142)
			(xy 396.136095 -324.407613) (xy 396.196148 -324.38351) (xy 396.258774 -324.367222) (xy 396.322961 -324.359013)
			(xy 396.355316 -324.358508) (xy 396.387277 -324.358979) (xy 396.450696 -324.366992) (xy 396.51261 -324.382891)
			(xy 396.572043 -324.406424) (xy 396.628059 -324.43722) (xy 396.679773 -324.474794) (xy 396.72637 -324.518553)
			(xy 396.767115 -324.567807) (xy 396.801366 -324.621779) (xy 396.828582 -324.679618) (xy 396.848335 -324.740413)
			(xy 396.860313 -324.803203) (xy 396.864327 -324.867) (xy 396.860313 -324.930797) (xy 396.848335 -324.993587)
			(xy 396.828582 -325.054382) (xy 396.801366 -325.112221) (xy 396.767115 -325.166193) (xy 396.72637 -325.215447)
			(xy 396.679773 -325.259206) (xy 396.628059 -325.29678) (xy 396.572043 -325.327576) (xy 396.51261 -325.351109)
			(xy 396.450696 -325.367008) (xy 396.387277 -325.375021) (xy 396.355316 -325.375524) (xy 396.328134 -325.375156)
			(xy 396.27408 -325.369363) (xy 396.220952 -325.357841) (xy 396.195042 -325.349616) (xy 396.186056 -325.34707)
			(xy 396.167418 -325.347991) (xy 396.15872 -325.351394) (xy 396.09649 -325.378318) (xy 396.088091 -325.38245)
			(xy 396.074807 -325.395618) (xy 396.070582 -325.403972) (xy 396.056756 -325.433229) (xy 396.022775 -325.4883)
			(xy 395.98208 -325.538612) (xy 395.935328 -325.583353) (xy 395.883276 -325.621799) (xy 395.826766 -325.653327)
			(xy 395.766712 -325.677429) (xy 395.704084 -325.693714) (xy 395.639895 -325.70192) (xy 395.60754 -325.702422)
			(xy 395.575337 -325.701943) (xy 395.511445 -325.693827) (xy 395.449089 -325.677707) (xy 395.389268 -325.65384)
			(xy 395.332941 -325.62261) (xy 395.281008 -325.584516) (xy 395.234303 -325.540169) (xy 395.193572 -325.490278)
			(xy 395.159468 -325.435643) (xy 395.132537 -325.377138) (xy 395.1224 -325.346568) (xy 395.119352 -325.336662)
			(xy 395.10589 -325.32066) (xy 395.020546 -325.279258) (xy 394.999972 -325.278242) (xy 394.990066 -325.282052)
			(xy 394.961505 -325.292267) (xy 394.902567 -325.306612) (xy 394.842341 -325.313854) (xy 394.812012 -325.31431)
			(xy 394.811758 -325.31431) (xy 394.779799 -325.313802) (xy 394.716385 -325.305786) (xy 394.654476 -325.289885)
			(xy 394.595047 -325.266352) (xy 394.539037 -325.235556) (xy 394.487328 -325.197983) (xy 394.440735 -325.154226)
			(xy 394.399994 -325.104974) (xy 394.365746 -325.051005) (xy 394.338532 -324.993169) (xy 394.318781 -324.932379)
			(xy 394.306805 -324.869592) (xy 394.302791 -324.8058) (xy 393.590585 -324.8058) (xy 394.01242 -326.926956)
			(xy 394.012928 -326.929496) (xy 394.017096 -326.943858) (xy 394.032484 -326.969483) (xy 394.054626 -326.989562)
			(xy 394.081628 -327.00238) (xy 394.111184 -327.006841) (xy 394.140766 -327.002563) (xy 394.167848 -326.989913)
			(xy 394.179298 -326.980296) (xy 394.195508 -326.966008) (xy 394.229974 -326.939939) (xy 394.248132 -326.928226)
			(xy 394.259258 -326.920708) (xy 394.277425 -326.900947) (xy 394.289817 -326.877135) (xy 394.295576 -326.850916)
			(xy 394.294306 -326.824103) (xy 394.286095 -326.798546) (xy 394.271508 -326.776012) (xy 394.261848 -326.766682)
			(xy 394.23938 -326.745973) (xy 394.19905 -326.700066) (xy 394.164515 -326.649655) (xy 394.136272 -326.595468)
			(xy 394.114727 -326.538286) (xy 394.100193 -326.478934) (xy 394.092878 -326.418267) (xy 394.09243 -326.387714)
			(xy 394.092932 -326.355737) (xy 394.100947 -326.292287) (xy 394.116852 -326.230342) (xy 394.140395 -326.17088)
			(xy 394.171205 -326.114836) (xy 394.208797 -326.063096) (xy 394.252576 -326.016476) (xy 394.301854 -325.97571)
			(xy 394.355852 -325.941442) (xy 394.413719 -325.914211) (xy 394.474543 -325.894448) (xy 394.537364 -325.882465)
			(xy 394.601192 -325.878449) (xy 394.66502 -325.882465) (xy 394.727841 -325.894448) (xy 394.788665 -325.914211)
			(xy 394.846532 -325.941442) (xy 394.90053 -325.97571) (xy 394.92849 -325.99884) (xy 398.057622 -325.99884)
			(xy 398.061693 -325.943218) (xy 398.073819 -325.888781) (xy 398.093742 -325.83669) (xy 398.121038 -325.788055)
			(xy 398.155124 -325.743912) (xy 398.195273 -325.705203) (xy 398.240631 -325.672752) (xy 398.290231 -325.647251)
			(xy 398.343015 -325.629244) (xy 398.397858 -325.619114) (xy 398.453592 -325.617077) (xy 398.509029 -325.623177)
			(xy 398.562986 -325.637283) (xy 398.614315 -325.659095) (xy 398.661921 -325.688149) (xy 398.704789 -325.723824)
			(xy 398.742006 -325.765361) (xy 398.772779 -325.811874) (xy 398.796451 -325.862371) (xy 398.812519 -325.915778)
			(xy 398.820639 -325.970954) (xy 398.82099 -325.990161) (xy 399.330666 -325.990161) (xy 399.330666 -325.926239)
			(xy 399.338677 -325.862821) (xy 399.354574 -325.800907) (xy 399.378106 -325.741474) (xy 399.4089 -325.685459)
			(xy 399.446473 -325.633744) (xy 399.49023 -325.587147) (xy 399.539483 -325.546402) (xy 399.593454 -325.512151)
			(xy 399.651293 -325.484934) (xy 399.712086 -325.465181) (xy 399.774876 -325.453203) (xy 399.838672 -325.44919)
			(xy 399.902468 -325.453203) (xy 399.965258 -325.465181) (xy 400.026051 -325.484934) (xy 400.08389 -325.512151)
			(xy 400.137861 -325.546402) (xy 400.187114 -325.587147) (xy 400.230871 -325.633744) (xy 400.268444 -325.685459)
			(xy 400.299238 -325.741474) (xy 400.32277 -325.800907) (xy 400.338667 -325.862821) (xy 400.346678 -325.926239)
			(xy 400.34718 -325.9582) (xy 400.346678 -325.990161) (xy 400.346357 -325.992701) (xy 400.479254 -325.992701)
			(xy 400.479254 -325.928779) (xy 400.487265 -325.865361) (xy 400.503162 -325.803447) (xy 400.526694 -325.744014)
			(xy 400.557488 -325.687999) (xy 400.595061 -325.636284) (xy 400.638818 -325.589687) (xy 400.688071 -325.548942)
			(xy 400.742042 -325.514691) (xy 400.799881 -325.487474) (xy 400.860674 -325.467721) (xy 400.923464 -325.455743)
			(xy 400.98726 -325.45173) (xy 401.051056 -325.455743) (xy 401.113846 -325.467721) (xy 401.174639 -325.487474)
			(xy 401.232478 -325.514691) (xy 401.286449 -325.548942) (xy 401.335702 -325.589687) (xy 401.379459 -325.636284)
			(xy 401.417032 -325.687999) (xy 401.447826 -325.744014) (xy 401.460015 -325.7748) (xy 404.40558 -325.7748)
			(xy 404.409594 -325.711002) (xy 404.421573 -325.648211) (xy 404.441326 -325.587416) (xy 404.468544 -325.529576)
			(xy 404.502796 -325.475603) (xy 404.543543 -325.426349) (xy 404.590142 -325.382591) (xy 404.641858 -325.345018)
			(xy 404.697875 -325.314223) (xy 404.75731 -325.290692) (xy 404.819226 -325.274795) (xy 404.882646 -325.266784)
			(xy 404.914608 -325.266304) (xy 404.946608 -325.266791) (xy 405.010106 -325.274794) (xy 405.072095 -325.290709)
			(xy 405.131595 -325.314285) (xy 405.187662 -325.345148) (xy 405.21382 -325.363586) (xy 405.221534 -325.368695)
			(xy 405.239381 -325.373514) (xy 405.248618 -325.372984) (xy 405.279098 -325.37019) (xy 405.288179 -325.368845)
			(xy 405.304589 -325.360655) (xy 405.311102 -325.354188) (xy 405.331768 -325.332721) (xy 405.377243 -325.294214)
			(xy 405.426905 -325.261282) (xy 405.480074 -325.234378) (xy 405.536023 -325.21387) (xy 405.593984 -325.200038)
			(xy 405.653164 -325.193071) (xy 405.682958 -325.192644) (xy 405.713686 -325.193195) (xy 405.774695 -325.200598)
			(xy 405.834367 -325.215301) (xy 405.891832 -325.237088) (xy 405.946251 -325.265644) (xy 405.996832 -325.300551)
			(xy 406.042836 -325.3413) (xy 406.083594 -325.387297) (xy 406.118509 -325.437872) (xy 406.147075 -325.492286)
			(xy 406.168873 -325.549747) (xy 406.183586 -325.609416) (xy 406.190999 -325.670424) (xy 406.191466 -325.701152)
			(xy 406.190955 -325.732147) (xy 406.183402 -325.793676) (xy 406.168428 -325.85383) (xy 406.146253 -325.911719)
			(xy 406.117208 -325.966483) (xy 406.081721 -326.017312) (xy 406.040321 -326.063451) (xy 405.993619 -326.104216)
			(xy 405.94231 -326.139003) (xy 405.887153 -326.167296) (xy 405.858218 -326.178418) (xy 405.857964 -326.178418)
			(xy 405.849988 -326.181713) (xy 405.836755 -326.192775) (xy 405.827966 -326.207616) (xy 405.82596 -326.21601)
			(xy 405.808688 -326.3011) (xy 405.807322 -326.309548) (xy 405.809645 -326.32649) (xy 405.817449 -326.341707)
			(xy 405.82342 -326.347836) (xy 405.823928 -326.34809) (xy 405.845346 -326.368696) (xy 405.883668 -326.414129)
			(xy 405.916436 -326.463717) (xy 405.943202 -326.516786) (xy 405.963604 -326.572611) (xy 405.977362 -326.630434)
			(xy 405.983961 -326.686672) (xy 407.364946 -326.686672) (xy 407.36543 -326.655942) (xy 407.37284 -326.594931)
			(xy 407.387551 -326.535258) (xy 407.409346 -326.477792) (xy 407.437908 -326.423373) (xy 407.472821 -326.372792)
			(xy 407.513576 -326.326789) (xy 407.559578 -326.286032) (xy 407.610157 -326.251117) (xy 407.664576 -326.222553)
			(xy 407.72204 -326.200756) (xy 407.781713 -326.186044) (xy 407.842724 -326.178631) (xy 407.873454 -326.178164)
			(xy 407.906827 -326.178697) (xy 407.972998 -326.187443) (xy 408.037454 -326.204777) (xy 408.099086 -326.230401)
			(xy 408.156833 -326.263873) (xy 408.183588 -326.283828) (xy 408.191343 -326.289372) (xy 408.209627 -326.294716)
			(xy 408.219148 -326.294242) (xy 408.250136 -326.291194) (xy 408.259539 -326.28992) (xy 408.276501 -326.281447)
			(xy 408.283156 -326.274684) (xy 408.30388 -326.252422) (xy 408.349723 -326.21245) (xy 408.400005 -326.178227)
			(xy 408.454008 -326.150243) (xy 408.510962 -326.128897) (xy 408.570054 -326.114493) (xy 408.630443 -326.107237)
			(xy 408.660854 -326.10679) (xy 408.692818 -326.107272) (xy 408.756243 -326.115279) (xy 408.818164 -326.131173)
			(xy 408.877604 -326.154702) (xy 408.933627 -326.185496) (xy 408.985348 -326.22307) (xy 409.031951 -326.266829)
			(xy 409.072703 -326.316085) (xy 409.106959 -326.37006) (xy 409.13418 -326.427903) (xy 409.153936 -326.488702)
			(xy 409.165915 -326.551498) (xy 409.16993 -326.6153) (xy 409.165915 -326.679102) (xy 409.153936 -326.741898)
			(xy 409.13418 -326.802697) (xy 409.106959 -326.86054) (xy 409.072703 -326.914515) (xy 409.031951 -326.963771)
			(xy 408.985348 -327.00753) (xy 408.933627 -327.045104) (xy 408.877604 -327.075898) (xy 408.818164 -327.099427)
			(xy 408.756243 -327.115321) (xy 408.692818 -327.123328) (xy 408.660854 -327.123806) (xy 408.627482 -327.123254)
			(xy 408.561312 -327.114511) (xy 408.496857 -327.09718) (xy 408.435225 -327.071561) (xy 408.377477 -327.038094)
			(xy 408.35072 -327.018142) (xy 408.342965 -327.0126) (xy 408.324681 -327.007255) (xy 408.31516 -327.007728)
			(xy 408.284172 -327.010776) (xy 408.274772 -327.012062) (xy 408.257809 -327.020528) (xy 408.251152 -327.027286)
			(xy 408.230911 -327.049006) (xy 408.186217 -327.088091) (xy 408.161998 -327.105264) (xy 408.155018 -327.110569)
			(xy 408.144889 -327.124864) (xy 408.142186 -327.133204) (xy 408.133804 -327.161652) (xy 408.131808 -327.170003)
			(xy 408.132841 -327.187133) (xy 408.135836 -327.19518) (xy 408.1451 -327.218489) (xy 408.158122 -327.266928)
			(xy 408.164668 -327.316658) (xy 408.165046 -327.341738) (xy 408.165046 -327.341992) (xy 408.16456 -327.369243)
			(xy 408.156804 -327.423191) (xy 408.141449 -327.475486) (xy 408.118807 -327.525063) (xy 408.089341 -327.570913)
			(xy 408.05365 -327.612104) (xy 408.012459 -327.647795) (xy 407.966609 -327.677261) (xy 407.917032 -327.699903)
			(xy 407.864737 -327.715258) (xy 407.810789 -327.723014) (xy 407.756287 -327.723014) (xy 407.702339 -327.715258)
			(xy 407.650044 -327.699903) (xy 407.600467 -327.677261) (xy 407.554617 -327.647795) (xy 407.513426 -327.612104)
			(xy 407.477735 -327.570913) (xy 407.448269 -327.525063) (xy 407.425627 -327.475486) (xy 407.410272 -327.423191)
			(xy 407.402516 -327.369243) (xy 407.40203 -327.341992) (xy 407.40203 -327.341738) (xy 407.402477 -327.316312)
			(xy 407.409287 -327.265918) (xy 407.422725 -327.216874) (xy 407.442554 -327.170046) (xy 407.468422 -327.126265)
			(xy 407.483818 -327.106026) (xy 407.488819 -327.098998) (xy 407.494272 -327.082645) (xy 407.494486 -327.074022)
			(xy 407.494486 -327.04405) (xy 407.494016 -327.03532) (xy 407.487908 -327.018953) (xy 407.482548 -327.012046)
			(xy 407.464053 -326.989155) (xy 407.431896 -326.939864) (xy 407.40564 -326.887193) (xy 407.385636 -326.831845)
			(xy 407.372151 -326.774558) (xy 407.365364 -326.716098) (xy 407.364946 -326.686672) (xy 405.983961 -326.686672)
			(xy 405.984289 -326.689466) (xy 405.98471 -326.719184) (xy 405.984208 -326.751145) (xy 405.976197 -326.814563)
			(xy 405.9603 -326.876477) (xy 405.936768 -326.93591) (xy 405.905974 -326.991925) (xy 405.868401 -327.04364)
			(xy 405.824644 -327.090237) (xy 405.775391 -327.130982) (xy 405.72142 -327.165233) (xy 405.663581 -327.19245)
			(xy 405.602788 -327.212203) (xy 405.539998 -327.224181) (xy 405.476202 -327.228195) (xy 405.412406 -327.224181)
			(xy 405.349616 -327.212203) (xy 405.288823 -327.19245) (xy 405.230984 -327.165233) (xy 405.177013 -327.130982)
			(xy 405.12776 -327.090237) (xy 405.084003 -327.04364) (xy 405.04643 -326.991925) (xy 405.015636 -326.93591)
			(xy 404.992104 -326.876477) (xy 404.976207 -326.814563) (xy 404.968196 -326.751145) (xy 404.967694 -326.719184)
			(xy 404.968108 -326.689472) (xy 404.975045 -326.630455) (xy 404.988811 -326.572647) (xy 405.009218 -326.516838)
			(xy 405.035988 -326.463786) (xy 405.052022 -326.438768) (xy 405.056975 -326.430588) (xy 405.060998 -326.41191)
			(xy 405.057866 -326.393063) (xy 405.053292 -326.384666) (xy 404.99919 -326.29348) (xy 404.973028 -326.280272)
			(xy 404.95855 -326.281542) (xy 404.914608 -326.28332) (xy 404.882646 -326.282816) (xy 404.819226 -326.274805)
			(xy 404.75731 -326.258908) (xy 404.697875 -326.235377) (xy 404.641858 -326.204582) (xy 404.590142 -326.167009)
			(xy 404.543543 -326.123251) (xy 404.502796 -326.073997) (xy 404.468544 -326.020024) (xy 404.441326 -325.962184)
			(xy 404.421573 -325.901389) (xy 404.409594 -325.838598) (xy 404.40558 -325.7748) (xy 401.460015 -325.7748)
			(xy 401.471358 -325.803447) (xy 401.487255 -325.865361) (xy 401.495266 -325.928779) (xy 401.495768 -325.96074)
			(xy 401.495266 -325.992701) (xy 401.487255 -326.056119) (xy 401.471358 -326.118033) (xy 401.447826 -326.177466)
			(xy 401.417032 -326.233481) (xy 401.379459 -326.285196) (xy 401.335702 -326.331793) (xy 401.286449 -326.372538)
			(xy 401.232478 -326.406789) (xy 401.174639 -326.434006) (xy 401.1351 -326.446853) (xy 402.155654 -326.446853)
			(xy 402.155654 -326.382931) (xy 402.163665 -326.319513) (xy 402.179562 -326.257599) (xy 402.203094 -326.198166)
			(xy 402.233888 -326.142151) (xy 402.271461 -326.090436) (xy 402.315218 -326.043839) (xy 402.364471 -326.003094)
			(xy 402.418442 -325.968843) (xy 402.476281 -325.941626) (xy 402.537074 -325.921873) (xy 402.599864 -325.909895)
			(xy 402.66366 -325.905882) (xy 402.727456 -325.909895) (xy 402.790246 -325.921873) (xy 402.851039 -325.941626)
			(xy 402.908878 -325.968843) (xy 402.962849 -326.003094) (xy 403.012102 -326.043839) (xy 403.055859 -326.090436)
			(xy 403.093432 -326.142151) (xy 403.124226 -326.198166) (xy 403.147758 -326.257599) (xy 403.163655 -326.319513)
			(xy 403.171666 -326.382931) (xy 403.172168 -326.414892) (xy 403.171666 -326.446853) (xy 403.163655 -326.510271)
			(xy 403.147758 -326.572185) (xy 403.124226 -326.631618) (xy 403.093432 -326.687633) (xy 403.055859 -326.739348)
			(xy 403.012102 -326.785945) (xy 402.962849 -326.82669) (xy 402.908878 -326.860941) (xy 402.851039 -326.888158)
			(xy 402.790246 -326.907911) (xy 402.727456 -326.919889) (xy 402.66366 -326.923903) (xy 402.599864 -326.919889)
			(xy 402.537074 -326.907911) (xy 402.476281 -326.888158) (xy 402.418442 -326.860941) (xy 402.364471 -326.82669)
			(xy 402.315218 -326.785945) (xy 402.271461 -326.739348) (xy 402.233888 -326.687633) (xy 402.203094 -326.631618)
			(xy 402.179562 -326.572185) (xy 402.163665 -326.510271) (xy 402.155654 -326.446853) (xy 401.1351 -326.446853)
			(xy 401.113846 -326.453759) (xy 401.051056 -326.465737) (xy 400.98726 -326.469751) (xy 400.923464 -326.465737)
			(xy 400.860674 -326.453759) (xy 400.799881 -326.434006) (xy 400.742042 -326.406789) (xy 400.688071 -326.372538)
			(xy 400.638818 -326.331793) (xy 400.595061 -326.285196) (xy 400.557488 -326.233481) (xy 400.526694 -326.177466)
			(xy 400.503162 -326.118033) (xy 400.487265 -326.056119) (xy 400.479254 -325.992701) (xy 400.346357 -325.992701)
			(xy 400.338667 -326.053579) (xy 400.32277 -326.115493) (xy 400.299238 -326.174926) (xy 400.268444 -326.230941)
			(xy 400.230871 -326.282656) (xy 400.187114 -326.329253) (xy 400.137861 -326.369998) (xy 400.08389 -326.404249)
			(xy 400.026051 -326.431466) (xy 399.965258 -326.451219) (xy 399.902468 -326.463197) (xy 399.838672 -326.467211)
			(xy 399.774876 -326.463197) (xy 399.712086 -326.451219) (xy 399.651293 -326.431466) (xy 399.593454 -326.404249)
			(xy 399.539483 -326.369998) (xy 399.49023 -326.329253) (xy 399.446473 -326.282656) (xy 399.4089 -326.230941)
			(xy 399.378106 -326.174926) (xy 399.354574 -326.115493) (xy 399.338677 -326.053579) (xy 399.330666 -325.990161)
			(xy 398.82099 -325.990161) (xy 398.821148 -325.99884) (xy 398.820639 -326.026726) (xy 398.812519 -326.081902)
			(xy 398.796451 -326.135309) (xy 398.772779 -326.185806) (xy 398.742006 -326.232319) (xy 398.704789 -326.273856)
			(xy 398.661921 -326.309531) (xy 398.614315 -326.338585) (xy 398.562986 -326.360397) (xy 398.509029 -326.374503)
			(xy 398.453592 -326.380603) (xy 398.397858 -326.378566) (xy 398.343015 -326.368436) (xy 398.290231 -326.350429)
			(xy 398.240631 -326.324928) (xy 398.195273 -326.292477) (xy 398.155124 -326.253768) (xy 398.121038 -326.209625)
			(xy 398.093742 -326.16099) (xy 398.073819 -326.108899) (xy 398.061693 -326.054462) (xy 398.057622 -325.99884)
			(xy 394.92849 -325.99884) (xy 394.949808 -326.016476) (xy 394.993587 -326.063096) (xy 395.031179 -326.114836)
			(xy 395.061989 -326.17088) (xy 395.085532 -326.230342) (xy 395.101437 -326.292287) (xy 395.109452 -326.355737)
			(xy 395.109954 -326.387714) (xy 395.109466 -326.419797) (xy 395.101399 -326.483453) (xy 395.085395 -326.54559)
			(xy 395.061707 -326.605223) (xy 395.030712 -326.661406) (xy 394.992901 -326.713248) (xy 394.948874 -326.759925)
			(xy 394.899329 -326.800698) (xy 394.872464 -326.818244) (xy 394.861325 -326.825756) (xy 394.843133 -326.845514)
			(xy 394.830723 -326.869333) (xy 394.824951 -326.895563) (xy 394.826219 -326.922391) (xy 394.834437 -326.94796)
			(xy 394.849038 -326.970502) (xy 394.85047 -326.971871) (xy 395.523968 -326.971871) (xy 395.523968 -326.907949)
			(xy 395.531979 -326.844531) (xy 395.547876 -326.782617) (xy 395.571408 -326.723184) (xy 395.602202 -326.667169)
			(xy 395.639775 -326.615454) (xy 395.683532 -326.568857) (xy 395.732785 -326.528112) (xy 395.786756 -326.493861)
			(xy 395.844595 -326.466644) (xy 395.905388 -326.446891) (xy 395.968178 -326.434913) (xy 396.031974 -326.4309)
			(xy 396.09577 -326.434913) (xy 396.15856 -326.446891) (xy 396.219353 -326.466644) (xy 396.277192 -326.493861)
			(xy 396.331163 -326.528112) (xy 396.380416 -326.568857) (xy 396.424173 -326.615454) (xy 396.461746 -326.667169)
			(xy 396.49254 -326.723184) (xy 396.516072 -326.782617) (xy 396.531969 -326.844531) (xy 396.53998 -326.907949)
			(xy 396.540482 -326.93991) (xy 396.53998 -326.971871) (xy 396.531969 -327.035289) (xy 396.516072 -327.097203)
			(xy 396.49254 -327.156636) (xy 396.461746 -327.212651) (xy 396.424173 -327.264366) (xy 396.380416 -327.310963)
			(xy 396.331163 -327.351708) (xy 396.277192 -327.385959) (xy 396.219353 -327.413176) (xy 396.15856 -327.432929)
			(xy 396.09577 -327.444907) (xy 396.031974 -327.448921) (xy 395.968178 -327.444907) (xy 395.905388 -327.432929)
			(xy 395.844595 -327.413176) (xy 395.786756 -327.385959) (xy 395.732785 -327.351708) (xy 395.683532 -327.310963)
			(xy 395.639775 -327.264366) (xy 395.602202 -327.212651) (xy 395.571408 -327.156636) (xy 395.547876 -327.097203)
			(xy 395.531979 -327.035289) (xy 395.523968 -326.971871) (xy 394.85047 -326.971871) (xy 394.858748 -326.979788)
			(xy 394.881214 -327.000499) (xy 394.921539 -327.046408) (xy 394.956071 -327.09682) (xy 394.984312 -327.151007)
			(xy 395.005855 -327.208188) (xy 395.02039 -327.267539) (xy 395.027706 -327.328204) (xy 395.028166 -327.358756)
			(xy 395.027723 -327.389505) (xy 395.020315 -327.450556) (xy 395.005602 -327.510269) (xy 394.983798 -327.567772)
			(xy 394.955222 -327.622228) (xy 394.92029 -327.672842) (xy 394.879511 -327.718877) (xy 394.83348 -327.75966)
			(xy 394.782869 -327.794597) (xy 394.728416 -327.823178) (xy 394.670914 -327.844988) (xy 394.611203 -327.859706)
			(xy 394.550153 -327.86712) (xy 394.519404 -327.867518) (xy 394.518896 -327.867518) (xy 394.490188 -327.867112)
			(xy 394.433141 -327.860622) (xy 394.377187 -327.847748) (xy 394.349986 -327.838562) (xy 394.335669 -327.834075)
			(xy 394.305711 -327.832742) (xy 394.276658 -327.84017) (xy 394.251016 -327.855719) (xy 394.230997 -327.878046)
			(xy 394.218329 -327.905227) (xy 394.214104 -327.934916) (xy 394.215874 -327.949814) (xy 394.216382 -327.9521)
			(xy 394.277332 -328.258889) (xy 394.846804 -328.258889) (xy 394.846804 -328.194967) (xy 394.854815 -328.131549)
			(xy 394.870712 -328.069635) (xy 394.894244 -328.010202) (xy 394.925038 -327.954187) (xy 394.962611 -327.902472)
			(xy 395.006368 -327.855875) (xy 395.055621 -327.81513) (xy 395.109592 -327.780879) (xy 395.167431 -327.753662)
			(xy 395.228224 -327.733909) (xy 395.291014 -327.721931) (xy 395.35481 -327.717918) (xy 395.418606 -327.721931)
			(xy 395.481396 -327.733909) (xy 395.542189 -327.753662) (xy 395.600028 -327.780879) (xy 395.653999 -327.81513)
			(xy 395.703252 -327.855875) (xy 395.747009 -327.902472) (xy 395.784582 -327.954187) (xy 395.815376 -328.010202)
			(xy 395.838908 -328.069635) (xy 395.854805 -328.131549) (xy 395.862816 -328.194967) (xy 395.863318 -328.226928)
			(xy 395.862816 -328.258889) (xy 395.854805 -328.322307) (xy 395.838908 -328.384221) (xy 395.815376 -328.443654)
			(xy 395.784582 -328.499669) (xy 395.758706 -328.535284) (xy 397.509492 -328.535284) (xy 397.509949 -328.504662)
			(xy 397.517318 -328.443862) (xy 397.531934 -328.384387) (xy 397.553587 -328.327098) (xy 397.581963 -328.272824)
			(xy 397.616651 -328.22235) (xy 397.657149 -328.176406) (xy 397.702871 -328.135659) (xy 397.753156 -328.100697)
			(xy 397.780002 -328.085958) (xy 397.788638 -328.081386) (xy 397.800576 -328.067416) (xy 397.830548 -327.985374)
			(xy 397.83004 -327.966832) (xy 397.826484 -327.957942) (xy 397.814569 -327.927392) (xy 397.79783 -327.86399)
			(xy 397.789399 -327.798959) (xy 397.788892 -327.766172) (xy 397.789394 -327.734211) (xy 397.797405 -327.670793)
			(xy 397.813302 -327.608879) (xy 397.836834 -327.549446) (xy 397.867628 -327.493431) (xy 397.905201 -327.441716)
			(xy 397.948958 -327.395119) (xy 397.998211 -327.354374) (xy 398.052182 -327.320123) (xy 398.110021 -327.292906)
			(xy 398.170814 -327.273153) (xy 398.233604 -327.261175) (xy 398.2974 -327.257162) (xy 398.361196 -327.261175)
			(xy 398.423986 -327.273153) (xy 398.484779 -327.292906) (xy 398.542618 -327.320123) (xy 398.596589 -327.354374)
			(xy 398.645842 -327.395119) (xy 398.689599 -327.441716) (xy 398.727172 -327.493431) (xy 398.757966 -327.549446)
			(xy 398.781498 -327.608879) (xy 398.788102 -327.6346) (xy 400.943089 -327.6346) (xy 400.947103 -327.570806)
			(xy 400.95908 -327.508017) (xy 400.978832 -327.447225) (xy 401.006048 -327.389388) (xy 401.040297 -327.335418)
			(xy 401.081041 -327.286165) (xy 401.127636 -327.242408) (xy 401.179348 -327.204835) (xy 401.235361 -327.17404)
			(xy 401.294792 -327.150507) (xy 401.356704 -327.134609) (xy 401.42012 -327.126595) (xy 401.45208 -327.126092)
			(xy 401.452588 -327.126092) (xy 401.48317 -327.126576) (xy 401.543886 -327.133964) (xy 401.603277 -327.148586)
			(xy 401.660483 -327.170231) (xy 401.687792 -327.184004) (xy 401.69588 -327.187765) (xy 401.713549 -327.190107)
			(xy 401.722336 -327.188576) (xy 401.752054 -327.181718) (xy 401.760618 -327.179451) (xy 401.775557 -327.169953)
			(xy 401.781264 -327.163176) (xy 401.799427 -327.140384) (xy 401.841495 -327.100053) (xy 401.889213 -327.066598)
			(xy 401.941468 -327.040798) (xy 401.997042 -327.023256) (xy 402.054639 -327.014379) (xy 402.083778 -327.013824)
			(xy 402.111034 -327.014221) (xy 402.164992 -327.021977) (xy 402.217297 -327.037332) (xy 402.266884 -327.059975)
			(xy 402.312744 -327.089445) (xy 402.353943 -327.125142) (xy 402.389642 -327.166338) (xy 402.419114 -327.212197)
			(xy 402.44176 -327.261782) (xy 402.457119 -327.314086) (xy 402.464877 -327.368044) (xy 402.464877 -327.410529)
			(xy 403.607264 -327.410529) (xy 403.607264 -327.346607) (xy 403.615275 -327.283189) (xy 403.631172 -327.221275)
			(xy 403.654704 -327.161842) (xy 403.685498 -327.105827) (xy 403.723071 -327.054112) (xy 403.766828 -327.007515)
			(xy 403.816081 -326.96677) (xy 403.870052 -326.932519) (xy 403.927891 -326.905302) (xy 403.988684 -326.885549)
			(xy 404.051474 -326.873571) (xy 404.11527 -326.869558) (xy 404.179066 -326.873571) (xy 404.241856 -326.885549)
			(xy 404.302649 -326.905302) (xy 404.360488 -326.932519) (xy 404.414459 -326.96677) (xy 404.463712 -327.007515)
			(xy 404.507469 -327.054112) (xy 404.545042 -327.105827) (xy 404.575836 -327.161842) (xy 404.599368 -327.221275)
			(xy 404.615265 -327.283189) (xy 404.623276 -327.346607) (xy 404.623778 -327.378568) (xy 404.623276 -327.410529)
			(xy 404.615265 -327.473947) (xy 404.599368 -327.535861) (xy 404.575836 -327.595294) (xy 404.545042 -327.651309)
			(xy 404.507469 -327.703024) (xy 404.463712 -327.749621) (xy 404.414459 -327.790366) (xy 404.360488 -327.824617)
			(xy 404.302649 -327.851834) (xy 404.241856 -327.871587) (xy 404.179066 -327.883565) (xy 404.11527 -327.887579)
			(xy 404.051474 -327.883565) (xy 403.988684 -327.871587) (xy 403.927891 -327.851834) (xy 403.870052 -327.824617)
			(xy 403.816081 -327.790366) (xy 403.766828 -327.749621) (xy 403.723071 -327.703024) (xy 403.685498 -327.651309)
			(xy 403.654704 -327.595294) (xy 403.631172 -327.535861) (xy 403.615275 -327.473947) (xy 403.607264 -327.410529)
			(xy 402.464877 -327.410529) (xy 402.464877 -327.422556) (xy 402.457119 -327.476514) (xy 402.44176 -327.528818)
			(xy 402.419114 -327.578403) (xy 402.389642 -327.624262) (xy 402.353943 -327.665458) (xy 402.312744 -327.701155)
			(xy 402.266884 -327.730625) (xy 402.217297 -327.753268) (xy 402.164992 -327.768623) (xy 402.111034 -327.776379)
			(xy 402.083778 -327.77684) (xy 402.065435 -327.776599) (xy 402.028922 -327.773042) (xy 402.01088 -327.769728)
			(xy 402.002094 -327.768427) (xy 401.984558 -327.771142) (xy 401.97659 -327.775062) (xy 401.950174 -327.789794)
			(xy 401.942584 -327.794432) (xy 401.930887 -327.807811) (xy 401.927314 -327.815956) (xy 401.915927 -327.844451)
			(xy 401.88729 -327.898723) (xy 401.852333 -327.949155) (xy 401.811562 -327.995017) (xy 401.76557 -328.03564)
			(xy 401.715025 -328.070436) (xy 401.660662 -328.098899) (xy 401.603269 -328.120615) (xy 401.54368 -328.135269)
			(xy 401.482762 -328.142649) (xy 401.45208 -328.143108) (xy 401.42012 -328.142605) (xy 401.356704 -328.134591)
			(xy 401.294792 -328.118693) (xy 401.235361 -328.09516) (xy 401.179348 -328.064365) (xy 401.127636 -328.026792)
			(xy 401.081041 -327.983035) (xy 401.040297 -327.933782) (xy 401.006048 -327.879812) (xy 400.978832 -327.821975)
			(xy 400.95908 -327.761183) (xy 400.947103 -327.698394) (xy 400.943089 -327.6346) (xy 398.788102 -327.6346)
			(xy 398.797395 -327.670793) (xy 398.805406 -327.734211) (xy 398.805908 -327.766172) (xy 398.805414 -327.796793)
			(xy 398.798051 -327.857591) (xy 398.78344 -327.917065) (xy 398.761792 -327.974354) (xy 398.733421 -328.028629)
			(xy 398.698737 -328.079103) (xy 398.658242 -328.125047) (xy 398.612524 -328.165795) (xy 398.562242 -328.200758)
			(xy 398.535398 -328.215498) (xy 398.526762 -328.22007) (xy 398.514824 -328.23404) (xy 398.484852 -328.316082)
			(xy 398.48536 -328.334624) (xy 398.488916 -328.343514) (xy 398.500818 -328.374069) (xy 398.517562 -328.437469)
			(xy 398.525999 -328.502497) (xy 398.526508 -328.535284) (xy 398.526006 -328.567245) (xy 398.517995 -328.630663)
			(xy 398.502098 -328.692577) (xy 398.478566 -328.75201) (xy 398.447772 -328.808025) (xy 398.410199 -328.85974)
			(xy 398.366442 -328.906337) (xy 398.317189 -328.947082) (xy 398.263218 -328.981333) (xy 398.205379 -329.00855)
			(xy 398.144586 -329.028303) (xy 398.081796 -329.040281) (xy 398.018 -329.044295) (xy 397.954204 -329.040281)
			(xy 397.891414 -329.028303) (xy 397.830621 -329.00855) (xy 397.772782 -328.981333) (xy 397.718811 -328.947082)
			(xy 397.669558 -328.906337) (xy 397.625801 -328.85974) (xy 397.588228 -328.808025) (xy 397.557434 -328.75201)
			(xy 397.533902 -328.692577) (xy 397.518005 -328.630663) (xy 397.509994 -328.567245) (xy 397.509492 -328.535284)
			(xy 395.758706 -328.535284) (xy 395.747009 -328.551384) (xy 395.703252 -328.597981) (xy 395.653999 -328.638726)
			(xy 395.600028 -328.672977) (xy 395.542189 -328.700194) (xy 395.481396 -328.719947) (xy 395.418606 -328.731925)
			(xy 395.35481 -328.735939) (xy 395.291014 -328.731925) (xy 395.228224 -328.719947) (xy 395.167431 -328.700194)
			(xy 395.109592 -328.672977) (xy 395.055621 -328.638726) (xy 395.006368 -328.597981) (xy 394.962611 -328.551384)
			(xy 394.925038 -328.499669) (xy 394.894244 -328.443654) (xy 394.870712 -328.384221) (xy 394.854815 -328.322307)
			(xy 394.846804 -328.258889) (xy 394.277332 -328.258889) (xy 394.353034 -328.639932) (xy 394.353542 -328.64171)
			(xy 394.584603 -329.320101) (xy 399.430234 -329.320101) (xy 399.430234 -329.256179) (xy 399.438245 -329.192761)
			(xy 399.454142 -329.130847) (xy 399.477674 -329.071414) (xy 399.508468 -329.015399) (xy 399.546041 -328.963684)
			(xy 399.589798 -328.917087) (xy 399.639051 -328.876342) (xy 399.693022 -328.842091) (xy 399.750861 -328.814874)
			(xy 399.811654 -328.795121) (xy 399.874444 -328.783143) (xy 399.93824 -328.77913) (xy 400.002036 -328.783143)
			(xy 400.064826 -328.795121) (xy 400.125619 -328.814874) (xy 400.183458 -328.842091) (xy 400.237429 -328.876342)
			(xy 400.286682 -328.917087) (xy 400.330439 -328.963684) (xy 400.368012 -329.015399) (xy 400.398806 -329.071414)
			(xy 400.422338 -329.130847) (xy 400.438235 -329.192761) (xy 400.444374 -329.241361) (xy 400.814534 -329.241361)
			(xy 400.814534 -329.177439) (xy 400.822545 -329.114021) (xy 400.838442 -329.052107) (xy 400.861974 -328.992674)
			(xy 400.892768 -328.936659) (xy 400.930341 -328.884944) (xy 400.974098 -328.838347) (xy 401.023351 -328.797602)
			(xy 401.077322 -328.763351) (xy 401.135161 -328.736134) (xy 401.195954 -328.716381) (xy 401.258744 -328.704403)
			(xy 401.32254 -328.70039) (xy 401.386336 -328.704403) (xy 401.449126 -328.716381) (xy 401.509919 -328.736134)
			(xy 401.567758 -328.763351) (xy 401.621729 -328.797602) (xy 401.670982 -328.838347) (xy 401.714739 -328.884944)
			(xy 401.752312 -328.936659) (xy 401.783106 -328.992674) (xy 401.806638 -329.052107) (xy 401.814666 -329.083373)
			(xy 402.378412 -329.083373) (xy 402.378412 -329.019451) (xy 402.386423 -328.956033) (xy 402.40232 -328.894119)
			(xy 402.425852 -328.834686) (xy 402.456646 -328.778671) (xy 402.494219 -328.726956) (xy 402.537976 -328.680359)
			(xy 402.587229 -328.639614) (xy 402.6412 -328.605363) (xy 402.699039 -328.578146) (xy 402.759832 -328.558393)
			(xy 402.822622 -328.546415) (xy 402.886418 -328.542402) (xy 402.950214 -328.546415) (xy 403.013004 -328.558393)
			(xy 403.073797 -328.578146) (xy 403.131636 -328.605363) (xy 403.185607 -328.639614) (xy 403.23486 -328.680359)
			(xy 403.278617 -328.726956) (xy 403.31619 -328.778671) (xy 403.346984 -328.834686) (xy 403.370516 -328.894119)
			(xy 403.386413 -328.956033) (xy 403.392365 -329.003152) (xy 404.630888 -329.003152) (xy 404.634959 -328.94753)
			(xy 404.647085 -328.893093) (xy 404.667008 -328.841002) (xy 404.694304 -328.792367) (xy 404.72839 -328.748224)
			(xy 404.768539 -328.709515) (xy 404.813897 -328.677064) (xy 404.863497 -328.651563) (xy 404.916281 -328.633556)
			(xy 404.971124 -328.623426) (xy 405.026858 -328.621389) (xy 405.082295 -328.627489) (xy 405.136252 -328.641595)
			(xy 405.187581 -328.663407) (xy 405.235187 -328.692461) (xy 405.278055 -328.728136) (xy 405.315272 -328.769673)
			(xy 405.346045 -328.816186) (xy 405.366158 -328.859091) (xy 407.253434 -328.859091) (xy 407.253434 -328.795169)
			(xy 407.261445 -328.731751) (xy 407.277342 -328.669837) (xy 407.300874 -328.610404) (xy 407.331668 -328.554389)
			(xy 407.369241 -328.502674) (xy 407.412998 -328.456077) (xy 407.462251 -328.415332) (xy 407.516222 -328.381081)
			(xy 407.574061 -328.353864) (xy 407.634854 -328.334111) (xy 407.697644 -328.322133) (xy 407.76144 -328.31812)
			(xy 407.825236 -328.322133) (xy 407.888026 -328.334111) (xy 407.948819 -328.353864) (xy 408.006658 -328.381081)
			(xy 408.060629 -328.415332) (xy 408.109882 -328.456077) (xy 408.153639 -328.502674) (xy 408.191212 -328.554389)
			(xy 408.222006 -328.610404) (xy 408.245538 -328.669837) (xy 408.261435 -328.731751) (xy 408.269446 -328.795169)
			(xy 408.269948 -328.82713) (xy 408.269446 -328.859091) (xy 408.261435 -328.922509) (xy 408.245538 -328.984423)
			(xy 408.222006 -329.043856) (xy 408.191212 -329.099871) (xy 408.153639 -329.151586) (xy 408.109882 -329.198183)
			(xy 408.060629 -329.238928) (xy 408.006658 -329.273179) (xy 407.948819 -329.300396) (xy 407.888026 -329.320149)
			(xy 407.825236 -329.332127) (xy 407.76144 -329.336141) (xy 407.697644 -329.332127) (xy 407.634854 -329.320149)
			(xy 407.574061 -329.300396) (xy 407.516222 -329.273179) (xy 407.462251 -329.238928) (xy 407.412998 -329.198183)
			(xy 407.369241 -329.151586) (xy 407.331668 -329.099871) (xy 407.300874 -329.043856) (xy 407.277342 -328.984423)
			(xy 407.261445 -328.922509) (xy 407.253434 -328.859091) (xy 405.366158 -328.859091) (xy 405.369717 -328.866683)
			(xy 405.385785 -328.92009) (xy 405.393905 -328.975266) (xy 405.394414 -329.003152) (xy 405.393905 -329.031038)
			(xy 405.385785 -329.086214) (xy 405.369717 -329.139621) (xy 405.346045 -329.190118) (xy 405.315272 -329.236631)
			(xy 405.278055 -329.278168) (xy 405.235187 -329.313843) (xy 405.187581 -329.342897) (xy 405.136252 -329.364709)
			(xy 405.082295 -329.378815) (xy 405.026858 -329.384915) (xy 404.971124 -329.382878) (xy 404.916281 -329.372748)
			(xy 404.863497 -329.354741) (xy 404.813897 -329.32924) (xy 404.768539 -329.296789) (xy 404.72839 -329.25808)
			(xy 404.694304 -329.213937) (xy 404.667008 -329.165302) (xy 404.647085 -329.113211) (xy 404.634959 -329.058774)
			(xy 404.630888 -329.003152) (xy 403.392365 -329.003152) (xy 403.394424 -329.019451) (xy 403.394926 -329.051412)
			(xy 403.394424 -329.083373) (xy 403.386413 -329.146791) (xy 403.370516 -329.208705) (xy 403.346984 -329.268138)
			(xy 403.31619 -329.324153) (xy 403.278617 -329.375868) (xy 403.23486 -329.422465) (xy 403.185607 -329.46321)
			(xy 403.131636 -329.497461) (xy 403.073797 -329.524678) (xy 403.013004 -329.544431) (xy 402.950214 -329.556409)
			(xy 402.886418 -329.560423) (xy 402.822622 -329.556409) (xy 402.759832 -329.544431) (xy 402.699039 -329.524678)
			(xy 402.6412 -329.497461) (xy 402.587229 -329.46321) (xy 402.537976 -329.422465) (xy 402.494219 -329.375868)
			(xy 402.456646 -329.324153) (xy 402.425852 -329.268138) (xy 402.40232 -329.208705) (xy 402.386423 -329.146791)
			(xy 402.378412 -329.083373) (xy 401.814666 -329.083373) (xy 401.822535 -329.114021) (xy 401.830546 -329.177439)
			(xy 401.831048 -329.2094) (xy 401.830546 -329.241361) (xy 401.822535 -329.304779) (xy 401.806638 -329.366693)
			(xy 401.783106 -329.426126) (xy 401.752312 -329.482141) (xy 401.714739 -329.533856) (xy 401.670982 -329.580453)
			(xy 401.621729 -329.621198) (xy 401.567758 -329.655449) (xy 401.509919 -329.682666) (xy 401.449126 -329.702419)
			(xy 401.386336 -329.714397) (xy 401.32254 -329.718411) (xy 401.258744 -329.714397) (xy 401.195954 -329.702419)
			(xy 401.135161 -329.682666) (xy 401.077322 -329.655449) (xy 401.023351 -329.621198) (xy 400.974098 -329.580453)
			(xy 400.930341 -329.533856) (xy 400.892768 -329.482141) (xy 400.861974 -329.426126) (xy 400.838442 -329.366693)
			(xy 400.822545 -329.304779) (xy 400.814534 -329.241361) (xy 400.444374 -329.241361) (xy 400.446246 -329.256179)
			(xy 400.446748 -329.28814) (xy 400.446246 -329.320101) (xy 400.438235 -329.383519) (xy 400.422338 -329.445433)
			(xy 400.398806 -329.504866) (xy 400.368012 -329.560881) (xy 400.330439 -329.612596) (xy 400.286682 -329.659193)
			(xy 400.237429 -329.699938) (xy 400.183458 -329.734189) (xy 400.125619 -329.761406) (xy 400.064826 -329.781159)
			(xy 400.002036 -329.793137) (xy 399.93824 -329.797151) (xy 399.874444 -329.793137) (xy 399.811654 -329.781159)
			(xy 399.750861 -329.761406) (xy 399.693022 -329.734189) (xy 399.639051 -329.699938) (xy 399.589798 -329.659193)
			(xy 399.546041 -329.612596) (xy 399.508468 -329.560881) (xy 399.477674 -329.504866) (xy 399.454142 -329.445433)
			(xy 399.438245 -329.383519) (xy 399.430234 -329.320101) (xy 394.584603 -329.320101) (xy 394.928852 -330.33081)
			(xy 394.930732 -330.335996) (xy 394.936372 -330.345474) (xy 394.940028 -330.349606) (xy 394.947394 -330.357226)
			(xy 394.957808 -330.361544) (xy 394.958062 -330.361544) (xy 394.973989 -330.368178) (xy 395.005004 -330.383305)
			(xy 395.020038 -330.39177) (xy 395.026388 -330.39177) (xy 395.05712 -330.392233) (xy 395.118136 -330.399641)
			(xy 395.177814 -330.414348) (xy 395.235284 -330.436142) (xy 395.289709 -330.464704) (xy 395.340294 -330.499618)
			(xy 395.386301 -330.540375) (xy 395.427061 -330.586379) (xy 395.461978 -330.636962) (xy 395.490544 -330.691385)
			(xy 395.512342 -330.748853) (xy 395.527053 -330.808531) (xy 395.534465 -330.869546) (xy 395.534896 -330.900278)
			(xy 395.53441 -330.93161) (xy 395.526703 -330.9938) (xy 395.524479 -331.00264) (xy 398.885156 -331.00264)
			(xy 398.885658 -330.970679) (xy 398.893669 -330.907261) (xy 398.909566 -330.845347) (xy 398.933098 -330.785914)
			(xy 398.963892 -330.729899) (xy 399.001465 -330.678184) (xy 399.045222 -330.631587) (xy 399.094475 -330.590842)
			(xy 399.148446 -330.556591) (xy 399.206285 -330.529374) (xy 399.267078 -330.509621) (xy 399.329868 -330.497643)
			(xy 399.393664 -330.49363) (xy 399.45746 -330.497643) (xy 399.52025 -330.509621) (xy 399.581043 -330.529374)
			(xy 399.638882 -330.556591) (xy 399.692853 -330.590842) (xy 399.742106 -330.631587) (xy 399.785863 -330.678184)
			(xy 399.823436 -330.729899) (xy 399.85423 -330.785914) (xy 399.877762 -330.845347) (xy 399.893659 -330.907261)
			(xy 399.90167 -330.970679) (xy 399.902172 -331.00264) (xy 399.901716 -331.032835) (xy 399.894535 -331.092797)
			(xy 399.880304 -331.151486) (xy 399.870168 -331.179932) (xy 399.865342 -331.192632) (xy 399.86966 -331.219048)
			(xy 399.933668 -331.297534) (xy 399.939459 -331.304211) (xy 399.954555 -331.31338) (xy 399.971878 -331.316831)
			(xy 399.980658 -331.315822) (xy 399.99928 -331.313206) (xy 400.036784 -331.310412) (xy 400.055588 -331.310234)
			(xy 400.056096 -331.310234) (xy 400.088061 -331.310631) (xy 400.151487 -331.318643) (xy 400.213409 -331.334541)
			(xy 400.240548 -331.345286) (xy 402.47697 -331.345286) (xy 402.477443 -331.314556) (xy 402.484853 -331.253543)
			(xy 402.499562 -331.193868) (xy 402.521357 -331.136401) (xy 402.54992 -331.081981) (xy 402.584833 -331.031399)
			(xy 402.625589 -330.985395) (xy 402.671593 -330.944638) (xy 402.722174 -330.909724) (xy 402.776594 -330.88116)
			(xy 402.834061 -330.859364) (xy 402.893735 -330.844654) (xy 402.954748 -330.837243) (xy 402.985478 -330.836778)
			(xy 403.017697 -330.837294) (xy 403.08162 -330.845432) (xy 403.144002 -330.861581) (xy 403.203844 -330.885482)
			(xy 403.260187 -330.916751) (xy 403.312128 -330.954889) (xy 403.358834 -330.999282) (xy 403.399558 -331.049221)
			(xy 403.417024 -331.0763) (xy 403.422358 -331.084682) (xy 403.43836 -331.096366) (xy 403.527768 -331.117448)
			(xy 403.547326 -331.1144) (xy 403.555962 -331.109066) (xy 403.58592 -331.091461) (xy 403.64964 -331.063745)
			(xy 403.716542 -331.044967) (xy 403.785379 -331.035477) (xy 403.820122 -331.034898) (xy 403.82063 -331.034898)
			(xy 403.851362 -331.035328) (xy 403.912377 -331.04274) (xy 403.933308 -331.0479) (xy 408.08852 -331.0479)
			(xy 408.092535 -330.984095) (xy 408.104514 -330.921296) (xy 408.124271 -330.860494) (xy 408.151491 -330.802647)
			(xy 408.185748 -330.748668) (xy 408.2265 -330.699408) (xy 408.273104 -330.655645) (xy 408.324826 -330.618067)
			(xy 408.38085 -330.587269) (xy 408.440292 -330.563735) (xy 408.502215 -330.547836) (xy 408.565642 -330.539825)
			(xy 408.597608 -330.539344) (xy 409.243784 -330.539344) (xy 409.253854 -330.538925) (xy 409.272453 -330.531201)
			(xy 409.279852 -330.524358) (xy 410.134562 -329.669902) (xy 410.141388 -329.662491) (xy 410.149117 -329.6439)
			(xy 410.149548 -329.633834) (xy 410.149548 -323.338952) (xy 410.150079 -323.305672) (xy 410.158751 -323.23968)
			(xy 410.175967 -323.175386) (xy 410.201431 -323.11389) (xy 410.234708 -323.056246) (xy 410.275227 -323.003441)
			(xy 410.298392 -322.979542) (xy 411.578552 -321.699382) (xy 411.602462 -321.676215) (xy 411.655251 -321.635651)
			(xy 411.712885 -321.602326) (xy 411.774377 -321.576812) (xy 411.838674 -321.559545) (xy 411.904675 -321.550821)
			(xy 411.937962 -321.550284) (xy 415.779458 -321.550284) (xy 415.812744 -321.55082) (xy 415.87874 -321.559562)
			(xy 415.943032 -321.576839) (xy 416.004521 -321.602353) (xy 416.062157 -321.63567) (xy 416.114955 -321.676221)
			(xy 416.138868 -321.699382) (xy 418.230812 -323.791326) (xy 418.253943 -323.815255) (xy 418.294451 -323.868062)
			(xy 418.327723 -323.925702) (xy 418.35319 -323.98719) (xy 418.370417 -324.051476) (xy 418.379108 -324.117459)
			(xy 418.379656 -324.150736) (xy 418.379179 -324.181456) (xy 418.371772 -324.242448) (xy 418.35707 -324.302104)
			(xy 418.335288 -324.359554) (xy 418.306742 -324.41396) (xy 418.27185 -324.464531) (xy 418.231118 -324.51053)
			(xy 418.203513 -324.535) (xy 420.094484 -324.535) (xy 420.098475 -324.446141) (xy 420.110415 -324.357997)
			(xy 420.130207 -324.271278) (xy 420.157694 -324.186683) (xy 420.192652 -324.104892) (xy 420.234801 -324.026563)
			(xy 420.283802 -323.952328) (xy 420.33926 -323.882785) (xy 420.400728 -323.818492) (xy 420.467712 -323.759968)
			(xy 420.539673 -323.707684) (xy 420.61603 -323.662061) (xy 420.696169 -323.623466) (xy 420.779445 -323.59221)
			(xy 420.865188 -323.568544) (xy 420.952707 -323.55266) (xy 421.041298 -323.544684) (xy 421.085772 -323.544184)
			(xy 422.838372 -323.544184) (xy 422.882852 -323.544591) (xy 422.971454 -323.552563) (xy 423.058985 -323.568445)
			(xy 423.14474 -323.59211) (xy 423.228028 -323.623366) (xy 423.308179 -323.661963) (xy 423.384548 -323.707589)
			(xy 423.456519 -323.759878) (xy 423.523513 -323.818407) (xy 423.584991 -323.882706) (xy 423.640458 -323.952257)
			(xy 423.689466 -324.0265) (xy 423.731622 -324.104838) (xy 423.766587 -324.186639) (xy 423.794077 -324.271245)
			(xy 423.813873 -324.357974) (xy 423.825815 -324.446129) (xy 423.829806 -324.535) (xy 427.63847 -324.535)
			(xy 427.642461 -324.446136) (xy 427.654402 -324.357988) (xy 427.674196 -324.271265) (xy 427.701684 -324.186666)
			(xy 427.736646 -324.104871) (xy 427.778799 -324.02654) (xy 427.827803 -323.952302) (xy 427.883265 -323.882757)
			(xy 427.944739 -323.818463) (xy 428.011727 -323.759938) (xy 428.083693 -323.707653) (xy 428.160055 -323.662031)
			(xy 428.2402 -323.623437) (xy 428.323482 -323.592183) (xy 428.40923 -323.56852) (xy 428.496754 -323.552639)
			(xy 428.585349 -323.544667) (xy 428.629826 -323.544184) (xy 430.382426 -323.544184) (xy 430.426904 -323.544608)
			(xy 430.515501 -323.552584) (xy 430.603027 -323.56847) (xy 430.688777 -323.592137) (xy 430.772059 -323.623396)
			(xy 430.852205 -323.661994) (xy 430.928568 -323.70762) (xy 431.000534 -323.759908) (xy 431.067523 -323.818437)
			(xy 431.128996 -323.882734) (xy 431.184459 -323.952283) (xy 431.233463 -324.026524) (xy 431.275616 -324.104858)
			(xy 431.310577 -324.186656) (xy 431.338066 -324.271258) (xy 431.35786 -324.357983) (xy 431.369801 -324.446134)
			(xy 431.373792 -324.535) (xy 435.182584 -324.535) (xy 435.186575 -324.44614) (xy 435.198515 -324.357996)
			(xy 435.218308 -324.271277) (xy 435.245794 -324.186681) (xy 435.280753 -324.104889) (xy 435.322903 -324.026561)
			(xy 435.371904 -323.952326) (xy 435.427363 -323.882782) (xy 435.488831 -323.818489) (xy 435.555816 -323.759965)
			(xy 435.627777 -323.707682) (xy 435.704135 -323.662059) (xy 435.784275 -323.623464) (xy 435.867551 -323.592208)
			(xy 435.953295 -323.568543) (xy 436.040814 -323.552659) (xy 436.129405 -323.544684) (xy 436.17388 -323.544184)
			(xy 437.92648 -323.544184) (xy 437.97096 -323.544591) (xy 438.059562 -323.552564) (xy 438.147092 -323.568447)
			(xy 438.232846 -323.592112) (xy 438.316134 -323.623369) (xy 438.396284 -323.661966) (xy 438.472652 -323.707592)
			(xy 438.544623 -323.75988) (xy 438.611616 -323.81841) (xy 438.673094 -323.882709) (xy 438.72856 -323.95226)
			(xy 438.777568 -324.026503) (xy 438.819723 -324.10484) (xy 438.854687 -324.186641) (xy 438.882178 -324.271246)
			(xy 438.901973 -324.357975) (xy 438.913915 -324.44613) (xy 438.917906 -324.535) (xy 438.913915 -324.62387)
			(xy 438.901973 -324.712025) (xy 438.882178 -324.798754) (xy 438.854687 -324.883359) (xy 438.819723 -324.96516)
			(xy 438.777568 -325.043497) (xy 438.72856 -325.11774) (xy 438.673094 -325.187291) (xy 438.611616 -325.25159)
			(xy 438.544623 -325.31012) (xy 438.472652 -325.362408) (xy 438.396284 -325.408034) (xy 438.316134 -325.446631)
			(xy 438.232846 -325.477888) (xy 438.147092 -325.501553) (xy 438.059562 -325.517436) (xy 437.97096 -325.525409)
			(xy 437.92648 -325.525892) (xy 436.17388 -325.525892) (xy 436.129405 -325.525316) (xy 436.040814 -325.517341)
			(xy 435.953295 -325.501457) (xy 435.867551 -325.477792) (xy 435.784275 -325.446536) (xy 435.704135 -325.407941)
			(xy 435.627777 -325.362318) (xy 435.555816 -325.310035) (xy 435.488831 -325.251511) (xy 435.427363 -325.187218)
			(xy 435.371904 -325.117674) (xy 435.322903 -325.043439) (xy 435.280753 -324.965111) (xy 435.245794 -324.883319)
			(xy 435.218308 -324.798723) (xy 435.198515 -324.712004) (xy 435.186575 -324.62386) (xy 435.182584 -324.535)
			(xy 431.373792 -324.535) (xy 431.369801 -324.623866) (xy 431.35786 -324.712017) (xy 431.338066 -324.798742)
			(xy 431.310577 -324.883344) (xy 431.275616 -324.965142) (xy 431.233463 -325.043476) (xy 431.184459 -325.117717)
			(xy 431.128996 -325.187266) (xy 431.067523 -325.251563) (xy 431.000534 -325.310092) (xy 430.928568 -325.36238)
			(xy 430.852205 -325.408006) (xy 430.772059 -325.446604) (xy 430.688777 -325.477863) (xy 430.603027 -325.50153)
			(xy 430.515501 -325.517416) (xy 430.426904 -325.525392) (xy 430.382426 -325.525892) (xy 428.629826 -325.525892)
			(xy 428.585349 -325.525333) (xy 428.496754 -325.517361) (xy 428.40923 -325.50148) (xy 428.323482 -325.477817)
			(xy 428.2402 -325.446563) (xy 428.160055 -325.407969) (xy 428.083693 -325.362347) (xy 428.011727 -325.310062)
			(xy 427.944739 -325.251537) (xy 427.883265 -325.187243) (xy 427.827803 -325.117698) (xy 427.778799 -325.04346)
			(xy 427.736646 -324.965129) (xy 427.701684 -324.883334) (xy 427.674196 -324.798735) (xy 427.654402 -324.712012)
			(xy 427.642461 -324.623864) (xy 427.63847 -324.535) (xy 423.829806 -324.535) (xy 423.825815 -324.623871)
			(xy 423.813873 -324.712026) (xy 423.794077 -324.798755) (xy 423.766587 -324.883361) (xy 423.731622 -324.965162)
			(xy 423.689466 -325.0435) (xy 423.640458 -325.117743) (xy 423.584991 -325.187294) (xy 423.523513 -325.251593)
			(xy 423.456519 -325.310122) (xy 423.384548 -325.362411) (xy 423.308179 -325.408037) (xy 423.228028 -325.446634)
			(xy 423.14474 -325.47789) (xy 423.058985 -325.501555) (xy 422.971454 -325.517437) (xy 422.882852 -325.525409)
			(xy 422.838372 -325.525892) (xy 421.085772 -325.525892) (xy 421.041298 -325.525316) (xy 420.952707 -325.51734)
			(xy 420.865188 -325.501456) (xy 420.779445 -325.47779) (xy 420.696169 -325.446534) (xy 420.61603 -325.407939)
			(xy 420.539673 -325.362316) (xy 420.467712 -325.310032) (xy 420.400728 -325.251508) (xy 420.33926 -325.187215)
			(xy 420.283802 -325.117672) (xy 420.234801 -325.043437) (xy 420.192652 -324.965108) (xy 420.157694 -324.883317)
			(xy 420.130207 -324.798722) (xy 420.110415 -324.712003) (xy 420.098475 -324.623859) (xy 420.094484 -324.535)
			(xy 418.203513 -324.535) (xy 418.185141 -324.551285) (xy 418.134588 -324.586205) (xy 418.080196 -324.614779)
			(xy 418.022758 -324.636591) (xy 417.96311 -324.651324) (xy 417.902122 -324.658763) (xy 417.871402 -324.659244)
			(xy 417.838118 -324.658662) (xy 417.772124 -324.649927) (xy 417.707833 -324.632659) (xy 417.646344 -324.607153)
			(xy 417.588707 -324.573845) (xy 417.535906 -324.533303) (xy 417.511992 -324.510146) (xy 415.583878 -322.582286)
			(xy 415.576481 -322.575442) (xy 415.557879 -322.567725) (xy 415.54781 -322.5673) (xy 412.16961 -322.5673)
			(xy 412.159538 -322.567704) (xy 412.140938 -322.575437) (xy 412.133542 -322.582286) (xy 411.181042 -323.534532)
			(xy 411.174201 -323.541932) (xy 411.166481 -323.560531) (xy 411.166056 -323.5706) (xy 411.166056 -324.535)
			(xy 412.55037 -324.535) (xy 412.554361 -324.446137) (xy 412.566301 -324.357989) (xy 412.586096 -324.271267)
			(xy 412.613584 -324.186668) (xy 412.648545 -324.104873) (xy 412.690697 -324.026542) (xy 412.739701 -323.952305)
			(xy 412.795163 -323.882759) (xy 412.856636 -323.818465) (xy 412.923624 -323.759941) (xy 412.995589 -323.707656)
			(xy 413.071951 -323.662033) (xy 413.152095 -323.623439) (xy 413.235376 -323.592185) (xy 413.321123 -323.568521)
			(xy 413.408647 -323.55264) (xy 413.497242 -323.544667) (xy 413.541718 -323.544184) (xy 415.294318 -323.544184)
			(xy 415.338796 -323.544608) (xy 415.427394 -323.552583) (xy 415.51492 -323.568468) (xy 415.600671 -323.592135)
			(xy 415.683954 -323.623393) (xy 415.7641 -323.661991) (xy 415.840464 -323.707617) (xy 415.912431 -323.759905)
			(xy 415.97942 -323.818434) (xy 416.040894 -323.882731) (xy 416.096357 -323.952281) (xy 416.145362 -324.026521)
			(xy 416.187515 -324.104856) (xy 416.222477 -324.186654) (xy 416.249965 -324.271256) (xy 416.26976 -324.357982)
			(xy 416.281701 -324.446133) (xy 416.285692 -324.535) (xy 416.281701 -324.623867) (xy 416.26976 -324.712018)
			(xy 416.249965 -324.798744) (xy 416.222477 -324.883346) (xy 416.187515 -324.965144) (xy 416.145362 -325.043479)
			(xy 416.096357 -325.117719) (xy 416.040894 -325.187269) (xy 415.97942 -325.251566) (xy 415.912431 -325.310095)
			(xy 415.840464 -325.362383) (xy 415.7641 -325.408009) (xy 415.683954 -325.446607) (xy 415.600671 -325.477865)
			(xy 415.51492 -325.501532) (xy 415.427394 -325.517417) (xy 415.338796 -325.525392) (xy 415.294318 -325.525892)
			(xy 413.541718 -325.525892) (xy 413.497242 -325.525333) (xy 413.408647 -325.51736) (xy 413.321123 -325.501479)
			(xy 413.235376 -325.477815) (xy 413.152095 -325.446561) (xy 413.071951 -325.407967) (xy 412.995589 -325.362344)
			(xy 412.923624 -325.310059) (xy 412.856636 -325.251535) (xy 412.795163 -325.187241) (xy 412.739701 -325.117695)
			(xy 412.690697 -325.043458) (xy 412.648545 -324.965127) (xy 412.613584 -324.883332) (xy 412.586096 -324.798733)
			(xy 412.566301 -324.712011) (xy 412.554361 -324.623863) (xy 412.55037 -324.535) (xy 411.166056 -324.535)
			(xy 411.166056 -329.865482) (xy 411.165545 -329.898762) (xy 411.156869 -329.964755) (xy 411.139649 -330.02905)
			(xy 411.114181 -330.090546) (xy 411.080901 -330.148189) (xy 411.040379 -330.200993) (xy 411.017212 -330.224892)
			(xy 409.834842 -331.407262) (xy 409.810925 -331.430421) (xy 409.758139 -331.470989) (xy 409.700506 -331.504316)
			(xy 409.639016 -331.529832) (xy 409.57472 -331.547099) (xy 409.508719 -331.555823) (xy 409.475432 -331.55636)
			(xy 408.597608 -331.55636) (xy 408.565642 -331.555975) (xy 408.502215 -331.547964) (xy 408.440292 -331.532065)
			(xy 408.38085 -331.508531) (xy 408.324826 -331.477733) (xy 408.273104 -331.440155) (xy 408.2265 -331.396392)
			(xy 408.185748 -331.347132) (xy 408.151491 -331.293153) (xy 408.124271 -331.235306) (xy 408.104514 -331.174504)
			(xy 408.092535 -331.111705) (xy 408.08852 -331.0479) (xy 403.933308 -331.0479) (xy 403.972054 -331.057452)
			(xy 404.029523 -331.07925) (xy 404.083945 -331.107816) (xy 404.134527 -331.142734) (xy 404.180532 -331.183494)
			(xy 404.221288 -331.229501) (xy 404.256202 -331.280086) (xy 404.284764 -331.33451) (xy 404.306558 -331.39198)
			(xy 404.321267 -331.451658) (xy 404.328674 -331.512674) (xy 404.329138 -331.543406) (xy 404.328664 -331.576088)
			(xy 404.320287 -331.640913) (xy 404.303672 -331.70413) (xy 404.279093 -331.764697) (xy 404.246954 -331.821615)
			(xy 404.207787 -331.873945) (xy 404.185374 -331.897736) (xy 404.179553 -331.904281) (xy 404.172389 -331.920254)
			(xy 404.171 -331.937705) (xy 404.172928 -331.94625) (xy 404.19909 -332.043786) (xy 404.217886 -332.062582)
			(xy 404.23084 -332.066392) (xy 404.262492 -332.07581) (xy 404.323256 -332.101666) (xy 404.380161 -332.135172)
			(xy 404.432249 -332.175763) (xy 404.478643 -332.222757) (xy 404.518563 -332.275361) (xy 404.551337 -332.332691)
			(xy 404.576412 -332.393782) (xy 404.593367 -332.457605) (xy 404.601916 -332.523086) (xy 404.602442 -332.556104)
			(xy 404.60194 -332.588065) (xy 404.593929 -332.651483) (xy 404.586723 -332.679548) (xy 405.63927 -332.679548)
			(xy 405.639799 -332.646088) (xy 405.648566 -332.579745) (xy 405.665967 -332.515128) (xy 405.691702 -332.453354)
			(xy 405.725324 -332.395494) (xy 405.766251 -332.342549) (xy 405.789638 -332.318614) (xy 405.79579 -332.311916)
			(xy 405.803352 -332.295392) (xy 405.80437 -332.286356) (xy 405.809958 -332.210664) (xy 405.805132 -332.193138)
			(xy 405.799544 -332.186026) (xy 405.799544 -332.185518) (xy 405.780515 -332.159109) (xy 405.748595 -332.102379)
			(xy 405.724169 -332.042044) (xy 405.707634 -331.979086) (xy 405.69926 -331.914534) (xy 405.698706 -331.881988)
			(xy 405.699208 -331.850027) (xy 405.707219 -331.786609) (xy 405.723116 -331.724695) (xy 405.746648 -331.665262)
			(xy 405.777442 -331.609247) (xy 405.815015 -331.557532) (xy 405.858772 -331.510935) (xy 405.908025 -331.47019)
			(xy 405.961996 -331.435939) (xy 406.019835 -331.408722) (xy 406.080628 -331.388969) (xy 406.143418 -331.376991)
			(xy 406.207214 -331.372978) (xy 406.27101 -331.376991) (xy 406.3338 -331.388969) (xy 406.394593 -331.408722)
			(xy 406.452432 -331.435939) (xy 406.506403 -331.47019) (xy 406.555656 -331.510935) (xy 406.599413 -331.557532)
			(xy 406.636986 -331.609247) (xy 406.66778 -331.665262) (xy 406.691312 -331.724695) (xy 406.707209 -331.786609)
			(xy 406.707707 -331.790548) (xy 406.90876 -331.790548) (xy 406.912831 -331.734926) (xy 406.924957 -331.680489)
			(xy 406.94488 -331.628398) (xy 406.972176 -331.579763) (xy 407.006262 -331.53562) (xy 407.046411 -331.496911)
			(xy 407.091769 -331.46446) (xy 407.141369 -331.438959) (xy 407.194153 -331.420952) (xy 407.248996 -331.410822)
			(xy 407.30473 -331.408785) (xy 407.360167 -331.414885) (xy 407.414124 -331.428991) (xy 407.465453 -331.450803)
			(xy 407.513059 -331.479857) (xy 407.555927 -331.515532) (xy 407.593144 -331.557069) (xy 407.623917 -331.603582)
			(xy 407.647589 -331.654079) (xy 407.663657 -331.707486) (xy 407.671777 -331.762662) (xy 407.672286 -331.790548)
			(xy 407.671777 -331.818434) (xy 407.663657 -331.87361) (xy 407.647589 -331.927017) (xy 407.623917 -331.977514)
			(xy 407.593144 -332.024027) (xy 407.555927 -332.065564) (xy 407.513059 -332.101239) (xy 407.465453 -332.130293)
			(xy 407.414124 -332.152105) (xy 407.360167 -332.166211) (xy 407.30473 -332.172311) (xy 407.248996 -332.170274)
			(xy 407.194153 -332.160144) (xy 407.141369 -332.142137) (xy 407.091769 -332.116636) (xy 407.046411 -332.084185)
			(xy 407.006262 -332.045476) (xy 406.972176 -332.001333) (xy 406.94488 -331.952698) (xy 406.924957 -331.900607)
			(xy 406.912831 -331.84617) (xy 406.90876 -331.790548) (xy 406.707707 -331.790548) (xy 406.71522 -331.850027)
			(xy 406.715722 -331.881988) (xy 406.715218 -331.915449) (xy 406.706447 -331.981793) (xy 406.689041 -332.046411)
			(xy 406.663302 -332.108184) (xy 406.629675 -332.166044) (xy 406.588743 -332.218987) (xy 406.565354 -332.242922)
			(xy 406.559187 -332.249608) (xy 406.551634 -332.266141) (xy 406.550622 -332.27518) (xy 406.545034 -332.350872)
			(xy 406.54986 -332.368398) (xy 406.555448 -332.37551) (xy 406.555448 -332.376018) (xy 406.574492 -332.402417)
			(xy 406.606409 -332.459149) (xy 406.630833 -332.519487) (xy 406.647365 -332.582448) (xy 406.655734 -332.647001)
			(xy 406.656286 -332.679548) (xy 406.655784 -332.711509) (xy 406.647773 -332.774927) (xy 406.631876 -332.836841)
			(xy 406.608344 -332.896274) (xy 406.57755 -332.952289) (xy 406.539977 -333.004004) (xy 406.527666 -333.017114)
			(xy 412.326074 -333.017114) (xy 412.326516 -332.979937) (xy 412.333767 -332.905936) (xy 412.348191 -332.832993)
			(xy 412.36965 -332.761802) (xy 412.397942 -332.69304) (xy 412.414974 -332.65999) (xy 412.420272 -332.64863)
			(xy 412.420278 -332.623594) (xy 412.414974 -332.612238) (xy 412.397952 -332.579185) (xy 412.369676 -332.510418)
			(xy 412.348224 -332.439227) (xy 412.333798 -332.366287) (xy 412.326535 -332.29229) (xy 412.326074 -332.255114)
			(xy 412.326563 -332.216469) (xy 412.334383 -332.139575) (xy 412.349941 -332.063867) (xy 412.373079 -331.990121)
			(xy 412.403559 -331.919094) (xy 412.441068 -331.851516) (xy 412.485222 -331.788078) (xy 412.535567 -331.729434)
			(xy 412.591586 -331.676183) (xy 412.652705 -331.628873) (xy 412.718298 -331.587989) (xy 412.787689 -331.553951)
			(xy 412.860169 -331.527108) (xy 412.934992 -331.507735) (xy 413.011391 -331.496031) (xy 413.088582 -331.492116)
			(xy 413.165773 -331.496031) (xy 413.242172 -331.507735) (xy 413.316995 -331.527108) (xy 413.389475 -331.553951)
			(xy 413.458866 -331.587989) (xy 413.524459 -331.628873) (xy 413.585578 -331.676183) (xy 413.641597 -331.729434)
			(xy 413.691942 -331.788078) (xy 413.736096 -331.851516) (xy 413.740744 -331.85989) (xy 419.01999 -331.85989)
			(xy 419.02051 -331.831151) (xy 419.029134 -331.774324) (xy 419.046185 -331.719433) (xy 419.071277 -331.667721)
			(xy 419.103843 -331.620359) (xy 419.123114 -331.599032) (xy 419.129718 -331.592174) (xy 419.13683 -331.57414)
			(xy 419.13683 -331.48524) (xy 419.129718 -331.467206) (xy 419.123114 -331.460348) (xy 419.103834 -331.43903)
			(xy 419.07127 -331.391665) (xy 419.046179 -331.339952) (xy 419.02913 -331.28506) (xy 419.020509 -331.228232)
			(xy 419.02051 -331.170753) (xy 419.029134 -331.113925) (xy 419.046185 -331.059034) (xy 419.071277 -331.007322)
			(xy 419.103843 -330.959959) (xy 419.123114 -330.938632) (xy 419.129718 -330.931774) (xy 419.13683 -330.91374)
			(xy 419.13683 -330.82484) (xy 419.129718 -330.806806) (xy 419.123114 -330.799948) (xy 419.103834 -330.77863)
			(xy 419.07127 -330.731265) (xy 419.046179 -330.679552) (xy 419.02913 -330.62466) (xy 419.020509 -330.567832)
			(xy 419.02051 -330.510353) (xy 419.029134 -330.453525) (xy 419.046185 -330.398634) (xy 419.071277 -330.346922)
			(xy 419.103843 -330.299559) (xy 419.123114 -330.278232) (xy 419.129718 -330.271374) (xy 419.13683 -330.25334)
			(xy 419.13683 -330.16444) (xy 419.129718 -330.146406) (xy 419.123114 -330.139548) (xy 419.103835 -330.118229)
			(xy 419.07127 -330.070864) (xy 419.04618 -330.01915) (xy 419.029131 -329.964258) (xy 419.02051 -329.907429)
			(xy 419.01999 -329.87869) (xy 419.020476 -329.851439) (xy 419.028232 -329.797491) (xy 419.043587 -329.745196)
			(xy 419.066229 -329.695619) (xy 419.095695 -329.649769) (xy 419.131386 -329.608578) (xy 419.172577 -329.572887)
			(xy 419.218427 -329.543421) (xy 419.268004 -329.520779) (xy 419.320299 -329.505424) (xy 419.374247 -329.497668)
			(xy 419.428749 -329.497668) (xy 419.482697 -329.505424) (xy 419.534992 -329.520779) (xy 419.584569 -329.543421)
			(xy 419.630419 -329.572887) (xy 419.67161 -329.608578) (xy 419.707301 -329.649769) (xy 419.736767 -329.695619)
			(xy 419.759409 -329.745196) (xy 419.774764 -329.797491) (xy 419.78252 -329.851439) (xy 419.783006 -329.87869)
			(xy 419.782475 -329.907429) (xy 419.773854 -329.964256) (xy 419.756805 -330.019146) (xy 419.731715 -330.070858)
			(xy 419.699152 -330.118221) (xy 419.679882 -330.139548) (xy 419.673278 -330.146406) (xy 419.666166 -330.16444)
			(xy 419.666166 -330.25334) (xy 419.673278 -330.271374) (xy 419.679882 -330.278232) (xy 419.699143 -330.299568)
			(xy 419.731708 -330.346929) (xy 419.756799 -330.398639) (xy 419.77385 -330.453528) (xy 419.782473 -330.510354)
			(xy 419.782474 -330.567831) (xy 419.773853 -330.624657) (xy 419.756805 -330.679547) (xy 419.731715 -330.731259)
			(xy 419.699152 -330.778621) (xy 419.679882 -330.799948) (xy 419.673278 -330.806806) (xy 419.666166 -330.82484)
			(xy 419.666166 -330.91374) (xy 419.673278 -330.931774) (xy 419.679882 -330.938632) (xy 419.699143 -330.959968)
			(xy 419.731708 -331.007329) (xy 419.756799 -331.059039) (xy 419.77385 -331.113928) (xy 419.782473 -331.170754)
			(xy 419.782474 -331.228231) (xy 419.773853 -331.285057) (xy 419.756805 -331.339947) (xy 419.731715 -331.391659)
			(xy 419.699152 -331.439021) (xy 419.679882 -331.460348) (xy 419.673278 -331.467206) (xy 419.666166 -331.48524)
			(xy 419.666166 -331.57414) (xy 419.673278 -331.592174) (xy 419.679882 -331.599032) (xy 419.699151 -331.62036)
			(xy 419.731717 -331.667722) (xy 419.756809 -331.719434) (xy 419.77386 -331.774324) (xy 419.782484 -331.831151)
			(xy 419.783006 -331.85989) (xy 421.409368 -331.85989) (xy 421.409894 -331.831151) (xy 421.418518 -331.774324)
			(xy 421.435567 -331.719434) (xy 421.460658 -331.667722) (xy 421.493222 -331.620359) (xy 421.512492 -331.599032)
			(xy 421.519096 -331.592174) (xy 421.526208 -331.57414) (xy 421.526208 -331.48524) (xy 421.519096 -331.467206)
			(xy 421.512492 -331.460348) (xy 421.493213 -331.439029) (xy 421.46065 -331.391664) (xy 421.435562 -331.339951)
			(xy 421.418514 -331.285059) (xy 421.409893 -331.228232) (xy 421.409894 -331.170754) (xy 421.418517 -331.113926)
			(xy 421.435567 -331.059035) (xy 421.460658 -331.007323) (xy 421.493222 -330.95996) (xy 421.512492 -330.938632)
			(xy 421.519096 -330.931774) (xy 421.526208 -330.91374) (xy 421.526208 -330.82484) (xy 421.519096 -330.806806)
			(xy 421.512492 -330.799948) (xy 421.493213 -330.778629) (xy 421.46065 -330.731264) (xy 421.435562 -330.679551)
			(xy 421.418514 -330.624659) (xy 421.409893 -330.567832) (xy 421.409894 -330.510354) (xy 421.418517 -330.453526)
			(xy 421.435567 -330.398635) (xy 421.460658 -330.346923) (xy 421.493222 -330.29956) (xy 421.512492 -330.278232)
			(xy 421.519096 -330.271374) (xy 421.526208 -330.25334) (xy 421.526208 -330.16444) (xy 421.519096 -330.146406)
			(xy 421.512492 -330.139548) (xy 421.493226 -330.118217) (xy 421.460657 -330.070857) (xy 421.435563 -330.019146)
			(xy 421.418511 -329.964256) (xy 421.409889 -329.907429) (xy 421.409368 -329.87869) (xy 421.409854 -329.851439)
			(xy 421.41761 -329.797491) (xy 421.432965 -329.745196) (xy 421.455607 -329.695619) (xy 421.485073 -329.649769)
			(xy 421.520764 -329.608578) (xy 421.561955 -329.572887) (xy 421.607805 -329.543421) (xy 421.657382 -329.520779)
			(xy 421.709677 -329.505424) (xy 421.763625 -329.497668) (xy 421.818127 -329.497668) (xy 421.872075 -329.505424)
			(xy 421.92437 -329.520779) (xy 421.973947 -329.543421) (xy 422.019797 -329.572887) (xy 422.060988 -329.608578)
			(xy 422.096679 -329.649769) (xy 422.126145 -329.695619) (xy 422.148787 -329.745196) (xy 422.164142 -329.797491)
			(xy 422.171898 -329.851439) (xy 422.172384 -329.87869) (xy 422.171832 -329.907428) (xy 422.163213 -329.964253)
			(xy 422.146168 -330.019142) (xy 422.121083 -330.070854) (xy 422.088526 -330.118219) (xy 422.06926 -330.139548)
			(xy 422.062656 -330.146406) (xy 422.055544 -330.16444) (xy 422.055544 -330.25334) (xy 422.062656 -330.271374)
			(xy 422.06926 -330.278232) (xy 422.088522 -330.299567) (xy 422.121089 -330.346928) (xy 422.146182 -330.398638)
			(xy 422.163233 -330.453528) (xy 422.171857 -330.510354) (xy 422.171858 -330.567831) (xy 422.163237 -330.624658)
			(xy 422.146187 -330.679548) (xy 422.121096 -330.73126) (xy 422.088531 -330.778622) (xy 422.06926 -330.799948)
			(xy 422.062656 -330.806806) (xy 422.055544 -330.82484) (xy 422.055544 -330.91374) (xy 422.062656 -330.931774)
			(xy 422.06926 -330.938632) (xy 422.088522 -330.959967) (xy 422.121089 -331.007328) (xy 422.146182 -331.059038)
			(xy 422.163233 -331.113928) (xy 422.171857 -331.170754) (xy 422.171858 -331.228231) (xy 422.163237 -331.285058)
			(xy 422.146187 -331.339948) (xy 422.121096 -331.39166) (xy 422.088531 -331.439022) (xy 422.06926 -331.460348)
			(xy 422.062656 -331.467206) (xy 422.055544 -331.48524) (xy 422.055544 -331.57414) (xy 422.062656 -331.592174)
			(xy 422.06926 -331.599032) (xy 422.088526 -331.620363) (xy 422.121093 -331.667724) (xy 422.146186 -331.719435)
			(xy 422.163238 -331.774325) (xy 422.171862 -331.831151) (xy 422.172384 -331.85989) (xy 425.11599 -331.85989)
			(xy 425.11651 -331.831151) (xy 425.125134 -331.774324) (xy 425.142185 -331.719433) (xy 425.167277 -331.667721)
			(xy 425.199843 -331.620359) (xy 425.219114 -331.599032) (xy 425.225718 -331.592174) (xy 425.23283 -331.57414)
			(xy 425.23283 -331.48524) (xy 425.225718 -331.467206) (xy 425.219114 -331.460348) (xy 425.199834 -331.43903)
			(xy 425.16727 -331.391665) (xy 425.142179 -331.339952) (xy 425.12513 -331.28506) (xy 425.116509 -331.228232)
			(xy 425.11651 -331.170753) (xy 425.125134 -331.113925) (xy 425.142185 -331.059034) (xy 425.167277 -331.007322)
			(xy 425.199843 -330.959959) (xy 425.219114 -330.938632) (xy 425.225718 -330.931774) (xy 425.23283 -330.91374)
			(xy 425.23283 -330.82484) (xy 425.225718 -330.806806) (xy 425.219114 -330.799948) (xy 425.199834 -330.77863)
			(xy 425.16727 -330.731265) (xy 425.142179 -330.679552) (xy 425.12513 -330.62466) (xy 425.116509 -330.567832)
			(xy 425.11651 -330.510353) (xy 425.125134 -330.453525) (xy 425.142185 -330.398634) (xy 425.167277 -330.346922)
			(xy 425.199843 -330.299559) (xy 425.219114 -330.278232) (xy 425.225718 -330.271374) (xy 425.23283 -330.25334)
			(xy 425.23283 -330.16444) (xy 425.225718 -330.146406) (xy 425.219114 -330.139548) (xy 425.199835 -330.118229)
			(xy 425.16727 -330.070864) (xy 425.14218 -330.01915) (xy 425.125131 -329.964258) (xy 425.11651 -329.907429)
			(xy 425.11599 -329.87869) (xy 425.116476 -329.851439) (xy 425.124232 -329.797491) (xy 425.139587 -329.745196)
			(xy 425.162229 -329.695619) (xy 425.191695 -329.649769) (xy 425.227386 -329.608578) (xy 425.268577 -329.572887)
			(xy 425.314427 -329.543421) (xy 425.364004 -329.520779) (xy 425.416299 -329.505424) (xy 425.470247 -329.497668)
			(xy 425.524749 -329.497668) (xy 425.578697 -329.505424) (xy 425.630992 -329.520779) (xy 425.680569 -329.543421)
			(xy 425.726419 -329.572887) (xy 425.76761 -329.608578) (xy 425.803301 -329.649769) (xy 425.832767 -329.695619)
			(xy 425.855409 -329.745196) (xy 425.870764 -329.797491) (xy 425.87852 -329.851439) (xy 425.879006 -329.87869)
			(xy 425.878475 -329.907429) (xy 425.869854 -329.964256) (xy 425.852805 -330.019146) (xy 425.827715 -330.070858)
			(xy 425.795152 -330.118221) (xy 425.775882 -330.139548) (xy 425.769278 -330.146406) (xy 425.762166 -330.16444)
			(xy 425.762166 -330.25334) (xy 425.769278 -330.271374) (xy 425.775882 -330.278232) (xy 425.795143 -330.299568)
			(xy 425.827708 -330.346929) (xy 425.852799 -330.398639) (xy 425.86985 -330.453528) (xy 425.878473 -330.510354)
			(xy 425.878474 -330.567831) (xy 425.869853 -330.624657) (xy 425.852805 -330.679547) (xy 425.827715 -330.731259)
			(xy 425.795152 -330.778621) (xy 425.775882 -330.799948) (xy 425.769278 -330.806806) (xy 425.762166 -330.82484)
			(xy 425.762166 -330.91374) (xy 425.769278 -330.931774) (xy 425.775882 -330.938632) (xy 425.795143 -330.959968)
			(xy 425.827708 -331.007329) (xy 425.852799 -331.059039) (xy 425.86985 -331.113928) (xy 425.878473 -331.170754)
			(xy 425.878474 -331.228231) (xy 425.869853 -331.285057) (xy 425.852805 -331.339947) (xy 425.827715 -331.391659)
			(xy 425.795152 -331.439021) (xy 425.775882 -331.460348) (xy 425.769278 -331.467206) (xy 425.762166 -331.48524)
			(xy 425.762166 -331.57414) (xy 425.769278 -331.592174) (xy 425.775882 -331.599032) (xy 425.795151 -331.62036)
			(xy 425.827717 -331.667722) (xy 425.852809 -331.719434) (xy 425.86986 -331.774324) (xy 425.871281 -331.78369)
			(xy 427.534324 -331.78369) (xy 427.534862 -331.754952) (xy 427.543484 -331.698126) (xy 427.560532 -331.643236)
			(xy 427.58562 -331.591524) (xy 427.61818 -331.54416) (xy 427.637448 -331.522832) (xy 427.644052 -331.515974)
			(xy 427.651164 -331.49794) (xy 427.651164 -331.40904) (xy 427.644052 -331.391006) (xy 427.637448 -331.384148)
			(xy 427.618166 -331.36283) (xy 427.585599 -331.315467) (xy 427.560507 -331.263754) (xy 427.543456 -331.208862)
			(xy 427.534834 -331.152032) (xy 427.534835 -331.094553) (xy 427.543459 -331.037724) (xy 427.560512 -330.982833)
			(xy 427.585607 -330.93112) (xy 427.618175 -330.883758) (xy 427.637448 -330.862432) (xy 427.644052 -330.855574)
			(xy 427.651164 -330.83754) (xy 427.651164 -330.74864) (xy 427.644052 -330.730606) (xy 427.637448 -330.723748)
			(xy 427.618166 -330.70243) (xy 427.585599 -330.655067) (xy 427.560507 -330.603354) (xy 427.543456 -330.548462)
			(xy 427.534834 -330.491632) (xy 427.534835 -330.434153) (xy 427.543459 -330.377324) (xy 427.560512 -330.322433)
			(xy 427.585607 -330.27072) (xy 427.618175 -330.223358) (xy 427.637448 -330.202032) (xy 427.644052 -330.195174)
			(xy 427.651164 -330.17714) (xy 427.651164 -330.08824) (xy 427.644052 -330.070206) (xy 427.637448 -330.063348)
			(xy 427.618174 -330.042024) (xy 427.585608 -329.994661) (xy 427.560516 -329.942949) (xy 427.543466 -329.888057)
			(xy 427.534844 -329.831229) (xy 427.534324 -329.80249) (xy 427.53481 -329.775239) (xy 427.542566 -329.721291)
			(xy 427.557921 -329.668996) (xy 427.580563 -329.619419) (xy 427.610029 -329.573569) (xy 427.64572 -329.532378)
			(xy 427.686911 -329.496687) (xy 427.732761 -329.467221) (xy 427.782338 -329.444579) (xy 427.834633 -329.429224)
			(xy 427.888581 -329.421468) (xy 427.943083 -329.421468) (xy 427.997031 -329.429224) (xy 428.049326 -329.444579)
			(xy 428.098903 -329.467221) (xy 428.144753 -329.496687) (xy 428.185944 -329.532378) (xy 428.221635 -329.573569)
			(xy 428.251101 -329.619419) (xy 428.273743 -329.668996) (xy 428.289098 -329.721291) (xy 428.296854 -329.775239)
			(xy 428.29734 -329.80249) (xy 428.296799 -329.831228) (xy 428.288179 -329.888054) (xy 428.271133 -329.942944)
			(xy 428.246045 -329.994656) (xy 428.213484 -330.04202) (xy 428.194216 -330.063348) (xy 428.187612 -330.070206)
			(xy 428.1805 -330.08824) (xy 428.1805 -330.17714) (xy 428.187612 -330.195174) (xy 428.194216 -330.202032)
			(xy 428.213475 -330.223368) (xy 428.246037 -330.27073) (xy 428.271127 -330.322441) (xy 428.288176 -330.37733)
			(xy 428.296798 -330.434155) (xy 428.296799 -330.491631) (xy 428.288179 -330.548456) (xy 428.271132 -330.603346)
			(xy 428.246045 -330.655057) (xy 428.213484 -330.70242) (xy 428.194216 -330.723748) (xy 428.187612 -330.730606)
			(xy 428.1805 -330.74864) (xy 428.1805 -330.83754) (xy 428.187612 -330.855574) (xy 428.194216 -330.862432)
			(xy 428.213475 -330.883768) (xy 428.246037 -330.93113) (xy 428.271127 -330.982841) (xy 428.288176 -331.03773)
			(xy 428.296798 -331.094555) (xy 428.296799 -331.152031) (xy 428.288179 -331.208856) (xy 428.271132 -331.263746)
			(xy 428.246045 -331.315457) (xy 428.213484 -331.36282) (xy 428.194216 -331.384148) (xy 428.187612 -331.391006)
			(xy 428.1805 -331.40904) (xy 428.1805 -331.49794) (xy 428.187612 -331.515974) (xy 428.194216 -331.522832)
			(xy 428.213474 -331.54417) (xy 428.246044 -331.591528) (xy 428.27114 -331.643237) (xy 428.288193 -331.698126)
			(xy 428.296818 -331.754952) (xy 428.29734 -331.78369) (xy 431.18659 -331.78369) (xy 431.18711 -331.754951)
			(xy 431.195734 -331.698124) (xy 431.212785 -331.643233) (xy 431.237877 -331.591521) (xy 431.270443 -331.544159)
			(xy 431.289714 -331.522832) (xy 431.296318 -331.515974) (xy 431.30343 -331.49794) (xy 431.30343 -331.40904)
			(xy 431.296318 -331.391006) (xy 431.289714 -331.384148) (xy 431.270434 -331.36283) (xy 431.23787 -331.315465)
			(xy 431.212779 -331.263752) (xy 431.19573 -331.20886) (xy 431.187109 -331.152032) (xy 431.18711 -331.094553)
			(xy 431.195734 -331.037725) (xy 431.212785 -330.982834) (xy 431.237877 -330.931122) (xy 431.270443 -330.883759)
			(xy 431.289714 -330.862432) (xy 431.296318 -330.855574) (xy 431.30343 -330.83754) (xy 431.30343 -330.74864)
			(xy 431.296318 -330.730606) (xy 431.289714 -330.723748) (xy 431.270434 -330.70243) (xy 431.23787 -330.655065)
			(xy 431.212779 -330.603352) (xy 431.19573 -330.54846) (xy 431.187109 -330.491632) (xy 431.18711 -330.434153)
			(xy 431.195734 -330.377325) (xy 431.212785 -330.322434) (xy 431.237877 -330.270722) (xy 431.270443 -330.223359)
			(xy 431.289714 -330.202032) (xy 431.296318 -330.195174) (xy 431.30343 -330.17714) (xy 431.30343 -330.08824)
			(xy 431.296318 -330.070206) (xy 431.289714 -330.063348) (xy 431.270435 -330.042029) (xy 431.23787 -329.994664)
			(xy 431.21278 -329.94295) (xy 431.195731 -329.888058) (xy 431.18711 -329.831229) (xy 431.18659 -329.80249)
			(xy 431.187076 -329.775239) (xy 431.194832 -329.721291) (xy 431.210187 -329.668996) (xy 431.232829 -329.619419)
			(xy 431.262295 -329.573569) (xy 431.297986 -329.532378) (xy 431.339177 -329.496687) (xy 431.385027 -329.467221)
			(xy 431.434604 -329.444579) (xy 431.486899 -329.429224) (xy 431.540847 -329.421468) (xy 431.595349 -329.421468)
			(xy 431.649297 -329.429224) (xy 431.701592 -329.444579) (xy 431.751169 -329.467221) (xy 431.797019 -329.496687)
			(xy 431.83821 -329.532378) (xy 431.873901 -329.573569) (xy 431.903367 -329.619419) (xy 431.926009 -329.668996)
			(xy 431.941364 -329.721291) (xy 431.94912 -329.775239) (xy 431.949606 -329.80249) (xy 431.949075 -329.831229)
			(xy 431.940454 -329.888056) (xy 431.923405 -329.942946) (xy 431.898315 -329.994658) (xy 431.865752 -330.042021)
			(xy 431.846482 -330.063348) (xy 431.839878 -330.070206) (xy 431.832766 -330.08824) (xy 431.832766 -330.17714)
			(xy 431.839878 -330.195174) (xy 431.846482 -330.202032) (xy 431.865743 -330.223368) (xy 431.898308 -330.270729)
			(xy 431.923399 -330.322439) (xy 431.94045 -330.377328) (xy 431.949073 -330.434154) (xy 431.949074 -330.491631)
			(xy 431.940453 -330.548457) (xy 431.923405 -330.603347) (xy 431.898315 -330.655059) (xy 431.865752 -330.702421)
			(xy 431.846482 -330.723748) (xy 431.839878 -330.730606) (xy 431.832766 -330.74864) (xy 431.832766 -330.83754)
			(xy 431.839878 -330.855574) (xy 431.846482 -330.862432) (xy 431.865743 -330.883768) (xy 431.898308 -330.931129)
			(xy 431.923399 -330.982839) (xy 431.94045 -331.037728) (xy 431.949073 -331.094554) (xy 431.949074 -331.152031)
			(xy 431.940453 -331.208857) (xy 431.923405 -331.263747) (xy 431.898315 -331.315459) (xy 431.865752 -331.362821)
			(xy 431.846482 -331.384148) (xy 431.839878 -331.391006) (xy 431.832766 -331.40904) (xy 431.832766 -331.49794)
			(xy 431.839878 -331.515974) (xy 431.846482 -331.522832) (xy 431.865751 -331.54416) (xy 431.898317 -331.591522)
			(xy 431.923409 -331.643234) (xy 431.94046 -331.698124) (xy 431.949084 -331.754951) (xy 431.949389 -331.771752)
			(xy 433.642008 -331.771752) (xy 433.6425 -331.743012) (xy 433.65113 -331.686183) (xy 433.668188 -331.631292)
			(xy 433.693286 -331.579581) (xy 433.725858 -331.53222) (xy 433.745132 -331.510894) (xy 433.751736 -331.504036)
			(xy 433.758848 -331.486002) (xy 433.758848 -331.397102) (xy 433.751736 -331.379068) (xy 433.745132 -331.37221)
			(xy 433.725813 -331.350925) (xy 433.693249 -331.303555) (xy 433.668159 -331.251837) (xy 433.651113 -331.19694)
			(xy 433.642494 -331.140106) (xy 433.6425 -331.082624) (xy 433.651128 -331.025792) (xy 433.668185 -330.970898)
			(xy 433.693284 -330.919184) (xy 433.725857 -330.871821) (xy 433.745132 -330.850494) (xy 433.751736 -330.843636)
			(xy 433.758848 -330.825602) (xy 433.758848 -330.736702) (xy 433.751736 -330.718668) (xy 433.745132 -330.71181)
			(xy 433.725813 -330.690525) (xy 433.693249 -330.643155) (xy 433.668159 -330.591437) (xy 433.651113 -330.53654)
			(xy 433.642494 -330.479706) (xy 433.6425 -330.422224) (xy 433.651128 -330.365392) (xy 433.668185 -330.310498)
			(xy 433.693284 -330.258784) (xy 433.725857 -330.211421) (xy 433.745132 -330.190094) (xy 433.751736 -330.183236)
			(xy 433.758848 -330.165202) (xy 433.758848 -330.076302) (xy 433.751736 -330.058268) (xy 433.745132 -330.05141)
			(xy 433.725838 -330.030103) (xy 433.693275 -329.982736) (xy 433.668187 -329.931019) (xy 433.651142 -329.876124)
			(xy 433.642525 -329.819292) (xy 433.642008 -329.790552) (xy 433.642494 -329.763301) (xy 433.65025 -329.709353)
			(xy 433.665605 -329.657058) (xy 433.688247 -329.607481) (xy 433.717713 -329.561631) (xy 433.753404 -329.52044)
			(xy 433.794595 -329.484749) (xy 433.840445 -329.455283) (xy 433.890022 -329.432641) (xy 433.942317 -329.417286)
			(xy 433.996265 -329.40953) (xy 434.050767 -329.40953) (xy 434.104715 -329.417286) (xy 434.15701 -329.432641)
			(xy 434.206587 -329.455283) (xy 434.252437 -329.484749) (xy 434.293628 -329.52044) (xy 434.329319 -329.561631)
			(xy 434.358785 -329.607481) (xy 434.381427 -329.657058) (xy 434.396782 -329.709353) (xy 434.404538 -329.763301)
			(xy 434.405024 -329.790552) (xy 434.404525 -329.819292) (xy 434.395896 -329.87612) (xy 434.378839 -329.931011)
			(xy 434.353742 -329.982722) (xy 434.321173 -330.030084) (xy 434.3019 -330.05141) (xy 434.295296 -330.058268)
			(xy 434.288184 -330.076302) (xy 434.288184 -330.165202) (xy 434.295296 -330.183236) (xy 434.3019 -330.190094)
			(xy 434.321122 -330.211463) (xy 434.353687 -330.258819) (xy 434.37878 -330.310524) (xy 434.395832 -330.365408)
			(xy 434.404458 -330.422229) (xy 434.404464 -330.479701) (xy 434.395848 -330.536524) (xy 434.378805 -330.591411)
			(xy 434.353722 -330.643121) (xy 434.321166 -330.690483) (xy 434.3019 -330.71181) (xy 434.295296 -330.718668)
			(xy 434.288184 -330.736702) (xy 434.288184 -330.825602) (xy 434.295296 -330.843636) (xy 434.3019 -330.850494)
			(xy 434.321122 -330.871863) (xy 434.353687 -330.919219) (xy 434.37878 -330.970924) (xy 434.395832 -331.025808)
			(xy 434.404458 -331.082629) (xy 434.404464 -331.140101) (xy 434.395848 -331.196924) (xy 434.378805 -331.251811)
			(xy 434.353722 -331.303521) (xy 434.321166 -331.350883) (xy 434.3019 -331.37221) (xy 434.295296 -331.379068)
			(xy 434.290688 -331.390752) (xy 436.944008 -331.390752) (xy 436.9445 -331.362012) (xy 436.95313 -331.305183)
			(xy 436.970188 -331.250292) (xy 436.995286 -331.198581) (xy 437.027858 -331.15122) (xy 437.047132 -331.129894)
			(xy 437.053736 -331.123036) (xy 437.060848 -331.105002) (xy 437.060848 -331.016102) (xy 437.053736 -330.998068)
			(xy 437.047132 -330.99121) (xy 437.027813 -330.969925) (xy 436.995249 -330.922555) (xy 436.970159 -330.870837)
			(xy 436.953113 -330.81594) (xy 436.944494 -330.759106) (xy 436.9445 -330.701624) (xy 436.953128 -330.644792)
			(xy 436.970185 -330.589898) (xy 436.995284 -330.538184) (xy 437.027857 -330.490821) (xy 437.047132 -330.469494)
			(xy 437.053736 -330.462636) (xy 437.060848 -330.444602) (xy 437.060848 -330.355702) (xy 437.053736 -330.337668)
			(xy 437.047132 -330.33081) (xy 437.027838 -330.309503) (xy 436.995275 -330.262136) (xy 436.970187 -330.210419)
			(xy 436.953142 -330.155524) (xy 436.944525 -330.098692) (xy 436.944008 -330.069952) (xy 436.944494 -330.042701)
			(xy 436.95225 -329.988753) (xy 436.967605 -329.936458) (xy 436.990247 -329.886881) (xy 437.019713 -329.841031)
			(xy 437.055404 -329.79984) (xy 437.096595 -329.764149) (xy 437.142445 -329.734683) (xy 437.192022 -329.712041)
			(xy 437.244317 -329.696686) (xy 437.298265 -329.68893) (xy 437.352767 -329.68893) (xy 437.406715 -329.696686)
			(xy 437.45901 -329.712041) (xy 437.508587 -329.734683) (xy 437.554437 -329.764149) (xy 437.595628 -329.79984)
			(xy 437.631319 -329.841031) (xy 437.660785 -329.886881) (xy 437.683427 -329.936458) (xy 437.698782 -329.988753)
			(xy 437.706538 -330.042701) (xy 437.707024 -330.069952) (xy 437.706525 -330.098692) (xy 437.697896 -330.15552)
			(xy 437.680839 -330.210411) (xy 437.655742 -330.262122) (xy 437.623173 -330.309484) (xy 437.6039 -330.33081)
			(xy 437.597296 -330.337668) (xy 437.590184 -330.355702) (xy 437.590184 -330.444602) (xy 437.597296 -330.462636)
			(xy 437.6039 -330.469494) (xy 437.623122 -330.490863) (xy 437.655687 -330.538219) (xy 437.68078 -330.589924)
			(xy 437.697832 -330.644808) (xy 437.706458 -330.701629) (xy 437.706464 -330.759101) (xy 437.697848 -330.815924)
			(xy 437.680805 -330.870811) (xy 437.655722 -330.922521) (xy 437.623166 -330.969883) (xy 437.6039 -330.99121)
			(xy 437.597296 -330.998068) (xy 437.590184 -331.016102) (xy 437.590184 -331.105002) (xy 437.597296 -331.123036)
			(xy 437.6039 -331.129894) (xy 437.623185 -331.151209) (xy 437.655751 -331.198573) (xy 437.680842 -331.250288)
			(xy 437.697889 -331.305182) (xy 437.706506 -331.362012) (xy 437.707024 -331.390752) (xy 437.706507 -331.418283)
			(xy 437.70202 -331.449172) (xy 439.704988 -331.449172) (xy 439.705498 -331.420433) (xy 439.714124 -331.363605)
			(xy 439.731178 -331.308714) (xy 439.756272 -331.257003) (xy 439.78884 -331.209641) (xy 439.808112 -331.188314)
			(xy 439.814716 -331.181456) (xy 439.821828 -331.163422) (xy 439.821828 -331.074522) (xy 439.814716 -331.056488)
			(xy 439.808112 -331.04963) (xy 439.788814 -331.028327) (xy 439.756251 -330.98096) (xy 439.731161 -330.929244)
			(xy 439.714114 -330.87435) (xy 439.705494 -330.81752) (xy 439.705497 -330.760039) (xy 439.714123 -330.70321)
			(xy 439.731176 -330.648318) (xy 439.756271 -330.596604) (xy 439.78884 -330.549241) (xy 439.808112 -330.527914)
			(xy 439.814716 -330.521056) (xy 439.821828 -330.503022) (xy 439.821828 -330.414122) (xy 439.814716 -330.396088)
			(xy 439.808112 -330.38923) (xy 439.788824 -330.367918) (xy 439.756261 -330.320552) (xy 439.731172 -330.268836)
			(xy 439.714126 -330.213942) (xy 439.705507 -330.157112) (xy 439.704988 -330.128372) (xy 439.705474 -330.101121)
			(xy 439.71323 -330.047173) (xy 439.728585 -329.994878) (xy 439.751227 -329.945301) (xy 439.780693 -329.899451)
			(xy 439.816384 -329.85826) (xy 439.857575 -329.822569) (xy 439.903425 -329.793103) (xy 439.953002 -329.770461)
			(xy 440.005297 -329.755106) (xy 440.059245 -329.74735) (xy 440.113747 -329.74735) (xy 440.167695 -329.755106)
			(xy 440.21999 -329.770461) (xy 440.269567 -329.793103) (xy 440.315417 -329.822569) (xy 440.356608 -329.85826)
			(xy 440.392299 -329.899451) (xy 440.421765 -329.945301) (xy 440.444407 -329.994878) (xy 440.459762 -330.047173)
			(xy 440.467518 -330.101121) (xy 440.468004 -330.128372) (xy 440.467462 -330.15711) (xy 440.458844 -330.213937)
			(xy 440.441798 -330.268827) (xy 440.41671 -330.320539) (xy 440.384149 -330.367903) (xy 440.36488 -330.38923)
			(xy 440.358276 -330.396088) (xy 440.351164 -330.414122) (xy 440.351164 -330.503022) (xy 440.358276 -330.521056)
			(xy 440.36488 -330.527914) (xy 440.384123 -330.549265) (xy 440.416689 -330.596623) (xy 440.441782 -330.648331)
			(xy 440.458833 -330.703218) (xy 440.467459 -330.760042) (xy 440.467462 -330.817517) (xy 440.458843 -330.874342)
			(xy 440.441797 -330.929231) (xy 440.416709 -330.980941) (xy 440.384149 -331.028303) (xy 440.36488 -331.04963)
			(xy 440.358276 -331.056488) (xy 440.351164 -331.074522) (xy 440.351164 -331.163422) (xy 440.358276 -331.181456)
			(xy 440.36488 -331.188314) (xy 440.38414 -331.20965) (xy 440.416707 -331.25701) (xy 440.441802 -331.308719)
			(xy 440.458855 -331.363608) (xy 440.467481 -331.420434) (xy 440.468004 -331.449172) (xy 440.467503 -331.476704)
			(xy 440.459585 -331.531196) (xy 440.443922 -331.583985) (xy 440.42084 -331.633978) (xy 440.390817 -331.680138)
			(xy 440.373008 -331.70114) (xy 440.366658 -331.708252) (xy 440.360054 -331.72654) (xy 440.362848 -331.806042)
			(xy 440.363647 -331.815723) (xy 440.371462 -331.833485) (xy 440.378088 -331.840586) (xy 440.399205 -331.862229)
			(xy 440.435007 -331.910954) (xy 440.462674 -331.964717) (xy 440.481512 -332.022172) (xy 440.491049 -332.08188)
			(xy 440.491626 -332.112112) (xy 440.49114 -332.139363) (xy 440.483384 -332.193311) (xy 440.468029 -332.245606)
			(xy 440.445387 -332.295183) (xy 440.415921 -332.341033) (xy 440.38023 -332.382224) (xy 440.339039 -332.417915)
			(xy 440.293189 -332.447381) (xy 440.243612 -332.470023) (xy 440.191317 -332.485378) (xy 440.137369 -332.493134)
			(xy 440.082867 -332.493134) (xy 440.028919 -332.485378) (xy 439.976624 -332.470023) (xy 439.927047 -332.447381)
			(xy 439.881197 -332.417915) (xy 439.840006 -332.382224) (xy 439.804315 -332.341033) (xy 439.774849 -332.295183)
			(xy 439.752207 -332.245606) (xy 439.736852 -332.193311) (xy 439.729096 -332.139363) (xy 439.72861 -332.112112)
			(xy 439.729098 -332.084579) (xy 439.737019 -332.030087) (xy 439.752685 -331.977297) (xy 439.77577 -331.927305)
			(xy 439.805796 -331.881146) (xy 439.823606 -331.860144) (xy 439.829956 -331.853032) (xy 439.83656 -331.834744)
			(xy 439.833766 -331.755242) (xy 439.832998 -331.745556) (xy 439.825163 -331.727794) (xy 439.818526 -331.720698)
			(xy 439.797404 -331.69906) (xy 439.761602 -331.650334) (xy 439.733936 -331.596569) (xy 439.715099 -331.539113)
			(xy 439.705563 -331.479405) (xy 439.704988 -331.449172) (xy 437.70202 -331.449172) (xy 437.698592 -331.472774)
			(xy 437.682933 -331.525564) (xy 437.659854 -331.575557) (xy 437.629835 -331.621717) (xy 437.612028 -331.64272)
			(xy 437.605678 -331.649832) (xy 437.599074 -331.66812) (xy 437.601868 -331.747622) (xy 437.602622 -331.75731)
			(xy 437.610468 -331.77507) (xy 437.617108 -331.782166) (xy 437.638201 -331.803831) (xy 437.67401 -331.852548)
			(xy 437.701682 -331.906306) (xy 437.720526 -331.963757) (xy 437.730068 -332.023461) (xy 437.730646 -332.053692)
			(xy 437.73016 -332.080943) (xy 437.722404 -332.134891) (xy 437.707049 -332.187186) (xy 437.684407 -332.236763)
			(xy 437.654941 -332.282613) (xy 437.61925 -332.323804) (xy 437.578059 -332.359495) (xy 437.532209 -332.388961)
			(xy 437.482632 -332.411603) (xy 437.430337 -332.426958) (xy 437.376389 -332.434714) (xy 437.321887 -332.434714)
			(xy 437.267939 -332.426958) (xy 437.215644 -332.411603) (xy 437.166067 -332.388961) (xy 437.120217 -332.359495)
			(xy 437.079026 -332.323804) (xy 437.043335 -332.282613) (xy 437.013869 -332.236763) (xy 436.991227 -332.187186)
			(xy 436.975872 -332.134891) (xy 436.968116 -332.080943) (xy 436.96763 -332.053692) (xy 436.968125 -332.02616)
			(xy 436.976048 -331.971669) (xy 436.991713 -331.918879) (xy 437.014795 -331.868887) (xy 437.044818 -331.822727)
			(xy 437.062626 -331.801724) (xy 437.068976 -331.794612) (xy 437.07558 -331.776324) (xy 437.072786 -331.696822)
			(xy 437.072022 -331.687136) (xy 437.064184 -331.669374) (xy 437.057546 -331.662278) (xy 437.036418 -331.640646)
			(xy 437.000616 -331.591919) (xy 436.97295 -331.538153) (xy 436.954115 -331.480695) (xy 436.944582 -331.420985)
			(xy 436.944008 -331.390752) (xy 434.290688 -331.390752) (xy 434.288184 -331.397102) (xy 434.288184 -331.486002)
			(xy 434.295296 -331.504036) (xy 434.3019 -331.510894) (xy 434.321185 -331.532209) (xy 434.353751 -331.579573)
			(xy 434.378842 -331.631288) (xy 434.395889 -331.686182) (xy 434.404506 -331.743012) (xy 434.405024 -331.771752)
			(xy 434.404538 -331.799003) (xy 434.396782 -331.852951) (xy 434.381427 -331.905246) (xy 434.358785 -331.954823)
			(xy 434.329319 -332.000673) (xy 434.293628 -332.041864) (xy 434.252437 -332.077555) (xy 434.206587 -332.107021)
			(xy 434.15701 -332.129663) (xy 434.104715 -332.145018) (xy 434.050767 -332.152774) (xy 433.996265 -332.152774)
			(xy 433.942317 -332.145018) (xy 433.890022 -332.129663) (xy 433.840445 -332.107021) (xy 433.794595 -332.077555)
			(xy 433.753404 -332.041864) (xy 433.717713 -332.000673) (xy 433.688247 -331.954823) (xy 433.665605 -331.905246)
			(xy 433.65025 -331.852951) (xy 433.642494 -331.799003) (xy 433.642008 -331.771752) (xy 431.949389 -331.771752)
			(xy 431.949606 -331.78369) (xy 431.94912 -331.810941) (xy 431.941364 -331.864889) (xy 431.926009 -331.917184)
			(xy 431.903367 -331.966761) (xy 431.873901 -332.012611) (xy 431.83821 -332.053802) (xy 431.797019 -332.089493)
			(xy 431.751169 -332.118959) (xy 431.701592 -332.141601) (xy 431.649297 -332.156956) (xy 431.595349 -332.164712)
			(xy 431.540847 -332.164712) (xy 431.486899 -332.156956) (xy 431.434604 -332.141601) (xy 431.385027 -332.118959)
			(xy 431.339177 -332.089493) (xy 431.297986 -332.053802) (xy 431.262295 -332.012611) (xy 431.232829 -331.966761)
			(xy 431.210187 -331.917184) (xy 431.194832 -331.864889) (xy 431.187076 -331.810941) (xy 431.18659 -331.78369)
			(xy 428.29734 -331.78369) (xy 428.296854 -331.810941) (xy 428.289098 -331.864889) (xy 428.273743 -331.917184)
			(xy 428.251101 -331.966761) (xy 428.221635 -332.012611) (xy 428.185944 -332.053802) (xy 428.144753 -332.089493)
			(xy 428.098903 -332.118959) (xy 428.049326 -332.141601) (xy 427.997031 -332.156956) (xy 427.943083 -332.164712)
			(xy 427.888581 -332.164712) (xy 427.834633 -332.156956) (xy 427.782338 -332.141601) (xy 427.732761 -332.118959)
			(xy 427.686911 -332.089493) (xy 427.64572 -332.053802) (xy 427.610029 -332.012611) (xy 427.580563 -331.966761)
			(xy 427.557921 -331.917184) (xy 427.542566 -331.864889) (xy 427.53481 -331.810941) (xy 427.534324 -331.78369)
			(xy 425.871281 -331.78369) (xy 425.878484 -331.831151) (xy 425.879006 -331.85989) (xy 425.87852 -331.887141)
			(xy 425.870764 -331.941089) (xy 425.855409 -331.993384) (xy 425.832767 -332.042961) (xy 425.803301 -332.088811)
			(xy 425.76761 -332.130002) (xy 425.726419 -332.165693) (xy 425.680569 -332.195159) (xy 425.630992 -332.217801)
			(xy 425.578697 -332.233156) (xy 425.524749 -332.240912) (xy 425.470247 -332.240912) (xy 425.416299 -332.233156)
			(xy 425.364004 -332.217801) (xy 425.314427 -332.195159) (xy 425.268577 -332.165693) (xy 425.227386 -332.130002)
			(xy 425.191695 -332.088811) (xy 425.162229 -332.042961) (xy 425.139587 -331.993384) (xy 425.124232 -331.941089)
			(xy 425.116476 -331.887141) (xy 425.11599 -331.85989) (xy 422.172384 -331.85989) (xy 422.171898 -331.887141)
			(xy 422.164142 -331.941089) (xy 422.148787 -331.993384) (xy 422.126145 -332.042961) (xy 422.096679 -332.088811)
			(xy 422.060988 -332.130002) (xy 422.019797 -332.165693) (xy 421.973947 -332.195159) (xy 421.92437 -332.217801)
			(xy 421.872075 -332.233156) (xy 421.818127 -332.240912) (xy 421.763625 -332.240912) (xy 421.709677 -332.233156)
			(xy 421.657382 -332.217801) (xy 421.607805 -332.195159) (xy 421.561955 -332.165693) (xy 421.520764 -332.130002)
			(xy 421.485073 -332.088811) (xy 421.455607 -332.042961) (xy 421.432965 -331.993384) (xy 421.41761 -331.941089)
			(xy 421.409854 -331.887141) (xy 421.409368 -331.85989) (xy 419.783006 -331.85989) (xy 419.78252 -331.887141)
			(xy 419.774764 -331.941089) (xy 419.759409 -331.993384) (xy 419.736767 -332.042961) (xy 419.707301 -332.088811)
			(xy 419.67161 -332.130002) (xy 419.630419 -332.165693) (xy 419.584569 -332.195159) (xy 419.534992 -332.217801)
			(xy 419.482697 -332.233156) (xy 419.428749 -332.240912) (xy 419.374247 -332.240912) (xy 419.320299 -332.233156)
			(xy 419.268004 -332.217801) (xy 419.218427 -332.195159) (xy 419.172577 -332.165693) (xy 419.131386 -332.130002)
			(xy 419.095695 -332.088811) (xy 419.066229 -332.042961) (xy 419.043587 -331.993384) (xy 419.028232 -331.941089)
			(xy 419.020476 -331.887141) (xy 419.01999 -331.85989) (xy 413.740744 -331.85989) (xy 413.773605 -331.919094)
			(xy 413.804085 -331.990121) (xy 413.827223 -332.063867) (xy 413.842781 -332.139575) (xy 413.850601 -332.216469)
			(xy 413.85109 -332.255114) (xy 413.850622 -332.292291) (xy 413.843378 -332.366291) (xy 413.82896 -332.439233)
			(xy 413.807506 -332.510425) (xy 413.77922 -332.579188) (xy 413.76219 -332.612238) (xy 413.756868 -332.62359)
			(xy 413.756875 -332.648634) (xy 413.76219 -332.65999) (xy 413.779228 -332.693035) (xy 413.8075 -332.761805)
			(xy 413.828948 -332.832997) (xy 413.843371 -332.905939) (xy 413.85063 -332.979937) (xy 413.85109 -333.017114)
			(xy 413.850601 -333.055759) (xy 413.842781 -333.132653) (xy 413.827223 -333.208361) (xy 413.804085 -333.282107)
			(xy 413.773605 -333.353134) (xy 413.736096 -333.420712) (xy 413.691942 -333.48415) (xy 413.641597 -333.542794)
			(xy 413.585578 -333.596045) (xy 413.524459 -333.643355) (xy 413.458866 -333.684239) (xy 413.389475 -333.718277)
			(xy 413.316995 -333.74512) (xy 413.242172 -333.764493) (xy 413.165773 -333.776197) (xy 413.088582 -333.780112)
			(xy 413.011391 -333.776197) (xy 412.934992 -333.764493) (xy 412.860169 -333.74512) (xy 412.787689 -333.718277)
			(xy 412.718298 -333.684239) (xy 412.652705 -333.643355) (xy 412.591586 -333.596045) (xy 412.535567 -333.542794)
			(xy 412.485222 -333.48415) (xy 412.441068 -333.420712) (xy 412.403559 -333.353134) (xy 412.373079 -333.282107)
			(xy 412.349941 -333.208361) (xy 412.334383 -333.132653) (xy 412.326563 -333.055759) (xy 412.326074 -333.017114)
			(xy 406.527666 -333.017114) (xy 406.49622 -333.050601) (xy 406.446967 -333.091346) (xy 406.392996 -333.125597)
			(xy 406.335157 -333.152814) (xy 406.274364 -333.172567) (xy 406.211574 -333.184545) (xy 406.147778 -333.188559)
			(xy 406.083982 -333.184545) (xy 406.021192 -333.172567) (xy 405.960399 -333.152814) (xy 405.90256 -333.125597)
			(xy 405.848589 -333.091346) (xy 405.799336 -333.050601) (xy 405.755579 -333.004004) (xy 405.718006 -332.952289)
			(xy 405.687212 -332.896274) (xy 405.66368 -332.836841) (xy 405.647783 -332.774927) (xy 405.639772 -332.711509)
			(xy 405.63927 -332.679548) (xy 404.586723 -332.679548) (xy 404.578032 -332.713397) (xy 404.5545 -332.77283)
			(xy 404.523706 -332.828845) (xy 404.486133 -332.88056) (xy 404.442376 -332.927157) (xy 404.393123 -332.967902)
			(xy 404.339152 -333.002153) (xy 404.281313 -333.02937) (xy 404.22052 -333.049123) (xy 404.15773 -333.061101)
			(xy 404.093934 -333.065115) (xy 404.030138 -333.061101) (xy 403.967348 -333.049123) (xy 403.906555 -333.02937)
			(xy 403.848716 -333.002153) (xy 403.794745 -332.967902) (xy 403.745492 -332.927157) (xy 403.701735 -332.88056)
			(xy 403.664162 -332.828845) (xy 403.633368 -332.77283) (xy 403.609836 -332.713397) (xy 403.593939 -332.651483)
			(xy 403.585928 -332.588065) (xy 403.585426 -332.556104) (xy 403.585916 -332.523423) (xy 403.594291 -332.458598)
			(xy 403.610904 -332.395382) (xy 403.635481 -332.334815) (xy 403.667615 -332.277897) (xy 403.706779 -332.225566)
			(xy 403.72919 -332.201774) (xy 403.735012 -332.195231) (xy 403.74217 -332.179256) (xy 403.743561 -332.161806)
			(xy 403.741636 -332.15326) (xy 403.715474 -332.055724) (xy 403.696678 -332.036928) (xy 403.683724 -332.033118)
			(xy 403.667405 -332.028407) (xy 403.635375 -332.017093) (xy 403.619716 -332.010512) (xy 403.609048 -332.00594)
			(xy 403.586188 -332.006702) (xy 403.49551 -332.054962) (xy 403.482048 -332.07325) (xy 403.479762 -332.08468)
			(xy 403.474297 -332.110469) (xy 403.457343 -332.16038) (xy 403.433678 -332.207482) (xy 403.403752 -332.250876)
			(xy 403.368136 -332.289736) (xy 403.327507 -332.323321) (xy 403.282641 -332.35099) (xy 403.234391 -332.372218)
			(xy 403.183678 -332.386599) (xy 403.131468 -332.39386) (xy 403.105112 -332.394306) (xy 403.077859 -332.393834)
			(xy 403.023909 -332.386078) (xy 402.971611 -332.370724) (xy 402.922031 -332.348082) (xy 402.876177 -332.318615)
			(xy 402.834985 -332.282923) (xy 402.799291 -332.241731) (xy 402.769823 -332.195878) (xy 402.74718 -332.146299)
			(xy 402.731824 -332.094001) (xy 402.724067 -332.040051) (xy 402.723604 -332.012798) (xy 402.723992 -331.988541)
			(xy 402.730156 -331.940421) (xy 402.742361 -331.893468) (xy 402.751036 -331.870812) (xy 402.754103 -331.862428)
			(xy 402.754751 -331.8446) (xy 402.752306 -331.836014) (xy 402.742908 -331.807058) (xy 402.739759 -331.798532)
			(xy 402.728419 -331.784344) (xy 402.72081 -331.779372) (xy 402.693286 -331.762025) (xy 402.642499 -331.721358)
			(xy 402.597317 -331.674543) (xy 402.558478 -331.622346) (xy 402.526616 -331.565619) (xy 402.502253 -331.505291)
			(xy 402.485787 -331.442347) (xy 402.477487 -331.377817) (xy 402.47697 -331.345286) (xy 400.240548 -331.345286)
			(xy 400.27285 -331.358075) (xy 400.328873 -331.388874) (xy 400.380594 -331.426451) (xy 400.427197 -331.470214)
			(xy 400.467948 -331.519473) (xy 400.502204 -331.573451) (xy 400.529424 -331.631297) (xy 400.54918 -331.692098)
			(xy 400.561159 -331.754896) (xy 400.565174 -331.8187) (xy 400.561159 -331.882504) (xy 400.54918 -331.945302)
			(xy 400.529424 -332.006103) (xy 400.502204 -332.063949) (xy 400.467948 -332.117927) (xy 400.427197 -332.167186)
			(xy 400.380594 -332.210949) (xy 400.328873 -332.248526) (xy 400.27285 -332.279325) (xy 400.213409 -332.302859)
			(xy 400.151487 -332.318757) (xy 400.088061 -332.326769) (xy 400.056096 -332.32725) (xy 400.024874 -332.326819)
			(xy 399.962898 -332.319183) (xy 399.902325 -332.304013) (xy 399.844065 -332.281538) (xy 399.788997 -332.252098)
			(xy 399.737949 -332.216133) (xy 399.691691 -332.174188) (xy 399.650918 -332.126892) (xy 399.633186 -332.10119)
			(xy 399.633186 -332.100936) (xy 399.627415 -332.093133) (xy 399.611339 -332.082291) (xy 399.601944 -332.079854)
			(xy 399.533364 -332.06436) (xy 399.523695 -332.062652) (xy 399.504351 -332.065932) (xy 399.495772 -332.07071)
			(xy 399.473243 -332.08395) (xy 399.425337 -332.104823) (xy 399.375034 -332.118974) (xy 399.323272 -332.12614)
			(xy 399.297144 -332.12659) (xy 399.269891 -332.126104) (xy 399.21594 -332.118352) (xy 399.163642 -332.103001)
			(xy 399.114061 -332.080362) (xy 399.068206 -332.050897) (xy 399.027013 -332.015206) (xy 398.991318 -331.974014)
			(xy 398.96185 -331.928162) (xy 398.939208 -331.878583) (xy 398.923853 -331.826285) (xy 398.916098 -331.772335)
			(xy 398.915636 -331.745082) (xy 398.916125 -331.716377) (xy 398.92473 -331.659616) (xy 398.941743 -331.604785)
			(xy 398.966779 -331.553122) (xy 398.999275 -331.505794) (xy 399.018506 -331.484478) (xy 399.02511 -331.477366)
			(xy 399.031968 -331.45984) (xy 399.032476 -331.3811) (xy 399.0321 -331.371572) (xy 399.025194 -331.353816)
			(xy 399.019014 -331.346556) (xy 398.998096 -331.323024) (xy 398.961579 -331.27173) (xy 398.931672 -331.216323)
			(xy 398.90883 -331.157649) (xy 398.893404 -331.096604) (xy 398.88563 -331.034122) (xy 398.885156 -331.00264)
			(xy 395.524479 -331.00264) (xy 395.511415 -331.054571) (xy 395.488777 -331.113005) (xy 395.459134 -331.168215)
			(xy 395.422933 -331.219366) (xy 395.380723 -331.265682) (xy 395.333143 -331.306463) (xy 395.307312 -331.324204)
			(xy 395.292834 -331.333856) (xy 395.281658 -331.366368) (xy 395.45006 -331.860906) (xy 395.704993 -332.609401)
			(xy 396.448274 -332.609401) (xy 396.448274 -332.545479) (xy 396.456285 -332.482061) (xy 396.472182 -332.420147)
			(xy 396.495714 -332.360714) (xy 396.526508 -332.304699) (xy 396.564081 -332.252984) (xy 396.607838 -332.206387)
			(xy 396.657091 -332.165642) (xy 396.711062 -332.131391) (xy 396.768901 -332.104174) (xy 396.829694 -332.084421)
			(xy 396.892484 -332.072443) (xy 396.95628 -332.06843) (xy 397.020076 -332.072443) (xy 397.082866 -332.084421)
			(xy 397.143659 -332.104174) (xy 397.201498 -332.131391) (xy 397.255469 -332.165642) (xy 397.304722 -332.206387)
			(xy 397.348479 -332.252984) (xy 397.386052 -332.304699) (xy 397.416846 -332.360714) (xy 397.440378 -332.420147)
			(xy 397.456275 -332.482061) (xy 397.464286 -332.545479) (xy 397.464788 -332.57744) (xy 397.464286 -332.609401)
			(xy 397.456275 -332.672819) (xy 397.440378 -332.734733) (xy 397.416846 -332.794166) (xy 397.386052 -332.850181)
			(xy 397.348479 -332.901896) (xy 397.304722 -332.948493) (xy 397.255469 -332.989238) (xy 397.201498 -333.023489)
			(xy 397.143659 -333.050706) (xy 397.082866 -333.070459) (xy 397.020076 -333.082437) (xy 396.95628 -333.086451)
			(xy 396.892484 -333.082437) (xy 396.829694 -333.070459) (xy 396.768901 -333.050706) (xy 396.711062 -333.023489)
			(xy 396.657091 -332.989238) (xy 396.607838 -332.948493) (xy 396.564081 -332.901896) (xy 396.526508 -332.850181)
			(xy 396.495714 -332.794166) (xy 396.472182 -332.734733) (xy 396.456285 -332.672819) (xy 396.448274 -332.609401)
			(xy 395.704993 -332.609401) (xy 395.892981 -333.161343) (xy 397.879818 -333.161343) (xy 397.879818 -333.097421)
			(xy 397.887829 -333.034003) (xy 397.903726 -332.972089) (xy 397.927258 -332.912656) (xy 397.958052 -332.856641)
			(xy 397.995625 -332.804926) (xy 398.039382 -332.758329) (xy 398.088635 -332.717584) (xy 398.142606 -332.683333)
			(xy 398.200445 -332.656116) (xy 398.261238 -332.636363) (xy 398.324028 -332.624385) (xy 398.387824 -332.620372)
			(xy 398.45162 -332.624385) (xy 398.51441 -332.636363) (xy 398.575203 -332.656116) (xy 398.633042 -332.683333)
			(xy 398.687013 -332.717584) (xy 398.736266 -332.758329) (xy 398.780023 -332.804926) (xy 398.817596 -332.856641)
			(xy 398.84839 -332.912656) (xy 398.871922 -332.972089) (xy 398.887819 -333.034003) (xy 398.89583 -333.097421)
			(xy 398.896332 -333.129382) (xy 398.89583 -333.161343) (xy 398.887819 -333.224761) (xy 398.871922 -333.286675)
			(xy 398.84839 -333.346108) (xy 398.817596 -333.402123) (xy 398.780023 -333.453838) (xy 398.736266 -333.500435)
			(xy 398.687013 -333.54118) (xy 398.633042 -333.575431) (xy 398.57597 -333.602287) (xy 408.010608 -333.602287)
			(xy 408.010608 -333.538365) (xy 408.018619 -333.474947) (xy 408.034516 -333.413033) (xy 408.058048 -333.3536)
			(xy 408.088842 -333.297585) (xy 408.126415 -333.24587) (xy 408.170172 -333.199273) (xy 408.219425 -333.158528)
			(xy 408.273396 -333.124277) (xy 408.331235 -333.09706) (xy 408.392028 -333.077307) (xy 408.454818 -333.065329)
			(xy 408.518614 -333.061316) (xy 408.58241 -333.065329) (xy 408.6452 -333.077307) (xy 408.705993 -333.09706)
			(xy 408.763832 -333.124277) (xy 408.817803 -333.158528) (xy 408.867056 -333.199273) (xy 408.910813 -333.24587)
			(xy 408.948386 -333.297585) (xy 408.97918 -333.3536) (xy 409.002712 -333.413033) (xy 409.018609 -333.474947)
			(xy 409.02662 -333.538365) (xy 409.027122 -333.570326) (xy 409.02662 -333.602287) (xy 409.018609 -333.665705)
			(xy 409.002712 -333.727619) (xy 408.97918 -333.787052) (xy 408.948386 -333.843067) (xy 408.910813 -333.894782)
			(xy 408.867056 -333.941379) (xy 408.817803 -333.982124) (xy 408.763832 -334.016375) (xy 408.705993 -334.043592)
			(xy 408.6452 -334.063345) (xy 408.58241 -334.075323) (xy 408.518614 -334.079337) (xy 408.454818 -334.075323)
			(xy 408.392028 -334.063345) (xy 408.331235 -334.043592) (xy 408.273396 -334.016375) (xy 408.219425 -333.982124)
			(xy 408.170172 -333.941379) (xy 408.126415 -333.894782) (xy 408.088842 -333.843067) (xy 408.058048 -333.787052)
			(xy 408.034516 -333.727619) (xy 408.018619 -333.665705) (xy 408.010608 -333.602287) (xy 398.57597 -333.602287)
			(xy 398.575203 -333.602648) (xy 398.51441 -333.622401) (xy 398.45162 -333.634379) (xy 398.387824 -333.638393)
			(xy 398.324028 -333.634379) (xy 398.261238 -333.622401) (xy 398.200445 -333.602648) (xy 398.142606 -333.575431)
			(xy 398.088635 -333.54118) (xy 398.039382 -333.500435) (xy 397.995625 -333.453838) (xy 397.958052 -333.402123)
			(xy 397.927258 -333.346108) (xy 397.903726 -333.286675) (xy 397.887829 -333.224761) (xy 397.879818 -333.161343)
			(xy 395.892981 -333.161343) (xy 396.522448 -335.00949) (xy 396.524118 -335.013363) (xy 396.528585 -335.020518)
			(xy 396.531338 -335.023714) (xy 396.538196 -335.03108) (xy 396.538196 -336.102198) (xy 396.539212 -336.11185)
			(xy 396.540839 -336.119095) (xy 396.547678 -336.132266) (xy 396.552674 -336.137758) (xy 397.080994 -336.666078)
			(xy 397.085025 -336.670283) (xy 397.091183 -336.680166) (xy 397.093186 -336.685636) (xy 397.790016 -338.731606)
			(xy 407.775664 -338.731606) (xy 407.776142 -338.693364) (xy 407.783843 -338.61727) (xy 407.799128 -338.542329)
			(xy 407.821844 -338.469297) (xy 407.83637 -338.433918) (xy 407.83992 -338.424325) (xy 407.839923 -338.403886)
			(xy 407.83637 -338.394294) (xy 407.821865 -338.358908) (xy 407.799159 -338.285875) (xy 407.783874 -338.210937)
			(xy 407.776162 -338.134846) (xy 407.775664 -338.096606) (xy 407.776153 -338.057961) (xy 407.783973 -337.981067)
			(xy 407.799531 -337.905359) (xy 407.822669 -337.831613) (xy 407.853149 -337.760586) (xy 407.890658 -337.693008)
			(xy 407.934812 -337.62957) (xy 407.985157 -337.570926) (xy 408.041176 -337.517675) (xy 408.102295 -337.470365)
			(xy 408.167888 -337.429481) (xy 408.237279 -337.395443) (xy 408.309759 -337.3686) (xy 408.384582 -337.349227)
			(xy 408.460981 -337.337523) (xy 408.538172 -337.333608) (xy 408.615363 -337.337523) (xy 408.691762 -337.349227)
			(xy 408.766585 -337.3686) (xy 408.839065 -337.395443) (xy 408.908456 -337.429481) (xy 408.974049 -337.470365)
			(xy 409.035168 -337.517675) (xy 409.091187 -337.570926) (xy 409.141532 -337.62957) (xy 409.185686 -337.693008)
			(xy 409.223195 -337.760586) (xy 409.253675 -337.831613) (xy 409.276813 -337.905359) (xy 409.292371 -337.981067)
			(xy 409.300191 -338.057961) (xy 409.30068 -338.096606) (xy 409.300202 -338.134848) (xy 409.292501 -338.210942)
			(xy 409.277215 -338.285883) (xy 409.2545 -338.358915) (xy 409.239974 -338.394294) (xy 409.23642 -338.403886)
			(xy 409.236422 -338.424325) (xy 409.239974 -338.433918) (xy 409.25448 -338.469304) (xy 409.277186 -338.542337)
			(xy 409.292471 -338.617275) (xy 409.300182 -338.693366) (xy 409.30068 -338.731606) (xy 409.300191 -338.770251)
			(xy 409.292371 -338.847145) (xy 409.276813 -338.922853) (xy 409.253675 -338.996599) (xy 409.223195 -339.067626)
			(xy 409.185686 -339.135204) (xy 409.141532 -339.198642) (xy 409.091187 -339.257286) (xy 409.035168 -339.310537)
			(xy 408.974049 -339.357847) (xy 408.908456 -339.398731) (xy 408.839065 -339.432769) (xy 408.766585 -339.459612)
			(xy 408.691762 -339.478985) (xy 408.615363 -339.490689) (xy 408.538172 -339.494604) (xy 408.460981 -339.490689)
			(xy 408.384582 -339.478985) (xy 408.309759 -339.459612) (xy 408.237279 -339.432769) (xy 408.167888 -339.398731)
			(xy 408.102295 -339.357847) (xy 408.041176 -339.310537) (xy 407.985157 -339.257286) (xy 407.934812 -339.198642)
			(xy 407.890658 -339.135204) (xy 407.853149 -339.067626) (xy 407.822669 -338.996599) (xy 407.799531 -338.922853)
			(xy 407.783973 -338.847145) (xy 407.776153 -338.770251) (xy 407.775664 -338.731606) (xy 397.790016 -338.731606)
			(xy 397.836644 -338.868512) (xy 397.838651 -338.873822) (xy 397.84468 -338.883439) (xy 397.848582 -338.887562)
			(xy 398.633442 -339.672422) (xy 406.46807 -339.672422) (xy 406.472141 -339.6168) (xy 406.484267 -339.562363)
			(xy 406.50419 -339.510272) (xy 406.531486 -339.461637) (xy 406.565572 -339.417494) (xy 406.605721 -339.378785)
			(xy 406.651079 -339.346334) (xy 406.700679 -339.320833) (xy 406.753463 -339.302826) (xy 406.808306 -339.292696)
			(xy 406.86404 -339.290659) (xy 406.919477 -339.296759) (xy 406.973434 -339.310865) (xy 407.024763 -339.332677)
			(xy 407.072369 -339.361731) (xy 407.115237 -339.397406) (xy 407.152454 -339.438943) (xy 407.183227 -339.485456)
			(xy 407.206899 -339.535953) (xy 407.222967 -339.58936) (xy 407.231087 -339.644536) (xy 407.231596 -339.672422)
			(xy 407.231087 -339.700308) (xy 407.222967 -339.755484) (xy 407.206899 -339.808891) (xy 407.183227 -339.859388)
			(xy 407.152454 -339.905901) (xy 407.115237 -339.947438) (xy 407.072369 -339.983113) (xy 407.024763 -340.012167)
			(xy 406.973434 -340.033979) (xy 406.919477 -340.048085) (xy 406.86404 -340.054185) (xy 406.808306 -340.052148)
			(xy 406.753463 -340.042018) (xy 406.700679 -340.024011) (xy 406.651079 -339.99851) (xy 406.605721 -339.966059)
			(xy 406.565572 -339.92735) (xy 406.531486 -339.883207) (xy 406.50419 -339.834572) (xy 406.484267 -339.782481)
			(xy 406.472141 -339.728044) (xy 406.46807 -339.672422) (xy 398.633442 -339.672422) (xy 400.24939 -341.28837)
			(xy 400.26086 -341.299048) (xy 400.288666 -341.313465) (xy 400.319534 -341.318775) (xy 400.350558 -341.314476)
			(xy 400.37882 -341.300973) (xy 400.390614 -341.290656) (xy 400.397726 -341.282528) (xy 400.420241 -341.251199)
			(xy 400.47318 -341.19508) (xy 400.503136 -341.170768) (xy 400.51101 -341.163148) (xy 400.519996 -341.151614)
			(xy 400.53158 -341.124779) (xy 400.535096 -341.095763) (xy 400.530257 -341.066939) (xy 400.517459 -341.040662)
			(xy 400.507962 -341.029544) (xy 400.489286 -341.008339) (xy 400.457751 -340.961453) (xy 400.433477 -340.910429)
			(xy 400.416997 -340.856381) (xy 400.40867 -340.800494) (xy 400.40814 -340.772242) (xy 400.408626 -340.744973)
			(xy 400.416388 -340.690989) (xy 400.431753 -340.638659) (xy 400.45441 -340.589049) (xy 400.483896 -340.543168)
			(xy 400.519611 -340.501951) (xy 400.560828 -340.466236) (xy 400.606709 -340.43675) (xy 400.656319 -340.414093)
			(xy 400.708649 -340.398728) (xy 400.762633 -340.390966) (xy 400.817171 -340.390966) (xy 400.871155 -340.398728)
			(xy 400.923485 -340.414093) (xy 400.973095 -340.43675) (xy 401.018976 -340.466236) (xy 401.060193 -340.501951)
			(xy 401.095908 -340.543168) (xy 401.125394 -340.589049) (xy 401.148051 -340.638659) (xy 401.163416 -340.690989)
			(xy 401.171178 -340.744973) (xy 401.171664 -340.772242) (xy 401.171664 -340.772496) (xy 401.171071 -340.802579)
			(xy 401.161584 -340.861993) (xy 401.142907 -340.919188) (xy 401.1155 -340.972751) (xy 401.080041 -341.021358)
			(xy 401.059142 -341.043006) (xy 401.054824 -341.047578) (xy 401.04949 -341.060278) (xy 401.045356 -341.071508)
			(xy 401.046798 -341.095364) (xy 401.052284 -341.105998) (xy 401.057618 -341.114888) (xy 401.061056 -341.120354)
			(xy 401.070189 -341.129478) (xy 401.075652 -341.132922) (xy 401.078954 -341.134954) (xy 401.090638 -341.138002)
			(xy 401.095681 -341.139256) (xy 401.106052 -341.139891) (xy 401.111212 -341.139272) (xy 401.116038 -341.13851)
			(xy 401.118324 -341.137748) (xy 401.11934 -341.137494) (xy 401.155249 -341.127297) (xy 401.229084 -341.116336)
			(xy 401.266406 -341.11565) (xy 401.267168 -341.11565) (xy 401.297901 -341.116112) (xy 401.35892 -341.123517)
			(xy 401.418601 -341.138223) (xy 401.476075 -341.160015) (xy 401.530502 -341.188576) (xy 401.581091 -341.223489)
			(xy 401.627102 -341.264246) (xy 401.667865 -341.310251) (xy 401.702786 -341.360834) (xy 401.731355 -341.415258)
			(xy 401.753155 -341.472728) (xy 401.76787 -341.532407) (xy 401.775284 -341.593425) (xy 401.775676 -341.624158)
			(xy 401.775625 -341.636496) (xy 401.774481 -341.661145) (xy 401.77339 -341.673434) (xy 401.772374 -341.684356)
			(xy 401.775676 -341.694262) (xy 401.777462 -341.699352) (xy 401.782851 -341.708693) (xy 401.786344 -341.712804)
			(xy 401.837144 -341.76843) (xy 401.83816 -341.769446) (xy 401.84556 -341.776459) (xy 401.864298 -341.784445)
			(xy 401.874482 -341.78494) (xy 441.557918 -341.78494)
		)
		(stroke
			(width 0)
			(type solid)
		)
		(fill yes)
		(layer "In11.Cu")
		(net "PVDD11_S3_P0")
	)
	(gr_poly
		(pts
			(xy 63.550038 -336.91322) (xy 63.559914 -336.912757) (xy 63.578209 -336.905311) (xy 63.585598 -336.898742)
			(xy 63.585852 -336.898488) (xy 70.455282 -330.029058) (xy 70.462682 -330.022218) (xy 70.481281 -330.014505)
			(xy 70.49135 -330.014072) (xy 76.234544 -330.014072) (xy 76.244611 -330.014502) (xy 76.263207 -330.022225)
			(xy 76.270612 -330.029058) (xy 76.286868 -330.045314) (xy 76.294266 -330.052159) (xy 76.312865 -330.059882)
			(xy 76.322936 -330.0603) (xy 78.487778 -330.0603) (xy 78.49765 -330.059829) (xy 78.515933 -330.052371)
			(xy 78.523338 -330.045822) (xy 78.523592 -330.045568) (xy 81.105502 -327.463658) (xy 81.112898 -327.456805)
			(xy 81.131496 -327.449063) (xy 81.14157 -327.448672) (xy 94.749112 -327.448672) (xy 94.758989 -327.448213)
			(xy 94.777287 -327.440768) (xy 94.784672 -327.434194) (xy 94.784926 -327.43394) (xy 94.787974 -327.430892)
			(xy 94.796864 -327.427082) (xy 94.801492 -327.425307) (xy 94.811213 -327.423383) (xy 94.816168 -327.423272)
			(xy 97.985072 -327.423272) (xy 97.99447 -327.419462) (xy 97.999097 -327.417685) (xy 98.008819 -327.415759)
			(xy 98.013774 -327.415652) (xy 99.646486 -327.415652) (xy 99.656359 -327.415181) (xy 99.674645 -327.407726)
			(xy 99.682046 -327.401174) (xy 99.6823 -327.40092) (xy 100.668074 -326.415146) (xy 100.674915 -326.407746)
			(xy 100.682633 -326.389147) (xy 100.68306 -326.379078) (xy 100.68306 -324.88759) (xy 100.682044 -324.88251)
			(xy 100.675675 -324.84873) (xy 100.671026 -324.780147) (xy 100.675663 -324.711563) (xy 100.682044 -324.677786)
			(xy 100.68306 -324.672706) (xy 100.68306 -324.25259) (xy 100.682044 -324.24751) (xy 100.675675 -324.21373)
			(xy 100.671026 -324.145147) (xy 100.675663 -324.076563) (xy 100.682044 -324.042786) (xy 100.68306 -324.037706)
			(xy 100.68306 -323.61759) (xy 100.682044 -323.61251) (xy 100.675675 -323.57873) (xy 100.671026 -323.510147)
			(xy 100.675663 -323.441563) (xy 100.682044 -323.407786) (xy 100.68306 -323.402706) (xy 100.68306 -322.98259)
			(xy 100.682044 -322.97751) (xy 100.675675 -322.94373) (xy 100.671026 -322.875147) (xy 100.675663 -322.806563)
			(xy 100.682044 -322.772786) (xy 100.68306 -322.767706) (xy 100.68306 -322.34759) (xy 100.682044 -322.34251)
			(xy 100.675675 -322.30873) (xy 100.671026 -322.240147) (xy 100.675663 -322.171563) (xy 100.682044 -322.137786)
			(xy 100.68306 -322.132706) (xy 100.68306 -321.71259) (xy 100.682044 -321.70751) (xy 100.675675 -321.67373)
			(xy 100.671026 -321.605147) (xy 100.675663 -321.536563) (xy 100.682044 -321.502786) (xy 100.68306 -321.497706)
			(xy 100.68306 -311.044082) (xy 100.678742 -311.029604) (xy 100.674424 -311.023254) (xy 100.249228 -310.38673)
			(xy 100.243894 -310.378602) (xy 100.24364 -310.378348) (xy 100.240846 -310.37403) (xy 100.221034 -310.344058)
			(xy 100.219002 -310.33974) (xy 100.218748 -310.338724) (xy 100.204524 -310.304688) (xy 100.20427 -310.30418)
			(xy 100.193348 -310.278018) (xy 100.193094 -310.277256) (xy 96.466914 -301.281338) (xy 96.461546 -301.269995)
			(xy 96.442229 -301.254024) (xy 96.430084 -301.250858) (xy 96.334834 -301.231808) (xy 96.310704 -301.23892)
			(xy 96.30156 -301.248064) (xy 96.279985 -301.268625) (xy 96.231637 -301.30347) (xy 96.178461 -301.330377)
			(xy 96.121749 -301.348691) (xy 96.06288 -301.357967) (xy 96.033082 -301.358554) (xy 96.00583 -301.358067)
			(xy 95.951882 -301.350309) (xy 95.899587 -301.334952) (xy 95.850009 -301.312311) (xy 95.804158 -301.282845)
			(xy 95.762966 -301.247154) (xy 95.727272 -301.205965) (xy 95.697803 -301.160116) (xy 95.675157 -301.110539)
			(xy 95.659797 -301.058245) (xy 95.652035 -301.004298) (xy 95.651574 -300.977046) (xy 95.652051 -300.949873)
			(xy 95.659756 -300.896076) (xy 95.675018 -300.843916) (xy 95.697526 -300.79445) (xy 95.726826 -300.748679)
			(xy 95.762324 -300.707529) (xy 95.803303 -300.671832) (xy 95.848932 -300.642311) (xy 95.898289 -300.619564)
			(xy 95.950374 -300.604051) (xy 96.004133 -300.596086) (xy 96.031304 -300.595538) (xy 96.044258 -300.595538)
			(xy 96.066356 -300.5836) (xy 96.120204 -300.502574) (xy 96.126543 -300.491779) (xy 96.128933 -300.466886)
			(xy 96.124776 -300.455076) (xy 95.894652 -299.899578) (xy 95.880695 -299.864293) (xy 95.861031 -299.791004)
			(xy 95.851098 -299.715776) (xy 95.850456 -299.677836) (xy 95.850456 -296.281348) (xy 95.850744 -296.25523)
			(xy 95.855453 -296.203208) (xy 95.859854 -296.177462) (xy 95.86214 -296.164762) (xy 95.852234 -296.133774)
			(xy 95.84817 -296.127678) (xy 95.835821 -296.10864) (xy 95.816276 -296.067689) (xy 95.802995 -296.0243)
			(xy 95.796271 -295.979424) (xy 95.795846 -295.956736) (xy 95.795846 -295.956228) (xy 95.796297 -295.932141)
			(xy 95.803857 -295.884565) (xy 95.818793 -295.838766) (xy 95.840735 -295.79588) (xy 95.869139 -295.756971)
			(xy 95.9033 -295.723005) (xy 95.922592 -295.708578) (xy 95.9231 -295.708324) (xy 95.92818 -295.704514)
			(xy 95.936054 -295.695116) (xy 95.941896 -295.683686) (xy 95.942912 -295.680638) (xy 95.953837 -295.651221)
			(xy 95.981307 -295.594797) (xy 96.014862 -295.541766) (xy 96.054087 -295.49278) (xy 96.076008 -295.470326)
			(xy 96.262698 -295.283636) (xy 96.269535 -295.276234) (xy 96.277246 -295.257636) (xy 96.277684 -295.247568)
			(xy 96.277684 -295.23182) (xy 96.275906 -295.22547) (xy 96.271044 -295.20602) (xy 96.265822 -295.166268)
			(xy 96.265492 -295.146222) (xy 96.265939 -295.12218) (xy 96.273468 -295.07469) (xy 96.288342 -295.028966)
			(xy 96.310196 -294.986136) (xy 96.338489 -294.947258) (xy 96.372523 -294.913292) (xy 96.39173 -294.898826)
			(xy 96.394778 -294.896794) (xy 96.399096 -294.89273) (xy 96.402387 -294.889497) (xy 96.407888 -294.88209)
			(xy 96.410018 -294.877998) (xy 96.414844 -294.867838) (xy 96.416114 -294.862758) (xy 96.430874 -294.808655)
			(xy 96.469685 -294.703433) (xy 96.493584 -294.6527) (xy 96.496124 -294.64762) (xy 96.498664 -294.636444)
			(xy 96.498664 -294.615616) (xy 96.49821 -294.605479) (xy 96.490357 -294.586785) (xy 96.475901 -294.572567)
			(xy 96.46666 -294.568372) (xy 96.364552 -294.527478) (xy 96.334072 -294.534082) (xy 96.323404 -294.545766)
			(xy 96.305955 -294.563534) (xy 96.266352 -294.59372) (xy 96.222376 -294.617082) (xy 96.175193 -294.633001)
			(xy 96.126052 -294.641055) (xy 96.101154 -294.641524) (xy 96.0759 -294.640999) (xy 96.026081 -294.632679)
			(xy 95.978312 -294.616273) (xy 95.933893 -294.592229) (xy 95.894038 -294.561203) (xy 95.859832 -294.52404)
			(xy 95.832209 -294.481754) (xy 95.811921 -294.435499) (xy 95.799524 -294.386536) (xy 95.795353 -294.3362)
			(xy 95.799524 -294.285864) (xy 95.811921 -294.236901) (xy 95.832209 -294.190646) (xy 95.859832 -294.14836)
			(xy 95.894038 -294.111197) (xy 95.933893 -294.080171) (xy 95.978312 -294.056127) (xy 96.026081 -294.039721)
			(xy 96.0759 -294.031401) (xy 96.101154 -294.030908) (xy 96.126055 -294.031373) (xy 96.175204 -294.039405)
			(xy 96.222396 -294.055314) (xy 96.266378 -294.078675) (xy 96.305981 -294.10887) (xy 96.323404 -294.126666)
			(xy 96.334072 -294.13835) (xy 96.364552 -294.144954) (xy 96.46666 -294.10406) (xy 96.469454 -294.10279)
			(xy 96.477977 -294.098323) (xy 96.491139 -294.084306) (xy 96.498219 -294.06643) (xy 96.498664 -294.056816)
			(xy 96.498664 -294.035988) (xy 96.496124 -294.025066) (xy 96.493584 -294.019732) (xy 96.485456 -294.00246)
			(xy 96.464314 -293.955717) (xy 96.429591 -293.859174) (xy 96.416114 -293.809674) (xy 96.414844 -293.804594)
			(xy 96.40951 -293.793672) (xy 96.407406 -293.789562) (xy 96.401917 -293.782139) (xy 96.398588 -293.77894)
			(xy 96.395286 -293.775892) (xy 96.392746 -293.774114) (xy 96.373444 -293.759652) (xy 96.339223 -293.725666)
			(xy 96.310766 -293.686727) (xy 96.288781 -293.643799) (xy 96.273813 -293.597951) (xy 96.266234 -293.550321)
			(xy 96.266233 -293.502091) (xy 96.27381 -293.45446) (xy 96.288776 -293.408611) (xy 96.31076 -293.365683)
			(xy 96.339215 -293.326742) (xy 96.373435 -293.292756) (xy 96.392746 -293.278306) (xy 96.395286 -293.276528)
			(xy 96.398588 -293.27348) (xy 96.401877 -293.270245) (xy 96.407371 -293.262835) (xy 96.40951 -293.258748)
			(xy 96.414844 -293.247826) (xy 96.416114 -293.242746) (xy 96.429591 -293.193246) (xy 96.464314 -293.096703)
			(xy 96.485456 -293.04996) (xy 96.493584 -293.032688) (xy 96.496124 -293.027354) (xy 96.498664 -293.016432)
			(xy 96.498664 -293.000938) (xy 96.498234 -292.99086) (xy 96.490458 -292.972264) (xy 96.476099 -292.958119)
			(xy 96.466914 -292.953948) (xy 96.37141 -292.91534) (xy 96.34093 -292.921944) (xy 96.330008 -292.933374)
			(xy 96.312011 -292.951617) (xy 96.271197 -292.982601) (xy 96.225911 -293.00658) (xy 96.177345 -293.022923)
			(xy 96.126775 -293.031199) (xy 96.101154 -293.031672) (xy 96.076366 -293.031183) (xy 96.027403 -293.023421)
			(xy 95.980255 -293.008096) (xy 95.936086 -292.985585) (xy 95.895981 -292.956441) (xy 95.860929 -292.921384)
			(xy 95.831791 -292.881275) (xy 95.809287 -292.837102) (xy 95.793968 -292.789953) (xy 95.786214 -292.740988)
			(xy 95.786214 -292.691412) (xy 95.793968 -292.642447) (xy 95.809287 -292.595298) (xy 95.831791 -292.551125)
			(xy 95.860929 -292.511016) (xy 95.895981 -292.475959) (xy 95.936086 -292.446815) (xy 95.980255 -292.424304)
			(xy 96.027403 -292.408979) (xy 96.076366 -292.401217) (xy 96.101154 -292.400736) (xy 96.126773 -292.401239)
			(xy 96.177336 -292.409523) (xy 96.225898 -292.425864) (xy 96.271183 -292.449834) (xy 96.312002 -292.480803)
			(xy 96.330008 -292.499034) (xy 96.34093 -292.510464) (xy 96.37141 -292.517068) (xy 96.466914 -292.47846)
			(xy 96.468946 -292.477698) (xy 96.476845 -292.473681) (xy 96.489492 -292.461286) (xy 96.497155 -292.445323)
			(xy 96.49841 -292.43655) (xy 96.498664 -292.43147) (xy 96.498664 -292.415976) (xy 96.496124 -292.405054)
			(xy 96.493584 -292.39972) (xy 96.485456 -292.382448) (xy 96.464315 -292.335705) (xy 96.429592 -292.239162)
			(xy 96.416114 -292.189662) (xy 96.414844 -292.184582) (xy 96.40951 -292.17366) (xy 96.407405 -292.169551)
			(xy 96.401915 -292.162129) (xy 96.398588 -292.158928) (xy 96.395286 -292.15588) (xy 96.392746 -292.154102)
			(xy 96.373445 -292.13964) (xy 96.339225 -292.105655) (xy 96.31077 -292.066716) (xy 96.288787 -292.023789)
			(xy 96.273821 -291.977942) (xy 96.266244 -291.930313) (xy 96.266244 -291.882085) (xy 96.273821 -291.834456)
			(xy 96.288788 -291.788609) (xy 96.310772 -291.745683) (xy 96.339227 -291.706743) (xy 96.373447 -291.672759)
			(xy 96.392746 -291.658294) (xy 96.395286 -291.656516) (xy 96.398588 -291.653468) (xy 96.401876 -291.650233)
			(xy 96.407369 -291.642822) (xy 96.40951 -291.638736) (xy 96.414844 -291.627814) (xy 96.416114 -291.622734)
			(xy 96.429591 -291.573234) (xy 96.464315 -291.476691) (xy 96.485456 -291.429948) (xy 96.493584 -291.412676)
			(xy 96.496124 -291.407342) (xy 96.498664 -291.39642) (xy 96.498664 -291.380926) (xy 96.498249 -291.370838)
			(xy 96.490492 -291.352215) (xy 96.476135 -291.338042) (xy 96.466914 -291.333936) (xy 96.37141 -291.295328)
			(xy 96.34093 -291.301932) (xy 96.330008 -291.313362) (xy 96.312011 -291.331606) (xy 96.271198 -291.362591)
			(xy 96.225912 -291.386571) (xy 96.177345 -291.402914) (xy 96.126775 -291.411191) (xy 96.101154 -291.41166)
			(xy 96.076367 -291.41117) (xy 96.027405 -291.403409) (xy 95.98026 -291.388084) (xy 95.936092 -291.365574)
			(xy 95.895989 -291.336432) (xy 95.860938 -291.301376) (xy 95.831802 -291.261268) (xy 95.809298 -291.217097)
			(xy 95.793981 -291.16995) (xy 95.786226 -291.120987) (xy 95.786226 -291.071413) (xy 95.793981 -291.02245)
			(xy 95.809298 -290.975303) (xy 95.831802 -290.931132) (xy 95.860938 -290.891024) (xy 95.895989 -290.855968)
			(xy 95.936092 -290.826826) (xy 95.98026 -290.804316) (xy 96.027405 -290.788991) (xy 96.076367 -290.78123)
			(xy 96.101154 -290.780724) (xy 96.126773 -290.781227) (xy 96.177337 -290.78951) (xy 96.225899 -290.805851)
			(xy 96.271184 -290.829821) (xy 96.312004 -290.860789) (xy 96.330008 -290.879022) (xy 96.34093 -290.890452)
			(xy 96.37141 -290.897056) (xy 96.466914 -290.858448) (xy 96.468946 -290.857686) (xy 96.476844 -290.853669)
			(xy 96.489488 -290.841273) (xy 96.497147 -290.825309) (xy 96.49841 -290.816538) (xy 96.498664 -290.811458)
			(xy 96.498664 -290.795964) (xy 96.496124 -290.785042) (xy 96.493584 -290.779708) (xy 96.485456 -290.762436)
			(xy 96.464311 -290.715694) (xy 96.429582 -290.619153) (xy 96.416114 -290.56965) (xy 96.414844 -290.56457)
			(xy 96.40951 -290.553648) (xy 96.407404 -290.549539) (xy 96.401913 -290.542119) (xy 96.398588 -290.538916)
			(xy 96.395286 -290.535868) (xy 96.392746 -290.53409) (xy 96.373446 -290.519628) (xy 96.339228 -290.485643)
			(xy 96.310775 -290.446704) (xy 96.288793 -290.403779) (xy 96.273829 -290.357933) (xy 96.266253 -290.310305)
			(xy 96.266254 -290.262079) (xy 96.273832 -290.214451) (xy 96.288799 -290.168606) (xy 96.310784 -290.125682)
			(xy 96.339239 -290.086744) (xy 96.373458 -290.052762) (xy 96.392746 -290.038282) (xy 96.395286 -290.036504)
			(xy 96.398588 -290.033456) (xy 96.401876 -290.03022) (xy 96.407367 -290.022809) (xy 96.40951 -290.018724)
			(xy 96.414844 -290.007802) (xy 96.416114 -290.002722) (xy 96.429592 -289.953222) (xy 96.464316 -289.85668)
			(xy 96.485456 -289.809936) (xy 96.493584 -289.792664) (xy 96.496124 -289.78733) (xy 96.498664 -289.776408)
			(xy 96.498664 -289.760914) (xy 96.498247 -289.750827) (xy 96.490487 -289.732208) (xy 96.47613 -289.718039)
			(xy 96.466914 -289.713924) (xy 96.37141 -289.675316) (xy 96.34093 -289.68192) (xy 96.330008 -289.69335)
			(xy 96.312012 -289.711594) (xy 96.271199 -289.742581) (xy 96.225913 -289.766561) (xy 96.177346 -289.782905)
			(xy 96.126776 -289.791182) (xy 96.101154 -289.791648) (xy 96.076368 -289.791158) (xy 96.027408 -289.783397)
			(xy 95.980265 -289.768073) (xy 95.936099 -289.745564) (xy 95.895997 -289.716423) (xy 95.860947 -289.681368)
			(xy 95.831812 -289.641262) (xy 95.809309 -289.597093) (xy 95.793992 -289.549947) (xy 95.786238 -289.500986)
			(xy 95.786238 -289.451414) (xy 95.793992 -289.402453) (xy 95.809309 -289.355307) (xy 95.831812 -289.311138)
			(xy 95.860947 -289.271032) (xy 95.895997 -289.235977) (xy 95.936099 -289.206836) (xy 95.980265 -289.184327)
			(xy 96.027408 -289.169003) (xy 96.076368 -289.161242) (xy 96.101154 -289.160712) (xy 96.126772 -289.161215)
			(xy 96.177334 -289.1695) (xy 96.225893 -289.185845) (xy 96.271175 -289.209819) (xy 96.311988 -289.240793)
			(xy 96.330008 -289.25901) (xy 96.34093 -289.27044) (xy 96.37141 -289.277044) (xy 96.466914 -289.238436)
			(xy 96.468946 -289.237674) (xy 96.476843 -289.233656) (xy 96.489484 -289.22126) (xy 96.49714 -289.205296)
			(xy 96.49841 -289.196526) (xy 96.498664 -289.191446) (xy 96.498664 -289.175952) (xy 96.496124 -289.16503)
			(xy 96.493584 -289.159696) (xy 96.477328 -289.12439) (xy 96.461979 -289.089077) (xy 96.435541 -289.016751)
			(xy 96.424496 -288.979864) (xy 96.421604 -288.971154) (xy 96.410676 -288.956427) (xy 96.40316 -288.951162)
			(xy 96.380651 -288.937295) (xy 96.339955 -288.903551) (xy 96.305145 -288.863764) (xy 96.277107 -288.818946)
			(xy 96.256554 -288.77024) (xy 96.24401 -288.718884) (xy 96.239794 -288.666187) (xy 96.244014 -288.61349)
			(xy 96.256562 -288.562135) (xy 96.277119 -288.51343) (xy 96.305161 -288.468615) (xy 96.339974 -288.42883)
			(xy 96.380672 -288.39509) (xy 96.40316 -288.381186) (xy 96.410659 -288.375901) (xy 96.421594 -288.361187)
			(xy 96.424496 -288.352484) (xy 96.435535 -288.315596) (xy 96.461976 -288.24327) (xy 96.477328 -288.207958)
			(xy 96.493584 -288.172652) (xy 96.496124 -288.167318) (xy 96.498664 -288.156396) (xy 96.498664 -288.125916)
			(xy 96.481392 -288.100008) (xy 96.37141 -288.055558) (xy 96.34093 -288.062162) (xy 96.330008 -288.073592)
			(xy 96.312013 -288.091849) (xy 96.271204 -288.122869) (xy 96.225924 -288.146894) (xy 96.177359 -288.163295)
			(xy 96.126783 -288.171642) (xy 96.101154 -288.172144) (xy 96.076345 -288.171654) (xy 96.027339 -288.163885)
			(xy 95.980151 -288.148547) (xy 95.935944 -288.126016) (xy 95.895804 -288.096848) (xy 95.860722 -288.06176)
			(xy 95.831559 -288.021617) (xy 95.809035 -287.977406) (xy 95.793704 -287.930216) (xy 95.785943 -287.881209)
			(xy 95.785943 -287.831591) (xy 95.793704 -287.782584) (xy 95.809035 -287.735394) (xy 95.831559 -287.691183)
			(xy 95.860722 -287.65104) (xy 95.895804 -287.615952) (xy 95.935944 -287.586784) (xy 95.980151 -287.564253)
			(xy 96.027339 -287.548915) (xy 96.076345 -287.541146) (xy 96.101154 -287.5407) (xy 96.126786 -287.541213)
			(xy 96.177373 -287.549526) (xy 96.22595 -287.565909) (xy 96.27124 -287.589929) (xy 96.31205 -287.620956)
			(xy 96.330008 -287.639252) (xy 96.34093 -287.650682) (xy 96.37141 -287.657286) (xy 96.466914 -287.618678)
			(xy 96.468946 -287.617916) (xy 96.476847 -287.6139) (xy 96.489498 -287.601506) (xy 96.497166 -287.585543)
			(xy 96.49841 -287.576768) (xy 96.498664 -287.571688) (xy 96.498664 -287.55594) (xy 96.496124 -287.545018)
			(xy 96.493584 -287.539684) (xy 96.47428 -287.498028) (xy 96.456833 -287.456921) (xy 96.427714 -287.372495)
			(xy 96.416114 -287.329372) (xy 96.414844 -287.324546) (xy 96.410272 -287.315148) (xy 96.408194 -287.310909)
			(xy 96.4027 -287.303234) (xy 96.39935 -287.299908) (xy 96.394778 -287.29559) (xy 96.391984 -287.293558)
			(xy 96.372116 -287.278577) (xy 96.337072 -287.243257) (xy 96.308224 -287.202718) (xy 96.286337 -287.158034)
			(xy 96.271991 -287.110391) (xy 96.268286 -287.085786) (xy 96.26727 -287.077912) (xy 96.252792 -287.046924)
			(xy 96.246188 -287.040574) (xy 96.210576 -287.004574) (xy 96.145218 -286.927218) (xy 96.087045 -286.844323)
			(xy 96.036523 -286.756556) (xy 95.994058 -286.664619) (xy 95.95999 -286.569251) (xy 95.946722 -286.520382)
			(xy 95.942404 -286.509206) (xy 95.922261 -286.497001) (xy 95.885506 -286.467553) (xy 95.853539 -286.432966)
			(xy 95.827071 -286.39401) (xy 95.806691 -286.351551) (xy 95.792852 -286.306534) (xy 95.785861 -286.259959)
			(xy 95.785432 -286.23641) (xy 95.785886 -286.212894) (xy 95.792903 -286.166387) (xy 95.806738 -286.121435)
			(xy 95.827086 -286.079031) (xy 95.853497 -286.040113) (xy 95.885386 -286.005542) (xy 95.922049 -285.976082)
			(xy 95.94215 -285.963868) (xy 95.946722 -285.952184) (xy 95.959117 -285.906481) (xy 95.990574 -285.817156)
			(xy 96.029417 -285.730787) (xy 96.075374 -285.647983) (xy 96.128119 -285.569329) (xy 96.18728 -285.49538)
			(xy 96.219518 -285.460694) (xy 96.219772 -285.46044) (xy 96.226122 -285.453582) (xy 96.240346 -285.4198)
			(xy 96.2406 -285.41091) (xy 96.242407 -285.383611) (xy 96.253916 -285.330128) (xy 96.274074 -285.279269)
			(xy 96.30233 -285.232424) (xy 96.337912 -285.190869) (xy 96.379851 -285.15574) (xy 96.40316 -285.141416)
			(xy 96.410662 -285.136133) (xy 96.421605 -285.121422) (xy 96.424496 -285.112714) (xy 96.435535 -285.075825)
			(xy 96.461973 -285.003499) (xy 96.477328 -284.968188) (xy 96.493584 -284.932882) (xy 96.496124 -284.927548)
			(xy 96.498664 -284.916626) (xy 96.498664 -284.901132) (xy 96.49825 -284.891043) (xy 96.490494 -284.872418)
			(xy 96.476137 -284.858244) (xy 96.466914 -284.854142) (xy 96.37141 -284.815534) (xy 96.34093 -284.822138)
			(xy 96.330008 -284.833568) (xy 96.312014 -284.851827) (xy 96.271206 -284.882848) (xy 96.225925 -284.906875)
			(xy 96.17736 -284.923278) (xy 96.126784 -284.931625) (xy 96.101154 -284.93212) (xy 96.076347 -284.93163)
			(xy 96.027345 -284.923862) (xy 95.980161 -284.908525) (xy 95.935956 -284.885996) (xy 95.89582 -284.85683)
			(xy 95.86074 -284.821745) (xy 95.83158 -284.781604) (xy 95.809057 -284.737397) (xy 95.793727 -284.690211)
			(xy 95.785967 -284.641207) (xy 95.785967 -284.591593) (xy 95.793727 -284.542589) (xy 95.809057 -284.495403)
			(xy 95.83158 -284.451196) (xy 95.86074 -284.411055) (xy 95.89582 -284.37597) (xy 95.935956 -284.346804)
			(xy 95.980161 -284.324275) (xy 96.027345 -284.308938) (xy 96.076347 -284.30117) (xy 96.101154 -284.300676)
			(xy 96.126786 -284.301189) (xy 96.177371 -284.309504) (xy 96.225946 -284.325889) (xy 96.271231 -284.349914)
			(xy 96.312036 -284.380946) (xy 96.330008 -284.399228) (xy 96.34093 -284.410658) (xy 96.37141 -284.417262)
			(xy 96.466914 -284.378654) (xy 96.468946 -284.377892) (xy 96.476845 -284.373875) (xy 96.48949 -284.36148)
			(xy 96.497151 -284.345516) (xy 96.49841 -284.336744) (xy 96.498664 -284.331664) (xy 96.498664 -284.31617)
			(xy 96.496124 -284.305248) (xy 96.493584 -284.299914) (xy 96.470075 -284.249956) (xy 96.43178 -284.146392)
			(xy 96.41713 -284.093158) (xy 96.414844 -284.084522) (xy 96.402652 -284.066742) (xy 96.397572 -284.060392)
			(xy 96.388936 -284.051502) (xy 96.385888 -284.049216) (xy 96.365908 -284.033313) (xy 96.331041 -283.996007)
			(xy 96.302862 -283.953424) (xy 96.282154 -283.906749) (xy 96.269495 -283.85728) (xy 96.265236 -283.806395)
			(xy 96.269496 -283.75551) (xy 96.282157 -283.706042) (xy 96.302866 -283.659368) (xy 96.331047 -283.616785)
			(xy 96.365915 -283.579481) (xy 96.385888 -283.563568) (xy 96.388936 -283.561282) (xy 96.397572 -283.552392)
			(xy 96.402652 -283.546042) (xy 96.414844 -283.528262) (xy 96.41713 -283.519626) (xy 96.430802 -283.469725)
			(xy 96.466061 -283.372443) (xy 96.510063 -283.278791) (xy 96.535748 -283.233876) (xy 96.539304 -283.22778)
			(xy 96.54286 -283.21508) (xy 96.54286 -282.777692) (xy 96.539304 -282.764992) (xy 96.535748 -282.758896)
			(xy 96.52036 -282.732277) (xy 96.49215 -282.677636) (xy 96.47936 -282.649676) (xy 96.47555 -282.64104)
			(xy 96.337882 -282.503372) (xy 96.331031 -282.495976) (xy 96.323294 -282.477377) (xy 96.322896 -282.467304)
			(xy 96.322896 -282.414472) (xy 96.317308 -282.398724) (xy 96.311974 -282.391866) (xy 96.29517 -282.369792)
			(xy 96.268417 -282.321196) (xy 96.25016 -282.268813) (xy 96.240911 -282.214117) (xy 96.240346 -282.18638)
			(xy 96.240778 -282.161968) (xy 96.247948 -282.113674) (xy 96.262143 -282.066961) (xy 96.283056 -282.022843)
			(xy 96.31023 -281.982281) (xy 96.343075 -281.946158) (xy 96.380876 -281.915258) (xy 96.401636 -281.902408)
			(xy 96.40971 -281.89713) (xy 96.421447 -281.881843) (xy 96.424496 -281.87269) (xy 96.439114 -281.824189)
			(xy 96.475861 -281.729781) (xy 96.52091 -281.639042) (xy 96.546924 -281.595576) (xy 96.55048 -281.58948)
			(xy 96.55429 -281.576272) (xy 96.55429 -281.234642) (xy 96.553856 -281.224577) (xy 96.546126 -281.205989)
			(xy 96.539304 -281.198574) (xy 96.13011 -280.78938) (xy 96.123266 -280.781981) (xy 96.115537 -280.763383)
			(xy 96.115124 -280.753312) (xy 96.115124 -280.532586) (xy 96.114699 -280.522516) (xy 96.106984 -280.503913)
			(xy 96.100138 -280.496518) (xy 96.012508 -280.408888) (xy 96.005061 -280.4022) (xy 95.986565 -280.394604)
			(xy 95.966569 -280.394604) (xy 95.948073 -280.4022) (xy 95.940626 -280.408888) (xy 95.930466 -280.419302)
			(xy 95.923862 -280.44775) (xy 95.928688 -280.46172) (xy 95.936993 -280.487081) (xy 95.945936 -280.539687)
			(xy 95.946468 -280.566368) (xy 95.946009 -280.59116) (xy 95.938258 -280.640135) (xy 95.92294 -280.687294)
			(xy 95.900433 -280.731475) (xy 95.871292 -280.771593) (xy 95.836233 -280.806657) (xy 95.796121 -280.835805)
			(xy 95.751943 -280.858319) (xy 95.704787 -280.873645) (xy 95.655813 -280.881405) (xy 95.606229 -280.881409)
			(xy 95.557255 -280.873655) (xy 95.510097 -280.858336) (xy 95.465915 -280.835827) (xy 95.425799 -280.806685)
			(xy 95.390736 -280.771625) (xy 95.361589 -280.731512) (xy 95.339077 -280.687333) (xy 95.323752 -280.640176)
			(xy 95.315994 -280.591203) (xy 95.315992 -280.541619) (xy 95.323747 -280.492645) (xy 95.339069 -280.445487)
			(xy 95.361578 -280.401306) (xy 95.390722 -280.361191) (xy 95.425783 -280.326129) (xy 95.465897 -280.296984)
			(xy 95.510077 -280.274473) (xy 95.557234 -280.25915) (xy 95.606208 -280.251393) (xy 95.631 -280.2509)
			(xy 95.639128 -280.2509) (xy 95.645891 -280.25086) (xy 95.659023 -280.247645) (xy 95.665036 -280.24455)
			(xy 95.67662 -280.237673) (xy 95.695955 -280.218928) (xy 95.709703 -280.195771) (xy 95.716903 -280.169821)
			(xy 95.717051 -280.142891) (xy 95.710137 -280.116863) (xy 95.696645 -280.093556) (xy 95.687388 -280.083768)
			(xy 95.580708 -279.977088) (xy 95.573863 -279.969689) (xy 95.566131 -279.951091) (xy 95.565722 -279.94102)
			(xy 95.565722 -279.823418) (xy 95.538036 -279.794208) (xy 95.517716 -279.793192) (xy 95.491046 -279.791668)
			(xy 95.461582 -279.813258) (xy 95.457264 -279.831038) (xy 95.450553 -279.85541) (xy 95.430248 -279.901701)
			(xy 95.402603 -279.944019) (xy 95.368371 -279.981212) (xy 95.328486 -280.012265) (xy 95.284035 -280.036331)
			(xy 95.23623 -280.052755) (xy 95.186374 -280.061089) (xy 95.1611 -280.06167) (xy 95.135848 -280.061149)
			(xy 95.086032 -280.052836) (xy 95.038264 -280.036437) (xy 94.993847 -280.0124) (xy 94.953992 -279.981379)
			(xy 94.919786 -279.944222) (xy 94.892163 -279.901941) (xy 94.871876 -279.855691) (xy 94.859478 -279.806732)
			(xy 94.855307 -279.7564) (xy 94.859478 -279.706068) (xy 94.871876 -279.657109) (xy 94.892163 -279.610859)
			(xy 94.919786 -279.568578) (xy 94.953992 -279.531421) (xy 94.993847 -279.5004) (xy 95.038264 -279.476363)
			(xy 95.086032 -279.459964) (xy 95.135848 -279.451651) (xy 95.1611 -279.451054) (xy 95.186385 -279.45154)
			(xy 95.236267 -279.459853) (xy 95.284099 -279.476267) (xy 95.328575 -279.500335) (xy 95.368479 -279.531399)
			(xy 95.402722 -279.568612) (xy 95.430368 -279.610955) (xy 95.450663 -279.657274) (xy 95.457264 -279.681686)
			(xy 95.461582 -279.699466) (xy 95.491046 -279.721056) (xy 95.517716 -279.719532) (xy 95.524066 -279.71877)
			(xy 95.532712 -279.716809) (xy 95.54801 -279.707878) (xy 95.559338 -279.69426) (xy 95.565334 -279.677591)
			(xy 95.565722 -279.668732) (xy 95.565722 -279.551638) (xy 95.566157 -279.541573) (xy 95.57389 -279.522987)
			(xy 95.580708 -279.51557) (xy 95.613474 -279.482804) (xy 95.620876 -279.475969) (xy 95.639475 -279.468261)
			(xy 95.649542 -279.467818) (xy 95.877888 -279.467818) (xy 95.88796 -279.467398) (xy 95.906569 -279.459688)
			(xy 95.913956 -279.452832) (xy 95.96374 -279.403048) (xy 95.96755 -279.391872) (xy 95.984376 -279.344427)
			(xy 96.025353 -279.252469) (xy 96.07439 -279.164545) (xy 96.131092 -279.081357) (xy 96.162622 -279.042114)
			(xy 96.183153 -279.017489) (xy 96.226614 -278.970344) (xy 96.24949 -278.94788) (xy 96.25203 -278.945594)
			(xy 96.260412 -278.93518) (xy 96.263206 -278.926798) (xy 96.26727 -278.91486) (xy 96.268032 -278.909526)
			(xy 96.271446 -278.885412) (xy 96.284925 -278.838616) (xy 96.305652 -278.794548) (xy 96.333104 -278.754324)
			(xy 96.366585 -278.71896) (xy 96.385634 -278.703786) (xy 96.388682 -278.7015) (xy 96.397572 -278.692356)
			(xy 96.402652 -278.686006) (xy 96.414844 -278.668226) (xy 96.41713 -278.65959) (xy 96.430457 -278.610945)
			(xy 96.464629 -278.516042) (xy 96.507125 -278.424563) (xy 96.557607 -278.337236) (xy 96.615671 -278.254756)
			(xy 96.680857 -278.177781) (xy 96.716342 -278.141938) (xy 96.722692 -278.135588) (xy 96.73717 -278.104854)
			(xy 96.738186 -278.09698) (xy 96.741982 -278.071278) (xy 96.757173 -278.021598) (xy 96.768412 -277.998174)
			(xy 96.770952 -277.99284) (xy 96.774 -277.980648) (xy 96.774 -276.67204) (xy 96.771206 -276.66061)
			(xy 96.768412 -276.655276) (xy 96.758072 -276.633771) (xy 96.743456 -276.588351) (xy 96.736078 -276.541211)
			(xy 96.735646 -276.517354) (xy 96.735646 -276.515322) (xy 96.736087 -276.491466) (xy 96.743467 -276.444327)
			(xy 96.758081 -276.398908) (xy 96.768412 -276.3774) (xy 96.771206 -276.372066) (xy 96.774 -276.360636)
			(xy 96.774 -276.100286) (xy 96.773599 -276.090766) (xy 96.76668 -276.073027) (xy 96.760538 -276.065742)
			(xy 96.75749 -276.06244) (xy 96.690942 -276.011132) (xy 96.682052 -276.004274) (xy 96.660462 -275.999194)
			(xy 96.645476 -276.002496) (xy 96.64446 -276.00275) (xy 96.626398 -276.006929) (xy 96.589592 -276.011392)
			(xy 96.571054 -276.01164) (xy 96.545799 -276.011115) (xy 96.495977 -276.002794) (xy 96.448205 -275.986388)
			(xy 96.403784 -275.962342) (xy 96.363927 -275.931314) (xy 96.329719 -275.89415) (xy 96.302095 -275.851862)
			(xy 96.281806 -275.805604) (xy 96.269408 -275.756639) (xy 96.265237 -275.7063) (xy 96.269408 -275.655961)
			(xy 96.281806 -275.606996) (xy 96.302095 -275.560738) (xy 96.329719 -275.51845) (xy 96.363927 -275.481286)
			(xy 96.403784 -275.450258) (xy 96.448205 -275.426212) (xy 96.495977 -275.409806) (xy 96.545799 -275.401485)
			(xy 96.571054 -275.401024) (xy 96.588876 -275.401315) (xy 96.624272 -275.405514) (xy 96.641666 -275.409406)
			(xy 96.647508 -275.410676) (xy 96.670368 -275.410676) (xy 96.68637 -275.405342) (xy 96.692974 -275.400008)
			(xy 96.75368 -275.353018) (xy 96.76003 -275.34743) (xy 96.760538 -275.346922) (xy 96.766728 -275.339664)
			(xy 96.773658 -275.321909) (xy 96.774 -275.312378) (xy 96.774 -275.052028) (xy 96.771206 -275.040598)
			(xy 96.768412 -275.035264) (xy 96.758073 -275.013759) (xy 96.743459 -274.968339) (xy 96.736082 -274.921199)
			(xy 96.735646 -274.897342) (xy 96.735646 -274.89531) (xy 96.736088 -274.871454) (xy 96.743469 -274.824316)
			(xy 96.758085 -274.778898) (xy 96.768412 -274.757388) (xy 96.771206 -274.752054) (xy 96.774 -274.740624)
			(xy 96.774 -273.432016) (xy 96.771206 -273.420586) (xy 96.768412 -273.415252) (xy 96.758074 -273.393747)
			(xy 96.743462 -273.348327) (xy 96.736087 -273.301187) (xy 96.735646 -273.27733) (xy 96.735646 -273.275298)
			(xy 96.736089 -273.251442) (xy 96.743472 -273.204305) (xy 96.758089 -273.158888) (xy 96.768412 -273.137376)
			(xy 96.771206 -273.132042) (xy 96.774 -273.120612) (xy 96.774 -272.860262) (xy 96.773595 -272.850744)
			(xy 96.76667 -272.83301) (xy 96.760538 -272.825718) (xy 96.75749 -272.822416) (xy 96.690942 -272.771108)
			(xy 96.682052 -272.76425) (xy 96.660462 -272.75917) (xy 96.645476 -272.762472) (xy 96.64446 -272.762726)
			(xy 96.626398 -272.766906) (xy 96.589592 -272.771368) (xy 96.571054 -272.771616) (xy 96.545801 -272.771091)
			(xy 96.495983 -272.762771) (xy 96.448215 -272.746366) (xy 96.403798 -272.722322) (xy 96.363943 -272.691297)
			(xy 96.329738 -272.654135) (xy 96.302116 -272.61185) (xy 96.281829 -272.565597) (xy 96.269431 -272.516635)
			(xy 96.265261 -272.4663) (xy 96.269431 -272.415965) (xy 96.281829 -272.367003) (xy 96.302116 -272.32075)
			(xy 96.329738 -272.278465) (xy 96.363943 -272.241303) (xy 96.403798 -272.210278) (xy 96.448215 -272.186234)
			(xy 96.495983 -272.169829) (xy 96.545801 -272.161509) (xy 96.571054 -272.161) (xy 96.588876 -272.161291)
			(xy 96.624272 -272.16549) (xy 96.641666 -272.169382) (xy 96.647508 -272.170652) (xy 96.670368 -272.170652)
			(xy 96.68637 -272.165318) (xy 96.692974 -272.159984) (xy 96.75368 -272.112994) (xy 96.76003 -272.107406)
			(xy 96.760538 -272.106898) (xy 96.766724 -272.099639) (xy 96.773646 -272.081884) (xy 96.774 -272.072354)
			(xy 96.774 -271.812004) (xy 96.771206 -271.800574) (xy 96.768412 -271.79524) (xy 96.758075 -271.773735)
			(xy 96.743464 -271.728314) (xy 96.736091 -271.681175) (xy 96.735646 -271.657318) (xy 96.735646 -271.655286)
			(xy 96.736082 -271.631428) (xy 96.743453 -271.584286) (xy 96.758059 -271.538862) (xy 96.768412 -271.517364)
			(xy 96.771206 -271.51203) (xy 96.774 -271.5006) (xy 96.774 -270.191992) (xy 96.771206 -270.180562)
			(xy 96.768412 -270.175228) (xy 96.758076 -270.153722) (xy 96.743467 -270.108302) (xy 96.736096 -270.061163)
			(xy 96.735646 -270.037306) (xy 96.735646 -270.035274) (xy 96.736083 -270.011416) (xy 96.743455 -269.964275)
			(xy 96.758063 -269.918852) (xy 96.768412 -269.897352) (xy 96.771206 -269.892018) (xy 96.774 -269.880588)
			(xy 96.774 -269.620238) (xy 96.773608 -269.610715) (xy 96.766702 -269.592963) (xy 96.760538 -269.585694)
			(xy 96.75749 -269.582392) (xy 96.690942 -269.531084) (xy 96.682052 -269.524226) (xy 96.660462 -269.519146)
			(xy 96.645476 -269.522448) (xy 96.64446 -269.522702) (xy 96.626398 -269.526882) (xy 96.589592 -269.531345)
			(xy 96.571054 -269.531592) (xy 96.545802 -269.531067) (xy 96.495989 -269.522748) (xy 96.448224 -269.506344)
			(xy 96.403811 -269.482302) (xy 96.363959 -269.451279) (xy 96.329757 -269.41412) (xy 96.302137 -269.371839)
			(xy 96.281852 -269.325589) (xy 96.269455 -269.276631) (xy 96.265285 -269.2263) (xy 96.269455 -269.175969)
			(xy 96.281852 -269.127011) (xy 96.302137 -269.080761) (xy 96.329757 -269.03848) (xy 96.363959 -269.001321)
			(xy 96.403811 -268.970298) (xy 96.448224 -268.946256) (xy 96.495989 -268.929852) (xy 96.545802 -268.921533)
			(xy 96.571054 -268.920976) (xy 96.588876 -268.921267) (xy 96.624272 -268.925467) (xy 96.641666 -268.929358)
			(xy 96.647508 -268.930628) (xy 96.670368 -268.930628) (xy 96.68637 -268.925294) (xy 96.692974 -268.91996)
			(xy 96.75368 -268.87297) (xy 96.76003 -268.867382) (xy 96.760538 -268.866874) (xy 96.76672 -268.859614)
			(xy 96.773634 -268.841859) (xy 96.774 -268.83233) (xy 96.774 -268.57198) (xy 96.771206 -268.56055)
			(xy 96.768412 -268.555216) (xy 96.758045 -268.533632) (xy 96.743411 -268.488042) (xy 96.736068 -268.440728)
			(xy 96.735646 -268.416786) (xy 96.736157 -268.390038) (xy 96.745387 -268.337346) (xy 96.76365 -268.287066)
			(xy 96.77654 -268.263624) (xy 96.777302 -268.262608) (xy 96.778318 -268.260322) (xy 96.791442 -268.239176)
			(xy 96.823454 -268.201072) (xy 96.861228 -268.16867) (xy 96.90376 -268.142831) (xy 96.926654 -268.133068)
			(xy 96.943457 -268.126584) (xy 96.978219 -268.117161) (xy 96.995996 -268.114272) (xy 97.004124 -268.113002)
			(xy 97.018348 -268.10589) (xy 97.264728 -267.85951) (xy 97.270974 -267.852778) (xy 97.278618 -267.836096)
			(xy 97.279875 -267.817789) (xy 97.274583 -267.800219) (xy 97.2693 -267.792708) (xy 97.269046 -267.792454)
			(xy 97.25419 -267.772293) (xy 97.230568 -267.728138) (xy 97.214466 -267.68072) (xy 97.206316 -267.631311)
			(xy 97.2058 -267.606272) (xy 97.206273 -267.582282) (xy 97.213782 -267.534895) (xy 97.228612 -267.489265)
			(xy 97.250398 -267.446517) (xy 97.278602 -267.407703) (xy 97.31253 -267.373778) (xy 97.351347 -267.345579)
			(xy 97.394098 -267.323799) (xy 97.43973 -267.308974) (xy 97.487118 -267.30147) (xy 97.511108 -267.300964)
			(xy 97.536147 -267.301466) (xy 97.585555 -267.309628) (xy 97.632972 -267.325733) (xy 97.677131 -267.34935)
			(xy 97.69729 -267.36421) (xy 97.697544 -267.364464) (xy 97.705075 -267.369693) (xy 97.72263 -267.374932)
			(xy 97.740907 -267.373675) (xy 97.757579 -267.36608) (xy 97.764346 -267.359892) (xy 97.880932 -267.243306)
			(xy 97.888332 -267.236464) (xy 97.90693 -267.22874) (xy 97.917 -267.22832) (xy 99.630992 -267.22832)
			(xy 99.640864 -267.227847) (xy 99.659145 -267.220387) (xy 99.666552 -267.213842) (xy 99.666806 -267.213588)
			(xy 99.687634 -267.19276) (xy 99.694945 -267.184676) (xy 99.702594 -267.164286) (xy 99.702366 -267.15339)
			(xy 99.697794 -267.088112) (xy 99.697292 -267.082804) (xy 99.694341 -267.072559) (xy 99.691952 -267.067792)
			(xy 99.67722 -267.04036) (xy 99.669346 -267.033756) (xy 99.651941 -267.019189) (xy 99.621222 -266.985781)
			(xy 99.595794 -266.948188) (xy 99.576219 -266.907241) (xy 99.562931 -266.863845) (xy 99.556223 -266.818959)
			(xy 99.555808 -266.796266) (xy 99.556281 -266.772277) (xy 99.563792 -266.72489) (xy 99.578622 -266.679262)
			(xy 99.600408 -266.636515) (xy 99.628612 -266.597702) (xy 99.662541 -266.56378) (xy 99.701358 -266.535582)
			(xy 99.744108 -266.513803) (xy 99.789739 -266.49898) (xy 99.837127 -266.491477) (xy 99.861116 -266.490958)
			(xy 99.883808 -266.491375) (xy 99.928691 -266.498097) (xy 99.972084 -266.51139) (xy 100.01303 -266.530962)
			(xy 100.050628 -266.556381) (xy 100.084047 -266.587086) (xy 100.098606 -266.604496) (xy 100.10521 -266.61237)
			(xy 100.132642 -266.627102) (xy 100.137414 -266.629478) (xy 100.147657 -266.632424) (xy 100.152962 -266.632944)
			(xy 100.21824 -266.637516) (xy 100.229148 -266.637781) (xy 100.249569 -266.630158) (xy 100.25761 -266.622784)
			(xy 100.267008 -266.613386) (xy 100.273852 -266.605986) (xy 100.28158 -266.587389) (xy 100.281994 -266.577318)
			(xy 100.281994 -266.3317) (xy 100.281267 -266.319454) (xy 100.269982 -266.297713) (xy 100.260404 -266.290044)
			(xy 100.245672 -266.27963) (xy 100.238052 -266.27709) (xy 100.237798 -266.27709) (xy 100.214992 -266.269299)
			(xy 100.171984 -266.247558) (xy 100.132922 -266.219334) (xy 100.098776 -266.185328) (xy 100.070393 -266.146381)
			(xy 100.048477 -266.103462) (xy 100.033571 -266.057634) (xy 100.026046 -266.010034) (xy 100.026087 -265.961842)
			(xy 100.033694 -265.914255) (xy 100.048679 -265.868453) (xy 100.070669 -265.825571) (xy 100.099118 -265.786674)
			(xy 100.133323 -265.752726) (xy 100.172433 -265.724569) (xy 100.215479 -265.702902) (xy 100.238306 -265.695176)
			(xy 100.245672 -265.69289) (xy 100.259896 -265.683238) (xy 100.269798 -265.675715) (xy 100.281392 -265.653748)
			(xy 100.281994 -265.641328) (xy 100.281994 -264.711688) (xy 100.281265 -264.699443) (xy 100.269976 -264.677707)
			(xy 100.260404 -264.670032) (xy 100.245418 -264.659364) (xy 100.237798 -264.657078) (xy 100.215024 -264.649279)
			(xy 100.172078 -264.627539) (xy 100.13307 -264.599336) (xy 100.098965 -264.565368) (xy 100.070605 -264.526474)
			(xy 100.048692 -264.483615) (xy 100.033767 -264.437852) (xy 100.0262 -264.390315) (xy 100.025708 -264.366248)
			(xy 100.026151 -264.342253) (xy 100.033651 -264.294852) (xy 100.048476 -264.249209) (xy 100.070259 -264.206448)
			(xy 100.098464 -264.167621) (xy 100.132397 -264.133685) (xy 100.17122 -264.105476) (xy 100.21398 -264.083688)
			(xy 100.259621 -264.068859) (xy 100.307021 -264.061353) (xy 100.331016 -264.06094) (xy 100.357029 -264.061464)
			(xy 100.408305 -264.070274) (xy 100.45735 -264.087636) (xy 100.502748 -264.113049) (xy 100.523294 -264.129012)
			(xy 100.53066 -264.134854) (xy 100.54844 -264.140696) (xy 100.601526 -264.137902) (xy 100.624386 -264.136632)
			(xy 100.633625 -264.135726) (xy 100.650565 -264.128174) (xy 100.657406 -264.1219) (xy 100.968302 -263.811004)
			(xy 100.975539 -263.804288) (xy 100.993744 -263.796687) (xy 101.003608 -263.796272) (xy 101.358954 -263.796272)
			(xy 101.368828 -263.795805) (xy 101.387115 -263.788349) (xy 101.394514 -263.781794) (xy 101.394768 -263.78154)
			(xy 101.40188 -263.774428) (xy 101.44252 -263.716516) (xy 101.445314 -263.690862) (xy 101.440488 -263.678924)
			(xy 101.429265 -263.649568) (xy 101.417106 -263.587915) (xy 101.416358 -263.556496) (xy 101.416358 -263.556242)
			(xy 101.416858 -263.530734) (xy 101.424839 -263.480346) (xy 101.440604 -263.431826) (xy 101.463765 -263.38637)
			(xy 101.493751 -263.345097) (xy 101.529825 -263.309023) (xy 101.571098 -263.279037) (xy 101.616554 -263.255876)
			(xy 101.665074 -263.240111) (xy 101.715462 -263.23213) (xy 101.766478 -263.23213) (xy 101.816866 -263.240111)
			(xy 101.865386 -263.255876) (xy 101.910842 -263.279037) (xy 101.952115 -263.309023) (xy 101.988189 -263.345097)
			(xy 102.018175 -263.38637) (xy 102.041336 -263.431826) (xy 102.057101 -263.480346) (xy 102.065082 -263.530734)
			(xy 102.065582 -263.556242) (xy 102.065582 -263.556496) (xy 102.064848 -263.586618) (xy 102.05359 -263.645804)
			(xy 102.04323 -263.674098) (xy 102.042976 -263.67486) (xy 102.041452 -263.679178) (xy 102.03942 -263.68883)
			(xy 102.03782 -263.699031) (xy 102.042014 -263.719229) (xy 102.047548 -263.727946) (xy 102.079806 -263.774174)
			(xy 102.087172 -263.78154) (xy 102.087426 -263.781794) (xy 102.094808 -263.788376) (xy 102.113106 -263.79583)
			(xy 102.122986 -263.796272) (xy 102.299008 -263.796272) (xy 102.308885 -263.795813) (xy 102.327184 -263.788369)
			(xy 102.334568 -263.781794) (xy 102.334822 -263.78154) (xy 102.341934 -263.774428) (xy 102.382574 -263.716516)
			(xy 102.385368 -263.690862) (xy 102.380542 -263.678924) (xy 102.36932 -263.649567) (xy 102.357163 -263.587915)
			(xy 102.356412 -263.556496) (xy 102.356412 -263.556242) (xy 102.356912 -263.530734) (xy 102.364893 -263.480346)
			(xy 102.380658 -263.431826) (xy 102.403819 -263.38637) (xy 102.433805 -263.345097) (xy 102.469879 -263.309023)
			(xy 102.511152 -263.279037) (xy 102.556608 -263.255876) (xy 102.605128 -263.240111) (xy 102.655516 -263.23213)
			(xy 102.706532 -263.23213) (xy 102.75692 -263.240111) (xy 102.80544 -263.255876) (xy 102.850896 -263.279037)
			(xy 102.892169 -263.309023) (xy 102.928243 -263.345097) (xy 102.958229 -263.38637) (xy 102.98139 -263.431826)
			(xy 102.997155 -263.480346) (xy 103.005136 -263.530734) (xy 103.005636 -263.556242) (xy 103.005636 -263.556496)
			(xy 103.004902 -263.586618) (xy 102.993642 -263.645803) (xy 102.983284 -263.674098) (xy 102.98303 -263.67486)
			(xy 102.981506 -263.679178) (xy 102.979474 -263.68883) (xy 102.977874 -263.699032) (xy 102.982065 -263.719231)
			(xy 102.987602 -263.727946) (xy 103.01986 -263.774174) (xy 103.027226 -263.78154) (xy 103.02748 -263.781794)
			(xy 103.034865 -263.788368) (xy 103.053163 -263.795802) (xy 103.06304 -263.796272) (xy 104.210612 -263.796272)
			(xy 104.220681 -263.795846) (xy 104.239279 -263.788125) (xy 104.24668 -263.781286) (xy 105.37444 -262.653526)
			(xy 105.382628 -262.64438) (xy 105.390048 -262.621021) (xy 105.388664 -262.608822) (xy 105.385108 -262.588502)
			(xy 105.376726 -262.541258) (xy 105.374694 -262.528304) (xy 105.353866 -262.502396) (xy 105.352342 -262.500618)
			(xy 105.350564 -262.49884) (xy 105.347315 -262.495149) (xy 105.339638 -262.489008) (xy 105.335324 -262.486648)
			(xy 105.311457 -262.473951) (xy 105.267693 -262.442213) (xy 105.229437 -262.404016) (xy 105.197631 -262.360303)
			(xy 105.173059 -262.31215) (xy 105.156326 -262.260745) (xy 105.147845 -262.207354) (xy 105.147364 -262.180324)
			(xy 105.147891 -262.153337) (xy 105.156331 -262.100026) (xy 105.173006 -262.048693) (xy 105.197507 -262.000599)
			(xy 105.229229 -261.956931) (xy 105.267391 -261.918762) (xy 105.311055 -261.887034) (xy 105.359145 -261.862526)
			(xy 105.410476 -261.845843) (xy 105.463785 -261.837396) (xy 105.490772 -261.836916) (xy 105.517803 -261.837418)
			(xy 105.571199 -261.84588) (xy 105.622611 -261.8626) (xy 105.67077 -261.887166) (xy 105.714488 -261.91897)
			(xy 105.752686 -261.957228) (xy 105.78442 -262.000996) (xy 105.797096 -262.024876) (xy 105.79735 -262.02513)
			(xy 105.797604 -262.025892) (xy 105.800287 -262.030643) (xy 105.807331 -262.038972) (xy 105.811574 -262.042402)
			(xy 105.829862 -262.056626) (xy 105.834916 -262.06029) (xy 105.84635 -262.065291) (xy 105.852468 -262.066532)
			(xy 105.899458 -262.07466) (xy 105.899966 -262.07466) (xy 105.917746 -262.078216) (xy 105.928852 -262.079842)
			(xy 105.950613 -262.074449) (xy 105.959656 -262.067802) (xy 105.961942 -262.066024) (xy 106.241342 -261.786624)
			(xy 106.24858 -261.779912) (xy 106.266786 -261.772323) (xy 106.276648 -261.771892) (xy 107.943904 -261.771892)
			(xy 107.953974 -261.771468) (xy 107.972576 -261.763752) (xy 107.979972 -261.756906) (xy 108.2294 -261.507478)
			(xy 108.236243 -261.500078) (xy 108.243969 -261.48148) (xy 108.244386 -261.47141) (xy 108.244386 -258.787646)
			(xy 108.243953 -258.77758) (xy 108.236223 -258.758992) (xy 108.2294 -258.751578) (xy 107.979972 -258.50215)
			(xy 107.97286 -258.494784) (xy 107.954064 -258.487164) (xy 106.75112 -258.487164) (xy 106.725974 -258.503674)
			(xy 106.719878 -258.517898) (xy 106.709489 -258.540506) (xy 106.683157 -258.582722) (xy 106.651015 -258.6207)
			(xy 106.613733 -258.653649) (xy 106.572092 -258.680879) (xy 106.52696 -258.701822) (xy 106.47928 -258.716041)
			(xy 106.430049 -258.723238) (xy 106.405172 -258.723638) (xy 106.379592 -258.723171) (xy 106.328997 -258.715588)
			(xy 106.280089 -258.70058) (xy 106.23395 -258.678478) (xy 106.191602 -258.649772) (xy 106.153984 -258.615099)
			(xy 106.12193 -258.575226) (xy 106.096148 -258.531038) (xy 106.077212 -258.483512) (xy 106.070908 -258.458716)
			(xy 106.070654 -258.457954) (xy 106.068876 -258.45135) (xy 106.062272 -258.43865) (xy 106.056684 -258.433062)
			(xy 105.947718 -258.324096) (xy 105.941 -258.31686) (xy 105.933398 -258.298655) (xy 105.932986 -258.28879)
			(xy 105.932986 -257.441446) (xy 105.932553 -257.43138) (xy 105.924823 -257.412792) (xy 105.918 -257.405378)
			(xy 105.693972 -257.18135) (xy 105.68686 -257.173984) (xy 105.668064 -257.166364) (xy 100.92436 -257.166364)
			(xy 100.914519 -257.165835) (xy 100.896344 -257.158263) (xy 100.889054 -257.151632) (xy 100.029772 -256.29235)
			(xy 100.02266 -256.284984) (xy 100.003864 -256.277364) (xy 99.405186 -256.277364) (xy 99.395604 -256.277781)
			(xy 99.377773 -256.284812) (xy 99.363735 -256.297861) (xy 99.359212 -256.30632) (xy 99.314508 -256.400808)
			(xy 99.318064 -256.429764) (xy 99.327462 -256.441194) (xy 99.343592 -256.461814) (xy 99.369294 -256.507418)
			(xy 99.386857 -256.556731) (xy 99.39577 -256.608314) (xy 99.396296 -256.634488) (xy 99.395774 -256.659743)
			(xy 99.387461 -256.709565) (xy 99.37106 -256.757339) (xy 99.347019 -256.801762) (xy 99.315995 -256.841622)
			(xy 99.278833 -256.875832) (xy 99.236547 -256.903458) (xy 99.190291 -256.923748) (xy 99.141326 -256.936148)
			(xy 99.090988 -256.940319) (xy 99.04065 -256.936148) (xy 98.991685 -256.923748) (xy 98.945429 -256.903458)
			(xy 98.903143 -256.875832) (xy 98.865981 -256.841622) (xy 98.834957 -256.801762) (xy 98.810916 -256.757339)
			(xy 98.794515 -256.709565) (xy 98.786202 -256.659743) (xy 98.78568 -256.634488) (xy 98.786217 -256.608315)
			(xy 98.795129 -256.556733) (xy 98.812691 -256.507421) (xy 98.838391 -256.461818) (xy 98.854514 -256.441194)
			(xy 98.863912 -256.429764) (xy 98.867468 -256.400808) (xy 98.822764 -256.30632) (xy 98.818294 -256.297812)
			(xy 98.80427 -256.284694) (xy 98.786393 -256.277679) (xy 98.77679 -256.277364) (xy 97.525332 -256.277364)
			(xy 97.515745 -256.277774) (xy 97.497901 -256.284794) (xy 97.483849 -256.297842) (xy 97.479358 -256.30632)
			(xy 97.434654 -256.400808) (xy 97.43821 -256.429764) (xy 97.447608 -256.441194) (xy 97.463735 -256.461815)
			(xy 97.489434 -256.50742) (xy 97.506995 -256.556732) (xy 97.515906 -256.608315) (xy 97.516442 -256.634488)
			(xy 97.51592 -256.659743) (xy 97.507607 -256.709565) (xy 97.491206 -256.757339) (xy 97.467165 -256.801762)
			(xy 97.436141 -256.841622) (xy 97.398979 -256.875832) (xy 97.356693 -256.903458) (xy 97.310437 -256.923748)
			(xy 97.261472 -256.936148) (xy 97.211134 -256.940319) (xy 97.160796 -256.936148) (xy 97.111831 -256.923748)
			(xy 97.065575 -256.903458) (xy 97.023289 -256.875832) (xy 96.986127 -256.841622) (xy 96.955103 -256.801762)
			(xy 96.931062 -256.757339) (xy 96.914661 -256.709565) (xy 96.906348 -256.659743) (xy 96.905826 -256.634488)
			(xy 96.906363 -256.608315) (xy 96.915276 -256.556734) (xy 96.932841 -256.507424) (xy 96.958543 -256.461823)
			(xy 96.97466 -256.441194) (xy 96.984058 -256.429764) (xy 96.987614 -256.400808) (xy 96.94291 -256.30632)
			(xy 96.938437 -256.297818) (xy 96.92441 -256.284714) (xy 96.906536 -256.277718) (xy 96.896936 -256.277364)
			(xy 95.645224 -256.277364) (xy 95.635638 -256.277775) (xy 95.617796 -256.284797) (xy 95.603747 -256.297845)
			(xy 95.59925 -256.30632) (xy 95.554546 -256.400808) (xy 95.558102 -256.429764) (xy 95.5675 -256.441194)
			(xy 95.583628 -256.461815) (xy 95.609327 -256.507419) (xy 95.626888 -256.556732) (xy 95.6358 -256.608315)
			(xy 95.636334 -256.634488) (xy 95.635812 -256.659743) (xy 95.627499 -256.709565) (xy 95.611098 -256.757339)
			(xy 95.587057 -256.801762) (xy 95.556033 -256.841622) (xy 95.518871 -256.875832) (xy 95.476585 -256.903458)
			(xy 95.430329 -256.923748) (xy 95.381364 -256.936148) (xy 95.331026 -256.940319) (xy 95.280688 -256.936148)
			(xy 95.231723 -256.923748) (xy 95.185467 -256.903458) (xy 95.143181 -256.875832) (xy 95.106019 -256.841622)
			(xy 95.074995 -256.801762) (xy 95.050954 -256.757339) (xy 95.034553 -256.709565) (xy 95.02624 -256.659743)
			(xy 95.025718 -256.634488) (xy 95.026255 -256.608315) (xy 95.035168 -256.556734) (xy 95.052732 -256.507423)
			(xy 95.078434 -256.461822) (xy 95.094552 -256.441194) (xy 95.10395 -256.429764) (xy 95.107506 -256.400808)
			(xy 95.062802 -256.30632) (xy 95.058329 -256.297819) (xy 95.044302 -256.284718) (xy 95.026427 -256.277724)
			(xy 95.016828 -256.277364) (xy 94.70517 -256.277364) (xy 94.695694 -256.277823) (xy 94.678037 -256.284715)
			(xy 94.664061 -256.29752) (xy 94.65945 -256.305812) (xy 94.643702 -256.338324) (xy 94.643702 -256.338832)
			(xy 94.619318 -256.390648) (xy 94.623128 -256.420112) (xy 94.632526 -256.431542) (xy 94.649836 -256.453018)
			(xy 94.677442 -256.500768) (xy 94.696322 -256.552592) (xy 94.7059 -256.60691) (xy 94.70644 -256.634488)
			(xy 94.705954 -256.659278) (xy 94.698198 -256.708246) (xy 94.682877 -256.755399) (xy 94.660368 -256.799574)
			(xy 94.631226 -256.839685) (xy 94.596169 -256.874742) (xy 94.556058 -256.903884) (xy 94.511883 -256.926393)
			(xy 94.46473 -256.941714) (xy 94.415762 -256.94947) (xy 94.366182 -256.94947) (xy 94.317214 -256.941714)
			(xy 94.270061 -256.926393) (xy 94.225886 -256.903884) (xy 94.185775 -256.874742) (xy 94.150718 -256.839685)
			(xy 94.121576 -256.799574) (xy 94.099067 -256.755399) (xy 94.083746 -256.708246) (xy 94.07599 -256.659278)
			(xy 94.075504 -256.634488) (xy 94.076071 -256.606912) (xy 94.085653 -256.552598) (xy 94.104522 -256.500773)
			(xy 94.132106 -256.453014) (xy 94.149418 -256.431542) (xy 94.158816 -256.420112) (xy 94.162626 -256.390648)
			(xy 94.138242 -256.338832) (xy 94.138242 -256.338324) (xy 94.122494 -256.305812) (xy 94.117976 -256.297448)
			(xy 94.103989 -256.284594) (xy 94.086274 -256.277736) (xy 94.076774 -256.277364) (xy 93.765116 -256.277364)
			(xy 93.755531 -256.277776) (xy 93.737691 -256.2848) (xy 93.723644 -256.297848) (xy 93.719142 -256.30632)
			(xy 93.674438 -256.400808) (xy 93.677994 -256.429764) (xy 93.687392 -256.441194) (xy 93.70352 -256.461815)
			(xy 93.72922 -256.507419) (xy 93.746782 -256.556732) (xy 93.755694 -256.608315) (xy 93.756226 -256.634488)
			(xy 93.755704 -256.659743) (xy 93.747391 -256.709565) (xy 93.73099 -256.757339) (xy 93.706949 -256.801762)
			(xy 93.675925 -256.841622) (xy 93.638763 -256.875832) (xy 93.596477 -256.903458) (xy 93.550221 -256.923748)
			(xy 93.501256 -256.936148) (xy 93.450918 -256.940319) (xy 93.40058 -256.936148) (xy 93.351615 -256.923748)
			(xy 93.305359 -256.903458) (xy 93.263073 -256.875832) (xy 93.225911 -256.841622) (xy 93.194887 -256.801762)
			(xy 93.170846 -256.757339) (xy 93.154445 -256.709565) (xy 93.146132 -256.659743) (xy 93.14561 -256.634488)
			(xy 93.146147 -256.608315) (xy 93.15506 -256.556734) (xy 93.172623 -256.507423) (xy 93.198325 -256.461821)
			(xy 93.214444 -256.441194) (xy 93.223842 -256.429764) (xy 93.227398 -256.400808) (xy 93.182694 -256.30632)
			(xy 93.17822 -256.29782) (xy 93.164193 -256.284721) (xy 93.146319 -256.27773) (xy 93.13672 -256.277364)
			(xy 92.825316 -256.277364) (xy 92.815731 -256.277776) (xy 92.797891 -256.2848) (xy 92.783844 -256.297848)
			(xy 92.779342 -256.30632) (xy 92.734638 -256.400808) (xy 92.738194 -256.429764) (xy 92.747592 -256.441194)
			(xy 92.76372 -256.461815) (xy 92.78942 -256.507419) (xy 92.806982 -256.556732) (xy 92.815894 -256.608315)
			(xy 92.816426 -256.634488) (xy 92.815904 -256.659743) (xy 92.807591 -256.709565) (xy 92.79119 -256.757339)
			(xy 92.767149 -256.801762) (xy 92.736125 -256.841622) (xy 92.698963 -256.875832) (xy 92.656677 -256.903458)
			(xy 92.610421 -256.923748) (xy 92.561456 -256.936148) (xy 92.511118 -256.940319) (xy 92.46078 -256.936148)
			(xy 92.411815 -256.923748) (xy 92.365559 -256.903458) (xy 92.323273 -256.875832) (xy 92.286111 -256.841622)
			(xy 92.255087 -256.801762) (xy 92.231046 -256.757339) (xy 92.214645 -256.709565) (xy 92.206332 -256.659743)
			(xy 92.20581 -256.634488) (xy 92.206347 -256.608315) (xy 92.21526 -256.556734) (xy 92.232823 -256.507423)
			(xy 92.258525 -256.461821) (xy 92.274644 -256.441194) (xy 92.284042 -256.429764) (xy 92.287598 -256.400808)
			(xy 92.242894 -256.30632) (xy 92.23842 -256.29782) (xy 92.224393 -256.284721) (xy 92.206519 -256.27773)
			(xy 92.19692 -256.277364) (xy 91.885262 -256.277364) (xy 91.875682 -256.277786) (xy 91.857858 -256.284821)
			(xy 91.843827 -256.297872) (xy 91.839288 -256.30632) (xy 91.794584 -256.400808) (xy 91.79814 -256.429764)
			(xy 91.807538 -256.441194) (xy 91.823669 -256.461814) (xy 91.849373 -256.507417) (xy 91.866938 -256.55673)
			(xy 91.875852 -256.608314) (xy 91.876372 -256.634488) (xy 91.87585 -256.659743) (xy 91.867537 -256.709565)
			(xy 91.851136 -256.757339) (xy 91.827095 -256.801762) (xy 91.796071 -256.841622) (xy 91.758909 -256.875832)
			(xy 91.716623 -256.903458) (xy 91.670367 -256.923748) (xy 91.621402 -256.936148) (xy 91.571064 -256.940319)
			(xy 91.520726 -256.936148) (xy 91.471761 -256.923748) (xy 91.425505 -256.903458) (xy 91.383219 -256.875832)
			(xy 91.346057 -256.841622) (xy 91.315033 -256.801762) (xy 91.290992 -256.757339) (xy 91.274591 -256.709565)
			(xy 91.266278 -256.659743) (xy 91.265756 -256.634488) (xy 91.266293 -256.608315) (xy 91.275204 -256.556733)
			(xy 91.292765 -256.50742) (xy 91.318463 -256.461816) (xy 91.33459 -256.441194) (xy 91.343988 -256.429764)
			(xy 91.347544 -256.400808) (xy 91.30284 -256.30632) (xy 91.298369 -256.297815) (xy 91.284343 -256.284703)
			(xy 91.266468 -256.277696) (xy 91.256866 -256.277364) (xy 90.945208 -256.277364) (xy 90.935717 -256.27776)
			(xy 90.91803 -256.284651) (xy 90.904027 -256.297468) (xy 90.899488 -256.305812) (xy 90.88374 -256.338324)
			(xy 90.88374 -256.338832) (xy 90.859356 -256.390648) (xy 90.863166 -256.420112) (xy 90.872564 -256.431542)
			(xy 90.889852 -256.453041) (xy 90.917482 -256.500785) (xy 90.936412 -256.552597) (xy 90.946068 -256.606908)
			(xy 90.946732 -256.634488) (xy 90.946245 -256.659298) (xy 90.938483 -256.708306) (xy 90.92315 -256.755496)
			(xy 90.900623 -256.799707) (xy 90.871458 -256.83985) (xy 90.836372 -256.874936) (xy 90.796229 -256.904101)
			(xy 90.752018 -256.926628) (xy 90.704828 -256.941961) (xy 90.65582 -256.949723) (xy 90.6062 -256.949723)
			(xy 90.557192 -256.941961) (xy 90.510002 -256.926628) (xy 90.465791 -256.904101) (xy 90.425648 -256.874936)
			(xy 90.390562 -256.83985) (xy 90.361397 -256.799707) (xy 90.33887 -256.755496) (xy 90.323537 -256.708306)
			(xy 90.315775 -256.659298) (xy 90.315288 -256.634488) (xy 90.315868 -256.606898) (xy 90.325491 -256.552563)
			(xy 90.344423 -256.500731) (xy 90.372088 -256.452986) (xy 90.389456 -256.431542) (xy 90.398854 -256.420112)
			(xy 90.402664 -256.390648) (xy 90.37828 -256.338832) (xy 90.37828 -256.338324) (xy 90.362532 -256.305812)
			(xy 90.358016 -256.297444) (xy 90.34403 -256.28458) (xy 90.326314 -256.277709) (xy 90.316812 -256.277364)
			(xy 90.005154 -256.277364) (xy 89.995565 -256.27777) (xy 89.977715 -256.284786) (xy 89.963656 -256.297832)
			(xy 89.95918 -256.30632) (xy 89.914476 -256.400808) (xy 89.918032 -256.429764) (xy 89.92743 -256.441194)
			(xy 89.943556 -256.461816) (xy 89.969253 -256.50742) (xy 89.986812 -256.556733) (xy 89.995723 -256.608315)
			(xy 89.996264 -256.634488) (xy 89.995742 -256.659743) (xy 89.987429 -256.709565) (xy 89.971028 -256.757339)
			(xy 89.946987 -256.801762) (xy 89.915963 -256.841622) (xy 89.878801 -256.875832) (xy 89.836515 -256.903458)
			(xy 89.790259 -256.923748) (xy 89.741294 -256.936148) (xy 89.690956 -256.940319) (xy 89.640618 -256.936148)
			(xy 89.591653 -256.923748) (xy 89.545397 -256.903458) (xy 89.503111 -256.875832) (xy 89.465949 -256.841622)
			(xy 89.434925 -256.801762) (xy 89.410884 -256.757339) (xy 89.394483 -256.709565) (xy 89.38617 -256.659743)
			(xy 89.385648 -256.634488) (xy 89.386185 -256.608315) (xy 89.395096 -256.556732) (xy 89.412657 -256.507419)
			(xy 89.438354 -256.461815) (xy 89.454482 -256.441194) (xy 89.46388 -256.429764) (xy 89.467436 -256.400808)
			(xy 89.422732 -256.30632) (xy 89.41826 -256.297816) (xy 89.404235 -256.284706) (xy 89.386359 -256.277702)
			(xy 89.376758 -256.277364) (xy 89.065354 -256.277364) (xy 89.055765 -256.27777) (xy 89.037915 -256.284786)
			(xy 89.023856 -256.297832) (xy 89.01938 -256.30632) (xy 88.974676 -256.400808) (xy 88.978232 -256.429764)
			(xy 88.98763 -256.441194) (xy 89.003756 -256.461816) (xy 89.029453 -256.50742) (xy 89.047012 -256.556733)
			(xy 89.055923 -256.608315) (xy 89.056464 -256.634488) (xy 89.055942 -256.659743) (xy 89.047629 -256.709565)
			(xy 89.031228 -256.757339) (xy 89.007187 -256.801762) (xy 88.976163 -256.841622) (xy 88.939001 -256.875832)
			(xy 88.896715 -256.903458) (xy 88.850459 -256.923748) (xy 88.801494 -256.936148) (xy 88.751156 -256.940319)
			(xy 88.700818 -256.936148) (xy 88.651853 -256.923748) (xy 88.605597 -256.903458) (xy 88.563311 -256.875832)
			(xy 88.526149 -256.841622) (xy 88.495125 -256.801762) (xy 88.471084 -256.757339) (xy 88.454683 -256.709565)
			(xy 88.44637 -256.659743) (xy 88.445848 -256.634488) (xy 88.446385 -256.608315) (xy 88.455296 -256.556732)
			(xy 88.472857 -256.507419) (xy 88.498554 -256.461815) (xy 88.514682 -256.441194) (xy 88.52408 -256.429764)
			(xy 88.527636 -256.400808) (xy 88.482932 -256.30632) (xy 88.47846 -256.297816) (xy 88.464435 -256.284706)
			(xy 88.446559 -256.277702) (xy 88.436958 -256.277364) (xy 88.1253 -256.277364) (xy 88.115716 -256.277779)
			(xy 88.097882 -256.284806) (xy 88.083839 -256.297855) (xy 88.079326 -256.30632) (xy 88.034622 -256.400808)
			(xy 88.038178 -256.429764) (xy 88.047576 -256.441194) (xy 88.063705 -256.461815) (xy 88.089406 -256.507418)
			(xy 88.106969 -256.556731) (xy 88.115881 -256.608314) (xy 88.11641 -256.634488) (xy 88.115888 -256.659743)
			(xy 88.107575 -256.709565) (xy 88.091174 -256.757339) (xy 88.067133 -256.801762) (xy 88.036109 -256.841622)
			(xy 87.998947 -256.875832) (xy 87.956661 -256.903458) (xy 87.910405 -256.923748) (xy 87.86144 -256.936148)
			(xy 87.811102 -256.940319) (xy 87.760764 -256.936148) (xy 87.711799 -256.923748) (xy 87.665543 -256.903458)
			(xy 87.623257 -256.875832) (xy 87.586095 -256.841622) (xy 87.555071 -256.801762) (xy 87.53103 -256.757339)
			(xy 87.514629 -256.709565) (xy 87.506316 -256.659743) (xy 87.505794 -256.634488) (xy 87.506343 -256.60857)
			(xy 87.515099 -256.557478) (xy 87.532356 -256.508599) (xy 87.55762 -256.463336) (xy 87.590165 -256.422989)
			(xy 87.629056 -256.388718) (xy 87.650828 -256.374646) (xy 87.6554 -256.371852) (xy 87.662766 -256.36474)
			(xy 87.669757 -256.357423) (xy 87.67781 -256.338875) (xy 87.678077 -256.318655) (xy 87.674704 -256.309114)
			(xy 87.668862 -256.294636) (xy 87.643462 -256.277364) (xy 87.539068 -256.277364) (xy 87.529002 -256.277795)
			(xy 87.510412 -256.285524) (xy 87.503 -256.29235) (xy 87.191342 -256.604008) (xy 87.18794 -256.607579)
			(xy 87.18244 -256.615764) (xy 87.18042 -256.620264) (xy 87.176356 -256.629662) (xy 87.176356 -256.639568)
			(xy 87.176356 -256.64287) (xy 87.175233 -256.666876) (xy 87.166374 -256.714107) (xy 87.150225 -256.759368)
			(xy 87.127184 -256.801539) (xy 87.097821 -256.83958) (xy 87.06286 -256.872551) (xy 87.04326 -256.886456)
			(xy 87.038688 -256.889758) (xy 87.034878 -256.893822) (xy 87.03056 -256.898394) (xy 87.01659 -256.923032)
			(xy 87.013493 -256.928849) (xy 87.010146 -256.94159) (xy 87.009986 -256.948178) (xy 87.009986 -257.930396)
			(xy 98.711261 -257.930396) (xy 98.715291 -257.877898) (xy 98.727288 -257.82663) (xy 98.746971 -257.777795)
			(xy 98.773877 -257.732536) (xy 98.807377 -257.691915) (xy 98.846685 -257.656884) (xy 98.89088 -257.628264)
			(xy 98.938925 -257.606725) (xy 98.989696 -257.592773) (xy 99.042001 -257.586735) (xy 99.094615 -257.588752)
			(xy 99.146305 -257.598776) (xy 99.195858 -257.616574) (xy 99.242114 -257.641727) (xy 99.283988 -257.673646)
			(xy 99.3205 -257.711584) (xy 99.350792 -257.75465) (xy 99.374155 -257.801835) (xy 99.390041 -257.852034)
			(xy 99.398078 -257.90407) (xy 99.398582 -257.930396) (xy 100.611181 -257.930396) (xy 100.615211 -257.877898)
			(xy 100.627208 -257.82663) (xy 100.646891 -257.777795) (xy 100.673797 -257.732536) (xy 100.707297 -257.691915)
			(xy 100.746605 -257.656884) (xy 100.7908 -257.628264) (xy 100.838845 -257.606725) (xy 100.889616 -257.592773)
			(xy 100.941921 -257.586735) (xy 100.994535 -257.588752) (xy 101.046225 -257.598776) (xy 101.095778 -257.616574)
			(xy 101.142034 -257.641727) (xy 101.183908 -257.673646) (xy 101.22042 -257.711584) (xy 101.250712 -257.75465)
			(xy 101.274075 -257.801835) (xy 101.289961 -257.852034) (xy 101.297998 -257.90407) (xy 101.298502 -257.930396)
			(xy 102.511101 -257.930396) (xy 102.515131 -257.877898) (xy 102.527128 -257.82663) (xy 102.546811 -257.777795)
			(xy 102.573717 -257.732536) (xy 102.607217 -257.691915) (xy 102.646525 -257.656884) (xy 102.69072 -257.628264)
			(xy 102.738765 -257.606725) (xy 102.789536 -257.592773) (xy 102.841841 -257.586735) (xy 102.894455 -257.588752)
			(xy 102.946145 -257.598776) (xy 102.995698 -257.616574) (xy 103.041954 -257.641727) (xy 103.083828 -257.673646)
			(xy 103.12034 -257.711584) (xy 103.150632 -257.75465) (xy 103.173995 -257.801835) (xy 103.189881 -257.852034)
			(xy 103.197918 -257.90407) (xy 103.198422 -257.930396) (xy 103.197918 -257.956722) (xy 103.189881 -258.008758)
			(xy 103.173995 -258.058957) (xy 103.150632 -258.106142) (xy 103.12034 -258.149208) (xy 103.083828 -258.187146)
			(xy 103.041954 -258.219065) (xy 102.995698 -258.244218) (xy 102.946145 -258.262016) (xy 102.894455 -258.27204)
			(xy 102.841841 -258.274057) (xy 102.789536 -258.268019) (xy 102.738765 -258.254067) (xy 102.69072 -258.232528)
			(xy 102.646525 -258.203908) (xy 102.607217 -258.168877) (xy 102.573717 -258.128256) (xy 102.546811 -258.082997)
			(xy 102.527128 -258.034162) (xy 102.515131 -257.982894) (xy 102.511101 -257.930396) (xy 101.298502 -257.930396)
			(xy 101.297998 -257.956722) (xy 101.289961 -258.008758) (xy 101.274075 -258.058957) (xy 101.250712 -258.106142)
			(xy 101.22042 -258.149208) (xy 101.183908 -258.187146) (xy 101.142034 -258.219065) (xy 101.095778 -258.244218)
			(xy 101.046225 -258.262016) (xy 100.994535 -258.27204) (xy 100.941921 -258.274057) (xy 100.889616 -258.268019)
			(xy 100.838845 -258.254067) (xy 100.7908 -258.232528) (xy 100.746605 -258.203908) (xy 100.707297 -258.168877)
			(xy 100.673797 -258.128256) (xy 100.646891 -258.082997) (xy 100.627208 -258.034162) (xy 100.615211 -257.982894)
			(xy 100.611181 -257.930396) (xy 99.398582 -257.930396) (xy 99.398078 -257.956722) (xy 99.390041 -258.008758)
			(xy 99.374155 -258.058957) (xy 99.350792 -258.106142) (xy 99.3205 -258.149208) (xy 99.283988 -258.187146)
			(xy 99.242114 -258.219065) (xy 99.195858 -258.244218) (xy 99.146305 -258.262016) (xy 99.094615 -258.27204)
			(xy 99.042001 -258.274057) (xy 98.989696 -258.268019) (xy 98.938925 -258.254067) (xy 98.89088 -258.232528)
			(xy 98.846685 -258.203908) (xy 98.807377 -258.168877) (xy 98.773877 -258.128256) (xy 98.746971 -258.082997)
			(xy 98.727288 -258.034162) (xy 98.715291 -257.982894) (xy 98.711261 -257.930396) (xy 87.009986 -257.930396)
			(xy 87.009986 -258.830318) (xy 98.711261 -258.830318) (xy 98.715291 -258.77782) (xy 98.727288 -258.726552)
			(xy 98.746971 -258.677717) (xy 98.773877 -258.632458) (xy 98.807377 -258.591837) (xy 98.846685 -258.556806)
			(xy 98.89088 -258.528186) (xy 98.938925 -258.506647) (xy 98.989696 -258.492695) (xy 99.042001 -258.486657)
			(xy 99.094615 -258.488674) (xy 99.146305 -258.498698) (xy 99.195858 -258.516496) (xy 99.242114 -258.541649)
			(xy 99.283988 -258.573568) (xy 99.3205 -258.611506) (xy 99.350792 -258.654572) (xy 99.374155 -258.701757)
			(xy 99.390041 -258.751956) (xy 99.398078 -258.803992) (xy 99.398582 -258.830318) (xy 100.611181 -258.830318)
			(xy 100.615211 -258.77782) (xy 100.627208 -258.726552) (xy 100.646891 -258.677717) (xy 100.673797 -258.632458)
			(xy 100.707297 -258.591837) (xy 100.746605 -258.556806) (xy 100.7908 -258.528186) (xy 100.838845 -258.506647)
			(xy 100.889616 -258.492695) (xy 100.941921 -258.486657) (xy 100.994535 -258.488674) (xy 101.046225 -258.498698)
			(xy 101.095778 -258.516496) (xy 101.142034 -258.541649) (xy 101.183908 -258.573568) (xy 101.22042 -258.611506)
			(xy 101.250712 -258.654572) (xy 101.274075 -258.701757) (xy 101.289961 -258.751956) (xy 101.297998 -258.803992)
			(xy 101.298502 -258.830318) (xy 102.511101 -258.830318) (xy 102.515131 -258.77782) (xy 102.527128 -258.726552)
			(xy 102.546811 -258.677717) (xy 102.573717 -258.632458) (xy 102.607217 -258.591837) (xy 102.646525 -258.556806)
			(xy 102.69072 -258.528186) (xy 102.738765 -258.506647) (xy 102.789536 -258.492695) (xy 102.841841 -258.486657)
			(xy 102.894455 -258.488674) (xy 102.946145 -258.498698) (xy 102.995698 -258.516496) (xy 103.041954 -258.541649)
			(xy 103.083828 -258.573568) (xy 103.12034 -258.611506) (xy 103.150632 -258.654572) (xy 103.173995 -258.701757)
			(xy 103.189881 -258.751956) (xy 103.197918 -258.803992) (xy 103.198422 -258.830318) (xy 103.197918 -258.856644)
			(xy 103.189881 -258.90868) (xy 103.173995 -258.958879) (xy 103.150632 -259.006064) (xy 103.12034 -259.04913)
			(xy 103.083828 -259.087068) (xy 103.041954 -259.118987) (xy 102.995698 -259.14414) (xy 102.946145 -259.161938)
			(xy 102.894455 -259.171962) (xy 102.841841 -259.173979) (xy 102.789536 -259.167941) (xy 102.738765 -259.153989)
			(xy 102.69072 -259.13245) (xy 102.646525 -259.10383) (xy 102.607217 -259.068799) (xy 102.573717 -259.028178)
			(xy 102.546811 -258.982919) (xy 102.527128 -258.934084) (xy 102.515131 -258.882816) (xy 102.511101 -258.830318)
			(xy 101.298502 -258.830318) (xy 101.297998 -258.856644) (xy 101.289961 -258.90868) (xy 101.274075 -258.958879)
			(xy 101.250712 -259.006064) (xy 101.22042 -259.04913) (xy 101.183908 -259.087068) (xy 101.142034 -259.118987)
			(xy 101.095778 -259.14414) (xy 101.046225 -259.161938) (xy 100.994535 -259.171962) (xy 100.941921 -259.173979)
			(xy 100.889616 -259.167941) (xy 100.838845 -259.153989) (xy 100.7908 -259.13245) (xy 100.746605 -259.10383)
			(xy 100.707297 -259.068799) (xy 100.673797 -259.028178) (xy 100.646891 -258.982919) (xy 100.627208 -258.934084)
			(xy 100.615211 -258.882816) (xy 100.611181 -258.830318) (xy 99.398582 -258.830318) (xy 99.398078 -258.856644)
			(xy 99.390041 -258.90868) (xy 99.374155 -258.958879) (xy 99.350792 -259.006064) (xy 99.3205 -259.04913)
			(xy 99.283988 -259.087068) (xy 99.242114 -259.118987) (xy 99.195858 -259.14414) (xy 99.146305 -259.161938)
			(xy 99.094615 -259.171962) (xy 99.042001 -259.173979) (xy 98.989696 -259.167941) (xy 98.938925 -259.153989)
			(xy 98.89088 -259.13245) (xy 98.846685 -259.10383) (xy 98.807377 -259.068799) (xy 98.773877 -259.028178)
			(xy 98.746971 -258.982919) (xy 98.727288 -258.934084) (xy 98.715291 -258.882816) (xy 98.711261 -258.830318)
			(xy 87.009986 -258.830318) (xy 87.009986 -259.330444) (xy 106.061259 -259.330444) (xy 106.065289 -259.277946)
			(xy 106.077286 -259.226678) (xy 106.096969 -259.177843) (xy 106.123875 -259.132584) (xy 106.157375 -259.091963)
			(xy 106.196683 -259.056932) (xy 106.240878 -259.028312) (xy 106.288923 -259.006773) (xy 106.339694 -258.992821)
			(xy 106.391999 -258.986783) (xy 106.444613 -258.9888) (xy 106.496303 -258.998824) (xy 106.545856 -259.016622)
			(xy 106.592112 -259.041775) (xy 106.633986 -259.073694) (xy 106.670498 -259.111632) (xy 106.70079 -259.154698)
			(xy 106.724153 -259.201883) (xy 106.740039 -259.252082) (xy 106.748076 -259.304118) (xy 106.74858 -259.330444)
			(xy 106.748076 -259.35677) (xy 106.740039 -259.408806) (xy 106.724153 -259.459005) (xy 106.70079 -259.50619)
			(xy 106.670498 -259.549256) (xy 106.633986 -259.587194) (xy 106.592112 -259.619113) (xy 106.545856 -259.644266)
			(xy 106.496303 -259.662064) (xy 106.444613 -259.672088) (xy 106.391999 -259.674105) (xy 106.339694 -259.668067)
			(xy 106.288923 -259.654115) (xy 106.240878 -259.632576) (xy 106.196683 -259.603956) (xy 106.157375 -259.568925)
			(xy 106.123875 -259.528304) (xy 106.096969 -259.483045) (xy 106.077286 -259.43421) (xy 106.065289 -259.382942)
			(xy 106.061259 -259.330444) (xy 87.009986 -259.330444) (xy 87.009986 -259.73024) (xy 98.711261 -259.73024)
			(xy 98.715291 -259.677742) (xy 98.727288 -259.626474) (xy 98.746971 -259.577639) (xy 98.773877 -259.53238)
			(xy 98.807377 -259.491759) (xy 98.846685 -259.456728) (xy 98.89088 -259.428108) (xy 98.938925 -259.406569)
			(xy 98.989696 -259.392617) (xy 99.042001 -259.386579) (xy 99.094615 -259.388596) (xy 99.146305 -259.39862)
			(xy 99.195858 -259.416418) (xy 99.242114 -259.441571) (xy 99.283988 -259.47349) (xy 99.3205 -259.511428)
			(xy 99.350792 -259.554494) (xy 99.374155 -259.601679) (xy 99.390041 -259.651878) (xy 99.398078 -259.703914)
			(xy 99.398582 -259.73024) (xy 100.611181 -259.73024) (xy 100.615211 -259.677742) (xy 100.627208 -259.626474)
			(xy 100.646891 -259.577639) (xy 100.673797 -259.53238) (xy 100.707297 -259.491759) (xy 100.746605 -259.456728)
			(xy 100.7908 -259.428108) (xy 100.838845 -259.406569) (xy 100.889616 -259.392617) (xy 100.941921 -259.386579)
			(xy 100.994535 -259.388596) (xy 101.046225 -259.39862) (xy 101.095778 -259.416418) (xy 101.142034 -259.441571)
			(xy 101.183908 -259.47349) (xy 101.22042 -259.511428) (xy 101.250712 -259.554494) (xy 101.274075 -259.601679)
			(xy 101.289961 -259.651878) (xy 101.297998 -259.703914) (xy 101.298502 -259.73024) (xy 102.511101 -259.73024)
			(xy 102.515131 -259.677742) (xy 102.527128 -259.626474) (xy 102.546811 -259.577639) (xy 102.573717 -259.53238)
			(xy 102.607217 -259.491759) (xy 102.646525 -259.456728) (xy 102.69072 -259.428108) (xy 102.738765 -259.406569)
			(xy 102.789536 -259.392617) (xy 102.841841 -259.386579) (xy 102.894455 -259.388596) (xy 102.946145 -259.39862)
			(xy 102.995698 -259.416418) (xy 103.041954 -259.441571) (xy 103.083828 -259.47349) (xy 103.12034 -259.511428)
			(xy 103.150632 -259.554494) (xy 103.173995 -259.601679) (xy 103.189881 -259.651878) (xy 103.197918 -259.703914)
			(xy 103.198422 -259.73024) (xy 103.197918 -259.756566) (xy 103.189881 -259.808602) (xy 103.173995 -259.858801)
			(xy 103.150632 -259.905986) (xy 103.12034 -259.949052) (xy 103.083828 -259.98699) (xy 103.041954 -260.018909)
			(xy 102.995698 -260.044062) (xy 102.946145 -260.06186) (xy 102.894455 -260.071884) (xy 102.841841 -260.073901)
			(xy 102.789536 -260.067863) (xy 102.738765 -260.053911) (xy 102.69072 -260.032372) (xy 102.646525 -260.003752)
			(xy 102.607217 -259.968721) (xy 102.573717 -259.9281) (xy 102.546811 -259.882841) (xy 102.527128 -259.834006)
			(xy 102.515131 -259.782738) (xy 102.511101 -259.73024) (xy 101.298502 -259.73024) (xy 101.297998 -259.756566)
			(xy 101.289961 -259.808602) (xy 101.274075 -259.858801) (xy 101.250712 -259.905986) (xy 101.22042 -259.949052)
			(xy 101.183908 -259.98699) (xy 101.142034 -260.018909) (xy 101.095778 -260.044062) (xy 101.046225 -260.06186)
			(xy 100.994535 -260.071884) (xy 100.941921 -260.073901) (xy 100.889616 -260.067863) (xy 100.838845 -260.053911)
			(xy 100.7908 -260.032372) (xy 100.746605 -260.003752) (xy 100.707297 -259.968721) (xy 100.673797 -259.9281)
			(xy 100.646891 -259.882841) (xy 100.627208 -259.834006) (xy 100.615211 -259.782738) (xy 100.611181 -259.73024)
			(xy 99.398582 -259.73024) (xy 99.398078 -259.756566) (xy 99.390041 -259.808602) (xy 99.374155 -259.858801)
			(xy 99.350792 -259.905986) (xy 99.3205 -259.949052) (xy 99.283988 -259.98699) (xy 99.242114 -260.018909)
			(xy 99.195858 -260.044062) (xy 99.146305 -260.06186) (xy 99.094615 -260.071884) (xy 99.042001 -260.073901)
			(xy 98.989696 -260.067863) (xy 98.938925 -260.053911) (xy 98.89088 -260.032372) (xy 98.846685 -260.003752)
			(xy 98.807377 -259.968721) (xy 98.773877 -259.9281) (xy 98.746971 -259.882841) (xy 98.727288 -259.834006)
			(xy 98.715291 -259.782738) (xy 98.711261 -259.73024) (xy 87.009986 -259.73024) (xy 87.009986 -260.280404)
			(xy 106.061259 -260.280404) (xy 106.065289 -260.227906) (xy 106.077286 -260.176638) (xy 106.096969 -260.127803)
			(xy 106.123875 -260.082544) (xy 106.157375 -260.041923) (xy 106.196683 -260.006892) (xy 106.240878 -259.978272)
			(xy 106.288923 -259.956733) (xy 106.339694 -259.942781) (xy 106.391999 -259.936743) (xy 106.444613 -259.93876)
			(xy 106.496303 -259.948784) (xy 106.545856 -259.966582) (xy 106.592112 -259.991735) (xy 106.633986 -260.023654)
			(xy 106.670498 -260.061592) (xy 106.70079 -260.104658) (xy 106.724153 -260.151843) (xy 106.740039 -260.202042)
			(xy 106.748076 -260.254078) (xy 106.74858 -260.280404) (xy 106.748076 -260.30673) (xy 106.740039 -260.358766)
			(xy 106.724153 -260.408965) (xy 106.70079 -260.45615) (xy 106.670498 -260.499216) (xy 106.633986 -260.537154)
			(xy 106.592112 -260.569073) (xy 106.545856 -260.594226) (xy 106.496303 -260.612024) (xy 106.444613 -260.622048)
			(xy 106.391999 -260.624065) (xy 106.339694 -260.618027) (xy 106.288923 -260.604075) (xy 106.240878 -260.582536)
			(xy 106.196683 -260.553916) (xy 106.157375 -260.518885) (xy 106.123875 -260.478264) (xy 106.096969 -260.433005)
			(xy 106.077286 -260.38417) (xy 106.065289 -260.332902) (xy 106.061259 -260.280404) (xy 87.009986 -260.280404)
			(xy 87.009986 -261.126224) (xy 87.805272 -261.126224) (xy 87.809232 -261.07717) (xy 87.821009 -261.029386)
			(xy 87.8403 -260.98411) (xy 87.866603 -260.942514) (xy 87.899238 -260.905677) (xy 87.937359 -260.874552)
			(xy 87.97998 -260.849945) (xy 88.025996 -260.832493) (xy 88.074215 -260.822649) (xy 88.12339 -260.820668)
			(xy 88.172245 -260.8266) (xy 88.219516 -260.840292) (xy 88.263978 -260.86139) (xy 88.304481 -260.889346)
			(xy 88.339974 -260.923438) (xy 88.369539 -260.962782) (xy 88.39241 -261.006359) (xy 88.407994 -261.05304)
			(xy 88.415889 -261.101617) (xy 88.416384 -261.126224) (xy 88.745326 -261.126224) (xy 88.749286 -261.07717)
			(xy 88.761063 -261.029386) (xy 88.780354 -260.98411) (xy 88.806657 -260.942514) (xy 88.839292 -260.905677)
			(xy 88.877413 -260.874552) (xy 88.920034 -260.849945) (xy 88.96605 -260.832493) (xy 89.014269 -260.822649)
			(xy 89.063444 -260.820668) (xy 89.112299 -260.8266) (xy 89.15957 -260.840292) (xy 89.204032 -260.86139)
			(xy 89.244535 -260.889346) (xy 89.280028 -260.923438) (xy 89.309593 -260.962782) (xy 89.332464 -261.006359)
			(xy 89.348048 -261.05304) (xy 89.355943 -261.101617) (xy 89.356438 -261.126224) (xy 89.685126 -261.126224)
			(xy 89.689086 -261.07717) (xy 89.700863 -261.029386) (xy 89.720154 -260.98411) (xy 89.746457 -260.942514)
			(xy 89.779092 -260.905677) (xy 89.817213 -260.874552) (xy 89.859834 -260.849945) (xy 89.90585 -260.832493)
			(xy 89.954069 -260.822649) (xy 90.003244 -260.820668) (xy 90.052099 -260.8266) (xy 90.09937 -260.840292)
			(xy 90.143832 -260.86139) (xy 90.184335 -260.889346) (xy 90.219828 -260.923438) (xy 90.249393 -260.962782)
			(xy 90.272264 -261.006359) (xy 90.287848 -261.05304) (xy 90.295743 -261.101617) (xy 90.296238 -261.126224)
			(xy 90.62518 -261.126224) (xy 90.62914 -261.07717) (xy 90.640917 -261.029386) (xy 90.660208 -260.98411)
			(xy 90.686511 -260.942514) (xy 90.719146 -260.905677) (xy 90.757267 -260.874552) (xy 90.799888 -260.849945)
			(xy 90.845904 -260.832493) (xy 90.894123 -260.822649) (xy 90.943298 -260.820668) (xy 90.992153 -260.8266)
			(xy 91.039424 -260.840292) (xy 91.083886 -260.86139) (xy 91.124389 -260.889346) (xy 91.159882 -260.923438)
			(xy 91.189447 -260.962782) (xy 91.212318 -261.006359) (xy 91.227902 -261.05304) (xy 91.235797 -261.101617)
			(xy 91.236292 -261.126224) (xy 91.565234 -261.126224) (xy 91.569194 -261.07717) (xy 91.580971 -261.029386)
			(xy 91.600262 -260.98411) (xy 91.626565 -260.942514) (xy 91.6592 -260.905677) (xy 91.697321 -260.874552)
			(xy 91.739942 -260.849945) (xy 91.785958 -260.832493) (xy 91.834177 -260.822649) (xy 91.883352 -260.820668)
			(xy 91.932207 -260.8266) (xy 91.979478 -260.840292) (xy 92.02394 -260.86139) (xy 92.064443 -260.889346)
			(xy 92.099936 -260.923438) (xy 92.129501 -260.962782) (xy 92.152372 -261.006359) (xy 92.167956 -261.05304)
			(xy 92.175851 -261.101617) (xy 92.176346 -261.126224) (xy 92.505288 -261.126224) (xy 92.509248 -261.07717)
			(xy 92.521025 -261.029386) (xy 92.540316 -260.98411) (xy 92.566619 -260.942514) (xy 92.599254 -260.905677)
			(xy 92.637375 -260.874552) (xy 92.679996 -260.849945) (xy 92.726012 -260.832493) (xy 92.774231 -260.822649)
			(xy 92.823406 -260.820668) (xy 92.872261 -260.8266) (xy 92.919532 -260.840292) (xy 92.963994 -260.86139)
			(xy 93.004497 -260.889346) (xy 93.03999 -260.923438) (xy 93.069555 -260.962782) (xy 93.092426 -261.006359)
			(xy 93.10801 -261.05304) (xy 93.115905 -261.101617) (xy 93.1164 -261.126224) (xy 94.385142 -261.126224)
			(xy 94.389102 -261.07717) (xy 94.400879 -261.029386) (xy 94.42017 -260.98411) (xy 94.446473 -260.942514)
			(xy 94.479108 -260.905677) (xy 94.517229 -260.874552) (xy 94.55985 -260.849945) (xy 94.605866 -260.832493)
			(xy 94.654085 -260.822649) (xy 94.70326 -260.820668) (xy 94.752115 -260.8266) (xy 94.799386 -260.840292)
			(xy 94.843848 -260.86139) (xy 94.884351 -260.889346) (xy 94.919844 -260.923438) (xy 94.949409 -260.962782)
			(xy 94.97228 -261.006359) (xy 94.987864 -261.05304) (xy 94.995759 -261.101617) (xy 94.996254 -261.126224)
			(xy 95.325196 -261.126224) (xy 95.329156 -261.07717) (xy 95.340933 -261.029386) (xy 95.360224 -260.98411)
			(xy 95.386527 -260.942514) (xy 95.419162 -260.905677) (xy 95.457283 -260.874552) (xy 95.499904 -260.849945)
			(xy 95.54592 -260.832493) (xy 95.594139 -260.822649) (xy 95.643314 -260.820668) (xy 95.692169 -260.8266)
			(xy 95.73944 -260.840292) (xy 95.783902 -260.86139) (xy 95.824405 -260.889346) (xy 95.859898 -260.923438)
			(xy 95.889463 -260.962782) (xy 95.912334 -261.006359) (xy 95.927918 -261.05304) (xy 95.935813 -261.101617)
			(xy 95.936308 -261.126224) (xy 96.26525 -261.126224) (xy 96.26921 -261.07717) (xy 96.280987 -261.029386)
			(xy 96.300278 -260.98411) (xy 96.326581 -260.942514) (xy 96.359216 -260.905677) (xy 96.397337 -260.874552)
			(xy 96.439958 -260.849945) (xy 96.485974 -260.832493) (xy 96.534193 -260.822649) (xy 96.583368 -260.820668)
			(xy 96.632223 -260.8266) (xy 96.679494 -260.840292) (xy 96.723956 -260.86139) (xy 96.764459 -260.889346)
			(xy 96.799952 -260.923438) (xy 96.829517 -260.962782) (xy 96.852388 -261.006359) (xy 96.867972 -261.05304)
			(xy 96.875867 -261.101617) (xy 96.876362 -261.126224) (xy 98.145358 -261.126224) (xy 98.149318 -261.07717)
			(xy 98.161095 -261.029386) (xy 98.180386 -260.98411) (xy 98.206689 -260.942514) (xy 98.239324 -260.905677)
			(xy 98.277445 -260.874552) (xy 98.320066 -260.849945) (xy 98.366082 -260.832493) (xy 98.414301 -260.822649)
			(xy 98.463476 -260.820668) (xy 98.512331 -260.8266) (xy 98.559602 -260.840292) (xy 98.604064 -260.86139)
			(xy 98.644567 -260.889346) (xy 98.68006 -260.923438) (xy 98.709625 -260.962782) (xy 98.732496 -261.006359)
			(xy 98.74808 -261.05304) (xy 98.755975 -261.101617) (xy 98.75647 -261.126224) (xy 100.025212 -261.126224)
			(xy 100.029172 -261.07717) (xy 100.040949 -261.029386) (xy 100.06024 -260.98411) (xy 100.086543 -260.942514)
			(xy 100.119178 -260.905677) (xy 100.157299 -260.874552) (xy 100.19992 -260.849945) (xy 100.245936 -260.832493)
			(xy 100.294155 -260.822649) (xy 100.34333 -260.820668) (xy 100.392185 -260.8266) (xy 100.439456 -260.840292)
			(xy 100.483918 -260.86139) (xy 100.524421 -260.889346) (xy 100.559914 -260.923438) (xy 100.589479 -260.962782)
			(xy 100.61235 -261.006359) (xy 100.627934 -261.05304) (xy 100.635829 -261.101617) (xy 100.636324 -261.126224)
			(xy 100.965266 -261.126224) (xy 100.969226 -261.07717) (xy 100.981003 -261.029386) (xy 101.000294 -260.98411)
			(xy 101.026597 -260.942514) (xy 101.059232 -260.905677) (xy 101.097353 -260.874552) (xy 101.139974 -260.849945)
			(xy 101.18599 -260.832493) (xy 101.234209 -260.822649) (xy 101.283384 -260.820668) (xy 101.332239 -260.8266)
			(xy 101.37951 -260.840292) (xy 101.423972 -260.86139) (xy 101.464475 -260.889346) (xy 101.499968 -260.923438)
			(xy 101.529533 -260.962782) (xy 101.552404 -261.006359) (xy 101.567988 -261.05304) (xy 101.575883 -261.101617)
			(xy 101.576378 -261.126224) (xy 101.90532 -261.126224) (xy 101.90928 -261.07717) (xy 101.921057 -261.029386)
			(xy 101.940348 -260.98411) (xy 101.966651 -260.942514) (xy 101.999286 -260.905677) (xy 102.037407 -260.874552)
			(xy 102.080028 -260.849945) (xy 102.126044 -260.832493) (xy 102.174263 -260.822649) (xy 102.223438 -260.820668)
			(xy 102.272293 -260.8266) (xy 102.319564 -260.840292) (xy 102.364026 -260.86139) (xy 102.404529 -260.889346)
			(xy 102.440022 -260.923438) (xy 102.469587 -260.962782) (xy 102.492458 -261.006359) (xy 102.508042 -261.05304)
			(xy 102.515937 -261.101617) (xy 102.516432 -261.126224) (xy 102.516391 -261.128256) (xy 102.842072 -261.128256)
			(xy 102.846032 -261.079202) (xy 102.857809 -261.031418) (xy 102.8771 -260.986142) (xy 102.903403 -260.944546)
			(xy 102.936038 -260.907709) (xy 102.974159 -260.876584) (xy 103.01678 -260.851977) (xy 103.062796 -260.834525)
			(xy 103.111015 -260.824681) (xy 103.16019 -260.8227) (xy 103.209045 -260.828632) (xy 103.256316 -260.842324)
			(xy 103.300778 -260.863422) (xy 103.341281 -260.891378) (xy 103.376774 -260.92547) (xy 103.406339 -260.964814)
			(xy 103.42921 -261.008391) (xy 103.444794 -261.055072) (xy 103.452689 -261.103649) (xy 103.453184 -261.128256)
			(xy 103.782126 -261.128256) (xy 103.786086 -261.079202) (xy 103.797863 -261.031418) (xy 103.817154 -260.986142)
			(xy 103.843457 -260.944546) (xy 103.876092 -260.907709) (xy 103.914213 -260.876584) (xy 103.956834 -260.851977)
			(xy 104.00285 -260.834525) (xy 104.051069 -260.824681) (xy 104.100244 -260.8227) (xy 104.149099 -260.828632)
			(xy 104.19637 -260.842324) (xy 104.240832 -260.863422) (xy 104.281335 -260.891378) (xy 104.316828 -260.92547)
			(xy 104.346393 -260.964814) (xy 104.369264 -261.008391) (xy 104.384848 -261.055072) (xy 104.392743 -261.103649)
			(xy 104.393238 -261.128256) (xy 104.392743 -261.152863) (xy 104.384848 -261.20144) (xy 104.375192 -261.230364)
			(xy 106.061259 -261.230364) (xy 106.065289 -261.177866) (xy 106.077286 -261.126598) (xy 106.096969 -261.077763)
			(xy 106.123875 -261.032504) (xy 106.157375 -260.991883) (xy 106.196683 -260.956852) (xy 106.240878 -260.928232)
			(xy 106.288923 -260.906693) (xy 106.339694 -260.892741) (xy 106.391999 -260.886703) (xy 106.444613 -260.88872)
			(xy 106.496303 -260.898744) (xy 106.545856 -260.916542) (xy 106.592112 -260.941695) (xy 106.633986 -260.973614)
			(xy 106.670498 -261.011552) (xy 106.70079 -261.054618) (xy 106.724153 -261.101803) (xy 106.740039 -261.152002)
			(xy 106.748076 -261.204038) (xy 106.74858 -261.230364) (xy 106.748076 -261.25669) (xy 106.740039 -261.308726)
			(xy 106.735498 -261.323074) (xy 107.304081 -261.323074) (xy 107.308111 -261.270576) (xy 107.320108 -261.219308)
			(xy 107.339791 -261.170473) (xy 107.366697 -261.125214) (xy 107.400197 -261.084593) (xy 107.439505 -261.049562)
			(xy 107.4837 -261.020942) (xy 107.531745 -260.999403) (xy 107.582516 -260.985451) (xy 107.634821 -260.979413)
			(xy 107.687435 -260.98143) (xy 107.739125 -260.991454) (xy 107.788678 -261.009252) (xy 107.834934 -261.034405)
			(xy 107.876808 -261.066324) (xy 107.91332 -261.104262) (xy 107.943612 -261.147328) (xy 107.966975 -261.194513)
			(xy 107.982861 -261.244712) (xy 107.990898 -261.296748) (xy 107.991402 -261.323074) (xy 107.990898 -261.3494)
			(xy 107.982861 -261.401436) (xy 107.966975 -261.451635) (xy 107.943612 -261.49882) (xy 107.91332 -261.541886)
			(xy 107.876808 -261.579824) (xy 107.834934 -261.611743) (xy 107.788678 -261.636896) (xy 107.739125 -261.654694)
			(xy 107.687435 -261.664718) (xy 107.634821 -261.666735) (xy 107.582516 -261.660697) (xy 107.531745 -261.646745)
			(xy 107.4837 -261.625206) (xy 107.439505 -261.596586) (xy 107.400197 -261.561555) (xy 107.366697 -261.520934)
			(xy 107.339791 -261.475675) (xy 107.320108 -261.42684) (xy 107.308111 -261.375572) (xy 107.304081 -261.323074)
			(xy 106.735498 -261.323074) (xy 106.724153 -261.358925) (xy 106.70079 -261.40611) (xy 106.670498 -261.449176)
			(xy 106.633986 -261.487114) (xy 106.592112 -261.519033) (xy 106.545856 -261.544186) (xy 106.496303 -261.561984)
			(xy 106.444613 -261.572008) (xy 106.391999 -261.574025) (xy 106.339694 -261.567987) (xy 106.288923 -261.554035)
			(xy 106.240878 -261.532496) (xy 106.196683 -261.503876) (xy 106.157375 -261.468845) (xy 106.123875 -261.428224)
			(xy 106.096969 -261.382965) (xy 106.077286 -261.33413) (xy 106.065289 -261.282862) (xy 106.061259 -261.230364)
			(xy 104.375192 -261.230364) (xy 104.369264 -261.248121) (xy 104.346393 -261.291698) (xy 104.316828 -261.331042)
			(xy 104.281335 -261.365134) (xy 104.240832 -261.39309) (xy 104.19637 -261.414188) (xy 104.149099 -261.42788)
			(xy 104.100244 -261.433812) (xy 104.051069 -261.431831) (xy 104.00285 -261.421987) (xy 103.956834 -261.404535)
			(xy 103.914213 -261.379928) (xy 103.876092 -261.348803) (xy 103.843457 -261.311966) (xy 103.817154 -261.27037)
			(xy 103.797863 -261.225094) (xy 103.786086 -261.17731) (xy 103.782126 -261.128256) (xy 103.453184 -261.128256)
			(xy 103.452689 -261.152863) (xy 103.444794 -261.20144) (xy 103.42921 -261.248121) (xy 103.406339 -261.291698)
			(xy 103.376774 -261.331042) (xy 103.341281 -261.365134) (xy 103.300778 -261.39309) (xy 103.256316 -261.414188)
			(xy 103.209045 -261.42788) (xy 103.16019 -261.433812) (xy 103.111015 -261.431831) (xy 103.062796 -261.421987)
			(xy 103.01678 -261.404535) (xy 102.974159 -261.379928) (xy 102.936038 -261.348803) (xy 102.903403 -261.311966)
			(xy 102.8771 -261.27037) (xy 102.857809 -261.225094) (xy 102.846032 -261.17731) (xy 102.842072 -261.128256)
			(xy 102.516391 -261.128256) (xy 102.515937 -261.150831) (xy 102.508042 -261.199408) (xy 102.492458 -261.246089)
			(xy 102.469587 -261.289666) (xy 102.440022 -261.32901) (xy 102.404529 -261.363102) (xy 102.364026 -261.391058)
			(xy 102.319564 -261.412156) (xy 102.272293 -261.425848) (xy 102.223438 -261.43178) (xy 102.174263 -261.429799)
			(xy 102.126044 -261.419955) (xy 102.080028 -261.402503) (xy 102.037407 -261.377896) (xy 101.999286 -261.346771)
			(xy 101.966651 -261.309934) (xy 101.940348 -261.268338) (xy 101.921057 -261.223062) (xy 101.90928 -261.175278)
			(xy 101.90532 -261.126224) (xy 101.576378 -261.126224) (xy 101.575883 -261.150831) (xy 101.567988 -261.199408)
			(xy 101.552404 -261.246089) (xy 101.529533 -261.289666) (xy 101.499968 -261.32901) (xy 101.464475 -261.363102)
			(xy 101.423972 -261.391058) (xy 101.37951 -261.412156) (xy 101.332239 -261.425848) (xy 101.283384 -261.43178)
			(xy 101.234209 -261.429799) (xy 101.18599 -261.419955) (xy 101.139974 -261.402503) (xy 101.097353 -261.377896)
			(xy 101.059232 -261.346771) (xy 101.026597 -261.309934) (xy 101.000294 -261.268338) (xy 100.981003 -261.223062)
			(xy 100.969226 -261.175278) (xy 100.965266 -261.126224) (xy 100.636324 -261.126224) (xy 100.635829 -261.150831)
			(xy 100.627934 -261.199408) (xy 100.61235 -261.246089) (xy 100.589479 -261.289666) (xy 100.559914 -261.32901)
			(xy 100.524421 -261.363102) (xy 100.483918 -261.391058) (xy 100.439456 -261.412156) (xy 100.392185 -261.425848)
			(xy 100.34333 -261.43178) (xy 100.294155 -261.429799) (xy 100.245936 -261.419955) (xy 100.19992 -261.402503)
			(xy 100.157299 -261.377896) (xy 100.119178 -261.346771) (xy 100.086543 -261.309934) (xy 100.06024 -261.268338)
			(xy 100.040949 -261.223062) (xy 100.029172 -261.175278) (xy 100.025212 -261.126224) (xy 98.75647 -261.126224)
			(xy 98.755975 -261.150831) (xy 98.74808 -261.199408) (xy 98.732496 -261.246089) (xy 98.709625 -261.289666)
			(xy 98.68006 -261.32901) (xy 98.644567 -261.363102) (xy 98.604064 -261.391058) (xy 98.559602 -261.412156)
			(xy 98.512331 -261.425848) (xy 98.463476 -261.43178) (xy 98.414301 -261.429799) (xy 98.366082 -261.419955)
			(xy 98.320066 -261.402503) (xy 98.277445 -261.377896) (xy 98.239324 -261.346771) (xy 98.206689 -261.309934)
			(xy 98.180386 -261.268338) (xy 98.161095 -261.223062) (xy 98.149318 -261.175278) (xy 98.145358 -261.126224)
			(xy 96.876362 -261.126224) (xy 96.875867 -261.150831) (xy 96.867972 -261.199408) (xy 96.852388 -261.246089)
			(xy 96.829517 -261.289666) (xy 96.799952 -261.32901) (xy 96.764459 -261.363102) (xy 96.723956 -261.391058)
			(xy 96.679494 -261.412156) (xy 96.632223 -261.425848) (xy 96.583368 -261.43178) (xy 96.534193 -261.429799)
			(xy 96.485974 -261.419955) (xy 96.439958 -261.402503) (xy 96.397337 -261.377896) (xy 96.359216 -261.346771)
			(xy 96.326581 -261.309934) (xy 96.300278 -261.268338) (xy 96.280987 -261.223062) (xy 96.26921 -261.175278)
			(xy 96.26525 -261.126224) (xy 95.936308 -261.126224) (xy 95.935813 -261.150831) (xy 95.927918 -261.199408)
			(xy 95.912334 -261.246089) (xy 95.889463 -261.289666) (xy 95.859898 -261.32901) (xy 95.824405 -261.363102)
			(xy 95.783902 -261.391058) (xy 95.73944 -261.412156) (xy 95.692169 -261.425848) (xy 95.643314 -261.43178)
			(xy 95.594139 -261.429799) (xy 95.54592 -261.419955) (xy 95.499904 -261.402503) (xy 95.457283 -261.377896)
			(xy 95.419162 -261.346771) (xy 95.386527 -261.309934) (xy 95.360224 -261.268338) (xy 95.340933 -261.223062)
			(xy 95.329156 -261.175278) (xy 95.325196 -261.126224) (xy 94.996254 -261.126224) (xy 94.995759 -261.150831)
			(xy 94.987864 -261.199408) (xy 94.97228 -261.246089) (xy 94.949409 -261.289666) (xy 94.919844 -261.32901)
			(xy 94.884351 -261.363102) (xy 94.843848 -261.391058) (xy 94.799386 -261.412156) (xy 94.752115 -261.425848)
			(xy 94.70326 -261.43178) (xy 94.654085 -261.429799) (xy 94.605866 -261.419955) (xy 94.55985 -261.402503)
			(xy 94.517229 -261.377896) (xy 94.479108 -261.346771) (xy 94.446473 -261.309934) (xy 94.42017 -261.268338)
			(xy 94.400879 -261.223062) (xy 94.389102 -261.175278) (xy 94.385142 -261.126224) (xy 93.1164 -261.126224)
			(xy 93.115905 -261.150831) (xy 93.10801 -261.199408) (xy 93.092426 -261.246089) (xy 93.069555 -261.289666)
			(xy 93.03999 -261.32901) (xy 93.004497 -261.363102) (xy 92.963994 -261.391058) (xy 92.919532 -261.412156)
			(xy 92.872261 -261.425848) (xy 92.823406 -261.43178) (xy 92.774231 -261.429799) (xy 92.726012 -261.419955)
			(xy 92.679996 -261.402503) (xy 92.637375 -261.377896) (xy 92.599254 -261.346771) (xy 92.566619 -261.309934)
			(xy 92.540316 -261.268338) (xy 92.521025 -261.223062) (xy 92.509248 -261.175278) (xy 92.505288 -261.126224)
			(xy 92.176346 -261.126224) (xy 92.175851 -261.150831) (xy 92.167956 -261.199408) (xy 92.152372 -261.246089)
			(xy 92.129501 -261.289666) (xy 92.099936 -261.32901) (xy 92.064443 -261.363102) (xy 92.02394 -261.391058)
			(xy 91.979478 -261.412156) (xy 91.932207 -261.425848) (xy 91.883352 -261.43178) (xy 91.834177 -261.429799)
			(xy 91.785958 -261.419955) (xy 91.739942 -261.402503) (xy 91.697321 -261.377896) (xy 91.6592 -261.346771)
			(xy 91.626565 -261.309934) (xy 91.600262 -261.268338) (xy 91.580971 -261.223062) (xy 91.569194 -261.175278)
			(xy 91.565234 -261.126224) (xy 91.236292 -261.126224) (xy 91.235797 -261.150831) (xy 91.227902 -261.199408)
			(xy 91.212318 -261.246089) (xy 91.189447 -261.289666) (xy 91.159882 -261.32901) (xy 91.124389 -261.363102)
			(xy 91.083886 -261.391058) (xy 91.039424 -261.412156) (xy 90.992153 -261.425848) (xy 90.943298 -261.43178)
			(xy 90.894123 -261.429799) (xy 90.845904 -261.419955) (xy 90.799888 -261.402503) (xy 90.757267 -261.377896)
			(xy 90.719146 -261.346771) (xy 90.686511 -261.309934) (xy 90.660208 -261.268338) (xy 90.640917 -261.223062)
			(xy 90.62914 -261.175278) (xy 90.62518 -261.126224) (xy 90.296238 -261.126224) (xy 90.295743 -261.150831)
			(xy 90.287848 -261.199408) (xy 90.272264 -261.246089) (xy 90.249393 -261.289666) (xy 90.219828 -261.32901)
			(xy 90.184335 -261.363102) (xy 90.143832 -261.391058) (xy 90.09937 -261.412156) (xy 90.052099 -261.425848)
			(xy 90.003244 -261.43178) (xy 89.954069 -261.429799) (xy 89.90585 -261.419955) (xy 89.859834 -261.402503)
			(xy 89.817213 -261.377896) (xy 89.779092 -261.346771) (xy 89.746457 -261.309934) (xy 89.720154 -261.268338)
			(xy 89.700863 -261.223062) (xy 89.689086 -261.175278) (xy 89.685126 -261.126224) (xy 89.356438 -261.126224)
			(xy 89.355943 -261.150831) (xy 89.348048 -261.199408) (xy 89.332464 -261.246089) (xy 89.309593 -261.289666)
			(xy 89.280028 -261.32901) (xy 89.244535 -261.363102) (xy 89.204032 -261.391058) (xy 89.15957 -261.412156)
			(xy 89.112299 -261.425848) (xy 89.063444 -261.43178) (xy 89.014269 -261.429799) (xy 88.96605 -261.419955)
			(xy 88.920034 -261.402503) (xy 88.877413 -261.377896) (xy 88.839292 -261.346771) (xy 88.806657 -261.309934)
			(xy 88.780354 -261.268338) (xy 88.761063 -261.223062) (xy 88.749286 -261.175278) (xy 88.745326 -261.126224)
			(xy 88.416384 -261.126224) (xy 88.415889 -261.150831) (xy 88.407994 -261.199408) (xy 88.39241 -261.246089)
			(xy 88.369539 -261.289666) (xy 88.339974 -261.32901) (xy 88.304481 -261.363102) (xy 88.263978 -261.391058)
			(xy 88.219516 -261.412156) (xy 88.172245 -261.425848) (xy 88.12339 -261.43178) (xy 88.074215 -261.429799)
			(xy 88.025996 -261.419955) (xy 87.97998 -261.402503) (xy 87.937359 -261.377896) (xy 87.899238 -261.346771)
			(xy 87.866603 -261.309934) (xy 87.8403 -261.268338) (xy 87.821009 -261.223062) (xy 87.809232 -261.175278)
			(xy 87.805272 -261.126224) (xy 87.009986 -261.126224) (xy 87.009986 -261.93623) (xy 87.335118 -261.93623)
			(xy 87.339078 -261.887176) (xy 87.350855 -261.839392) (xy 87.370146 -261.794116) (xy 87.396449 -261.75252)
			(xy 87.429084 -261.715683) (xy 87.467205 -261.684558) (xy 87.509826 -261.659951) (xy 87.555842 -261.642499)
			(xy 87.604061 -261.632655) (xy 87.653236 -261.630674) (xy 87.702091 -261.636606) (xy 87.749362 -261.650298)
			(xy 87.793824 -261.671396) (xy 87.834327 -261.699352) (xy 87.86982 -261.733444) (xy 87.899385 -261.772788)
			(xy 87.922256 -261.816365) (xy 87.93784 -261.863046) (xy 87.945735 -261.911623) (xy 87.94623 -261.93623)
			(xy 88.275172 -261.93623) (xy 88.279132 -261.887176) (xy 88.290909 -261.839392) (xy 88.3102 -261.794116)
			(xy 88.336503 -261.75252) (xy 88.369138 -261.715683) (xy 88.407259 -261.684558) (xy 88.44988 -261.659951)
			(xy 88.495896 -261.642499) (xy 88.544115 -261.632655) (xy 88.59329 -261.630674) (xy 88.642145 -261.636606)
			(xy 88.689416 -261.650298) (xy 88.733878 -261.671396) (xy 88.774381 -261.699352) (xy 88.809874 -261.733444)
			(xy 88.839439 -261.772788) (xy 88.86231 -261.816365) (xy 88.877894 -261.863046) (xy 88.885789 -261.911623)
			(xy 88.886284 -261.93623) (xy 89.215226 -261.93623) (xy 89.219186 -261.887176) (xy 89.230963 -261.839392)
			(xy 89.250254 -261.794116) (xy 89.276557 -261.75252) (xy 89.309192 -261.715683) (xy 89.347313 -261.684558)
			(xy 89.389934 -261.659951) (xy 89.43595 -261.642499) (xy 89.484169 -261.632655) (xy 89.533344 -261.630674)
			(xy 89.582199 -261.636606) (xy 89.62947 -261.650298) (xy 89.673932 -261.671396) (xy 89.714435 -261.699352)
			(xy 89.749928 -261.733444) (xy 89.779493 -261.772788) (xy 89.802364 -261.816365) (xy 89.817948 -261.863046)
			(xy 89.825843 -261.911623) (xy 89.826338 -261.93623) (xy 90.15528 -261.93623) (xy 90.15924 -261.887176)
			(xy 90.171017 -261.839392) (xy 90.190308 -261.794116) (xy 90.216611 -261.75252) (xy 90.249246 -261.715683)
			(xy 90.287367 -261.684558) (xy 90.329988 -261.659951) (xy 90.376004 -261.642499) (xy 90.424223 -261.632655)
			(xy 90.473398 -261.630674) (xy 90.522253 -261.636606) (xy 90.569524 -261.650298) (xy 90.613986 -261.671396)
			(xy 90.654489 -261.699352) (xy 90.689982 -261.733444) (xy 90.719547 -261.772788) (xy 90.742418 -261.816365)
			(xy 90.758002 -261.863046) (xy 90.765897 -261.911623) (xy 90.766392 -261.93623) (xy 91.095334 -261.93623)
			(xy 91.099294 -261.887176) (xy 91.111071 -261.839392) (xy 91.130362 -261.794116) (xy 91.156665 -261.75252)
			(xy 91.1893 -261.715683) (xy 91.227421 -261.684558) (xy 91.270042 -261.659951) (xy 91.316058 -261.642499)
			(xy 91.364277 -261.632655) (xy 91.413452 -261.630674) (xy 91.462307 -261.636606) (xy 91.509578 -261.650298)
			(xy 91.55404 -261.671396) (xy 91.594543 -261.699352) (xy 91.630036 -261.733444) (xy 91.659601 -261.772788)
			(xy 91.682472 -261.816365) (xy 91.698056 -261.863046) (xy 91.705951 -261.911623) (xy 91.706446 -261.93623)
			(xy 92.024703 -261.93623) (xy 92.028798 -261.885502) (xy 92.040977 -261.836088) (xy 92.060925 -261.789268)
			(xy 92.088126 -261.746254) (xy 92.121874 -261.70816) (xy 92.161296 -261.675973) (xy 92.20537 -261.650527)
			(xy 92.252956 -261.63248) (xy 92.30282 -261.6223) (xy 92.353672 -261.620251) (xy 92.404193 -261.626385)
			(xy 92.453077 -261.640545) (xy 92.499056 -261.662362) (xy 92.54094 -261.691272) (xy 92.577644 -261.726527)
			(xy 92.608217 -261.767213) (xy 92.631868 -261.812276) (xy 92.647984 -261.86055) (xy 92.656148 -261.910784)
			(xy 92.65666 -261.93623) (xy 92.975188 -261.93623) (xy 92.979148 -261.887176) (xy 92.990925 -261.839392)
			(xy 93.010216 -261.794116) (xy 93.036519 -261.75252) (xy 93.069154 -261.715683) (xy 93.107275 -261.684558)
			(xy 93.149896 -261.659951) (xy 93.195912 -261.642499) (xy 93.244131 -261.632655) (xy 93.293306 -261.630674)
			(xy 93.342161 -261.636606) (xy 93.389432 -261.650298) (xy 93.433894 -261.671396) (xy 93.474397 -261.699352)
			(xy 93.50989 -261.733444) (xy 93.539455 -261.772788) (xy 93.562326 -261.816365) (xy 93.57791 -261.863046)
			(xy 93.585805 -261.911623) (xy 93.5863 -261.93623) (xy 93.915242 -261.93623) (xy 93.919202 -261.887176)
			(xy 93.930979 -261.839392) (xy 93.95027 -261.794116) (xy 93.976573 -261.75252) (xy 94.009208 -261.715683)
			(xy 94.047329 -261.684558) (xy 94.08995 -261.659951) (xy 94.135966 -261.642499) (xy 94.184185 -261.632655)
			(xy 94.23336 -261.630674) (xy 94.282215 -261.636606) (xy 94.329486 -261.650298) (xy 94.373948 -261.671396)
			(xy 94.414451 -261.699352) (xy 94.449944 -261.733444) (xy 94.479509 -261.772788) (xy 94.50238 -261.816365)
			(xy 94.517964 -261.863046) (xy 94.525859 -261.911623) (xy 94.526354 -261.93623) (xy 94.855296 -261.93623)
			(xy 94.859256 -261.887176) (xy 94.871033 -261.839392) (xy 94.890324 -261.794116) (xy 94.916627 -261.75252)
			(xy 94.949262 -261.715683) (xy 94.987383 -261.684558) (xy 95.030004 -261.659951) (xy 95.07602 -261.642499)
			(xy 95.124239 -261.632655) (xy 95.173414 -261.630674) (xy 95.222269 -261.636606) (xy 95.26954 -261.650298)
			(xy 95.314002 -261.671396) (xy 95.354505 -261.699352) (xy 95.389998 -261.733444) (xy 95.419563 -261.772788)
			(xy 95.442434 -261.816365) (xy 95.458018 -261.863046) (xy 95.465913 -261.911623) (xy 95.466408 -261.93623)
			(xy 95.784919 -261.93623) (xy 95.789014 -261.885502) (xy 95.801193 -261.836088) (xy 95.821141 -261.789268)
			(xy 95.848342 -261.746254) (xy 95.88209 -261.70816) (xy 95.921512 -261.675973) (xy 95.965586 -261.650527)
			(xy 96.013172 -261.63248) (xy 96.063036 -261.6223) (xy 96.113888 -261.620251) (xy 96.164409 -261.626385)
			(xy 96.213293 -261.640545) (xy 96.259272 -261.662362) (xy 96.301156 -261.691272) (xy 96.33786 -261.726527)
			(xy 96.368433 -261.767213) (xy 96.392084 -261.812276) (xy 96.4082 -261.86055) (xy 96.416364 -261.910784)
			(xy 96.416876 -261.93623) (xy 97.675204 -261.93623) (xy 97.679164 -261.887176) (xy 97.690941 -261.839392)
			(xy 97.710232 -261.794116) (xy 97.736535 -261.75252) (xy 97.76917 -261.715683) (xy 97.807291 -261.684558)
			(xy 97.849912 -261.659951) (xy 97.895928 -261.642499) (xy 97.944147 -261.632655) (xy 97.993322 -261.630674)
			(xy 98.042177 -261.636606) (xy 98.089448 -261.650298) (xy 98.13391 -261.671396) (xy 98.174413 -261.699352)
			(xy 98.209906 -261.733444) (xy 98.239471 -261.772788) (xy 98.262342 -261.816365) (xy 98.277926 -261.863046)
			(xy 98.285821 -261.911623) (xy 98.286316 -261.93623) (xy 99.555312 -261.93623) (xy 99.559272 -261.887176)
			(xy 99.571049 -261.839392) (xy 99.59034 -261.794116) (xy 99.616643 -261.75252) (xy 99.649278 -261.715683)
			(xy 99.687399 -261.684558) (xy 99.73002 -261.659951) (xy 99.776036 -261.642499) (xy 99.824255 -261.632655)
			(xy 99.87343 -261.630674) (xy 99.922285 -261.636606) (xy 99.969556 -261.650298) (xy 100.014018 -261.671396)
			(xy 100.054521 -261.699352) (xy 100.090014 -261.733444) (xy 100.119579 -261.772788) (xy 100.14245 -261.816365)
			(xy 100.158034 -261.863046) (xy 100.165929 -261.911623) (xy 100.166424 -261.93623) (xy 101.435166 -261.93623)
			(xy 101.439126 -261.887176) (xy 101.450903 -261.839392) (xy 101.470194 -261.794116) (xy 101.496497 -261.75252)
			(xy 101.529132 -261.715683) (xy 101.567253 -261.684558) (xy 101.609874 -261.659951) (xy 101.65589 -261.642499)
			(xy 101.704109 -261.632655) (xy 101.753284 -261.630674) (xy 101.802139 -261.636606) (xy 101.84941 -261.650298)
			(xy 101.893872 -261.671396) (xy 101.934375 -261.699352) (xy 101.969868 -261.733444) (xy 101.999433 -261.772788)
			(xy 102.022304 -261.816365) (xy 102.037888 -261.863046) (xy 102.045783 -261.911623) (xy 102.046278 -261.93623)
			(xy 102.37522 -261.93623) (xy 102.37918 -261.887176) (xy 102.390957 -261.839392) (xy 102.410248 -261.794116)
			(xy 102.436551 -261.75252) (xy 102.469186 -261.715683) (xy 102.507307 -261.684558) (xy 102.549928 -261.659951)
			(xy 102.595944 -261.642499) (xy 102.644163 -261.632655) (xy 102.693338 -261.630674) (xy 102.742193 -261.636606)
			(xy 102.789464 -261.650298) (xy 102.833926 -261.671396) (xy 102.874429 -261.699352) (xy 102.909922 -261.733444)
			(xy 102.939487 -261.772788) (xy 102.962358 -261.816365) (xy 102.977942 -261.863046) (xy 102.985837 -261.911623)
			(xy 102.986332 -261.93623) (xy 102.985837 -261.960837) (xy 102.977942 -262.009414) (xy 102.962358 -262.056095)
			(xy 102.939487 -262.099672) (xy 102.909922 -262.139016) (xy 102.874429 -262.173108) (xy 102.833926 -262.201064)
			(xy 102.789464 -262.222162) (xy 102.742193 -262.235854) (xy 102.693338 -262.241786) (xy 102.644163 -262.239805)
			(xy 102.595944 -262.229961) (xy 102.549928 -262.212509) (xy 102.507307 -262.187902) (xy 102.469186 -262.156777)
			(xy 102.436551 -262.11994) (xy 102.410248 -262.078344) (xy 102.390957 -262.033068) (xy 102.37918 -261.985284)
			(xy 102.37522 -261.93623) (xy 102.046278 -261.93623) (xy 102.045783 -261.960837) (xy 102.037888 -262.009414)
			(xy 102.022304 -262.056095) (xy 101.999433 -262.099672) (xy 101.969868 -262.139016) (xy 101.934375 -262.173108)
			(xy 101.893872 -262.201064) (xy 101.84941 -262.222162) (xy 101.802139 -262.235854) (xy 101.753284 -262.241786)
			(xy 101.704109 -262.239805) (xy 101.65589 -262.229961) (xy 101.609874 -262.212509) (xy 101.567253 -262.187902)
			(xy 101.529132 -262.156777) (xy 101.496497 -262.11994) (xy 101.470194 -262.078344) (xy 101.450903 -262.033068)
			(xy 101.439126 -261.985284) (xy 101.435166 -261.93623) (xy 100.166424 -261.93623) (xy 100.165929 -261.960837)
			(xy 100.158034 -262.009414) (xy 100.14245 -262.056095) (xy 100.119579 -262.099672) (xy 100.090014 -262.139016)
			(xy 100.054521 -262.173108) (xy 100.014018 -262.201064) (xy 99.969556 -262.222162) (xy 99.922285 -262.235854)
			(xy 99.87343 -262.241786) (xy 99.824255 -262.239805) (xy 99.776036 -262.229961) (xy 99.73002 -262.212509)
			(xy 99.687399 -262.187902) (xy 99.649278 -262.156777) (xy 99.616643 -262.11994) (xy 99.59034 -262.078344)
			(xy 99.571049 -262.033068) (xy 99.559272 -261.985284) (xy 99.555312 -261.93623) (xy 98.286316 -261.93623)
			(xy 98.285821 -261.960837) (xy 98.277926 -262.009414) (xy 98.262342 -262.056095) (xy 98.239471 -262.099672)
			(xy 98.209906 -262.139016) (xy 98.174413 -262.173108) (xy 98.13391 -262.201064) (xy 98.089448 -262.222162)
			(xy 98.042177 -262.235854) (xy 97.993322 -262.241786) (xy 97.944147 -262.239805) (xy 97.895928 -262.229961)
			(xy 97.849912 -262.212509) (xy 97.807291 -262.187902) (xy 97.76917 -262.156777) (xy 97.736535 -262.11994)
			(xy 97.710232 -262.078344) (xy 97.690941 -262.033068) (xy 97.679164 -261.985284) (xy 97.675204 -261.93623)
			(xy 96.416876 -261.93623) (xy 96.416364 -261.961676) (xy 96.4082 -262.01191) (xy 96.392084 -262.060184)
			(xy 96.368433 -262.105247) (xy 96.33786 -262.145933) (xy 96.301156 -262.181188) (xy 96.259272 -262.210098)
			(xy 96.213293 -262.231915) (xy 96.164409 -262.246075) (xy 96.113888 -262.252209) (xy 96.063036 -262.25016)
			(xy 96.013172 -262.23998) (xy 95.965586 -262.221933) (xy 95.921512 -262.196487) (xy 95.88209 -262.1643)
			(xy 95.848342 -262.126206) (xy 95.821141 -262.083192) (xy 95.801193 -262.036372) (xy 95.789014 -261.986958)
			(xy 95.784919 -261.93623) (xy 95.466408 -261.93623) (xy 95.465913 -261.960837) (xy 95.458018 -262.009414)
			(xy 95.442434 -262.056095) (xy 95.419563 -262.099672) (xy 95.389998 -262.139016) (xy 95.354505 -262.173108)
			(xy 95.314002 -262.201064) (xy 95.26954 -262.222162) (xy 95.222269 -262.235854) (xy 95.173414 -262.241786)
			(xy 95.124239 -262.239805) (xy 95.07602 -262.229961) (xy 95.030004 -262.212509) (xy 94.987383 -262.187902)
			(xy 94.949262 -262.156777) (xy 94.916627 -262.11994) (xy 94.890324 -262.078344) (xy 94.871033 -262.033068)
			(xy 94.859256 -261.985284) (xy 94.855296 -261.93623) (xy 94.526354 -261.93623) (xy 94.525859 -261.960837)
			(xy 94.517964 -262.009414) (xy 94.50238 -262.056095) (xy 94.479509 -262.099672) (xy 94.449944 -262.139016)
			(xy 94.414451 -262.173108) (xy 94.373948 -262.201064) (xy 94.329486 -262.222162) (xy 94.282215 -262.235854)
			(xy 94.23336 -262.241786) (xy 94.184185 -262.239805) (xy 94.135966 -262.229961) (xy 94.08995 -262.212509)
			(xy 94.047329 -262.187902) (xy 94.009208 -262.156777) (xy 93.976573 -262.11994) (xy 93.95027 -262.078344)
			(xy 93.930979 -262.033068) (xy 93.919202 -261.985284) (xy 93.915242 -261.93623) (xy 93.5863 -261.93623)
			(xy 93.585805 -261.960837) (xy 93.57791 -262.009414) (xy 93.562326 -262.056095) (xy 93.539455 -262.099672)
			(xy 93.50989 -262.139016) (xy 93.474397 -262.173108) (xy 93.433894 -262.201064) (xy 93.389432 -262.222162)
			(xy 93.342161 -262.235854) (xy 93.293306 -262.241786) (xy 93.244131 -262.239805) (xy 93.195912 -262.229961)
			(xy 93.149896 -262.212509) (xy 93.107275 -262.187902) (xy 93.069154 -262.156777) (xy 93.036519 -262.11994)
			(xy 93.010216 -262.078344) (xy 92.990925 -262.033068) (xy 92.979148 -261.985284) (xy 92.975188 -261.93623)
			(xy 92.65666 -261.93623) (xy 92.656148 -261.961676) (xy 92.647984 -262.01191) (xy 92.631868 -262.060184)
			(xy 92.608217 -262.105247) (xy 92.577644 -262.145933) (xy 92.54094 -262.181188) (xy 92.499056 -262.210098)
			(xy 92.453077 -262.231915) (xy 92.404193 -262.246075) (xy 92.353672 -262.252209) (xy 92.30282 -262.25016)
			(xy 92.252956 -262.23998) (xy 92.20537 -262.221933) (xy 92.161296 -262.196487) (xy 92.121874 -262.1643)
			(xy 92.088126 -262.126206) (xy 92.060925 -262.083192) (xy 92.040977 -262.036372) (xy 92.028798 -261.986958)
			(xy 92.024703 -261.93623) (xy 91.706446 -261.93623) (xy 91.705951 -261.960837) (xy 91.698056 -262.009414)
			(xy 91.682472 -262.056095) (xy 91.659601 -262.099672) (xy 91.630036 -262.139016) (xy 91.594543 -262.173108)
			(xy 91.55404 -262.201064) (xy 91.509578 -262.222162) (xy 91.462307 -262.235854) (xy 91.413452 -262.241786)
			(xy 91.364277 -262.239805) (xy 91.316058 -262.229961) (xy 91.270042 -262.212509) (xy 91.227421 -262.187902)
			(xy 91.1893 -262.156777) (xy 91.156665 -262.11994) (xy 91.130362 -262.078344) (xy 91.111071 -262.033068)
			(xy 91.099294 -261.985284) (xy 91.095334 -261.93623) (xy 90.766392 -261.93623) (xy 90.765897 -261.960837)
			(xy 90.758002 -262.009414) (xy 90.742418 -262.056095) (xy 90.719547 -262.099672) (xy 90.689982 -262.139016)
			(xy 90.654489 -262.173108) (xy 90.613986 -262.201064) (xy 90.569524 -262.222162) (xy 90.522253 -262.235854)
			(xy 90.473398 -262.241786) (xy 90.424223 -262.239805) (xy 90.376004 -262.229961) (xy 90.329988 -262.212509)
			(xy 90.287367 -262.187902) (xy 90.249246 -262.156777) (xy 90.216611 -262.11994) (xy 90.190308 -262.078344)
			(xy 90.171017 -262.033068) (xy 90.15924 -261.985284) (xy 90.15528 -261.93623) (xy 89.826338 -261.93623)
			(xy 89.825843 -261.960837) (xy 89.817948 -262.009414) (xy 89.802364 -262.056095) (xy 89.779493 -262.099672)
			(xy 89.749928 -262.139016) (xy 89.714435 -262.173108) (xy 89.673932 -262.201064) (xy 89.62947 -262.222162)
			(xy 89.582199 -262.235854) (xy 89.533344 -262.241786) (xy 89.484169 -262.239805) (xy 89.43595 -262.229961)
			(xy 89.389934 -262.212509) (xy 89.347313 -262.187902) (xy 89.309192 -262.156777) (xy 89.276557 -262.11994)
			(xy 89.250254 -262.078344) (xy 89.230963 -262.033068) (xy 89.219186 -261.985284) (xy 89.215226 -261.93623)
			(xy 88.886284 -261.93623) (xy 88.885789 -261.960837) (xy 88.877894 -262.009414) (xy 88.86231 -262.056095)
			(xy 88.839439 -262.099672) (xy 88.809874 -262.139016) (xy 88.774381 -262.173108) (xy 88.733878 -262.201064)
			(xy 88.689416 -262.222162) (xy 88.642145 -262.235854) (xy 88.59329 -262.241786) (xy 88.544115 -262.239805)
			(xy 88.495896 -262.229961) (xy 88.44988 -262.212509) (xy 88.407259 -262.187902) (xy 88.369138 -262.156777)
			(xy 88.336503 -262.11994) (xy 88.3102 -262.078344) (xy 88.290909 -262.033068) (xy 88.279132 -261.985284)
			(xy 88.275172 -261.93623) (xy 87.94623 -261.93623) (xy 87.945735 -261.960837) (xy 87.93784 -262.009414)
			(xy 87.922256 -262.056095) (xy 87.899385 -262.099672) (xy 87.86982 -262.139016) (xy 87.834327 -262.173108)
			(xy 87.793824 -262.201064) (xy 87.749362 -262.222162) (xy 87.702091 -262.235854) (xy 87.653236 -262.241786)
			(xy 87.604061 -262.239805) (xy 87.555842 -262.229961) (xy 87.509826 -262.212509) (xy 87.467205 -262.187902)
			(xy 87.429084 -262.156777) (xy 87.396449 -262.11994) (xy 87.370146 -262.078344) (xy 87.350855 -262.033068)
			(xy 87.339078 -261.985284) (xy 87.335118 -261.93623) (xy 87.009986 -261.93623) (xy 87.009986 -262.344916)
			(xy 87.010351 -262.354024) (xy 87.016717 -262.37109) (xy 87.022432 -262.37819) (xy 87.024972 -262.380984)
			(xy 87.065104 -262.415528) (xy 87.080344 -262.428736) (xy 87.081614 -262.429752) (xy 87.088576 -262.434956)
			(xy 87.104934 -262.440801) (xy 87.113618 -262.441182) (xy 87.159592 -262.441182) (xy 87.171022 -262.440928)
			(xy 87.171276 -262.440928) (xy 87.195252 -262.441419) (xy 87.242608 -262.44896) (xy 87.288203 -262.463812)
			(xy 87.330915 -262.485611) (xy 87.369693 -262.51382) (xy 87.403583 -262.547745) (xy 87.431752 -262.586552)
			(xy 87.453508 -262.629286) (xy 87.468313 -262.674896) (xy 87.475805 -262.72226) (xy 87.47633 -262.746236)
			(xy 87.805272 -262.746236) (xy 87.809232 -262.697182) (xy 87.821009 -262.649398) (xy 87.8403 -262.604122)
			(xy 87.866603 -262.562526) (xy 87.899238 -262.525689) (xy 87.937359 -262.494564) (xy 87.97998 -262.469957)
			(xy 88.025996 -262.452505) (xy 88.074215 -262.442661) (xy 88.12339 -262.44068) (xy 88.172245 -262.446612)
			(xy 88.219516 -262.460304) (xy 88.263978 -262.481402) (xy 88.304481 -262.509358) (xy 88.339974 -262.54345)
			(xy 88.369539 -262.582794) (xy 88.39241 -262.626371) (xy 88.407994 -262.673052) (xy 88.415889 -262.721629)
			(xy 88.416384 -262.746236) (xy 88.745326 -262.746236) (xy 88.749286 -262.697182) (xy 88.761063 -262.649398)
			(xy 88.780354 -262.604122) (xy 88.806657 -262.562526) (xy 88.839292 -262.525689) (xy 88.877413 -262.494564)
			(xy 88.920034 -262.469957) (xy 88.96605 -262.452505) (xy 89.014269 -262.442661) (xy 89.063444 -262.44068)
			(xy 89.112299 -262.446612) (xy 89.15957 -262.460304) (xy 89.204032 -262.481402) (xy 89.244535 -262.509358)
			(xy 89.280028 -262.54345) (xy 89.309593 -262.582794) (xy 89.332464 -262.626371) (xy 89.348048 -262.673052)
			(xy 89.355943 -262.721629) (xy 89.356438 -262.746236) (xy 89.685126 -262.746236) (xy 89.689086 -262.697182)
			(xy 89.700863 -262.649398) (xy 89.720154 -262.604122) (xy 89.746457 -262.562526) (xy 89.779092 -262.525689)
			(xy 89.817213 -262.494564) (xy 89.859834 -262.469957) (xy 89.90585 -262.452505) (xy 89.954069 -262.442661)
			(xy 90.003244 -262.44068) (xy 90.052099 -262.446612) (xy 90.09937 -262.460304) (xy 90.143832 -262.481402)
			(xy 90.184335 -262.509358) (xy 90.219828 -262.54345) (xy 90.249393 -262.582794) (xy 90.272264 -262.626371)
			(xy 90.287848 -262.673052) (xy 90.295743 -262.721629) (xy 90.296238 -262.746236) (xy 90.614749 -262.746236)
			(xy 90.618844 -262.695508) (xy 90.631023 -262.646094) (xy 90.650971 -262.599274) (xy 90.678172 -262.55626)
			(xy 90.71192 -262.518166) (xy 90.751342 -262.485979) (xy 90.795416 -262.460533) (xy 90.843002 -262.442486)
			(xy 90.892866 -262.432306) (xy 90.943718 -262.430257) (xy 90.994239 -262.436391) (xy 91.043123 -262.450551)
			(xy 91.089102 -262.472368) (xy 91.130986 -262.501278) (xy 91.16769 -262.536533) (xy 91.198263 -262.577219)
			(xy 91.221914 -262.622282) (xy 91.23803 -262.670556) (xy 91.246194 -262.72079) (xy 91.246706 -262.746236)
			(xy 91.565234 -262.746236) (xy 91.569194 -262.697182) (xy 91.580971 -262.649398) (xy 91.600262 -262.604122)
			(xy 91.626565 -262.562526) (xy 91.6592 -262.525689) (xy 91.697321 -262.494564) (xy 91.739942 -262.469957)
			(xy 91.785958 -262.452505) (xy 91.834177 -262.442661) (xy 91.883352 -262.44068) (xy 91.932207 -262.446612)
			(xy 91.979478 -262.460304) (xy 92.02394 -262.481402) (xy 92.064443 -262.509358) (xy 92.099936 -262.54345)
			(xy 92.129501 -262.582794) (xy 92.152372 -262.626371) (xy 92.167956 -262.673052) (xy 92.175851 -262.721629)
			(xy 92.176346 -262.746236) (xy 92.494857 -262.746236) (xy 92.498952 -262.695508) (xy 92.511131 -262.646094)
			(xy 92.531079 -262.599274) (xy 92.55828 -262.55626) (xy 92.592028 -262.518166) (xy 92.63145 -262.485979)
			(xy 92.675524 -262.460533) (xy 92.72311 -262.442486) (xy 92.772974 -262.432306) (xy 92.823826 -262.430257)
			(xy 92.874347 -262.436391) (xy 92.923231 -262.450551) (xy 92.96921 -262.472368) (xy 93.011094 -262.501278)
			(xy 93.047798 -262.536533) (xy 93.078371 -262.577219) (xy 93.102022 -262.622282) (xy 93.118138 -262.670556)
			(xy 93.126302 -262.72079) (xy 93.126814 -262.746236) (xy 93.445342 -262.746236) (xy 93.449302 -262.697182)
			(xy 93.461079 -262.649398) (xy 93.48037 -262.604122) (xy 93.506673 -262.562526) (xy 93.539308 -262.525689)
			(xy 93.577429 -262.494564) (xy 93.62005 -262.469957) (xy 93.666066 -262.452505) (xy 93.714285 -262.442661)
			(xy 93.76346 -262.44068) (xy 93.812315 -262.446612) (xy 93.859586 -262.460304) (xy 93.904048 -262.481402)
			(xy 93.944551 -262.509358) (xy 93.980044 -262.54345) (xy 94.009609 -262.582794) (xy 94.03248 -262.626371)
			(xy 94.048064 -262.673052) (xy 94.055959 -262.721629) (xy 94.056454 -262.746236) (xy 94.374711 -262.746236)
			(xy 94.378806 -262.695508) (xy 94.390985 -262.646094) (xy 94.410933 -262.599274) (xy 94.438134 -262.55626)
			(xy 94.471882 -262.518166) (xy 94.511304 -262.485979) (xy 94.555378 -262.460533) (xy 94.602964 -262.442486)
			(xy 94.652828 -262.432306) (xy 94.70368 -262.430257) (xy 94.754201 -262.436391) (xy 94.803085 -262.450551)
			(xy 94.849064 -262.472368) (xy 94.890948 -262.501278) (xy 94.927652 -262.536533) (xy 94.958225 -262.577219)
			(xy 94.981876 -262.622282) (xy 94.997992 -262.670556) (xy 95.006156 -262.72079) (xy 95.006668 -262.746236)
			(xy 95.314765 -262.746236) (xy 95.31886 -262.695508) (xy 95.331039 -262.646094) (xy 95.350987 -262.599274)
			(xy 95.378188 -262.55626) (xy 95.411936 -262.518166) (xy 95.451358 -262.485979) (xy 95.495432 -262.460533)
			(xy 95.543018 -262.442486) (xy 95.592882 -262.432306) (xy 95.643734 -262.430257) (xy 95.694255 -262.436391)
			(xy 95.743139 -262.450551) (xy 95.789118 -262.472368) (xy 95.831002 -262.501278) (xy 95.867706 -262.536533)
			(xy 95.898279 -262.577219) (xy 95.92193 -262.622282) (xy 95.938046 -262.670556) (xy 95.94621 -262.72079)
			(xy 95.946722 -262.746236) (xy 96.26525 -262.746236) (xy 96.26921 -262.697182) (xy 96.280987 -262.649398)
			(xy 96.300278 -262.604122) (xy 96.326581 -262.562526) (xy 96.359216 -262.525689) (xy 96.397337 -262.494564)
			(xy 96.439958 -262.469957) (xy 96.485974 -262.452505) (xy 96.534193 -262.442661) (xy 96.583368 -262.44068)
			(xy 96.632223 -262.446612) (xy 96.679494 -262.460304) (xy 96.723956 -262.481402) (xy 96.764459 -262.509358)
			(xy 96.799952 -262.54345) (xy 96.829517 -262.582794) (xy 96.852388 -262.626371) (xy 96.867972 -262.673052)
			(xy 96.875867 -262.721629) (xy 96.876362 -262.746236) (xy 98.145358 -262.746236) (xy 98.149318 -262.697182)
			(xy 98.161095 -262.649398) (xy 98.180386 -262.604122) (xy 98.206689 -262.562526) (xy 98.239324 -262.525689)
			(xy 98.277445 -262.494564) (xy 98.320066 -262.469957) (xy 98.366082 -262.452505) (xy 98.414301 -262.442661)
			(xy 98.463476 -262.44068) (xy 98.512331 -262.446612) (xy 98.559602 -262.460304) (xy 98.604064 -262.481402)
			(xy 98.644567 -262.509358) (xy 98.68006 -262.54345) (xy 98.709625 -262.582794) (xy 98.732496 -262.626371)
			(xy 98.74808 -262.673052) (xy 98.755975 -262.721629) (xy 98.75647 -262.746236) (xy 100.025212 -262.746236)
			(xy 100.029172 -262.697182) (xy 100.040949 -262.649398) (xy 100.06024 -262.604122) (xy 100.086543 -262.562526)
			(xy 100.119178 -262.525689) (xy 100.157299 -262.494564) (xy 100.19992 -262.469957) (xy 100.245936 -262.452505)
			(xy 100.294155 -262.442661) (xy 100.34333 -262.44068) (xy 100.392185 -262.446612) (xy 100.439456 -262.460304)
			(xy 100.483918 -262.481402) (xy 100.524421 -262.509358) (xy 100.559914 -262.54345) (xy 100.589479 -262.582794)
			(xy 100.61235 -262.626371) (xy 100.627934 -262.673052) (xy 100.635829 -262.721629) (xy 100.636324 -262.746236)
			(xy 100.965266 -262.746236) (xy 100.969226 -262.697182) (xy 100.981003 -262.649398) (xy 101.000294 -262.604122)
			(xy 101.026597 -262.562526) (xy 101.059232 -262.525689) (xy 101.097353 -262.494564) (xy 101.139974 -262.469957)
			(xy 101.18599 -262.452505) (xy 101.234209 -262.442661) (xy 101.283384 -262.44068) (xy 101.332239 -262.446612)
			(xy 101.37951 -262.460304) (xy 101.423972 -262.481402) (xy 101.464475 -262.509358) (xy 101.499968 -262.54345)
			(xy 101.529533 -262.582794) (xy 101.552404 -262.626371) (xy 101.567988 -262.673052) (xy 101.575883 -262.721629)
			(xy 101.576378 -262.746236) (xy 101.90532 -262.746236) (xy 101.90928 -262.697182) (xy 101.921057 -262.649398)
			(xy 101.940348 -262.604122) (xy 101.966651 -262.562526) (xy 101.999286 -262.525689) (xy 102.037407 -262.494564)
			(xy 102.080028 -262.469957) (xy 102.126044 -262.452505) (xy 102.174263 -262.442661) (xy 102.223438 -262.44068)
			(xy 102.272293 -262.446612) (xy 102.319564 -262.460304) (xy 102.364026 -262.481402) (xy 102.404529 -262.509358)
			(xy 102.440022 -262.54345) (xy 102.469587 -262.582794) (xy 102.492458 -262.626371) (xy 102.508042 -262.673052)
			(xy 102.515937 -262.721629) (xy 102.516432 -262.746236) (xy 102.516391 -262.748268) (xy 102.842072 -262.748268)
			(xy 102.846032 -262.699214) (xy 102.857809 -262.65143) (xy 102.8771 -262.606154) (xy 102.903403 -262.564558)
			(xy 102.936038 -262.527721) (xy 102.974159 -262.496596) (xy 103.01678 -262.471989) (xy 103.062796 -262.454537)
			(xy 103.111015 -262.444693) (xy 103.16019 -262.442712) (xy 103.209045 -262.448644) (xy 103.256316 -262.462336)
			(xy 103.300778 -262.483434) (xy 103.341281 -262.51139) (xy 103.376774 -262.545482) (xy 103.406339 -262.584826)
			(xy 103.42921 -262.628403) (xy 103.444794 -262.675084) (xy 103.452689 -262.723661) (xy 103.453184 -262.748268)
			(xy 103.782126 -262.748268) (xy 103.786086 -262.699214) (xy 103.797863 -262.65143) (xy 103.817154 -262.606154)
			(xy 103.843457 -262.564558) (xy 103.876092 -262.527721) (xy 103.914213 -262.496596) (xy 103.956834 -262.471989)
			(xy 104.00285 -262.454537) (xy 104.051069 -262.444693) (xy 104.100244 -262.442712) (xy 104.149099 -262.448644)
			(xy 104.19637 -262.462336) (xy 104.240832 -262.483434) (xy 104.281335 -262.51139) (xy 104.316828 -262.545482)
			(xy 104.346393 -262.584826) (xy 104.369264 -262.628403) (xy 104.384848 -262.675084) (xy 104.392743 -262.723661)
			(xy 104.393238 -262.748268) (xy 104.392743 -262.772875) (xy 104.384848 -262.821452) (xy 104.369264 -262.868133)
			(xy 104.346393 -262.91171) (xy 104.316828 -262.951054) (xy 104.281335 -262.985146) (xy 104.240832 -263.013102)
			(xy 104.19637 -263.0342) (xy 104.149099 -263.047892) (xy 104.100244 -263.053824) (xy 104.051069 -263.051843)
			(xy 104.00285 -263.041999) (xy 103.956834 -263.024547) (xy 103.914213 -262.99994) (xy 103.876092 -262.968815)
			(xy 103.843457 -262.931978) (xy 103.817154 -262.890382) (xy 103.797863 -262.845106) (xy 103.786086 -262.797322)
			(xy 103.782126 -262.748268) (xy 103.453184 -262.748268) (xy 103.452689 -262.772875) (xy 103.444794 -262.821452)
			(xy 103.42921 -262.868133) (xy 103.406339 -262.91171) (xy 103.376774 -262.951054) (xy 103.341281 -262.985146)
			(xy 103.300778 -263.013102) (xy 103.256316 -263.0342) (xy 103.209045 -263.047892) (xy 103.16019 -263.053824)
			(xy 103.111015 -263.051843) (xy 103.062796 -263.041999) (xy 103.01678 -263.024547) (xy 102.974159 -262.99994)
			(xy 102.936038 -262.968815) (xy 102.903403 -262.931978) (xy 102.8771 -262.890382) (xy 102.857809 -262.845106)
			(xy 102.846032 -262.797322) (xy 102.842072 -262.748268) (xy 102.516391 -262.748268) (xy 102.515937 -262.770843)
			(xy 102.508042 -262.81942) (xy 102.492458 -262.866101) (xy 102.469587 -262.909678) (xy 102.440022 -262.949022)
			(xy 102.404529 -262.983114) (xy 102.364026 -263.01107) (xy 102.319564 -263.032168) (xy 102.272293 -263.04586)
			(xy 102.223438 -263.051792) (xy 102.174263 -263.049811) (xy 102.126044 -263.039967) (xy 102.080028 -263.022515)
			(xy 102.037407 -262.997908) (xy 101.999286 -262.966783) (xy 101.966651 -262.929946) (xy 101.940348 -262.88835)
			(xy 101.921057 -262.843074) (xy 101.90928 -262.79529) (xy 101.90532 -262.746236) (xy 101.576378 -262.746236)
			(xy 101.575883 -262.770843) (xy 101.567988 -262.81942) (xy 101.552404 -262.866101) (xy 101.529533 -262.909678)
			(xy 101.499968 -262.949022) (xy 101.464475 -262.983114) (xy 101.423972 -263.01107) (xy 101.37951 -263.032168)
			(xy 101.332239 -263.04586) (xy 101.283384 -263.051792) (xy 101.234209 -263.049811) (xy 101.18599 -263.039967)
			(xy 101.139974 -263.022515) (xy 101.097353 -262.997908) (xy 101.059232 -262.966783) (xy 101.026597 -262.929946)
			(xy 101.000294 -262.88835) (xy 100.981003 -262.843074) (xy 100.969226 -262.79529) (xy 100.965266 -262.746236)
			(xy 100.636324 -262.746236) (xy 100.635829 -262.770843) (xy 100.627934 -262.81942) (xy 100.61235 -262.866101)
			(xy 100.589479 -262.909678) (xy 100.559914 -262.949022) (xy 100.524421 -262.983114) (xy 100.483918 -263.01107)
			(xy 100.439456 -263.032168) (xy 100.392185 -263.04586) (xy 100.34333 -263.051792) (xy 100.294155 -263.049811)
			(xy 100.245936 -263.039967) (xy 100.19992 -263.022515) (xy 100.157299 -262.997908) (xy 100.119178 -262.966783)
			(xy 100.086543 -262.929946) (xy 100.06024 -262.88835) (xy 100.040949 -262.843074) (xy 100.029172 -262.79529)
			(xy 100.025212 -262.746236) (xy 98.75647 -262.746236) (xy 98.755975 -262.770843) (xy 98.74808 -262.81942)
			(xy 98.732496 -262.866101) (xy 98.709625 -262.909678) (xy 98.68006 -262.949022) (xy 98.644567 -262.983114)
			(xy 98.604064 -263.01107) (xy 98.559602 -263.032168) (xy 98.512331 -263.04586) (xy 98.463476 -263.051792)
			(xy 98.414301 -263.049811) (xy 98.366082 -263.039967) (xy 98.320066 -263.022515) (xy 98.277445 -262.997908)
			(xy 98.239324 -262.966783) (xy 98.206689 -262.929946) (xy 98.180386 -262.88835) (xy 98.161095 -262.843074)
			(xy 98.149318 -262.79529) (xy 98.145358 -262.746236) (xy 96.876362 -262.746236) (xy 96.875867 -262.770843)
			(xy 96.867972 -262.81942) (xy 96.852388 -262.866101) (xy 96.829517 -262.909678) (xy 96.799952 -262.949022)
			(xy 96.764459 -262.983114) (xy 96.723956 -263.01107) (xy 96.679494 -263.032168) (xy 96.632223 -263.04586)
			(xy 96.583368 -263.051792) (xy 96.534193 -263.049811) (xy 96.485974 -263.039967) (xy 96.439958 -263.022515)
			(xy 96.397337 -262.997908) (xy 96.359216 -262.966783) (xy 96.326581 -262.929946) (xy 96.300278 -262.88835)
			(xy 96.280987 -262.843074) (xy 96.26921 -262.79529) (xy 96.26525 -262.746236) (xy 95.946722 -262.746236)
			(xy 95.94621 -262.771682) (xy 95.938046 -262.821916) (xy 95.92193 -262.87019) (xy 95.898279 -262.915253)
			(xy 95.867706 -262.955939) (xy 95.831002 -262.991194) (xy 95.789118 -263.020104) (xy 95.743139 -263.041921)
			(xy 95.694255 -263.056081) (xy 95.643734 -263.062215) (xy 95.592882 -263.060166) (xy 95.543018 -263.049986)
			(xy 95.495432 -263.031939) (xy 95.451358 -263.006493) (xy 95.411936 -262.974306) (xy 95.378188 -262.936212)
			(xy 95.350987 -262.893198) (xy 95.331039 -262.846378) (xy 95.31886 -262.796964) (xy 95.314765 -262.746236)
			(xy 95.006668 -262.746236) (xy 95.006156 -262.771682) (xy 94.997992 -262.821916) (xy 94.981876 -262.87019)
			(xy 94.958225 -262.915253) (xy 94.927652 -262.955939) (xy 94.890948 -262.991194) (xy 94.849064 -263.020104)
			(xy 94.803085 -263.041921) (xy 94.754201 -263.056081) (xy 94.70368 -263.062215) (xy 94.652828 -263.060166)
			(xy 94.602964 -263.049986) (xy 94.555378 -263.031939) (xy 94.511304 -263.006493) (xy 94.471882 -262.974306)
			(xy 94.438134 -262.936212) (xy 94.410933 -262.893198) (xy 94.390985 -262.846378) (xy 94.378806 -262.796964)
			(xy 94.374711 -262.746236) (xy 94.056454 -262.746236) (xy 94.055959 -262.770843) (xy 94.048064 -262.81942)
			(xy 94.03248 -262.866101) (xy 94.009609 -262.909678) (xy 93.980044 -262.949022) (xy 93.944551 -262.983114)
			(xy 93.904048 -263.01107) (xy 93.859586 -263.032168) (xy 93.812315 -263.04586) (xy 93.76346 -263.051792)
			(xy 93.714285 -263.049811) (xy 93.666066 -263.039967) (xy 93.62005 -263.022515) (xy 93.577429 -262.997908)
			(xy 93.539308 -262.966783) (xy 93.506673 -262.929946) (xy 93.48037 -262.88835) (xy 93.461079 -262.843074)
			(xy 93.449302 -262.79529) (xy 93.445342 -262.746236) (xy 93.126814 -262.746236) (xy 93.126302 -262.771682)
			(xy 93.118138 -262.821916) (xy 93.102022 -262.87019) (xy 93.078371 -262.915253) (xy 93.047798 -262.955939)
			(xy 93.011094 -262.991194) (xy 92.96921 -263.020104) (xy 92.923231 -263.041921) (xy 92.874347 -263.056081)
			(xy 92.823826 -263.062215) (xy 92.772974 -263.060166) (xy 92.72311 -263.049986) (xy 92.675524 -263.031939)
			(xy 92.63145 -263.006493) (xy 92.592028 -262.974306) (xy 92.55828 -262.936212) (xy 92.531079 -262.893198)
			(xy 92.511131 -262.846378) (xy 92.498952 -262.796964) (xy 92.494857 -262.746236) (xy 92.176346 -262.746236)
			(xy 92.175851 -262.770843) (xy 92.167956 -262.81942) (xy 92.152372 -262.866101) (xy 92.129501 -262.909678)
			(xy 92.099936 -262.949022) (xy 92.064443 -262.983114) (xy 92.02394 -263.01107) (xy 91.979478 -263.032168)
			(xy 91.932207 -263.04586) (xy 91.883352 -263.051792) (xy 91.834177 -263.049811) (xy 91.785958 -263.039967)
			(xy 91.739942 -263.022515) (xy 91.697321 -262.997908) (xy 91.6592 -262.966783) (xy 91.626565 -262.929946)
			(xy 91.600262 -262.88835) (xy 91.580971 -262.843074) (xy 91.569194 -262.79529) (xy 91.565234 -262.746236)
			(xy 91.246706 -262.746236) (xy 91.246194 -262.771682) (xy 91.23803 -262.821916) (xy 91.221914 -262.87019)
			(xy 91.198263 -262.915253) (xy 91.16769 -262.955939) (xy 91.130986 -262.991194) (xy 91.089102 -263.020104)
			(xy 91.043123 -263.041921) (xy 90.994239 -263.056081) (xy 90.943718 -263.062215) (xy 90.892866 -263.060166)
			(xy 90.843002 -263.049986) (xy 90.795416 -263.031939) (xy 90.751342 -263.006493) (xy 90.71192 -262.974306)
			(xy 90.678172 -262.936212) (xy 90.650971 -262.893198) (xy 90.631023 -262.846378) (xy 90.618844 -262.796964)
			(xy 90.614749 -262.746236) (xy 90.296238 -262.746236) (xy 90.295743 -262.770843) (xy 90.287848 -262.81942)
			(xy 90.272264 -262.866101) (xy 90.249393 -262.909678) (xy 90.219828 -262.949022) (xy 90.184335 -262.983114)
			(xy 90.143832 -263.01107) (xy 90.09937 -263.032168) (xy 90.052099 -263.04586) (xy 90.003244 -263.051792)
			(xy 89.954069 -263.049811) (xy 89.90585 -263.039967) (xy 89.859834 -263.022515) (xy 89.817213 -262.997908)
			(xy 89.779092 -262.966783) (xy 89.746457 -262.929946) (xy 89.720154 -262.88835) (xy 89.700863 -262.843074)
			(xy 89.689086 -262.79529) (xy 89.685126 -262.746236) (xy 89.356438 -262.746236) (xy 89.355943 -262.770843)
			(xy 89.348048 -262.81942) (xy 89.332464 -262.866101) (xy 89.309593 -262.909678) (xy 89.280028 -262.949022)
			(xy 89.244535 -262.983114) (xy 89.204032 -263.01107) (xy 89.15957 -263.032168) (xy 89.112299 -263.04586)
			(xy 89.063444 -263.051792) (xy 89.014269 -263.049811) (xy 88.96605 -263.039967) (xy 88.920034 -263.022515)
			(xy 88.877413 -262.997908) (xy 88.839292 -262.966783) (xy 88.806657 -262.929946) (xy 88.780354 -262.88835)
			(xy 88.761063 -262.843074) (xy 88.749286 -262.79529) (xy 88.745326 -262.746236) (xy 88.416384 -262.746236)
			(xy 88.415889 -262.770843) (xy 88.407994 -262.81942) (xy 88.39241 -262.866101) (xy 88.369539 -262.909678)
			(xy 88.339974 -262.949022) (xy 88.304481 -262.983114) (xy 88.263978 -263.01107) (xy 88.219516 -263.032168)
			(xy 88.172245 -263.04586) (xy 88.12339 -263.051792) (xy 88.074215 -263.049811) (xy 88.025996 -263.039967)
			(xy 87.97998 -263.022515) (xy 87.937359 -262.997908) (xy 87.899238 -262.966783) (xy 87.866603 -262.929946)
			(xy 87.8403 -262.88835) (xy 87.821009 -262.843074) (xy 87.809232 -262.79529) (xy 87.805272 -262.746236)
			(xy 87.47633 -262.746236) (xy 87.475857 -262.770226) (xy 87.468346 -262.817615) (xy 87.453516 -262.863245)
			(xy 87.431731 -262.905995) (xy 87.403527 -262.94481) (xy 87.369599 -262.978736) (xy 87.330783 -263.006938)
			(xy 87.288032 -263.028721) (xy 87.242401 -263.04355) (xy 87.195012 -263.051058) (xy 87.171022 -263.051544)
			(xy 87.159613 -263.051469) (xy 87.136856 -263.049814) (xy 87.125556 -263.048242) (xy 87.114634 -263.046464)
			(xy 87.09279 -263.052814) (xy 87.065358 -263.07669) (xy 87.06485 -263.077198) (xy 87.030814 -263.106408)
			(xy 87.02929 -263.107678) (xy 87.024972 -263.111996) (xy 87.017606 -263.119108) (xy 87.009986 -263.137904)
			(xy 87.009986 -263.437624) (xy 87.01278 -263.446006) (xy 87.02161 -263.472709) (xy 87.031188 -263.528125)
			(xy 87.03183 -263.556242) (xy 87.335118 -263.556242) (xy 87.339078 -263.507188) (xy 87.350855 -263.459404)
			(xy 87.370146 -263.414128) (xy 87.396449 -263.372532) (xy 87.429084 -263.335695) (xy 87.467205 -263.30457)
			(xy 87.509826 -263.279963) (xy 87.555842 -263.262511) (xy 87.604061 -263.252667) (xy 87.653236 -263.250686)
			(xy 87.702091 -263.256618) (xy 87.749362 -263.27031) (xy 87.793824 -263.291408) (xy 87.834327 -263.319364)
			(xy 87.86982 -263.353456) (xy 87.899385 -263.3928) (xy 87.922256 -263.436377) (xy 87.93784 -263.483058)
			(xy 87.945735 -263.531635) (xy 87.94623 -263.556242) (xy 88.275172 -263.556242) (xy 88.279132 -263.507188)
			(xy 88.290909 -263.459404) (xy 88.3102 -263.414128) (xy 88.336503 -263.372532) (xy 88.369138 -263.335695)
			(xy 88.407259 -263.30457) (xy 88.44988 -263.279963) (xy 88.495896 -263.262511) (xy 88.544115 -263.252667)
			(xy 88.59329 -263.250686) (xy 88.642145 -263.256618) (xy 88.689416 -263.27031) (xy 88.733878 -263.291408)
			(xy 88.774381 -263.319364) (xy 88.809874 -263.353456) (xy 88.839439 -263.3928) (xy 88.86231 -263.436377)
			(xy 88.877894 -263.483058) (xy 88.885789 -263.531635) (xy 88.886284 -263.556242) (xy 89.215226 -263.556242)
			(xy 89.219186 -263.507188) (xy 89.230963 -263.459404) (xy 89.250254 -263.414128) (xy 89.276557 -263.372532)
			(xy 89.309192 -263.335695) (xy 89.347313 -263.30457) (xy 89.389934 -263.279963) (xy 89.43595 -263.262511)
			(xy 89.484169 -263.252667) (xy 89.533344 -263.250686) (xy 89.582199 -263.256618) (xy 89.62947 -263.27031)
			(xy 89.673932 -263.291408) (xy 89.714435 -263.319364) (xy 89.749928 -263.353456) (xy 89.779493 -263.3928)
			(xy 89.802364 -263.436377) (xy 89.817948 -263.483058) (xy 89.825843 -263.531635) (xy 89.826338 -263.556242)
			(xy 90.15528 -263.556242) (xy 90.15924 -263.507188) (xy 90.171017 -263.459404) (xy 90.190308 -263.414128)
			(xy 90.216611 -263.372532) (xy 90.249246 -263.335695) (xy 90.287367 -263.30457) (xy 90.329988 -263.279963)
			(xy 90.376004 -263.262511) (xy 90.424223 -263.252667) (xy 90.473398 -263.250686) (xy 90.522253 -263.256618)
			(xy 90.569524 -263.27031) (xy 90.613986 -263.291408) (xy 90.654489 -263.319364) (xy 90.689982 -263.353456)
			(xy 90.719547 -263.3928) (xy 90.742418 -263.436377) (xy 90.758002 -263.483058) (xy 90.765897 -263.531635)
			(xy 90.766392 -263.556242) (xy 91.084903 -263.556242) (xy 91.088998 -263.505514) (xy 91.101177 -263.4561)
			(xy 91.121125 -263.40928) (xy 91.148326 -263.366266) (xy 91.182074 -263.328172) (xy 91.221496 -263.295985)
			(xy 91.26557 -263.270539) (xy 91.313156 -263.252492) (xy 91.36302 -263.242312) (xy 91.413872 -263.240263)
			(xy 91.464393 -263.246397) (xy 91.513277 -263.260557) (xy 91.559256 -263.282374) (xy 91.60114 -263.311284)
			(xy 91.637844 -263.346539) (xy 91.668417 -263.387225) (xy 91.692068 -263.432288) (xy 91.708184 -263.480562)
			(xy 91.716348 -263.530796) (xy 91.71686 -263.556242) (xy 92.024703 -263.556242) (xy 92.028798 -263.505514)
			(xy 92.040977 -263.4561) (xy 92.060925 -263.40928) (xy 92.088126 -263.366266) (xy 92.121874 -263.328172)
			(xy 92.161296 -263.295985) (xy 92.20537 -263.270539) (xy 92.252956 -263.252492) (xy 92.30282 -263.242312)
			(xy 92.353672 -263.240263) (xy 92.404193 -263.246397) (xy 92.453077 -263.260557) (xy 92.499056 -263.282374)
			(xy 92.54094 -263.311284) (xy 92.577644 -263.346539) (xy 92.608217 -263.387225) (xy 92.631868 -263.432288)
			(xy 92.647984 -263.480562) (xy 92.656148 -263.530796) (xy 92.65666 -263.556242) (xy 93.904811 -263.556242)
			(xy 93.908906 -263.505514) (xy 93.921085 -263.4561) (xy 93.941033 -263.40928) (xy 93.968234 -263.366266)
			(xy 94.001982 -263.328172) (xy 94.041404 -263.295985) (xy 94.085478 -263.270539) (xy 94.133064 -263.252492)
			(xy 94.182928 -263.242312) (xy 94.23378 -263.240263) (xy 94.284301 -263.246397) (xy 94.333185 -263.260557)
			(xy 94.379164 -263.282374) (xy 94.421048 -263.311284) (xy 94.457752 -263.346539) (xy 94.488325 -263.387225)
			(xy 94.511976 -263.432288) (xy 94.528092 -263.480562) (xy 94.536256 -263.530796) (xy 94.536768 -263.556242)
			(xy 94.855296 -263.556242) (xy 94.859256 -263.507188) (xy 94.871033 -263.459404) (xy 94.890324 -263.414128)
			(xy 94.916627 -263.372532) (xy 94.949262 -263.335695) (xy 94.987383 -263.30457) (xy 95.030004 -263.279963)
			(xy 95.07602 -263.262511) (xy 95.124239 -263.252667) (xy 95.173414 -263.250686) (xy 95.222269 -263.256618)
			(xy 95.26954 -263.27031) (xy 95.314002 -263.291408) (xy 95.354505 -263.319364) (xy 95.389998 -263.353456)
			(xy 95.419563 -263.3928) (xy 95.442434 -263.436377) (xy 95.458018 -263.483058) (xy 95.465913 -263.531635)
			(xy 95.466408 -263.556242) (xy 95.784919 -263.556242) (xy 95.789014 -263.505514) (xy 95.801193 -263.4561)
			(xy 95.821141 -263.40928) (xy 95.848342 -263.366266) (xy 95.88209 -263.328172) (xy 95.921512 -263.295985)
			(xy 95.965586 -263.270539) (xy 96.013172 -263.252492) (xy 96.063036 -263.242312) (xy 96.113888 -263.240263)
			(xy 96.164409 -263.246397) (xy 96.213293 -263.260557) (xy 96.259272 -263.282374) (xy 96.301156 -263.311284)
			(xy 96.33786 -263.346539) (xy 96.368433 -263.387225) (xy 96.392084 -263.432288) (xy 96.4082 -263.480562)
			(xy 96.416364 -263.530796) (xy 96.416876 -263.556242) (xy 97.675204 -263.556242) (xy 97.679164 -263.507188)
			(xy 97.690941 -263.459404) (xy 97.710232 -263.414128) (xy 97.736535 -263.372532) (xy 97.76917 -263.335695)
			(xy 97.807291 -263.30457) (xy 97.849912 -263.279963) (xy 97.895928 -263.262511) (xy 97.944147 -263.252667)
			(xy 97.993322 -263.250686) (xy 98.042177 -263.256618) (xy 98.089448 -263.27031) (xy 98.13391 -263.291408)
			(xy 98.174413 -263.319364) (xy 98.209906 -263.353456) (xy 98.239471 -263.3928) (xy 98.262342 -263.436377)
			(xy 98.277926 -263.483058) (xy 98.285821 -263.531635) (xy 98.286316 -263.556242) (xy 99.555312 -263.556242)
			(xy 99.559272 -263.507188) (xy 99.571049 -263.459404) (xy 99.59034 -263.414128) (xy 99.616643 -263.372532)
			(xy 99.649278 -263.335695) (xy 99.687399 -263.30457) (xy 99.73002 -263.279963) (xy 99.776036 -263.262511)
			(xy 99.824255 -263.252667) (xy 99.87343 -263.250686) (xy 99.922285 -263.256618) (xy 99.969556 -263.27031)
			(xy 100.014018 -263.291408) (xy 100.054521 -263.319364) (xy 100.090014 -263.353456) (xy 100.119579 -263.3928)
			(xy 100.14245 -263.436377) (xy 100.158034 -263.483058) (xy 100.165929 -263.531635) (xy 100.166424 -263.556242)
			(xy 100.165929 -263.580849) (xy 100.158034 -263.629426) (xy 100.14245 -263.676107) (xy 100.119579 -263.719684)
			(xy 100.090014 -263.759028) (xy 100.054521 -263.79312) (xy 100.014018 -263.821076) (xy 99.969556 -263.842174)
			(xy 99.922285 -263.855866) (xy 99.87343 -263.861798) (xy 99.824255 -263.859817) (xy 99.776036 -263.849973)
			(xy 99.73002 -263.832521) (xy 99.687399 -263.807914) (xy 99.649278 -263.776789) (xy 99.616643 -263.739952)
			(xy 99.59034 -263.698356) (xy 99.571049 -263.65308) (xy 99.559272 -263.605296) (xy 99.555312 -263.556242)
			(xy 98.286316 -263.556242) (xy 98.285821 -263.580849) (xy 98.277926 -263.629426) (xy 98.262342 -263.676107)
			(xy 98.239471 -263.719684) (xy 98.209906 -263.759028) (xy 98.174413 -263.79312) (xy 98.13391 -263.821076)
			(xy 98.089448 -263.842174) (xy 98.042177 -263.855866) (xy 97.993322 -263.861798) (xy 97.944147 -263.859817)
			(xy 97.895928 -263.849973) (xy 97.849912 -263.832521) (xy 97.807291 -263.807914) (xy 97.76917 -263.776789)
			(xy 97.736535 -263.739952) (xy 97.710232 -263.698356) (xy 97.690941 -263.65308) (xy 97.679164 -263.605296)
			(xy 97.675204 -263.556242) (xy 96.416876 -263.556242) (xy 96.416364 -263.581688) (xy 96.4082 -263.631922)
			(xy 96.392084 -263.680196) (xy 96.368433 -263.725259) (xy 96.33786 -263.765945) (xy 96.301156 -263.8012)
			(xy 96.259272 -263.83011) (xy 96.213293 -263.851927) (xy 96.164409 -263.866087) (xy 96.113888 -263.872221)
			(xy 96.063036 -263.870172) (xy 96.013172 -263.859992) (xy 95.965586 -263.841945) (xy 95.921512 -263.816499)
			(xy 95.88209 -263.784312) (xy 95.848342 -263.746218) (xy 95.821141 -263.703204) (xy 95.801193 -263.656384)
			(xy 95.789014 -263.60697) (xy 95.784919 -263.556242) (xy 95.466408 -263.556242) (xy 95.465913 -263.580849)
			(xy 95.458018 -263.629426) (xy 95.442434 -263.676107) (xy 95.419563 -263.719684) (xy 95.389998 -263.759028)
			(xy 95.354505 -263.79312) (xy 95.314002 -263.821076) (xy 95.26954 -263.842174) (xy 95.222269 -263.855866)
			(xy 95.173414 -263.861798) (xy 95.124239 -263.859817) (xy 95.07602 -263.849973) (xy 95.030004 -263.832521)
			(xy 94.987383 -263.807914) (xy 94.949262 -263.776789) (xy 94.916627 -263.739952) (xy 94.890324 -263.698356)
			(xy 94.871033 -263.65308) (xy 94.859256 -263.605296) (xy 94.855296 -263.556242) (xy 94.536768 -263.556242)
			(xy 94.536256 -263.581688) (xy 94.528092 -263.631922) (xy 94.511976 -263.680196) (xy 94.488325 -263.725259)
			(xy 94.457752 -263.765945) (xy 94.421048 -263.8012) (xy 94.379164 -263.83011) (xy 94.333185 -263.851927)
			(xy 94.284301 -263.866087) (xy 94.23378 -263.872221) (xy 94.182928 -263.870172) (xy 94.133064 -263.859992)
			(xy 94.085478 -263.841945) (xy 94.041404 -263.816499) (xy 94.001982 -263.784312) (xy 93.968234 -263.746218)
			(xy 93.941033 -263.703204) (xy 93.921085 -263.656384) (xy 93.908906 -263.60697) (xy 93.904811 -263.556242)
			(xy 92.65666 -263.556242) (xy 92.656148 -263.581688) (xy 92.647984 -263.631922) (xy 92.631868 -263.680196)
			(xy 92.608217 -263.725259) (xy 92.577644 -263.765945) (xy 92.54094 -263.8012) (xy 92.499056 -263.83011)
			(xy 92.453077 -263.851927) (xy 92.404193 -263.866087) (xy 92.353672 -263.872221) (xy 92.30282 -263.870172)
			(xy 92.252956 -263.859992) (xy 92.20537 -263.841945) (xy 92.161296 -263.816499) (xy 92.121874 -263.784312)
			(xy 92.088126 -263.746218) (xy 92.060925 -263.703204) (xy 92.040977 -263.656384) (xy 92.028798 -263.60697)
			(xy 92.024703 -263.556242) (xy 91.71686 -263.556242) (xy 91.716348 -263.581688) (xy 91.708184 -263.631922)
			(xy 91.692068 -263.680196) (xy 91.668417 -263.725259) (xy 91.637844 -263.765945) (xy 91.60114 -263.8012)
			(xy 91.559256 -263.83011) (xy 91.513277 -263.851927) (xy 91.464393 -263.866087) (xy 91.413872 -263.872221)
			(xy 91.36302 -263.870172) (xy 91.313156 -263.859992) (xy 91.26557 -263.841945) (xy 91.221496 -263.816499)
			(xy 91.182074 -263.784312) (xy 91.148326 -263.746218) (xy 91.121125 -263.703204) (xy 91.101177 -263.656384)
			(xy 91.088998 -263.60697) (xy 91.084903 -263.556242) (xy 90.766392 -263.556242) (xy 90.765897 -263.580849)
			(xy 90.758002 -263.629426) (xy 90.742418 -263.676107) (xy 90.719547 -263.719684) (xy 90.689982 -263.759028)
			(xy 90.654489 -263.79312) (xy 90.613986 -263.821076) (xy 90.569524 -263.842174) (xy 90.522253 -263.855866)
			(xy 90.473398 -263.861798) (xy 90.424223 -263.859817) (xy 90.376004 -263.849973) (xy 90.329988 -263.832521)
			(xy 90.287367 -263.807914) (xy 90.249246 -263.776789) (xy 90.216611 -263.739952) (xy 90.190308 -263.698356)
			(xy 90.171017 -263.65308) (xy 90.15924 -263.605296) (xy 90.15528 -263.556242) (xy 89.826338 -263.556242)
			(xy 89.825843 -263.580849) (xy 89.817948 -263.629426) (xy 89.802364 -263.676107) (xy 89.779493 -263.719684)
			(xy 89.749928 -263.759028) (xy 89.714435 -263.79312) (xy 89.673932 -263.821076) (xy 89.62947 -263.842174)
			(xy 89.582199 -263.855866) (xy 89.533344 -263.861798) (xy 89.484169 -263.859817) (xy 89.43595 -263.849973)
			(xy 89.389934 -263.832521) (xy 89.347313 -263.807914) (xy 89.309192 -263.776789) (xy 89.276557 -263.739952)
			(xy 89.250254 -263.698356) (xy 89.230963 -263.65308) (xy 89.219186 -263.605296) (xy 89.215226 -263.556242)
			(xy 88.886284 -263.556242) (xy 88.885789 -263.580849) (xy 88.877894 -263.629426) (xy 88.86231 -263.676107)
			(xy 88.839439 -263.719684) (xy 88.809874 -263.759028) (xy 88.774381 -263.79312) (xy 88.733878 -263.821076)
			(xy 88.689416 -263.842174) (xy 88.642145 -263.855866) (xy 88.59329 -263.861798) (xy 88.544115 -263.859817)
			(xy 88.495896 -263.849973) (xy 88.44988 -263.832521) (xy 88.407259 -263.807914) (xy 88.369138 -263.776789)
			(xy 88.336503 -263.739952) (xy 88.3102 -263.698356) (xy 88.290909 -263.65308) (xy 88.279132 -263.605296)
			(xy 88.275172 -263.556242) (xy 87.94623 -263.556242) (xy 87.945735 -263.580849) (xy 87.93784 -263.629426)
			(xy 87.922256 -263.676107) (xy 87.899385 -263.719684) (xy 87.86982 -263.759028) (xy 87.834327 -263.79312)
			(xy 87.793824 -263.821076) (xy 87.749362 -263.842174) (xy 87.702091 -263.855866) (xy 87.653236 -263.861798)
			(xy 87.604061 -263.859817) (xy 87.555842 -263.849973) (xy 87.509826 -263.832521) (xy 87.467205 -263.807914)
			(xy 87.429084 -263.776789) (xy 87.396449 -263.739952) (xy 87.370146 -263.698356) (xy 87.350855 -263.65308)
			(xy 87.339078 -263.605296) (xy 87.335118 -263.556242) (xy 87.03183 -263.556242) (xy 87.031245 -263.584365)
			(xy 87.021662 -263.639788) (xy 87.01278 -263.666478) (xy 87.009986 -263.67486) (xy 87.009986 -263.964928)
			(xy 87.010353 -263.974035) (xy 87.016723 -263.991099) (xy 87.022432 -263.998202) (xy 87.024972 -264.000996)
			(xy 87.065104 -264.03554) (xy 87.080344 -264.048748) (xy 87.081614 -264.049764) (xy 87.088577 -264.054967)
			(xy 87.104935 -264.060811) (xy 87.113618 -264.061194) (xy 87.159592 -264.061194) (xy 87.171022 -264.06094)
			(xy 87.171276 -264.06094) (xy 87.195252 -264.061431) (xy 87.242607 -264.068972) (xy 87.288201 -264.083824)
			(xy 87.330912 -264.105623) (xy 87.369689 -264.133832) (xy 87.403578 -264.167758) (xy 87.431746 -264.206565)
			(xy 87.4535 -264.249299) (xy 87.468304 -264.294908) (xy 87.475794 -264.342272) (xy 87.47633 -264.366248)
			(xy 87.805272 -264.366248) (xy 87.809232 -264.317194) (xy 87.821009 -264.26941) (xy 87.8403 -264.224134)
			(xy 87.866603 -264.182538) (xy 87.899238 -264.145701) (xy 87.937359 -264.114576) (xy 87.97998 -264.089969)
			(xy 88.025996 -264.072517) (xy 88.074215 -264.062673) (xy 88.12339 -264.060692) (xy 88.172245 -264.066624)
			(xy 88.219516 -264.080316) (xy 88.263978 -264.101414) (xy 88.304481 -264.12937) (xy 88.339974 -264.163462)
			(xy 88.369539 -264.202806) (xy 88.39241 -264.246383) (xy 88.407994 -264.293064) (xy 88.415889 -264.341641)
			(xy 88.416384 -264.366248) (xy 88.745326 -264.366248) (xy 88.749286 -264.317194) (xy 88.761063 -264.26941)
			(xy 88.780354 -264.224134) (xy 88.806657 -264.182538) (xy 88.839292 -264.145701) (xy 88.877413 -264.114576)
			(xy 88.920034 -264.089969) (xy 88.96605 -264.072517) (xy 89.014269 -264.062673) (xy 89.063444 -264.060692)
			(xy 89.112299 -264.066624) (xy 89.15957 -264.080316) (xy 89.204032 -264.101414) (xy 89.244535 -264.12937)
			(xy 89.280028 -264.163462) (xy 89.309593 -264.202806) (xy 89.332464 -264.246383) (xy 89.348048 -264.293064)
			(xy 89.355943 -264.341641) (xy 89.356438 -264.366248) (xy 89.685126 -264.366248) (xy 89.689086 -264.317194)
			(xy 89.700863 -264.26941) (xy 89.720154 -264.224134) (xy 89.746457 -264.182538) (xy 89.779092 -264.145701)
			(xy 89.817213 -264.114576) (xy 89.859834 -264.089969) (xy 89.90585 -264.072517) (xy 89.954069 -264.062673)
			(xy 90.003244 -264.060692) (xy 90.052099 -264.066624) (xy 90.09937 -264.080316) (xy 90.143832 -264.101414)
			(xy 90.184335 -264.12937) (xy 90.219828 -264.163462) (xy 90.249393 -264.202806) (xy 90.272264 -264.246383)
			(xy 90.287848 -264.293064) (xy 90.295743 -264.341641) (xy 90.296238 -264.366248) (xy 90.614749 -264.366248)
			(xy 90.618844 -264.31552) (xy 90.631023 -264.266106) (xy 90.650971 -264.219286) (xy 90.678172 -264.176272)
			(xy 90.71192 -264.138178) (xy 90.751342 -264.105991) (xy 90.795416 -264.080545) (xy 90.843002 -264.062498)
			(xy 90.892866 -264.052318) (xy 90.943718 -264.050269) (xy 90.994239 -264.056403) (xy 91.043123 -264.070563)
			(xy 91.089102 -264.09238) (xy 91.130986 -264.12129) (xy 91.16769 -264.156545) (xy 91.198263 -264.197231)
			(xy 91.221914 -264.242294) (xy 91.23803 -264.290568) (xy 91.246194 -264.340802) (xy 91.246706 -264.366248)
			(xy 91.565234 -264.366248) (xy 91.569194 -264.317194) (xy 91.580971 -264.26941) (xy 91.600262 -264.224134)
			(xy 91.626565 -264.182538) (xy 91.6592 -264.145701) (xy 91.697321 -264.114576) (xy 91.739942 -264.089969)
			(xy 91.785958 -264.072517) (xy 91.834177 -264.062673) (xy 91.883352 -264.060692) (xy 91.932207 -264.066624)
			(xy 91.979478 -264.080316) (xy 92.02394 -264.101414) (xy 92.064443 -264.12937) (xy 92.099936 -264.163462)
			(xy 92.129501 -264.202806) (xy 92.152372 -264.246383) (xy 92.167956 -264.293064) (xy 92.175851 -264.341641)
			(xy 92.176346 -264.366248) (xy 92.494857 -264.366248) (xy 92.498952 -264.31552) (xy 92.511131 -264.266106)
			(xy 92.531079 -264.219286) (xy 92.55828 -264.176272) (xy 92.592028 -264.138178) (xy 92.63145 -264.105991)
			(xy 92.675524 -264.080545) (xy 92.72311 -264.062498) (xy 92.772974 -264.052318) (xy 92.823826 -264.050269)
			(xy 92.874347 -264.056403) (xy 92.923231 -264.070563) (xy 92.96921 -264.09238) (xy 93.011094 -264.12129)
			(xy 93.047798 -264.156545) (xy 93.078371 -264.197231) (xy 93.102022 -264.242294) (xy 93.118138 -264.290568)
			(xy 93.126302 -264.340802) (xy 93.126814 -264.366248) (xy 93.445342 -264.366248) (xy 93.449302 -264.317194)
			(xy 93.461079 -264.26941) (xy 93.48037 -264.224134) (xy 93.506673 -264.182538) (xy 93.539308 -264.145701)
			(xy 93.577429 -264.114576) (xy 93.62005 -264.089969) (xy 93.666066 -264.072517) (xy 93.714285 -264.062673)
			(xy 93.76346 -264.060692) (xy 93.812315 -264.066624) (xy 93.859586 -264.080316) (xy 93.904048 -264.101414)
			(xy 93.944551 -264.12937) (xy 93.980044 -264.163462) (xy 94.009609 -264.202806) (xy 94.03248 -264.246383)
			(xy 94.048064 -264.293064) (xy 94.055959 -264.341641) (xy 94.056454 -264.366248) (xy 94.374711 -264.366248)
			(xy 94.378806 -264.31552) (xy 94.390985 -264.266106) (xy 94.410933 -264.219286) (xy 94.438134 -264.176272)
			(xy 94.471882 -264.138178) (xy 94.511304 -264.105991) (xy 94.555378 -264.080545) (xy 94.602964 -264.062498)
			(xy 94.652828 -264.052318) (xy 94.70368 -264.050269) (xy 94.754201 -264.056403) (xy 94.803085 -264.070563)
			(xy 94.849064 -264.09238) (xy 94.890948 -264.12129) (xy 94.927652 -264.156545) (xy 94.958225 -264.197231)
			(xy 94.981876 -264.242294) (xy 94.997992 -264.290568) (xy 95.006156 -264.340802) (xy 95.006668 -264.366248)
			(xy 95.314765 -264.366248) (xy 95.31886 -264.31552) (xy 95.331039 -264.266106) (xy 95.350987 -264.219286)
			(xy 95.378188 -264.176272) (xy 95.411936 -264.138178) (xy 95.451358 -264.105991) (xy 95.495432 -264.080545)
			(xy 95.543018 -264.062498) (xy 95.592882 -264.052318) (xy 95.643734 -264.050269) (xy 95.694255 -264.056403)
			(xy 95.743139 -264.070563) (xy 95.789118 -264.09238) (xy 95.831002 -264.12129) (xy 95.867706 -264.156545)
			(xy 95.898279 -264.197231) (xy 95.92193 -264.242294) (xy 95.938046 -264.290568) (xy 95.94621 -264.340802)
			(xy 95.946722 -264.366248) (xy 96.26525 -264.366248) (xy 96.26921 -264.317194) (xy 96.280987 -264.26941)
			(xy 96.300278 -264.224134) (xy 96.326581 -264.182538) (xy 96.359216 -264.145701) (xy 96.397337 -264.114576)
			(xy 96.439958 -264.089969) (xy 96.485974 -264.072517) (xy 96.534193 -264.062673) (xy 96.583368 -264.060692)
			(xy 96.632223 -264.066624) (xy 96.679494 -264.080316) (xy 96.723956 -264.101414) (xy 96.764459 -264.12937)
			(xy 96.799952 -264.163462) (xy 96.829517 -264.202806) (xy 96.852388 -264.246383) (xy 96.867972 -264.293064)
			(xy 96.875867 -264.341641) (xy 96.876362 -264.366248) (xy 98.145358 -264.366248) (xy 98.149318 -264.317194)
			(xy 98.161095 -264.26941) (xy 98.180386 -264.224134) (xy 98.206689 -264.182538) (xy 98.239324 -264.145701)
			(xy 98.277445 -264.114576) (xy 98.320066 -264.089969) (xy 98.366082 -264.072517) (xy 98.414301 -264.062673)
			(xy 98.463476 -264.060692) (xy 98.512331 -264.066624) (xy 98.559602 -264.080316) (xy 98.604064 -264.101414)
			(xy 98.644567 -264.12937) (xy 98.68006 -264.163462) (xy 98.709625 -264.202806) (xy 98.732496 -264.246383)
			(xy 98.74808 -264.293064) (xy 98.755975 -264.341641) (xy 98.75647 -264.366248) (xy 98.755975 -264.390855)
			(xy 98.74808 -264.439432) (xy 98.732496 -264.486113) (xy 98.709625 -264.52969) (xy 98.68006 -264.569034)
			(xy 98.644567 -264.603126) (xy 98.604064 -264.631082) (xy 98.559602 -264.65218) (xy 98.512331 -264.665872)
			(xy 98.463476 -264.671804) (xy 98.414301 -264.669823) (xy 98.366082 -264.659979) (xy 98.320066 -264.642527)
			(xy 98.277445 -264.61792) (xy 98.239324 -264.586795) (xy 98.206689 -264.549958) (xy 98.180386 -264.508362)
			(xy 98.161095 -264.463086) (xy 98.149318 -264.415302) (xy 98.145358 -264.366248) (xy 96.876362 -264.366248)
			(xy 96.875867 -264.390855) (xy 96.867972 -264.439432) (xy 96.852388 -264.486113) (xy 96.829517 -264.52969)
			(xy 96.799952 -264.569034) (xy 96.764459 -264.603126) (xy 96.723956 -264.631082) (xy 96.679494 -264.65218)
			(xy 96.632223 -264.665872) (xy 96.583368 -264.671804) (xy 96.534193 -264.669823) (xy 96.485974 -264.659979)
			(xy 96.439958 -264.642527) (xy 96.397337 -264.61792) (xy 96.359216 -264.586795) (xy 96.326581 -264.549958)
			(xy 96.300278 -264.508362) (xy 96.280987 -264.463086) (xy 96.26921 -264.415302) (xy 96.26525 -264.366248)
			(xy 95.946722 -264.366248) (xy 95.94621 -264.391694) (xy 95.938046 -264.441928) (xy 95.92193 -264.490202)
			(xy 95.898279 -264.535265) (xy 95.867706 -264.575951) (xy 95.831002 -264.611206) (xy 95.789118 -264.640116)
			(xy 95.743139 -264.661933) (xy 95.694255 -264.676093) (xy 95.643734 -264.682227) (xy 95.592882 -264.680178)
			(xy 95.543018 -264.669998) (xy 95.495432 -264.651951) (xy 95.451358 -264.626505) (xy 95.411936 -264.594318)
			(xy 95.378188 -264.556224) (xy 95.350987 -264.51321) (xy 95.331039 -264.46639) (xy 95.31886 -264.416976)
			(xy 95.314765 -264.366248) (xy 95.006668 -264.366248) (xy 95.006156 -264.391694) (xy 94.997992 -264.441928)
			(xy 94.981876 -264.490202) (xy 94.958225 -264.535265) (xy 94.927652 -264.575951) (xy 94.890948 -264.611206)
			(xy 94.849064 -264.640116) (xy 94.803085 -264.661933) (xy 94.754201 -264.676093) (xy 94.70368 -264.682227)
			(xy 94.652828 -264.680178) (xy 94.602964 -264.669998) (xy 94.555378 -264.651951) (xy 94.511304 -264.626505)
			(xy 94.471882 -264.594318) (xy 94.438134 -264.556224) (xy 94.410933 -264.51321) (xy 94.390985 -264.46639)
			(xy 94.378806 -264.416976) (xy 94.374711 -264.366248) (xy 94.056454 -264.366248) (xy 94.055959 -264.390855)
			(xy 94.048064 -264.439432) (xy 94.03248 -264.486113) (xy 94.009609 -264.52969) (xy 93.980044 -264.569034)
			(xy 93.944551 -264.603126) (xy 93.904048 -264.631082) (xy 93.859586 -264.65218) (xy 93.812315 -264.665872)
			(xy 93.76346 -264.671804) (xy 93.714285 -264.669823) (xy 93.666066 -264.659979) (xy 93.62005 -264.642527)
			(xy 93.577429 -264.61792) (xy 93.539308 -264.586795) (xy 93.506673 -264.549958) (xy 93.48037 -264.508362)
			(xy 93.461079 -264.463086) (xy 93.449302 -264.415302) (xy 93.445342 -264.366248) (xy 93.126814 -264.366248)
			(xy 93.126302 -264.391694) (xy 93.118138 -264.441928) (xy 93.102022 -264.490202) (xy 93.078371 -264.535265)
			(xy 93.047798 -264.575951) (xy 93.011094 -264.611206) (xy 92.96921 -264.640116) (xy 92.923231 -264.661933)
			(xy 92.874347 -264.676093) (xy 92.823826 -264.682227) (xy 92.772974 -264.680178) (xy 92.72311 -264.669998)
			(xy 92.675524 -264.651951) (xy 92.63145 -264.626505) (xy 92.592028 -264.594318) (xy 92.55828 -264.556224)
			(xy 92.531079 -264.51321) (xy 92.511131 -264.46639) (xy 92.498952 -264.416976) (xy 92.494857 -264.366248)
			(xy 92.176346 -264.366248) (xy 92.175851 -264.390855) (xy 92.167956 -264.439432) (xy 92.152372 -264.486113)
			(xy 92.129501 -264.52969) (xy 92.099936 -264.569034) (xy 92.064443 -264.603126) (xy 92.02394 -264.631082)
			(xy 91.979478 -264.65218) (xy 91.932207 -264.665872) (xy 91.883352 -264.671804) (xy 91.834177 -264.669823)
			(xy 91.785958 -264.659979) (xy 91.739942 -264.642527) (xy 91.697321 -264.61792) (xy 91.6592 -264.586795)
			(xy 91.626565 -264.549958) (xy 91.600262 -264.508362) (xy 91.580971 -264.463086) (xy 91.569194 -264.415302)
			(xy 91.565234 -264.366248) (xy 91.246706 -264.366248) (xy 91.246194 -264.391694) (xy 91.23803 -264.441928)
			(xy 91.221914 -264.490202) (xy 91.198263 -264.535265) (xy 91.16769 -264.575951) (xy 91.130986 -264.611206)
			(xy 91.089102 -264.640116) (xy 91.043123 -264.661933) (xy 90.994239 -264.676093) (xy 90.943718 -264.682227)
			(xy 90.892866 -264.680178) (xy 90.843002 -264.669998) (xy 90.795416 -264.651951) (xy 90.751342 -264.626505)
			(xy 90.71192 -264.594318) (xy 90.678172 -264.556224) (xy 90.650971 -264.51321) (xy 90.631023 -264.46639)
			(xy 90.618844 -264.416976) (xy 90.614749 -264.366248) (xy 90.296238 -264.366248) (xy 90.295743 -264.390855)
			(xy 90.287848 -264.439432) (xy 90.272264 -264.486113) (xy 90.249393 -264.52969) (xy 90.219828 -264.569034)
			(xy 90.184335 -264.603126) (xy 90.143832 -264.631082) (xy 90.09937 -264.65218) (xy 90.052099 -264.665872)
			(xy 90.003244 -264.671804) (xy 89.954069 -264.669823) (xy 89.90585 -264.659979) (xy 89.859834 -264.642527)
			(xy 89.817213 -264.61792) (xy 89.779092 -264.586795) (xy 89.746457 -264.549958) (xy 89.720154 -264.508362)
			(xy 89.700863 -264.463086) (xy 89.689086 -264.415302) (xy 89.685126 -264.366248) (xy 89.356438 -264.366248)
			(xy 89.355943 -264.390855) (xy 89.348048 -264.439432) (xy 89.332464 -264.486113) (xy 89.309593 -264.52969)
			(xy 89.280028 -264.569034) (xy 89.244535 -264.603126) (xy 89.204032 -264.631082) (xy 89.15957 -264.65218)
			(xy 89.112299 -264.665872) (xy 89.063444 -264.671804) (xy 89.014269 -264.669823) (xy 88.96605 -264.659979)
			(xy 88.920034 -264.642527) (xy 88.877413 -264.61792) (xy 88.839292 -264.586795) (xy 88.806657 -264.549958)
			(xy 88.780354 -264.508362) (xy 88.761063 -264.463086) (xy 88.749286 -264.415302) (xy 88.745326 -264.366248)
			(xy 88.416384 -264.366248) (xy 88.415889 -264.390855) (xy 88.407994 -264.439432) (xy 88.39241 -264.486113)
			(xy 88.369539 -264.52969) (xy 88.339974 -264.569034) (xy 88.304481 -264.603126) (xy 88.263978 -264.631082)
			(xy 88.219516 -264.65218) (xy 88.172245 -264.665872) (xy 88.12339 -264.671804) (xy 88.074215 -264.669823)
			(xy 88.025996 -264.659979) (xy 87.97998 -264.642527) (xy 87.937359 -264.61792) (xy 87.899238 -264.586795)
			(xy 87.866603 -264.549958) (xy 87.8403 -264.508362) (xy 87.821009 -264.463086) (xy 87.809232 -264.415302)
			(xy 87.805272 -264.366248) (xy 87.47633 -264.366248) (xy 87.475856 -264.390237) (xy 87.468344 -264.437625)
			(xy 87.453513 -264.483254) (xy 87.431727 -264.526001) (xy 87.403523 -264.564815) (xy 87.369595 -264.59874)
			(xy 87.330779 -264.62694) (xy 87.28803 -264.648722) (xy 87.242399 -264.66355) (xy 87.195011 -264.671058)
			(xy 87.171022 -264.671556) (xy 87.159613 -264.671481) (xy 87.136856 -264.669826) (xy 87.125556 -264.668254)
			(xy 87.114634 -264.666476) (xy 87.09279 -264.672826) (xy 87.065358 -264.696702) (xy 87.06485 -264.69721)
			(xy 87.030814 -264.72642) (xy 87.02929 -264.72769) (xy 87.024972 -264.732008) (xy 87.017606 -264.73912)
			(xy 87.009986 -264.757916) (xy 87.009986 -265.176254) (xy 87.335118 -265.176254) (xy 87.339078 -265.1272)
			(xy 87.350855 -265.079416) (xy 87.370146 -265.03414) (xy 87.396449 -264.992544) (xy 87.429084 -264.955707)
			(xy 87.467205 -264.924582) (xy 87.509826 -264.899975) (xy 87.555842 -264.882523) (xy 87.604061 -264.872679)
			(xy 87.653236 -264.870698) (xy 87.702091 -264.87663) (xy 87.749362 -264.890322) (xy 87.793824 -264.91142)
			(xy 87.834327 -264.939376) (xy 87.86982 -264.973468) (xy 87.899385 -265.012812) (xy 87.922256 -265.056389)
			(xy 87.93784 -265.10307) (xy 87.945735 -265.151647) (xy 87.94623 -265.176254) (xy 88.275172 -265.176254)
			(xy 88.279132 -265.1272) (xy 88.290909 -265.079416) (xy 88.3102 -265.03414) (xy 88.336503 -264.992544)
			(xy 88.369138 -264.955707) (xy 88.407259 -264.924582) (xy 88.44988 -264.899975) (xy 88.495896 -264.882523)
			(xy 88.544115 -264.872679) (xy 88.59329 -264.870698) (xy 88.642145 -264.87663) (xy 88.689416 -264.890322)
			(xy 88.733878 -264.91142) (xy 88.774381 -264.939376) (xy 88.809874 -264.973468) (xy 88.839439 -265.012812)
			(xy 88.86231 -265.056389) (xy 88.877894 -265.10307) (xy 88.885789 -265.151647) (xy 88.886284 -265.176254)
			(xy 89.215226 -265.176254) (xy 89.219186 -265.1272) (xy 89.230963 -265.079416) (xy 89.250254 -265.03414)
			(xy 89.276557 -264.992544) (xy 89.309192 -264.955707) (xy 89.347313 -264.924582) (xy 89.389934 -264.899975)
			(xy 89.43595 -264.882523) (xy 89.484169 -264.872679) (xy 89.533344 -264.870698) (xy 89.582199 -264.87663)
			(xy 89.62947 -264.890322) (xy 89.673932 -264.91142) (xy 89.714435 -264.939376) (xy 89.749928 -264.973468)
			(xy 89.779493 -265.012812) (xy 89.802364 -265.056389) (xy 89.817948 -265.10307) (xy 89.825843 -265.151647)
			(xy 89.826338 -265.176254) (xy 90.15528 -265.176254) (xy 90.15924 -265.1272) (xy 90.171017 -265.079416)
			(xy 90.190308 -265.03414) (xy 90.216611 -264.992544) (xy 90.249246 -264.955707) (xy 90.287367 -264.924582)
			(xy 90.329988 -264.899975) (xy 90.376004 -264.882523) (xy 90.424223 -264.872679) (xy 90.473398 -264.870698)
			(xy 90.522253 -264.87663) (xy 90.569524 -264.890322) (xy 90.613986 -264.91142) (xy 90.654489 -264.939376)
			(xy 90.689982 -264.973468) (xy 90.719547 -265.012812) (xy 90.742418 -265.056389) (xy 90.758002 -265.10307)
			(xy 90.765897 -265.151647) (xy 90.766392 -265.176254) (xy 91.084903 -265.176254) (xy 91.088998 -265.125526)
			(xy 91.101177 -265.076112) (xy 91.121125 -265.029292) (xy 91.148326 -264.986278) (xy 91.182074 -264.948184)
			(xy 91.221496 -264.915997) (xy 91.26557 -264.890551) (xy 91.313156 -264.872504) (xy 91.36302 -264.862324)
			(xy 91.413872 -264.860275) (xy 91.464393 -264.866409) (xy 91.513277 -264.880569) (xy 91.559256 -264.902386)
			(xy 91.60114 -264.931296) (xy 91.637844 -264.966551) (xy 91.668417 -265.007237) (xy 91.692068 -265.0523)
			(xy 91.708184 -265.100574) (xy 91.716348 -265.150808) (xy 91.71686 -265.176254) (xy 92.035134 -265.176254)
			(xy 92.039094 -265.1272) (xy 92.050871 -265.079416) (xy 92.070162 -265.03414) (xy 92.096465 -264.992544)
			(xy 92.1291 -264.955707) (xy 92.167221 -264.924582) (xy 92.209842 -264.899975) (xy 92.255858 -264.882523)
			(xy 92.304077 -264.872679) (xy 92.353252 -264.870698) (xy 92.402107 -264.87663) (xy 92.449378 -264.890322)
			(xy 92.49384 -264.91142) (xy 92.534343 -264.939376) (xy 92.569836 -264.973468) (xy 92.599401 -265.012812)
			(xy 92.622272 -265.056389) (xy 92.637856 -265.10307) (xy 92.645751 -265.151647) (xy 92.646246 -265.176254)
			(xy 92.975188 -265.176254) (xy 92.979148 -265.1272) (xy 92.990925 -265.079416) (xy 93.010216 -265.03414)
			(xy 93.036519 -264.992544) (xy 93.069154 -264.955707) (xy 93.107275 -264.924582) (xy 93.149896 -264.899975)
			(xy 93.195912 -264.882523) (xy 93.244131 -264.872679) (xy 93.293306 -264.870698) (xy 93.342161 -264.87663)
			(xy 93.389432 -264.890322) (xy 93.433894 -264.91142) (xy 93.474397 -264.939376) (xy 93.50989 -264.973468)
			(xy 93.539455 -265.012812) (xy 93.562326 -265.056389) (xy 93.57791 -265.10307) (xy 93.585805 -265.151647)
			(xy 93.5863 -265.176254) (xy 93.904811 -265.176254) (xy 93.908906 -265.125526) (xy 93.921085 -265.076112)
			(xy 93.941033 -265.029292) (xy 93.968234 -264.986278) (xy 94.001982 -264.948184) (xy 94.041404 -264.915997)
			(xy 94.085478 -264.890551) (xy 94.133064 -264.872504) (xy 94.182928 -264.862324) (xy 94.23378 -264.860275)
			(xy 94.284301 -264.866409) (xy 94.333185 -264.880569) (xy 94.379164 -264.902386) (xy 94.421048 -264.931296)
			(xy 94.457752 -264.966551) (xy 94.488325 -265.007237) (xy 94.511976 -265.0523) (xy 94.528092 -265.100574)
			(xy 94.536256 -265.150808) (xy 94.536768 -265.176254) (xy 94.855296 -265.176254) (xy 94.859256 -265.1272)
			(xy 94.871033 -265.079416) (xy 94.890324 -265.03414) (xy 94.916627 -264.992544) (xy 94.949262 -264.955707)
			(xy 94.987383 -264.924582) (xy 95.030004 -264.899975) (xy 95.07602 -264.882523) (xy 95.124239 -264.872679)
			(xy 95.173414 -264.870698) (xy 95.222269 -264.87663) (xy 95.26954 -264.890322) (xy 95.314002 -264.91142)
			(xy 95.354505 -264.939376) (xy 95.389998 -264.973468) (xy 95.419563 -265.012812) (xy 95.442434 -265.056389)
			(xy 95.458018 -265.10307) (xy 95.465913 -265.151647) (xy 95.466408 -265.176254) (xy 95.79535 -265.176254)
			(xy 95.79931 -265.1272) (xy 95.811087 -265.079416) (xy 95.830378 -265.03414) (xy 95.856681 -264.992544)
			(xy 95.889316 -264.955707) (xy 95.927437 -264.924582) (xy 95.970058 -264.899975) (xy 96.016074 -264.882523)
			(xy 96.064293 -264.872679) (xy 96.113468 -264.870698) (xy 96.162323 -264.87663) (xy 96.209594 -264.890322)
			(xy 96.254056 -264.91142) (xy 96.294559 -264.939376) (xy 96.330052 -264.973468) (xy 96.359617 -265.012812)
			(xy 96.382488 -265.056389) (xy 96.398072 -265.10307) (xy 96.405967 -265.151647) (xy 96.406462 -265.176254)
			(xy 97.675204 -265.176254) (xy 97.679164 -265.1272) (xy 97.690941 -265.079416) (xy 97.710232 -265.03414)
			(xy 97.736535 -264.992544) (xy 97.76917 -264.955707) (xy 97.807291 -264.924582) (xy 97.849912 -264.899975)
			(xy 97.895928 -264.882523) (xy 97.944147 -264.872679) (xy 97.993322 -264.870698) (xy 98.042177 -264.87663)
			(xy 98.089448 -264.890322) (xy 98.13391 -264.91142) (xy 98.174413 -264.939376) (xy 98.209906 -264.973468)
			(xy 98.239471 -265.012812) (xy 98.262342 -265.056389) (xy 98.277926 -265.10307) (xy 98.285821 -265.151647)
			(xy 98.286316 -265.176254) (xy 99.555312 -265.176254) (xy 99.559272 -265.1272) (xy 99.571049 -265.079416)
			(xy 99.59034 -265.03414) (xy 99.616643 -264.992544) (xy 99.649278 -264.955707) (xy 99.687399 -264.924582)
			(xy 99.73002 -264.899975) (xy 99.776036 -264.882523) (xy 99.824255 -264.872679) (xy 99.87343 -264.870698)
			(xy 99.922285 -264.87663) (xy 99.969556 -264.890322) (xy 100.014018 -264.91142) (xy 100.054521 -264.939376)
			(xy 100.090014 -264.973468) (xy 100.119579 -265.012812) (xy 100.14245 -265.056389) (xy 100.158034 -265.10307)
			(xy 100.165929 -265.151647) (xy 100.166424 -265.176254) (xy 100.165929 -265.200861) (xy 100.158034 -265.249438)
			(xy 100.14245 -265.296119) (xy 100.119579 -265.339696) (xy 100.090014 -265.37904) (xy 100.054521 -265.413132)
			(xy 100.014018 -265.441088) (xy 99.969556 -265.462186) (xy 99.922285 -265.475878) (xy 99.87343 -265.48181)
			(xy 99.824255 -265.479829) (xy 99.776036 -265.469985) (xy 99.73002 -265.452533) (xy 99.687399 -265.427926)
			(xy 99.649278 -265.396801) (xy 99.616643 -265.359964) (xy 99.59034 -265.318368) (xy 99.571049 -265.273092)
			(xy 99.559272 -265.225308) (xy 99.555312 -265.176254) (xy 98.286316 -265.176254) (xy 98.285821 -265.200861)
			(xy 98.277926 -265.249438) (xy 98.262342 -265.296119) (xy 98.239471 -265.339696) (xy 98.209906 -265.37904)
			(xy 98.174413 -265.413132) (xy 98.13391 -265.441088) (xy 98.089448 -265.462186) (xy 98.042177 -265.475878)
			(xy 97.993322 -265.48181) (xy 97.944147 -265.479829) (xy 97.895928 -265.469985) (xy 97.849912 -265.452533)
			(xy 97.807291 -265.427926) (xy 97.76917 -265.396801) (xy 97.736535 -265.359964) (xy 97.710232 -265.318368)
			(xy 97.690941 -265.273092) (xy 97.679164 -265.225308) (xy 97.675204 -265.176254) (xy 96.406462 -265.176254)
			(xy 96.405967 -265.200861) (xy 96.398072 -265.249438) (xy 96.382488 -265.296119) (xy 96.359617 -265.339696)
			(xy 96.330052 -265.37904) (xy 96.294559 -265.413132) (xy 96.254056 -265.441088) (xy 96.209594 -265.462186)
			(xy 96.162323 -265.475878) (xy 96.113468 -265.48181) (xy 96.064293 -265.479829) (xy 96.016074 -265.469985)
			(xy 95.970058 -265.452533) (xy 95.927437 -265.427926) (xy 95.889316 -265.396801) (xy 95.856681 -265.359964)
			(xy 95.830378 -265.318368) (xy 95.811087 -265.273092) (xy 95.79931 -265.225308) (xy 95.79535 -265.176254)
			(xy 95.466408 -265.176254) (xy 95.465913 -265.200861) (xy 95.458018 -265.249438) (xy 95.442434 -265.296119)
			(xy 95.419563 -265.339696) (xy 95.389998 -265.37904) (xy 95.354505 -265.413132) (xy 95.314002 -265.441088)
			(xy 95.26954 -265.462186) (xy 95.222269 -265.475878) (xy 95.173414 -265.48181) (xy 95.124239 -265.479829)
			(xy 95.07602 -265.469985) (xy 95.030004 -265.452533) (xy 94.987383 -265.427926) (xy 94.949262 -265.396801)
			(xy 94.916627 -265.359964) (xy 94.890324 -265.318368) (xy 94.871033 -265.273092) (xy 94.859256 -265.225308)
			(xy 94.855296 -265.176254) (xy 94.536768 -265.176254) (xy 94.536256 -265.2017) (xy 94.528092 -265.251934)
			(xy 94.511976 -265.300208) (xy 94.488325 -265.345271) (xy 94.457752 -265.385957) (xy 94.421048 -265.421212)
			(xy 94.379164 -265.450122) (xy 94.333185 -265.471939) (xy 94.284301 -265.486099) (xy 94.23378 -265.492233)
			(xy 94.182928 -265.490184) (xy 94.133064 -265.480004) (xy 94.085478 -265.461957) (xy 94.041404 -265.436511)
			(xy 94.001982 -265.404324) (xy 93.968234 -265.36623) (xy 93.941033 -265.323216) (xy 93.921085 -265.276396)
			(xy 93.908906 -265.226982) (xy 93.904811 -265.176254) (xy 93.5863 -265.176254) (xy 93.585805 -265.200861)
			(xy 93.57791 -265.249438) (xy 93.562326 -265.296119) (xy 93.539455 -265.339696) (xy 93.50989 -265.37904)
			(xy 93.474397 -265.413132) (xy 93.433894 -265.441088) (xy 93.389432 -265.462186) (xy 93.342161 -265.475878)
			(xy 93.293306 -265.48181) (xy 93.244131 -265.479829) (xy 93.195912 -265.469985) (xy 93.149896 -265.452533)
			(xy 93.107275 -265.427926) (xy 93.069154 -265.396801) (xy 93.036519 -265.359964) (xy 93.010216 -265.318368)
			(xy 92.990925 -265.273092) (xy 92.979148 -265.225308) (xy 92.975188 -265.176254) (xy 92.646246 -265.176254)
			(xy 92.645751 -265.200861) (xy 92.637856 -265.249438) (xy 92.622272 -265.296119) (xy 92.599401 -265.339696)
			(xy 92.569836 -265.37904) (xy 92.534343 -265.413132) (xy 92.49384 -265.441088) (xy 92.449378 -265.462186)
			(xy 92.402107 -265.475878) (xy 92.353252 -265.48181) (xy 92.304077 -265.479829) (xy 92.255858 -265.469985)
			(xy 92.209842 -265.452533) (xy 92.167221 -265.427926) (xy 92.1291 -265.396801) (xy 92.096465 -265.359964)
			(xy 92.070162 -265.318368) (xy 92.050871 -265.273092) (xy 92.039094 -265.225308) (xy 92.035134 -265.176254)
			(xy 91.71686 -265.176254) (xy 91.716348 -265.2017) (xy 91.708184 -265.251934) (xy 91.692068 -265.300208)
			(xy 91.668417 -265.345271) (xy 91.637844 -265.385957) (xy 91.60114 -265.421212) (xy 91.559256 -265.450122)
			(xy 91.513277 -265.471939) (xy 91.464393 -265.486099) (xy 91.413872 -265.492233) (xy 91.36302 -265.490184)
			(xy 91.313156 -265.480004) (xy 91.26557 -265.461957) (xy 91.221496 -265.436511) (xy 91.182074 -265.404324)
			(xy 91.148326 -265.36623) (xy 91.121125 -265.323216) (xy 91.101177 -265.276396) (xy 91.088998 -265.226982)
			(xy 91.084903 -265.176254) (xy 90.766392 -265.176254) (xy 90.765897 -265.200861) (xy 90.758002 -265.249438)
			(xy 90.742418 -265.296119) (xy 90.719547 -265.339696) (xy 90.689982 -265.37904) (xy 90.654489 -265.413132)
			(xy 90.613986 -265.441088) (xy 90.569524 -265.462186) (xy 90.522253 -265.475878) (xy 90.473398 -265.48181)
			(xy 90.424223 -265.479829) (xy 90.376004 -265.469985) (xy 90.329988 -265.452533) (xy 90.287367 -265.427926)
			(xy 90.249246 -265.396801) (xy 90.216611 -265.359964) (xy 90.190308 -265.318368) (xy 90.171017 -265.273092)
			(xy 90.15924 -265.225308) (xy 90.15528 -265.176254) (xy 89.826338 -265.176254) (xy 89.825843 -265.200861)
			(xy 89.817948 -265.249438) (xy 89.802364 -265.296119) (xy 89.779493 -265.339696) (xy 89.749928 -265.37904)
			(xy 89.714435 -265.413132) (xy 89.673932 -265.441088) (xy 89.62947 -265.462186) (xy 89.582199 -265.475878)
			(xy 89.533344 -265.48181) (xy 89.484169 -265.479829) (xy 89.43595 -265.469985) (xy 89.389934 -265.452533)
			(xy 89.347313 -265.427926) (xy 89.309192 -265.396801) (xy 89.276557 -265.359964) (xy 89.250254 -265.318368)
			(xy 89.230963 -265.273092) (xy 89.219186 -265.225308) (xy 89.215226 -265.176254) (xy 88.886284 -265.176254)
			(xy 88.885789 -265.200861) (xy 88.877894 -265.249438) (xy 88.86231 -265.296119) (xy 88.839439 -265.339696)
			(xy 88.809874 -265.37904) (xy 88.774381 -265.413132) (xy 88.733878 -265.441088) (xy 88.689416 -265.462186)
			(xy 88.642145 -265.475878) (xy 88.59329 -265.48181) (xy 88.544115 -265.479829) (xy 88.495896 -265.469985)
			(xy 88.44988 -265.452533) (xy 88.407259 -265.427926) (xy 88.369138 -265.396801) (xy 88.336503 -265.359964)
			(xy 88.3102 -265.318368) (xy 88.290909 -265.273092) (xy 88.279132 -265.225308) (xy 88.275172 -265.176254)
			(xy 87.94623 -265.176254) (xy 87.945735 -265.200861) (xy 87.93784 -265.249438) (xy 87.922256 -265.296119)
			(xy 87.899385 -265.339696) (xy 87.86982 -265.37904) (xy 87.834327 -265.413132) (xy 87.793824 -265.441088)
			(xy 87.749362 -265.462186) (xy 87.702091 -265.475878) (xy 87.653236 -265.48181) (xy 87.604061 -265.479829)
			(xy 87.555842 -265.469985) (xy 87.509826 -265.452533) (xy 87.467205 -265.427926) (xy 87.429084 -265.396801)
			(xy 87.396449 -265.359964) (xy 87.370146 -265.318368) (xy 87.350855 -265.273092) (xy 87.339078 -265.225308)
			(xy 87.335118 -265.176254) (xy 87.009986 -265.176254) (xy 87.009986 -265.98626) (xy 87.805272 -265.98626)
			(xy 87.809232 -265.937206) (xy 87.821009 -265.889422) (xy 87.8403 -265.844146) (xy 87.866603 -265.80255)
			(xy 87.899238 -265.765713) (xy 87.937359 -265.734588) (xy 87.97998 -265.709981) (xy 88.025996 -265.692529)
			(xy 88.074215 -265.682685) (xy 88.12339 -265.680704) (xy 88.172245 -265.686636) (xy 88.219516 -265.700328)
			(xy 88.263978 -265.721426) (xy 88.304481 -265.749382) (xy 88.339974 -265.783474) (xy 88.369539 -265.822818)
			(xy 88.39241 -265.866395) (xy 88.407994 -265.913076) (xy 88.415889 -265.961653) (xy 88.416384 -265.98626)
			(xy 88.745326 -265.98626) (xy 88.749286 -265.937206) (xy 88.761063 -265.889422) (xy 88.780354 -265.844146)
			(xy 88.806657 -265.80255) (xy 88.839292 -265.765713) (xy 88.877413 -265.734588) (xy 88.920034 -265.709981)
			(xy 88.96605 -265.692529) (xy 89.014269 -265.682685) (xy 89.063444 -265.680704) (xy 89.112299 -265.686636)
			(xy 89.15957 -265.700328) (xy 89.204032 -265.721426) (xy 89.244535 -265.749382) (xy 89.280028 -265.783474)
			(xy 89.309593 -265.822818) (xy 89.332464 -265.866395) (xy 89.348048 -265.913076) (xy 89.355943 -265.961653)
			(xy 89.356438 -265.98626) (xy 89.685126 -265.98626) (xy 89.689086 -265.937206) (xy 89.700863 -265.889422)
			(xy 89.720154 -265.844146) (xy 89.746457 -265.80255) (xy 89.779092 -265.765713) (xy 89.817213 -265.734588)
			(xy 89.859834 -265.709981) (xy 89.90585 -265.692529) (xy 89.954069 -265.682685) (xy 90.003244 -265.680704)
			(xy 90.052099 -265.686636) (xy 90.09937 -265.700328) (xy 90.143832 -265.721426) (xy 90.184335 -265.749382)
			(xy 90.219828 -265.783474) (xy 90.249393 -265.822818) (xy 90.272264 -265.866395) (xy 90.287848 -265.913076)
			(xy 90.295743 -265.961653) (xy 90.296238 -265.98626) (xy 90.62518 -265.98626) (xy 90.62914 -265.937206)
			(xy 90.640917 -265.889422) (xy 90.660208 -265.844146) (xy 90.686511 -265.80255) (xy 90.719146 -265.765713)
			(xy 90.757267 -265.734588) (xy 90.799888 -265.709981) (xy 90.845904 -265.692529) (xy 90.894123 -265.682685)
			(xy 90.943298 -265.680704) (xy 90.992153 -265.686636) (xy 91.039424 -265.700328) (xy 91.083886 -265.721426)
			(xy 91.124389 -265.749382) (xy 91.159882 -265.783474) (xy 91.189447 -265.822818) (xy 91.212318 -265.866395)
			(xy 91.227902 -265.913076) (xy 91.235797 -265.961653) (xy 91.236292 -265.98626) (xy 91.565234 -265.98626)
			(xy 91.569194 -265.937206) (xy 91.580971 -265.889422) (xy 91.600262 -265.844146) (xy 91.626565 -265.80255)
			(xy 91.6592 -265.765713) (xy 91.697321 -265.734588) (xy 91.739942 -265.709981) (xy 91.785958 -265.692529)
			(xy 91.834177 -265.682685) (xy 91.883352 -265.680704) (xy 91.932207 -265.686636) (xy 91.979478 -265.700328)
			(xy 92.02394 -265.721426) (xy 92.064443 -265.749382) (xy 92.099936 -265.783474) (xy 92.129501 -265.822818)
			(xy 92.152372 -265.866395) (xy 92.167956 -265.913076) (xy 92.175851 -265.961653) (xy 92.176346 -265.98626)
			(xy 92.494857 -265.98626) (xy 92.498952 -265.935532) (xy 92.511131 -265.886118) (xy 92.531079 -265.839298)
			(xy 92.55828 -265.796284) (xy 92.592028 -265.75819) (xy 92.63145 -265.726003) (xy 92.675524 -265.700557)
			(xy 92.72311 -265.68251) (xy 92.772974 -265.67233) (xy 92.823826 -265.670281) (xy 92.874347 -265.676415)
			(xy 92.923231 -265.690575) (xy 92.96921 -265.712392) (xy 93.011094 -265.741302) (xy 93.047798 -265.776557)
			(xy 93.078371 -265.817243) (xy 93.102022 -265.862306) (xy 93.118138 -265.91058) (xy 93.126302 -265.960814)
			(xy 93.126814 -265.98626) (xy 94.385142 -265.98626) (xy 94.389102 -265.937206) (xy 94.400879 -265.889422)
			(xy 94.42017 -265.844146) (xy 94.446473 -265.80255) (xy 94.479108 -265.765713) (xy 94.517229 -265.734588)
			(xy 94.55985 -265.709981) (xy 94.605866 -265.692529) (xy 94.654085 -265.682685) (xy 94.70326 -265.680704)
			(xy 94.752115 -265.686636) (xy 94.799386 -265.700328) (xy 94.843848 -265.721426) (xy 94.884351 -265.749382)
			(xy 94.919844 -265.783474) (xy 94.949409 -265.822818) (xy 94.97228 -265.866395) (xy 94.987864 -265.913076)
			(xy 94.995759 -265.961653) (xy 94.996254 -265.98626) (xy 95.314765 -265.98626) (xy 95.31886 -265.935532)
			(xy 95.331039 -265.886118) (xy 95.350987 -265.839298) (xy 95.378188 -265.796284) (xy 95.411936 -265.75819)
			(xy 95.451358 -265.726003) (xy 95.495432 -265.700557) (xy 95.543018 -265.68251) (xy 95.592882 -265.67233)
			(xy 95.643734 -265.670281) (xy 95.694255 -265.676415) (xy 95.743139 -265.690575) (xy 95.789118 -265.712392)
			(xy 95.831002 -265.741302) (xy 95.867706 -265.776557) (xy 95.898279 -265.817243) (xy 95.92193 -265.862306)
			(xy 95.938046 -265.91058) (xy 95.94621 -265.960814) (xy 95.946722 -265.98626) (xy 96.26525 -265.98626)
			(xy 96.26921 -265.937206) (xy 96.280987 -265.889422) (xy 96.300278 -265.844146) (xy 96.326581 -265.80255)
			(xy 96.359216 -265.765713) (xy 96.397337 -265.734588) (xy 96.439958 -265.709981) (xy 96.485974 -265.692529)
			(xy 96.534193 -265.682685) (xy 96.583368 -265.680704) (xy 96.632223 -265.686636) (xy 96.679494 -265.700328)
			(xy 96.723956 -265.721426) (xy 96.764459 -265.749382) (xy 96.799952 -265.783474) (xy 96.829517 -265.822818)
			(xy 96.852388 -265.866395) (xy 96.867972 -265.913076) (xy 96.875867 -265.961653) (xy 96.876362 -265.98626)
			(xy 98.145358 -265.98626) (xy 98.149318 -265.937206) (xy 98.161095 -265.889422) (xy 98.180386 -265.844146)
			(xy 98.206689 -265.80255) (xy 98.239324 -265.765713) (xy 98.277445 -265.734588) (xy 98.320066 -265.709981)
			(xy 98.366082 -265.692529) (xy 98.414301 -265.682685) (xy 98.463476 -265.680704) (xy 98.512331 -265.686636)
			(xy 98.559602 -265.700328) (xy 98.604064 -265.721426) (xy 98.644567 -265.749382) (xy 98.68006 -265.783474)
			(xy 98.709625 -265.822818) (xy 98.732496 -265.866395) (xy 98.74808 -265.913076) (xy 98.755975 -265.961653)
			(xy 98.75647 -265.98626) (xy 98.755975 -266.010867) (xy 98.74808 -266.059444) (xy 98.732496 -266.106125)
			(xy 98.709625 -266.149702) (xy 98.68006 -266.189046) (xy 98.644567 -266.223138) (xy 98.604064 -266.251094)
			(xy 98.559602 -266.272192) (xy 98.512331 -266.285884) (xy 98.463476 -266.291816) (xy 98.414301 -266.289835)
			(xy 98.366082 -266.279991) (xy 98.320066 -266.262539) (xy 98.277445 -266.237932) (xy 98.239324 -266.206807)
			(xy 98.206689 -266.16997) (xy 98.180386 -266.128374) (xy 98.161095 -266.083098) (xy 98.149318 -266.035314)
			(xy 98.145358 -265.98626) (xy 96.876362 -265.98626) (xy 96.875867 -266.010867) (xy 96.867972 -266.059444)
			(xy 96.852388 -266.106125) (xy 96.829517 -266.149702) (xy 96.799952 -266.189046) (xy 96.764459 -266.223138)
			(xy 96.723956 -266.251094) (xy 96.679494 -266.272192) (xy 96.632223 -266.285884) (xy 96.583368 -266.291816)
			(xy 96.534193 -266.289835) (xy 96.485974 -266.279991) (xy 96.439958 -266.262539) (xy 96.397337 -266.237932)
			(xy 96.359216 -266.206807) (xy 96.326581 -266.16997) (xy 96.300278 -266.128374) (xy 96.280987 -266.083098)
			(xy 96.26921 -266.035314) (xy 96.26525 -265.98626) (xy 95.946722 -265.98626) (xy 95.94621 -266.011706)
			(xy 95.938046 -266.06194) (xy 95.92193 -266.110214) (xy 95.898279 -266.155277) (xy 95.867706 -266.195963)
			(xy 95.831002 -266.231218) (xy 95.789118 -266.260128) (xy 95.743139 -266.281945) (xy 95.694255 -266.296105)
			(xy 95.643734 -266.302239) (xy 95.592882 -266.30019) (xy 95.543018 -266.29001) (xy 95.495432 -266.271963)
			(xy 95.451358 -266.246517) (xy 95.411936 -266.21433) (xy 95.378188 -266.176236) (xy 95.350987 -266.133222)
			(xy 95.331039 -266.086402) (xy 95.31886 -266.036988) (xy 95.314765 -265.98626) (xy 94.996254 -265.98626)
			(xy 94.995759 -266.010867) (xy 94.987864 -266.059444) (xy 94.97228 -266.106125) (xy 94.949409 -266.149702)
			(xy 94.919844 -266.189046) (xy 94.884351 -266.223138) (xy 94.843848 -266.251094) (xy 94.799386 -266.272192)
			(xy 94.752115 -266.285884) (xy 94.70326 -266.291816) (xy 94.654085 -266.289835) (xy 94.605866 -266.279991)
			(xy 94.55985 -266.262539) (xy 94.517229 -266.237932) (xy 94.479108 -266.206807) (xy 94.446473 -266.16997)
			(xy 94.42017 -266.128374) (xy 94.400879 -266.083098) (xy 94.389102 -266.035314) (xy 94.385142 -265.98626)
			(xy 93.126814 -265.98626) (xy 93.126302 -266.011706) (xy 93.118138 -266.06194) (xy 93.102022 -266.110214)
			(xy 93.078371 -266.155277) (xy 93.047798 -266.195963) (xy 93.011094 -266.231218) (xy 92.96921 -266.260128)
			(xy 92.923231 -266.281945) (xy 92.874347 -266.296105) (xy 92.823826 -266.302239) (xy 92.772974 -266.30019)
			(xy 92.72311 -266.29001) (xy 92.675524 -266.271963) (xy 92.63145 -266.246517) (xy 92.592028 -266.21433)
			(xy 92.55828 -266.176236) (xy 92.531079 -266.133222) (xy 92.511131 -266.086402) (xy 92.498952 -266.036988)
			(xy 92.494857 -265.98626) (xy 92.176346 -265.98626) (xy 92.175851 -266.010867) (xy 92.167956 -266.059444)
			(xy 92.152372 -266.106125) (xy 92.129501 -266.149702) (xy 92.099936 -266.189046) (xy 92.064443 -266.223138)
			(xy 92.02394 -266.251094) (xy 91.979478 -266.272192) (xy 91.932207 -266.285884) (xy 91.883352 -266.291816)
			(xy 91.834177 -266.289835) (xy 91.785958 -266.279991) (xy 91.739942 -266.262539) (xy 91.697321 -266.237932)
			(xy 91.6592 -266.206807) (xy 91.626565 -266.16997) (xy 91.600262 -266.128374) (xy 91.580971 -266.083098)
			(xy 91.569194 -266.035314) (xy 91.565234 -265.98626) (xy 91.236292 -265.98626) (xy 91.235797 -266.010867)
			(xy 91.227902 -266.059444) (xy 91.212318 -266.106125) (xy 91.189447 -266.149702) (xy 91.159882 -266.189046)
			(xy 91.124389 -266.223138) (xy 91.083886 -266.251094) (xy 91.039424 -266.272192) (xy 90.992153 -266.285884)
			(xy 90.943298 -266.291816) (xy 90.894123 -266.289835) (xy 90.845904 -266.279991) (xy 90.799888 -266.262539)
			(xy 90.757267 -266.237932) (xy 90.719146 -266.206807) (xy 90.686511 -266.16997) (xy 90.660208 -266.128374)
			(xy 90.640917 -266.083098) (xy 90.62914 -266.035314) (xy 90.62518 -265.98626) (xy 90.296238 -265.98626)
			(xy 90.295743 -266.010867) (xy 90.287848 -266.059444) (xy 90.272264 -266.106125) (xy 90.249393 -266.149702)
			(xy 90.219828 -266.189046) (xy 90.184335 -266.223138) (xy 90.143832 -266.251094) (xy 90.09937 -266.272192)
			(xy 90.052099 -266.285884) (xy 90.003244 -266.291816) (xy 89.954069 -266.289835) (xy 89.90585 -266.279991)
			(xy 89.859834 -266.262539) (xy 89.817213 -266.237932) (xy 89.779092 -266.206807) (xy 89.746457 -266.16997)
			(xy 89.720154 -266.128374) (xy 89.700863 -266.083098) (xy 89.689086 -266.035314) (xy 89.685126 -265.98626)
			(xy 89.356438 -265.98626) (xy 89.355943 -266.010867) (xy 89.348048 -266.059444) (xy 89.332464 -266.106125)
			(xy 89.309593 -266.149702) (xy 89.280028 -266.189046) (xy 89.244535 -266.223138) (xy 89.204032 -266.251094)
			(xy 89.15957 -266.272192) (xy 89.112299 -266.285884) (xy 89.063444 -266.291816) (xy 89.014269 -266.289835)
			(xy 88.96605 -266.279991) (xy 88.920034 -266.262539) (xy 88.877413 -266.237932) (xy 88.839292 -266.206807)
			(xy 88.806657 -266.16997) (xy 88.780354 -266.128374) (xy 88.761063 -266.083098) (xy 88.749286 -266.035314)
			(xy 88.745326 -265.98626) (xy 88.416384 -265.98626) (xy 88.415889 -266.010867) (xy 88.407994 -266.059444)
			(xy 88.39241 -266.106125) (xy 88.369539 -266.149702) (xy 88.339974 -266.189046) (xy 88.304481 -266.223138)
			(xy 88.263978 -266.251094) (xy 88.219516 -266.272192) (xy 88.172245 -266.285884) (xy 88.12339 -266.291816)
			(xy 88.074215 -266.289835) (xy 88.025996 -266.279991) (xy 87.97998 -266.262539) (xy 87.937359 -266.237932)
			(xy 87.899238 -266.206807) (xy 87.866603 -266.16997) (xy 87.8403 -266.128374) (xy 87.821009 -266.083098)
			(xy 87.809232 -266.035314) (xy 87.805272 -265.98626) (xy 87.009986 -265.98626) (xy 87.009986 -266.796266)
			(xy 87.335118 -266.796266) (xy 87.339078 -266.747212) (xy 87.350855 -266.699428) (xy 87.370146 -266.654152)
			(xy 87.396449 -266.612556) (xy 87.429084 -266.575719) (xy 87.467205 -266.544594) (xy 87.509826 -266.519987)
			(xy 87.555842 -266.502535) (xy 87.604061 -266.492691) (xy 87.653236 -266.49071) (xy 87.702091 -266.496642)
			(xy 87.749362 -266.510334) (xy 87.793824 -266.531432) (xy 87.834327 -266.559388) (xy 87.86982 -266.59348)
			(xy 87.899385 -266.632824) (xy 87.922256 -266.676401) (xy 87.93784 -266.723082) (xy 87.945735 -266.771659)
			(xy 87.94623 -266.796266) (xy 88.275172 -266.796266) (xy 88.279132 -266.747212) (xy 88.290909 -266.699428)
			(xy 88.3102 -266.654152) (xy 88.336503 -266.612556) (xy 88.369138 -266.575719) (xy 88.407259 -266.544594)
			(xy 88.44988 -266.519987) (xy 88.495896 -266.502535) (xy 88.544115 -266.492691) (xy 88.59329 -266.49071)
			(xy 88.642145 -266.496642) (xy 88.689416 -266.510334) (xy 88.733878 -266.531432) (xy 88.774381 -266.559388)
			(xy 88.809874 -266.59348) (xy 88.839439 -266.632824) (xy 88.86231 -266.676401) (xy 88.877894 -266.723082)
			(xy 88.885789 -266.771659) (xy 88.886284 -266.796266) (xy 89.215226 -266.796266) (xy 89.219186 -266.747212)
			(xy 89.230963 -266.699428) (xy 89.250254 -266.654152) (xy 89.276557 -266.612556) (xy 89.309192 -266.575719)
			(xy 89.347313 -266.544594) (xy 89.389934 -266.519987) (xy 89.43595 -266.502535) (xy 89.484169 -266.492691)
			(xy 89.533344 -266.49071) (xy 89.582199 -266.496642) (xy 89.62947 -266.510334) (xy 89.673932 -266.531432)
			(xy 89.714435 -266.559388) (xy 89.749928 -266.59348) (xy 89.779493 -266.632824) (xy 89.802364 -266.676401)
			(xy 89.817948 -266.723082) (xy 89.825843 -266.771659) (xy 89.826338 -266.796266) (xy 90.15528 -266.796266)
			(xy 90.15924 -266.747212) (xy 90.171017 -266.699428) (xy 90.190308 -266.654152) (xy 90.216611 -266.612556)
			(xy 90.249246 -266.575719) (xy 90.287367 -266.544594) (xy 90.329988 -266.519987) (xy 90.376004 -266.502535)
			(xy 90.424223 -266.492691) (xy 90.473398 -266.49071) (xy 90.522253 -266.496642) (xy 90.569524 -266.510334)
			(xy 90.613986 -266.531432) (xy 90.654489 -266.559388) (xy 90.689982 -266.59348) (xy 90.719547 -266.632824)
			(xy 90.742418 -266.676401) (xy 90.758002 -266.723082) (xy 90.765897 -266.771659) (xy 90.766392 -266.796266)
			(xy 91.084903 -266.796266) (xy 91.088998 -266.745538) (xy 91.101177 -266.696124) (xy 91.121125 -266.649304)
			(xy 91.148326 -266.60629) (xy 91.182074 -266.568196) (xy 91.221496 -266.536009) (xy 91.26557 -266.510563)
			(xy 91.313156 -266.492516) (xy 91.36302 -266.482336) (xy 91.413872 -266.480287) (xy 91.464393 -266.486421)
			(xy 91.513277 -266.500581) (xy 91.559256 -266.522398) (xy 91.60114 -266.551308) (xy 91.637844 -266.586563)
			(xy 91.668417 -266.627249) (xy 91.692068 -266.672312) (xy 91.708184 -266.720586) (xy 91.716348 -266.77082)
			(xy 91.71686 -266.796266) (xy 92.024703 -266.796266) (xy 92.028798 -266.745538) (xy 92.040977 -266.696124)
			(xy 92.060925 -266.649304) (xy 92.088126 -266.60629) (xy 92.121874 -266.568196) (xy 92.161296 -266.536009)
			(xy 92.20537 -266.510563) (xy 92.252956 -266.492516) (xy 92.30282 -266.482336) (xy 92.353672 -266.480287)
			(xy 92.404193 -266.486421) (xy 92.453077 -266.500581) (xy 92.499056 -266.522398) (xy 92.54094 -266.551308)
			(xy 92.577644 -266.586563) (xy 92.608217 -266.627249) (xy 92.631868 -266.672312) (xy 92.647984 -266.720586)
			(xy 92.656148 -266.77082) (xy 92.65666 -266.796266) (xy 92.975188 -266.796266) (xy 92.979148 -266.747212)
			(xy 92.990925 -266.699428) (xy 93.010216 -266.654152) (xy 93.036519 -266.612556) (xy 93.069154 -266.575719)
			(xy 93.107275 -266.544594) (xy 93.149896 -266.519987) (xy 93.195912 -266.502535) (xy 93.244131 -266.492691)
			(xy 93.293306 -266.49071) (xy 93.342161 -266.496642) (xy 93.389432 -266.510334) (xy 93.433894 -266.531432)
			(xy 93.474397 -266.559388) (xy 93.50989 -266.59348) (xy 93.539455 -266.632824) (xy 93.562326 -266.676401)
			(xy 93.57791 -266.723082) (xy 93.585805 -266.771659) (xy 93.5863 -266.796266) (xy 93.904811 -266.796266)
			(xy 93.908906 -266.745538) (xy 93.921085 -266.696124) (xy 93.941033 -266.649304) (xy 93.968234 -266.60629)
			(xy 94.001982 -266.568196) (xy 94.041404 -266.536009) (xy 94.085478 -266.510563) (xy 94.133064 -266.492516)
			(xy 94.182928 -266.482336) (xy 94.23378 -266.480287) (xy 94.284301 -266.486421) (xy 94.333185 -266.500581)
			(xy 94.379164 -266.522398) (xy 94.421048 -266.551308) (xy 94.457752 -266.586563) (xy 94.488325 -266.627249)
			(xy 94.511976 -266.672312) (xy 94.528092 -266.720586) (xy 94.536256 -266.77082) (xy 94.536768 -266.796266)
			(xy 94.855296 -266.796266) (xy 94.859256 -266.747212) (xy 94.871033 -266.699428) (xy 94.890324 -266.654152)
			(xy 94.916627 -266.612556) (xy 94.949262 -266.575719) (xy 94.987383 -266.544594) (xy 95.030004 -266.519987)
			(xy 95.07602 -266.502535) (xy 95.124239 -266.492691) (xy 95.173414 -266.49071) (xy 95.222269 -266.496642)
			(xy 95.26954 -266.510334) (xy 95.314002 -266.531432) (xy 95.354505 -266.559388) (xy 95.389998 -266.59348)
			(xy 95.419563 -266.632824) (xy 95.442434 -266.676401) (xy 95.458018 -266.723082) (xy 95.465913 -266.771659)
			(xy 95.466408 -266.796266) (xy 95.784919 -266.796266) (xy 95.789014 -266.745538) (xy 95.801193 -266.696124)
			(xy 95.821141 -266.649304) (xy 95.848342 -266.60629) (xy 95.88209 -266.568196) (xy 95.921512 -266.536009)
			(xy 95.965586 -266.510563) (xy 96.013172 -266.492516) (xy 96.063036 -266.482336) (xy 96.113888 -266.480287)
			(xy 96.164409 -266.486421) (xy 96.213293 -266.500581) (xy 96.259272 -266.522398) (xy 96.301156 -266.551308)
			(xy 96.33786 -266.586563) (xy 96.368433 -266.627249) (xy 96.392084 -266.672312) (xy 96.4082 -266.720586)
			(xy 96.416364 -266.77082) (xy 96.416876 -266.796266) (xy 97.675204 -266.796266) (xy 97.679164 -266.747212)
			(xy 97.690941 -266.699428) (xy 97.710232 -266.654152) (xy 97.736535 -266.612556) (xy 97.76917 -266.575719)
			(xy 97.807291 -266.544594) (xy 97.849912 -266.519987) (xy 97.895928 -266.502535) (xy 97.944147 -266.492691)
			(xy 97.993322 -266.49071) (xy 98.042177 -266.496642) (xy 98.089448 -266.510334) (xy 98.13391 -266.531432)
			(xy 98.174413 -266.559388) (xy 98.209906 -266.59348) (xy 98.239471 -266.632824) (xy 98.262342 -266.676401)
			(xy 98.277926 -266.723082) (xy 98.285821 -266.771659) (xy 98.286316 -266.796266) (xy 98.615258 -266.796266)
			(xy 98.619218 -266.747212) (xy 98.630995 -266.699428) (xy 98.650286 -266.654152) (xy 98.676589 -266.612556)
			(xy 98.709224 -266.575719) (xy 98.747345 -266.544594) (xy 98.789966 -266.519987) (xy 98.835982 -266.502535)
			(xy 98.884201 -266.492691) (xy 98.933376 -266.49071) (xy 98.982231 -266.496642) (xy 99.029502 -266.510334)
			(xy 99.073964 -266.531432) (xy 99.114467 -266.559388) (xy 99.14996 -266.59348) (xy 99.179525 -266.632824)
			(xy 99.202396 -266.676401) (xy 99.21798 -266.723082) (xy 99.225875 -266.771659) (xy 99.22637 -266.796266)
			(xy 99.225875 -266.820873) (xy 99.21798 -266.86945) (xy 99.202396 -266.916131) (xy 99.179525 -266.959708)
			(xy 99.14996 -266.999052) (xy 99.114467 -267.033144) (xy 99.073964 -267.0611) (xy 99.029502 -267.082198)
			(xy 98.982231 -267.09589) (xy 98.933376 -267.101822) (xy 98.884201 -267.099841) (xy 98.835982 -267.089997)
			(xy 98.789966 -267.072545) (xy 98.747345 -267.047938) (xy 98.709224 -267.016813) (xy 98.676589 -266.979976)
			(xy 98.650286 -266.93838) (xy 98.630995 -266.893104) (xy 98.619218 -266.84532) (xy 98.615258 -266.796266)
			(xy 98.286316 -266.796266) (xy 98.285821 -266.820873) (xy 98.277926 -266.86945) (xy 98.262342 -266.916131)
			(xy 98.239471 -266.959708) (xy 98.209906 -266.999052) (xy 98.174413 -267.033144) (xy 98.13391 -267.0611)
			(xy 98.089448 -267.082198) (xy 98.042177 -267.09589) (xy 97.993322 -267.101822) (xy 97.944147 -267.099841)
			(xy 97.895928 -267.089997) (xy 97.849912 -267.072545) (xy 97.807291 -267.047938) (xy 97.76917 -267.016813)
			(xy 97.736535 -266.979976) (xy 97.710232 -266.93838) (xy 97.690941 -266.893104) (xy 97.679164 -266.84532)
			(xy 97.675204 -266.796266) (xy 96.416876 -266.796266) (xy 96.416364 -266.821712) (xy 96.4082 -266.871946)
			(xy 96.392084 -266.92022) (xy 96.368433 -266.965283) (xy 96.33786 -267.005969) (xy 96.301156 -267.041224)
			(xy 96.259272 -267.070134) (xy 96.213293 -267.091951) (xy 96.164409 -267.106111) (xy 96.113888 -267.112245)
			(xy 96.063036 -267.110196) (xy 96.013172 -267.100016) (xy 95.965586 -267.081969) (xy 95.921512 -267.056523)
			(xy 95.88209 -267.024336) (xy 95.848342 -266.986242) (xy 95.821141 -266.943228) (xy 95.801193 -266.896408)
			(xy 95.789014 -266.846994) (xy 95.784919 -266.796266) (xy 95.466408 -266.796266) (xy 95.465913 -266.820873)
			(xy 95.458018 -266.86945) (xy 95.442434 -266.916131) (xy 95.419563 -266.959708) (xy 95.389998 -266.999052)
			(xy 95.354505 -267.033144) (xy 95.314002 -267.0611) (xy 95.26954 -267.082198) (xy 95.222269 -267.09589)
			(xy 95.173414 -267.101822) (xy 95.124239 -267.099841) (xy 95.07602 -267.089997) (xy 95.030004 -267.072545)
			(xy 94.987383 -267.047938) (xy 94.949262 -267.016813) (xy 94.916627 -266.979976) (xy 94.890324 -266.93838)
			(xy 94.871033 -266.893104) (xy 94.859256 -266.84532) (xy 94.855296 -266.796266) (xy 94.536768 -266.796266)
			(xy 94.536256 -266.821712) (xy 94.528092 -266.871946) (xy 94.511976 -266.92022) (xy 94.488325 -266.965283)
			(xy 94.457752 -267.005969) (xy 94.421048 -267.041224) (xy 94.379164 -267.070134) (xy 94.333185 -267.091951)
			(xy 94.284301 -267.106111) (xy 94.23378 -267.112245) (xy 94.182928 -267.110196) (xy 94.133064 -267.100016)
			(xy 94.085478 -267.081969) (xy 94.041404 -267.056523) (xy 94.001982 -267.024336) (xy 93.968234 -266.986242)
			(xy 93.941033 -266.943228) (xy 93.921085 -266.896408) (xy 93.908906 -266.846994) (xy 93.904811 -266.796266)
			(xy 93.5863 -266.796266) (xy 93.585805 -266.820873) (xy 93.57791 -266.86945) (xy 93.562326 -266.916131)
			(xy 93.539455 -266.959708) (xy 93.50989 -266.999052) (xy 93.474397 -267.033144) (xy 93.433894 -267.0611)
			(xy 93.389432 -267.082198) (xy 93.342161 -267.09589) (xy 93.293306 -267.101822) (xy 93.244131 -267.099841)
			(xy 93.195912 -267.089997) (xy 93.149896 -267.072545) (xy 93.107275 -267.047938) (xy 93.069154 -267.016813)
			(xy 93.036519 -266.979976) (xy 93.010216 -266.93838) (xy 92.990925 -266.893104) (xy 92.979148 -266.84532)
			(xy 92.975188 -266.796266) (xy 92.65666 -266.796266) (xy 92.656148 -266.821712) (xy 92.647984 -266.871946)
			(xy 92.631868 -266.92022) (xy 92.608217 -266.965283) (xy 92.577644 -267.005969) (xy 92.54094 -267.041224)
			(xy 92.499056 -267.070134) (xy 92.453077 -267.091951) (xy 92.404193 -267.106111) (xy 92.353672 -267.112245)
			(xy 92.30282 -267.110196) (xy 92.252956 -267.100016) (xy 92.20537 -267.081969) (xy 92.161296 -267.056523)
			(xy 92.121874 -267.024336) (xy 92.088126 -266.986242) (xy 92.060925 -266.943228) (xy 92.040977 -266.896408)
			(xy 92.028798 -266.846994) (xy 92.024703 -266.796266) (xy 91.71686 -266.796266) (xy 91.716348 -266.821712)
			(xy 91.708184 -266.871946) (xy 91.692068 -266.92022) (xy 91.668417 -266.965283) (xy 91.637844 -267.005969)
			(xy 91.60114 -267.041224) (xy 91.559256 -267.070134) (xy 91.513277 -267.091951) (xy 91.464393 -267.106111)
			(xy 91.413872 -267.112245) (xy 91.36302 -267.110196) (xy 91.313156 -267.100016) (xy 91.26557 -267.081969)
			(xy 91.221496 -267.056523) (xy 91.182074 -267.024336) (xy 91.148326 -266.986242) (xy 91.121125 -266.943228)
			(xy 91.101177 -266.896408) (xy 91.088998 -266.846994) (xy 91.084903 -266.796266) (xy 90.766392 -266.796266)
			(xy 90.765897 -266.820873) (xy 90.758002 -266.86945) (xy 90.742418 -266.916131) (xy 90.719547 -266.959708)
			(xy 90.689982 -266.999052) (xy 90.654489 -267.033144) (xy 90.613986 -267.0611) (xy 90.569524 -267.082198)
			(xy 90.522253 -267.09589) (xy 90.473398 -267.101822) (xy 90.424223 -267.099841) (xy 90.376004 -267.089997)
			(xy 90.329988 -267.072545) (xy 90.287367 -267.047938) (xy 90.249246 -267.016813) (xy 90.216611 -266.979976)
			(xy 90.190308 -266.93838) (xy 90.171017 -266.893104) (xy 90.15924 -266.84532) (xy 90.15528 -266.796266)
			(xy 89.826338 -266.796266) (xy 89.825843 -266.820873) (xy 89.817948 -266.86945) (xy 89.802364 -266.916131)
			(xy 89.779493 -266.959708) (xy 89.749928 -266.999052) (xy 89.714435 -267.033144) (xy 89.673932 -267.0611)
			(xy 89.62947 -267.082198) (xy 89.582199 -267.09589) (xy 89.533344 -267.101822) (xy 89.484169 -267.099841)
			(xy 89.43595 -267.089997) (xy 89.389934 -267.072545) (xy 89.347313 -267.047938) (xy 89.309192 -267.016813)
			(xy 89.276557 -266.979976) (xy 89.250254 -266.93838) (xy 89.230963 -266.893104) (xy 89.219186 -266.84532)
			(xy 89.215226 -266.796266) (xy 88.886284 -266.796266) (xy 88.885789 -266.820873) (xy 88.877894 -266.86945)
			(xy 88.86231 -266.916131) (xy 88.839439 -266.959708) (xy 88.809874 -266.999052) (xy 88.774381 -267.033144)
			(xy 88.733878 -267.0611) (xy 88.689416 -267.082198) (xy 88.642145 -267.09589) (xy 88.59329 -267.101822)
			(xy 88.544115 -267.099841) (xy 88.495896 -267.089997) (xy 88.44988 -267.072545) (xy 88.407259 -267.047938)
			(xy 88.369138 -267.016813) (xy 88.336503 -266.979976) (xy 88.3102 -266.93838) (xy 88.290909 -266.893104)
			(xy 88.279132 -266.84532) (xy 88.275172 -266.796266) (xy 87.94623 -266.796266) (xy 87.945735 -266.820873)
			(xy 87.93784 -266.86945) (xy 87.922256 -266.916131) (xy 87.899385 -266.959708) (xy 87.86982 -266.999052)
			(xy 87.834327 -267.033144) (xy 87.793824 -267.0611) (xy 87.749362 -267.082198) (xy 87.702091 -267.09589)
			(xy 87.653236 -267.101822) (xy 87.604061 -267.099841) (xy 87.555842 -267.089997) (xy 87.509826 -267.072545)
			(xy 87.467205 -267.047938) (xy 87.429084 -267.016813) (xy 87.396449 -266.979976) (xy 87.370146 -266.93838)
			(xy 87.350855 -266.893104) (xy 87.339078 -266.84532) (xy 87.335118 -266.796266) (xy 87.009986 -266.796266)
			(xy 87.009986 -267.204952) (xy 87.010357 -267.214058) (xy 87.016733 -267.231115) (xy 87.022432 -267.238226)
			(xy 87.024972 -267.24102) (xy 87.065104 -267.275564) (xy 87.080344 -267.288772) (xy 87.081614 -267.289788)
			(xy 87.088577 -267.294989) (xy 87.104935 -267.30083) (xy 87.113618 -267.301218) (xy 87.159592 -267.301218)
			(xy 87.171022 -267.300964) (xy 87.171276 -267.300964) (xy 87.195254 -267.301455) (xy 87.242614 -267.308995)
			(xy 87.288213 -267.323847) (xy 87.330929 -267.345645) (xy 87.369712 -267.373852) (xy 87.403609 -267.407776)
			(xy 87.431785 -267.446583) (xy 87.453548 -267.489317) (xy 87.468363 -267.534928) (xy 87.475864 -267.582294)
			(xy 87.47633 -267.606272) (xy 87.805272 -267.606272) (xy 87.809232 -267.557218) (xy 87.821009 -267.509434)
			(xy 87.8403 -267.464158) (xy 87.866603 -267.422562) (xy 87.899238 -267.385725) (xy 87.937359 -267.3546)
			(xy 87.97998 -267.329993) (xy 88.025996 -267.312541) (xy 88.074215 -267.302697) (xy 88.12339 -267.300716)
			(xy 88.172245 -267.306648) (xy 88.219516 -267.32034) (xy 88.263978 -267.341438) (xy 88.304481 -267.369394)
			(xy 88.339974 -267.403486) (xy 88.369539 -267.44283) (xy 88.39241 -267.486407) (xy 88.407994 -267.533088)
			(xy 88.415889 -267.581665) (xy 88.416384 -267.606272) (xy 88.745326 -267.606272) (xy 88.749286 -267.557218)
			(xy 88.761063 -267.509434) (xy 88.780354 -267.464158) (xy 88.806657 -267.422562) (xy 88.839292 -267.385725)
			(xy 88.877413 -267.3546) (xy 88.920034 -267.329993) (xy 88.96605 -267.312541) (xy 89.014269 -267.302697)
			(xy 89.063444 -267.300716) (xy 89.112299 -267.306648) (xy 89.15957 -267.32034) (xy 89.204032 -267.341438)
			(xy 89.244535 -267.369394) (xy 89.280028 -267.403486) (xy 89.309593 -267.44283) (xy 89.332464 -267.486407)
			(xy 89.348048 -267.533088) (xy 89.355943 -267.581665) (xy 89.356438 -267.606272) (xy 89.685126 -267.606272)
			(xy 89.689086 -267.557218) (xy 89.700863 -267.509434) (xy 89.720154 -267.464158) (xy 89.746457 -267.422562)
			(xy 89.779092 -267.385725) (xy 89.817213 -267.3546) (xy 89.859834 -267.329993) (xy 89.90585 -267.312541)
			(xy 89.954069 -267.302697) (xy 90.003244 -267.300716) (xy 90.052099 -267.306648) (xy 90.09937 -267.32034)
			(xy 90.143832 -267.341438) (xy 90.184335 -267.369394) (xy 90.219828 -267.403486) (xy 90.249393 -267.44283)
			(xy 90.272264 -267.486407) (xy 90.287848 -267.533088) (xy 90.295743 -267.581665) (xy 90.296238 -267.606272)
			(xy 90.614749 -267.606272) (xy 90.618844 -267.555544) (xy 90.631023 -267.50613) (xy 90.650971 -267.45931)
			(xy 90.678172 -267.416296) (xy 90.71192 -267.378202) (xy 90.751342 -267.346015) (xy 90.795416 -267.320569)
			(xy 90.843002 -267.302522) (xy 90.892866 -267.292342) (xy 90.943718 -267.290293) (xy 90.994239 -267.296427)
			(xy 91.043123 -267.310587) (xy 91.089102 -267.332404) (xy 91.130986 -267.361314) (xy 91.16769 -267.396569)
			(xy 91.198263 -267.437255) (xy 91.221914 -267.482318) (xy 91.23803 -267.530592) (xy 91.246194 -267.580826)
			(xy 91.246706 -267.606272) (xy 91.565234 -267.606272) (xy 91.569194 -267.557218) (xy 91.580971 -267.509434)
			(xy 91.600262 -267.464158) (xy 91.626565 -267.422562) (xy 91.6592 -267.385725) (xy 91.697321 -267.3546)
			(xy 91.739942 -267.329993) (xy 91.785958 -267.312541) (xy 91.834177 -267.302697) (xy 91.883352 -267.300716)
			(xy 91.932207 -267.306648) (xy 91.979478 -267.32034) (xy 92.02394 -267.341438) (xy 92.064443 -267.369394)
			(xy 92.099936 -267.403486) (xy 92.129501 -267.44283) (xy 92.152372 -267.486407) (xy 92.167956 -267.533088)
			(xy 92.175851 -267.581665) (xy 92.176346 -267.606272) (xy 92.505288 -267.606272) (xy 92.509248 -267.557218)
			(xy 92.521025 -267.509434) (xy 92.540316 -267.464158) (xy 92.566619 -267.422562) (xy 92.599254 -267.385725)
			(xy 92.637375 -267.3546) (xy 92.679996 -267.329993) (xy 92.726012 -267.312541) (xy 92.774231 -267.302697)
			(xy 92.823406 -267.300716) (xy 92.872261 -267.306648) (xy 92.919532 -267.32034) (xy 92.963994 -267.341438)
			(xy 93.004497 -267.369394) (xy 93.03999 -267.403486) (xy 93.069555 -267.44283) (xy 93.092426 -267.486407)
			(xy 93.10801 -267.533088) (xy 93.115905 -267.581665) (xy 93.1164 -267.606272) (xy 93.445342 -267.606272)
			(xy 93.449302 -267.557218) (xy 93.461079 -267.509434) (xy 93.48037 -267.464158) (xy 93.506673 -267.422562)
			(xy 93.539308 -267.385725) (xy 93.577429 -267.3546) (xy 93.62005 -267.329993) (xy 93.666066 -267.312541)
			(xy 93.714285 -267.302697) (xy 93.76346 -267.300716) (xy 93.812315 -267.306648) (xy 93.859586 -267.32034)
			(xy 93.904048 -267.341438) (xy 93.944551 -267.369394) (xy 93.980044 -267.403486) (xy 94.009609 -267.44283)
			(xy 94.03248 -267.486407) (xy 94.048064 -267.533088) (xy 94.055959 -267.581665) (xy 94.056454 -267.606272)
			(xy 94.374711 -267.606272) (xy 94.378806 -267.555544) (xy 94.390985 -267.50613) (xy 94.410933 -267.45931)
			(xy 94.438134 -267.416296) (xy 94.471882 -267.378202) (xy 94.511304 -267.346015) (xy 94.555378 -267.320569)
			(xy 94.602964 -267.302522) (xy 94.652828 -267.292342) (xy 94.70368 -267.290293) (xy 94.754201 -267.296427)
			(xy 94.803085 -267.310587) (xy 94.849064 -267.332404) (xy 94.890948 -267.361314) (xy 94.927652 -267.396569)
			(xy 94.958225 -267.437255) (xy 94.981876 -267.482318) (xy 94.997992 -267.530592) (xy 95.006156 -267.580826)
			(xy 95.006668 -267.606272) (xy 95.325196 -267.606272) (xy 95.329156 -267.557218) (xy 95.340933 -267.509434)
			(xy 95.360224 -267.464158) (xy 95.386527 -267.422562) (xy 95.419162 -267.385725) (xy 95.457283 -267.3546)
			(xy 95.499904 -267.329993) (xy 95.54592 -267.312541) (xy 95.594139 -267.302697) (xy 95.643314 -267.300716)
			(xy 95.692169 -267.306648) (xy 95.73944 -267.32034) (xy 95.783902 -267.341438) (xy 95.824405 -267.369394)
			(xy 95.859898 -267.403486) (xy 95.889463 -267.44283) (xy 95.912334 -267.486407) (xy 95.927918 -267.533088)
			(xy 95.935813 -267.581665) (xy 95.936308 -267.606272) (xy 96.26525 -267.606272) (xy 96.26921 -267.557218)
			(xy 96.280987 -267.509434) (xy 96.300278 -267.464158) (xy 96.326581 -267.422562) (xy 96.359216 -267.385725)
			(xy 96.397337 -267.3546) (xy 96.439958 -267.329993) (xy 96.485974 -267.312541) (xy 96.534193 -267.302697)
			(xy 96.583368 -267.300716) (xy 96.632223 -267.306648) (xy 96.679494 -267.32034) (xy 96.723956 -267.341438)
			(xy 96.764459 -267.369394) (xy 96.799952 -267.403486) (xy 96.829517 -267.44283) (xy 96.852388 -267.486407)
			(xy 96.867972 -267.533088) (xy 96.875867 -267.581665) (xy 96.876362 -267.606272) (xy 96.875867 -267.630879)
			(xy 96.867972 -267.679456) (xy 96.852388 -267.726137) (xy 96.829517 -267.769714) (xy 96.799952 -267.809058)
			(xy 96.764459 -267.84315) (xy 96.723956 -267.871106) (xy 96.679494 -267.892204) (xy 96.632223 -267.905896)
			(xy 96.583368 -267.911828) (xy 96.534193 -267.909847) (xy 96.485974 -267.900003) (xy 96.439958 -267.882551)
			(xy 96.397337 -267.857944) (xy 96.359216 -267.826819) (xy 96.326581 -267.789982) (xy 96.300278 -267.748386)
			(xy 96.280987 -267.70311) (xy 96.26921 -267.655326) (xy 96.26525 -267.606272) (xy 95.936308 -267.606272)
			(xy 95.935813 -267.630879) (xy 95.927918 -267.679456) (xy 95.912334 -267.726137) (xy 95.889463 -267.769714)
			(xy 95.859898 -267.809058) (xy 95.824405 -267.84315) (xy 95.783902 -267.871106) (xy 95.73944 -267.892204)
			(xy 95.692169 -267.905896) (xy 95.643314 -267.911828) (xy 95.594139 -267.909847) (xy 95.54592 -267.900003)
			(xy 95.499904 -267.882551) (xy 95.457283 -267.857944) (xy 95.419162 -267.826819) (xy 95.386527 -267.789982)
			(xy 95.360224 -267.748386) (xy 95.340933 -267.70311) (xy 95.329156 -267.655326) (xy 95.325196 -267.606272)
			(xy 95.006668 -267.606272) (xy 95.006156 -267.631718) (xy 94.997992 -267.681952) (xy 94.981876 -267.730226)
			(xy 94.958225 -267.775289) (xy 94.927652 -267.815975) (xy 94.890948 -267.85123) (xy 94.849064 -267.88014)
			(xy 94.803085 -267.901957) (xy 94.754201 -267.916117) (xy 94.70368 -267.922251) (xy 94.652828 -267.920202)
			(xy 94.602964 -267.910022) (xy 94.555378 -267.891975) (xy 94.511304 -267.866529) (xy 94.471882 -267.834342)
			(xy 94.438134 -267.796248) (xy 94.410933 -267.753234) (xy 94.390985 -267.706414) (xy 94.378806 -267.657)
			(xy 94.374711 -267.606272) (xy 94.056454 -267.606272) (xy 94.055959 -267.630879) (xy 94.048064 -267.679456)
			(xy 94.03248 -267.726137) (xy 94.009609 -267.769714) (xy 93.980044 -267.809058) (xy 93.944551 -267.84315)
			(xy 93.904048 -267.871106) (xy 93.859586 -267.892204) (xy 93.812315 -267.905896) (xy 93.76346 -267.911828)
			(xy 93.714285 -267.909847) (xy 93.666066 -267.900003) (xy 93.62005 -267.882551) (xy 93.577429 -267.857944)
			(xy 93.539308 -267.826819) (xy 93.506673 -267.789982) (xy 93.48037 -267.748386) (xy 93.461079 -267.70311)
			(xy 93.449302 -267.655326) (xy 93.445342 -267.606272) (xy 93.1164 -267.606272) (xy 93.115905 -267.630879)
			(xy 93.10801 -267.679456) (xy 93.092426 -267.726137) (xy 93.069555 -267.769714) (xy 93.03999 -267.809058)
			(xy 93.004497 -267.84315) (xy 92.963994 -267.871106) (xy 92.919532 -267.892204) (xy 92.872261 -267.905896)
			(xy 92.823406 -267.911828) (xy 92.774231 -267.909847) (xy 92.726012 -267.900003) (xy 92.679996 -267.882551)
			(xy 92.637375 -267.857944) (xy 92.599254 -267.826819) (xy 92.566619 -267.789982) (xy 92.540316 -267.748386)
			(xy 92.521025 -267.70311) (xy 92.509248 -267.655326) (xy 92.505288 -267.606272) (xy 92.176346 -267.606272)
			(xy 92.175851 -267.630879) (xy 92.167956 -267.679456) (xy 92.152372 -267.726137) (xy 92.129501 -267.769714)
			(xy 92.099936 -267.809058) (xy 92.064443 -267.84315) (xy 92.02394 -267.871106) (xy 91.979478 -267.892204)
			(xy 91.932207 -267.905896) (xy 91.883352 -267.911828) (xy 91.834177 -267.909847) (xy 91.785958 -267.900003)
			(xy 91.739942 -267.882551) (xy 91.697321 -267.857944) (xy 91.6592 -267.826819) (xy 91.626565 -267.789982)
			(xy 91.600262 -267.748386) (xy 91.580971 -267.70311) (xy 91.569194 -267.655326) (xy 91.565234 -267.606272)
			(xy 91.246706 -267.606272) (xy 91.246194 -267.631718) (xy 91.23803 -267.681952) (xy 91.221914 -267.730226)
			(xy 91.198263 -267.775289) (xy 91.16769 -267.815975) (xy 91.130986 -267.85123) (xy 91.089102 -267.88014)
			(xy 91.043123 -267.901957) (xy 90.994239 -267.916117) (xy 90.943718 -267.922251) (xy 90.892866 -267.920202)
			(xy 90.843002 -267.910022) (xy 90.795416 -267.891975) (xy 90.751342 -267.866529) (xy 90.71192 -267.834342)
			(xy 90.678172 -267.796248) (xy 90.650971 -267.753234) (xy 90.631023 -267.706414) (xy 90.618844 -267.657)
			(xy 90.614749 -267.606272) (xy 90.296238 -267.606272) (xy 90.295743 -267.630879) (xy 90.287848 -267.679456)
			(xy 90.272264 -267.726137) (xy 90.249393 -267.769714) (xy 90.219828 -267.809058) (xy 90.184335 -267.84315)
			(xy 90.143832 -267.871106) (xy 90.09937 -267.892204) (xy 90.052099 -267.905896) (xy 90.003244 -267.911828)
			(xy 89.954069 -267.909847) (xy 89.90585 -267.900003) (xy 89.859834 -267.882551) (xy 89.817213 -267.857944)
			(xy 89.779092 -267.826819) (xy 89.746457 -267.789982) (xy 89.720154 -267.748386) (xy 89.700863 -267.70311)
			(xy 89.689086 -267.655326) (xy 89.685126 -267.606272) (xy 89.356438 -267.606272) (xy 89.355943 -267.630879)
			(xy 89.348048 -267.679456) (xy 89.332464 -267.726137) (xy 89.309593 -267.769714) (xy 89.280028 -267.809058)
			(xy 89.244535 -267.84315) (xy 89.204032 -267.871106) (xy 89.15957 -267.892204) (xy 89.112299 -267.905896)
			(xy 89.063444 -267.911828) (xy 89.014269 -267.909847) (xy 88.96605 -267.900003) (xy 88.920034 -267.882551)
			(xy 88.877413 -267.857944) (xy 88.839292 -267.826819) (xy 88.806657 -267.789982) (xy 88.780354 -267.748386)
			(xy 88.761063 -267.70311) (xy 88.749286 -267.655326) (xy 88.745326 -267.606272) (xy 88.416384 -267.606272)
			(xy 88.415889 -267.630879) (xy 88.407994 -267.679456) (xy 88.39241 -267.726137) (xy 88.369539 -267.769714)
			(xy 88.339974 -267.809058) (xy 88.304481 -267.84315) (xy 88.263978 -267.871106) (xy 88.219516 -267.892204)
			(xy 88.172245 -267.905896) (xy 88.12339 -267.911828) (xy 88.074215 -267.909847) (xy 88.025996 -267.900003)
			(xy 87.97998 -267.882551) (xy 87.937359 -267.857944) (xy 87.899238 -267.826819) (xy 87.866603 -267.789982)
			(xy 87.8403 -267.748386) (xy 87.821009 -267.70311) (xy 87.809232 -267.655326) (xy 87.805272 -267.606272)
			(xy 87.47633 -267.606272) (xy 87.475886 -267.630267) (xy 87.468383 -267.677667) (xy 87.453557 -267.72331)
			(xy 87.431774 -267.766072) (xy 87.403569 -267.804899) (xy 87.369637 -267.838836) (xy 87.330814 -267.867047)
			(xy 87.288056 -267.888838) (xy 87.242416 -267.903671) (xy 87.195017 -267.911182) (xy 87.171022 -267.91158)
			(xy 87.159613 -267.911505) (xy 87.136856 -267.909851) (xy 87.125556 -267.908278) (xy 87.114634 -267.9065)
			(xy 87.09279 -267.91285) (xy 87.065358 -267.936726) (xy 87.06485 -267.937234) (xy 87.030814 -267.966444)
			(xy 87.02929 -267.967714) (xy 87.024972 -267.972032) (xy 87.017606 -267.979144) (xy 87.009986 -267.99794)
			(xy 87.009986 -268.29766) (xy 87.01278 -268.306042) (xy 87.021607 -268.332745) (xy 87.031179 -268.388161)
			(xy 87.03183 -268.416278) (xy 87.335118 -268.416278) (xy 87.339078 -268.367224) (xy 87.350855 -268.31944)
			(xy 87.370146 -268.274164) (xy 87.396449 -268.232568) (xy 87.429084 -268.195731) (xy 87.467205 -268.164606)
			(xy 87.509826 -268.139999) (xy 87.555842 -268.122547) (xy 87.604061 -268.112703) (xy 87.653236 -268.110722)
			(xy 87.702091 -268.116654) (xy 87.749362 -268.130346) (xy 87.793824 -268.151444) (xy 87.834327 -268.1794)
			(xy 87.86982 -268.213492) (xy 87.899385 -268.252836) (xy 87.922256 -268.296413) (xy 87.93784 -268.343094)
			(xy 87.945735 -268.391671) (xy 87.94623 -268.416278) (xy 88.275172 -268.416278) (xy 88.279132 -268.367224)
			(xy 88.290909 -268.31944) (xy 88.3102 -268.274164) (xy 88.336503 -268.232568) (xy 88.369138 -268.195731)
			(xy 88.407259 -268.164606) (xy 88.44988 -268.139999) (xy 88.495896 -268.122547) (xy 88.544115 -268.112703)
			(xy 88.59329 -268.110722) (xy 88.642145 -268.116654) (xy 88.689416 -268.130346) (xy 88.733878 -268.151444)
			(xy 88.774381 -268.1794) (xy 88.809874 -268.213492) (xy 88.839439 -268.252836) (xy 88.86231 -268.296413)
			(xy 88.877894 -268.343094) (xy 88.885789 -268.391671) (xy 88.886284 -268.416278) (xy 89.215226 -268.416278)
			(xy 89.219186 -268.367224) (xy 89.230963 -268.31944) (xy 89.250254 -268.274164) (xy 89.276557 -268.232568)
			(xy 89.309192 -268.195731) (xy 89.347313 -268.164606) (xy 89.389934 -268.139999) (xy 89.43595 -268.122547)
			(xy 89.484169 -268.112703) (xy 89.533344 -268.110722) (xy 89.582199 -268.116654) (xy 89.62947 -268.130346)
			(xy 89.673932 -268.151444) (xy 89.714435 -268.1794) (xy 89.749928 -268.213492) (xy 89.779493 -268.252836)
			(xy 89.802364 -268.296413) (xy 89.817948 -268.343094) (xy 89.825843 -268.391671) (xy 89.826338 -268.416278)
			(xy 90.15528 -268.416278) (xy 90.15924 -268.367224) (xy 90.171017 -268.31944) (xy 90.190308 -268.274164)
			(xy 90.216611 -268.232568) (xy 90.249246 -268.195731) (xy 90.287367 -268.164606) (xy 90.329988 -268.139999)
			(xy 90.376004 -268.122547) (xy 90.424223 -268.112703) (xy 90.473398 -268.110722) (xy 90.522253 -268.116654)
			(xy 90.569524 -268.130346) (xy 90.613986 -268.151444) (xy 90.654489 -268.1794) (xy 90.689982 -268.213492)
			(xy 90.719547 -268.252836) (xy 90.742418 -268.296413) (xy 90.758002 -268.343094) (xy 90.765897 -268.391671)
			(xy 90.766392 -268.416278) (xy 91.095334 -268.416278) (xy 91.099294 -268.367224) (xy 91.111071 -268.31944)
			(xy 91.130362 -268.274164) (xy 91.156665 -268.232568) (xy 91.1893 -268.195731) (xy 91.227421 -268.164606)
			(xy 91.270042 -268.139999) (xy 91.316058 -268.122547) (xy 91.364277 -268.112703) (xy 91.413452 -268.110722)
			(xy 91.462307 -268.116654) (xy 91.509578 -268.130346) (xy 91.55404 -268.151444) (xy 91.594543 -268.1794)
			(xy 91.630036 -268.213492) (xy 91.659601 -268.252836) (xy 91.682472 -268.296413) (xy 91.698056 -268.343094)
			(xy 91.705951 -268.391671) (xy 91.706446 -268.416278) (xy 92.035134 -268.416278) (xy 92.039094 -268.367224)
			(xy 92.050871 -268.31944) (xy 92.070162 -268.274164) (xy 92.096465 -268.232568) (xy 92.1291 -268.195731)
			(xy 92.167221 -268.164606) (xy 92.209842 -268.139999) (xy 92.255858 -268.122547) (xy 92.304077 -268.112703)
			(xy 92.353252 -268.110722) (xy 92.402107 -268.116654) (xy 92.449378 -268.130346) (xy 92.49384 -268.151444)
			(xy 92.534343 -268.1794) (xy 92.569836 -268.213492) (xy 92.599401 -268.252836) (xy 92.622272 -268.296413)
			(xy 92.637856 -268.343094) (xy 92.645751 -268.391671) (xy 92.646246 -268.416278) (xy 93.915242 -268.416278)
			(xy 93.919202 -268.367224) (xy 93.930979 -268.31944) (xy 93.95027 -268.274164) (xy 93.976573 -268.232568)
			(xy 94.009208 -268.195731) (xy 94.047329 -268.164606) (xy 94.08995 -268.139999) (xy 94.135966 -268.122547)
			(xy 94.184185 -268.112703) (xy 94.23336 -268.110722) (xy 94.282215 -268.116654) (xy 94.329486 -268.130346)
			(xy 94.373948 -268.151444) (xy 94.414451 -268.1794) (xy 94.449944 -268.213492) (xy 94.479509 -268.252836)
			(xy 94.50238 -268.296413) (xy 94.517964 -268.343094) (xy 94.525859 -268.391671) (xy 94.526354 -268.416278)
			(xy 94.855296 -268.416278) (xy 94.859256 -268.367224) (xy 94.871033 -268.31944) (xy 94.890324 -268.274164)
			(xy 94.916627 -268.232568) (xy 94.949262 -268.195731) (xy 94.987383 -268.164606) (xy 95.030004 -268.139999)
			(xy 95.07602 -268.122547) (xy 95.124239 -268.112703) (xy 95.173414 -268.110722) (xy 95.222269 -268.116654)
			(xy 95.26954 -268.130346) (xy 95.314002 -268.151444) (xy 95.354505 -268.1794) (xy 95.389998 -268.213492)
			(xy 95.419563 -268.252836) (xy 95.442434 -268.296413) (xy 95.458018 -268.343094) (xy 95.465913 -268.391671)
			(xy 95.466408 -268.416278) (xy 95.79535 -268.416278) (xy 95.79931 -268.367224) (xy 95.811087 -268.31944)
			(xy 95.830378 -268.274164) (xy 95.856681 -268.232568) (xy 95.889316 -268.195731) (xy 95.927437 -268.164606)
			(xy 95.970058 -268.139999) (xy 96.016074 -268.122547) (xy 96.064293 -268.112703) (xy 96.113468 -268.110722)
			(xy 96.162323 -268.116654) (xy 96.209594 -268.130346) (xy 96.254056 -268.151444) (xy 96.294559 -268.1794)
			(xy 96.330052 -268.213492) (xy 96.359617 -268.252836) (xy 96.382488 -268.296413) (xy 96.398072 -268.343094)
			(xy 96.405967 -268.391671) (xy 96.406462 -268.416278) (xy 96.405967 -268.440885) (xy 96.398072 -268.489462)
			(xy 96.382488 -268.536143) (xy 96.359617 -268.57972) (xy 96.330052 -268.619064) (xy 96.294559 -268.653156)
			(xy 96.254056 -268.681112) (xy 96.209594 -268.70221) (xy 96.162323 -268.715902) (xy 96.113468 -268.721834)
			(xy 96.064293 -268.719853) (xy 96.016074 -268.710009) (xy 95.970058 -268.692557) (xy 95.927437 -268.66795)
			(xy 95.889316 -268.636825) (xy 95.856681 -268.599988) (xy 95.830378 -268.558392) (xy 95.811087 -268.513116)
			(xy 95.79931 -268.465332) (xy 95.79535 -268.416278) (xy 95.466408 -268.416278) (xy 95.465913 -268.440885)
			(xy 95.458018 -268.489462) (xy 95.442434 -268.536143) (xy 95.419563 -268.57972) (xy 95.389998 -268.619064)
			(xy 95.354505 -268.653156) (xy 95.314002 -268.681112) (xy 95.26954 -268.70221) (xy 95.222269 -268.715902)
			(xy 95.173414 -268.721834) (xy 95.124239 -268.719853) (xy 95.07602 -268.710009) (xy 95.030004 -268.692557)
			(xy 94.987383 -268.66795) (xy 94.949262 -268.636825) (xy 94.916627 -268.599988) (xy 94.890324 -268.558392)
			(xy 94.871033 -268.513116) (xy 94.859256 -268.465332) (xy 94.855296 -268.416278) (xy 94.526354 -268.416278)
			(xy 94.525859 -268.440885) (xy 94.517964 -268.489462) (xy 94.50238 -268.536143) (xy 94.479509 -268.57972)
			(xy 94.449944 -268.619064) (xy 94.414451 -268.653156) (xy 94.373948 -268.681112) (xy 94.329486 -268.70221)
			(xy 94.282215 -268.715902) (xy 94.23336 -268.721834) (xy 94.184185 -268.719853) (xy 94.135966 -268.710009)
			(xy 94.08995 -268.692557) (xy 94.047329 -268.66795) (xy 94.009208 -268.636825) (xy 93.976573 -268.599988)
			(xy 93.95027 -268.558392) (xy 93.930979 -268.513116) (xy 93.919202 -268.465332) (xy 93.915242 -268.416278)
			(xy 92.646246 -268.416278) (xy 92.645751 -268.440885) (xy 92.637856 -268.489462) (xy 92.622272 -268.536143)
			(xy 92.599401 -268.57972) (xy 92.569836 -268.619064) (xy 92.534343 -268.653156) (xy 92.49384 -268.681112)
			(xy 92.449378 -268.70221) (xy 92.402107 -268.715902) (xy 92.353252 -268.721834) (xy 92.304077 -268.719853)
			(xy 92.255858 -268.710009) (xy 92.209842 -268.692557) (xy 92.167221 -268.66795) (xy 92.1291 -268.636825)
			(xy 92.096465 -268.599988) (xy 92.070162 -268.558392) (xy 92.050871 -268.513116) (xy 92.039094 -268.465332)
			(xy 92.035134 -268.416278) (xy 91.706446 -268.416278) (xy 91.705951 -268.440885) (xy 91.698056 -268.489462)
			(xy 91.682472 -268.536143) (xy 91.659601 -268.57972) (xy 91.630036 -268.619064) (xy 91.594543 -268.653156)
			(xy 91.55404 -268.681112) (xy 91.509578 -268.70221) (xy 91.462307 -268.715902) (xy 91.413452 -268.721834)
			(xy 91.364277 -268.719853) (xy 91.316058 -268.710009) (xy 91.270042 -268.692557) (xy 91.227421 -268.66795)
			(xy 91.1893 -268.636825) (xy 91.156665 -268.599988) (xy 91.130362 -268.558392) (xy 91.111071 -268.513116)
			(xy 91.099294 -268.465332) (xy 91.095334 -268.416278) (xy 90.766392 -268.416278) (xy 90.765897 -268.440885)
			(xy 90.758002 -268.489462) (xy 90.742418 -268.536143) (xy 90.719547 -268.57972) (xy 90.689982 -268.619064)
			(xy 90.654489 -268.653156) (xy 90.613986 -268.681112) (xy 90.569524 -268.70221) (xy 90.522253 -268.715902)
			(xy 90.473398 -268.721834) (xy 90.424223 -268.719853) (xy 90.376004 -268.710009) (xy 90.329988 -268.692557)
			(xy 90.287367 -268.66795) (xy 90.249246 -268.636825) (xy 90.216611 -268.599988) (xy 90.190308 -268.558392)
			(xy 90.171017 -268.513116) (xy 90.15924 -268.465332) (xy 90.15528 -268.416278) (xy 89.826338 -268.416278)
			(xy 89.825843 -268.440885) (xy 89.817948 -268.489462) (xy 89.802364 -268.536143) (xy 89.779493 -268.57972)
			(xy 89.749928 -268.619064) (xy 89.714435 -268.653156) (xy 89.673932 -268.681112) (xy 89.62947 -268.70221)
			(xy 89.582199 -268.715902) (xy 89.533344 -268.721834) (xy 89.484169 -268.719853) (xy 89.43595 -268.710009)
			(xy 89.389934 -268.692557) (xy 89.347313 -268.66795) (xy 89.309192 -268.636825) (xy 89.276557 -268.599988)
			(xy 89.250254 -268.558392) (xy 89.230963 -268.513116) (xy 89.219186 -268.465332) (xy 89.215226 -268.416278)
			(xy 88.886284 -268.416278) (xy 88.885789 -268.440885) (xy 88.877894 -268.489462) (xy 88.86231 -268.536143)
			(xy 88.839439 -268.57972) (xy 88.809874 -268.619064) (xy 88.774381 -268.653156) (xy 88.733878 -268.681112)
			(xy 88.689416 -268.70221) (xy 88.642145 -268.715902) (xy 88.59329 -268.721834) (xy 88.544115 -268.719853)
			(xy 88.495896 -268.710009) (xy 88.44988 -268.692557) (xy 88.407259 -268.66795) (xy 88.369138 -268.636825)
			(xy 88.336503 -268.599988) (xy 88.3102 -268.558392) (xy 88.290909 -268.513116) (xy 88.279132 -268.465332)
			(xy 88.275172 -268.416278) (xy 87.94623 -268.416278) (xy 87.945735 -268.440885) (xy 87.93784 -268.489462)
			(xy 87.922256 -268.536143) (xy 87.899385 -268.57972) (xy 87.86982 -268.619064) (xy 87.834327 -268.653156)
			(xy 87.793824 -268.681112) (xy 87.749362 -268.70221) (xy 87.702091 -268.715902) (xy 87.653236 -268.721834)
			(xy 87.604061 -268.719853) (xy 87.555842 -268.710009) (xy 87.509826 -268.692557) (xy 87.467205 -268.66795)
			(xy 87.429084 -268.636825) (xy 87.396449 -268.599988) (xy 87.370146 -268.558392) (xy 87.350855 -268.513116)
			(xy 87.339078 -268.465332) (xy 87.335118 -268.416278) (xy 87.03183 -268.416278) (xy 87.03125 -268.444402)
			(xy 87.021678 -268.499829) (xy 87.01278 -268.526514) (xy 87.009986 -268.534896) (xy 87.009986 -268.824964)
			(xy 87.010359 -268.834069) (xy 87.016738 -268.851124) (xy 87.022432 -268.858238) (xy 87.024972 -268.861032)
			(xy 87.065104 -268.895576) (xy 87.080344 -268.908784) (xy 87.081614 -268.9098) (xy 87.088578 -268.915)
			(xy 87.104936 -268.92084) (xy 87.113618 -268.92123) (xy 87.159592 -268.92123) (xy 87.171022 -268.920976)
			(xy 87.171276 -268.920976) (xy 87.195253 -268.921467) (xy 87.242613 -268.929007) (xy 87.288211 -268.943859)
			(xy 87.330926 -268.965657) (xy 87.369709 -268.993865) (xy 87.403604 -269.027789) (xy 87.431779 -269.066596)
			(xy 87.453541 -269.10933) (xy 87.468353 -269.15494) (xy 87.475853 -269.202306) (xy 87.47633 -269.226284)
			(xy 87.805272 -269.226284) (xy 87.809232 -269.17723) (xy 87.821009 -269.129446) (xy 87.8403 -269.08417)
			(xy 87.866603 -269.042574) (xy 87.899238 -269.005737) (xy 87.937359 -268.974612) (xy 87.97998 -268.950005)
			(xy 88.025996 -268.932553) (xy 88.074215 -268.922709) (xy 88.12339 -268.920728) (xy 88.172245 -268.92666)
			(xy 88.219516 -268.940352) (xy 88.263978 -268.96145) (xy 88.304481 -268.989406) (xy 88.339974 -269.023498)
			(xy 88.369539 -269.062842) (xy 88.39241 -269.106419) (xy 88.407994 -269.1531) (xy 88.415889 -269.201677)
			(xy 88.416384 -269.226284) (xy 88.745326 -269.226284) (xy 88.749286 -269.17723) (xy 88.761063 -269.129446)
			(xy 88.780354 -269.08417) (xy 88.806657 -269.042574) (xy 88.839292 -269.005737) (xy 88.877413 -268.974612)
			(xy 88.920034 -268.950005) (xy 88.96605 -268.932553) (xy 89.014269 -268.922709) (xy 89.063444 -268.920728)
			(xy 89.112299 -268.92666) (xy 89.15957 -268.940352) (xy 89.204032 -268.96145) (xy 89.244535 -268.989406)
			(xy 89.280028 -269.023498) (xy 89.309593 -269.062842) (xy 89.332464 -269.106419) (xy 89.348048 -269.1531)
			(xy 89.355943 -269.201677) (xy 89.356438 -269.226284) (xy 89.685126 -269.226284) (xy 89.689086 -269.17723)
			(xy 89.700863 -269.129446) (xy 89.720154 -269.08417) (xy 89.746457 -269.042574) (xy 89.779092 -269.005737)
			(xy 89.817213 -268.974612) (xy 89.859834 -268.950005) (xy 89.90585 -268.932553) (xy 89.954069 -268.922709)
			(xy 90.003244 -268.920728) (xy 90.052099 -268.92666) (xy 90.09937 -268.940352) (xy 90.143832 -268.96145)
			(xy 90.184335 -268.989406) (xy 90.219828 -269.023498) (xy 90.249393 -269.062842) (xy 90.272264 -269.106419)
			(xy 90.287848 -269.1531) (xy 90.295743 -269.201677) (xy 90.296238 -269.226284) (xy 90.614749 -269.226284)
			(xy 90.618844 -269.175556) (xy 90.631023 -269.126142) (xy 90.650971 -269.079322) (xy 90.678172 -269.036308)
			(xy 90.71192 -268.998214) (xy 90.751342 -268.966027) (xy 90.795416 -268.940581) (xy 90.843002 -268.922534)
			(xy 90.892866 -268.912354) (xy 90.943718 -268.910305) (xy 90.994239 -268.916439) (xy 91.043123 -268.930599)
			(xy 91.089102 -268.952416) (xy 91.130986 -268.981326) (xy 91.16769 -269.016581) (xy 91.198263 -269.057267)
			(xy 91.221914 -269.10233) (xy 91.23803 -269.150604) (xy 91.246194 -269.200838) (xy 91.246706 -269.226284)
			(xy 91.565234 -269.226284) (xy 91.569194 -269.17723) (xy 91.580971 -269.129446) (xy 91.600262 -269.08417)
			(xy 91.626565 -269.042574) (xy 91.6592 -269.005737) (xy 91.697321 -268.974612) (xy 91.739942 -268.950005)
			(xy 91.785958 -268.932553) (xy 91.834177 -268.922709) (xy 91.883352 -268.920728) (xy 91.932207 -268.92666)
			(xy 91.979478 -268.940352) (xy 92.02394 -268.96145) (xy 92.064443 -268.989406) (xy 92.099936 -269.023498)
			(xy 92.129501 -269.062842) (xy 92.152372 -269.106419) (xy 92.167956 -269.1531) (xy 92.175851 -269.201677)
			(xy 92.176346 -269.226284) (xy 92.505288 -269.226284) (xy 92.509248 -269.17723) (xy 92.521025 -269.129446)
			(xy 92.540316 -269.08417) (xy 92.566619 -269.042574) (xy 92.599254 -269.005737) (xy 92.637375 -268.974612)
			(xy 92.679996 -268.950005) (xy 92.726012 -268.932553) (xy 92.774231 -268.922709) (xy 92.823406 -268.920728)
			(xy 92.872261 -268.92666) (xy 92.919532 -268.940352) (xy 92.963994 -268.96145) (xy 93.004497 -268.989406)
			(xy 93.03999 -269.023498) (xy 93.069555 -269.062842) (xy 93.092426 -269.106419) (xy 93.10801 -269.1531)
			(xy 93.115905 -269.201677) (xy 93.1164 -269.226284) (xy 93.445342 -269.226284) (xy 93.449302 -269.17723)
			(xy 93.461079 -269.129446) (xy 93.48037 -269.08417) (xy 93.506673 -269.042574) (xy 93.539308 -269.005737)
			(xy 93.577429 -268.974612) (xy 93.62005 -268.950005) (xy 93.666066 -268.932553) (xy 93.714285 -268.922709)
			(xy 93.76346 -268.920728) (xy 93.812315 -268.92666) (xy 93.859586 -268.940352) (xy 93.904048 -268.96145)
			(xy 93.944551 -268.989406) (xy 93.980044 -269.023498) (xy 94.009609 -269.062842) (xy 94.03248 -269.106419)
			(xy 94.048064 -269.1531) (xy 94.055959 -269.201677) (xy 94.056454 -269.226284) (xy 94.374711 -269.226284)
			(xy 94.378806 -269.175556) (xy 94.390985 -269.126142) (xy 94.410933 -269.079322) (xy 94.438134 -269.036308)
			(xy 94.471882 -268.998214) (xy 94.511304 -268.966027) (xy 94.555378 -268.940581) (xy 94.602964 -268.922534)
			(xy 94.652828 -268.912354) (xy 94.70368 -268.910305) (xy 94.754201 -268.916439) (xy 94.803085 -268.930599)
			(xy 94.849064 -268.952416) (xy 94.890948 -268.981326) (xy 94.927652 -269.016581) (xy 94.958225 -269.057267)
			(xy 94.981876 -269.10233) (xy 94.997992 -269.150604) (xy 95.006156 -269.200838) (xy 95.006668 -269.226284)
			(xy 95.325196 -269.226284) (xy 95.329156 -269.17723) (xy 95.340933 -269.129446) (xy 95.360224 -269.08417)
			(xy 95.386527 -269.042574) (xy 95.419162 -269.005737) (xy 95.457283 -268.974612) (xy 95.499904 -268.950005)
			(xy 95.54592 -268.932553) (xy 95.594139 -268.922709) (xy 95.643314 -268.920728) (xy 95.692169 -268.92666)
			(xy 95.73944 -268.940352) (xy 95.783902 -268.96145) (xy 95.824405 -268.989406) (xy 95.859898 -269.023498)
			(xy 95.889463 -269.062842) (xy 95.912334 -269.106419) (xy 95.927918 -269.1531) (xy 95.935813 -269.201677)
			(xy 95.936308 -269.226284) (xy 95.935813 -269.250891) (xy 95.927918 -269.299468) (xy 95.912334 -269.346149)
			(xy 95.889463 -269.389726) (xy 95.859898 -269.42907) (xy 95.824405 -269.463162) (xy 95.783902 -269.491118)
			(xy 95.73944 -269.512216) (xy 95.692169 -269.525908) (xy 95.643314 -269.53184) (xy 95.594139 -269.529859)
			(xy 95.54592 -269.520015) (xy 95.499904 -269.502563) (xy 95.457283 -269.477956) (xy 95.419162 -269.446831)
			(xy 95.386527 -269.409994) (xy 95.360224 -269.368398) (xy 95.340933 -269.323122) (xy 95.329156 -269.275338)
			(xy 95.325196 -269.226284) (xy 95.006668 -269.226284) (xy 95.006156 -269.25173) (xy 94.997992 -269.301964)
			(xy 94.981876 -269.350238) (xy 94.958225 -269.395301) (xy 94.927652 -269.435987) (xy 94.890948 -269.471242)
			(xy 94.849064 -269.500152) (xy 94.803085 -269.521969) (xy 94.754201 -269.536129) (xy 94.70368 -269.542263)
			(xy 94.652828 -269.540214) (xy 94.602964 -269.530034) (xy 94.555378 -269.511987) (xy 94.511304 -269.486541)
			(xy 94.471882 -269.454354) (xy 94.438134 -269.41626) (xy 94.410933 -269.373246) (xy 94.390985 -269.326426)
			(xy 94.378806 -269.277012) (xy 94.374711 -269.226284) (xy 94.056454 -269.226284) (xy 94.055959 -269.250891)
			(xy 94.048064 -269.299468) (xy 94.03248 -269.346149) (xy 94.009609 -269.389726) (xy 93.980044 -269.42907)
			(xy 93.944551 -269.463162) (xy 93.904048 -269.491118) (xy 93.859586 -269.512216) (xy 93.812315 -269.525908)
			(xy 93.76346 -269.53184) (xy 93.714285 -269.529859) (xy 93.666066 -269.520015) (xy 93.62005 -269.502563)
			(xy 93.577429 -269.477956) (xy 93.539308 -269.446831) (xy 93.506673 -269.409994) (xy 93.48037 -269.368398)
			(xy 93.461079 -269.323122) (xy 93.449302 -269.275338) (xy 93.445342 -269.226284) (xy 93.1164 -269.226284)
			(xy 93.115905 -269.250891) (xy 93.10801 -269.299468) (xy 93.092426 -269.346149) (xy 93.069555 -269.389726)
			(xy 93.03999 -269.42907) (xy 93.004497 -269.463162) (xy 92.963994 -269.491118) (xy 92.919532 -269.512216)
			(xy 92.872261 -269.525908) (xy 92.823406 -269.53184) (xy 92.774231 -269.529859) (xy 92.726012 -269.520015)
			(xy 92.679996 -269.502563) (xy 92.637375 -269.477956) (xy 92.599254 -269.446831) (xy 92.566619 -269.409994)
			(xy 92.540316 -269.368398) (xy 92.521025 -269.323122) (xy 92.509248 -269.275338) (xy 92.505288 -269.226284)
			(xy 92.176346 -269.226284) (xy 92.175851 -269.250891) (xy 92.167956 -269.299468) (xy 92.152372 -269.346149)
			(xy 92.129501 -269.389726) (xy 92.099936 -269.42907) (xy 92.064443 -269.463162) (xy 92.02394 -269.491118)
			(xy 91.979478 -269.512216) (xy 91.932207 -269.525908) (xy 91.883352 -269.53184) (xy 91.834177 -269.529859)
			(xy 91.785958 -269.520015) (xy 91.739942 -269.502563) (xy 91.697321 -269.477956) (xy 91.6592 -269.446831)
			(xy 91.626565 -269.409994) (xy 91.600262 -269.368398) (xy 91.580971 -269.323122) (xy 91.569194 -269.275338)
			(xy 91.565234 -269.226284) (xy 91.246706 -269.226284) (xy 91.246194 -269.25173) (xy 91.23803 -269.301964)
			(xy 91.221914 -269.350238) (xy 91.198263 -269.395301) (xy 91.16769 -269.435987) (xy 91.130986 -269.471242)
			(xy 91.089102 -269.500152) (xy 91.043123 -269.521969) (xy 90.994239 -269.536129) (xy 90.943718 -269.542263)
			(xy 90.892866 -269.540214) (xy 90.843002 -269.530034) (xy 90.795416 -269.511987) (xy 90.751342 -269.486541)
			(xy 90.71192 -269.454354) (xy 90.678172 -269.41626) (xy 90.650971 -269.373246) (xy 90.631023 -269.326426)
			(xy 90.618844 -269.277012) (xy 90.614749 -269.226284) (xy 90.296238 -269.226284) (xy 90.295743 -269.250891)
			(xy 90.287848 -269.299468) (xy 90.272264 -269.346149) (xy 90.249393 -269.389726) (xy 90.219828 -269.42907)
			(xy 90.184335 -269.463162) (xy 90.143832 -269.491118) (xy 90.09937 -269.512216) (xy 90.052099 -269.525908)
			(xy 90.003244 -269.53184) (xy 89.954069 -269.529859) (xy 89.90585 -269.520015) (xy 89.859834 -269.502563)
			(xy 89.817213 -269.477956) (xy 89.779092 -269.446831) (xy 89.746457 -269.409994) (xy 89.720154 -269.368398)
			(xy 89.700863 -269.323122) (xy 89.689086 -269.275338) (xy 89.685126 -269.226284) (xy 89.356438 -269.226284)
			(xy 89.355943 -269.250891) (xy 89.348048 -269.299468) (xy 89.332464 -269.346149) (xy 89.309593 -269.389726)
			(xy 89.280028 -269.42907) (xy 89.244535 -269.463162) (xy 89.204032 -269.491118) (xy 89.15957 -269.512216)
			(xy 89.112299 -269.525908) (xy 89.063444 -269.53184) (xy 89.014269 -269.529859) (xy 88.96605 -269.520015)
			(xy 88.920034 -269.502563) (xy 88.877413 -269.477956) (xy 88.839292 -269.446831) (xy 88.806657 -269.409994)
			(xy 88.780354 -269.368398) (xy 88.761063 -269.323122) (xy 88.749286 -269.275338) (xy 88.745326 -269.226284)
			(xy 88.416384 -269.226284) (xy 88.415889 -269.250891) (xy 88.407994 -269.299468) (xy 88.39241 -269.346149)
			(xy 88.369539 -269.389726) (xy 88.339974 -269.42907) (xy 88.304481 -269.463162) (xy 88.263978 -269.491118)
			(xy 88.219516 -269.512216) (xy 88.172245 -269.525908) (xy 88.12339 -269.53184) (xy 88.074215 -269.529859)
			(xy 88.025996 -269.520015) (xy 87.97998 -269.502563) (xy 87.937359 -269.477956) (xy 87.899238 -269.446831)
			(xy 87.866603 -269.409994) (xy 87.8403 -269.368398) (xy 87.821009 -269.323122) (xy 87.809232 -269.275338)
			(xy 87.805272 -269.226284) (xy 87.47633 -269.226284) (xy 87.475861 -269.250277) (xy 87.468357 -269.297672)
			(xy 87.453531 -269.343309) (xy 87.431749 -269.386066) (xy 87.403546 -269.424888) (xy 87.369617 -269.458821)
			(xy 87.330798 -269.487029) (xy 87.288044 -269.508816) (xy 87.242409 -269.523648) (xy 87.195015 -269.531158)
			(xy 87.171022 -269.531592) (xy 87.159613 -269.531517) (xy 87.136856 -269.529863) (xy 87.125556 -269.52829)
			(xy 87.114634 -269.526512) (xy 87.09279 -269.532862) (xy 87.065358 -269.556738) (xy 87.06485 -269.557246)
			(xy 87.030814 -269.586456) (xy 87.02929 -269.587726) (xy 87.024972 -269.592044) (xy 87.017606 -269.599156)
			(xy 87.009986 -269.617952) (xy 87.009986 -270.03629) (xy 87.335118 -270.03629) (xy 87.339078 -269.987236)
			(xy 87.350855 -269.939452) (xy 87.370146 -269.894176) (xy 87.396449 -269.85258) (xy 87.429084 -269.815743)
			(xy 87.467205 -269.784618) (xy 87.509826 -269.760011) (xy 87.555842 -269.742559) (xy 87.604061 -269.732715)
			(xy 87.653236 -269.730734) (xy 87.702091 -269.736666) (xy 87.749362 -269.750358) (xy 87.793824 -269.771456)
			(xy 87.834327 -269.799412) (xy 87.86982 -269.833504) (xy 87.899385 -269.872848) (xy 87.922256 -269.916425)
			(xy 87.93784 -269.963106) (xy 87.945735 -270.011683) (xy 87.94623 -270.03629) (xy 88.275172 -270.03629)
			(xy 88.279132 -269.987236) (xy 88.290909 -269.939452) (xy 88.3102 -269.894176) (xy 88.336503 -269.85258)
			(xy 88.369138 -269.815743) (xy 88.407259 -269.784618) (xy 88.44988 -269.760011) (xy 88.495896 -269.742559)
			(xy 88.544115 -269.732715) (xy 88.59329 -269.730734) (xy 88.642145 -269.736666) (xy 88.689416 -269.750358)
			(xy 88.733878 -269.771456) (xy 88.774381 -269.799412) (xy 88.809874 -269.833504) (xy 88.839439 -269.872848)
			(xy 88.86231 -269.916425) (xy 88.877894 -269.963106) (xy 88.885789 -270.011683) (xy 88.886284 -270.03629)
			(xy 89.215226 -270.03629) (xy 89.219186 -269.987236) (xy 89.230963 -269.939452) (xy 89.250254 -269.894176)
			(xy 89.276557 -269.85258) (xy 89.309192 -269.815743) (xy 89.347313 -269.784618) (xy 89.389934 -269.760011)
			(xy 89.43595 -269.742559) (xy 89.484169 -269.732715) (xy 89.533344 -269.730734) (xy 89.582199 -269.736666)
			(xy 89.62947 -269.750358) (xy 89.673932 -269.771456) (xy 89.714435 -269.799412) (xy 89.749928 -269.833504)
			(xy 89.779493 -269.872848) (xy 89.802364 -269.916425) (xy 89.817948 -269.963106) (xy 89.825843 -270.011683)
			(xy 89.826338 -270.03629) (xy 90.15528 -270.03629) (xy 90.15924 -269.987236) (xy 90.171017 -269.939452)
			(xy 90.190308 -269.894176) (xy 90.216611 -269.85258) (xy 90.249246 -269.815743) (xy 90.287367 -269.784618)
			(xy 90.329988 -269.760011) (xy 90.376004 -269.742559) (xy 90.424223 -269.732715) (xy 90.473398 -269.730734)
			(xy 90.522253 -269.736666) (xy 90.569524 -269.750358) (xy 90.613986 -269.771456) (xy 90.654489 -269.799412)
			(xy 90.689982 -269.833504) (xy 90.719547 -269.872848) (xy 90.742418 -269.916425) (xy 90.758002 -269.963106)
			(xy 90.765897 -270.011683) (xy 90.766392 -270.03629) (xy 91.084903 -270.03629) (xy 91.088998 -269.985562)
			(xy 91.101177 -269.936148) (xy 91.121125 -269.889328) (xy 91.148326 -269.846314) (xy 91.182074 -269.80822)
			(xy 91.221496 -269.776033) (xy 91.26557 -269.750587) (xy 91.313156 -269.73254) (xy 91.36302 -269.72236)
			(xy 91.413872 -269.720311) (xy 91.464393 -269.726445) (xy 91.513277 -269.740605) (xy 91.559256 -269.762422)
			(xy 91.60114 -269.791332) (xy 91.637844 -269.826587) (xy 91.668417 -269.867273) (xy 91.692068 -269.912336)
			(xy 91.708184 -269.96061) (xy 91.716348 -270.010844) (xy 91.71686 -270.03629) (xy 92.024703 -270.03629)
			(xy 92.028798 -269.985562) (xy 92.040977 -269.936148) (xy 92.060925 -269.889328) (xy 92.088126 -269.846314)
			(xy 92.121874 -269.80822) (xy 92.161296 -269.776033) (xy 92.20537 -269.750587) (xy 92.252956 -269.73254)
			(xy 92.30282 -269.72236) (xy 92.353672 -269.720311) (xy 92.404193 -269.726445) (xy 92.453077 -269.740605)
			(xy 92.499056 -269.762422) (xy 92.54094 -269.791332) (xy 92.577644 -269.826587) (xy 92.608217 -269.867273)
			(xy 92.631868 -269.912336) (xy 92.647984 -269.96061) (xy 92.656148 -270.010844) (xy 92.65666 -270.03629)
			(xy 92.975188 -270.03629) (xy 92.979148 -269.987236) (xy 92.990925 -269.939452) (xy 93.010216 -269.894176)
			(xy 93.036519 -269.85258) (xy 93.069154 -269.815743) (xy 93.107275 -269.784618) (xy 93.149896 -269.760011)
			(xy 93.195912 -269.742559) (xy 93.244131 -269.732715) (xy 93.293306 -269.730734) (xy 93.342161 -269.736666)
			(xy 93.389432 -269.750358) (xy 93.433894 -269.771456) (xy 93.474397 -269.799412) (xy 93.50989 -269.833504)
			(xy 93.539455 -269.872848) (xy 93.562326 -269.916425) (xy 93.57791 -269.963106) (xy 93.585805 -270.011683)
			(xy 93.5863 -270.03629) (xy 93.904811 -270.03629) (xy 93.908906 -269.985562) (xy 93.921085 -269.936148)
			(xy 93.941033 -269.889328) (xy 93.968234 -269.846314) (xy 94.001982 -269.80822) (xy 94.041404 -269.776033)
			(xy 94.085478 -269.750587) (xy 94.133064 -269.73254) (xy 94.182928 -269.72236) (xy 94.23378 -269.720311)
			(xy 94.284301 -269.726445) (xy 94.333185 -269.740605) (xy 94.379164 -269.762422) (xy 94.421048 -269.791332)
			(xy 94.457752 -269.826587) (xy 94.488325 -269.867273) (xy 94.511976 -269.912336) (xy 94.528092 -269.96061)
			(xy 94.536256 -270.010844) (xy 94.536768 -270.03629) (xy 94.855296 -270.03629) (xy 94.859256 -269.987236)
			(xy 94.871033 -269.939452) (xy 94.890324 -269.894176) (xy 94.916627 -269.85258) (xy 94.949262 -269.815743)
			(xy 94.987383 -269.784618) (xy 95.030004 -269.760011) (xy 95.07602 -269.742559) (xy 95.124239 -269.732715)
			(xy 95.173414 -269.730734) (xy 95.222269 -269.736666) (xy 95.26954 -269.750358) (xy 95.314002 -269.771456)
			(xy 95.354505 -269.799412) (xy 95.389998 -269.833504) (xy 95.419563 -269.872848) (xy 95.442434 -269.916425)
			(xy 95.458018 -269.963106) (xy 95.465913 -270.011683) (xy 95.466408 -270.03629) (xy 95.784919 -270.03629)
			(xy 95.789014 -269.985562) (xy 95.801193 -269.936148) (xy 95.821141 -269.889328) (xy 95.848342 -269.846314)
			(xy 95.88209 -269.80822) (xy 95.921512 -269.776033) (xy 95.965586 -269.750587) (xy 96.013172 -269.73254)
			(xy 96.063036 -269.72236) (xy 96.113888 -269.720311) (xy 96.164409 -269.726445) (xy 96.213293 -269.740605)
			(xy 96.259272 -269.762422) (xy 96.301156 -269.791332) (xy 96.33786 -269.826587) (xy 96.368433 -269.867273)
			(xy 96.392084 -269.912336) (xy 96.4082 -269.96061) (xy 96.416364 -270.010844) (xy 96.416876 -270.03629)
			(xy 96.416364 -270.061736) (xy 96.4082 -270.11197) (xy 96.392084 -270.160244) (xy 96.368433 -270.205307)
			(xy 96.33786 -270.245993) (xy 96.301156 -270.281248) (xy 96.259272 -270.310158) (xy 96.213293 -270.331975)
			(xy 96.164409 -270.346135) (xy 96.113888 -270.352269) (xy 96.063036 -270.35022) (xy 96.013172 -270.34004)
			(xy 95.965586 -270.321993) (xy 95.921512 -270.296547) (xy 95.88209 -270.26436) (xy 95.848342 -270.226266)
			(xy 95.821141 -270.183252) (xy 95.801193 -270.136432) (xy 95.789014 -270.087018) (xy 95.784919 -270.03629)
			(xy 95.466408 -270.03629) (xy 95.465913 -270.060897) (xy 95.458018 -270.109474) (xy 95.442434 -270.156155)
			(xy 95.419563 -270.199732) (xy 95.389998 -270.239076) (xy 95.354505 -270.273168) (xy 95.314002 -270.301124)
			(xy 95.26954 -270.322222) (xy 95.222269 -270.335914) (xy 95.173414 -270.341846) (xy 95.124239 -270.339865)
			(xy 95.07602 -270.330021) (xy 95.030004 -270.312569) (xy 94.987383 -270.287962) (xy 94.949262 -270.256837)
			(xy 94.916627 -270.22) (xy 94.890324 -270.178404) (xy 94.871033 -270.133128) (xy 94.859256 -270.085344)
			(xy 94.855296 -270.03629) (xy 94.536768 -270.03629) (xy 94.536256 -270.061736) (xy 94.528092 -270.11197)
			(xy 94.511976 -270.160244) (xy 94.488325 -270.205307) (xy 94.457752 -270.245993) (xy 94.421048 -270.281248)
			(xy 94.379164 -270.310158) (xy 94.333185 -270.331975) (xy 94.284301 -270.346135) (xy 94.23378 -270.352269)
			(xy 94.182928 -270.35022) (xy 94.133064 -270.34004) (xy 94.085478 -270.321993) (xy 94.041404 -270.296547)
			(xy 94.001982 -270.26436) (xy 93.968234 -270.226266) (xy 93.941033 -270.183252) (xy 93.921085 -270.136432)
			(xy 93.908906 -270.087018) (xy 93.904811 -270.03629) (xy 93.5863 -270.03629) (xy 93.585805 -270.060897)
			(xy 93.57791 -270.109474) (xy 93.562326 -270.156155) (xy 93.539455 -270.199732) (xy 93.50989 -270.239076)
			(xy 93.474397 -270.273168) (xy 93.433894 -270.301124) (xy 93.389432 -270.322222) (xy 93.342161 -270.335914)
			(xy 93.293306 -270.341846) (xy 93.244131 -270.339865) (xy 93.195912 -270.330021) (xy 93.149896 -270.312569)
			(xy 93.107275 -270.287962) (xy 93.069154 -270.256837) (xy 93.036519 -270.22) (xy 93.010216 -270.178404)
			(xy 92.990925 -270.133128) (xy 92.979148 -270.085344) (xy 92.975188 -270.03629) (xy 92.65666 -270.03629)
			(xy 92.656148 -270.061736) (xy 92.647984 -270.11197) (xy 92.631868 -270.160244) (xy 92.608217 -270.205307)
			(xy 92.577644 -270.245993) (xy 92.54094 -270.281248) (xy 92.499056 -270.310158) (xy 92.453077 -270.331975)
			(xy 92.404193 -270.346135) (xy 92.353672 -270.352269) (xy 92.30282 -270.35022) (xy 92.252956 -270.34004)
			(xy 92.20537 -270.321993) (xy 92.161296 -270.296547) (xy 92.121874 -270.26436) (xy 92.088126 -270.226266)
			(xy 92.060925 -270.183252) (xy 92.040977 -270.136432) (xy 92.028798 -270.087018) (xy 92.024703 -270.03629)
			(xy 91.71686 -270.03629) (xy 91.716348 -270.061736) (xy 91.708184 -270.11197) (xy 91.692068 -270.160244)
			(xy 91.668417 -270.205307) (xy 91.637844 -270.245993) (xy 91.60114 -270.281248) (xy 91.559256 -270.310158)
			(xy 91.513277 -270.331975) (xy 91.464393 -270.346135) (xy 91.413872 -270.352269) (xy 91.36302 -270.35022)
			(xy 91.313156 -270.34004) (xy 91.26557 -270.321993) (xy 91.221496 -270.296547) (xy 91.182074 -270.26436)
			(xy 91.148326 -270.226266) (xy 91.121125 -270.183252) (xy 91.101177 -270.136432) (xy 91.088998 -270.087018)
			(xy 91.084903 -270.03629) (xy 90.766392 -270.03629) (xy 90.765897 -270.060897) (xy 90.758002 -270.109474)
			(xy 90.742418 -270.156155) (xy 90.719547 -270.199732) (xy 90.689982 -270.239076) (xy 90.654489 -270.273168)
			(xy 90.613986 -270.301124) (xy 90.569524 -270.322222) (xy 90.522253 -270.335914) (xy 90.473398 -270.341846)
			(xy 90.424223 -270.339865) (xy 90.376004 -270.330021) (xy 90.329988 -270.312569) (xy 90.287367 -270.287962)
			(xy 90.249246 -270.256837) (xy 90.216611 -270.22) (xy 90.190308 -270.178404) (xy 90.171017 -270.133128)
			(xy 90.15924 -270.085344) (xy 90.15528 -270.03629) (xy 89.826338 -270.03629) (xy 89.825843 -270.060897)
			(xy 89.817948 -270.109474) (xy 89.802364 -270.156155) (xy 89.779493 -270.199732) (xy 89.749928 -270.239076)
			(xy 89.714435 -270.273168) (xy 89.673932 -270.301124) (xy 89.62947 -270.322222) (xy 89.582199 -270.335914)
			(xy 89.533344 -270.341846) (xy 89.484169 -270.339865) (xy 89.43595 -270.330021) (xy 89.389934 -270.312569)
			(xy 89.347313 -270.287962) (xy 89.309192 -270.256837) (xy 89.276557 -270.22) (xy 89.250254 -270.178404)
			(xy 89.230963 -270.133128) (xy 89.219186 -270.085344) (xy 89.215226 -270.03629) (xy 88.886284 -270.03629)
			(xy 88.885789 -270.060897) (xy 88.877894 -270.109474) (xy 88.86231 -270.156155) (xy 88.839439 -270.199732)
			(xy 88.809874 -270.239076) (xy 88.774381 -270.273168) (xy 88.733878 -270.301124) (xy 88.689416 -270.322222)
			(xy 88.642145 -270.335914) (xy 88.59329 -270.341846) (xy 88.544115 -270.339865) (xy 88.495896 -270.330021)
			(xy 88.44988 -270.312569) (xy 88.407259 -270.287962) (xy 88.369138 -270.256837) (xy 88.336503 -270.22)
			(xy 88.3102 -270.178404) (xy 88.290909 -270.133128) (xy 88.279132 -270.085344) (xy 88.275172 -270.03629)
			(xy 87.94623 -270.03629) (xy 87.945735 -270.060897) (xy 87.93784 -270.109474) (xy 87.922256 -270.156155)
			(xy 87.899385 -270.199732) (xy 87.86982 -270.239076) (xy 87.834327 -270.273168) (xy 87.793824 -270.301124)
			(xy 87.749362 -270.322222) (xy 87.702091 -270.335914) (xy 87.653236 -270.341846) (xy 87.604061 -270.339865)
			(xy 87.555842 -270.330021) (xy 87.509826 -270.312569) (xy 87.467205 -270.287962) (xy 87.429084 -270.256837)
			(xy 87.396449 -270.22) (xy 87.370146 -270.178404) (xy 87.350855 -270.133128) (xy 87.339078 -270.085344)
			(xy 87.335118 -270.03629) (xy 87.009986 -270.03629) (xy 87.009986 -270.846296) (xy 87.805272 -270.846296)
			(xy 87.809232 -270.797242) (xy 87.821009 -270.749458) (xy 87.8403 -270.704182) (xy 87.866603 -270.662586)
			(xy 87.899238 -270.625749) (xy 87.937359 -270.594624) (xy 87.97998 -270.570017) (xy 88.025996 -270.552565)
			(xy 88.074215 -270.542721) (xy 88.12339 -270.54074) (xy 88.172245 -270.546672) (xy 88.219516 -270.560364)
			(xy 88.263978 -270.581462) (xy 88.304481 -270.609418) (xy 88.339974 -270.64351) (xy 88.369539 -270.682854)
			(xy 88.39241 -270.726431) (xy 88.407994 -270.773112) (xy 88.415889 -270.821689) (xy 88.416384 -270.846296)
			(xy 88.745326 -270.846296) (xy 88.749286 -270.797242) (xy 88.761063 -270.749458) (xy 88.780354 -270.704182)
			(xy 88.806657 -270.662586) (xy 88.839292 -270.625749) (xy 88.877413 -270.594624) (xy 88.920034 -270.570017)
			(xy 88.96605 -270.552565) (xy 89.014269 -270.542721) (xy 89.063444 -270.54074) (xy 89.112299 -270.546672)
			(xy 89.15957 -270.560364) (xy 89.204032 -270.581462) (xy 89.244535 -270.609418) (xy 89.280028 -270.64351)
			(xy 89.309593 -270.682854) (xy 89.332464 -270.726431) (xy 89.348048 -270.773112) (xy 89.355943 -270.821689)
			(xy 89.356438 -270.846296) (xy 89.685126 -270.846296) (xy 89.689086 -270.797242) (xy 89.700863 -270.749458)
			(xy 89.720154 -270.704182) (xy 89.746457 -270.662586) (xy 89.779092 -270.625749) (xy 89.817213 -270.594624)
			(xy 89.859834 -270.570017) (xy 89.90585 -270.552565) (xy 89.954069 -270.542721) (xy 90.003244 -270.54074)
			(xy 90.052099 -270.546672) (xy 90.09937 -270.560364) (xy 90.143832 -270.581462) (xy 90.184335 -270.609418)
			(xy 90.219828 -270.64351) (xy 90.249393 -270.682854) (xy 90.272264 -270.726431) (xy 90.287848 -270.773112)
			(xy 90.295743 -270.821689) (xy 90.296238 -270.846296) (xy 90.614749 -270.846296) (xy 90.618844 -270.795568)
			(xy 90.631023 -270.746154) (xy 90.650971 -270.699334) (xy 90.678172 -270.65632) (xy 90.71192 -270.618226)
			(xy 90.751342 -270.586039) (xy 90.795416 -270.560593) (xy 90.843002 -270.542546) (xy 90.892866 -270.532366)
			(xy 90.943718 -270.530317) (xy 90.994239 -270.536451) (xy 91.043123 -270.550611) (xy 91.089102 -270.572428)
			(xy 91.130986 -270.601338) (xy 91.16769 -270.636593) (xy 91.198263 -270.677279) (xy 91.221914 -270.722342)
			(xy 91.23803 -270.770616) (xy 91.246194 -270.82085) (xy 91.246706 -270.846296) (xy 91.565234 -270.846296)
			(xy 91.569194 -270.797242) (xy 91.580971 -270.749458) (xy 91.600262 -270.704182) (xy 91.626565 -270.662586)
			(xy 91.6592 -270.625749) (xy 91.697321 -270.594624) (xy 91.739942 -270.570017) (xy 91.785958 -270.552565)
			(xy 91.834177 -270.542721) (xy 91.883352 -270.54074) (xy 91.932207 -270.546672) (xy 91.979478 -270.560364)
			(xy 92.02394 -270.581462) (xy 92.064443 -270.609418) (xy 92.099936 -270.64351) (xy 92.129501 -270.682854)
			(xy 92.152372 -270.726431) (xy 92.167956 -270.773112) (xy 92.175851 -270.821689) (xy 92.176346 -270.846296)
			(xy 92.494857 -270.846296) (xy 92.498952 -270.795568) (xy 92.511131 -270.746154) (xy 92.531079 -270.699334)
			(xy 92.55828 -270.65632) (xy 92.592028 -270.618226) (xy 92.63145 -270.586039) (xy 92.675524 -270.560593)
			(xy 92.72311 -270.542546) (xy 92.772974 -270.532366) (xy 92.823826 -270.530317) (xy 92.874347 -270.536451)
			(xy 92.923231 -270.550611) (xy 92.96921 -270.572428) (xy 93.011094 -270.601338) (xy 93.047798 -270.636593)
			(xy 93.078371 -270.677279) (xy 93.102022 -270.722342) (xy 93.118138 -270.770616) (xy 93.126302 -270.82085)
			(xy 93.126814 -270.846296) (xy 94.374711 -270.846296) (xy 94.378806 -270.795568) (xy 94.390985 -270.746154)
			(xy 94.410933 -270.699334) (xy 94.438134 -270.65632) (xy 94.471882 -270.618226) (xy 94.511304 -270.586039)
			(xy 94.555378 -270.560593) (xy 94.602964 -270.542546) (xy 94.652828 -270.532366) (xy 94.70368 -270.530317)
			(xy 94.754201 -270.536451) (xy 94.803085 -270.550611) (xy 94.849064 -270.572428) (xy 94.890948 -270.601338)
			(xy 94.927652 -270.636593) (xy 94.958225 -270.677279) (xy 94.981876 -270.722342) (xy 94.997992 -270.770616)
			(xy 95.006156 -270.82085) (xy 95.006668 -270.846296) (xy 95.314765 -270.846296) (xy 95.31886 -270.795568)
			(xy 95.331039 -270.746154) (xy 95.350987 -270.699334) (xy 95.378188 -270.65632) (xy 95.411936 -270.618226)
			(xy 95.451358 -270.586039) (xy 95.495432 -270.560593) (xy 95.543018 -270.542546) (xy 95.592882 -270.532366)
			(xy 95.643734 -270.530317) (xy 95.694255 -270.536451) (xy 95.743139 -270.550611) (xy 95.789118 -270.572428)
			(xy 95.831002 -270.601338) (xy 95.867706 -270.636593) (xy 95.898279 -270.677279) (xy 95.92193 -270.722342)
			(xy 95.938046 -270.770616) (xy 95.94621 -270.82085) (xy 95.946722 -270.846296) (xy 95.94621 -270.871742)
			(xy 95.938046 -270.921976) (xy 95.92193 -270.97025) (xy 95.898279 -271.015313) (xy 95.867706 -271.055999)
			(xy 95.831002 -271.091254) (xy 95.789118 -271.120164) (xy 95.743139 -271.141981) (xy 95.694255 -271.156141)
			(xy 95.643734 -271.162275) (xy 95.592882 -271.160226) (xy 95.543018 -271.150046) (xy 95.495432 -271.131999)
			(xy 95.451358 -271.106553) (xy 95.411936 -271.074366) (xy 95.378188 -271.036272) (xy 95.350987 -270.993258)
			(xy 95.331039 -270.946438) (xy 95.31886 -270.897024) (xy 95.314765 -270.846296) (xy 95.006668 -270.846296)
			(xy 95.006156 -270.871742) (xy 94.997992 -270.921976) (xy 94.981876 -270.97025) (xy 94.958225 -271.015313)
			(xy 94.927652 -271.055999) (xy 94.890948 -271.091254) (xy 94.849064 -271.120164) (xy 94.803085 -271.141981)
			(xy 94.754201 -271.156141) (xy 94.70368 -271.162275) (xy 94.652828 -271.160226) (xy 94.602964 -271.150046)
			(xy 94.555378 -271.131999) (xy 94.511304 -271.106553) (xy 94.471882 -271.074366) (xy 94.438134 -271.036272)
			(xy 94.410933 -270.993258) (xy 94.390985 -270.946438) (xy 94.378806 -270.897024) (xy 94.374711 -270.846296)
			(xy 93.126814 -270.846296) (xy 93.126302 -270.871742) (xy 93.118138 -270.921976) (xy 93.102022 -270.97025)
			(xy 93.078371 -271.015313) (xy 93.047798 -271.055999) (xy 93.011094 -271.091254) (xy 92.96921 -271.120164)
			(xy 92.923231 -271.141981) (xy 92.874347 -271.156141) (xy 92.823826 -271.162275) (xy 92.772974 -271.160226)
			(xy 92.72311 -271.150046) (xy 92.675524 -271.131999) (xy 92.63145 -271.106553) (xy 92.592028 -271.074366)
			(xy 92.55828 -271.036272) (xy 92.531079 -270.993258) (xy 92.511131 -270.946438) (xy 92.498952 -270.897024)
			(xy 92.494857 -270.846296) (xy 92.176346 -270.846296) (xy 92.175851 -270.870903) (xy 92.167956 -270.91948)
			(xy 92.152372 -270.966161) (xy 92.129501 -271.009738) (xy 92.099936 -271.049082) (xy 92.064443 -271.083174)
			(xy 92.02394 -271.11113) (xy 91.979478 -271.132228) (xy 91.932207 -271.14592) (xy 91.883352 -271.151852)
			(xy 91.834177 -271.149871) (xy 91.785958 -271.140027) (xy 91.739942 -271.122575) (xy 91.697321 -271.097968)
			(xy 91.6592 -271.066843) (xy 91.626565 -271.030006) (xy 91.600262 -270.98841) (xy 91.580971 -270.943134)
			(xy 91.569194 -270.89535) (xy 91.565234 -270.846296) (xy 91.246706 -270.846296) (xy 91.246194 -270.871742)
			(xy 91.23803 -270.921976) (xy 91.221914 -270.97025) (xy 91.198263 -271.015313) (xy 91.16769 -271.055999)
			(xy 91.130986 -271.091254) (xy 91.089102 -271.120164) (xy 91.043123 -271.141981) (xy 90.994239 -271.156141)
			(xy 90.943718 -271.162275) (xy 90.892866 -271.160226) (xy 90.843002 -271.150046) (xy 90.795416 -271.131999)
			(xy 90.751342 -271.106553) (xy 90.71192 -271.074366) (xy 90.678172 -271.036272) (xy 90.650971 -270.993258)
			(xy 90.631023 -270.946438) (xy 90.618844 -270.897024) (xy 90.614749 -270.846296) (xy 90.296238 -270.846296)
			(xy 90.295743 -270.870903) (xy 90.287848 -270.91948) (xy 90.272264 -270.966161) (xy 90.249393 -271.009738)
			(xy 90.219828 -271.049082) (xy 90.184335 -271.083174) (xy 90.143832 -271.11113) (xy 90.09937 -271.132228)
			(xy 90.052099 -271.14592) (xy 90.003244 -271.151852) (xy 89.954069 -271.149871) (xy 89.90585 -271.140027)
			(xy 89.859834 -271.122575) (xy 89.817213 -271.097968) (xy 89.779092 -271.066843) (xy 89.746457 -271.030006)
			(xy 89.720154 -270.98841) (xy 89.700863 -270.943134) (xy 89.689086 -270.89535) (xy 89.685126 -270.846296)
			(xy 89.356438 -270.846296) (xy 89.355943 -270.870903) (xy 89.348048 -270.91948) (xy 89.332464 -270.966161)
			(xy 89.309593 -271.009738) (xy 89.280028 -271.049082) (xy 89.244535 -271.083174) (xy 89.204032 -271.11113)
			(xy 89.15957 -271.132228) (xy 89.112299 -271.14592) (xy 89.063444 -271.151852) (xy 89.014269 -271.149871)
			(xy 88.96605 -271.140027) (xy 88.920034 -271.122575) (xy 88.877413 -271.097968) (xy 88.839292 -271.066843)
			(xy 88.806657 -271.030006) (xy 88.780354 -270.98841) (xy 88.761063 -270.943134) (xy 88.749286 -270.89535)
			(xy 88.745326 -270.846296) (xy 88.416384 -270.846296) (xy 88.415889 -270.870903) (xy 88.407994 -270.91948)
			(xy 88.39241 -270.966161) (xy 88.369539 -271.009738) (xy 88.339974 -271.049082) (xy 88.304481 -271.083174)
			(xy 88.263978 -271.11113) (xy 88.219516 -271.132228) (xy 88.172245 -271.14592) (xy 88.12339 -271.151852)
			(xy 88.074215 -271.149871) (xy 88.025996 -271.140027) (xy 87.97998 -271.122575) (xy 87.937359 -271.097968)
			(xy 87.899238 -271.066843) (xy 87.866603 -271.030006) (xy 87.8403 -270.98841) (xy 87.821009 -270.943134)
			(xy 87.809232 -270.89535) (xy 87.805272 -270.846296) (xy 87.009986 -270.846296) (xy 87.009986 -271.656302)
			(xy 87.335118 -271.656302) (xy 87.339078 -271.607248) (xy 87.350855 -271.559464) (xy 87.370146 -271.514188)
			(xy 87.396449 -271.472592) (xy 87.429084 -271.435755) (xy 87.467205 -271.40463) (xy 87.509826 -271.380023)
			(xy 87.555842 -271.362571) (xy 87.604061 -271.352727) (xy 87.653236 -271.350746) (xy 87.702091 -271.356678)
			(xy 87.749362 -271.37037) (xy 87.793824 -271.391468) (xy 87.834327 -271.419424) (xy 87.86982 -271.453516)
			(xy 87.899385 -271.49286) (xy 87.922256 -271.536437) (xy 87.93784 -271.583118) (xy 87.945735 -271.631695)
			(xy 87.94623 -271.656302) (xy 88.275172 -271.656302) (xy 88.279132 -271.607248) (xy 88.290909 -271.559464)
			(xy 88.3102 -271.514188) (xy 88.336503 -271.472592) (xy 88.369138 -271.435755) (xy 88.407259 -271.40463)
			(xy 88.44988 -271.380023) (xy 88.495896 -271.362571) (xy 88.544115 -271.352727) (xy 88.59329 -271.350746)
			(xy 88.642145 -271.356678) (xy 88.689416 -271.37037) (xy 88.733878 -271.391468) (xy 88.774381 -271.419424)
			(xy 88.809874 -271.453516) (xy 88.839439 -271.49286) (xy 88.86231 -271.536437) (xy 88.877894 -271.583118)
			(xy 88.885789 -271.631695) (xy 88.886284 -271.656302) (xy 89.215226 -271.656302) (xy 89.219186 -271.607248)
			(xy 89.230963 -271.559464) (xy 89.250254 -271.514188) (xy 89.276557 -271.472592) (xy 89.309192 -271.435755)
			(xy 89.347313 -271.40463) (xy 89.389934 -271.380023) (xy 89.43595 -271.362571) (xy 89.484169 -271.352727)
			(xy 89.533344 -271.350746) (xy 89.582199 -271.356678) (xy 89.62947 -271.37037) (xy 89.673932 -271.391468)
			(xy 89.714435 -271.419424) (xy 89.749928 -271.453516) (xy 89.779493 -271.49286) (xy 89.802364 -271.536437)
			(xy 89.817948 -271.583118) (xy 89.825843 -271.631695) (xy 89.826338 -271.656302) (xy 90.15528 -271.656302)
			(xy 90.15924 -271.607248) (xy 90.171017 -271.559464) (xy 90.190308 -271.514188) (xy 90.216611 -271.472592)
			(xy 90.249246 -271.435755) (xy 90.287367 -271.40463) (xy 90.329988 -271.380023) (xy 90.376004 -271.362571)
			(xy 90.424223 -271.352727) (xy 90.473398 -271.350746) (xy 90.522253 -271.356678) (xy 90.569524 -271.37037)
			(xy 90.613986 -271.391468) (xy 90.654489 -271.419424) (xy 90.689982 -271.453516) (xy 90.719547 -271.49286)
			(xy 90.742418 -271.536437) (xy 90.758002 -271.583118) (xy 90.765897 -271.631695) (xy 90.766392 -271.656302)
			(xy 91.084903 -271.656302) (xy 91.088998 -271.605574) (xy 91.101177 -271.55616) (xy 91.121125 -271.50934)
			(xy 91.148326 -271.466326) (xy 91.182074 -271.428232) (xy 91.221496 -271.396045) (xy 91.26557 -271.370599)
			(xy 91.313156 -271.352552) (xy 91.36302 -271.342372) (xy 91.413872 -271.340323) (xy 91.464393 -271.346457)
			(xy 91.513277 -271.360617) (xy 91.559256 -271.382434) (xy 91.60114 -271.411344) (xy 91.637844 -271.446599)
			(xy 91.668417 -271.487285) (xy 91.692068 -271.532348) (xy 91.708184 -271.580622) (xy 91.716348 -271.630856)
			(xy 91.71686 -271.656302) (xy 92.024703 -271.656302) (xy 92.028798 -271.605574) (xy 92.040977 -271.55616)
			(xy 92.060925 -271.50934) (xy 92.088126 -271.466326) (xy 92.121874 -271.428232) (xy 92.161296 -271.396045)
			(xy 92.20537 -271.370599) (xy 92.252956 -271.352552) (xy 92.30282 -271.342372) (xy 92.353672 -271.340323)
			(xy 92.404193 -271.346457) (xy 92.453077 -271.360617) (xy 92.499056 -271.382434) (xy 92.54094 -271.411344)
			(xy 92.577644 -271.446599) (xy 92.608217 -271.487285) (xy 92.631868 -271.532348) (xy 92.647984 -271.580622)
			(xy 92.656148 -271.630856) (xy 92.65666 -271.656302) (xy 92.975188 -271.656302) (xy 92.979148 -271.607248)
			(xy 92.990925 -271.559464) (xy 93.010216 -271.514188) (xy 93.036519 -271.472592) (xy 93.069154 -271.435755)
			(xy 93.107275 -271.40463) (xy 93.149896 -271.380023) (xy 93.195912 -271.362571) (xy 93.244131 -271.352727)
			(xy 93.293306 -271.350746) (xy 93.342161 -271.356678) (xy 93.389432 -271.37037) (xy 93.433894 -271.391468)
			(xy 93.474397 -271.419424) (xy 93.50989 -271.453516) (xy 93.539455 -271.49286) (xy 93.562326 -271.536437)
			(xy 93.57791 -271.583118) (xy 93.585805 -271.631695) (xy 93.5863 -271.656302) (xy 93.904811 -271.656302)
			(xy 93.908906 -271.605574) (xy 93.921085 -271.55616) (xy 93.941033 -271.50934) (xy 93.968234 -271.466326)
			(xy 94.001982 -271.428232) (xy 94.041404 -271.396045) (xy 94.085478 -271.370599) (xy 94.133064 -271.352552)
			(xy 94.182928 -271.342372) (xy 94.23378 -271.340323) (xy 94.284301 -271.346457) (xy 94.333185 -271.360617)
			(xy 94.379164 -271.382434) (xy 94.421048 -271.411344) (xy 94.457752 -271.446599) (xy 94.488325 -271.487285)
			(xy 94.511976 -271.532348) (xy 94.528092 -271.580622) (xy 94.536256 -271.630856) (xy 94.536768 -271.656302)
			(xy 94.855296 -271.656302) (xy 94.859256 -271.607248) (xy 94.871033 -271.559464) (xy 94.890324 -271.514188)
			(xy 94.916627 -271.472592) (xy 94.949262 -271.435755) (xy 94.987383 -271.40463) (xy 95.030004 -271.380023)
			(xy 95.07602 -271.362571) (xy 95.124239 -271.352727) (xy 95.173414 -271.350746) (xy 95.222269 -271.356678)
			(xy 95.26954 -271.37037) (xy 95.314002 -271.391468) (xy 95.354505 -271.419424) (xy 95.389998 -271.453516)
			(xy 95.419563 -271.49286) (xy 95.442434 -271.536437) (xy 95.458018 -271.583118) (xy 95.465913 -271.631695)
			(xy 95.466408 -271.656302) (xy 95.784919 -271.656302) (xy 95.789014 -271.605574) (xy 95.801193 -271.55616)
			(xy 95.821141 -271.50934) (xy 95.848342 -271.466326) (xy 95.88209 -271.428232) (xy 95.921512 -271.396045)
			(xy 95.965586 -271.370599) (xy 96.013172 -271.352552) (xy 96.063036 -271.342372) (xy 96.113888 -271.340323)
			(xy 96.164409 -271.346457) (xy 96.213293 -271.360617) (xy 96.259272 -271.382434) (xy 96.301156 -271.411344)
			(xy 96.33786 -271.446599) (xy 96.368433 -271.487285) (xy 96.392084 -271.532348) (xy 96.4082 -271.580622)
			(xy 96.416364 -271.630856) (xy 96.416876 -271.656302) (xy 96.416364 -271.681748) (xy 96.4082 -271.731982)
			(xy 96.392084 -271.780256) (xy 96.368433 -271.825319) (xy 96.33786 -271.866005) (xy 96.301156 -271.90126)
			(xy 96.259272 -271.93017) (xy 96.213293 -271.951987) (xy 96.164409 -271.966147) (xy 96.113888 -271.972281)
			(xy 96.063036 -271.970232) (xy 96.013172 -271.960052) (xy 95.965586 -271.942005) (xy 95.921512 -271.916559)
			(xy 95.88209 -271.884372) (xy 95.848342 -271.846278) (xy 95.821141 -271.803264) (xy 95.801193 -271.756444)
			(xy 95.789014 -271.70703) (xy 95.784919 -271.656302) (xy 95.466408 -271.656302) (xy 95.465913 -271.680909)
			(xy 95.458018 -271.729486) (xy 95.442434 -271.776167) (xy 95.419563 -271.819744) (xy 95.389998 -271.859088)
			(xy 95.354505 -271.89318) (xy 95.314002 -271.921136) (xy 95.26954 -271.942234) (xy 95.222269 -271.955926)
			(xy 95.173414 -271.961858) (xy 95.124239 -271.959877) (xy 95.07602 -271.950033) (xy 95.030004 -271.932581)
			(xy 94.987383 -271.907974) (xy 94.949262 -271.876849) (xy 94.916627 -271.840012) (xy 94.890324 -271.798416)
			(xy 94.871033 -271.75314) (xy 94.859256 -271.705356) (xy 94.855296 -271.656302) (xy 94.536768 -271.656302)
			(xy 94.536256 -271.681748) (xy 94.528092 -271.731982) (xy 94.511976 -271.780256) (xy 94.488325 -271.825319)
			(xy 94.457752 -271.866005) (xy 94.421048 -271.90126) (xy 94.379164 -271.93017) (xy 94.333185 -271.951987)
			(xy 94.284301 -271.966147) (xy 94.23378 -271.972281) (xy 94.182928 -271.970232) (xy 94.133064 -271.960052)
			(xy 94.085478 -271.942005) (xy 94.041404 -271.916559) (xy 94.001982 -271.884372) (xy 93.968234 -271.846278)
			(xy 93.941033 -271.803264) (xy 93.921085 -271.756444) (xy 93.908906 -271.70703) (xy 93.904811 -271.656302)
			(xy 93.5863 -271.656302) (xy 93.585805 -271.680909) (xy 93.57791 -271.729486) (xy 93.562326 -271.776167)
			(xy 93.539455 -271.819744) (xy 93.50989 -271.859088) (xy 93.474397 -271.89318) (xy 93.433894 -271.921136)
			(xy 93.389432 -271.942234) (xy 93.342161 -271.955926) (xy 93.293306 -271.961858) (xy 93.244131 -271.959877)
			(xy 93.195912 -271.950033) (xy 93.149896 -271.932581) (xy 93.107275 -271.907974) (xy 93.069154 -271.876849)
			(xy 93.036519 -271.840012) (xy 93.010216 -271.798416) (xy 92.990925 -271.75314) (xy 92.979148 -271.705356)
			(xy 92.975188 -271.656302) (xy 92.65666 -271.656302) (xy 92.656148 -271.681748) (xy 92.647984 -271.731982)
			(xy 92.631868 -271.780256) (xy 92.608217 -271.825319) (xy 92.577644 -271.866005) (xy 92.54094 -271.90126)
			(xy 92.499056 -271.93017) (xy 92.453077 -271.951987) (xy 92.404193 -271.966147) (xy 92.353672 -271.972281)
			(xy 92.30282 -271.970232) (xy 92.252956 -271.960052) (xy 92.20537 -271.942005) (xy 92.161296 -271.916559)
			(xy 92.121874 -271.884372) (xy 92.088126 -271.846278) (xy 92.060925 -271.803264) (xy 92.040977 -271.756444)
			(xy 92.028798 -271.70703) (xy 92.024703 -271.656302) (xy 91.71686 -271.656302) (xy 91.716348 -271.681748)
			(xy 91.708184 -271.731982) (xy 91.692068 -271.780256) (xy 91.668417 -271.825319) (xy 91.637844 -271.866005)
			(xy 91.60114 -271.90126) (xy 91.559256 -271.93017) (xy 91.513277 -271.951987) (xy 91.464393 -271.966147)
			(xy 91.413872 -271.972281) (xy 91.36302 -271.970232) (xy 91.313156 -271.960052) (xy 91.26557 -271.942005)
			(xy 91.221496 -271.916559) (xy 91.182074 -271.884372) (xy 91.148326 -271.846278) (xy 91.121125 -271.803264)
			(xy 91.101177 -271.756444) (xy 91.088998 -271.70703) (xy 91.084903 -271.656302) (xy 90.766392 -271.656302)
			(xy 90.765897 -271.680909) (xy 90.758002 -271.729486) (xy 90.742418 -271.776167) (xy 90.719547 -271.819744)
			(xy 90.689982 -271.859088) (xy 90.654489 -271.89318) (xy 90.613986 -271.921136) (xy 90.569524 -271.942234)
			(xy 90.522253 -271.955926) (xy 90.473398 -271.961858) (xy 90.424223 -271.959877) (xy 90.376004 -271.950033)
			(xy 90.329988 -271.932581) (xy 90.287367 -271.907974) (xy 90.249246 -271.876849) (xy 90.216611 -271.840012)
			(xy 90.190308 -271.798416) (xy 90.171017 -271.75314) (xy 90.15924 -271.705356) (xy 90.15528 -271.656302)
			(xy 89.826338 -271.656302) (xy 89.825843 -271.680909) (xy 89.817948 -271.729486) (xy 89.802364 -271.776167)
			(xy 89.779493 -271.819744) (xy 89.749928 -271.859088) (xy 89.714435 -271.89318) (xy 89.673932 -271.921136)
			(xy 89.62947 -271.942234) (xy 89.582199 -271.955926) (xy 89.533344 -271.961858) (xy 89.484169 -271.959877)
			(xy 89.43595 -271.950033) (xy 89.389934 -271.932581) (xy 89.347313 -271.907974) (xy 89.309192 -271.876849)
			(xy 89.276557 -271.840012) (xy 89.250254 -271.798416) (xy 89.230963 -271.75314) (xy 89.219186 -271.705356)
			(xy 89.215226 -271.656302) (xy 88.886284 -271.656302) (xy 88.885789 -271.680909) (xy 88.877894 -271.729486)
			(xy 88.86231 -271.776167) (xy 88.839439 -271.819744) (xy 88.809874 -271.859088) (xy 88.774381 -271.89318)
			(xy 88.733878 -271.921136) (xy 88.689416 -271.942234) (xy 88.642145 -271.955926) (xy 88.59329 -271.961858)
			(xy 88.544115 -271.959877) (xy 88.495896 -271.950033) (xy 88.44988 -271.932581) (xy 88.407259 -271.907974)
			(xy 88.369138 -271.876849) (xy 88.336503 -271.840012) (xy 88.3102 -271.798416) (xy 88.290909 -271.75314)
			(xy 88.279132 -271.705356) (xy 88.275172 -271.656302) (xy 87.94623 -271.656302) (xy 87.945735 -271.680909)
			(xy 87.93784 -271.729486) (xy 87.922256 -271.776167) (xy 87.899385 -271.819744) (xy 87.86982 -271.859088)
			(xy 87.834327 -271.89318) (xy 87.793824 -271.921136) (xy 87.749362 -271.942234) (xy 87.702091 -271.955926)
			(xy 87.653236 -271.961858) (xy 87.604061 -271.959877) (xy 87.555842 -271.950033) (xy 87.509826 -271.932581)
			(xy 87.467205 -271.907974) (xy 87.429084 -271.876849) (xy 87.396449 -271.840012) (xy 87.370146 -271.798416)
			(xy 87.350855 -271.75314) (xy 87.339078 -271.705356) (xy 87.335118 -271.656302) (xy 87.009986 -271.656302)
			(xy 87.009986 -272.064988) (xy 87.010363 -272.074091) (xy 87.016748 -272.091141) (xy 87.022432 -272.098262)
			(xy 87.024972 -272.101056) (xy 87.065104 -272.1356) (xy 87.080344 -272.148808) (xy 87.081614 -272.149824)
			(xy 87.088575 -272.15503) (xy 87.104934 -272.160879) (xy 87.113618 -272.161254) (xy 87.159592 -272.161254)
			(xy 87.171022 -272.161) (xy 87.171276 -272.161) (xy 87.195253 -272.161491) (xy 87.242611 -272.169032)
			(xy 87.288207 -272.183884) (xy 87.330921 -272.205682) (xy 87.369701 -272.23389) (xy 87.403595 -272.267815)
			(xy 87.431767 -272.306621) (xy 87.453525 -272.349355) (xy 87.468335 -272.394966) (xy 87.475831 -272.442331)
			(xy 87.47633 -272.466308) (xy 87.805272 -272.466308) (xy 87.809232 -272.417254) (xy 87.821009 -272.36947)
			(xy 87.8403 -272.324194) (xy 87.866603 -272.282598) (xy 87.899238 -272.245761) (xy 87.937359 -272.214636)
			(xy 87.97998 -272.190029) (xy 88.025996 -272.172577) (xy 88.074215 -272.162733) (xy 88.12339 -272.160752)
			(xy 88.172245 -272.166684) (xy 88.219516 -272.180376) (xy 88.263978 -272.201474) (xy 88.304481 -272.22943)
			(xy 88.339974 -272.263522) (xy 88.369539 -272.302866) (xy 88.39241 -272.346443) (xy 88.407994 -272.393124)
			(xy 88.415889 -272.441701) (xy 88.416384 -272.466308) (xy 88.745326 -272.466308) (xy 88.749286 -272.417254)
			(xy 88.761063 -272.36947) (xy 88.780354 -272.324194) (xy 88.806657 -272.282598) (xy 88.839292 -272.245761)
			(xy 88.877413 -272.214636) (xy 88.920034 -272.190029) (xy 88.96605 -272.172577) (xy 89.014269 -272.162733)
			(xy 89.063444 -272.160752) (xy 89.112299 -272.166684) (xy 89.15957 -272.180376) (xy 89.204032 -272.201474)
			(xy 89.244535 -272.22943) (xy 89.280028 -272.263522) (xy 89.309593 -272.302866) (xy 89.332464 -272.346443)
			(xy 89.348048 -272.393124) (xy 89.355943 -272.441701) (xy 89.356438 -272.466308) (xy 89.685126 -272.466308)
			(xy 89.689086 -272.417254) (xy 89.700863 -272.36947) (xy 89.720154 -272.324194) (xy 89.746457 -272.282598)
			(xy 89.779092 -272.245761) (xy 89.817213 -272.214636) (xy 89.859834 -272.190029) (xy 89.90585 -272.172577)
			(xy 89.954069 -272.162733) (xy 90.003244 -272.160752) (xy 90.052099 -272.166684) (xy 90.09937 -272.180376)
			(xy 90.143832 -272.201474) (xy 90.184335 -272.22943) (xy 90.219828 -272.263522) (xy 90.249393 -272.302866)
			(xy 90.272264 -272.346443) (xy 90.287848 -272.393124) (xy 90.295743 -272.441701) (xy 90.296238 -272.466308)
			(xy 90.614749 -272.466308) (xy 90.618844 -272.41558) (xy 90.631023 -272.366166) (xy 90.650971 -272.319346)
			(xy 90.678172 -272.276332) (xy 90.71192 -272.238238) (xy 90.751342 -272.206051) (xy 90.795416 -272.180605)
			(xy 90.843002 -272.162558) (xy 90.892866 -272.152378) (xy 90.943718 -272.150329) (xy 90.994239 -272.156463)
			(xy 91.043123 -272.170623) (xy 91.089102 -272.19244) (xy 91.130986 -272.22135) (xy 91.16769 -272.256605)
			(xy 91.198263 -272.297291) (xy 91.221914 -272.342354) (xy 91.23803 -272.390628) (xy 91.246194 -272.440862)
			(xy 91.246706 -272.466308) (xy 91.565234 -272.466308) (xy 91.569194 -272.417254) (xy 91.580971 -272.36947)
			(xy 91.600262 -272.324194) (xy 91.626565 -272.282598) (xy 91.6592 -272.245761) (xy 91.697321 -272.214636)
			(xy 91.739942 -272.190029) (xy 91.785958 -272.172577) (xy 91.834177 -272.162733) (xy 91.883352 -272.160752)
			(xy 91.932207 -272.166684) (xy 91.979478 -272.180376) (xy 92.02394 -272.201474) (xy 92.064443 -272.22943)
			(xy 92.099936 -272.263522) (xy 92.129501 -272.302866) (xy 92.152372 -272.346443) (xy 92.167956 -272.393124)
			(xy 92.175851 -272.441701) (xy 92.176346 -272.466308) (xy 92.494857 -272.466308) (xy 92.498952 -272.41558)
			(xy 92.511131 -272.366166) (xy 92.531079 -272.319346) (xy 92.55828 -272.276332) (xy 92.592028 -272.238238)
			(xy 92.63145 -272.206051) (xy 92.675524 -272.180605) (xy 92.72311 -272.162558) (xy 92.772974 -272.152378)
			(xy 92.823826 -272.150329) (xy 92.874347 -272.156463) (xy 92.923231 -272.170623) (xy 92.96921 -272.19244)
			(xy 93.011094 -272.22135) (xy 93.047798 -272.256605) (xy 93.078371 -272.297291) (xy 93.102022 -272.342354)
			(xy 93.118138 -272.390628) (xy 93.126302 -272.440862) (xy 93.126814 -272.466308) (xy 93.445342 -272.466308)
			(xy 93.449302 -272.417254) (xy 93.461079 -272.36947) (xy 93.48037 -272.324194) (xy 93.506673 -272.282598)
			(xy 93.539308 -272.245761) (xy 93.577429 -272.214636) (xy 93.62005 -272.190029) (xy 93.666066 -272.172577)
			(xy 93.714285 -272.162733) (xy 93.76346 -272.160752) (xy 93.812315 -272.166684) (xy 93.859586 -272.180376)
			(xy 93.904048 -272.201474) (xy 93.944551 -272.22943) (xy 93.980044 -272.263522) (xy 94.009609 -272.302866)
			(xy 94.03248 -272.346443) (xy 94.048064 -272.393124) (xy 94.055959 -272.441701) (xy 94.056454 -272.466308)
			(xy 94.374711 -272.466308) (xy 94.378806 -272.41558) (xy 94.390985 -272.366166) (xy 94.410933 -272.319346)
			(xy 94.438134 -272.276332) (xy 94.471882 -272.238238) (xy 94.511304 -272.206051) (xy 94.555378 -272.180605)
			(xy 94.602964 -272.162558) (xy 94.652828 -272.152378) (xy 94.70368 -272.150329) (xy 94.754201 -272.156463)
			(xy 94.803085 -272.170623) (xy 94.849064 -272.19244) (xy 94.890948 -272.22135) (xy 94.927652 -272.256605)
			(xy 94.958225 -272.297291) (xy 94.981876 -272.342354) (xy 94.997992 -272.390628) (xy 95.006156 -272.440862)
			(xy 95.006668 -272.466308) (xy 95.314765 -272.466308) (xy 95.31886 -272.41558) (xy 95.331039 -272.366166)
			(xy 95.350987 -272.319346) (xy 95.378188 -272.276332) (xy 95.411936 -272.238238) (xy 95.451358 -272.206051)
			(xy 95.495432 -272.180605) (xy 95.543018 -272.162558) (xy 95.592882 -272.152378) (xy 95.643734 -272.150329)
			(xy 95.694255 -272.156463) (xy 95.743139 -272.170623) (xy 95.789118 -272.19244) (xy 95.831002 -272.22135)
			(xy 95.867706 -272.256605) (xy 95.898279 -272.297291) (xy 95.92193 -272.342354) (xy 95.938046 -272.390628)
			(xy 95.94621 -272.440862) (xy 95.946722 -272.466308) (xy 95.94621 -272.491754) (xy 95.938046 -272.541988)
			(xy 95.92193 -272.590262) (xy 95.898279 -272.635325) (xy 95.867706 -272.676011) (xy 95.831002 -272.711266)
			(xy 95.789118 -272.740176) (xy 95.743139 -272.761993) (xy 95.694255 -272.776153) (xy 95.643734 -272.782287)
			(xy 95.592882 -272.780238) (xy 95.543018 -272.770058) (xy 95.495432 -272.752011) (xy 95.451358 -272.726565)
			(xy 95.411936 -272.694378) (xy 95.378188 -272.656284) (xy 95.350987 -272.61327) (xy 95.331039 -272.56645)
			(xy 95.31886 -272.517036) (xy 95.314765 -272.466308) (xy 95.006668 -272.466308) (xy 95.006156 -272.491754)
			(xy 94.997992 -272.541988) (xy 94.981876 -272.590262) (xy 94.958225 -272.635325) (xy 94.927652 -272.676011)
			(xy 94.890948 -272.711266) (xy 94.849064 -272.740176) (xy 94.803085 -272.761993) (xy 94.754201 -272.776153)
			(xy 94.70368 -272.782287) (xy 94.652828 -272.780238) (xy 94.602964 -272.770058) (xy 94.555378 -272.752011)
			(xy 94.511304 -272.726565) (xy 94.471882 -272.694378) (xy 94.438134 -272.656284) (xy 94.410933 -272.61327)
			(xy 94.390985 -272.56645) (xy 94.378806 -272.517036) (xy 94.374711 -272.466308) (xy 94.056454 -272.466308)
			(xy 94.055959 -272.490915) (xy 94.048064 -272.539492) (xy 94.03248 -272.586173) (xy 94.009609 -272.62975)
			(xy 93.980044 -272.669094) (xy 93.944551 -272.703186) (xy 93.904048 -272.731142) (xy 93.859586 -272.75224)
			(xy 93.812315 -272.765932) (xy 93.76346 -272.771864) (xy 93.714285 -272.769883) (xy 93.666066 -272.760039)
			(xy 93.62005 -272.742587) (xy 93.577429 -272.71798) (xy 93.539308 -272.686855) (xy 93.506673 -272.650018)
			(xy 93.48037 -272.608422) (xy 93.461079 -272.563146) (xy 93.449302 -272.515362) (xy 93.445342 -272.466308)
			(xy 93.126814 -272.466308) (xy 93.126302 -272.491754) (xy 93.118138 -272.541988) (xy 93.102022 -272.590262)
			(xy 93.078371 -272.635325) (xy 93.047798 -272.676011) (xy 93.011094 -272.711266) (xy 92.96921 -272.740176)
			(xy 92.923231 -272.761993) (xy 92.874347 -272.776153) (xy 92.823826 -272.782287) (xy 92.772974 -272.780238)
			(xy 92.72311 -272.770058) (xy 92.675524 -272.752011) (xy 92.63145 -272.726565) (xy 92.592028 -272.694378)
			(xy 92.55828 -272.656284) (xy 92.531079 -272.61327) (xy 92.511131 -272.56645) (xy 92.498952 -272.517036)
			(xy 92.494857 -272.466308) (xy 92.176346 -272.466308) (xy 92.175851 -272.490915) (xy 92.167956 -272.539492)
			(xy 92.152372 -272.586173) (xy 92.129501 -272.62975) (xy 92.099936 -272.669094) (xy 92.064443 -272.703186)
			(xy 92.02394 -272.731142) (xy 91.979478 -272.75224) (xy 91.932207 -272.765932) (xy 91.883352 -272.771864)
			(xy 91.834177 -272.769883) (xy 91.785958 -272.760039) (xy 91.739942 -272.742587) (xy 91.697321 -272.71798)
			(xy 91.6592 -272.686855) (xy 91.626565 -272.650018) (xy 91.600262 -272.608422) (xy 91.580971 -272.563146)
			(xy 91.569194 -272.515362) (xy 91.565234 -272.466308) (xy 91.246706 -272.466308) (xy 91.246194 -272.491754)
			(xy 91.23803 -272.541988) (xy 91.221914 -272.590262) (xy 91.198263 -272.635325) (xy 91.16769 -272.676011)
			(xy 91.130986 -272.711266) (xy 91.089102 -272.740176) (xy 91.043123 -272.761993) (xy 90.994239 -272.776153)
			(xy 90.943718 -272.782287) (xy 90.892866 -272.780238) (xy 90.843002 -272.770058) (xy 90.795416 -272.752011)
			(xy 90.751342 -272.726565) (xy 90.71192 -272.694378) (xy 90.678172 -272.656284) (xy 90.650971 -272.61327)
			(xy 90.631023 -272.56645) (xy 90.618844 -272.517036) (xy 90.614749 -272.466308) (xy 90.296238 -272.466308)
			(xy 90.295743 -272.490915) (xy 90.287848 -272.539492) (xy 90.272264 -272.586173) (xy 90.249393 -272.62975)
			(xy 90.219828 -272.669094) (xy 90.184335 -272.703186) (xy 90.143832 -272.731142) (xy 90.09937 -272.75224)
			(xy 90.052099 -272.765932) (xy 90.003244 -272.771864) (xy 89.954069 -272.769883) (xy 89.90585 -272.760039)
			(xy 89.859834 -272.742587) (xy 89.817213 -272.71798) (xy 89.779092 -272.686855) (xy 89.746457 -272.650018)
			(xy 89.720154 -272.608422) (xy 89.700863 -272.563146) (xy 89.689086 -272.515362) (xy 89.685126 -272.466308)
			(xy 89.356438 -272.466308) (xy 89.355943 -272.490915) (xy 89.348048 -272.539492) (xy 89.332464 -272.586173)
			(xy 89.309593 -272.62975) (xy 89.280028 -272.669094) (xy 89.244535 -272.703186) (xy 89.204032 -272.731142)
			(xy 89.15957 -272.75224) (xy 89.112299 -272.765932) (xy 89.063444 -272.771864) (xy 89.014269 -272.769883)
			(xy 88.96605 -272.760039) (xy 88.920034 -272.742587) (xy 88.877413 -272.71798) (xy 88.839292 -272.686855)
			(xy 88.806657 -272.650018) (xy 88.780354 -272.608422) (xy 88.761063 -272.563146) (xy 88.749286 -272.515362)
			(xy 88.745326 -272.466308) (xy 88.416384 -272.466308) (xy 88.415889 -272.490915) (xy 88.407994 -272.539492)
			(xy 88.39241 -272.586173) (xy 88.369539 -272.62975) (xy 88.339974 -272.669094) (xy 88.304481 -272.703186)
			(xy 88.263978 -272.731142) (xy 88.219516 -272.75224) (xy 88.172245 -272.765932) (xy 88.12339 -272.771864)
			(xy 88.074215 -272.769883) (xy 88.025996 -272.760039) (xy 87.97998 -272.742587) (xy 87.937359 -272.71798)
			(xy 87.899238 -272.686855) (xy 87.866603 -272.650018) (xy 87.8403 -272.608422) (xy 87.821009 -272.563146)
			(xy 87.809232 -272.515362) (xy 87.805272 -272.466308) (xy 87.47633 -272.466308) (xy 87.475859 -272.490299)
			(xy 87.468352 -272.537691) (xy 87.453524 -272.583326) (xy 87.43174 -272.626079) (xy 87.403537 -272.664898)
			(xy 87.369609 -272.698828) (xy 87.330791 -272.727033) (xy 87.288039 -272.748819) (xy 87.242405 -272.763649)
			(xy 87.195013 -272.771158) (xy 87.171022 -272.771616) (xy 87.159613 -272.771541) (xy 87.136856 -272.769887)
			(xy 87.125556 -272.768314) (xy 87.114634 -272.766536) (xy 87.09279 -272.772886) (xy 87.065358 -272.796762)
			(xy 87.06485 -272.79727) (xy 87.030814 -272.82648) (xy 87.02929 -272.82775) (xy 87.024972 -272.832068)
			(xy 87.017606 -272.83918) (xy 87.009986 -272.857976) (xy 87.009986 -273.157696) (xy 87.01278 -273.166078)
			(xy 87.021612 -273.19278) (xy 87.031195 -273.248196) (xy 87.03183 -273.276314) (xy 87.335118 -273.276314)
			(xy 87.339078 -273.22726) (xy 87.350855 -273.179476) (xy 87.370146 -273.1342) (xy 87.396449 -273.092604)
			(xy 87.429084 -273.055767) (xy 87.467205 -273.024642) (xy 87.509826 -273.000035) (xy 87.555842 -272.982583)
			(xy 87.604061 -272.972739) (xy 87.653236 -272.970758) (xy 87.702091 -272.97669) (xy 87.749362 -272.990382)
			(xy 87.793824 -273.01148) (xy 87.834327 -273.039436) (xy 87.86982 -273.073528) (xy 87.899385 -273.112872)
			(xy 87.922256 -273.156449) (xy 87.93784 -273.20313) (xy 87.945735 -273.251707) (xy 87.94623 -273.276314)
			(xy 88.275172 -273.276314) (xy 88.279132 -273.22726) (xy 88.290909 -273.179476) (xy 88.3102 -273.1342)
			(xy 88.336503 -273.092604) (xy 88.369138 -273.055767) (xy 88.407259 -273.024642) (xy 88.44988 -273.000035)
			(xy 88.495896 -272.982583) (xy 88.544115 -272.972739) (xy 88.59329 -272.970758) (xy 88.642145 -272.97669)
			(xy 88.689416 -272.990382) (xy 88.733878 -273.01148) (xy 88.774381 -273.039436) (xy 88.809874 -273.073528)
			(xy 88.839439 -273.112872) (xy 88.86231 -273.156449) (xy 88.877894 -273.20313) (xy 88.885789 -273.251707)
			(xy 88.886284 -273.276314) (xy 89.215226 -273.276314) (xy 89.219186 -273.22726) (xy 89.230963 -273.179476)
			(xy 89.250254 -273.1342) (xy 89.276557 -273.092604) (xy 89.309192 -273.055767) (xy 89.347313 -273.024642)
			(xy 89.389934 -273.000035) (xy 89.43595 -272.982583) (xy 89.484169 -272.972739) (xy 89.533344 -272.970758)
			(xy 89.582199 -272.97669) (xy 89.62947 -272.990382) (xy 89.673932 -273.01148) (xy 89.714435 -273.039436)
			(xy 89.749928 -273.073528) (xy 89.779493 -273.112872) (xy 89.802364 -273.156449) (xy 89.817948 -273.20313)
			(xy 89.825843 -273.251707) (xy 89.826338 -273.276314) (xy 90.15528 -273.276314) (xy 90.15924 -273.22726)
			(xy 90.171017 -273.179476) (xy 90.190308 -273.1342) (xy 90.216611 -273.092604) (xy 90.249246 -273.055767)
			(xy 90.287367 -273.024642) (xy 90.329988 -273.000035) (xy 90.376004 -272.982583) (xy 90.424223 -272.972739)
			(xy 90.473398 -272.970758) (xy 90.522253 -272.97669) (xy 90.569524 -272.990382) (xy 90.613986 -273.01148)
			(xy 90.654489 -273.039436) (xy 90.689982 -273.073528) (xy 90.719547 -273.112872) (xy 90.742418 -273.156449)
			(xy 90.758002 -273.20313) (xy 90.765897 -273.251707) (xy 90.766392 -273.276314) (xy 91.084903 -273.276314)
			(xy 91.088998 -273.225586) (xy 91.101177 -273.176172) (xy 91.121125 -273.129352) (xy 91.148326 -273.086338)
			(xy 91.182074 -273.048244) (xy 91.221496 -273.016057) (xy 91.26557 -272.990611) (xy 91.313156 -272.972564)
			(xy 91.36302 -272.962384) (xy 91.413872 -272.960335) (xy 91.464393 -272.966469) (xy 91.513277 -272.980629)
			(xy 91.559256 -273.002446) (xy 91.60114 -273.031356) (xy 91.637844 -273.066611) (xy 91.668417 -273.107297)
			(xy 91.692068 -273.15236) (xy 91.708184 -273.200634) (xy 91.716348 -273.250868) (xy 91.71686 -273.276314)
			(xy 92.024703 -273.276314) (xy 92.028798 -273.225586) (xy 92.040977 -273.176172) (xy 92.060925 -273.129352)
			(xy 92.088126 -273.086338) (xy 92.121874 -273.048244) (xy 92.161296 -273.016057) (xy 92.20537 -272.990611)
			(xy 92.252956 -272.972564) (xy 92.30282 -272.962384) (xy 92.353672 -272.960335) (xy 92.404193 -272.966469)
			(xy 92.453077 -272.980629) (xy 92.499056 -273.002446) (xy 92.54094 -273.031356) (xy 92.577644 -273.066611)
			(xy 92.608217 -273.107297) (xy 92.631868 -273.15236) (xy 92.647984 -273.200634) (xy 92.656148 -273.250868)
			(xy 92.65666 -273.276314) (xy 93.904811 -273.276314) (xy 93.908906 -273.225586) (xy 93.921085 -273.176172)
			(xy 93.941033 -273.129352) (xy 93.968234 -273.086338) (xy 94.001982 -273.048244) (xy 94.041404 -273.016057)
			(xy 94.085478 -272.990611) (xy 94.133064 -272.972564) (xy 94.182928 -272.962384) (xy 94.23378 -272.960335)
			(xy 94.284301 -272.966469) (xy 94.333185 -272.980629) (xy 94.379164 -273.002446) (xy 94.421048 -273.031356)
			(xy 94.457752 -273.066611) (xy 94.488325 -273.107297) (xy 94.511976 -273.15236) (xy 94.528092 -273.200634)
			(xy 94.536256 -273.250868) (xy 94.536768 -273.276314) (xy 94.855296 -273.276314) (xy 94.859256 -273.22726)
			(xy 94.871033 -273.179476) (xy 94.890324 -273.1342) (xy 94.916627 -273.092604) (xy 94.949262 -273.055767)
			(xy 94.987383 -273.024642) (xy 95.030004 -273.000035) (xy 95.07602 -272.982583) (xy 95.124239 -272.972739)
			(xy 95.173414 -272.970758) (xy 95.222269 -272.97669) (xy 95.26954 -272.990382) (xy 95.314002 -273.01148)
			(xy 95.354505 -273.039436) (xy 95.389998 -273.073528) (xy 95.419563 -273.112872) (xy 95.442434 -273.156449)
			(xy 95.458018 -273.20313) (xy 95.465913 -273.251707) (xy 95.466408 -273.276314) (xy 95.784919 -273.276314)
			(xy 95.789014 -273.225586) (xy 95.801193 -273.176172) (xy 95.821141 -273.129352) (xy 95.848342 -273.086338)
			(xy 95.88209 -273.048244) (xy 95.921512 -273.016057) (xy 95.965586 -272.990611) (xy 96.013172 -272.972564)
			(xy 96.063036 -272.962384) (xy 96.113888 -272.960335) (xy 96.164409 -272.966469) (xy 96.213293 -272.980629)
			(xy 96.259272 -273.002446) (xy 96.301156 -273.031356) (xy 96.33786 -273.066611) (xy 96.368433 -273.107297)
			(xy 96.392084 -273.15236) (xy 96.4082 -273.200634) (xy 96.416364 -273.250868) (xy 96.416876 -273.276314)
			(xy 96.416364 -273.30176) (xy 96.4082 -273.351994) (xy 96.392084 -273.400268) (xy 96.368433 -273.445331)
			(xy 96.33786 -273.486017) (xy 96.301156 -273.521272) (xy 96.259272 -273.550182) (xy 96.213293 -273.571999)
			(xy 96.164409 -273.586159) (xy 96.113888 -273.592293) (xy 96.063036 -273.590244) (xy 96.013172 -273.580064)
			(xy 95.965586 -273.562017) (xy 95.921512 -273.536571) (xy 95.88209 -273.504384) (xy 95.848342 -273.46629)
			(xy 95.821141 -273.423276) (xy 95.801193 -273.376456) (xy 95.789014 -273.327042) (xy 95.784919 -273.276314)
			(xy 95.466408 -273.276314) (xy 95.465913 -273.300921) (xy 95.458018 -273.349498) (xy 95.442434 -273.396179)
			(xy 95.419563 -273.439756) (xy 95.389998 -273.4791) (xy 95.354505 -273.513192) (xy 95.314002 -273.541148)
			(xy 95.26954 -273.562246) (xy 95.222269 -273.575938) (xy 95.173414 -273.58187) (xy 95.124239 -273.579889)
			(xy 95.07602 -273.570045) (xy 95.030004 -273.552593) (xy 94.987383 -273.527986) (xy 94.949262 -273.496861)
			(xy 94.916627 -273.460024) (xy 94.890324 -273.418428) (xy 94.871033 -273.373152) (xy 94.859256 -273.325368)
			(xy 94.855296 -273.276314) (xy 94.536768 -273.276314) (xy 94.536256 -273.30176) (xy 94.528092 -273.351994)
			(xy 94.511976 -273.400268) (xy 94.488325 -273.445331) (xy 94.457752 -273.486017) (xy 94.421048 -273.521272)
			(xy 94.379164 -273.550182) (xy 94.333185 -273.571999) (xy 94.284301 -273.586159) (xy 94.23378 -273.592293)
			(xy 94.182928 -273.590244) (xy 94.133064 -273.580064) (xy 94.085478 -273.562017) (xy 94.041404 -273.536571)
			(xy 94.001982 -273.504384) (xy 93.968234 -273.46629) (xy 93.941033 -273.423276) (xy 93.921085 -273.376456)
			(xy 93.908906 -273.327042) (xy 93.904811 -273.276314) (xy 92.65666 -273.276314) (xy 92.656148 -273.30176)
			(xy 92.647984 -273.351994) (xy 92.631868 -273.400268) (xy 92.608217 -273.445331) (xy 92.577644 -273.486017)
			(xy 92.54094 -273.521272) (xy 92.499056 -273.550182) (xy 92.453077 -273.571999) (xy 92.404193 -273.586159)
			(xy 92.353672 -273.592293) (xy 92.30282 -273.590244) (xy 92.252956 -273.580064) (xy 92.20537 -273.562017)
			(xy 92.161296 -273.536571) (xy 92.121874 -273.504384) (xy 92.088126 -273.46629) (xy 92.060925 -273.423276)
			(xy 92.040977 -273.376456) (xy 92.028798 -273.327042) (xy 92.024703 -273.276314) (xy 91.71686 -273.276314)
			(xy 91.716348 -273.30176) (xy 91.708184 -273.351994) (xy 91.692068 -273.400268) (xy 91.668417 -273.445331)
			(xy 91.637844 -273.486017) (xy 91.60114 -273.521272) (xy 91.559256 -273.550182) (xy 91.513277 -273.571999)
			(xy 91.464393 -273.586159) (xy 91.413872 -273.592293) (xy 91.36302 -273.590244) (xy 91.313156 -273.580064)
			(xy 91.26557 -273.562017) (xy 91.221496 -273.536571) (xy 91.182074 -273.504384) (xy 91.148326 -273.46629)
			(xy 91.121125 -273.423276) (xy 91.101177 -273.376456) (xy 91.088998 -273.327042) (xy 91.084903 -273.276314)
			(xy 90.766392 -273.276314) (xy 90.765897 -273.300921) (xy 90.758002 -273.349498) (xy 90.742418 -273.396179)
			(xy 90.719547 -273.439756) (xy 90.689982 -273.4791) (xy 90.654489 -273.513192) (xy 90.613986 -273.541148)
			(xy 90.569524 -273.562246) (xy 90.522253 -273.575938) (xy 90.473398 -273.58187) (xy 90.424223 -273.579889)
			(xy 90.376004 -273.570045) (xy 90.329988 -273.552593) (xy 90.287367 -273.527986) (xy 90.249246 -273.496861)
			(xy 90.216611 -273.460024) (xy 90.190308 -273.418428) (xy 90.171017 -273.373152) (xy 90.15924 -273.325368)
			(xy 90.15528 -273.276314) (xy 89.826338 -273.276314) (xy 89.825843 -273.300921) (xy 89.817948 -273.349498)
			(xy 89.802364 -273.396179) (xy 89.779493 -273.439756) (xy 89.749928 -273.4791) (xy 89.714435 -273.513192)
			(xy 89.673932 -273.541148) (xy 89.62947 -273.562246) (xy 89.582199 -273.575938) (xy 89.533344 -273.58187)
			(xy 89.484169 -273.579889) (xy 89.43595 -273.570045) (xy 89.389934 -273.552593) (xy 89.347313 -273.527986)
			(xy 89.309192 -273.496861) (xy 89.276557 -273.460024) (xy 89.250254 -273.418428) (xy 89.230963 -273.373152)
			(xy 89.219186 -273.325368) (xy 89.215226 -273.276314) (xy 88.886284 -273.276314) (xy 88.885789 -273.300921)
			(xy 88.877894 -273.349498) (xy 88.86231 -273.396179) (xy 88.839439 -273.439756) (xy 88.809874 -273.4791)
			(xy 88.774381 -273.513192) (xy 88.733878 -273.541148) (xy 88.689416 -273.562246) (xy 88.642145 -273.575938)
			(xy 88.59329 -273.58187) (xy 88.544115 -273.579889) (xy 88.495896 -273.570045) (xy 88.44988 -273.552593)
			(xy 88.407259 -273.527986) (xy 88.369138 -273.496861) (xy 88.336503 -273.460024) (xy 88.3102 -273.418428)
			(xy 88.290909 -273.373152) (xy 88.279132 -273.325368) (xy 88.275172 -273.276314) (xy 87.94623 -273.276314)
			(xy 87.945735 -273.300921) (xy 87.93784 -273.349498) (xy 87.922256 -273.396179) (xy 87.899385 -273.439756)
			(xy 87.86982 -273.4791) (xy 87.834327 -273.513192) (xy 87.793824 -273.541148) (xy 87.749362 -273.562246)
			(xy 87.702091 -273.575938) (xy 87.653236 -273.58187) (xy 87.604061 -273.579889) (xy 87.555842 -273.570045)
			(xy 87.509826 -273.552593) (xy 87.467205 -273.527986) (xy 87.429084 -273.496861) (xy 87.396449 -273.460024)
			(xy 87.370146 -273.418428) (xy 87.350855 -273.373152) (xy 87.339078 -273.325368) (xy 87.335118 -273.276314)
			(xy 87.03183 -273.276314) (xy 87.031247 -273.304437) (xy 87.021669 -273.359862) (xy 87.01278 -273.38655)
			(xy 87.009986 -273.394932) (xy 87.009986 -273.685) (xy 87.010365 -273.694102) (xy 87.016753 -273.711149)
			(xy 87.022432 -273.718274) (xy 87.024972 -273.721068) (xy 87.065104 -273.755612) (xy 87.080344 -273.76882)
			(xy 87.081614 -273.769836) (xy 87.088576 -273.775041) (xy 87.104934 -273.780888) (xy 87.113618 -273.781266)
			(xy 87.159592 -273.781266) (xy 87.171022 -273.781012) (xy 87.171276 -273.781012) (xy 87.195252 -273.781503)
			(xy 87.24261 -273.789044) (xy 87.288205 -273.803896) (xy 87.330918 -273.825694) (xy 87.369698 -273.853903)
			(xy 87.40359 -273.887828) (xy 87.431761 -273.926634) (xy 87.453518 -273.969368) (xy 87.468326 -274.014979)
			(xy 87.47582 -274.062343) (xy 87.47633 -274.08632) (xy 87.805272 -274.08632) (xy 87.809232 -274.037266)
			(xy 87.821009 -273.989482) (xy 87.8403 -273.944206) (xy 87.866603 -273.90261) (xy 87.899238 -273.865773)
			(xy 87.937359 -273.834648) (xy 87.97998 -273.810041) (xy 88.025996 -273.792589) (xy 88.074215 -273.782745)
			(xy 88.12339 -273.780764) (xy 88.172245 -273.786696) (xy 88.219516 -273.800388) (xy 88.263978 -273.821486)
			(xy 88.304481 -273.849442) (xy 88.339974 -273.883534) (xy 88.369539 -273.922878) (xy 88.39241 -273.966455)
			(xy 88.407994 -274.013136) (xy 88.415889 -274.061713) (xy 88.416384 -274.08632) (xy 88.745326 -274.08632)
			(xy 88.749286 -274.037266) (xy 88.761063 -273.989482) (xy 88.780354 -273.944206) (xy 88.806657 -273.90261)
			(xy 88.839292 -273.865773) (xy 88.877413 -273.834648) (xy 88.920034 -273.810041) (xy 88.96605 -273.792589)
			(xy 89.014269 -273.782745) (xy 89.063444 -273.780764) (xy 89.112299 -273.786696) (xy 89.15957 -273.800388)
			(xy 89.204032 -273.821486) (xy 89.244535 -273.849442) (xy 89.280028 -273.883534) (xy 89.309593 -273.922878)
			(xy 89.332464 -273.966455) (xy 89.348048 -274.013136) (xy 89.355943 -274.061713) (xy 89.356438 -274.08632)
			(xy 89.685126 -274.08632) (xy 89.689086 -274.037266) (xy 89.700863 -273.989482) (xy 89.720154 -273.944206)
			(xy 89.746457 -273.90261) (xy 89.779092 -273.865773) (xy 89.817213 -273.834648) (xy 89.859834 -273.810041)
			(xy 89.90585 -273.792589) (xy 89.954069 -273.782745) (xy 90.003244 -273.780764) (xy 90.052099 -273.786696)
			(xy 90.09937 -273.800388) (xy 90.143832 -273.821486) (xy 90.184335 -273.849442) (xy 90.219828 -273.883534)
			(xy 90.249393 -273.922878) (xy 90.272264 -273.966455) (xy 90.287848 -274.013136) (xy 90.295743 -274.061713)
			(xy 90.296238 -274.08632) (xy 90.614749 -274.08632) (xy 90.618844 -274.035592) (xy 90.631023 -273.986178)
			(xy 90.650971 -273.939358) (xy 90.678172 -273.896344) (xy 90.71192 -273.85825) (xy 90.751342 -273.826063)
			(xy 90.795416 -273.800617) (xy 90.843002 -273.78257) (xy 90.892866 -273.77239) (xy 90.943718 -273.770341)
			(xy 90.994239 -273.776475) (xy 91.043123 -273.790635) (xy 91.089102 -273.812452) (xy 91.130986 -273.841362)
			(xy 91.16769 -273.876617) (xy 91.198263 -273.917303) (xy 91.221914 -273.962366) (xy 91.23803 -274.01064)
			(xy 91.246194 -274.060874) (xy 91.246706 -274.08632) (xy 91.565234 -274.08632) (xy 91.569194 -274.037266)
			(xy 91.580971 -273.989482) (xy 91.600262 -273.944206) (xy 91.626565 -273.90261) (xy 91.6592 -273.865773)
			(xy 91.697321 -273.834648) (xy 91.739942 -273.810041) (xy 91.785958 -273.792589) (xy 91.834177 -273.782745)
			(xy 91.883352 -273.780764) (xy 91.932207 -273.786696) (xy 91.979478 -273.800388) (xy 92.02394 -273.821486)
			(xy 92.064443 -273.849442) (xy 92.099936 -273.883534) (xy 92.129501 -273.922878) (xy 92.152372 -273.966455)
			(xy 92.167956 -274.013136) (xy 92.175851 -274.061713) (xy 92.176346 -274.08632) (xy 92.494857 -274.08632)
			(xy 92.498952 -274.035592) (xy 92.511131 -273.986178) (xy 92.531079 -273.939358) (xy 92.55828 -273.896344)
			(xy 92.592028 -273.85825) (xy 92.63145 -273.826063) (xy 92.675524 -273.800617) (xy 92.72311 -273.78257)
			(xy 92.772974 -273.77239) (xy 92.823826 -273.770341) (xy 92.874347 -273.776475) (xy 92.923231 -273.790635)
			(xy 92.96921 -273.812452) (xy 93.011094 -273.841362) (xy 93.047798 -273.876617) (xy 93.078371 -273.917303)
			(xy 93.102022 -273.962366) (xy 93.118138 -274.01064) (xy 93.126302 -274.060874) (xy 93.126814 -274.08632)
			(xy 93.445342 -274.08632) (xy 93.449302 -274.037266) (xy 93.461079 -273.989482) (xy 93.48037 -273.944206)
			(xy 93.506673 -273.90261) (xy 93.539308 -273.865773) (xy 93.577429 -273.834648) (xy 93.62005 -273.810041)
			(xy 93.666066 -273.792589) (xy 93.714285 -273.782745) (xy 93.76346 -273.780764) (xy 93.812315 -273.786696)
			(xy 93.859586 -273.800388) (xy 93.904048 -273.821486) (xy 93.944551 -273.849442) (xy 93.980044 -273.883534)
			(xy 94.009609 -273.922878) (xy 94.03248 -273.966455) (xy 94.048064 -274.013136) (xy 94.055959 -274.061713)
			(xy 94.056454 -274.08632) (xy 94.374711 -274.08632) (xy 94.378806 -274.035592) (xy 94.390985 -273.986178)
			(xy 94.410933 -273.939358) (xy 94.438134 -273.896344) (xy 94.471882 -273.85825) (xy 94.511304 -273.826063)
			(xy 94.555378 -273.800617) (xy 94.602964 -273.78257) (xy 94.652828 -273.77239) (xy 94.70368 -273.770341)
			(xy 94.754201 -273.776475) (xy 94.803085 -273.790635) (xy 94.849064 -273.812452) (xy 94.890948 -273.841362)
			(xy 94.927652 -273.876617) (xy 94.958225 -273.917303) (xy 94.981876 -273.962366) (xy 94.997992 -274.01064)
			(xy 95.006156 -274.060874) (xy 95.006668 -274.08632) (xy 95.314765 -274.08632) (xy 95.31886 -274.035592)
			(xy 95.331039 -273.986178) (xy 95.350987 -273.939358) (xy 95.378188 -273.896344) (xy 95.411936 -273.85825)
			(xy 95.451358 -273.826063) (xy 95.495432 -273.800617) (xy 95.543018 -273.78257) (xy 95.592882 -273.77239)
			(xy 95.643734 -273.770341) (xy 95.694255 -273.776475) (xy 95.743139 -273.790635) (xy 95.789118 -273.812452)
			(xy 95.831002 -273.841362) (xy 95.867706 -273.876617) (xy 95.898279 -273.917303) (xy 95.92193 -273.962366)
			(xy 95.938046 -274.01064) (xy 95.94621 -274.060874) (xy 95.946722 -274.08632) (xy 95.94621 -274.111766)
			(xy 95.938046 -274.162) (xy 95.92193 -274.210274) (xy 95.898279 -274.255337) (xy 95.867706 -274.296023)
			(xy 95.831002 -274.331278) (xy 95.789118 -274.360188) (xy 95.743139 -274.382005) (xy 95.694255 -274.396165)
			(xy 95.643734 -274.402299) (xy 95.592882 -274.40025) (xy 95.543018 -274.39007) (xy 95.495432 -274.372023)
			(xy 95.451358 -274.346577) (xy 95.411936 -274.31439) (xy 95.378188 -274.276296) (xy 95.350987 -274.233282)
			(xy 95.331039 -274.186462) (xy 95.31886 -274.137048) (xy 95.314765 -274.08632) (xy 95.006668 -274.08632)
			(xy 95.006156 -274.111766) (xy 94.997992 -274.162) (xy 94.981876 -274.210274) (xy 94.958225 -274.255337)
			(xy 94.927652 -274.296023) (xy 94.890948 -274.331278) (xy 94.849064 -274.360188) (xy 94.803085 -274.382005)
			(xy 94.754201 -274.396165) (xy 94.70368 -274.402299) (xy 94.652828 -274.40025) (xy 94.602964 -274.39007)
			(xy 94.555378 -274.372023) (xy 94.511304 -274.346577) (xy 94.471882 -274.31439) (xy 94.438134 -274.276296)
			(xy 94.410933 -274.233282) (xy 94.390985 -274.186462) (xy 94.378806 -274.137048) (xy 94.374711 -274.08632)
			(xy 94.056454 -274.08632) (xy 94.055959 -274.110927) (xy 94.048064 -274.159504) (xy 94.03248 -274.206185)
			(xy 94.009609 -274.249762) (xy 93.980044 -274.289106) (xy 93.944551 -274.323198) (xy 93.904048 -274.351154)
			(xy 93.859586 -274.372252) (xy 93.812315 -274.385944) (xy 93.76346 -274.391876) (xy 93.714285 -274.389895)
			(xy 93.666066 -274.380051) (xy 93.62005 -274.362599) (xy 93.577429 -274.337992) (xy 93.539308 -274.306867)
			(xy 93.506673 -274.27003) (xy 93.48037 -274.228434) (xy 93.461079 -274.183158) (xy 93.449302 -274.135374)
			(xy 93.445342 -274.08632) (xy 93.126814 -274.08632) (xy 93.126302 -274.111766) (xy 93.118138 -274.162)
			(xy 93.102022 -274.210274) (xy 93.078371 -274.255337) (xy 93.047798 -274.296023) (xy 93.011094 -274.331278)
			(xy 92.96921 -274.360188) (xy 92.923231 -274.382005) (xy 92.874347 -274.396165) (xy 92.823826 -274.402299)
			(xy 92.772974 -274.40025) (xy 92.72311 -274.39007) (xy 92.675524 -274.372023) (xy 92.63145 -274.346577)
			(xy 92.592028 -274.31439) (xy 92.55828 -274.276296) (xy 92.531079 -274.233282) (xy 92.511131 -274.186462)
			(xy 92.498952 -274.137048) (xy 92.494857 -274.08632) (xy 92.176346 -274.08632) (xy 92.175851 -274.110927)
			(xy 92.167956 -274.159504) (xy 92.152372 -274.206185) (xy 92.129501 -274.249762) (xy 92.099936 -274.289106)
			(xy 92.064443 -274.323198) (xy 92.02394 -274.351154) (xy 91.979478 -274.372252) (xy 91.932207 -274.385944)
			(xy 91.883352 -274.391876) (xy 91.834177 -274.389895) (xy 91.785958 -274.380051) (xy 91.739942 -274.362599)
			(xy 91.697321 -274.337992) (xy 91.6592 -274.306867) (xy 91.626565 -274.27003) (xy 91.600262 -274.228434)
			(xy 91.580971 -274.183158) (xy 91.569194 -274.135374) (xy 91.565234 -274.08632) (xy 91.246706 -274.08632)
			(xy 91.246194 -274.111766) (xy 91.23803 -274.162) (xy 91.221914 -274.210274) (xy 91.198263 -274.255337)
			(xy 91.16769 -274.296023) (xy 91.130986 -274.331278) (xy 91.089102 -274.360188) (xy 91.043123 -274.382005)
			(xy 90.994239 -274.396165) (xy 90.943718 -274.402299) (xy 90.892866 -274.40025) (xy 90.843002 -274.39007)
			(xy 90.795416 -274.372023) (xy 90.751342 -274.346577) (xy 90.71192 -274.31439) (xy 90.678172 -274.276296)
			(xy 90.650971 -274.233282) (xy 90.631023 -274.186462) (xy 90.618844 -274.137048) (xy 90.614749 -274.08632)
			(xy 90.296238 -274.08632) (xy 90.295743 -274.110927) (xy 90.287848 -274.159504) (xy 90.272264 -274.206185)
			(xy 90.249393 -274.249762) (xy 90.219828 -274.289106) (xy 90.184335 -274.323198) (xy 90.143832 -274.351154)
			(xy 90.09937 -274.372252) (xy 90.052099 -274.385944) (xy 90.003244 -274.391876) (xy 89.954069 -274.389895)
			(xy 89.90585 -274.380051) (xy 89.859834 -274.362599) (xy 89.817213 -274.337992) (xy 89.779092 -274.306867)
			(xy 89.746457 -274.27003) (xy 89.720154 -274.228434) (xy 89.700863 -274.183158) (xy 89.689086 -274.135374)
			(xy 89.685126 -274.08632) (xy 89.356438 -274.08632) (xy 89.355943 -274.110927) (xy 89.348048 -274.159504)
			(xy 89.332464 -274.206185) (xy 89.309593 -274.249762) (xy 89.280028 -274.289106) (xy 89.244535 -274.323198)
			(xy 89.204032 -274.351154) (xy 89.15957 -274.372252) (xy 89.112299 -274.385944) (xy 89.063444 -274.391876)
			(xy 89.014269 -274.389895) (xy 88.96605 -274.380051) (xy 88.920034 -274.362599) (xy 88.877413 -274.337992)
			(xy 88.839292 -274.306867) (xy 88.806657 -274.27003) (xy 88.780354 -274.228434) (xy 88.761063 -274.183158)
			(xy 88.749286 -274.135374) (xy 88.745326 -274.08632) (xy 88.416384 -274.08632) (xy 88.415889 -274.110927)
			(xy 88.407994 -274.159504) (xy 88.39241 -274.206185) (xy 88.369539 -274.249762) (xy 88.339974 -274.289106)
			(xy 88.304481 -274.323198) (xy 88.263978 -274.351154) (xy 88.219516 -274.372252) (xy 88.172245 -274.385944)
			(xy 88.12339 -274.391876) (xy 88.074215 -274.389895) (xy 88.025996 -274.380051) (xy 87.97998 -274.362599)
			(xy 87.937359 -274.337992) (xy 87.899238 -274.306867) (xy 87.866603 -274.27003) (xy 87.8403 -274.228434)
			(xy 87.821009 -274.183158) (xy 87.809232 -274.135374) (xy 87.805272 -274.08632) (xy 87.47633 -274.08632)
			(xy 87.475858 -274.110311) (xy 87.468349 -274.157701) (xy 87.453521 -274.203334) (xy 87.431736 -274.246086)
			(xy 87.403533 -274.284903) (xy 87.369605 -274.318832) (xy 87.330787 -274.347035) (xy 87.288036 -274.36882)
			(xy 87.242403 -274.383649) (xy 87.195013 -274.391158) (xy 87.171022 -274.391628) (xy 87.159613 -274.391553)
			(xy 87.136856 -274.389899) (xy 87.125556 -274.388326) (xy 87.114634 -274.386548) (xy 87.09279 -274.392898)
			(xy 87.065358 -274.416774) (xy 87.06485 -274.417282) (xy 87.030814 -274.446492) (xy 87.02929 -274.447762)
			(xy 87.024972 -274.45208) (xy 87.017606 -274.459192) (xy 87.009986 -274.477988) (xy 87.009986 -274.896326)
			(xy 87.335118 -274.896326) (xy 87.339078 -274.847272) (xy 87.350855 -274.799488) (xy 87.370146 -274.754212)
			(xy 87.396449 -274.712616) (xy 87.429084 -274.675779) (xy 87.467205 -274.644654) (xy 87.509826 -274.620047)
			(xy 87.555842 -274.602595) (xy 87.604061 -274.592751) (xy 87.653236 -274.59077) (xy 87.702091 -274.596702)
			(xy 87.749362 -274.610394) (xy 87.793824 -274.631492) (xy 87.834327 -274.659448) (xy 87.86982 -274.69354)
			(xy 87.899385 -274.732884) (xy 87.922256 -274.776461) (xy 87.93784 -274.823142) (xy 87.945735 -274.871719)
			(xy 87.94623 -274.896326) (xy 88.275172 -274.896326) (xy 88.279132 -274.847272) (xy 88.290909 -274.799488)
			(xy 88.3102 -274.754212) (xy 88.336503 -274.712616) (xy 88.369138 -274.675779) (xy 88.407259 -274.644654)
			(xy 88.44988 -274.620047) (xy 88.495896 -274.602595) (xy 88.544115 -274.592751) (xy 88.59329 -274.59077)
			(xy 88.642145 -274.596702) (xy 88.689416 -274.610394) (xy 88.733878 -274.631492) (xy 88.774381 -274.659448)
			(xy 88.809874 -274.69354) (xy 88.839439 -274.732884) (xy 88.86231 -274.776461) (xy 88.877894 -274.823142)
			(xy 88.885789 -274.871719) (xy 88.886284 -274.896326) (xy 89.215226 -274.896326) (xy 89.219186 -274.847272)
			(xy 89.230963 -274.799488) (xy 89.250254 -274.754212) (xy 89.276557 -274.712616) (xy 89.309192 -274.675779)
			(xy 89.347313 -274.644654) (xy 89.389934 -274.620047) (xy 89.43595 -274.602595) (xy 89.484169 -274.592751)
			(xy 89.533344 -274.59077) (xy 89.582199 -274.596702) (xy 89.62947 -274.610394) (xy 89.673932 -274.631492)
			(xy 89.714435 -274.659448) (xy 89.749928 -274.69354) (xy 89.779493 -274.732884) (xy 89.802364 -274.776461)
			(xy 89.817948 -274.823142) (xy 89.825843 -274.871719) (xy 89.826338 -274.896326) (xy 90.15528 -274.896326)
			(xy 90.15924 -274.847272) (xy 90.171017 -274.799488) (xy 90.190308 -274.754212) (xy 90.216611 -274.712616)
			(xy 90.249246 -274.675779) (xy 90.287367 -274.644654) (xy 90.329988 -274.620047) (xy 90.376004 -274.602595)
			(xy 90.424223 -274.592751) (xy 90.473398 -274.59077) (xy 90.522253 -274.596702) (xy 90.569524 -274.610394)
			(xy 90.613986 -274.631492) (xy 90.654489 -274.659448) (xy 90.689982 -274.69354) (xy 90.719547 -274.732884)
			(xy 90.742418 -274.776461) (xy 90.758002 -274.823142) (xy 90.765897 -274.871719) (xy 90.766392 -274.896326)
			(xy 91.084903 -274.896326) (xy 91.088998 -274.845598) (xy 91.101177 -274.796184) (xy 91.121125 -274.749364)
			(xy 91.148326 -274.70635) (xy 91.182074 -274.668256) (xy 91.221496 -274.636069) (xy 91.26557 -274.610623)
			(xy 91.313156 -274.592576) (xy 91.36302 -274.582396) (xy 91.413872 -274.580347) (xy 91.464393 -274.586481)
			(xy 91.513277 -274.600641) (xy 91.559256 -274.622458) (xy 91.60114 -274.651368) (xy 91.637844 -274.686623)
			(xy 91.668417 -274.727309) (xy 91.692068 -274.772372) (xy 91.708184 -274.820646) (xy 91.716348 -274.87088)
			(xy 91.71686 -274.896326) (xy 92.024703 -274.896326) (xy 92.028798 -274.845598) (xy 92.040977 -274.796184)
			(xy 92.060925 -274.749364) (xy 92.088126 -274.70635) (xy 92.121874 -274.668256) (xy 92.161296 -274.636069)
			(xy 92.20537 -274.610623) (xy 92.252956 -274.592576) (xy 92.30282 -274.582396) (xy 92.353672 -274.580347)
			(xy 92.404193 -274.586481) (xy 92.453077 -274.600641) (xy 92.499056 -274.622458) (xy 92.54094 -274.651368)
			(xy 92.577644 -274.686623) (xy 92.608217 -274.727309) (xy 92.631868 -274.772372) (xy 92.647984 -274.820646)
			(xy 92.656148 -274.87088) (xy 92.65666 -274.896326) (xy 92.975188 -274.896326) (xy 92.979148 -274.847272)
			(xy 92.990925 -274.799488) (xy 93.010216 -274.754212) (xy 93.036519 -274.712616) (xy 93.069154 -274.675779)
			(xy 93.107275 -274.644654) (xy 93.149896 -274.620047) (xy 93.195912 -274.602595) (xy 93.244131 -274.592751)
			(xy 93.293306 -274.59077) (xy 93.342161 -274.596702) (xy 93.389432 -274.610394) (xy 93.433894 -274.631492)
			(xy 93.474397 -274.659448) (xy 93.50989 -274.69354) (xy 93.539455 -274.732884) (xy 93.562326 -274.776461)
			(xy 93.57791 -274.823142) (xy 93.585805 -274.871719) (xy 93.5863 -274.896326) (xy 93.904811 -274.896326)
			(xy 93.908906 -274.845598) (xy 93.921085 -274.796184) (xy 93.941033 -274.749364) (xy 93.968234 -274.70635)
			(xy 94.001982 -274.668256) (xy 94.041404 -274.636069) (xy 94.085478 -274.610623) (xy 94.133064 -274.592576)
			(xy 94.182928 -274.582396) (xy 94.23378 -274.580347) (xy 94.284301 -274.586481) (xy 94.333185 -274.600641)
			(xy 94.379164 -274.622458) (xy 94.421048 -274.651368) (xy 94.457752 -274.686623) (xy 94.488325 -274.727309)
			(xy 94.511976 -274.772372) (xy 94.528092 -274.820646) (xy 94.536256 -274.87088) (xy 94.536768 -274.896326)
			(xy 94.855296 -274.896326) (xy 94.859256 -274.847272) (xy 94.871033 -274.799488) (xy 94.890324 -274.754212)
			(xy 94.916627 -274.712616) (xy 94.949262 -274.675779) (xy 94.987383 -274.644654) (xy 95.030004 -274.620047)
			(xy 95.07602 -274.602595) (xy 95.124239 -274.592751) (xy 95.173414 -274.59077) (xy 95.222269 -274.596702)
			(xy 95.26954 -274.610394) (xy 95.314002 -274.631492) (xy 95.354505 -274.659448) (xy 95.389998 -274.69354)
			(xy 95.419563 -274.732884) (xy 95.442434 -274.776461) (xy 95.458018 -274.823142) (xy 95.465913 -274.871719)
			(xy 95.466408 -274.896326) (xy 95.784919 -274.896326) (xy 95.789014 -274.845598) (xy 95.801193 -274.796184)
			(xy 95.821141 -274.749364) (xy 95.848342 -274.70635) (xy 95.88209 -274.668256) (xy 95.921512 -274.636069)
			(xy 95.965586 -274.610623) (xy 96.013172 -274.592576) (xy 96.063036 -274.582396) (xy 96.113888 -274.580347)
			(xy 96.164409 -274.586481) (xy 96.213293 -274.600641) (xy 96.259272 -274.622458) (xy 96.301156 -274.651368)
			(xy 96.33786 -274.686623) (xy 96.368433 -274.727309) (xy 96.392084 -274.772372) (xy 96.4082 -274.820646)
			(xy 96.416364 -274.87088) (xy 96.416876 -274.896326) (xy 96.416364 -274.921772) (xy 96.4082 -274.972006)
			(xy 96.392084 -275.02028) (xy 96.368433 -275.065343) (xy 96.33786 -275.106029) (xy 96.301156 -275.141284)
			(xy 96.259272 -275.170194) (xy 96.213293 -275.192011) (xy 96.164409 -275.206171) (xy 96.113888 -275.212305)
			(xy 96.063036 -275.210256) (xy 96.013172 -275.200076) (xy 95.965586 -275.182029) (xy 95.921512 -275.156583)
			(xy 95.88209 -275.124396) (xy 95.848342 -275.086302) (xy 95.821141 -275.043288) (xy 95.801193 -274.996468)
			(xy 95.789014 -274.947054) (xy 95.784919 -274.896326) (xy 95.466408 -274.896326) (xy 95.465913 -274.920933)
			(xy 95.458018 -274.96951) (xy 95.442434 -275.016191) (xy 95.419563 -275.059768) (xy 95.389998 -275.099112)
			(xy 95.354505 -275.133204) (xy 95.314002 -275.16116) (xy 95.26954 -275.182258) (xy 95.222269 -275.19595)
			(xy 95.173414 -275.201882) (xy 95.124239 -275.199901) (xy 95.07602 -275.190057) (xy 95.030004 -275.172605)
			(xy 94.987383 -275.147998) (xy 94.949262 -275.116873) (xy 94.916627 -275.080036) (xy 94.890324 -275.03844)
			(xy 94.871033 -274.993164) (xy 94.859256 -274.94538) (xy 94.855296 -274.896326) (xy 94.536768 -274.896326)
			(xy 94.536256 -274.921772) (xy 94.528092 -274.972006) (xy 94.511976 -275.02028) (xy 94.488325 -275.065343)
			(xy 94.457752 -275.106029) (xy 94.421048 -275.141284) (xy 94.379164 -275.170194) (xy 94.333185 -275.192011)
			(xy 94.284301 -275.206171) (xy 94.23378 -275.212305) (xy 94.182928 -275.210256) (xy 94.133064 -275.200076)
			(xy 94.085478 -275.182029) (xy 94.041404 -275.156583) (xy 94.001982 -275.124396) (xy 93.968234 -275.086302)
			(xy 93.941033 -275.043288) (xy 93.921085 -274.996468) (xy 93.908906 -274.947054) (xy 93.904811 -274.896326)
			(xy 93.5863 -274.896326) (xy 93.585805 -274.920933) (xy 93.57791 -274.96951) (xy 93.562326 -275.016191)
			(xy 93.539455 -275.059768) (xy 93.50989 -275.099112) (xy 93.474397 -275.133204) (xy 93.433894 -275.16116)
			(xy 93.389432 -275.182258) (xy 93.342161 -275.19595) (xy 93.293306 -275.201882) (xy 93.244131 -275.199901)
			(xy 93.195912 -275.190057) (xy 93.149896 -275.172605) (xy 93.107275 -275.147998) (xy 93.069154 -275.116873)
			(xy 93.036519 -275.080036) (xy 93.010216 -275.03844) (xy 92.990925 -274.993164) (xy 92.979148 -274.94538)
			(xy 92.975188 -274.896326) (xy 92.65666 -274.896326) (xy 92.656148 -274.921772) (xy 92.647984 -274.972006)
			(xy 92.631868 -275.02028) (xy 92.608217 -275.065343) (xy 92.577644 -275.106029) (xy 92.54094 -275.141284)
			(xy 92.499056 -275.170194) (xy 92.453077 -275.192011) (xy 92.404193 -275.206171) (xy 92.353672 -275.212305)
			(xy 92.30282 -275.210256) (xy 92.252956 -275.200076) (xy 92.20537 -275.182029) (xy 92.161296 -275.156583)
			(xy 92.121874 -275.124396) (xy 92.088126 -275.086302) (xy 92.060925 -275.043288) (xy 92.040977 -274.996468)
			(xy 92.028798 -274.947054) (xy 92.024703 -274.896326) (xy 91.71686 -274.896326) (xy 91.716348 -274.921772)
			(xy 91.708184 -274.972006) (xy 91.692068 -275.02028) (xy 91.668417 -275.065343) (xy 91.637844 -275.106029)
			(xy 91.60114 -275.141284) (xy 91.559256 -275.170194) (xy 91.513277 -275.192011) (xy 91.464393 -275.206171)
			(xy 91.413872 -275.212305) (xy 91.36302 -275.210256) (xy 91.313156 -275.200076) (xy 91.26557 -275.182029)
			(xy 91.221496 -275.156583) (xy 91.182074 -275.124396) (xy 91.148326 -275.086302) (xy 91.121125 -275.043288)
			(xy 91.101177 -274.996468) (xy 91.088998 -274.947054) (xy 91.084903 -274.896326) (xy 90.766392 -274.896326)
			(xy 90.765897 -274.920933) (xy 90.758002 -274.96951) (xy 90.742418 -275.016191) (xy 90.719547 -275.059768)
			(xy 90.689982 -275.099112) (xy 90.654489 -275.133204) (xy 90.613986 -275.16116) (xy 90.569524 -275.182258)
			(xy 90.522253 -275.19595) (xy 90.473398 -275.201882) (xy 90.424223 -275.199901) (xy 90.376004 -275.190057)
			(xy 90.329988 -275.172605) (xy 90.287367 -275.147998) (xy 90.249246 -275.116873) (xy 90.216611 -275.080036)
			(xy 90.190308 -275.03844) (xy 90.171017 -274.993164) (xy 90.15924 -274.94538) (xy 90.15528 -274.896326)
			(xy 89.826338 -274.896326) (xy 89.825843 -274.920933) (xy 89.817948 -274.96951) (xy 89.802364 -275.016191)
			(xy 89.779493 -275.059768) (xy 89.749928 -275.099112) (xy 89.714435 -275.133204) (xy 89.673932 -275.16116)
			(xy 89.62947 -275.182258) (xy 89.582199 -275.19595) (xy 89.533344 -275.201882) (xy 89.484169 -275.199901)
			(xy 89.43595 -275.190057) (xy 89.389934 -275.172605) (xy 89.347313 -275.147998) (xy 89.309192 -275.116873)
			(xy 89.276557 -275.080036) (xy 89.250254 -275.03844) (xy 89.230963 -274.993164) (xy 89.219186 -274.94538)
			(xy 89.215226 -274.896326) (xy 88.886284 -274.896326) (xy 88.885789 -274.920933) (xy 88.877894 -274.96951)
			(xy 88.86231 -275.016191) (xy 88.839439 -275.059768) (xy 88.809874 -275.099112) (xy 88.774381 -275.133204)
			(xy 88.733878 -275.16116) (xy 88.689416 -275.182258) (xy 88.642145 -275.19595) (xy 88.59329 -275.201882)
			(xy 88.544115 -275.199901) (xy 88.495896 -275.190057) (xy 88.44988 -275.172605) (xy 88.407259 -275.147998)
			(xy 88.369138 -275.116873) (xy 88.336503 -275.080036) (xy 88.3102 -275.03844) (xy 88.290909 -274.993164)
			(xy 88.279132 -274.94538) (xy 88.275172 -274.896326) (xy 87.94623 -274.896326) (xy 87.945735 -274.920933)
			(xy 87.93784 -274.96951) (xy 87.922256 -275.016191) (xy 87.899385 -275.059768) (xy 87.86982 -275.099112)
			(xy 87.834327 -275.133204) (xy 87.793824 -275.16116) (xy 87.749362 -275.182258) (xy 87.702091 -275.19595)
			(xy 87.653236 -275.201882) (xy 87.604061 -275.199901) (xy 87.555842 -275.190057) (xy 87.509826 -275.172605)
			(xy 87.467205 -275.147998) (xy 87.429084 -275.116873) (xy 87.396449 -275.080036) (xy 87.370146 -275.03844)
			(xy 87.350855 -274.993164) (xy 87.339078 -274.94538) (xy 87.335118 -274.896326) (xy 87.009986 -274.896326)
			(xy 87.009986 -275.706332) (xy 87.805272 -275.706332) (xy 87.809232 -275.657278) (xy 87.821009 -275.609494)
			(xy 87.8403 -275.564218) (xy 87.866603 -275.522622) (xy 87.899238 -275.485785) (xy 87.937359 -275.45466)
			(xy 87.97998 -275.430053) (xy 88.025996 -275.412601) (xy 88.074215 -275.402757) (xy 88.12339 -275.400776)
			(xy 88.172245 -275.406708) (xy 88.219516 -275.4204) (xy 88.263978 -275.441498) (xy 88.304481 -275.469454)
			(xy 88.339974 -275.503546) (xy 88.369539 -275.54289) (xy 88.39241 -275.586467) (xy 88.407994 -275.633148)
			(xy 88.415889 -275.681725) (xy 88.416384 -275.706332) (xy 88.745326 -275.706332) (xy 88.749286 -275.657278)
			(xy 88.761063 -275.609494) (xy 88.780354 -275.564218) (xy 88.806657 -275.522622) (xy 88.839292 -275.485785)
			(xy 88.877413 -275.45466) (xy 88.920034 -275.430053) (xy 88.96605 -275.412601) (xy 89.014269 -275.402757)
			(xy 89.063444 -275.400776) (xy 89.112299 -275.406708) (xy 89.15957 -275.4204) (xy 89.204032 -275.441498)
			(xy 89.244535 -275.469454) (xy 89.280028 -275.503546) (xy 89.309593 -275.54289) (xy 89.332464 -275.586467)
			(xy 89.348048 -275.633148) (xy 89.355943 -275.681725) (xy 89.356438 -275.706332) (xy 89.685126 -275.706332)
			(xy 89.689086 -275.657278) (xy 89.700863 -275.609494) (xy 89.720154 -275.564218) (xy 89.746457 -275.522622)
			(xy 89.779092 -275.485785) (xy 89.817213 -275.45466) (xy 89.859834 -275.430053) (xy 89.90585 -275.412601)
			(xy 89.954069 -275.402757) (xy 90.003244 -275.400776) (xy 90.052099 -275.406708) (xy 90.09937 -275.4204)
			(xy 90.143832 -275.441498) (xy 90.184335 -275.469454) (xy 90.219828 -275.503546) (xy 90.249393 -275.54289)
			(xy 90.272264 -275.586467) (xy 90.287848 -275.633148) (xy 90.295743 -275.681725) (xy 90.296238 -275.706332)
			(xy 90.614749 -275.706332) (xy 90.618844 -275.655604) (xy 90.631023 -275.60619) (xy 90.650971 -275.55937)
			(xy 90.678172 -275.516356) (xy 90.71192 -275.478262) (xy 90.751342 -275.446075) (xy 90.795416 -275.420629)
			(xy 90.843002 -275.402582) (xy 90.892866 -275.392402) (xy 90.943718 -275.390353) (xy 90.994239 -275.396487)
			(xy 91.043123 -275.410647) (xy 91.089102 -275.432464) (xy 91.130986 -275.461374) (xy 91.16769 -275.496629)
			(xy 91.198263 -275.537315) (xy 91.221914 -275.582378) (xy 91.23803 -275.630652) (xy 91.246194 -275.680886)
			(xy 91.246706 -275.706332) (xy 91.565234 -275.706332) (xy 91.569194 -275.657278) (xy 91.580971 -275.609494)
			(xy 91.600262 -275.564218) (xy 91.626565 -275.522622) (xy 91.6592 -275.485785) (xy 91.697321 -275.45466)
			(xy 91.739942 -275.430053) (xy 91.785958 -275.412601) (xy 91.834177 -275.402757) (xy 91.883352 -275.400776)
			(xy 91.932207 -275.406708) (xy 91.979478 -275.4204) (xy 92.02394 -275.441498) (xy 92.064443 -275.469454)
			(xy 92.099936 -275.503546) (xy 92.129501 -275.54289) (xy 92.152372 -275.586467) (xy 92.167956 -275.633148)
			(xy 92.175851 -275.681725) (xy 92.176346 -275.706332) (xy 92.494857 -275.706332) (xy 92.498952 -275.655604)
			(xy 92.511131 -275.60619) (xy 92.531079 -275.55937) (xy 92.55828 -275.516356) (xy 92.592028 -275.478262)
			(xy 92.63145 -275.446075) (xy 92.675524 -275.420629) (xy 92.72311 -275.402582) (xy 92.772974 -275.392402)
			(xy 92.823826 -275.390353) (xy 92.874347 -275.396487) (xy 92.923231 -275.410647) (xy 92.96921 -275.432464)
			(xy 93.011094 -275.461374) (xy 93.047798 -275.496629) (xy 93.078371 -275.537315) (xy 93.102022 -275.582378)
			(xy 93.118138 -275.630652) (xy 93.126302 -275.680886) (xy 93.126814 -275.706332) (xy 94.374711 -275.706332)
			(xy 94.378806 -275.655604) (xy 94.390985 -275.60619) (xy 94.410933 -275.55937) (xy 94.438134 -275.516356)
			(xy 94.471882 -275.478262) (xy 94.511304 -275.446075) (xy 94.555378 -275.420629) (xy 94.602964 -275.402582)
			(xy 94.652828 -275.392402) (xy 94.70368 -275.390353) (xy 94.754201 -275.396487) (xy 94.803085 -275.410647)
			(xy 94.849064 -275.432464) (xy 94.890948 -275.461374) (xy 94.927652 -275.496629) (xy 94.958225 -275.537315)
			(xy 94.981876 -275.582378) (xy 94.997992 -275.630652) (xy 95.006156 -275.680886) (xy 95.006668 -275.706332)
			(xy 95.314765 -275.706332) (xy 95.31886 -275.655604) (xy 95.331039 -275.60619) (xy 95.350987 -275.55937)
			(xy 95.378188 -275.516356) (xy 95.411936 -275.478262) (xy 95.451358 -275.446075) (xy 95.495432 -275.420629)
			(xy 95.543018 -275.402582) (xy 95.592882 -275.392402) (xy 95.643734 -275.390353) (xy 95.694255 -275.396487)
			(xy 95.743139 -275.410647) (xy 95.789118 -275.432464) (xy 95.831002 -275.461374) (xy 95.867706 -275.496629)
			(xy 95.898279 -275.537315) (xy 95.92193 -275.582378) (xy 95.938046 -275.630652) (xy 95.94621 -275.680886)
			(xy 95.946722 -275.706332) (xy 95.94621 -275.731778) (xy 95.938046 -275.782012) (xy 95.92193 -275.830286)
			(xy 95.898279 -275.875349) (xy 95.867706 -275.916035) (xy 95.831002 -275.95129) (xy 95.789118 -275.9802)
			(xy 95.743139 -276.002017) (xy 95.694255 -276.016177) (xy 95.643734 -276.022311) (xy 95.592882 -276.020262)
			(xy 95.543018 -276.010082) (xy 95.495432 -275.992035) (xy 95.451358 -275.966589) (xy 95.411936 -275.934402)
			(xy 95.378188 -275.896308) (xy 95.350987 -275.853294) (xy 95.331039 -275.806474) (xy 95.31886 -275.75706)
			(xy 95.314765 -275.706332) (xy 95.006668 -275.706332) (xy 95.006156 -275.731778) (xy 94.997992 -275.782012)
			(xy 94.981876 -275.830286) (xy 94.958225 -275.875349) (xy 94.927652 -275.916035) (xy 94.890948 -275.95129)
			(xy 94.849064 -275.9802) (xy 94.803085 -276.002017) (xy 94.754201 -276.016177) (xy 94.70368 -276.022311)
			(xy 94.652828 -276.020262) (xy 94.602964 -276.010082) (xy 94.555378 -275.992035) (xy 94.511304 -275.966589)
			(xy 94.471882 -275.934402) (xy 94.438134 -275.896308) (xy 94.410933 -275.853294) (xy 94.390985 -275.806474)
			(xy 94.378806 -275.75706) (xy 94.374711 -275.706332) (xy 93.126814 -275.706332) (xy 93.126302 -275.731778)
			(xy 93.118138 -275.782012) (xy 93.102022 -275.830286) (xy 93.078371 -275.875349) (xy 93.047798 -275.916035)
			(xy 93.011094 -275.95129) (xy 92.96921 -275.9802) (xy 92.923231 -276.002017) (xy 92.874347 -276.016177)
			(xy 92.823826 -276.022311) (xy 92.772974 -276.020262) (xy 92.72311 -276.010082) (xy 92.675524 -275.992035)
			(xy 92.63145 -275.966589) (xy 92.592028 -275.934402) (xy 92.55828 -275.896308) (xy 92.531079 -275.853294)
			(xy 92.511131 -275.806474) (xy 92.498952 -275.75706) (xy 92.494857 -275.706332) (xy 92.176346 -275.706332)
			(xy 92.175851 -275.730939) (xy 92.167956 -275.779516) (xy 92.152372 -275.826197) (xy 92.129501 -275.869774)
			(xy 92.099936 -275.909118) (xy 92.064443 -275.94321) (xy 92.02394 -275.971166) (xy 91.979478 -275.992264)
			(xy 91.932207 -276.005956) (xy 91.883352 -276.011888) (xy 91.834177 -276.009907) (xy 91.785958 -276.000063)
			(xy 91.739942 -275.982611) (xy 91.697321 -275.958004) (xy 91.6592 -275.926879) (xy 91.626565 -275.890042)
			(xy 91.600262 -275.848446) (xy 91.580971 -275.80317) (xy 91.569194 -275.755386) (xy 91.565234 -275.706332)
			(xy 91.246706 -275.706332) (xy 91.246194 -275.731778) (xy 91.23803 -275.782012) (xy 91.221914 -275.830286)
			(xy 91.198263 -275.875349) (xy 91.16769 -275.916035) (xy 91.130986 -275.95129) (xy 91.089102 -275.9802)
			(xy 91.043123 -276.002017) (xy 90.994239 -276.016177) (xy 90.943718 -276.022311) (xy 90.892866 -276.020262)
			(xy 90.843002 -276.010082) (xy 90.795416 -275.992035) (xy 90.751342 -275.966589) (xy 90.71192 -275.934402)
			(xy 90.678172 -275.896308) (xy 90.650971 -275.853294) (xy 90.631023 -275.806474) (xy 90.618844 -275.75706)
			(xy 90.614749 -275.706332) (xy 90.296238 -275.706332) (xy 90.295743 -275.730939) (xy 90.287848 -275.779516)
			(xy 90.272264 -275.826197) (xy 90.249393 -275.869774) (xy 90.219828 -275.909118) (xy 90.184335 -275.94321)
			(xy 90.143832 -275.971166) (xy 90.09937 -275.992264) (xy 90.052099 -276.005956) (xy 90.003244 -276.011888)
			(xy 89.954069 -276.009907) (xy 89.90585 -276.000063) (xy 89.859834 -275.982611) (xy 89.817213 -275.958004)
			(xy 89.779092 -275.926879) (xy 89.746457 -275.890042) (xy 89.720154 -275.848446) (xy 89.700863 -275.80317)
			(xy 89.689086 -275.755386) (xy 89.685126 -275.706332) (xy 89.356438 -275.706332) (xy 89.355943 -275.730939)
			(xy 89.348048 -275.779516) (xy 89.332464 -275.826197) (xy 89.309593 -275.869774) (xy 89.280028 -275.909118)
			(xy 89.244535 -275.94321) (xy 89.204032 -275.971166) (xy 89.15957 -275.992264) (xy 89.112299 -276.005956)
			(xy 89.063444 -276.011888) (xy 89.014269 -276.009907) (xy 88.96605 -276.000063) (xy 88.920034 -275.982611)
			(xy 88.877413 -275.958004) (xy 88.839292 -275.926879) (xy 88.806657 -275.890042) (xy 88.780354 -275.848446)
			(xy 88.761063 -275.80317) (xy 88.749286 -275.755386) (xy 88.745326 -275.706332) (xy 88.416384 -275.706332)
			(xy 88.415889 -275.730939) (xy 88.407994 -275.779516) (xy 88.39241 -275.826197) (xy 88.369539 -275.869774)
			(xy 88.339974 -275.909118) (xy 88.304481 -275.94321) (xy 88.263978 -275.971166) (xy 88.219516 -275.992264)
			(xy 88.172245 -276.005956) (xy 88.12339 -276.011888) (xy 88.074215 -276.009907) (xy 88.025996 -276.000063)
			(xy 87.97998 -275.982611) (xy 87.937359 -275.958004) (xy 87.899238 -275.926879) (xy 87.866603 -275.890042)
			(xy 87.8403 -275.848446) (xy 87.821009 -275.80317) (xy 87.809232 -275.755386) (xy 87.805272 -275.706332)
			(xy 87.009986 -275.706332) (xy 87.009986 -276.516338) (xy 87.335118 -276.516338) (xy 87.339078 -276.467284)
			(xy 87.350855 -276.4195) (xy 87.370146 -276.374224) (xy 87.396449 -276.332628) (xy 87.429084 -276.295791)
			(xy 87.467205 -276.264666) (xy 87.509826 -276.240059) (xy 87.555842 -276.222607) (xy 87.604061 -276.212763)
			(xy 87.653236 -276.210782) (xy 87.702091 -276.216714) (xy 87.749362 -276.230406) (xy 87.793824 -276.251504)
			(xy 87.834327 -276.27946) (xy 87.86982 -276.313552) (xy 87.899385 -276.352896) (xy 87.922256 -276.396473)
			(xy 87.93784 -276.443154) (xy 87.945735 -276.491731) (xy 87.94623 -276.516338) (xy 88.275172 -276.516338)
			(xy 88.279132 -276.467284) (xy 88.290909 -276.4195) (xy 88.3102 -276.374224) (xy 88.336503 -276.332628)
			(xy 88.369138 -276.295791) (xy 88.407259 -276.264666) (xy 88.44988 -276.240059) (xy 88.495896 -276.222607)
			(xy 88.544115 -276.212763) (xy 88.59329 -276.210782) (xy 88.642145 -276.216714) (xy 88.689416 -276.230406)
			(xy 88.733878 -276.251504) (xy 88.774381 -276.27946) (xy 88.809874 -276.313552) (xy 88.839439 -276.352896)
			(xy 88.86231 -276.396473) (xy 88.877894 -276.443154) (xy 88.885789 -276.491731) (xy 88.886284 -276.516338)
			(xy 89.215226 -276.516338) (xy 89.219186 -276.467284) (xy 89.230963 -276.4195) (xy 89.250254 -276.374224)
			(xy 89.276557 -276.332628) (xy 89.309192 -276.295791) (xy 89.347313 -276.264666) (xy 89.389934 -276.240059)
			(xy 89.43595 -276.222607) (xy 89.484169 -276.212763) (xy 89.533344 -276.210782) (xy 89.582199 -276.216714)
			(xy 89.62947 -276.230406) (xy 89.673932 -276.251504) (xy 89.714435 -276.27946) (xy 89.749928 -276.313552)
			(xy 89.779493 -276.352896) (xy 89.802364 -276.396473) (xy 89.817948 -276.443154) (xy 89.825843 -276.491731)
			(xy 89.826338 -276.516338) (xy 90.15528 -276.516338) (xy 90.15924 -276.467284) (xy 90.171017 -276.4195)
			(xy 90.190308 -276.374224) (xy 90.216611 -276.332628) (xy 90.249246 -276.295791) (xy 90.287367 -276.264666)
			(xy 90.329988 -276.240059) (xy 90.376004 -276.222607) (xy 90.424223 -276.212763) (xy 90.473398 -276.210782)
			(xy 90.522253 -276.216714) (xy 90.569524 -276.230406) (xy 90.613986 -276.251504) (xy 90.654489 -276.27946)
			(xy 90.689982 -276.313552) (xy 90.719547 -276.352896) (xy 90.742418 -276.396473) (xy 90.758002 -276.443154)
			(xy 90.765897 -276.491731) (xy 90.766392 -276.516338) (xy 91.084903 -276.516338) (xy 91.088998 -276.46561)
			(xy 91.101177 -276.416196) (xy 91.121125 -276.369376) (xy 91.148326 -276.326362) (xy 91.182074 -276.288268)
			(xy 91.221496 -276.256081) (xy 91.26557 -276.230635) (xy 91.313156 -276.212588) (xy 91.36302 -276.202408)
			(xy 91.413872 -276.200359) (xy 91.464393 -276.206493) (xy 91.513277 -276.220653) (xy 91.559256 -276.24247)
			(xy 91.60114 -276.27138) (xy 91.637844 -276.306635) (xy 91.668417 -276.347321) (xy 91.692068 -276.392384)
			(xy 91.708184 -276.440658) (xy 91.716348 -276.490892) (xy 91.71686 -276.516338) (xy 92.024703 -276.516338)
			(xy 92.028798 -276.46561) (xy 92.040977 -276.416196) (xy 92.060925 -276.369376) (xy 92.088126 -276.326362)
			(xy 92.121874 -276.288268) (xy 92.161296 -276.256081) (xy 92.20537 -276.230635) (xy 92.252956 -276.212588)
			(xy 92.30282 -276.202408) (xy 92.353672 -276.200359) (xy 92.404193 -276.206493) (xy 92.453077 -276.220653)
			(xy 92.499056 -276.24247) (xy 92.54094 -276.27138) (xy 92.577644 -276.306635) (xy 92.608217 -276.347321)
			(xy 92.631868 -276.392384) (xy 92.647984 -276.440658) (xy 92.656148 -276.490892) (xy 92.65666 -276.516338)
			(xy 92.975188 -276.516338) (xy 92.979148 -276.467284) (xy 92.990925 -276.4195) (xy 93.010216 -276.374224)
			(xy 93.036519 -276.332628) (xy 93.069154 -276.295791) (xy 93.107275 -276.264666) (xy 93.149896 -276.240059)
			(xy 93.195912 -276.222607) (xy 93.244131 -276.212763) (xy 93.293306 -276.210782) (xy 93.342161 -276.216714)
			(xy 93.389432 -276.230406) (xy 93.433894 -276.251504) (xy 93.474397 -276.27946) (xy 93.50989 -276.313552)
			(xy 93.539455 -276.352896) (xy 93.562326 -276.396473) (xy 93.57791 -276.443154) (xy 93.585805 -276.491731)
			(xy 93.5863 -276.516338) (xy 93.904811 -276.516338) (xy 93.908906 -276.46561) (xy 93.921085 -276.416196)
			(xy 93.941033 -276.369376) (xy 93.968234 -276.326362) (xy 94.001982 -276.288268) (xy 94.041404 -276.256081)
			(xy 94.085478 -276.230635) (xy 94.133064 -276.212588) (xy 94.182928 -276.202408) (xy 94.23378 -276.200359)
			(xy 94.284301 -276.206493) (xy 94.333185 -276.220653) (xy 94.379164 -276.24247) (xy 94.421048 -276.27138)
			(xy 94.457752 -276.306635) (xy 94.488325 -276.347321) (xy 94.511976 -276.392384) (xy 94.528092 -276.440658)
			(xy 94.536256 -276.490892) (xy 94.536768 -276.516338) (xy 94.855296 -276.516338) (xy 94.859256 -276.467284)
			(xy 94.871033 -276.4195) (xy 94.890324 -276.374224) (xy 94.916627 -276.332628) (xy 94.949262 -276.295791)
			(xy 94.987383 -276.264666) (xy 95.030004 -276.240059) (xy 95.07602 -276.222607) (xy 95.124239 -276.212763)
			(xy 95.173414 -276.210782) (xy 95.222269 -276.216714) (xy 95.26954 -276.230406) (xy 95.314002 -276.251504)
			(xy 95.354505 -276.27946) (xy 95.389998 -276.313552) (xy 95.419563 -276.352896) (xy 95.442434 -276.396473)
			(xy 95.458018 -276.443154) (xy 95.465913 -276.491731) (xy 95.466408 -276.516338) (xy 95.784919 -276.516338)
			(xy 95.789014 -276.46561) (xy 95.801193 -276.416196) (xy 95.821141 -276.369376) (xy 95.848342 -276.326362)
			(xy 95.88209 -276.288268) (xy 95.921512 -276.256081) (xy 95.965586 -276.230635) (xy 96.013172 -276.212588)
			(xy 96.063036 -276.202408) (xy 96.113888 -276.200359) (xy 96.164409 -276.206493) (xy 96.213293 -276.220653)
			(xy 96.259272 -276.24247) (xy 96.301156 -276.27138) (xy 96.33786 -276.306635) (xy 96.368433 -276.347321)
			(xy 96.392084 -276.392384) (xy 96.4082 -276.440658) (xy 96.416364 -276.490892) (xy 96.416876 -276.516338)
			(xy 96.416364 -276.541784) (xy 96.4082 -276.592018) (xy 96.392084 -276.640292) (xy 96.368433 -276.685355)
			(xy 96.33786 -276.726041) (xy 96.301156 -276.761296) (xy 96.259272 -276.790206) (xy 96.213293 -276.812023)
			(xy 96.164409 -276.826183) (xy 96.113888 -276.832317) (xy 96.063036 -276.830268) (xy 96.013172 -276.820088)
			(xy 95.965586 -276.802041) (xy 95.921512 -276.776595) (xy 95.88209 -276.744408) (xy 95.848342 -276.706314)
			(xy 95.821141 -276.6633) (xy 95.801193 -276.61648) (xy 95.789014 -276.567066) (xy 95.784919 -276.516338)
			(xy 95.466408 -276.516338) (xy 95.465913 -276.540945) (xy 95.458018 -276.589522) (xy 95.442434 -276.636203)
			(xy 95.419563 -276.67978) (xy 95.389998 -276.719124) (xy 95.354505 -276.753216) (xy 95.314002 -276.781172)
			(xy 95.26954 -276.80227) (xy 95.222269 -276.815962) (xy 95.173414 -276.821894) (xy 95.124239 -276.819913)
			(xy 95.07602 -276.810069) (xy 95.030004 -276.792617) (xy 94.987383 -276.76801) (xy 94.949262 -276.736885)
			(xy 94.916627 -276.700048) (xy 94.890324 -276.658452) (xy 94.871033 -276.613176) (xy 94.859256 -276.565392)
			(xy 94.855296 -276.516338) (xy 94.536768 -276.516338) (xy 94.536256 -276.541784) (xy 94.528092 -276.592018)
			(xy 94.511976 -276.640292) (xy 94.488325 -276.685355) (xy 94.457752 -276.726041) (xy 94.421048 -276.761296)
			(xy 94.379164 -276.790206) (xy 94.333185 -276.812023) (xy 94.284301 -276.826183) (xy 94.23378 -276.832317)
			(xy 94.182928 -276.830268) (xy 94.133064 -276.820088) (xy 94.085478 -276.802041) (xy 94.041404 -276.776595)
			(xy 94.001982 -276.744408) (xy 93.968234 -276.706314) (xy 93.941033 -276.6633) (xy 93.921085 -276.61648)
			(xy 93.908906 -276.567066) (xy 93.904811 -276.516338) (xy 93.5863 -276.516338) (xy 93.585805 -276.540945)
			(xy 93.57791 -276.589522) (xy 93.562326 -276.636203) (xy 93.539455 -276.67978) (xy 93.50989 -276.719124)
			(xy 93.474397 -276.753216) (xy 93.433894 -276.781172) (xy 93.389432 -276.80227) (xy 93.342161 -276.815962)
			(xy 93.293306 -276.821894) (xy 93.244131 -276.819913) (xy 93.195912 -276.810069) (xy 93.149896 -276.792617)
			(xy 93.107275 -276.76801) (xy 93.069154 -276.736885) (xy 93.036519 -276.700048) (xy 93.010216 -276.658452)
			(xy 92.990925 -276.613176) (xy 92.979148 -276.565392) (xy 92.975188 -276.516338) (xy 92.65666 -276.516338)
			(xy 92.656148 -276.541784) (xy 92.647984 -276.592018) (xy 92.631868 -276.640292) (xy 92.608217 -276.685355)
			(xy 92.577644 -276.726041) (xy 92.54094 -276.761296) (xy 92.499056 -276.790206) (xy 92.453077 -276.812023)
			(xy 92.404193 -276.826183) (xy 92.353672 -276.832317) (xy 92.30282 -276.830268) (xy 92.252956 -276.820088)
			(xy 92.20537 -276.802041) (xy 92.161296 -276.776595) (xy 92.121874 -276.744408) (xy 92.088126 -276.706314)
			(xy 92.060925 -276.6633) (xy 92.040977 -276.61648) (xy 92.028798 -276.567066) (xy 92.024703 -276.516338)
			(xy 91.71686 -276.516338) (xy 91.716348 -276.541784) (xy 91.708184 -276.592018) (xy 91.692068 -276.640292)
			(xy 91.668417 -276.685355) (xy 91.637844 -276.726041) (xy 91.60114 -276.761296) (xy 91.559256 -276.790206)
			(xy 91.513277 -276.812023) (xy 91.464393 -276.826183) (xy 91.413872 -276.832317) (xy 91.36302 -276.830268)
			(xy 91.313156 -276.820088) (xy 91.26557 -276.802041) (xy 91.221496 -276.776595) (xy 91.182074 -276.744408)
			(xy 91.148326 -276.706314) (xy 91.121125 -276.6633) (xy 91.101177 -276.61648) (xy 91.088998 -276.567066)
			(xy 91.084903 -276.516338) (xy 90.766392 -276.516338) (xy 90.765897 -276.540945) (xy 90.758002 -276.589522)
			(xy 90.742418 -276.636203) (xy 90.719547 -276.67978) (xy 90.689982 -276.719124) (xy 90.654489 -276.753216)
			(xy 90.613986 -276.781172) (xy 90.569524 -276.80227) (xy 90.522253 -276.815962) (xy 90.473398 -276.821894)
			(xy 90.424223 -276.819913) (xy 90.376004 -276.810069) (xy 90.329988 -276.792617) (xy 90.287367 -276.76801)
			(xy 90.249246 -276.736885) (xy 90.216611 -276.700048) (xy 90.190308 -276.658452) (xy 90.171017 -276.613176)
			(xy 90.15924 -276.565392) (xy 90.15528 -276.516338) (xy 89.826338 -276.516338) (xy 89.825843 -276.540945)
			(xy 89.817948 -276.589522) (xy 89.802364 -276.636203) (xy 89.779493 -276.67978) (xy 89.749928 -276.719124)
			(xy 89.714435 -276.753216) (xy 89.673932 -276.781172) (xy 89.62947 -276.80227) (xy 89.582199 -276.815962)
			(xy 89.533344 -276.821894) (xy 89.484169 -276.819913) (xy 89.43595 -276.810069) (xy 89.389934 -276.792617)
			(xy 89.347313 -276.76801) (xy 89.309192 -276.736885) (xy 89.276557 -276.700048) (xy 89.250254 -276.658452)
			(xy 89.230963 -276.613176) (xy 89.219186 -276.565392) (xy 89.215226 -276.516338) (xy 88.886284 -276.516338)
			(xy 88.885789 -276.540945) (xy 88.877894 -276.589522) (xy 88.86231 -276.636203) (xy 88.839439 -276.67978)
			(xy 88.809874 -276.719124) (xy 88.774381 -276.753216) (xy 88.733878 -276.781172) (xy 88.689416 -276.80227)
			(xy 88.642145 -276.815962) (xy 88.59329 -276.821894) (xy 88.544115 -276.819913) (xy 88.495896 -276.810069)
			(xy 88.44988 -276.792617) (xy 88.407259 -276.76801) (xy 88.369138 -276.736885) (xy 88.336503 -276.700048)
			(xy 88.3102 -276.658452) (xy 88.290909 -276.613176) (xy 88.279132 -276.565392) (xy 88.275172 -276.516338)
			(xy 87.94623 -276.516338) (xy 87.945735 -276.540945) (xy 87.93784 -276.589522) (xy 87.922256 -276.636203)
			(xy 87.899385 -276.67978) (xy 87.86982 -276.719124) (xy 87.834327 -276.753216) (xy 87.793824 -276.781172)
			(xy 87.749362 -276.80227) (xy 87.702091 -276.815962) (xy 87.653236 -276.821894) (xy 87.604061 -276.819913)
			(xy 87.555842 -276.810069) (xy 87.509826 -276.792617) (xy 87.467205 -276.76801) (xy 87.429084 -276.736885)
			(xy 87.396449 -276.700048) (xy 87.370146 -276.658452) (xy 87.350855 -276.613176) (xy 87.339078 -276.565392)
			(xy 87.335118 -276.516338) (xy 87.009986 -276.516338) (xy 87.009986 -276.925024) (xy 87.010353 -276.934131)
			(xy 87.016721 -276.951196) (xy 87.022432 -276.958298) (xy 87.024972 -276.961092) (xy 87.065104 -276.995636)
			(xy 87.080344 -277.008844) (xy 87.081614 -277.00986) (xy 87.088577 -277.015063) (xy 87.104935 -277.020907)
			(xy 87.113618 -277.02129) (xy 87.159592 -277.02129) (xy 87.171022 -277.021036) (xy 87.171276 -277.021036)
			(xy 87.195252 -277.021527) (xy 87.242608 -277.029068) (xy 87.288202 -277.04392) (xy 87.330913 -277.065719)
			(xy 87.36969 -277.093928) (xy 87.40358 -277.127853) (xy 87.431748 -277.16666) (xy 87.453502 -277.209394)
			(xy 87.468307 -277.255004) (xy 87.475798 -277.302368) (xy 87.47633 -277.326344) (xy 87.805272 -277.326344)
			(xy 87.809232 -277.27729) (xy 87.821009 -277.229506) (xy 87.8403 -277.18423) (xy 87.866603 -277.142634)
			(xy 87.899238 -277.105797) (xy 87.937359 -277.074672) (xy 87.97998 -277.050065) (xy 88.025996 -277.032613)
			(xy 88.074215 -277.022769) (xy 88.12339 -277.020788) (xy 88.172245 -277.02672) (xy 88.219516 -277.040412)
			(xy 88.263978 -277.06151) (xy 88.304481 -277.089466) (xy 88.339974 -277.123558) (xy 88.369539 -277.162902)
			(xy 88.39241 -277.206479) (xy 88.407994 -277.25316) (xy 88.415889 -277.301737) (xy 88.416384 -277.326344)
			(xy 88.745326 -277.326344) (xy 88.749286 -277.27729) (xy 88.761063 -277.229506) (xy 88.780354 -277.18423)
			(xy 88.806657 -277.142634) (xy 88.839292 -277.105797) (xy 88.877413 -277.074672) (xy 88.920034 -277.050065)
			(xy 88.96605 -277.032613) (xy 89.014269 -277.022769) (xy 89.063444 -277.020788) (xy 89.112299 -277.02672)
			(xy 89.15957 -277.040412) (xy 89.204032 -277.06151) (xy 89.244535 -277.089466) (xy 89.280028 -277.123558)
			(xy 89.309593 -277.162902) (xy 89.332464 -277.206479) (xy 89.348048 -277.25316) (xy 89.355943 -277.301737)
			(xy 89.356438 -277.326344) (xy 89.685126 -277.326344) (xy 89.689086 -277.27729) (xy 89.700863 -277.229506)
			(xy 89.720154 -277.18423) (xy 89.746457 -277.142634) (xy 89.779092 -277.105797) (xy 89.817213 -277.074672)
			(xy 89.859834 -277.050065) (xy 89.90585 -277.032613) (xy 89.954069 -277.022769) (xy 90.003244 -277.020788)
			(xy 90.052099 -277.02672) (xy 90.09937 -277.040412) (xy 90.143832 -277.06151) (xy 90.184335 -277.089466)
			(xy 90.219828 -277.123558) (xy 90.249393 -277.162902) (xy 90.272264 -277.206479) (xy 90.287848 -277.25316)
			(xy 90.295743 -277.301737) (xy 90.296238 -277.326344) (xy 90.614749 -277.326344) (xy 90.618844 -277.275616)
			(xy 90.631023 -277.226202) (xy 90.650971 -277.179382) (xy 90.678172 -277.136368) (xy 90.71192 -277.098274)
			(xy 90.751342 -277.066087) (xy 90.795416 -277.040641) (xy 90.843002 -277.022594) (xy 90.892866 -277.012414)
			(xy 90.943718 -277.010365) (xy 90.994239 -277.016499) (xy 91.043123 -277.030659) (xy 91.089102 -277.052476)
			(xy 91.130986 -277.081386) (xy 91.16769 -277.116641) (xy 91.198263 -277.157327) (xy 91.221914 -277.20239)
			(xy 91.23803 -277.250664) (xy 91.246194 -277.300898) (xy 91.246706 -277.326344) (xy 91.565234 -277.326344)
			(xy 91.569194 -277.27729) (xy 91.580971 -277.229506) (xy 91.600262 -277.18423) (xy 91.626565 -277.142634)
			(xy 91.6592 -277.105797) (xy 91.697321 -277.074672) (xy 91.739942 -277.050065) (xy 91.785958 -277.032613)
			(xy 91.834177 -277.022769) (xy 91.883352 -277.020788) (xy 91.932207 -277.02672) (xy 91.979478 -277.040412)
			(xy 92.02394 -277.06151) (xy 92.064443 -277.089466) (xy 92.099936 -277.123558) (xy 92.129501 -277.162902)
			(xy 92.152372 -277.206479) (xy 92.167956 -277.25316) (xy 92.175851 -277.301737) (xy 92.176346 -277.326344)
			(xy 92.494857 -277.326344) (xy 92.498952 -277.275616) (xy 92.511131 -277.226202) (xy 92.531079 -277.179382)
			(xy 92.55828 -277.136368) (xy 92.592028 -277.098274) (xy 92.63145 -277.066087) (xy 92.675524 -277.040641)
			(xy 92.72311 -277.022594) (xy 92.772974 -277.012414) (xy 92.823826 -277.010365) (xy 92.874347 -277.016499)
			(xy 92.923231 -277.030659) (xy 92.96921 -277.052476) (xy 93.011094 -277.081386) (xy 93.047798 -277.116641)
			(xy 93.078371 -277.157327) (xy 93.102022 -277.20239) (xy 93.118138 -277.250664) (xy 93.126302 -277.300898)
			(xy 93.126814 -277.326344) (xy 93.445342 -277.326344) (xy 93.449302 -277.27729) (xy 93.461079 -277.229506)
			(xy 93.48037 -277.18423) (xy 93.506673 -277.142634) (xy 93.539308 -277.105797) (xy 93.577429 -277.074672)
			(xy 93.62005 -277.050065) (xy 93.666066 -277.032613) (xy 93.714285 -277.022769) (xy 93.76346 -277.020788)
			(xy 93.812315 -277.02672) (xy 93.859586 -277.040412) (xy 93.904048 -277.06151) (xy 93.944551 -277.089466)
			(xy 93.980044 -277.123558) (xy 94.009609 -277.162902) (xy 94.03248 -277.206479) (xy 94.048064 -277.25316)
			(xy 94.055959 -277.301737) (xy 94.056454 -277.326344) (xy 94.374711 -277.326344) (xy 94.378806 -277.275616)
			(xy 94.390985 -277.226202) (xy 94.410933 -277.179382) (xy 94.438134 -277.136368) (xy 94.471882 -277.098274)
			(xy 94.511304 -277.066087) (xy 94.555378 -277.040641) (xy 94.602964 -277.022594) (xy 94.652828 -277.012414)
			(xy 94.70368 -277.010365) (xy 94.754201 -277.016499) (xy 94.803085 -277.030659) (xy 94.849064 -277.052476)
			(xy 94.890948 -277.081386) (xy 94.927652 -277.116641) (xy 94.958225 -277.157327) (xy 94.981876 -277.20239)
			(xy 94.997992 -277.250664) (xy 95.006156 -277.300898) (xy 95.006668 -277.326344) (xy 95.314765 -277.326344)
			(xy 95.31886 -277.275616) (xy 95.331039 -277.226202) (xy 95.350987 -277.179382) (xy 95.378188 -277.136368)
			(xy 95.411936 -277.098274) (xy 95.451358 -277.066087) (xy 95.495432 -277.040641) (xy 95.543018 -277.022594)
			(xy 95.592882 -277.012414) (xy 95.643734 -277.010365) (xy 95.694255 -277.016499) (xy 95.743139 -277.030659)
			(xy 95.789118 -277.052476) (xy 95.831002 -277.081386) (xy 95.867706 -277.116641) (xy 95.898279 -277.157327)
			(xy 95.92193 -277.20239) (xy 95.938046 -277.250664) (xy 95.94621 -277.300898) (xy 95.946722 -277.326344)
			(xy 95.94621 -277.35179) (xy 95.938046 -277.402024) (xy 95.92193 -277.450298) (xy 95.898279 -277.495361)
			(xy 95.867706 -277.536047) (xy 95.831002 -277.571302) (xy 95.789118 -277.600212) (xy 95.743139 -277.622029)
			(xy 95.694255 -277.636189) (xy 95.643734 -277.642323) (xy 95.592882 -277.640274) (xy 95.543018 -277.630094)
			(xy 95.495432 -277.612047) (xy 95.451358 -277.586601) (xy 95.411936 -277.554414) (xy 95.378188 -277.51632)
			(xy 95.350987 -277.473306) (xy 95.331039 -277.426486) (xy 95.31886 -277.377072) (xy 95.314765 -277.326344)
			(xy 95.006668 -277.326344) (xy 95.006156 -277.35179) (xy 94.997992 -277.402024) (xy 94.981876 -277.450298)
			(xy 94.958225 -277.495361) (xy 94.927652 -277.536047) (xy 94.890948 -277.571302) (xy 94.849064 -277.600212)
			(xy 94.803085 -277.622029) (xy 94.754201 -277.636189) (xy 94.70368 -277.642323) (xy 94.652828 -277.640274)
			(xy 94.602964 -277.630094) (xy 94.555378 -277.612047) (xy 94.511304 -277.586601) (xy 94.471882 -277.554414)
			(xy 94.438134 -277.51632) (xy 94.410933 -277.473306) (xy 94.390985 -277.426486) (xy 94.378806 -277.377072)
			(xy 94.374711 -277.326344) (xy 94.056454 -277.326344) (xy 94.055959 -277.350951) (xy 94.048064 -277.399528)
			(xy 94.03248 -277.446209) (xy 94.009609 -277.489786) (xy 93.980044 -277.52913) (xy 93.944551 -277.563222)
			(xy 93.904048 -277.591178) (xy 93.859586 -277.612276) (xy 93.812315 -277.625968) (xy 93.76346 -277.6319)
			(xy 93.714285 -277.629919) (xy 93.666066 -277.620075) (xy 93.62005 -277.602623) (xy 93.577429 -277.578016)
			(xy 93.539308 -277.546891) (xy 93.506673 -277.510054) (xy 93.48037 -277.468458) (xy 93.461079 -277.423182)
			(xy 93.449302 -277.375398) (xy 93.445342 -277.326344) (xy 93.126814 -277.326344) (xy 93.126302 -277.35179)
			(xy 93.118138 -277.402024) (xy 93.102022 -277.450298) (xy 93.078371 -277.495361) (xy 93.047798 -277.536047)
			(xy 93.011094 -277.571302) (xy 92.96921 -277.600212) (xy 92.923231 -277.622029) (xy 92.874347 -277.636189)
			(xy 92.823826 -277.642323) (xy 92.772974 -277.640274) (xy 92.72311 -277.630094) (xy 92.675524 -277.612047)
			(xy 92.63145 -277.586601) (xy 92.592028 -277.554414) (xy 92.55828 -277.51632) (xy 92.531079 -277.473306)
			(xy 92.511131 -277.426486) (xy 92.498952 -277.377072) (xy 92.494857 -277.326344) (xy 92.176346 -277.326344)
			(xy 92.175851 -277.350951) (xy 92.167956 -277.399528) (xy 92.152372 -277.446209) (xy 92.129501 -277.489786)
			(xy 92.099936 -277.52913) (xy 92.064443 -277.563222) (xy 92.02394 -277.591178) (xy 91.979478 -277.612276)
			(xy 91.932207 -277.625968) (xy 91.883352 -277.6319) (xy 91.834177 -277.629919) (xy 91.785958 -277.620075)
			(xy 91.739942 -277.602623) (xy 91.697321 -277.578016) (xy 91.6592 -277.546891) (xy 91.626565 -277.510054)
			(xy 91.600262 -277.468458) (xy 91.580971 -277.423182) (xy 91.569194 -277.375398) (xy 91.565234 -277.326344)
			(xy 91.246706 -277.326344) (xy 91.246194 -277.35179) (xy 91.23803 -277.402024) (xy 91.221914 -277.450298)
			(xy 91.198263 -277.495361) (xy 91.16769 -277.536047) (xy 91.130986 -277.571302) (xy 91.089102 -277.600212)
			(xy 91.043123 -277.622029) (xy 90.994239 -277.636189) (xy 90.943718 -277.642323) (xy 90.892866 -277.640274)
			(xy 90.843002 -277.630094) (xy 90.795416 -277.612047) (xy 90.751342 -277.586601) (xy 90.71192 -277.554414)
			(xy 90.678172 -277.51632) (xy 90.650971 -277.473306) (xy 90.631023 -277.426486) (xy 90.618844 -277.377072)
			(xy 90.614749 -277.326344) (xy 90.296238 -277.326344) (xy 90.295743 -277.350951) (xy 90.287848 -277.399528)
			(xy 90.272264 -277.446209) (xy 90.249393 -277.489786) (xy 90.219828 -277.52913) (xy 90.184335 -277.563222)
			(xy 90.143832 -277.591178) (xy 90.09937 -277.612276) (xy 90.052099 -277.625968) (xy 90.003244 -277.6319)
			(xy 89.954069 -277.629919) (xy 89.90585 -277.620075) (xy 89.859834 -277.602623) (xy 89.817213 -277.578016)
			(xy 89.779092 -277.546891) (xy 89.746457 -277.510054) (xy 89.720154 -277.468458) (xy 89.700863 -277.423182)
			(xy 89.689086 -277.375398) (xy 89.685126 -277.326344) (xy 89.356438 -277.326344) (xy 89.355943 -277.350951)
			(xy 89.348048 -277.399528) (xy 89.332464 -277.446209) (xy 89.309593 -277.489786) (xy 89.280028 -277.52913)
			(xy 89.244535 -277.563222) (xy 89.204032 -277.591178) (xy 89.15957 -277.612276) (xy 89.112299 -277.625968)
			(xy 89.063444 -277.6319) (xy 89.014269 -277.629919) (xy 88.96605 -277.620075) (xy 88.920034 -277.602623)
			(xy 88.877413 -277.578016) (xy 88.839292 -277.546891) (xy 88.806657 -277.510054) (xy 88.780354 -277.468458)
			(xy 88.761063 -277.423182) (xy 88.749286 -277.375398) (xy 88.745326 -277.326344) (xy 88.416384 -277.326344)
			(xy 88.415889 -277.350951) (xy 88.407994 -277.399528) (xy 88.39241 -277.446209) (xy 88.369539 -277.489786)
			(xy 88.339974 -277.52913) (xy 88.304481 -277.563222) (xy 88.263978 -277.591178) (xy 88.219516 -277.612276)
			(xy 88.172245 -277.625968) (xy 88.12339 -277.6319) (xy 88.074215 -277.629919) (xy 88.025996 -277.620075)
			(xy 87.97998 -277.602623) (xy 87.937359 -277.578016) (xy 87.899238 -277.546891) (xy 87.866603 -277.510054)
			(xy 87.8403 -277.468458) (xy 87.821009 -277.423182) (xy 87.809232 -277.375398) (xy 87.805272 -277.326344)
			(xy 87.47633 -277.326344) (xy 87.475856 -277.350334) (xy 87.468345 -277.397721) (xy 87.453514 -277.443351)
			(xy 87.431728 -277.486099) (xy 87.403524 -277.524913) (xy 87.369597 -277.558839) (xy 87.33078 -277.58704)
			(xy 87.28803 -277.608822) (xy 87.2424 -277.62365) (xy 87.195012 -277.631158) (xy 87.171022 -277.631652)
			(xy 87.159613 -277.631577) (xy 87.136856 -277.629922) (xy 87.125556 -277.62835) (xy 87.114634 -277.626572)
			(xy 87.09279 -277.632922) (xy 87.065358 -277.656798) (xy 87.06485 -277.657306) (xy 87.030814 -277.686516)
			(xy 87.02929 -277.687786) (xy 87.024972 -277.692104) (xy 87.017606 -277.699216) (xy 87.009986 -277.718012)
			(xy 87.009986 -278.017732) (xy 87.01278 -278.026114) (xy 87.021609 -278.052817) (xy 87.031186 -278.108233)
			(xy 87.03183 -278.13635) (xy 87.335118 -278.13635) (xy 87.339078 -278.087296) (xy 87.350855 -278.039512)
			(xy 87.370146 -277.994236) (xy 87.396449 -277.95264) (xy 87.429084 -277.915803) (xy 87.467205 -277.884678)
			(xy 87.509826 -277.860071) (xy 87.555842 -277.842619) (xy 87.604061 -277.832775) (xy 87.653236 -277.830794)
			(xy 87.702091 -277.836726) (xy 87.749362 -277.850418) (xy 87.793824 -277.871516) (xy 87.834327 -277.899472)
			(xy 87.86982 -277.933564) (xy 87.899385 -277.972908) (xy 87.922256 -278.016485) (xy 87.93784 -278.063166)
			(xy 87.945735 -278.111743) (xy 87.94623 -278.13635) (xy 88.275172 -278.13635) (xy 88.279132 -278.087296)
			(xy 88.290909 -278.039512) (xy 88.3102 -277.994236) (xy 88.336503 -277.95264) (xy 88.369138 -277.915803)
			(xy 88.407259 -277.884678) (xy 88.44988 -277.860071) (xy 88.495896 -277.842619) (xy 88.544115 -277.832775)
			(xy 88.59329 -277.830794) (xy 88.642145 -277.836726) (xy 88.689416 -277.850418) (xy 88.733878 -277.871516)
			(xy 88.774381 -277.899472) (xy 88.809874 -277.933564) (xy 88.839439 -277.972908) (xy 88.86231 -278.016485)
			(xy 88.877894 -278.063166) (xy 88.885789 -278.111743) (xy 88.886284 -278.13635) (xy 89.215226 -278.13635)
			(xy 89.219186 -278.087296) (xy 89.230963 -278.039512) (xy 89.250254 -277.994236) (xy 89.276557 -277.95264)
			(xy 89.309192 -277.915803) (xy 89.347313 -277.884678) (xy 89.389934 -277.860071) (xy 89.43595 -277.842619)
			(xy 89.484169 -277.832775) (xy 89.533344 -277.830794) (xy 89.582199 -277.836726) (xy 89.62947 -277.850418)
			(xy 89.673932 -277.871516) (xy 89.714435 -277.899472) (xy 89.749928 -277.933564) (xy 89.779493 -277.972908)
			(xy 89.802364 -278.016485) (xy 89.817948 -278.063166) (xy 89.825843 -278.111743) (xy 89.826338 -278.13635)
			(xy 90.15528 -278.13635) (xy 90.15924 -278.087296) (xy 90.171017 -278.039512) (xy 90.190308 -277.994236)
			(xy 90.216611 -277.95264) (xy 90.249246 -277.915803) (xy 90.287367 -277.884678) (xy 90.329988 -277.860071)
			(xy 90.376004 -277.842619) (xy 90.424223 -277.832775) (xy 90.473398 -277.830794) (xy 90.522253 -277.836726)
			(xy 90.569524 -277.850418) (xy 90.613986 -277.871516) (xy 90.654489 -277.899472) (xy 90.689982 -277.933564)
			(xy 90.719547 -277.972908) (xy 90.742418 -278.016485) (xy 90.758002 -278.063166) (xy 90.765897 -278.111743)
			(xy 90.766392 -278.13635) (xy 91.084903 -278.13635) (xy 91.088998 -278.085622) (xy 91.101177 -278.036208)
			(xy 91.121125 -277.989388) (xy 91.148326 -277.946374) (xy 91.182074 -277.90828) (xy 91.221496 -277.876093)
			(xy 91.26557 -277.850647) (xy 91.313156 -277.8326) (xy 91.36302 -277.82242) (xy 91.413872 -277.820371)
			(xy 91.464393 -277.826505) (xy 91.513277 -277.840665) (xy 91.559256 -277.862482) (xy 91.60114 -277.891392)
			(xy 91.637844 -277.926647) (xy 91.668417 -277.967333) (xy 91.692068 -278.012396) (xy 91.708184 -278.06067)
			(xy 91.716348 -278.110904) (xy 91.71686 -278.13635) (xy 92.024703 -278.13635) (xy 92.028798 -278.085622)
			(xy 92.040977 -278.036208) (xy 92.060925 -277.989388) (xy 92.088126 -277.946374) (xy 92.121874 -277.90828)
			(xy 92.161296 -277.876093) (xy 92.20537 -277.850647) (xy 92.252956 -277.8326) (xy 92.30282 -277.82242)
			(xy 92.353672 -277.820371) (xy 92.404193 -277.826505) (xy 92.453077 -277.840665) (xy 92.499056 -277.862482)
			(xy 92.54094 -277.891392) (xy 92.577644 -277.926647) (xy 92.608217 -277.967333) (xy 92.631868 -278.012396)
			(xy 92.647984 -278.06067) (xy 92.656148 -278.110904) (xy 92.65666 -278.13635) (xy 93.904811 -278.13635)
			(xy 93.908906 -278.085622) (xy 93.921085 -278.036208) (xy 93.941033 -277.989388) (xy 93.968234 -277.946374)
			(xy 94.001982 -277.90828) (xy 94.041404 -277.876093) (xy 94.085478 -277.850647) (xy 94.133064 -277.8326)
			(xy 94.182928 -277.82242) (xy 94.23378 -277.820371) (xy 94.284301 -277.826505) (xy 94.333185 -277.840665)
			(xy 94.379164 -277.862482) (xy 94.421048 -277.891392) (xy 94.457752 -277.926647) (xy 94.488325 -277.967333)
			(xy 94.511976 -278.012396) (xy 94.528092 -278.06067) (xy 94.536256 -278.110904) (xy 94.536768 -278.13635)
			(xy 94.855296 -278.13635) (xy 94.859256 -278.087296) (xy 94.871033 -278.039512) (xy 94.890324 -277.994236)
			(xy 94.916627 -277.95264) (xy 94.949262 -277.915803) (xy 94.987383 -277.884678) (xy 95.030004 -277.860071)
			(xy 95.07602 -277.842619) (xy 95.124239 -277.832775) (xy 95.173414 -277.830794) (xy 95.222269 -277.836726)
			(xy 95.26954 -277.850418) (xy 95.314002 -277.871516) (xy 95.354505 -277.899472) (xy 95.389998 -277.933564)
			(xy 95.419563 -277.972908) (xy 95.442434 -278.016485) (xy 95.458018 -278.063166) (xy 95.465913 -278.111743)
			(xy 95.466408 -278.13635) (xy 95.784919 -278.13635) (xy 95.789014 -278.085622) (xy 95.801193 -278.036208)
			(xy 95.821141 -277.989388) (xy 95.848342 -277.946374) (xy 95.88209 -277.90828) (xy 95.921512 -277.876093)
			(xy 95.965586 -277.850647) (xy 96.013172 -277.8326) (xy 96.063036 -277.82242) (xy 96.113888 -277.820371)
			(xy 96.164409 -277.826505) (xy 96.213293 -277.840665) (xy 96.259272 -277.862482) (xy 96.301156 -277.891392)
			(xy 96.33786 -277.926647) (xy 96.368433 -277.967333) (xy 96.392084 -278.012396) (xy 96.4082 -278.06067)
			(xy 96.416364 -278.110904) (xy 96.416876 -278.13635) (xy 96.416364 -278.161796) (xy 96.4082 -278.21203)
			(xy 96.392084 -278.260304) (xy 96.368433 -278.305367) (xy 96.33786 -278.346053) (xy 96.301156 -278.381308)
			(xy 96.259272 -278.410218) (xy 96.213293 -278.432035) (xy 96.164409 -278.446195) (xy 96.113888 -278.452329)
			(xy 96.063036 -278.45028) (xy 96.013172 -278.4401) (xy 95.965586 -278.422053) (xy 95.921512 -278.396607)
			(xy 95.88209 -278.36442) (xy 95.848342 -278.326326) (xy 95.821141 -278.283312) (xy 95.801193 -278.236492)
			(xy 95.789014 -278.187078) (xy 95.784919 -278.13635) (xy 95.466408 -278.13635) (xy 95.465913 -278.160957)
			(xy 95.458018 -278.209534) (xy 95.442434 -278.256215) (xy 95.419563 -278.299792) (xy 95.389998 -278.339136)
			(xy 95.354505 -278.373228) (xy 95.314002 -278.401184) (xy 95.26954 -278.422282) (xy 95.222269 -278.435974)
			(xy 95.173414 -278.441906) (xy 95.124239 -278.439925) (xy 95.07602 -278.430081) (xy 95.030004 -278.412629)
			(xy 94.987383 -278.388022) (xy 94.949262 -278.356897) (xy 94.916627 -278.32006) (xy 94.890324 -278.278464)
			(xy 94.871033 -278.233188) (xy 94.859256 -278.185404) (xy 94.855296 -278.13635) (xy 94.536768 -278.13635)
			(xy 94.536256 -278.161796) (xy 94.528092 -278.21203) (xy 94.511976 -278.260304) (xy 94.488325 -278.305367)
			(xy 94.457752 -278.346053) (xy 94.421048 -278.381308) (xy 94.379164 -278.410218) (xy 94.333185 -278.432035)
			(xy 94.284301 -278.446195) (xy 94.23378 -278.452329) (xy 94.182928 -278.45028) (xy 94.133064 -278.4401)
			(xy 94.085478 -278.422053) (xy 94.041404 -278.396607) (xy 94.001982 -278.36442) (xy 93.968234 -278.326326)
			(xy 93.941033 -278.283312) (xy 93.921085 -278.236492) (xy 93.908906 -278.187078) (xy 93.904811 -278.13635)
			(xy 92.65666 -278.13635) (xy 92.656148 -278.161796) (xy 92.647984 -278.21203) (xy 92.631868 -278.260304)
			(xy 92.608217 -278.305367) (xy 92.577644 -278.346053) (xy 92.54094 -278.381308) (xy 92.499056 -278.410218)
			(xy 92.453077 -278.432035) (xy 92.404193 -278.446195) (xy 92.353672 -278.452329) (xy 92.30282 -278.45028)
			(xy 92.252956 -278.4401) (xy 92.20537 -278.422053) (xy 92.161296 -278.396607) (xy 92.121874 -278.36442)
			(xy 92.088126 -278.326326) (xy 92.060925 -278.283312) (xy 92.040977 -278.236492) (xy 92.028798 -278.187078)
			(xy 92.024703 -278.13635) (xy 91.71686 -278.13635) (xy 91.716348 -278.161796) (xy 91.708184 -278.21203)
			(xy 91.692068 -278.260304) (xy 91.668417 -278.305367) (xy 91.637844 -278.346053) (xy 91.60114 -278.381308)
			(xy 91.559256 -278.410218) (xy 91.513277 -278.432035) (xy 91.464393 -278.446195) (xy 91.413872 -278.452329)
			(xy 91.36302 -278.45028) (xy 91.313156 -278.4401) (xy 91.26557 -278.422053) (xy 91.221496 -278.396607)
			(xy 91.182074 -278.36442) (xy 91.148326 -278.326326) (xy 91.121125 -278.283312) (xy 91.101177 -278.236492)
			(xy 91.088998 -278.187078) (xy 91.084903 -278.13635) (xy 90.766392 -278.13635) (xy 90.765897 -278.160957)
			(xy 90.758002 -278.209534) (xy 90.742418 -278.256215) (xy 90.719547 -278.299792) (xy 90.689982 -278.339136)
			(xy 90.654489 -278.373228) (xy 90.613986 -278.401184) (xy 90.569524 -278.422282) (xy 90.522253 -278.435974)
			(xy 90.473398 -278.441906) (xy 90.424223 -278.439925) (xy 90.376004 -278.430081) (xy 90.329988 -278.412629)
			(xy 90.287367 -278.388022) (xy 90.249246 -278.356897) (xy 90.216611 -278.32006) (xy 90.190308 -278.278464)
			(xy 90.171017 -278.233188) (xy 90.15924 -278.185404) (xy 90.15528 -278.13635) (xy 89.826338 -278.13635)
			(xy 89.825843 -278.160957) (xy 89.817948 -278.209534) (xy 89.802364 -278.256215) (xy 89.779493 -278.299792)
			(xy 89.749928 -278.339136) (xy 89.714435 -278.373228) (xy 89.673932 -278.401184) (xy 89.62947 -278.422282)
			(xy 89.582199 -278.435974) (xy 89.533344 -278.441906) (xy 89.484169 -278.439925) (xy 89.43595 -278.430081)
			(xy 89.389934 -278.412629) (xy 89.347313 -278.388022) (xy 89.309192 -278.356897) (xy 89.276557 -278.32006)
			(xy 89.250254 -278.278464) (xy 89.230963 -278.233188) (xy 89.219186 -278.185404) (xy 89.215226 -278.13635)
			(xy 88.886284 -278.13635) (xy 88.885789 -278.160957) (xy 88.877894 -278.209534) (xy 88.86231 -278.256215)
			(xy 88.839439 -278.299792) (xy 88.809874 -278.339136) (xy 88.774381 -278.373228) (xy 88.733878 -278.401184)
			(xy 88.689416 -278.422282) (xy 88.642145 -278.435974) (xy 88.59329 -278.441906) (xy 88.544115 -278.439925)
			(xy 88.495896 -278.430081) (xy 88.44988 -278.412629) (xy 88.407259 -278.388022) (xy 88.369138 -278.356897)
			(xy 88.336503 -278.32006) (xy 88.3102 -278.278464) (xy 88.290909 -278.233188) (xy 88.279132 -278.185404)
			(xy 88.275172 -278.13635) (xy 87.94623 -278.13635) (xy 87.945735 -278.160957) (xy 87.93784 -278.209534)
			(xy 87.922256 -278.256215) (xy 87.899385 -278.299792) (xy 87.86982 -278.339136) (xy 87.834327 -278.373228)
			(xy 87.793824 -278.401184) (xy 87.749362 -278.422282) (xy 87.702091 -278.435974) (xy 87.653236 -278.441906)
			(xy 87.604061 -278.439925) (xy 87.555842 -278.430081) (xy 87.509826 -278.412629) (xy 87.467205 -278.388022)
			(xy 87.429084 -278.356897) (xy 87.396449 -278.32006) (xy 87.370146 -278.278464) (xy 87.350855 -278.233188)
			(xy 87.339078 -278.185404) (xy 87.335118 -278.13635) (xy 87.03183 -278.13635) (xy 87.031244 -278.164473)
			(xy 87.02166 -278.219896) (xy 87.01278 -278.246586) (xy 87.009986 -278.254968) (xy 87.009986 -278.545036)
			(xy 87.010355 -278.554143) (xy 87.016726 -278.571204) (xy 87.022432 -278.57831) (xy 87.024972 -278.581104)
			(xy 87.065104 -278.615648) (xy 87.080344 -278.628856) (xy 87.081614 -278.629872) (xy 87.088577 -278.635074)
			(xy 87.104935 -278.640917) (xy 87.113618 -278.641302) (xy 87.159592 -278.641302) (xy 87.171022 -278.641048)
			(xy 87.171276 -278.641048) (xy 87.195254 -278.641539) (xy 87.242615 -278.649079) (xy 87.288215 -278.663931)
			(xy 87.330933 -278.685728) (xy 87.369717 -278.713935) (xy 87.403616 -278.747859) (xy 87.431794 -278.786665)
			(xy 87.453558 -278.829399) (xy 87.468375 -278.875011) (xy 87.475879 -278.922377) (xy 87.47633 -278.946356)
			(xy 87.805272 -278.946356) (xy 87.809232 -278.897302) (xy 87.821009 -278.849518) (xy 87.8403 -278.804242)
			(xy 87.866603 -278.762646) (xy 87.899238 -278.725809) (xy 87.937359 -278.694684) (xy 87.97998 -278.670077)
			(xy 88.025996 -278.652625) (xy 88.074215 -278.642781) (xy 88.12339 -278.6408) (xy 88.172245 -278.646732)
			(xy 88.219516 -278.660424) (xy 88.263978 -278.681522) (xy 88.304481 -278.709478) (xy 88.339974 -278.74357)
			(xy 88.369539 -278.782914) (xy 88.39241 -278.826491) (xy 88.407994 -278.873172) (xy 88.415889 -278.921749)
			(xy 88.416384 -278.946356) (xy 88.745326 -278.946356) (xy 88.749286 -278.897302) (xy 88.761063 -278.849518)
			(xy 88.780354 -278.804242) (xy 88.806657 -278.762646) (xy 88.839292 -278.725809) (xy 88.877413 -278.694684)
			(xy 88.920034 -278.670077) (xy 88.96605 -278.652625) (xy 89.014269 -278.642781) (xy 89.063444 -278.6408)
			(xy 89.112299 -278.646732) (xy 89.15957 -278.660424) (xy 89.204032 -278.681522) (xy 89.244535 -278.709478)
			(xy 89.280028 -278.74357) (xy 89.309593 -278.782914) (xy 89.332464 -278.826491) (xy 89.348048 -278.873172)
			(xy 89.355943 -278.921749) (xy 89.356438 -278.946356) (xy 89.685126 -278.946356) (xy 89.689086 -278.897302)
			(xy 89.700863 -278.849518) (xy 89.720154 -278.804242) (xy 89.746457 -278.762646) (xy 89.779092 -278.725809)
			(xy 89.817213 -278.694684) (xy 89.859834 -278.670077) (xy 89.90585 -278.652625) (xy 89.954069 -278.642781)
			(xy 90.003244 -278.6408) (xy 90.052099 -278.646732) (xy 90.09937 -278.660424) (xy 90.143832 -278.681522)
			(xy 90.184335 -278.709478) (xy 90.219828 -278.74357) (xy 90.249393 -278.782914) (xy 90.272264 -278.826491)
			(xy 90.287848 -278.873172) (xy 90.295743 -278.921749) (xy 90.296238 -278.946356) (xy 90.614749 -278.946356)
			(xy 90.618844 -278.895628) (xy 90.631023 -278.846214) (xy 90.650971 -278.799394) (xy 90.678172 -278.75638)
			(xy 90.71192 -278.718286) (xy 90.751342 -278.686099) (xy 90.795416 -278.660653) (xy 90.843002 -278.642606)
			(xy 90.892866 -278.632426) (xy 90.943718 -278.630377) (xy 90.994239 -278.636511) (xy 91.043123 -278.650671)
			(xy 91.089102 -278.672488) (xy 91.130986 -278.701398) (xy 91.16769 -278.736653) (xy 91.198263 -278.777339)
			(xy 91.221914 -278.822402) (xy 91.23803 -278.870676) (xy 91.246194 -278.92091) (xy 91.246706 -278.946356)
			(xy 91.565234 -278.946356) (xy 91.569194 -278.897302) (xy 91.580971 -278.849518) (xy 91.600262 -278.804242)
			(xy 91.626565 -278.762646) (xy 91.6592 -278.725809) (xy 91.697321 -278.694684) (xy 91.739942 -278.670077)
			(xy 91.785958 -278.652625) (xy 91.834177 -278.642781) (xy 91.883352 -278.6408) (xy 91.932207 -278.646732)
			(xy 91.979478 -278.660424) (xy 92.02394 -278.681522) (xy 92.064443 -278.709478) (xy 92.099936 -278.74357)
			(xy 92.129501 -278.782914) (xy 92.152372 -278.826491) (xy 92.167956 -278.873172) (xy 92.175851 -278.921749)
			(xy 92.176346 -278.946356) (xy 92.494857 -278.946356) (xy 92.498952 -278.895628) (xy 92.511131 -278.846214)
			(xy 92.531079 -278.799394) (xy 92.55828 -278.75638) (xy 92.592028 -278.718286) (xy 92.63145 -278.686099)
			(xy 92.675524 -278.660653) (xy 92.72311 -278.642606) (xy 92.772974 -278.632426) (xy 92.823826 -278.630377)
			(xy 92.874347 -278.636511) (xy 92.923231 -278.650671) (xy 92.96921 -278.672488) (xy 93.011094 -278.701398)
			(xy 93.047798 -278.736653) (xy 93.078371 -278.777339) (xy 93.102022 -278.822402) (xy 93.118138 -278.870676)
			(xy 93.126302 -278.92091) (xy 93.126814 -278.946356) (xy 93.445342 -278.946356) (xy 93.449302 -278.897302)
			(xy 93.461079 -278.849518) (xy 93.48037 -278.804242) (xy 93.506673 -278.762646) (xy 93.539308 -278.725809)
			(xy 93.577429 -278.694684) (xy 93.62005 -278.670077) (xy 93.666066 -278.652625) (xy 93.714285 -278.642781)
			(xy 93.76346 -278.6408) (xy 93.812315 -278.646732) (xy 93.859586 -278.660424) (xy 93.904048 -278.681522)
			(xy 93.944551 -278.709478) (xy 93.980044 -278.74357) (xy 94.009609 -278.782914) (xy 94.03248 -278.826491)
			(xy 94.048064 -278.873172) (xy 94.055959 -278.921749) (xy 94.056454 -278.946356) (xy 94.374711 -278.946356)
			(xy 94.378806 -278.895628) (xy 94.390985 -278.846214) (xy 94.410933 -278.799394) (xy 94.438134 -278.75638)
			(xy 94.471882 -278.718286) (xy 94.511304 -278.686099) (xy 94.555378 -278.660653) (xy 94.602964 -278.642606)
			(xy 94.652828 -278.632426) (xy 94.70368 -278.630377) (xy 94.754201 -278.636511) (xy 94.803085 -278.650671)
			(xy 94.849064 -278.672488) (xy 94.890948 -278.701398) (xy 94.927652 -278.736653) (xy 94.958225 -278.777339)
			(xy 94.981876 -278.822402) (xy 94.997992 -278.870676) (xy 95.006156 -278.92091) (xy 95.006668 -278.946356)
			(xy 95.314765 -278.946356) (xy 95.31886 -278.895628) (xy 95.331039 -278.846214) (xy 95.350987 -278.799394)
			(xy 95.378188 -278.75638) (xy 95.411936 -278.718286) (xy 95.451358 -278.686099) (xy 95.495432 -278.660653)
			(xy 95.543018 -278.642606) (xy 95.592882 -278.632426) (xy 95.643734 -278.630377) (xy 95.694255 -278.636511)
			(xy 95.743139 -278.650671) (xy 95.789118 -278.672488) (xy 95.831002 -278.701398) (xy 95.867706 -278.736653)
			(xy 95.898279 -278.777339) (xy 95.92193 -278.822402) (xy 95.938046 -278.870676) (xy 95.94621 -278.92091)
			(xy 95.946722 -278.946356) (xy 95.94621 -278.971802) (xy 95.938046 -279.022036) (xy 95.92193 -279.07031)
			(xy 95.898279 -279.115373) (xy 95.867706 -279.156059) (xy 95.831002 -279.191314) (xy 95.789118 -279.220224)
			(xy 95.743139 -279.242041) (xy 95.694255 -279.256201) (xy 95.643734 -279.262335) (xy 95.592882 -279.260286)
			(xy 95.543018 -279.250106) (xy 95.495432 -279.232059) (xy 95.451358 -279.206613) (xy 95.411936 -279.174426)
			(xy 95.378188 -279.136332) (xy 95.350987 -279.093318) (xy 95.331039 -279.046498) (xy 95.31886 -278.997084)
			(xy 95.314765 -278.946356) (xy 95.006668 -278.946356) (xy 95.006156 -278.971802) (xy 94.997992 -279.022036)
			(xy 94.981876 -279.07031) (xy 94.958225 -279.115373) (xy 94.927652 -279.156059) (xy 94.890948 -279.191314)
			(xy 94.849064 -279.220224) (xy 94.803085 -279.242041) (xy 94.754201 -279.256201) (xy 94.70368 -279.262335)
			(xy 94.652828 -279.260286) (xy 94.602964 -279.250106) (xy 94.555378 -279.232059) (xy 94.511304 -279.206613)
			(xy 94.471882 -279.174426) (xy 94.438134 -279.136332) (xy 94.410933 -279.093318) (xy 94.390985 -279.046498)
			(xy 94.378806 -278.997084) (xy 94.374711 -278.946356) (xy 94.056454 -278.946356) (xy 94.055959 -278.970963)
			(xy 94.048064 -279.01954) (xy 94.03248 -279.066221) (xy 94.009609 -279.109798) (xy 93.980044 -279.149142)
			(xy 93.944551 -279.183234) (xy 93.904048 -279.21119) (xy 93.859586 -279.232288) (xy 93.812315 -279.24598)
			(xy 93.76346 -279.251912) (xy 93.714285 -279.249931) (xy 93.666066 -279.240087) (xy 93.62005 -279.222635)
			(xy 93.577429 -279.198028) (xy 93.539308 -279.166903) (xy 93.506673 -279.130066) (xy 93.48037 -279.08847)
			(xy 93.461079 -279.043194) (xy 93.449302 -278.99541) (xy 93.445342 -278.946356) (xy 93.126814 -278.946356)
			(xy 93.126302 -278.971802) (xy 93.118138 -279.022036) (xy 93.102022 -279.07031) (xy 93.078371 -279.115373)
			(xy 93.047798 -279.156059) (xy 93.011094 -279.191314) (xy 92.96921 -279.220224) (xy 92.923231 -279.242041)
			(xy 92.874347 -279.256201) (xy 92.823826 -279.262335) (xy 92.772974 -279.260286) (xy 92.72311 -279.250106)
			(xy 92.675524 -279.232059) (xy 92.63145 -279.206613) (xy 92.592028 -279.174426) (xy 92.55828 -279.136332)
			(xy 92.531079 -279.093318) (xy 92.511131 -279.046498) (xy 92.498952 -278.997084) (xy 92.494857 -278.946356)
			(xy 92.176346 -278.946356) (xy 92.175851 -278.970963) (xy 92.167956 -279.01954) (xy 92.152372 -279.066221)
			(xy 92.129501 -279.109798) (xy 92.099936 -279.149142) (xy 92.064443 -279.183234) (xy 92.02394 -279.21119)
			(xy 91.979478 -279.232288) (xy 91.932207 -279.24598) (xy 91.883352 -279.251912) (xy 91.834177 -279.249931)
			(xy 91.785958 -279.240087) (xy 91.739942 -279.222635) (xy 91.697321 -279.198028) (xy 91.6592 -279.166903)
			(xy 91.626565 -279.130066) (xy 91.600262 -279.08847) (xy 91.580971 -279.043194) (xy 91.569194 -278.99541)
			(xy 91.565234 -278.946356) (xy 91.246706 -278.946356) (xy 91.246194 -278.971802) (xy 91.23803 -279.022036)
			(xy 91.221914 -279.07031) (xy 91.198263 -279.115373) (xy 91.16769 -279.156059) (xy 91.130986 -279.191314)
			(xy 91.089102 -279.220224) (xy 91.043123 -279.242041) (xy 90.994239 -279.256201) (xy 90.943718 -279.262335)
			(xy 90.892866 -279.260286) (xy 90.843002 -279.250106) (xy 90.795416 -279.232059) (xy 90.751342 -279.206613)
			(xy 90.71192 -279.174426) (xy 90.678172 -279.136332) (xy 90.650971 -279.093318) (xy 90.631023 -279.046498)
			(xy 90.618844 -278.997084) (xy 90.614749 -278.946356) (xy 90.296238 -278.946356) (xy 90.295743 -278.970963)
			(xy 90.287848 -279.01954) (xy 90.272264 -279.066221) (xy 90.249393 -279.109798) (xy 90.219828 -279.149142)
			(xy 90.184335 -279.183234) (xy 90.143832 -279.21119) (xy 90.09937 -279.232288) (xy 90.052099 -279.24598)
			(xy 90.003244 -279.251912) (xy 89.954069 -279.249931) (xy 89.90585 -279.240087) (xy 89.859834 -279.222635)
			(xy 89.817213 -279.198028) (xy 89.779092 -279.166903) (xy 89.746457 -279.130066) (xy 89.720154 -279.08847)
			(xy 89.700863 -279.043194) (xy 89.689086 -278.99541) (xy 89.685126 -278.946356) (xy 89.356438 -278.946356)
			(xy 89.355943 -278.970963) (xy 89.348048 -279.01954) (xy 89.332464 -279.066221) (xy 89.309593 -279.109798)
			(xy 89.280028 -279.149142) (xy 89.244535 -279.183234) (xy 89.204032 -279.21119) (xy 89.15957 -279.232288)
			(xy 89.112299 -279.24598) (xy 89.063444 -279.251912) (xy 89.014269 -279.249931) (xy 88.96605 -279.240087)
			(xy 88.920034 -279.222635) (xy 88.877413 -279.198028) (xy 88.839292 -279.166903) (xy 88.806657 -279.130066)
			(xy 88.780354 -279.08847) (xy 88.761063 -279.043194) (xy 88.749286 -278.99541) (xy 88.745326 -278.946356)
			(xy 88.416384 -278.946356) (xy 88.415889 -278.970963) (xy 88.407994 -279.01954) (xy 88.39241 -279.066221)
			(xy 88.369539 -279.109798) (xy 88.339974 -279.149142) (xy 88.304481 -279.183234) (xy 88.263978 -279.21119)
			(xy 88.219516 -279.232288) (xy 88.172245 -279.24598) (xy 88.12339 -279.251912) (xy 88.074215 -279.249931)
			(xy 88.025996 -279.240087) (xy 87.97998 -279.222635) (xy 87.937359 -279.198028) (xy 87.899238 -279.166903)
			(xy 87.866603 -279.130066) (xy 87.8403 -279.08847) (xy 87.821009 -279.043194) (xy 87.809232 -278.99541)
			(xy 87.805272 -278.946356) (xy 87.47633 -278.946356) (xy 87.475887 -278.970352) (xy 87.468386 -279.017754)
			(xy 87.453562 -279.063399) (xy 87.431779 -279.106163) (xy 87.403574 -279.144992) (xy 87.369643 -279.178932)
			(xy 87.330819 -279.207144) (xy 87.28806 -279.228936) (xy 87.242418 -279.243771) (xy 87.195018 -279.251282)
			(xy 87.171022 -279.251664) (xy 87.159613 -279.251589) (xy 87.136856 -279.249934) (xy 87.125556 -279.248362)
			(xy 87.114634 -279.246584) (xy 87.09279 -279.252934) (xy 87.065358 -279.27681) (xy 87.06485 -279.277318)
			(xy 87.030814 -279.306528) (xy 87.02929 -279.307798) (xy 87.024972 -279.312116) (xy 87.017606 -279.319228)
			(xy 87.009986 -279.338024) (xy 87.009986 -279.756362) (xy 87.335118 -279.756362) (xy 87.339078 -279.707308)
			(xy 87.350855 -279.659524) (xy 87.370146 -279.614248) (xy 87.396449 -279.572652) (xy 87.429084 -279.535815)
			(xy 87.467205 -279.50469) (xy 87.509826 -279.480083) (xy 87.555842 -279.462631) (xy 87.604061 -279.452787)
			(xy 87.653236 -279.450806) (xy 87.702091 -279.456738) (xy 87.749362 -279.47043) (xy 87.793824 -279.491528)
			(xy 87.834327 -279.519484) (xy 87.86982 -279.553576) (xy 87.899385 -279.59292) (xy 87.922256 -279.636497)
			(xy 87.93784 -279.683178) (xy 87.945735 -279.731755) (xy 87.94623 -279.756362) (xy 88.275172 -279.756362)
			(xy 88.279132 -279.707308) (xy 88.290909 -279.659524) (xy 88.3102 -279.614248) (xy 88.336503 -279.572652)
			(xy 88.369138 -279.535815) (xy 88.407259 -279.50469) (xy 88.44988 -279.480083) (xy 88.495896 -279.462631)
			(xy 88.544115 -279.452787) (xy 88.59329 -279.450806) (xy 88.642145 -279.456738) (xy 88.689416 -279.47043)
			(xy 88.733878 -279.491528) (xy 88.774381 -279.519484) (xy 88.809874 -279.553576) (xy 88.839439 -279.59292)
			(xy 88.86231 -279.636497) (xy 88.877894 -279.683178) (xy 88.885789 -279.731755) (xy 88.886284 -279.756362)
			(xy 89.215226 -279.756362) (xy 89.219186 -279.707308) (xy 89.230963 -279.659524) (xy 89.250254 -279.614248)
			(xy 89.276557 -279.572652) (xy 89.309192 -279.535815) (xy 89.347313 -279.50469) (xy 89.389934 -279.480083)
			(xy 89.43595 -279.462631) (xy 89.484169 -279.452787) (xy 89.533344 -279.450806) (xy 89.582199 -279.456738)
			(xy 89.62947 -279.47043) (xy 89.673932 -279.491528) (xy 89.714435 -279.519484) (xy 89.749928 -279.553576)
			(xy 89.779493 -279.59292) (xy 89.802364 -279.636497) (xy 89.817948 -279.683178) (xy 89.825843 -279.731755)
			(xy 89.826338 -279.756362) (xy 90.15528 -279.756362) (xy 90.15924 -279.707308) (xy 90.171017 -279.659524)
			(xy 90.190308 -279.614248) (xy 90.216611 -279.572652) (xy 90.249246 -279.535815) (xy 90.287367 -279.50469)
			(xy 90.329988 -279.480083) (xy 90.376004 -279.462631) (xy 90.424223 -279.452787) (xy 90.473398 -279.450806)
			(xy 90.522253 -279.456738) (xy 90.569524 -279.47043) (xy 90.613986 -279.491528) (xy 90.654489 -279.519484)
			(xy 90.689982 -279.553576) (xy 90.719547 -279.59292) (xy 90.742418 -279.636497) (xy 90.758002 -279.683178)
			(xy 90.765897 -279.731755) (xy 90.766392 -279.756362) (xy 91.084903 -279.756362) (xy 91.088998 -279.705634)
			(xy 91.101177 -279.65622) (xy 91.121125 -279.6094) (xy 91.148326 -279.566386) (xy 91.182074 -279.528292)
			(xy 91.221496 -279.496105) (xy 91.26557 -279.470659) (xy 91.313156 -279.452612) (xy 91.36302 -279.442432)
			(xy 91.413872 -279.440383) (xy 91.464393 -279.446517) (xy 91.513277 -279.460677) (xy 91.559256 -279.482494)
			(xy 91.60114 -279.511404) (xy 91.637844 -279.546659) (xy 91.668417 -279.587345) (xy 91.692068 -279.632408)
			(xy 91.708184 -279.680682) (xy 91.716348 -279.730916) (xy 91.71686 -279.756362) (xy 92.024703 -279.756362)
			(xy 92.028798 -279.705634) (xy 92.040977 -279.65622) (xy 92.060925 -279.6094) (xy 92.088126 -279.566386)
			(xy 92.121874 -279.528292) (xy 92.161296 -279.496105) (xy 92.20537 -279.470659) (xy 92.252956 -279.452612)
			(xy 92.30282 -279.442432) (xy 92.353672 -279.440383) (xy 92.404193 -279.446517) (xy 92.453077 -279.460677)
			(xy 92.499056 -279.482494) (xy 92.54094 -279.511404) (xy 92.577644 -279.546659) (xy 92.608217 -279.587345)
			(xy 92.631868 -279.632408) (xy 92.647984 -279.680682) (xy 92.656148 -279.730916) (xy 92.65666 -279.756362)
			(xy 92.975188 -279.756362) (xy 92.979148 -279.707308) (xy 92.990925 -279.659524) (xy 93.010216 -279.614248)
			(xy 93.036519 -279.572652) (xy 93.069154 -279.535815) (xy 93.107275 -279.50469) (xy 93.149896 -279.480083)
			(xy 93.195912 -279.462631) (xy 93.244131 -279.452787) (xy 93.293306 -279.450806) (xy 93.342161 -279.456738)
			(xy 93.389432 -279.47043) (xy 93.433894 -279.491528) (xy 93.474397 -279.519484) (xy 93.50989 -279.553576)
			(xy 93.539455 -279.59292) (xy 93.562326 -279.636497) (xy 93.57791 -279.683178) (xy 93.585805 -279.731755)
			(xy 93.5863 -279.756362) (xy 93.904811 -279.756362) (xy 93.908906 -279.705634) (xy 93.921085 -279.65622)
			(xy 93.941033 -279.6094) (xy 93.968234 -279.566386) (xy 94.001982 -279.528292) (xy 94.041404 -279.496105)
			(xy 94.085478 -279.470659) (xy 94.133064 -279.452612) (xy 94.182928 -279.442432) (xy 94.23378 -279.440383)
			(xy 94.284301 -279.446517) (xy 94.333185 -279.460677) (xy 94.379164 -279.482494) (xy 94.421048 -279.511404)
			(xy 94.457752 -279.546659) (xy 94.488325 -279.587345) (xy 94.511976 -279.632408) (xy 94.528092 -279.680682)
			(xy 94.536256 -279.730916) (xy 94.536768 -279.756362) (xy 94.536256 -279.781808) (xy 94.528092 -279.832042)
			(xy 94.511976 -279.880316) (xy 94.488325 -279.925379) (xy 94.457752 -279.966065) (xy 94.421048 -280.00132)
			(xy 94.379164 -280.03023) (xy 94.333185 -280.052047) (xy 94.284301 -280.066207) (xy 94.23378 -280.072341)
			(xy 94.182928 -280.070292) (xy 94.133064 -280.060112) (xy 94.085478 -280.042065) (xy 94.041404 -280.016619)
			(xy 94.001982 -279.984432) (xy 93.968234 -279.946338) (xy 93.941033 -279.903324) (xy 93.921085 -279.856504)
			(xy 93.908906 -279.80709) (xy 93.904811 -279.756362) (xy 93.5863 -279.756362) (xy 93.585805 -279.780969)
			(xy 93.57791 -279.829546) (xy 93.562326 -279.876227) (xy 93.539455 -279.919804) (xy 93.50989 -279.959148)
			(xy 93.474397 -279.99324) (xy 93.433894 -280.021196) (xy 93.389432 -280.042294) (xy 93.342161 -280.055986)
			(xy 93.293306 -280.061918) (xy 93.244131 -280.059937) (xy 93.195912 -280.050093) (xy 93.149896 -280.032641)
			(xy 93.107275 -280.008034) (xy 93.069154 -279.976909) (xy 93.036519 -279.940072) (xy 93.010216 -279.898476)
			(xy 92.990925 -279.8532) (xy 92.979148 -279.805416) (xy 92.975188 -279.756362) (xy 92.65666 -279.756362)
			(xy 92.656148 -279.781808) (xy 92.647984 -279.832042) (xy 92.631868 -279.880316) (xy 92.608217 -279.925379)
			(xy 92.577644 -279.966065) (xy 92.54094 -280.00132) (xy 92.499056 -280.03023) (xy 92.453077 -280.052047)
			(xy 92.404193 -280.066207) (xy 92.353672 -280.072341) (xy 92.30282 -280.070292) (xy 92.252956 -280.060112)
			(xy 92.20537 -280.042065) (xy 92.161296 -280.016619) (xy 92.121874 -279.984432) (xy 92.088126 -279.946338)
			(xy 92.060925 -279.903324) (xy 92.040977 -279.856504) (xy 92.028798 -279.80709) (xy 92.024703 -279.756362)
			(xy 91.71686 -279.756362) (xy 91.716348 -279.781808) (xy 91.708184 -279.832042) (xy 91.692068 -279.880316)
			(xy 91.668417 -279.925379) (xy 91.637844 -279.966065) (xy 91.60114 -280.00132) (xy 91.559256 -280.03023)
			(xy 91.513277 -280.052047) (xy 91.464393 -280.066207) (xy 91.413872 -280.072341) (xy 91.36302 -280.070292)
			(xy 91.313156 -280.060112) (xy 91.26557 -280.042065) (xy 91.221496 -280.016619) (xy 91.182074 -279.984432)
			(xy 91.148326 -279.946338) (xy 91.121125 -279.903324) (xy 91.101177 -279.856504) (xy 91.088998 -279.80709)
			(xy 91.084903 -279.756362) (xy 90.766392 -279.756362) (xy 90.765897 -279.780969) (xy 90.758002 -279.829546)
			(xy 90.742418 -279.876227) (xy 90.719547 -279.919804) (xy 90.689982 -279.959148) (xy 90.654489 -279.99324)
			(xy 90.613986 -280.021196) (xy 90.569524 -280.042294) (xy 90.522253 -280.055986) (xy 90.473398 -280.061918)
			(xy 90.424223 -280.059937) (xy 90.376004 -280.050093) (xy 90.329988 -280.032641) (xy 90.287367 -280.008034)
			(xy 90.249246 -279.976909) (xy 90.216611 -279.940072) (xy 90.190308 -279.898476) (xy 90.171017 -279.8532)
			(xy 90.15924 -279.805416) (xy 90.15528 -279.756362) (xy 89.826338 -279.756362) (xy 89.825843 -279.780969)
			(xy 89.817948 -279.829546) (xy 89.802364 -279.876227) (xy 89.779493 -279.919804) (xy 89.749928 -279.959148)
			(xy 89.714435 -279.99324) (xy 89.673932 -280.021196) (xy 89.62947 -280.042294) (xy 89.582199 -280.055986)
			(xy 89.533344 -280.061918) (xy 89.484169 -280.059937) (xy 89.43595 -280.050093) (xy 89.389934 -280.032641)
			(xy 89.347313 -280.008034) (xy 89.309192 -279.976909) (xy 89.276557 -279.940072) (xy 89.250254 -279.898476)
			(xy 89.230963 -279.8532) (xy 89.219186 -279.805416) (xy 89.215226 -279.756362) (xy 88.886284 -279.756362)
			(xy 88.885789 -279.780969) (xy 88.877894 -279.829546) (xy 88.86231 -279.876227) (xy 88.839439 -279.919804)
			(xy 88.809874 -279.959148) (xy 88.774381 -279.99324) (xy 88.733878 -280.021196) (xy 88.689416 -280.042294)
			(xy 88.642145 -280.055986) (xy 88.59329 -280.061918) (xy 88.544115 -280.059937) (xy 88.495896 -280.050093)
			(xy 88.44988 -280.032641) (xy 88.407259 -280.008034) (xy 88.369138 -279.976909) (xy 88.336503 -279.940072)
			(xy 88.3102 -279.898476) (xy 88.290909 -279.8532) (xy 88.279132 -279.805416) (xy 88.275172 -279.756362)
			(xy 87.94623 -279.756362) (xy 87.945735 -279.780969) (xy 87.93784 -279.829546) (xy 87.922256 -279.876227)
			(xy 87.899385 -279.919804) (xy 87.86982 -279.959148) (xy 87.834327 -279.99324) (xy 87.793824 -280.021196)
			(xy 87.749362 -280.042294) (xy 87.702091 -280.055986) (xy 87.653236 -280.061918) (xy 87.604061 -280.059937)
			(xy 87.555842 -280.050093) (xy 87.509826 -280.032641) (xy 87.467205 -280.008034) (xy 87.429084 -279.976909)
			(xy 87.396449 -279.940072) (xy 87.370146 -279.898476) (xy 87.350855 -279.8532) (xy 87.339078 -279.805416)
			(xy 87.335118 -279.756362) (xy 87.009986 -279.756362) (xy 87.009986 -280.566368) (xy 87.805272 -280.566368)
			(xy 87.809232 -280.517314) (xy 87.821009 -280.46953) (xy 87.8403 -280.424254) (xy 87.866603 -280.382658)
			(xy 87.899238 -280.345821) (xy 87.937359 -280.314696) (xy 87.97998 -280.290089) (xy 88.025996 -280.272637)
			(xy 88.074215 -280.262793) (xy 88.12339 -280.260812) (xy 88.172245 -280.266744) (xy 88.219516 -280.280436)
			(xy 88.263978 -280.301534) (xy 88.304481 -280.32949) (xy 88.339974 -280.363582) (xy 88.369539 -280.402926)
			(xy 88.39241 -280.446503) (xy 88.407994 -280.493184) (xy 88.415889 -280.541761) (xy 88.416384 -280.566368)
			(xy 88.745326 -280.566368) (xy 88.749286 -280.517314) (xy 88.761063 -280.46953) (xy 88.780354 -280.424254)
			(xy 88.806657 -280.382658) (xy 88.839292 -280.345821) (xy 88.877413 -280.314696) (xy 88.920034 -280.290089)
			(xy 88.96605 -280.272637) (xy 89.014269 -280.262793) (xy 89.063444 -280.260812) (xy 89.112299 -280.266744)
			(xy 89.15957 -280.280436) (xy 89.204032 -280.301534) (xy 89.244535 -280.32949) (xy 89.280028 -280.363582)
			(xy 89.309593 -280.402926) (xy 89.332464 -280.446503) (xy 89.348048 -280.493184) (xy 89.355943 -280.541761)
			(xy 89.356438 -280.566368) (xy 89.685126 -280.566368) (xy 89.689086 -280.517314) (xy 89.700863 -280.46953)
			(xy 89.720154 -280.424254) (xy 89.746457 -280.382658) (xy 89.779092 -280.345821) (xy 89.817213 -280.314696)
			(xy 89.859834 -280.290089) (xy 89.90585 -280.272637) (xy 89.954069 -280.262793) (xy 90.003244 -280.260812)
			(xy 90.052099 -280.266744) (xy 90.09937 -280.280436) (xy 90.143832 -280.301534) (xy 90.184335 -280.32949)
			(xy 90.219828 -280.363582) (xy 90.249393 -280.402926) (xy 90.272264 -280.446503) (xy 90.287848 -280.493184)
			(xy 90.295743 -280.541761) (xy 90.296238 -280.566368) (xy 90.614749 -280.566368) (xy 90.618844 -280.51564)
			(xy 90.631023 -280.466226) (xy 90.650971 -280.419406) (xy 90.678172 -280.376392) (xy 90.71192 -280.338298)
			(xy 90.751342 -280.306111) (xy 90.795416 -280.280665) (xy 90.843002 -280.262618) (xy 90.892866 -280.252438)
			(xy 90.943718 -280.250389) (xy 90.994239 -280.256523) (xy 91.043123 -280.270683) (xy 91.089102 -280.2925)
			(xy 91.130986 -280.32141) (xy 91.16769 -280.356665) (xy 91.198263 -280.397351) (xy 91.221914 -280.442414)
			(xy 91.23803 -280.490688) (xy 91.246194 -280.540922) (xy 91.246706 -280.566368) (xy 91.565234 -280.566368)
			(xy 91.569194 -280.517314) (xy 91.580971 -280.46953) (xy 91.600262 -280.424254) (xy 91.626565 -280.382658)
			(xy 91.6592 -280.345821) (xy 91.697321 -280.314696) (xy 91.739942 -280.290089) (xy 91.785958 -280.272637)
			(xy 91.834177 -280.262793) (xy 91.883352 -280.260812) (xy 91.932207 -280.266744) (xy 91.979478 -280.280436)
			(xy 92.02394 -280.301534) (xy 92.064443 -280.32949) (xy 92.099936 -280.363582) (xy 92.129501 -280.402926)
			(xy 92.152372 -280.446503) (xy 92.167956 -280.493184) (xy 92.175851 -280.541761) (xy 92.176346 -280.566368)
			(xy 92.494857 -280.566368) (xy 92.498952 -280.51564) (xy 92.511131 -280.466226) (xy 92.531079 -280.419406)
			(xy 92.55828 -280.376392) (xy 92.592028 -280.338298) (xy 92.63145 -280.306111) (xy 92.675524 -280.280665)
			(xy 92.72311 -280.262618) (xy 92.772974 -280.252438) (xy 92.823826 -280.250389) (xy 92.874347 -280.256523)
			(xy 92.923231 -280.270683) (xy 92.96921 -280.2925) (xy 93.011094 -280.32141) (xy 93.047798 -280.356665)
			(xy 93.078371 -280.397351) (xy 93.102022 -280.442414) (xy 93.118138 -280.490688) (xy 93.126302 -280.540922)
			(xy 93.126814 -280.566368) (xy 94.374711 -280.566368) (xy 94.378806 -280.51564) (xy 94.390985 -280.466226)
			(xy 94.410933 -280.419406) (xy 94.438134 -280.376392) (xy 94.471882 -280.338298) (xy 94.511304 -280.306111)
			(xy 94.555378 -280.280665) (xy 94.602964 -280.262618) (xy 94.652828 -280.252438) (xy 94.70368 -280.250389)
			(xy 94.754201 -280.256523) (xy 94.803085 -280.270683) (xy 94.849064 -280.2925) (xy 94.890948 -280.32141)
			(xy 94.927652 -280.356665) (xy 94.958225 -280.397351) (xy 94.981876 -280.442414) (xy 94.997992 -280.490688)
			(xy 95.006156 -280.540922) (xy 95.006668 -280.566368) (xy 95.006156 -280.591814) (xy 94.997992 -280.642048)
			(xy 94.981876 -280.690322) (xy 94.958225 -280.735385) (xy 94.927652 -280.776071) (xy 94.890948 -280.811326)
			(xy 94.849064 -280.840236) (xy 94.803085 -280.862053) (xy 94.754201 -280.876213) (xy 94.70368 -280.882347)
			(xy 94.652828 -280.880298) (xy 94.602964 -280.870118) (xy 94.555378 -280.852071) (xy 94.511304 -280.826625)
			(xy 94.471882 -280.794438) (xy 94.438134 -280.756344) (xy 94.410933 -280.71333) (xy 94.390985 -280.66651)
			(xy 94.378806 -280.617096) (xy 94.374711 -280.566368) (xy 93.126814 -280.566368) (xy 93.126302 -280.591814)
			(xy 93.118138 -280.642048) (xy 93.102022 -280.690322) (xy 93.078371 -280.735385) (xy 93.047798 -280.776071)
			(xy 93.011094 -280.811326) (xy 92.96921 -280.840236) (xy 92.923231 -280.862053) (xy 92.874347 -280.876213)
			(xy 92.823826 -280.882347) (xy 92.772974 -280.880298) (xy 92.72311 -280.870118) (xy 92.675524 -280.852071)
			(xy 92.63145 -280.826625) (xy 92.592028 -280.794438) (xy 92.55828 -280.756344) (xy 92.531079 -280.71333)
			(xy 92.511131 -280.66651) (xy 92.498952 -280.617096) (xy 92.494857 -280.566368) (xy 92.176346 -280.566368)
			(xy 92.175851 -280.590975) (xy 92.167956 -280.639552) (xy 92.152372 -280.686233) (xy 92.129501 -280.72981)
			(xy 92.099936 -280.769154) (xy 92.064443 -280.803246) (xy 92.02394 -280.831202) (xy 91.979478 -280.8523)
			(xy 91.932207 -280.865992) (xy 91.883352 -280.871924) (xy 91.834177 -280.869943) (xy 91.785958 -280.860099)
			(xy 91.739942 -280.842647) (xy 91.697321 -280.81804) (xy 91.6592 -280.786915) (xy 91.626565 -280.750078)
			(xy 91.600262 -280.708482) (xy 91.580971 -280.663206) (xy 91.569194 -280.615422) (xy 91.565234 -280.566368)
			(xy 91.246706 -280.566368) (xy 91.246194 -280.591814) (xy 91.23803 -280.642048) (xy 91.221914 -280.690322)
			(xy 91.198263 -280.735385) (xy 91.16769 -280.776071) (xy 91.130986 -280.811326) (xy 91.089102 -280.840236)
			(xy 91.043123 -280.862053) (xy 90.994239 -280.876213) (xy 90.943718 -280.882347) (xy 90.892866 -280.880298)
			(xy 90.843002 -280.870118) (xy 90.795416 -280.852071) (xy 90.751342 -280.826625) (xy 90.71192 -280.794438)
			(xy 90.678172 -280.756344) (xy 90.650971 -280.71333) (xy 90.631023 -280.66651) (xy 90.618844 -280.617096)
			(xy 90.614749 -280.566368) (xy 90.296238 -280.566368) (xy 90.295743 -280.590975) (xy 90.287848 -280.639552)
			(xy 90.272264 -280.686233) (xy 90.249393 -280.72981) (xy 90.219828 -280.769154) (xy 90.184335 -280.803246)
			(xy 90.143832 -280.831202) (xy 90.09937 -280.8523) (xy 90.052099 -280.865992) (xy 90.003244 -280.871924)
			(xy 89.954069 -280.869943) (xy 89.90585 -280.860099) (xy 89.859834 -280.842647) (xy 89.817213 -280.81804)
			(xy 89.779092 -280.786915) (xy 89.746457 -280.750078) (xy 89.720154 -280.708482) (xy 89.700863 -280.663206)
			(xy 89.689086 -280.615422) (xy 89.685126 -280.566368) (xy 89.356438 -280.566368) (xy 89.355943 -280.590975)
			(xy 89.348048 -280.639552) (xy 89.332464 -280.686233) (xy 89.309593 -280.72981) (xy 89.280028 -280.769154)
			(xy 89.244535 -280.803246) (xy 89.204032 -280.831202) (xy 89.15957 -280.8523) (xy 89.112299 -280.865992)
			(xy 89.063444 -280.871924) (xy 89.014269 -280.869943) (xy 88.96605 -280.860099) (xy 88.920034 -280.842647)
			(xy 88.877413 -280.81804) (xy 88.839292 -280.786915) (xy 88.806657 -280.750078) (xy 88.780354 -280.708482)
			(xy 88.761063 -280.663206) (xy 88.749286 -280.615422) (xy 88.745326 -280.566368) (xy 88.416384 -280.566368)
			(xy 88.415889 -280.590975) (xy 88.407994 -280.639552) (xy 88.39241 -280.686233) (xy 88.369539 -280.72981)
			(xy 88.339974 -280.769154) (xy 88.304481 -280.803246) (xy 88.263978 -280.831202) (xy 88.219516 -280.8523)
			(xy 88.172245 -280.865992) (xy 88.12339 -280.871924) (xy 88.074215 -280.869943) (xy 88.025996 -280.860099)
			(xy 87.97998 -280.842647) (xy 87.937359 -280.81804) (xy 87.899238 -280.786915) (xy 87.866603 -280.750078)
			(xy 87.8403 -280.708482) (xy 87.821009 -280.663206) (xy 87.809232 -280.615422) (xy 87.805272 -280.566368)
			(xy 87.009986 -280.566368) (xy 87.009986 -281.376374) (xy 87.335118 -281.376374) (xy 87.339078 -281.32732)
			(xy 87.350855 -281.279536) (xy 87.370146 -281.23426) (xy 87.396449 -281.192664) (xy 87.429084 -281.155827)
			(xy 87.467205 -281.124702) (xy 87.509826 -281.100095) (xy 87.555842 -281.082643) (xy 87.604061 -281.072799)
			(xy 87.653236 -281.070818) (xy 87.702091 -281.07675) (xy 87.749362 -281.090442) (xy 87.793824 -281.11154)
			(xy 87.834327 -281.139496) (xy 87.86982 -281.173588) (xy 87.899385 -281.212932) (xy 87.922256 -281.256509)
			(xy 87.93784 -281.30319) (xy 87.945735 -281.351767) (xy 87.94623 -281.376374) (xy 88.275172 -281.376374)
			(xy 88.279132 -281.32732) (xy 88.290909 -281.279536) (xy 88.3102 -281.23426) (xy 88.336503 -281.192664)
			(xy 88.369138 -281.155827) (xy 88.407259 -281.124702) (xy 88.44988 -281.100095) (xy 88.495896 -281.082643)
			(xy 88.544115 -281.072799) (xy 88.59329 -281.070818) (xy 88.642145 -281.07675) (xy 88.689416 -281.090442)
			(xy 88.733878 -281.11154) (xy 88.774381 -281.139496) (xy 88.809874 -281.173588) (xy 88.839439 -281.212932)
			(xy 88.86231 -281.256509) (xy 88.877894 -281.30319) (xy 88.885789 -281.351767) (xy 88.886284 -281.376374)
			(xy 89.215226 -281.376374) (xy 89.219186 -281.32732) (xy 89.230963 -281.279536) (xy 89.250254 -281.23426)
			(xy 89.276557 -281.192664) (xy 89.309192 -281.155827) (xy 89.347313 -281.124702) (xy 89.389934 -281.100095)
			(xy 89.43595 -281.082643) (xy 89.484169 -281.072799) (xy 89.533344 -281.070818) (xy 89.582199 -281.07675)
			(xy 89.62947 -281.090442) (xy 89.673932 -281.11154) (xy 89.714435 -281.139496) (xy 89.749928 -281.173588)
			(xy 89.779493 -281.212932) (xy 89.802364 -281.256509) (xy 89.817948 -281.30319) (xy 89.825843 -281.351767)
			(xy 89.826338 -281.376374) (xy 90.15528 -281.376374) (xy 90.15924 -281.32732) (xy 90.171017 -281.279536)
			(xy 90.190308 -281.23426) (xy 90.216611 -281.192664) (xy 90.249246 -281.155827) (xy 90.287367 -281.124702)
			(xy 90.329988 -281.100095) (xy 90.376004 -281.082643) (xy 90.424223 -281.072799) (xy 90.473398 -281.070818)
			(xy 90.522253 -281.07675) (xy 90.569524 -281.090442) (xy 90.613986 -281.11154) (xy 90.654489 -281.139496)
			(xy 90.689982 -281.173588) (xy 90.719547 -281.212932) (xy 90.742418 -281.256509) (xy 90.758002 -281.30319)
			(xy 90.765897 -281.351767) (xy 90.766392 -281.376374) (xy 91.084903 -281.376374) (xy 91.088998 -281.325646)
			(xy 91.101177 -281.276232) (xy 91.121125 -281.229412) (xy 91.148326 -281.186398) (xy 91.182074 -281.148304)
			(xy 91.221496 -281.116117) (xy 91.26557 -281.090671) (xy 91.313156 -281.072624) (xy 91.36302 -281.062444)
			(xy 91.413872 -281.060395) (xy 91.464393 -281.066529) (xy 91.513277 -281.080689) (xy 91.559256 -281.102506)
			(xy 91.60114 -281.131416) (xy 91.637844 -281.166671) (xy 91.668417 -281.207357) (xy 91.692068 -281.25242)
			(xy 91.708184 -281.300694) (xy 91.716348 -281.350928) (xy 91.71686 -281.376374) (xy 92.024703 -281.376374)
			(xy 92.028798 -281.325646) (xy 92.040977 -281.276232) (xy 92.060925 -281.229412) (xy 92.088126 -281.186398)
			(xy 92.121874 -281.148304) (xy 92.161296 -281.116117) (xy 92.20537 -281.090671) (xy 92.252956 -281.072624)
			(xy 92.30282 -281.062444) (xy 92.353672 -281.060395) (xy 92.404193 -281.066529) (xy 92.453077 -281.080689)
			(xy 92.499056 -281.102506) (xy 92.54094 -281.131416) (xy 92.577644 -281.166671) (xy 92.608217 -281.207357)
			(xy 92.631868 -281.25242) (xy 92.647984 -281.300694) (xy 92.656148 -281.350928) (xy 92.65666 -281.376374)
			(xy 92.975188 -281.376374) (xy 92.979148 -281.32732) (xy 92.990925 -281.279536) (xy 93.010216 -281.23426)
			(xy 93.036519 -281.192664) (xy 93.069154 -281.155827) (xy 93.107275 -281.124702) (xy 93.149896 -281.100095)
			(xy 93.195912 -281.082643) (xy 93.244131 -281.072799) (xy 93.293306 -281.070818) (xy 93.342161 -281.07675)
			(xy 93.389432 -281.090442) (xy 93.433894 -281.11154) (xy 93.474397 -281.139496) (xy 93.50989 -281.173588)
			(xy 93.539455 -281.212932) (xy 93.562326 -281.256509) (xy 93.57791 -281.30319) (xy 93.585805 -281.351767)
			(xy 93.5863 -281.376374) (xy 93.904811 -281.376374) (xy 93.908906 -281.325646) (xy 93.921085 -281.276232)
			(xy 93.941033 -281.229412) (xy 93.968234 -281.186398) (xy 94.001982 -281.148304) (xy 94.041404 -281.116117)
			(xy 94.085478 -281.090671) (xy 94.133064 -281.072624) (xy 94.182928 -281.062444) (xy 94.23378 -281.060395)
			(xy 94.284301 -281.066529) (xy 94.333185 -281.080689) (xy 94.379164 -281.102506) (xy 94.421048 -281.131416)
			(xy 94.457752 -281.166671) (xy 94.488325 -281.207357) (xy 94.511976 -281.25242) (xy 94.528092 -281.300694)
			(xy 94.536256 -281.350928) (xy 94.536768 -281.376374) (xy 94.855296 -281.376374) (xy 94.859256 -281.32732)
			(xy 94.871033 -281.279536) (xy 94.890324 -281.23426) (xy 94.916627 -281.192664) (xy 94.949262 -281.155827)
			(xy 94.987383 -281.124702) (xy 95.030004 -281.100095) (xy 95.07602 -281.082643) (xy 95.124239 -281.072799)
			(xy 95.173414 -281.070818) (xy 95.222269 -281.07675) (xy 95.26954 -281.090442) (xy 95.314002 -281.11154)
			(xy 95.354505 -281.139496) (xy 95.389998 -281.173588) (xy 95.419563 -281.212932) (xy 95.442434 -281.256509)
			(xy 95.458018 -281.30319) (xy 95.465913 -281.351767) (xy 95.466408 -281.376374) (xy 95.784919 -281.376374)
			(xy 95.789014 -281.325646) (xy 95.801193 -281.276232) (xy 95.821141 -281.229412) (xy 95.848342 -281.186398)
			(xy 95.88209 -281.148304) (xy 95.921512 -281.116117) (xy 95.965586 -281.090671) (xy 96.013172 -281.072624)
			(xy 96.063036 -281.062444) (xy 96.113888 -281.060395) (xy 96.164409 -281.066529) (xy 96.213293 -281.080689)
			(xy 96.259272 -281.102506) (xy 96.301156 -281.131416) (xy 96.33786 -281.166671) (xy 96.368433 -281.207357)
			(xy 96.392084 -281.25242) (xy 96.4082 -281.300694) (xy 96.416364 -281.350928) (xy 96.416876 -281.376374)
			(xy 96.416364 -281.40182) (xy 96.4082 -281.452054) (xy 96.392084 -281.500328) (xy 96.368433 -281.545391)
			(xy 96.33786 -281.586077) (xy 96.301156 -281.621332) (xy 96.259272 -281.650242) (xy 96.213293 -281.672059)
			(xy 96.164409 -281.686219) (xy 96.113888 -281.692353) (xy 96.063036 -281.690304) (xy 96.013172 -281.680124)
			(xy 95.965586 -281.662077) (xy 95.921512 -281.636631) (xy 95.88209 -281.604444) (xy 95.848342 -281.56635)
			(xy 95.821141 -281.523336) (xy 95.801193 -281.476516) (xy 95.789014 -281.427102) (xy 95.784919 -281.376374)
			(xy 95.466408 -281.376374) (xy 95.465913 -281.400981) (xy 95.458018 -281.449558) (xy 95.442434 -281.496239)
			(xy 95.419563 -281.539816) (xy 95.389998 -281.57916) (xy 95.354505 -281.613252) (xy 95.314002 -281.641208)
			(xy 95.26954 -281.662306) (xy 95.222269 -281.675998) (xy 95.173414 -281.68193) (xy 95.124239 -281.679949)
			(xy 95.07602 -281.670105) (xy 95.030004 -281.652653) (xy 94.987383 -281.628046) (xy 94.949262 -281.596921)
			(xy 94.916627 -281.560084) (xy 94.890324 -281.518488) (xy 94.871033 -281.473212) (xy 94.859256 -281.425428)
			(xy 94.855296 -281.376374) (xy 94.536768 -281.376374) (xy 94.536256 -281.40182) (xy 94.528092 -281.452054)
			(xy 94.511976 -281.500328) (xy 94.488325 -281.545391) (xy 94.457752 -281.586077) (xy 94.421048 -281.621332)
			(xy 94.379164 -281.650242) (xy 94.333185 -281.672059) (xy 94.284301 -281.686219) (xy 94.23378 -281.692353)
			(xy 94.182928 -281.690304) (xy 94.133064 -281.680124) (xy 94.085478 -281.662077) (xy 94.041404 -281.636631)
			(xy 94.001982 -281.604444) (xy 93.968234 -281.56635) (xy 93.941033 -281.523336) (xy 93.921085 -281.476516)
			(xy 93.908906 -281.427102) (xy 93.904811 -281.376374) (xy 93.5863 -281.376374) (xy 93.585805 -281.400981)
			(xy 93.57791 -281.449558) (xy 93.562326 -281.496239) (xy 93.539455 -281.539816) (xy 93.50989 -281.57916)
			(xy 93.474397 -281.613252) (xy 93.433894 -281.641208) (xy 93.389432 -281.662306) (xy 93.342161 -281.675998)
			(xy 93.293306 -281.68193) (xy 93.244131 -281.679949) (xy 93.195912 -281.670105) (xy 93.149896 -281.652653)
			(xy 93.107275 -281.628046) (xy 93.069154 -281.596921) (xy 93.036519 -281.560084) (xy 93.010216 -281.518488)
			(xy 92.990925 -281.473212) (xy 92.979148 -281.425428) (xy 92.975188 -281.376374) (xy 92.65666 -281.376374)
			(xy 92.656148 -281.40182) (xy 92.647984 -281.452054) (xy 92.631868 -281.500328) (xy 92.608217 -281.545391)
			(xy 92.577644 -281.586077) (xy 92.54094 -281.621332) (xy 92.499056 -281.650242) (xy 92.453077 -281.672059)
			(xy 92.404193 -281.686219) (xy 92.353672 -281.692353) (xy 92.30282 -281.690304) (xy 92.252956 -281.680124)
			(xy 92.20537 -281.662077) (xy 92.161296 -281.636631) (xy 92.121874 -281.604444) (xy 92.088126 -281.56635)
			(xy 92.060925 -281.523336) (xy 92.040977 -281.476516) (xy 92.028798 -281.427102) (xy 92.024703 -281.376374)
			(xy 91.71686 -281.376374) (xy 91.716348 -281.40182) (xy 91.708184 -281.452054) (xy 91.692068 -281.500328)
			(xy 91.668417 -281.545391) (xy 91.637844 -281.586077) (xy 91.60114 -281.621332) (xy 91.559256 -281.650242)
			(xy 91.513277 -281.672059) (xy 91.464393 -281.686219) (xy 91.413872 -281.692353) (xy 91.36302 -281.690304)
			(xy 91.313156 -281.680124) (xy 91.26557 -281.662077) (xy 91.221496 -281.636631) (xy 91.182074 -281.604444)
			(xy 91.148326 -281.56635) (xy 91.121125 -281.523336) (xy 91.101177 -281.476516) (xy 91.088998 -281.427102)
			(xy 91.084903 -281.376374) (xy 90.766392 -281.376374) (xy 90.765897 -281.400981) (xy 90.758002 -281.449558)
			(xy 90.742418 -281.496239) (xy 90.719547 -281.539816) (xy 90.689982 -281.57916) (xy 90.654489 -281.613252)
			(xy 90.613986 -281.641208) (xy 90.569524 -281.662306) (xy 90.522253 -281.675998) (xy 90.473398 -281.68193)
			(xy 90.424223 -281.679949) (xy 90.376004 -281.670105) (xy 90.329988 -281.652653) (xy 90.287367 -281.628046)
			(xy 90.249246 -281.596921) (xy 90.216611 -281.560084) (xy 90.190308 -281.518488) (xy 90.171017 -281.473212)
			(xy 90.15924 -281.425428) (xy 90.15528 -281.376374) (xy 89.826338 -281.376374) (xy 89.825843 -281.400981)
			(xy 89.817948 -281.449558) (xy 89.802364 -281.496239) (xy 89.779493 -281.539816) (xy 89.749928 -281.57916)
			(xy 89.714435 -281.613252) (xy 89.673932 -281.641208) (xy 89.62947 -281.662306) (xy 89.582199 -281.675998)
			(xy 89.533344 -281.68193) (xy 89.484169 -281.679949) (xy 89.43595 -281.670105) (xy 89.389934 -281.652653)
			(xy 89.347313 -281.628046) (xy 89.309192 -281.596921) (xy 89.276557 -281.560084) (xy 89.250254 -281.518488)
			(xy 89.230963 -281.473212) (xy 89.219186 -281.425428) (xy 89.215226 -281.376374) (xy 88.886284 -281.376374)
			(xy 88.885789 -281.400981) (xy 88.877894 -281.449558) (xy 88.86231 -281.496239) (xy 88.839439 -281.539816)
			(xy 88.809874 -281.57916) (xy 88.774381 -281.613252) (xy 88.733878 -281.641208) (xy 88.689416 -281.662306)
			(xy 88.642145 -281.675998) (xy 88.59329 -281.68193) (xy 88.544115 -281.679949) (xy 88.495896 -281.670105)
			(xy 88.44988 -281.652653) (xy 88.407259 -281.628046) (xy 88.369138 -281.596921) (xy 88.336503 -281.560084)
			(xy 88.3102 -281.518488) (xy 88.290909 -281.473212) (xy 88.279132 -281.425428) (xy 88.275172 -281.376374)
			(xy 87.94623 -281.376374) (xy 87.945735 -281.400981) (xy 87.93784 -281.449558) (xy 87.922256 -281.496239)
			(xy 87.899385 -281.539816) (xy 87.86982 -281.57916) (xy 87.834327 -281.613252) (xy 87.793824 -281.641208)
			(xy 87.749362 -281.662306) (xy 87.702091 -281.675998) (xy 87.653236 -281.68193) (xy 87.604061 -281.679949)
			(xy 87.555842 -281.670105) (xy 87.509826 -281.652653) (xy 87.467205 -281.628046) (xy 87.429084 -281.596921)
			(xy 87.396449 -281.560084) (xy 87.370146 -281.518488) (xy 87.350855 -281.473212) (xy 87.339078 -281.425428)
			(xy 87.335118 -281.376374) (xy 87.009986 -281.376374) (xy 87.009986 -281.78506) (xy 87.010359 -281.794165)
			(xy 87.016736 -281.811221) (xy 87.022432 -281.818334) (xy 87.024972 -281.821128) (xy 87.065104 -281.855672)
			(xy 87.080344 -281.86888) (xy 87.081614 -281.869896) (xy 87.088578 -281.875096) (xy 87.104935 -281.880936)
			(xy 87.113618 -281.881326) (xy 87.159592 -281.881326) (xy 87.171022 -281.881072) (xy 87.171276 -281.881072)
			(xy 87.195254 -281.881563) (xy 87.242613 -281.889103) (xy 87.288212 -281.903955) (xy 87.330927 -281.925753)
			(xy 87.36971 -281.953961) (xy 87.403606 -281.987885) (xy 87.431781 -282.026691) (xy 87.453543 -282.069425)
			(xy 87.468357 -282.115036) (xy 87.475857 -282.162402) (xy 87.47633 -282.18638) (xy 87.805272 -282.18638)
			(xy 87.809232 -282.137326) (xy 87.821009 -282.089542) (xy 87.8403 -282.044266) (xy 87.866603 -282.00267)
			(xy 87.899238 -281.965833) (xy 87.937359 -281.934708) (xy 87.97998 -281.910101) (xy 88.025996 -281.892649)
			(xy 88.074215 -281.882805) (xy 88.12339 -281.880824) (xy 88.172245 -281.886756) (xy 88.219516 -281.900448)
			(xy 88.263978 -281.921546) (xy 88.304481 -281.949502) (xy 88.339974 -281.983594) (xy 88.369539 -282.022938)
			(xy 88.39241 -282.066515) (xy 88.407994 -282.113196) (xy 88.415889 -282.161773) (xy 88.416384 -282.18638)
			(xy 88.745326 -282.18638) (xy 88.749286 -282.137326) (xy 88.761063 -282.089542) (xy 88.780354 -282.044266)
			(xy 88.806657 -282.00267) (xy 88.839292 -281.965833) (xy 88.877413 -281.934708) (xy 88.920034 -281.910101)
			(xy 88.96605 -281.892649) (xy 89.014269 -281.882805) (xy 89.063444 -281.880824) (xy 89.112299 -281.886756)
			(xy 89.15957 -281.900448) (xy 89.204032 -281.921546) (xy 89.244535 -281.949502) (xy 89.280028 -281.983594)
			(xy 89.309593 -282.022938) (xy 89.332464 -282.066515) (xy 89.348048 -282.113196) (xy 89.355943 -282.161773)
			(xy 89.356438 -282.18638) (xy 89.685126 -282.18638) (xy 89.689086 -282.137326) (xy 89.700863 -282.089542)
			(xy 89.720154 -282.044266) (xy 89.746457 -282.00267) (xy 89.779092 -281.965833) (xy 89.817213 -281.934708)
			(xy 89.859834 -281.910101) (xy 89.90585 -281.892649) (xy 89.954069 -281.882805) (xy 90.003244 -281.880824)
			(xy 90.052099 -281.886756) (xy 90.09937 -281.900448) (xy 90.143832 -281.921546) (xy 90.184335 -281.949502)
			(xy 90.219828 -281.983594) (xy 90.249393 -282.022938) (xy 90.272264 -282.066515) (xy 90.287848 -282.113196)
			(xy 90.295743 -282.161773) (xy 90.296238 -282.18638) (xy 90.614749 -282.18638) (xy 90.618844 -282.135652)
			(xy 90.631023 -282.086238) (xy 90.650971 -282.039418) (xy 90.678172 -281.996404) (xy 90.71192 -281.95831)
			(xy 90.751342 -281.926123) (xy 90.795416 -281.900677) (xy 90.843002 -281.88263) (xy 90.892866 -281.87245)
			(xy 90.943718 -281.870401) (xy 90.994239 -281.876535) (xy 91.043123 -281.890695) (xy 91.089102 -281.912512)
			(xy 91.130986 -281.941422) (xy 91.16769 -281.976677) (xy 91.198263 -282.017363) (xy 91.221914 -282.062426)
			(xy 91.23803 -282.1107) (xy 91.246194 -282.160934) (xy 91.246706 -282.18638) (xy 91.565234 -282.18638)
			(xy 91.569194 -282.137326) (xy 91.580971 -282.089542) (xy 91.600262 -282.044266) (xy 91.626565 -282.00267)
			(xy 91.6592 -281.965833) (xy 91.697321 -281.934708) (xy 91.739942 -281.910101) (xy 91.785958 -281.892649)
			(xy 91.834177 -281.882805) (xy 91.883352 -281.880824) (xy 91.932207 -281.886756) (xy 91.979478 -281.900448)
			(xy 92.02394 -281.921546) (xy 92.064443 -281.949502) (xy 92.099936 -281.983594) (xy 92.129501 -282.022938)
			(xy 92.152372 -282.066515) (xy 92.167956 -282.113196) (xy 92.175851 -282.161773) (xy 92.176346 -282.18638)
			(xy 92.494857 -282.18638) (xy 92.498952 -282.135652) (xy 92.511131 -282.086238) (xy 92.531079 -282.039418)
			(xy 92.55828 -281.996404) (xy 92.592028 -281.95831) (xy 92.63145 -281.926123) (xy 92.675524 -281.900677)
			(xy 92.72311 -281.88263) (xy 92.772974 -281.87245) (xy 92.823826 -281.870401) (xy 92.874347 -281.876535)
			(xy 92.923231 -281.890695) (xy 92.96921 -281.912512) (xy 93.011094 -281.941422) (xy 93.047798 -281.976677)
			(xy 93.078371 -282.017363) (xy 93.102022 -282.062426) (xy 93.118138 -282.1107) (xy 93.126302 -282.160934)
			(xy 93.126814 -282.18638) (xy 93.445342 -282.18638) (xy 93.449302 -282.137326) (xy 93.461079 -282.089542)
			(xy 93.48037 -282.044266) (xy 93.506673 -282.00267) (xy 93.539308 -281.965833) (xy 93.577429 -281.934708)
			(xy 93.62005 -281.910101) (xy 93.666066 -281.892649) (xy 93.714285 -281.882805) (xy 93.76346 -281.880824)
			(xy 93.812315 -281.886756) (xy 93.859586 -281.900448) (xy 93.904048 -281.921546) (xy 93.944551 -281.949502)
			(xy 93.980044 -281.983594) (xy 94.009609 -282.022938) (xy 94.03248 -282.066515) (xy 94.048064 -282.113196)
			(xy 94.055959 -282.161773) (xy 94.056454 -282.18638) (xy 94.374711 -282.18638) (xy 94.378806 -282.135652)
			(xy 94.390985 -282.086238) (xy 94.410933 -282.039418) (xy 94.438134 -281.996404) (xy 94.471882 -281.95831)
			(xy 94.511304 -281.926123) (xy 94.555378 -281.900677) (xy 94.602964 -281.88263) (xy 94.652828 -281.87245)
			(xy 94.70368 -281.870401) (xy 94.754201 -281.876535) (xy 94.803085 -281.890695) (xy 94.849064 -281.912512)
			(xy 94.890948 -281.941422) (xy 94.927652 -281.976677) (xy 94.958225 -282.017363) (xy 94.981876 -282.062426)
			(xy 94.997992 -282.1107) (xy 95.006156 -282.160934) (xy 95.006668 -282.18638) (xy 95.314765 -282.18638)
			(xy 95.31886 -282.135652) (xy 95.331039 -282.086238) (xy 95.350987 -282.039418) (xy 95.378188 -281.996404)
			(xy 95.411936 -281.95831) (xy 95.451358 -281.926123) (xy 95.495432 -281.900677) (xy 95.543018 -281.88263)
			(xy 95.592882 -281.87245) (xy 95.643734 -281.870401) (xy 95.694255 -281.876535) (xy 95.743139 -281.890695)
			(xy 95.789118 -281.912512) (xy 95.831002 -281.941422) (xy 95.867706 -281.976677) (xy 95.898279 -282.017363)
			(xy 95.92193 -282.062426) (xy 95.938046 -282.1107) (xy 95.94621 -282.160934) (xy 95.946722 -282.18638)
			(xy 95.94621 -282.211826) (xy 95.938046 -282.26206) (xy 95.92193 -282.310334) (xy 95.898279 -282.355397)
			(xy 95.867706 -282.396083) (xy 95.831002 -282.431338) (xy 95.789118 -282.460248) (xy 95.743139 -282.482065)
			(xy 95.694255 -282.496225) (xy 95.643734 -282.502359) (xy 95.592882 -282.50031) (xy 95.543018 -282.49013)
			(xy 95.495432 -282.472083) (xy 95.451358 -282.446637) (xy 95.411936 -282.41445) (xy 95.378188 -282.376356)
			(xy 95.350987 -282.333342) (xy 95.331039 -282.286522) (xy 95.31886 -282.237108) (xy 95.314765 -282.18638)
			(xy 95.006668 -282.18638) (xy 95.006156 -282.211826) (xy 94.997992 -282.26206) (xy 94.981876 -282.310334)
			(xy 94.958225 -282.355397) (xy 94.927652 -282.396083) (xy 94.890948 -282.431338) (xy 94.849064 -282.460248)
			(xy 94.803085 -282.482065) (xy 94.754201 -282.496225) (xy 94.70368 -282.502359) (xy 94.652828 -282.50031)
			(xy 94.602964 -282.49013) (xy 94.555378 -282.472083) (xy 94.511304 -282.446637) (xy 94.471882 -282.41445)
			(xy 94.438134 -282.376356) (xy 94.410933 -282.333342) (xy 94.390985 -282.286522) (xy 94.378806 -282.237108)
			(xy 94.374711 -282.18638) (xy 94.056454 -282.18638) (xy 94.055959 -282.210987) (xy 94.048064 -282.259564)
			(xy 94.03248 -282.306245) (xy 94.009609 -282.349822) (xy 93.980044 -282.389166) (xy 93.944551 -282.423258)
			(xy 93.904048 -282.451214) (xy 93.859586 -282.472312) (xy 93.812315 -282.486004) (xy 93.76346 -282.491936)
			(xy 93.714285 -282.489955) (xy 93.666066 -282.480111) (xy 93.62005 -282.462659) (xy 93.577429 -282.438052)
			(xy 93.539308 -282.406927) (xy 93.506673 -282.37009) (xy 93.48037 -282.328494) (xy 93.461079 -282.283218)
			(xy 93.449302 -282.235434) (xy 93.445342 -282.18638) (xy 93.126814 -282.18638) (xy 93.126302 -282.211826)
			(xy 93.118138 -282.26206) (xy 93.102022 -282.310334) (xy 93.078371 -282.355397) (xy 93.047798 -282.396083)
			(xy 93.011094 -282.431338) (xy 92.96921 -282.460248) (xy 92.923231 -282.482065) (xy 92.874347 -282.496225)
			(xy 92.823826 -282.502359) (xy 92.772974 -282.50031) (xy 92.72311 -282.49013) (xy 92.675524 -282.472083)
			(xy 92.63145 -282.446637) (xy 92.592028 -282.41445) (xy 92.55828 -282.376356) (xy 92.531079 -282.333342)
			(xy 92.511131 -282.286522) (xy 92.498952 -282.237108) (xy 92.494857 -282.18638) (xy 92.176346 -282.18638)
			(xy 92.175851 -282.210987) (xy 92.167956 -282.259564) (xy 92.152372 -282.306245) (xy 92.129501 -282.349822)
			(xy 92.099936 -282.389166) (xy 92.064443 -282.423258) (xy 92.02394 -282.451214) (xy 91.979478 -282.472312)
			(xy 91.932207 -282.486004) (xy 91.883352 -282.491936) (xy 91.834177 -282.489955) (xy 91.785958 -282.480111)
			(xy 91.739942 -282.462659) (xy 91.697321 -282.438052) (xy 91.6592 -282.406927) (xy 91.626565 -282.37009)
			(xy 91.600262 -282.328494) (xy 91.580971 -282.283218) (xy 91.569194 -282.235434) (xy 91.565234 -282.18638)
			(xy 91.246706 -282.18638) (xy 91.246194 -282.211826) (xy 91.23803 -282.26206) (xy 91.221914 -282.310334)
			(xy 91.198263 -282.355397) (xy 91.16769 -282.396083) (xy 91.130986 -282.431338) (xy 91.089102 -282.460248)
			(xy 91.043123 -282.482065) (xy 90.994239 -282.496225) (xy 90.943718 -282.502359) (xy 90.892866 -282.50031)
			(xy 90.843002 -282.49013) (xy 90.795416 -282.472083) (xy 90.751342 -282.446637) (xy 90.71192 -282.41445)
			(xy 90.678172 -282.376356) (xy 90.650971 -282.333342) (xy 90.631023 -282.286522) (xy 90.618844 -282.237108)
			(xy 90.614749 -282.18638) (xy 90.296238 -282.18638) (xy 90.295743 -282.210987) (xy 90.287848 -282.259564)
			(xy 90.272264 -282.306245) (xy 90.249393 -282.349822) (xy 90.219828 -282.389166) (xy 90.184335 -282.423258)
			(xy 90.143832 -282.451214) (xy 90.09937 -282.472312) (xy 90.052099 -282.486004) (xy 90.003244 -282.491936)
			(xy 89.954069 -282.489955) (xy 89.90585 -282.480111) (xy 89.859834 -282.462659) (xy 89.817213 -282.438052)
			(xy 89.779092 -282.406927) (xy 89.746457 -282.37009) (xy 89.720154 -282.328494) (xy 89.700863 -282.283218)
			(xy 89.689086 -282.235434) (xy 89.685126 -282.18638) (xy 89.356438 -282.18638) (xy 89.355943 -282.210987)
			(xy 89.348048 -282.259564) (xy 89.332464 -282.306245) (xy 89.309593 -282.349822) (xy 89.280028 -282.389166)
			(xy 89.244535 -282.423258) (xy 89.204032 -282.451214) (xy 89.15957 -282.472312) (xy 89.112299 -282.486004)
			(xy 89.063444 -282.491936) (xy 89.014269 -282.489955) (xy 88.96605 -282.480111) (xy 88.920034 -282.462659)
			(xy 88.877413 -282.438052) (xy 88.839292 -282.406927) (xy 88.806657 -282.37009) (xy 88.780354 -282.328494)
			(xy 88.761063 -282.283218) (xy 88.749286 -282.235434) (xy 88.745326 -282.18638) (xy 88.416384 -282.18638)
			(xy 88.415889 -282.210987) (xy 88.407994 -282.259564) (xy 88.39241 -282.306245) (xy 88.369539 -282.349822)
			(xy 88.339974 -282.389166) (xy 88.304481 -282.423258) (xy 88.263978 -282.451214) (xy 88.219516 -282.472312)
			(xy 88.172245 -282.486004) (xy 88.12339 -282.491936) (xy 88.074215 -282.489955) (xy 88.025996 -282.480111)
			(xy 87.97998 -282.462659) (xy 87.937359 -282.438052) (xy 87.899238 -282.406927) (xy 87.866603 -282.37009)
			(xy 87.8403 -282.328494) (xy 87.821009 -282.283218) (xy 87.809232 -282.235434) (xy 87.805272 -282.18638)
			(xy 87.47633 -282.18638) (xy 87.475861 -282.210373) (xy 87.468357 -282.257768) (xy 87.453532 -282.303406)
			(xy 87.43175 -282.346163) (xy 87.403547 -282.384987) (xy 87.369619 -282.41892) (xy 87.330799 -282.447128)
			(xy 87.288045 -282.468916) (xy 87.242409 -282.483748) (xy 87.195015 -282.491258) (xy 87.171022 -282.491688)
			(xy 87.159613 -282.491613) (xy 87.136856 -282.489959) (xy 87.125556 -282.488386) (xy 87.114634 -282.486608)
			(xy 87.09279 -282.492958) (xy 87.065358 -282.516834) (xy 87.06485 -282.517342) (xy 87.030814 -282.546552)
			(xy 87.02929 -282.547822) (xy 87.024972 -282.55214) (xy 87.017606 -282.559252) (xy 87.009986 -282.578048)
			(xy 87.009986 -282.877768) (xy 87.01278 -282.88615) (xy 87.021606 -282.912853) (xy 87.031177 -282.968269)
			(xy 87.03183 -282.996386) (xy 87.335118 -282.996386) (xy 87.339078 -282.947332) (xy 87.350855 -282.899548)
			(xy 87.370146 -282.854272) (xy 87.396449 -282.812676) (xy 87.429084 -282.775839) (xy 87.467205 -282.744714)
			(xy 87.509826 -282.720107) (xy 87.555842 -282.702655) (xy 87.604061 -282.692811) (xy 87.653236 -282.69083)
			(xy 87.702091 -282.696762) (xy 87.749362 -282.710454) (xy 87.793824 -282.731552) (xy 87.834327 -282.759508)
			(xy 87.86982 -282.7936) (xy 87.899385 -282.832944) (xy 87.922256 -282.876521) (xy 87.93784 -282.923202)
			(xy 87.945735 -282.971779) (xy 87.94623 -282.996386) (xy 88.275172 -282.996386) (xy 88.279132 -282.947332)
			(xy 88.290909 -282.899548) (xy 88.3102 -282.854272) (xy 88.336503 -282.812676) (xy 88.369138 -282.775839)
			(xy 88.407259 -282.744714) (xy 88.44988 -282.720107) (xy 88.495896 -282.702655) (xy 88.544115 -282.692811)
			(xy 88.59329 -282.69083) (xy 88.642145 -282.696762) (xy 88.689416 -282.710454) (xy 88.733878 -282.731552)
			(xy 88.774381 -282.759508) (xy 88.809874 -282.7936) (xy 88.839439 -282.832944) (xy 88.86231 -282.876521)
			(xy 88.877894 -282.923202) (xy 88.885789 -282.971779) (xy 88.886284 -282.996386) (xy 89.215226 -282.996386)
			(xy 89.219186 -282.947332) (xy 89.230963 -282.899548) (xy 89.250254 -282.854272) (xy 89.276557 -282.812676)
			(xy 89.309192 -282.775839) (xy 89.347313 -282.744714) (xy 89.389934 -282.720107) (xy 89.43595 -282.702655)
			(xy 89.484169 -282.692811) (xy 89.533344 -282.69083) (xy 89.582199 -282.696762) (xy 89.62947 -282.710454)
			(xy 89.673932 -282.731552) (xy 89.714435 -282.759508) (xy 89.749928 -282.7936) (xy 89.779493 -282.832944)
			(xy 89.802364 -282.876521) (xy 89.817948 -282.923202) (xy 89.825843 -282.971779) (xy 89.826338 -282.996386)
			(xy 90.15528 -282.996386) (xy 90.15924 -282.947332) (xy 90.171017 -282.899548) (xy 90.190308 -282.854272)
			(xy 90.216611 -282.812676) (xy 90.249246 -282.775839) (xy 90.287367 -282.744714) (xy 90.329988 -282.720107)
			(xy 90.376004 -282.702655) (xy 90.424223 -282.692811) (xy 90.473398 -282.69083) (xy 90.522253 -282.696762)
			(xy 90.569524 -282.710454) (xy 90.613986 -282.731552) (xy 90.654489 -282.759508) (xy 90.689982 -282.7936)
			(xy 90.719547 -282.832944) (xy 90.742418 -282.876521) (xy 90.758002 -282.923202) (xy 90.765897 -282.971779)
			(xy 90.766392 -282.996386) (xy 91.084903 -282.996386) (xy 91.088998 -282.945658) (xy 91.101177 -282.896244)
			(xy 91.121125 -282.849424) (xy 91.148326 -282.80641) (xy 91.182074 -282.768316) (xy 91.221496 -282.736129)
			(xy 91.26557 -282.710683) (xy 91.313156 -282.692636) (xy 91.36302 -282.682456) (xy 91.413872 -282.680407)
			(xy 91.464393 -282.686541) (xy 91.513277 -282.700701) (xy 91.559256 -282.722518) (xy 91.60114 -282.751428)
			(xy 91.637844 -282.786683) (xy 91.668417 -282.827369) (xy 91.692068 -282.872432) (xy 91.708184 -282.920706)
			(xy 91.716348 -282.97094) (xy 91.71686 -282.996386) (xy 92.024703 -282.996386) (xy 92.028798 -282.945658)
			(xy 92.040977 -282.896244) (xy 92.060925 -282.849424) (xy 92.088126 -282.80641) (xy 92.121874 -282.768316)
			(xy 92.161296 -282.736129) (xy 92.20537 -282.710683) (xy 92.252956 -282.692636) (xy 92.30282 -282.682456)
			(xy 92.353672 -282.680407) (xy 92.404193 -282.686541) (xy 92.453077 -282.700701) (xy 92.499056 -282.722518)
			(xy 92.54094 -282.751428) (xy 92.577644 -282.786683) (xy 92.608217 -282.827369) (xy 92.631868 -282.872432)
			(xy 92.647984 -282.920706) (xy 92.656148 -282.97094) (xy 92.65666 -282.996386) (xy 93.904811 -282.996386)
			(xy 93.908906 -282.945658) (xy 93.921085 -282.896244) (xy 93.941033 -282.849424) (xy 93.968234 -282.80641)
			(xy 94.001982 -282.768316) (xy 94.041404 -282.736129) (xy 94.085478 -282.710683) (xy 94.133064 -282.692636)
			(xy 94.182928 -282.682456) (xy 94.23378 -282.680407) (xy 94.284301 -282.686541) (xy 94.333185 -282.700701)
			(xy 94.379164 -282.722518) (xy 94.421048 -282.751428) (xy 94.457752 -282.786683) (xy 94.488325 -282.827369)
			(xy 94.511976 -282.872432) (xy 94.528092 -282.920706) (xy 94.536256 -282.97094) (xy 94.536768 -282.996386)
			(xy 94.855296 -282.996386) (xy 94.859256 -282.947332) (xy 94.871033 -282.899548) (xy 94.890324 -282.854272)
			(xy 94.916627 -282.812676) (xy 94.949262 -282.775839) (xy 94.987383 -282.744714) (xy 95.030004 -282.720107)
			(xy 95.07602 -282.702655) (xy 95.124239 -282.692811) (xy 95.173414 -282.69083) (xy 95.222269 -282.696762)
			(xy 95.26954 -282.710454) (xy 95.314002 -282.731552) (xy 95.354505 -282.759508) (xy 95.389998 -282.7936)
			(xy 95.419563 -282.832944) (xy 95.442434 -282.876521) (xy 95.458018 -282.923202) (xy 95.465913 -282.971779)
			(xy 95.466408 -282.996386) (xy 95.784919 -282.996386) (xy 95.789014 -282.945658) (xy 95.801193 -282.896244)
			(xy 95.821141 -282.849424) (xy 95.848342 -282.80641) (xy 95.88209 -282.768316) (xy 95.921512 -282.736129)
			(xy 95.965586 -282.710683) (xy 96.013172 -282.692636) (xy 96.063036 -282.682456) (xy 96.113888 -282.680407)
			(xy 96.164409 -282.686541) (xy 96.213293 -282.700701) (xy 96.259272 -282.722518) (xy 96.301156 -282.751428)
			(xy 96.33786 -282.786683) (xy 96.368433 -282.827369) (xy 96.392084 -282.872432) (xy 96.4082 -282.920706)
			(xy 96.416364 -282.97094) (xy 96.416876 -282.996386) (xy 96.416364 -283.021832) (xy 96.4082 -283.072066)
			(xy 96.392084 -283.12034) (xy 96.368433 -283.165403) (xy 96.33786 -283.206089) (xy 96.301156 -283.241344)
			(xy 96.259272 -283.270254) (xy 96.213293 -283.292071) (xy 96.164409 -283.306231) (xy 96.113888 -283.312365)
			(xy 96.063036 -283.310316) (xy 96.013172 -283.300136) (xy 95.965586 -283.282089) (xy 95.921512 -283.256643)
			(xy 95.88209 -283.224456) (xy 95.848342 -283.186362) (xy 95.821141 -283.143348) (xy 95.801193 -283.096528)
			(xy 95.789014 -283.047114) (xy 95.784919 -282.996386) (xy 95.466408 -282.996386) (xy 95.465913 -283.020993)
			(xy 95.458018 -283.06957) (xy 95.442434 -283.116251) (xy 95.419563 -283.159828) (xy 95.389998 -283.199172)
			(xy 95.354505 -283.233264) (xy 95.314002 -283.26122) (xy 95.26954 -283.282318) (xy 95.222269 -283.29601)
			(xy 95.173414 -283.301942) (xy 95.124239 -283.299961) (xy 95.07602 -283.290117) (xy 95.030004 -283.272665)
			(xy 94.987383 -283.248058) (xy 94.949262 -283.216933) (xy 94.916627 -283.180096) (xy 94.890324 -283.1385)
			(xy 94.871033 -283.093224) (xy 94.859256 -283.04544) (xy 94.855296 -282.996386) (xy 94.536768 -282.996386)
			(xy 94.536256 -283.021832) (xy 94.528092 -283.072066) (xy 94.511976 -283.12034) (xy 94.488325 -283.165403)
			(xy 94.457752 -283.206089) (xy 94.421048 -283.241344) (xy 94.379164 -283.270254) (xy 94.333185 -283.292071)
			(xy 94.284301 -283.306231) (xy 94.23378 -283.312365) (xy 94.182928 -283.310316) (xy 94.133064 -283.300136)
			(xy 94.085478 -283.282089) (xy 94.041404 -283.256643) (xy 94.001982 -283.224456) (xy 93.968234 -283.186362)
			(xy 93.941033 -283.143348) (xy 93.921085 -283.096528) (xy 93.908906 -283.047114) (xy 93.904811 -282.996386)
			(xy 92.65666 -282.996386) (xy 92.656148 -283.021832) (xy 92.647984 -283.072066) (xy 92.631868 -283.12034)
			(xy 92.608217 -283.165403) (xy 92.577644 -283.206089) (xy 92.54094 -283.241344) (xy 92.499056 -283.270254)
			(xy 92.453077 -283.292071) (xy 92.404193 -283.306231) (xy 92.353672 -283.312365) (xy 92.30282 -283.310316)
			(xy 92.252956 -283.300136) (xy 92.20537 -283.282089) (xy 92.161296 -283.256643) (xy 92.121874 -283.224456)
			(xy 92.088126 -283.186362) (xy 92.060925 -283.143348) (xy 92.040977 -283.096528) (xy 92.028798 -283.047114)
			(xy 92.024703 -282.996386) (xy 91.71686 -282.996386) (xy 91.716348 -283.021832) (xy 91.708184 -283.072066)
			(xy 91.692068 -283.12034) (xy 91.668417 -283.165403) (xy 91.637844 -283.206089) (xy 91.60114 -283.241344)
			(xy 91.559256 -283.270254) (xy 91.513277 -283.292071) (xy 91.464393 -283.306231) (xy 91.413872 -283.312365)
			(xy 91.36302 -283.310316) (xy 91.313156 -283.300136) (xy 91.26557 -283.282089) (xy 91.221496 -283.256643)
			(xy 91.182074 -283.224456) (xy 91.148326 -283.186362) (xy 91.121125 -283.143348) (xy 91.101177 -283.096528)
			(xy 91.088998 -283.047114) (xy 91.084903 -282.996386) (xy 90.766392 -282.996386) (xy 90.765897 -283.020993)
			(xy 90.758002 -283.06957) (xy 90.742418 -283.116251) (xy 90.719547 -283.159828) (xy 90.689982 -283.199172)
			(xy 90.654489 -283.233264) (xy 90.613986 -283.26122) (xy 90.569524 -283.282318) (xy 90.522253 -283.29601)
			(xy 90.473398 -283.301942) (xy 90.424223 -283.299961) (xy 90.376004 -283.290117) (xy 90.329988 -283.272665)
			(xy 90.287367 -283.248058) (xy 90.249246 -283.216933) (xy 90.216611 -283.180096) (xy 90.190308 -283.1385)
			(xy 90.171017 -283.093224) (xy 90.15924 -283.04544) (xy 90.15528 -282.996386) (xy 89.826338 -282.996386)
			(xy 89.825843 -283.020993) (xy 89.817948 -283.06957) (xy 89.802364 -283.116251) (xy 89.779493 -283.159828)
			(xy 89.749928 -283.199172) (xy 89.714435 -283.233264) (xy 89.673932 -283.26122) (xy 89.62947 -283.282318)
			(xy 89.582199 -283.29601) (xy 89.533344 -283.301942) (xy 89.484169 -283.299961) (xy 89.43595 -283.290117)
			(xy 89.389934 -283.272665) (xy 89.347313 -283.248058) (xy 89.309192 -283.216933) (xy 89.276557 -283.180096)
			(xy 89.250254 -283.1385) (xy 89.230963 -283.093224) (xy 89.219186 -283.04544) (xy 89.215226 -282.996386)
			(xy 88.886284 -282.996386) (xy 88.885789 -283.020993) (xy 88.877894 -283.06957) (xy 88.86231 -283.116251)
			(xy 88.839439 -283.159828) (xy 88.809874 -283.199172) (xy 88.774381 -283.233264) (xy 88.733878 -283.26122)
			(xy 88.689416 -283.282318) (xy 88.642145 -283.29601) (xy 88.59329 -283.301942) (xy 88.544115 -283.299961)
			(xy 88.495896 -283.290117) (xy 88.44988 -283.272665) (xy 88.407259 -283.248058) (xy 88.369138 -283.216933)
			(xy 88.336503 -283.180096) (xy 88.3102 -283.1385) (xy 88.290909 -283.093224) (xy 88.279132 -283.04544)
			(xy 88.275172 -282.996386) (xy 87.94623 -282.996386) (xy 87.945735 -283.020993) (xy 87.93784 -283.06957)
			(xy 87.922256 -283.116251) (xy 87.899385 -283.159828) (xy 87.86982 -283.199172) (xy 87.834327 -283.233264)
			(xy 87.793824 -283.26122) (xy 87.749362 -283.282318) (xy 87.702091 -283.29601) (xy 87.653236 -283.301942)
			(xy 87.604061 -283.299961) (xy 87.555842 -283.290117) (xy 87.509826 -283.272665) (xy 87.467205 -283.248058)
			(xy 87.429084 -283.216933) (xy 87.396449 -283.180096) (xy 87.370146 -283.1385) (xy 87.350855 -283.093224)
			(xy 87.339078 -283.04544) (xy 87.335118 -282.996386) (xy 87.03183 -282.996386) (xy 87.03125 -283.02451)
			(xy 87.021676 -283.079936) (xy 87.01278 -283.106622) (xy 87.009986 -283.115004) (xy 87.009986 -283.405072)
			(xy 87.010361 -283.414176) (xy 87.016741 -283.43123) (xy 87.022432 -283.438346) (xy 87.024972 -283.44114)
			(xy 87.065104 -283.475684) (xy 87.080344 -283.488892) (xy 87.081614 -283.489908) (xy 87.088578 -283.495107)
			(xy 87.104936 -283.500946) (xy 87.113618 -283.501338) (xy 87.159592 -283.501338) (xy 87.171022 -283.501084)
			(xy 87.171276 -283.501084) (xy 87.195253 -283.501575) (xy 87.242612 -283.509115) (xy 87.28821 -283.523967)
			(xy 87.330925 -283.545765) (xy 87.369706 -283.573973) (xy 87.403601 -283.607898) (xy 87.431775 -283.646704)
			(xy 87.453536 -283.689438) (xy 87.468347 -283.735049) (xy 87.475846 -283.782414) (xy 87.47633 -283.806392)
			(xy 87.805272 -283.806392) (xy 87.809232 -283.757338) (xy 87.821009 -283.709554) (xy 87.8403 -283.664278)
			(xy 87.866603 -283.622682) (xy 87.899238 -283.585845) (xy 87.937359 -283.55472) (xy 87.97998 -283.530113)
			(xy 88.025996 -283.512661) (xy 88.074215 -283.502817) (xy 88.12339 -283.500836) (xy 88.172245 -283.506768)
			(xy 88.219516 -283.52046) (xy 88.263978 -283.541558) (xy 88.304481 -283.569514) (xy 88.339974 -283.603606)
			(xy 88.369539 -283.64295) (xy 88.39241 -283.686527) (xy 88.407994 -283.733208) (xy 88.415889 -283.781785)
			(xy 88.416384 -283.806392) (xy 88.745326 -283.806392) (xy 88.749286 -283.757338) (xy 88.761063 -283.709554)
			(xy 88.780354 -283.664278) (xy 88.806657 -283.622682) (xy 88.839292 -283.585845) (xy 88.877413 -283.55472)
			(xy 88.920034 -283.530113) (xy 88.96605 -283.512661) (xy 89.014269 -283.502817) (xy 89.063444 -283.500836)
			(xy 89.112299 -283.506768) (xy 89.15957 -283.52046) (xy 89.204032 -283.541558) (xy 89.244535 -283.569514)
			(xy 89.280028 -283.603606) (xy 89.309593 -283.64295) (xy 89.332464 -283.686527) (xy 89.348048 -283.733208)
			(xy 89.355943 -283.781785) (xy 89.356438 -283.806392) (xy 89.685126 -283.806392) (xy 89.689086 -283.757338)
			(xy 89.700863 -283.709554) (xy 89.720154 -283.664278) (xy 89.746457 -283.622682) (xy 89.779092 -283.585845)
			(xy 89.817213 -283.55472) (xy 89.859834 -283.530113) (xy 89.90585 -283.512661) (xy 89.954069 -283.502817)
			(xy 90.003244 -283.500836) (xy 90.052099 -283.506768) (xy 90.09937 -283.52046) (xy 90.143832 -283.541558)
			(xy 90.184335 -283.569514) (xy 90.219828 -283.603606) (xy 90.249393 -283.64295) (xy 90.272264 -283.686527)
			(xy 90.287848 -283.733208) (xy 90.295743 -283.781785) (xy 90.296238 -283.806392) (xy 90.614749 -283.806392)
			(xy 90.618844 -283.755664) (xy 90.631023 -283.70625) (xy 90.650971 -283.65943) (xy 90.678172 -283.616416)
			(xy 90.71192 -283.578322) (xy 90.751342 -283.546135) (xy 90.795416 -283.520689) (xy 90.843002 -283.502642)
			(xy 90.892866 -283.492462) (xy 90.943718 -283.490413) (xy 90.994239 -283.496547) (xy 91.043123 -283.510707)
			(xy 91.089102 -283.532524) (xy 91.130986 -283.561434) (xy 91.16769 -283.596689) (xy 91.198263 -283.637375)
			(xy 91.221914 -283.682438) (xy 91.23803 -283.730712) (xy 91.246194 -283.780946) (xy 91.246706 -283.806392)
			(xy 91.565234 -283.806392) (xy 91.569194 -283.757338) (xy 91.580971 -283.709554) (xy 91.600262 -283.664278)
			(xy 91.626565 -283.622682) (xy 91.6592 -283.585845) (xy 91.697321 -283.55472) (xy 91.739942 -283.530113)
			(xy 91.785958 -283.512661) (xy 91.834177 -283.502817) (xy 91.883352 -283.500836) (xy 91.932207 -283.506768)
			(xy 91.979478 -283.52046) (xy 92.02394 -283.541558) (xy 92.064443 -283.569514) (xy 92.099936 -283.603606)
			(xy 92.129501 -283.64295) (xy 92.152372 -283.686527) (xy 92.167956 -283.733208) (xy 92.175851 -283.781785)
			(xy 92.176346 -283.806392) (xy 92.494857 -283.806392) (xy 92.498952 -283.755664) (xy 92.511131 -283.70625)
			(xy 92.531079 -283.65943) (xy 92.55828 -283.616416) (xy 92.592028 -283.578322) (xy 92.63145 -283.546135)
			(xy 92.675524 -283.520689) (xy 92.72311 -283.502642) (xy 92.772974 -283.492462) (xy 92.823826 -283.490413)
			(xy 92.874347 -283.496547) (xy 92.923231 -283.510707) (xy 92.96921 -283.532524) (xy 93.011094 -283.561434)
			(xy 93.047798 -283.596689) (xy 93.078371 -283.637375) (xy 93.102022 -283.682438) (xy 93.118138 -283.730712)
			(xy 93.126302 -283.780946) (xy 93.126814 -283.806392) (xy 93.445342 -283.806392) (xy 93.449302 -283.757338)
			(xy 93.461079 -283.709554) (xy 93.48037 -283.664278) (xy 93.506673 -283.622682) (xy 93.539308 -283.585845)
			(xy 93.577429 -283.55472) (xy 93.62005 -283.530113) (xy 93.666066 -283.512661) (xy 93.714285 -283.502817)
			(xy 93.76346 -283.500836) (xy 93.812315 -283.506768) (xy 93.859586 -283.52046) (xy 93.904048 -283.541558)
			(xy 93.944551 -283.569514) (xy 93.980044 -283.603606) (xy 94.009609 -283.64295) (xy 94.03248 -283.686527)
			(xy 94.048064 -283.733208) (xy 94.055959 -283.781785) (xy 94.056454 -283.806392) (xy 94.374711 -283.806392)
			(xy 94.378806 -283.755664) (xy 94.390985 -283.70625) (xy 94.410933 -283.65943) (xy 94.438134 -283.616416)
			(xy 94.471882 -283.578322) (xy 94.511304 -283.546135) (xy 94.555378 -283.520689) (xy 94.602964 -283.502642)
			(xy 94.652828 -283.492462) (xy 94.70368 -283.490413) (xy 94.754201 -283.496547) (xy 94.803085 -283.510707)
			(xy 94.849064 -283.532524) (xy 94.890948 -283.561434) (xy 94.927652 -283.596689) (xy 94.958225 -283.637375)
			(xy 94.981876 -283.682438) (xy 94.997992 -283.730712) (xy 95.006156 -283.780946) (xy 95.006668 -283.806392)
			(xy 95.314765 -283.806392) (xy 95.31886 -283.755664) (xy 95.331039 -283.70625) (xy 95.350987 -283.65943)
			(xy 95.378188 -283.616416) (xy 95.411936 -283.578322) (xy 95.451358 -283.546135) (xy 95.495432 -283.520689)
			(xy 95.543018 -283.502642) (xy 95.592882 -283.492462) (xy 95.643734 -283.490413) (xy 95.694255 -283.496547)
			(xy 95.743139 -283.510707) (xy 95.789118 -283.532524) (xy 95.831002 -283.561434) (xy 95.867706 -283.596689)
			(xy 95.898279 -283.637375) (xy 95.92193 -283.682438) (xy 95.938046 -283.730712) (xy 95.94621 -283.780946)
			(xy 95.946722 -283.806392) (xy 95.94621 -283.831838) (xy 95.938046 -283.882072) (xy 95.92193 -283.930346)
			(xy 95.898279 -283.975409) (xy 95.867706 -284.016095) (xy 95.831002 -284.05135) (xy 95.789118 -284.08026)
			(xy 95.743139 -284.102077) (xy 95.694255 -284.116237) (xy 95.643734 -284.122371) (xy 95.592882 -284.120322)
			(xy 95.543018 -284.110142) (xy 95.495432 -284.092095) (xy 95.451358 -284.066649) (xy 95.411936 -284.034462)
			(xy 95.378188 -283.996368) (xy 95.350987 -283.953354) (xy 95.331039 -283.906534) (xy 95.31886 -283.85712)
			(xy 95.314765 -283.806392) (xy 95.006668 -283.806392) (xy 95.006156 -283.831838) (xy 94.997992 -283.882072)
			(xy 94.981876 -283.930346) (xy 94.958225 -283.975409) (xy 94.927652 -284.016095) (xy 94.890948 -284.05135)
			(xy 94.849064 -284.08026) (xy 94.803085 -284.102077) (xy 94.754201 -284.116237) (xy 94.70368 -284.122371)
			(xy 94.652828 -284.120322) (xy 94.602964 -284.110142) (xy 94.555378 -284.092095) (xy 94.511304 -284.066649)
			(xy 94.471882 -284.034462) (xy 94.438134 -283.996368) (xy 94.410933 -283.953354) (xy 94.390985 -283.906534)
			(xy 94.378806 -283.85712) (xy 94.374711 -283.806392) (xy 94.056454 -283.806392) (xy 94.055959 -283.830999)
			(xy 94.048064 -283.879576) (xy 94.03248 -283.926257) (xy 94.009609 -283.969834) (xy 93.980044 -284.009178)
			(xy 93.944551 -284.04327) (xy 93.904048 -284.071226) (xy 93.859586 -284.092324) (xy 93.812315 -284.106016)
			(xy 93.76346 -284.111948) (xy 93.714285 -284.109967) (xy 93.666066 -284.100123) (xy 93.62005 -284.082671)
			(xy 93.577429 -284.058064) (xy 93.539308 -284.026939) (xy 93.506673 -283.990102) (xy 93.48037 -283.948506)
			(xy 93.461079 -283.90323) (xy 93.449302 -283.855446) (xy 93.445342 -283.806392) (xy 93.126814 -283.806392)
			(xy 93.126302 -283.831838) (xy 93.118138 -283.882072) (xy 93.102022 -283.930346) (xy 93.078371 -283.975409)
			(xy 93.047798 -284.016095) (xy 93.011094 -284.05135) (xy 92.96921 -284.08026) (xy 92.923231 -284.102077)
			(xy 92.874347 -284.116237) (xy 92.823826 -284.122371) (xy 92.772974 -284.120322) (xy 92.72311 -284.110142)
			(xy 92.675524 -284.092095) (xy 92.63145 -284.066649) (xy 92.592028 -284.034462) (xy 92.55828 -283.996368)
			(xy 92.531079 -283.953354) (xy 92.511131 -283.906534) (xy 92.498952 -283.85712) (xy 92.494857 -283.806392)
			(xy 92.176346 -283.806392) (xy 92.175851 -283.830999) (xy 92.167956 -283.879576) (xy 92.152372 -283.926257)
			(xy 92.129501 -283.969834) (xy 92.099936 -284.009178) (xy 92.064443 -284.04327) (xy 92.02394 -284.071226)
			(xy 91.979478 -284.092324) (xy 91.932207 -284.106016) (xy 91.883352 -284.111948) (xy 91.834177 -284.109967)
			(xy 91.785958 -284.100123) (xy 91.739942 -284.082671) (xy 91.697321 -284.058064) (xy 91.6592 -284.026939)
			(xy 91.626565 -283.990102) (xy 91.600262 -283.948506) (xy 91.580971 -283.90323) (xy 91.569194 -283.855446)
			(xy 91.565234 -283.806392) (xy 91.246706 -283.806392) (xy 91.246194 -283.831838) (xy 91.23803 -283.882072)
			(xy 91.221914 -283.930346) (xy 91.198263 -283.975409) (xy 91.16769 -284.016095) (xy 91.130986 -284.05135)
			(xy 91.089102 -284.08026) (xy 91.043123 -284.102077) (xy 90.994239 -284.116237) (xy 90.943718 -284.122371)
			(xy 90.892866 -284.120322) (xy 90.843002 -284.110142) (xy 90.795416 -284.092095) (xy 90.751342 -284.066649)
			(xy 90.71192 -284.034462) (xy 90.678172 -283.996368) (xy 90.650971 -283.953354) (xy 90.631023 -283.906534)
			(xy 90.618844 -283.85712) (xy 90.614749 -283.806392) (xy 90.296238 -283.806392) (xy 90.295743 -283.830999)
			(xy 90.287848 -283.879576) (xy 90.272264 -283.926257) (xy 90.249393 -283.969834) (xy 90.219828 -284.009178)
			(xy 90.184335 -284.04327) (xy 90.143832 -284.071226) (xy 90.09937 -284.092324) (xy 90.052099 -284.106016)
			(xy 90.003244 -284.111948) (xy 89.954069 -284.109967) (xy 89.90585 -284.100123) (xy 89.859834 -284.082671)
			(xy 89.817213 -284.058064) (xy 89.779092 -284.026939) (xy 89.746457 -283.990102) (xy 89.720154 -283.948506)
			(xy 89.700863 -283.90323) (xy 89.689086 -283.855446) (xy 89.685126 -283.806392) (xy 89.356438 -283.806392)
			(xy 89.355943 -283.830999) (xy 89.348048 -283.879576) (xy 89.332464 -283.926257) (xy 89.309593 -283.969834)
			(xy 89.280028 -284.009178) (xy 89.244535 -284.04327) (xy 89.204032 -284.071226) (xy 89.15957 -284.092324)
			(xy 89.112299 -284.106016) (xy 89.063444 -284.111948) (xy 89.014269 -284.109967) (xy 88.96605 -284.100123)
			(xy 88.920034 -284.082671) (xy 88.877413 -284.058064) (xy 88.839292 -284.026939) (xy 88.806657 -283.990102)
			(xy 88.780354 -283.948506) (xy 88.761063 -283.90323) (xy 88.749286 -283.855446) (xy 88.745326 -283.806392)
			(xy 88.416384 -283.806392) (xy 88.415889 -283.830999) (xy 88.407994 -283.879576) (xy 88.39241 -283.926257)
			(xy 88.369539 -283.969834) (xy 88.339974 -284.009178) (xy 88.304481 -284.04327) (xy 88.263978 -284.071226)
			(xy 88.219516 -284.092324) (xy 88.172245 -284.106016) (xy 88.12339 -284.111948) (xy 88.074215 -284.109967)
			(xy 88.025996 -284.100123) (xy 87.97998 -284.082671) (xy 87.937359 -284.058064) (xy 87.899238 -284.026939)
			(xy 87.866603 -283.990102) (xy 87.8403 -283.948506) (xy 87.821009 -283.90323) (xy 87.809232 -283.855446)
			(xy 87.805272 -283.806392) (xy 87.47633 -283.806392) (xy 87.47586 -283.830384) (xy 87.468355 -283.877778)
			(xy 87.453529 -283.923415) (xy 87.431746 -283.96617) (xy 87.403543 -284.004992) (xy 87.369614 -284.038923)
			(xy 87.330796 -284.06713) (xy 87.288042 -284.088917) (xy 87.242407 -284.103748) (xy 87.195014 -284.111258)
			(xy 87.171022 -284.1117) (xy 87.159613 -284.111625) (xy 87.136856 -284.109971) (xy 87.125556 -284.108398)
			(xy 87.114634 -284.10662) (xy 87.09279 -284.11297) (xy 87.065358 -284.136846) (xy 87.06485 -284.137354)
			(xy 87.030814 -284.166564) (xy 87.02929 -284.167834) (xy 87.024972 -284.172152) (xy 87.017606 -284.179264)
			(xy 87.009986 -284.19806) (xy 87.009986 -284.616398) (xy 87.335118 -284.616398) (xy 87.339078 -284.567344)
			(xy 87.350855 -284.51956) (xy 87.370146 -284.474284) (xy 87.396449 -284.432688) (xy 87.429084 -284.395851)
			(xy 87.467205 -284.364726) (xy 87.509826 -284.340119) (xy 87.555842 -284.322667) (xy 87.604061 -284.312823)
			(xy 87.653236 -284.310842) (xy 87.702091 -284.316774) (xy 87.749362 -284.330466) (xy 87.793824 -284.351564)
			(xy 87.834327 -284.37952) (xy 87.86982 -284.413612) (xy 87.899385 -284.452956) (xy 87.922256 -284.496533)
			(xy 87.93784 -284.543214) (xy 87.945735 -284.591791) (xy 87.94623 -284.616398) (xy 88.275172 -284.616398)
			(xy 88.279132 -284.567344) (xy 88.290909 -284.51956) (xy 88.3102 -284.474284) (xy 88.336503 -284.432688)
			(xy 88.369138 -284.395851) (xy 88.407259 -284.364726) (xy 88.44988 -284.340119) (xy 88.495896 -284.322667)
			(xy 88.544115 -284.312823) (xy 88.59329 -284.310842) (xy 88.642145 -284.316774) (xy 88.689416 -284.330466)
			(xy 88.733878 -284.351564) (xy 88.774381 -284.37952) (xy 88.809874 -284.413612) (xy 88.839439 -284.452956)
			(xy 88.86231 -284.496533) (xy 88.877894 -284.543214) (xy 88.885789 -284.591791) (xy 88.886284 -284.616398)
			(xy 89.215226 -284.616398) (xy 89.219186 -284.567344) (xy 89.230963 -284.51956) (xy 89.250254 -284.474284)
			(xy 89.276557 -284.432688) (xy 89.309192 -284.395851) (xy 89.347313 -284.364726) (xy 89.389934 -284.340119)
			(xy 89.43595 -284.322667) (xy 89.484169 -284.312823) (xy 89.533344 -284.310842) (xy 89.582199 -284.316774)
			(xy 89.62947 -284.330466) (xy 89.673932 -284.351564) (xy 89.714435 -284.37952) (xy 89.749928 -284.413612)
			(xy 89.779493 -284.452956) (xy 89.802364 -284.496533) (xy 89.817948 -284.543214) (xy 89.825843 -284.591791)
			(xy 89.826338 -284.616398) (xy 90.15528 -284.616398) (xy 90.15924 -284.567344) (xy 90.171017 -284.51956)
			(xy 90.190308 -284.474284) (xy 90.216611 -284.432688) (xy 90.249246 -284.395851) (xy 90.287367 -284.364726)
			(xy 90.329988 -284.340119) (xy 90.376004 -284.322667) (xy 90.424223 -284.312823) (xy 90.473398 -284.310842)
			(xy 90.522253 -284.316774) (xy 90.569524 -284.330466) (xy 90.613986 -284.351564) (xy 90.654489 -284.37952)
			(xy 90.689982 -284.413612) (xy 90.719547 -284.452956) (xy 90.742418 -284.496533) (xy 90.758002 -284.543214)
			(xy 90.765897 -284.591791) (xy 90.766392 -284.616398) (xy 91.084903 -284.616398) (xy 91.088998 -284.56567)
			(xy 91.101177 -284.516256) (xy 91.121125 -284.469436) (xy 91.148326 -284.426422) (xy 91.182074 -284.388328)
			(xy 91.221496 -284.356141) (xy 91.26557 -284.330695) (xy 91.313156 -284.312648) (xy 91.36302 -284.302468)
			(xy 91.413872 -284.300419) (xy 91.464393 -284.306553) (xy 91.513277 -284.320713) (xy 91.559256 -284.34253)
			(xy 91.60114 -284.37144) (xy 91.637844 -284.406695) (xy 91.668417 -284.447381) (xy 91.692068 -284.492444)
			(xy 91.708184 -284.540718) (xy 91.716348 -284.590952) (xy 91.71686 -284.616398) (xy 92.024703 -284.616398)
			(xy 92.028798 -284.56567) (xy 92.040977 -284.516256) (xy 92.060925 -284.469436) (xy 92.088126 -284.426422)
			(xy 92.121874 -284.388328) (xy 92.161296 -284.356141) (xy 92.20537 -284.330695) (xy 92.252956 -284.312648)
			(xy 92.30282 -284.302468) (xy 92.353672 -284.300419) (xy 92.404193 -284.306553) (xy 92.453077 -284.320713)
			(xy 92.499056 -284.34253) (xy 92.54094 -284.37144) (xy 92.577644 -284.406695) (xy 92.608217 -284.447381)
			(xy 92.631868 -284.492444) (xy 92.647984 -284.540718) (xy 92.656148 -284.590952) (xy 92.65666 -284.616398)
			(xy 92.975188 -284.616398) (xy 92.979148 -284.567344) (xy 92.990925 -284.51956) (xy 93.010216 -284.474284)
			(xy 93.036519 -284.432688) (xy 93.069154 -284.395851) (xy 93.107275 -284.364726) (xy 93.149896 -284.340119)
			(xy 93.195912 -284.322667) (xy 93.244131 -284.312823) (xy 93.293306 -284.310842) (xy 93.342161 -284.316774)
			(xy 93.389432 -284.330466) (xy 93.433894 -284.351564) (xy 93.474397 -284.37952) (xy 93.50989 -284.413612)
			(xy 93.539455 -284.452956) (xy 93.562326 -284.496533) (xy 93.57791 -284.543214) (xy 93.585805 -284.591791)
			(xy 93.5863 -284.616398) (xy 93.904811 -284.616398) (xy 93.908906 -284.56567) (xy 93.921085 -284.516256)
			(xy 93.941033 -284.469436) (xy 93.968234 -284.426422) (xy 94.001982 -284.388328) (xy 94.041404 -284.356141)
			(xy 94.085478 -284.330695) (xy 94.133064 -284.312648) (xy 94.182928 -284.302468) (xy 94.23378 -284.300419)
			(xy 94.284301 -284.306553) (xy 94.333185 -284.320713) (xy 94.379164 -284.34253) (xy 94.421048 -284.37144)
			(xy 94.457752 -284.406695) (xy 94.488325 -284.447381) (xy 94.511976 -284.492444) (xy 94.528092 -284.540718)
			(xy 94.536256 -284.590952) (xy 94.536768 -284.616398) (xy 94.855296 -284.616398) (xy 94.859256 -284.567344)
			(xy 94.871033 -284.51956) (xy 94.890324 -284.474284) (xy 94.916627 -284.432688) (xy 94.949262 -284.395851)
			(xy 94.987383 -284.364726) (xy 95.030004 -284.340119) (xy 95.07602 -284.322667) (xy 95.124239 -284.312823)
			(xy 95.173414 -284.310842) (xy 95.222269 -284.316774) (xy 95.26954 -284.330466) (xy 95.314002 -284.351564)
			(xy 95.354505 -284.37952) (xy 95.389998 -284.413612) (xy 95.419563 -284.452956) (xy 95.442434 -284.496533)
			(xy 95.458018 -284.543214) (xy 95.465913 -284.591791) (xy 95.466408 -284.616398) (xy 95.465913 -284.641005)
			(xy 95.458018 -284.689582) (xy 95.442434 -284.736263) (xy 95.419563 -284.77984) (xy 95.389998 -284.819184)
			(xy 95.354505 -284.853276) (xy 95.314002 -284.881232) (xy 95.26954 -284.90233) (xy 95.222269 -284.916022)
			(xy 95.173414 -284.921954) (xy 95.124239 -284.919973) (xy 95.07602 -284.910129) (xy 95.030004 -284.892677)
			(xy 94.987383 -284.86807) (xy 94.949262 -284.836945) (xy 94.916627 -284.800108) (xy 94.890324 -284.758512)
			(xy 94.871033 -284.713236) (xy 94.859256 -284.665452) (xy 94.855296 -284.616398) (xy 94.536768 -284.616398)
			(xy 94.536256 -284.641844) (xy 94.528092 -284.692078) (xy 94.511976 -284.740352) (xy 94.488325 -284.785415)
			(xy 94.457752 -284.826101) (xy 94.421048 -284.861356) (xy 94.379164 -284.890266) (xy 94.333185 -284.912083)
			(xy 94.284301 -284.926243) (xy 94.23378 -284.932377) (xy 94.182928 -284.930328) (xy 94.133064 -284.920148)
			(xy 94.085478 -284.902101) (xy 94.041404 -284.876655) (xy 94.001982 -284.844468) (xy 93.968234 -284.806374)
			(xy 93.941033 -284.76336) (xy 93.921085 -284.71654) (xy 93.908906 -284.667126) (xy 93.904811 -284.616398)
			(xy 93.5863 -284.616398) (xy 93.585805 -284.641005) (xy 93.57791 -284.689582) (xy 93.562326 -284.736263)
			(xy 93.539455 -284.77984) (xy 93.50989 -284.819184) (xy 93.474397 -284.853276) (xy 93.433894 -284.881232)
			(xy 93.389432 -284.90233) (xy 93.342161 -284.916022) (xy 93.293306 -284.921954) (xy 93.244131 -284.919973)
			(xy 93.195912 -284.910129) (xy 93.149896 -284.892677) (xy 93.107275 -284.86807) (xy 93.069154 -284.836945)
			(xy 93.036519 -284.800108) (xy 93.010216 -284.758512) (xy 92.990925 -284.713236) (xy 92.979148 -284.665452)
			(xy 92.975188 -284.616398) (xy 92.65666 -284.616398) (xy 92.656148 -284.641844) (xy 92.647984 -284.692078)
			(xy 92.631868 -284.740352) (xy 92.608217 -284.785415) (xy 92.577644 -284.826101) (xy 92.54094 -284.861356)
			(xy 92.499056 -284.890266) (xy 92.453077 -284.912083) (xy 92.404193 -284.926243) (xy 92.353672 -284.932377)
			(xy 92.30282 -284.930328) (xy 92.252956 -284.920148) (xy 92.20537 -284.902101) (xy 92.161296 -284.876655)
			(xy 92.121874 -284.844468) (xy 92.088126 -284.806374) (xy 92.060925 -284.76336) (xy 92.040977 -284.71654)
			(xy 92.028798 -284.667126) (xy 92.024703 -284.616398) (xy 91.71686 -284.616398) (xy 91.716348 -284.641844)
			(xy 91.708184 -284.692078) (xy 91.692068 -284.740352) (xy 91.668417 -284.785415) (xy 91.637844 -284.826101)
			(xy 91.60114 -284.861356) (xy 91.559256 -284.890266) (xy 91.513277 -284.912083) (xy 91.464393 -284.926243)
			(xy 91.413872 -284.932377) (xy 91.36302 -284.930328) (xy 91.313156 -284.920148) (xy 91.26557 -284.902101)
			(xy 91.221496 -284.876655) (xy 91.182074 -284.844468) (xy 91.148326 -284.806374) (xy 91.121125 -284.76336)
			(xy 91.101177 -284.71654) (xy 91.088998 -284.667126) (xy 91.084903 -284.616398) (xy 90.766392 -284.616398)
			(xy 90.765897 -284.641005) (xy 90.758002 -284.689582) (xy 90.742418 -284.736263) (xy 90.719547 -284.77984)
			(xy 90.689982 -284.819184) (xy 90.654489 -284.853276) (xy 90.613986 -284.881232) (xy 90.569524 -284.90233)
			(xy 90.522253 -284.916022) (xy 90.473398 -284.921954) (xy 90.424223 -284.919973) (xy 90.376004 -284.910129)
			(xy 90.329988 -284.892677) (xy 90.287367 -284.86807) (xy 90.249246 -284.836945) (xy 90.216611 -284.800108)
			(xy 90.190308 -284.758512) (xy 90.171017 -284.713236) (xy 90.15924 -284.665452) (xy 90.15528 -284.616398)
			(xy 89.826338 -284.616398) (xy 89.825843 -284.641005) (xy 89.817948 -284.689582) (xy 89.802364 -284.736263)
			(xy 89.779493 -284.77984) (xy 89.749928 -284.819184) (xy 89.714435 -284.853276) (xy 89.673932 -284.881232)
			(xy 89.62947 -284.90233) (xy 89.582199 -284.916022) (xy 89.533344 -284.921954) (xy 89.484169 -284.919973)
			(xy 89.43595 -284.910129) (xy 89.389934 -284.892677) (xy 89.347313 -284.86807) (xy 89.309192 -284.836945)
			(xy 89.276557 -284.800108) (xy 89.250254 -284.758512) (xy 89.230963 -284.713236) (xy 89.219186 -284.665452)
			(xy 89.215226 -284.616398) (xy 88.886284 -284.616398) (xy 88.885789 -284.641005) (xy 88.877894 -284.689582)
			(xy 88.86231 -284.736263) (xy 88.839439 -284.77984) (xy 88.809874 -284.819184) (xy 88.774381 -284.853276)
			(xy 88.733878 -284.881232) (xy 88.689416 -284.90233) (xy 88.642145 -284.916022) (xy 88.59329 -284.921954)
			(xy 88.544115 -284.919973) (xy 88.495896 -284.910129) (xy 88.44988 -284.892677) (xy 88.407259 -284.86807)
			(xy 88.369138 -284.836945) (xy 88.336503 -284.800108) (xy 88.3102 -284.758512) (xy 88.290909 -284.713236)
			(xy 88.279132 -284.665452) (xy 88.275172 -284.616398) (xy 87.94623 -284.616398) (xy 87.945735 -284.641005)
			(xy 87.93784 -284.689582) (xy 87.922256 -284.736263) (xy 87.899385 -284.77984) (xy 87.86982 -284.819184)
			(xy 87.834327 -284.853276) (xy 87.793824 -284.881232) (xy 87.749362 -284.90233) (xy 87.702091 -284.916022)
			(xy 87.653236 -284.921954) (xy 87.604061 -284.919973) (xy 87.555842 -284.910129) (xy 87.509826 -284.892677)
			(xy 87.467205 -284.86807) (xy 87.429084 -284.836945) (xy 87.396449 -284.800108) (xy 87.370146 -284.758512)
			(xy 87.350855 -284.713236) (xy 87.339078 -284.665452) (xy 87.335118 -284.616398) (xy 87.009986 -284.616398)
			(xy 87.009986 -285.426404) (xy 87.805272 -285.426404) (xy 87.809232 -285.37735) (xy 87.821009 -285.329566)
			(xy 87.8403 -285.28429) (xy 87.866603 -285.242694) (xy 87.899238 -285.205857) (xy 87.937359 -285.174732)
			(xy 87.97998 -285.150125) (xy 88.025996 -285.132673) (xy 88.074215 -285.122829) (xy 88.12339 -285.120848)
			(xy 88.172245 -285.12678) (xy 88.219516 -285.140472) (xy 88.263978 -285.16157) (xy 88.304481 -285.189526)
			(xy 88.339974 -285.223618) (xy 88.369539 -285.262962) (xy 88.39241 -285.306539) (xy 88.407994 -285.35322)
			(xy 88.415889 -285.401797) (xy 88.416384 -285.426404) (xy 88.745326 -285.426404) (xy 88.749286 -285.37735)
			(xy 88.761063 -285.329566) (xy 88.780354 -285.28429) (xy 88.806657 -285.242694) (xy 88.839292 -285.205857)
			(xy 88.877413 -285.174732) (xy 88.920034 -285.150125) (xy 88.96605 -285.132673) (xy 89.014269 -285.122829)
			(xy 89.063444 -285.120848) (xy 89.112299 -285.12678) (xy 89.15957 -285.140472) (xy 89.204032 -285.16157)
			(xy 89.244535 -285.189526) (xy 89.280028 -285.223618) (xy 89.309593 -285.262962) (xy 89.332464 -285.306539)
			(xy 89.348048 -285.35322) (xy 89.355943 -285.401797) (xy 89.356438 -285.426404) (xy 89.685126 -285.426404)
			(xy 89.689086 -285.37735) (xy 89.700863 -285.329566) (xy 89.720154 -285.28429) (xy 89.746457 -285.242694)
			(xy 89.779092 -285.205857) (xy 89.817213 -285.174732) (xy 89.859834 -285.150125) (xy 89.90585 -285.132673)
			(xy 89.954069 -285.122829) (xy 90.003244 -285.120848) (xy 90.052099 -285.12678) (xy 90.09937 -285.140472)
			(xy 90.143832 -285.16157) (xy 90.184335 -285.189526) (xy 90.219828 -285.223618) (xy 90.249393 -285.262962)
			(xy 90.272264 -285.306539) (xy 90.287848 -285.35322) (xy 90.295743 -285.401797) (xy 90.296238 -285.426404)
			(xy 90.614749 -285.426404) (xy 90.618844 -285.375676) (xy 90.631023 -285.326262) (xy 90.650971 -285.279442)
			(xy 90.678172 -285.236428) (xy 90.71192 -285.198334) (xy 90.751342 -285.166147) (xy 90.795416 -285.140701)
			(xy 90.843002 -285.122654) (xy 90.892866 -285.112474) (xy 90.943718 -285.110425) (xy 90.994239 -285.116559)
			(xy 91.043123 -285.130719) (xy 91.089102 -285.152536) (xy 91.130986 -285.181446) (xy 91.16769 -285.216701)
			(xy 91.198263 -285.257387) (xy 91.221914 -285.30245) (xy 91.23803 -285.350724) (xy 91.246194 -285.400958)
			(xy 91.246706 -285.426404) (xy 91.565234 -285.426404) (xy 91.569194 -285.37735) (xy 91.580971 -285.329566)
			(xy 91.600262 -285.28429) (xy 91.626565 -285.242694) (xy 91.6592 -285.205857) (xy 91.697321 -285.174732)
			(xy 91.739942 -285.150125) (xy 91.785958 -285.132673) (xy 91.834177 -285.122829) (xy 91.883352 -285.120848)
			(xy 91.932207 -285.12678) (xy 91.979478 -285.140472) (xy 92.02394 -285.16157) (xy 92.064443 -285.189526)
			(xy 92.099936 -285.223618) (xy 92.129501 -285.262962) (xy 92.152372 -285.306539) (xy 92.167956 -285.35322)
			(xy 92.175851 -285.401797) (xy 92.176346 -285.426404) (xy 92.494857 -285.426404) (xy 92.498952 -285.375676)
			(xy 92.511131 -285.326262) (xy 92.531079 -285.279442) (xy 92.55828 -285.236428) (xy 92.592028 -285.198334)
			(xy 92.63145 -285.166147) (xy 92.675524 -285.140701) (xy 92.72311 -285.122654) (xy 92.772974 -285.112474)
			(xy 92.823826 -285.110425) (xy 92.874347 -285.116559) (xy 92.923231 -285.130719) (xy 92.96921 -285.152536)
			(xy 93.011094 -285.181446) (xy 93.047798 -285.216701) (xy 93.078371 -285.257387) (xy 93.102022 -285.30245)
			(xy 93.118138 -285.350724) (xy 93.126302 -285.400958) (xy 93.126814 -285.426404) (xy 94.374711 -285.426404)
			(xy 94.378806 -285.375676) (xy 94.390985 -285.326262) (xy 94.410933 -285.279442) (xy 94.438134 -285.236428)
			(xy 94.471882 -285.198334) (xy 94.511304 -285.166147) (xy 94.555378 -285.140701) (xy 94.602964 -285.122654)
			(xy 94.652828 -285.112474) (xy 94.70368 -285.110425) (xy 94.754201 -285.116559) (xy 94.803085 -285.130719)
			(xy 94.849064 -285.152536) (xy 94.890948 -285.181446) (xy 94.927652 -285.216701) (xy 94.958225 -285.257387)
			(xy 94.981876 -285.30245) (xy 94.997992 -285.350724) (xy 95.006156 -285.400958) (xy 95.006668 -285.426404)
			(xy 95.314765 -285.426404) (xy 95.31886 -285.375676) (xy 95.331039 -285.326262) (xy 95.350987 -285.279442)
			(xy 95.378188 -285.236428) (xy 95.411936 -285.198334) (xy 95.451358 -285.166147) (xy 95.495432 -285.140701)
			(xy 95.543018 -285.122654) (xy 95.592882 -285.112474) (xy 95.643734 -285.110425) (xy 95.694255 -285.116559)
			(xy 95.743139 -285.130719) (xy 95.789118 -285.152536) (xy 95.831002 -285.181446) (xy 95.867706 -285.216701)
			(xy 95.898279 -285.257387) (xy 95.92193 -285.30245) (xy 95.938046 -285.350724) (xy 95.94621 -285.400958)
			(xy 95.946722 -285.426404) (xy 95.94621 -285.45185) (xy 95.938046 -285.502084) (xy 95.92193 -285.550358)
			(xy 95.898279 -285.595421) (xy 95.867706 -285.636107) (xy 95.831002 -285.671362) (xy 95.789118 -285.700272)
			(xy 95.743139 -285.722089) (xy 95.694255 -285.736249) (xy 95.643734 -285.742383) (xy 95.592882 -285.740334)
			(xy 95.543018 -285.730154) (xy 95.495432 -285.712107) (xy 95.451358 -285.686661) (xy 95.411936 -285.654474)
			(xy 95.378188 -285.61638) (xy 95.350987 -285.573366) (xy 95.331039 -285.526546) (xy 95.31886 -285.477132)
			(xy 95.314765 -285.426404) (xy 95.006668 -285.426404) (xy 95.006156 -285.45185) (xy 94.997992 -285.502084)
			(xy 94.981876 -285.550358) (xy 94.958225 -285.595421) (xy 94.927652 -285.636107) (xy 94.890948 -285.671362)
			(xy 94.849064 -285.700272) (xy 94.803085 -285.722089) (xy 94.754201 -285.736249) (xy 94.70368 -285.742383)
			(xy 94.652828 -285.740334) (xy 94.602964 -285.730154) (xy 94.555378 -285.712107) (xy 94.511304 -285.686661)
			(xy 94.471882 -285.654474) (xy 94.438134 -285.61638) (xy 94.410933 -285.573366) (xy 94.390985 -285.526546)
			(xy 94.378806 -285.477132) (xy 94.374711 -285.426404) (xy 93.126814 -285.426404) (xy 93.126302 -285.45185)
			(xy 93.118138 -285.502084) (xy 93.102022 -285.550358) (xy 93.078371 -285.595421) (xy 93.047798 -285.636107)
			(xy 93.011094 -285.671362) (xy 92.96921 -285.700272) (xy 92.923231 -285.722089) (xy 92.874347 -285.736249)
			(xy 92.823826 -285.742383) (xy 92.772974 -285.740334) (xy 92.72311 -285.730154) (xy 92.675524 -285.712107)
			(xy 92.63145 -285.686661) (xy 92.592028 -285.654474) (xy 92.55828 -285.61638) (xy 92.531079 -285.573366)
			(xy 92.511131 -285.526546) (xy 92.498952 -285.477132) (xy 92.494857 -285.426404) (xy 92.176346 -285.426404)
			(xy 92.175851 -285.451011) (xy 92.167956 -285.499588) (xy 92.152372 -285.546269) (xy 92.129501 -285.589846)
			(xy 92.099936 -285.62919) (xy 92.064443 -285.663282) (xy 92.02394 -285.691238) (xy 91.979478 -285.712336)
			(xy 91.932207 -285.726028) (xy 91.883352 -285.73196) (xy 91.834177 -285.729979) (xy 91.785958 -285.720135)
			(xy 91.739942 -285.702683) (xy 91.697321 -285.678076) (xy 91.6592 -285.646951) (xy 91.626565 -285.610114)
			(xy 91.600262 -285.568518) (xy 91.580971 -285.523242) (xy 91.569194 -285.475458) (xy 91.565234 -285.426404)
			(xy 91.246706 -285.426404) (xy 91.246194 -285.45185) (xy 91.23803 -285.502084) (xy 91.221914 -285.550358)
			(xy 91.198263 -285.595421) (xy 91.16769 -285.636107) (xy 91.130986 -285.671362) (xy 91.089102 -285.700272)
			(xy 91.043123 -285.722089) (xy 90.994239 -285.736249) (xy 90.943718 -285.742383) (xy 90.892866 -285.740334)
			(xy 90.843002 -285.730154) (xy 90.795416 -285.712107) (xy 90.751342 -285.686661) (xy 90.71192 -285.654474)
			(xy 90.678172 -285.61638) (xy 90.650971 -285.573366) (xy 90.631023 -285.526546) (xy 90.618844 -285.477132)
			(xy 90.614749 -285.426404) (xy 90.296238 -285.426404) (xy 90.295743 -285.451011) (xy 90.287848 -285.499588)
			(xy 90.272264 -285.546269) (xy 90.249393 -285.589846) (xy 90.219828 -285.62919) (xy 90.184335 -285.663282)
			(xy 90.143832 -285.691238) (xy 90.09937 -285.712336) (xy 90.052099 -285.726028) (xy 90.003244 -285.73196)
			(xy 89.954069 -285.729979) (xy 89.90585 -285.720135) (xy 89.859834 -285.702683) (xy 89.817213 -285.678076)
			(xy 89.779092 -285.646951) (xy 89.746457 -285.610114) (xy 89.720154 -285.568518) (xy 89.700863 -285.523242)
			(xy 89.689086 -285.475458) (xy 89.685126 -285.426404) (xy 89.356438 -285.426404) (xy 89.355943 -285.451011)
			(xy 89.348048 -285.499588) (xy 89.332464 -285.546269) (xy 89.309593 -285.589846) (xy 89.280028 -285.62919)
			(xy 89.244535 -285.663282) (xy 89.204032 -285.691238) (xy 89.15957 -285.712336) (xy 89.112299 -285.726028)
			(xy 89.063444 -285.73196) (xy 89.014269 -285.729979) (xy 88.96605 -285.720135) (xy 88.920034 -285.702683)
			(xy 88.877413 -285.678076) (xy 88.839292 -285.646951) (xy 88.806657 -285.610114) (xy 88.780354 -285.568518)
			(xy 88.761063 -285.523242) (xy 88.749286 -285.475458) (xy 88.745326 -285.426404) (xy 88.416384 -285.426404)
			(xy 88.415889 -285.451011) (xy 88.407994 -285.499588) (xy 88.39241 -285.546269) (xy 88.369539 -285.589846)
			(xy 88.339974 -285.62919) (xy 88.304481 -285.663282) (xy 88.263978 -285.691238) (xy 88.219516 -285.712336)
			(xy 88.172245 -285.726028) (xy 88.12339 -285.73196) (xy 88.074215 -285.729979) (xy 88.025996 -285.720135)
			(xy 87.97998 -285.702683) (xy 87.937359 -285.678076) (xy 87.899238 -285.646951) (xy 87.866603 -285.610114)
			(xy 87.8403 -285.568518) (xy 87.821009 -285.523242) (xy 87.809232 -285.475458) (xy 87.805272 -285.426404)
			(xy 87.009986 -285.426404) (xy 87.009986 -286.23641) (xy 87.335118 -286.23641) (xy 87.339078 -286.187356)
			(xy 87.350855 -286.139572) (xy 87.370146 -286.094296) (xy 87.396449 -286.0527) (xy 87.429084 -286.015863)
			(xy 87.467205 -285.984738) (xy 87.509826 -285.960131) (xy 87.555842 -285.942679) (xy 87.604061 -285.932835)
			(xy 87.653236 -285.930854) (xy 87.702091 -285.936786) (xy 87.749362 -285.950478) (xy 87.793824 -285.971576)
			(xy 87.834327 -285.999532) (xy 87.86982 -286.033624) (xy 87.899385 -286.072968) (xy 87.922256 -286.116545)
			(xy 87.93784 -286.163226) (xy 87.945735 -286.211803) (xy 87.94623 -286.23641) (xy 88.275172 -286.23641)
			(xy 88.279132 -286.187356) (xy 88.290909 -286.139572) (xy 88.3102 -286.094296) (xy 88.336503 -286.0527)
			(xy 88.369138 -286.015863) (xy 88.407259 -285.984738) (xy 88.44988 -285.960131) (xy 88.495896 -285.942679)
			(xy 88.544115 -285.932835) (xy 88.59329 -285.930854) (xy 88.642145 -285.936786) (xy 88.689416 -285.950478)
			(xy 88.733878 -285.971576) (xy 88.774381 -285.999532) (xy 88.809874 -286.033624) (xy 88.839439 -286.072968)
			(xy 88.86231 -286.116545) (xy 88.877894 -286.163226) (xy 88.885789 -286.211803) (xy 88.886284 -286.23641)
			(xy 89.215226 -286.23641) (xy 89.219186 -286.187356) (xy 89.230963 -286.139572) (xy 89.250254 -286.094296)
			(xy 89.276557 -286.0527) (xy 89.309192 -286.015863) (xy 89.347313 -285.984738) (xy 89.389934 -285.960131)
			(xy 89.43595 -285.942679) (xy 89.484169 -285.932835) (xy 89.533344 -285.930854) (xy 89.582199 -285.936786)
			(xy 89.62947 -285.950478) (xy 89.673932 -285.971576) (xy 89.714435 -285.999532) (xy 89.749928 -286.033624)
			(xy 89.779493 -286.072968) (xy 89.802364 -286.116545) (xy 89.817948 -286.163226) (xy 89.825843 -286.211803)
			(xy 89.826338 -286.23641) (xy 90.15528 -286.23641) (xy 90.15924 -286.187356) (xy 90.171017 -286.139572)
			(xy 90.190308 -286.094296) (xy 90.216611 -286.0527) (xy 90.249246 -286.015863) (xy 90.287367 -285.984738)
			(xy 90.329988 -285.960131) (xy 90.376004 -285.942679) (xy 90.424223 -285.932835) (xy 90.473398 -285.930854)
			(xy 90.522253 -285.936786) (xy 90.569524 -285.950478) (xy 90.613986 -285.971576) (xy 90.654489 -285.999532)
			(xy 90.689982 -286.033624) (xy 90.719547 -286.072968) (xy 90.742418 -286.116545) (xy 90.758002 -286.163226)
			(xy 90.765897 -286.211803) (xy 90.766392 -286.23641) (xy 91.084903 -286.23641) (xy 91.088998 -286.185682)
			(xy 91.101177 -286.136268) (xy 91.121125 -286.089448) (xy 91.148326 -286.046434) (xy 91.182074 -286.00834)
			(xy 91.221496 -285.976153) (xy 91.26557 -285.950707) (xy 91.313156 -285.93266) (xy 91.36302 -285.92248)
			(xy 91.413872 -285.920431) (xy 91.464393 -285.926565) (xy 91.513277 -285.940725) (xy 91.559256 -285.962542)
			(xy 91.60114 -285.991452) (xy 91.637844 -286.026707) (xy 91.668417 -286.067393) (xy 91.692068 -286.112456)
			(xy 91.708184 -286.16073) (xy 91.716348 -286.210964) (xy 91.71686 -286.23641) (xy 92.024703 -286.23641)
			(xy 92.028798 -286.185682) (xy 92.040977 -286.136268) (xy 92.060925 -286.089448) (xy 92.088126 -286.046434)
			(xy 92.121874 -286.00834) (xy 92.161296 -285.976153) (xy 92.20537 -285.950707) (xy 92.252956 -285.93266)
			(xy 92.30282 -285.92248) (xy 92.353672 -285.920431) (xy 92.404193 -285.926565) (xy 92.453077 -285.940725)
			(xy 92.499056 -285.962542) (xy 92.54094 -285.991452) (xy 92.577644 -286.026707) (xy 92.608217 -286.067393)
			(xy 92.631868 -286.112456) (xy 92.647984 -286.16073) (xy 92.656148 -286.210964) (xy 92.65666 -286.23641)
			(xy 92.975188 -286.23641) (xy 92.979148 -286.187356) (xy 92.990925 -286.139572) (xy 93.010216 -286.094296)
			(xy 93.036519 -286.0527) (xy 93.069154 -286.015863) (xy 93.107275 -285.984738) (xy 93.149896 -285.960131)
			(xy 93.195912 -285.942679) (xy 93.244131 -285.932835) (xy 93.293306 -285.930854) (xy 93.342161 -285.936786)
			(xy 93.389432 -285.950478) (xy 93.433894 -285.971576) (xy 93.474397 -285.999532) (xy 93.50989 -286.033624)
			(xy 93.539455 -286.072968) (xy 93.562326 -286.116545) (xy 93.57791 -286.163226) (xy 93.585805 -286.211803)
			(xy 93.5863 -286.23641) (xy 93.904811 -286.23641) (xy 93.908906 -286.185682) (xy 93.921085 -286.136268)
			(xy 93.941033 -286.089448) (xy 93.968234 -286.046434) (xy 94.001982 -286.00834) (xy 94.041404 -285.976153)
			(xy 94.085478 -285.950707) (xy 94.133064 -285.93266) (xy 94.182928 -285.92248) (xy 94.23378 -285.920431)
			(xy 94.284301 -285.926565) (xy 94.333185 -285.940725) (xy 94.379164 -285.962542) (xy 94.421048 -285.991452)
			(xy 94.457752 -286.026707) (xy 94.488325 -286.067393) (xy 94.511976 -286.112456) (xy 94.528092 -286.16073)
			(xy 94.536256 -286.210964) (xy 94.536768 -286.23641) (xy 94.855296 -286.23641) (xy 94.859256 -286.187356)
			(xy 94.871033 -286.139572) (xy 94.890324 -286.094296) (xy 94.916627 -286.0527) (xy 94.949262 -286.015863)
			(xy 94.987383 -285.984738) (xy 95.030004 -285.960131) (xy 95.07602 -285.942679) (xy 95.124239 -285.932835)
			(xy 95.173414 -285.930854) (xy 95.222269 -285.936786) (xy 95.26954 -285.950478) (xy 95.314002 -285.971576)
			(xy 95.354505 -285.999532) (xy 95.389998 -286.033624) (xy 95.419563 -286.072968) (xy 95.442434 -286.116545)
			(xy 95.458018 -286.163226) (xy 95.465913 -286.211803) (xy 95.466408 -286.23641) (xy 95.465913 -286.261017)
			(xy 95.458018 -286.309594) (xy 95.442434 -286.356275) (xy 95.419563 -286.399852) (xy 95.389998 -286.439196)
			(xy 95.354505 -286.473288) (xy 95.314002 -286.501244) (xy 95.26954 -286.522342) (xy 95.222269 -286.536034)
			(xy 95.173414 -286.541966) (xy 95.124239 -286.539985) (xy 95.07602 -286.530141) (xy 95.030004 -286.512689)
			(xy 94.987383 -286.488082) (xy 94.949262 -286.456957) (xy 94.916627 -286.42012) (xy 94.890324 -286.378524)
			(xy 94.871033 -286.333248) (xy 94.859256 -286.285464) (xy 94.855296 -286.23641) (xy 94.536768 -286.23641)
			(xy 94.536256 -286.261856) (xy 94.528092 -286.31209) (xy 94.511976 -286.360364) (xy 94.488325 -286.405427)
			(xy 94.457752 -286.446113) (xy 94.421048 -286.481368) (xy 94.379164 -286.510278) (xy 94.333185 -286.532095)
			(xy 94.284301 -286.546255) (xy 94.23378 -286.552389) (xy 94.182928 -286.55034) (xy 94.133064 -286.54016)
			(xy 94.085478 -286.522113) (xy 94.041404 -286.496667) (xy 94.001982 -286.46448) (xy 93.968234 -286.426386)
			(xy 93.941033 -286.383372) (xy 93.921085 -286.336552) (xy 93.908906 -286.287138) (xy 93.904811 -286.23641)
			(xy 93.5863 -286.23641) (xy 93.585805 -286.261017) (xy 93.57791 -286.309594) (xy 93.562326 -286.356275)
			(xy 93.539455 -286.399852) (xy 93.50989 -286.439196) (xy 93.474397 -286.473288) (xy 93.433894 -286.501244)
			(xy 93.389432 -286.522342) (xy 93.342161 -286.536034) (xy 93.293306 -286.541966) (xy 93.244131 -286.539985)
			(xy 93.195912 -286.530141) (xy 93.149896 -286.512689) (xy 93.107275 -286.488082) (xy 93.069154 -286.456957)
			(xy 93.036519 -286.42012) (xy 93.010216 -286.378524) (xy 92.990925 -286.333248) (xy 92.979148 -286.285464)
			(xy 92.975188 -286.23641) (xy 92.65666 -286.23641) (xy 92.656148 -286.261856) (xy 92.647984 -286.31209)
			(xy 92.631868 -286.360364) (xy 92.608217 -286.405427) (xy 92.577644 -286.446113) (xy 92.54094 -286.481368)
			(xy 92.499056 -286.510278) (xy 92.453077 -286.532095) (xy 92.404193 -286.546255) (xy 92.353672 -286.552389)
			(xy 92.30282 -286.55034) (xy 92.252956 -286.54016) (xy 92.20537 -286.522113) (xy 92.161296 -286.496667)
			(xy 92.121874 -286.46448) (xy 92.088126 -286.426386) (xy 92.060925 -286.383372) (xy 92.040977 -286.336552)
			(xy 92.028798 -286.287138) (xy 92.024703 -286.23641) (xy 91.71686 -286.23641) (xy 91.716348 -286.261856)
			(xy 91.708184 -286.31209) (xy 91.692068 -286.360364) (xy 91.668417 -286.405427) (xy 91.637844 -286.446113)
			(xy 91.60114 -286.481368) (xy 91.559256 -286.510278) (xy 91.513277 -286.532095) (xy 91.464393 -286.546255)
			(xy 91.413872 -286.552389) (xy 91.36302 -286.55034) (xy 91.313156 -286.54016) (xy 91.26557 -286.522113)
			(xy 91.221496 -286.496667) (xy 91.182074 -286.46448) (xy 91.148326 -286.426386) (xy 91.121125 -286.383372)
			(xy 91.101177 -286.336552) (xy 91.088998 -286.287138) (xy 91.084903 -286.23641) (xy 90.766392 -286.23641)
			(xy 90.765897 -286.261017) (xy 90.758002 -286.309594) (xy 90.742418 -286.356275) (xy 90.719547 -286.399852)
			(xy 90.689982 -286.439196) (xy 90.654489 -286.473288) (xy 90.613986 -286.501244) (xy 90.569524 -286.522342)
			(xy 90.522253 -286.536034) (xy 90.473398 -286.541966) (xy 90.424223 -286.539985) (xy 90.376004 -286.530141)
			(xy 90.329988 -286.512689) (xy 90.287367 -286.488082) (xy 90.249246 -286.456957) (xy 90.216611 -286.42012)
			(xy 90.190308 -286.378524) (xy 90.171017 -286.333248) (xy 90.15924 -286.285464) (xy 90.15528 -286.23641)
			(xy 89.826338 -286.23641) (xy 89.825843 -286.261017) (xy 89.817948 -286.309594) (xy 89.802364 -286.356275)
			(xy 89.779493 -286.399852) (xy 89.749928 -286.439196) (xy 89.714435 -286.473288) (xy 89.673932 -286.501244)
			(xy 89.62947 -286.522342) (xy 89.582199 -286.536034) (xy 89.533344 -286.541966) (xy 89.484169 -286.539985)
			(xy 89.43595 -286.530141) (xy 89.389934 -286.512689) (xy 89.347313 -286.488082) (xy 89.309192 -286.456957)
			(xy 89.276557 -286.42012) (xy 89.250254 -286.378524) (xy 89.230963 -286.333248) (xy 89.219186 -286.285464)
			(xy 89.215226 -286.23641) (xy 88.886284 -286.23641) (xy 88.885789 -286.261017) (xy 88.877894 -286.309594)
			(xy 88.86231 -286.356275) (xy 88.839439 -286.399852) (xy 88.809874 -286.439196) (xy 88.774381 -286.473288)
			(xy 88.733878 -286.501244) (xy 88.689416 -286.522342) (xy 88.642145 -286.536034) (xy 88.59329 -286.541966)
			(xy 88.544115 -286.539985) (xy 88.495896 -286.530141) (xy 88.44988 -286.512689) (xy 88.407259 -286.488082)
			(xy 88.369138 -286.456957) (xy 88.336503 -286.42012) (xy 88.3102 -286.378524) (xy 88.290909 -286.333248)
			(xy 88.279132 -286.285464) (xy 88.275172 -286.23641) (xy 87.94623 -286.23641) (xy 87.945735 -286.261017)
			(xy 87.93784 -286.309594) (xy 87.922256 -286.356275) (xy 87.899385 -286.399852) (xy 87.86982 -286.439196)
			(xy 87.834327 -286.473288) (xy 87.793824 -286.501244) (xy 87.749362 -286.522342) (xy 87.702091 -286.536034)
			(xy 87.653236 -286.541966) (xy 87.604061 -286.539985) (xy 87.555842 -286.530141) (xy 87.509826 -286.512689)
			(xy 87.467205 -286.488082) (xy 87.429084 -286.456957) (xy 87.396449 -286.42012) (xy 87.370146 -286.378524)
			(xy 87.350855 -286.333248) (xy 87.339078 -286.285464) (xy 87.335118 -286.23641) (xy 87.009986 -286.23641)
			(xy 87.009986 -286.644842) (xy 87.010356 -286.653948) (xy 87.016728 -286.671008) (xy 87.022432 -286.678116)
			(xy 87.024972 -286.68091) (xy 87.065104 -286.715454) (xy 87.080344 -286.728662) (xy 87.081614 -286.729678)
			(xy 87.088577 -286.73488) (xy 87.104935 -286.740722) (xy 87.113618 -286.741108) (xy 87.159592 -286.741108)
			(xy 87.171022 -286.740854) (xy 87.171276 -286.740854) (xy 87.195254 -286.741345) (xy 87.242615 -286.748885)
			(xy 87.288214 -286.763737) (xy 87.330931 -286.785534) (xy 87.369716 -286.813742) (xy 87.403613 -286.847666)
			(xy 87.43179 -286.886472) (xy 87.453555 -286.929206) (xy 87.46837 -286.974817) (xy 87.475874 -287.022184)
			(xy 87.47633 -287.046162) (xy 87.805272 -287.046162) (xy 87.809232 -286.997108) (xy 87.821009 -286.949324)
			(xy 87.8403 -286.904048) (xy 87.866603 -286.862452) (xy 87.899238 -286.825615) (xy 87.937359 -286.79449)
			(xy 87.97998 -286.769883) (xy 88.025996 -286.752431) (xy 88.074215 -286.742587) (xy 88.12339 -286.740606)
			(xy 88.172245 -286.746538) (xy 88.219516 -286.76023) (xy 88.263978 -286.781328) (xy 88.304481 -286.809284)
			(xy 88.339974 -286.843376) (xy 88.369539 -286.88272) (xy 88.39241 -286.926297) (xy 88.407994 -286.972978)
			(xy 88.415889 -287.021555) (xy 88.416384 -287.046162) (xy 88.745326 -287.046162) (xy 88.749286 -286.997108)
			(xy 88.761063 -286.949324) (xy 88.780354 -286.904048) (xy 88.806657 -286.862452) (xy 88.839292 -286.825615)
			(xy 88.877413 -286.79449) (xy 88.920034 -286.769883) (xy 88.96605 -286.752431) (xy 89.014269 -286.742587)
			(xy 89.063444 -286.740606) (xy 89.112299 -286.746538) (xy 89.15957 -286.76023) (xy 89.204032 -286.781328)
			(xy 89.244535 -286.809284) (xy 89.280028 -286.843376) (xy 89.309593 -286.88272) (xy 89.332464 -286.926297)
			(xy 89.348048 -286.972978) (xy 89.355943 -287.021555) (xy 89.356438 -287.046162) (xy 89.356428 -287.04667)
			(xy 89.68538 -287.04667) (xy 89.68934 -286.997616) (xy 89.701117 -286.949832) (xy 89.720408 -286.904556)
			(xy 89.746711 -286.86296) (xy 89.779346 -286.826123) (xy 89.817467 -286.794998) (xy 89.860088 -286.770391)
			(xy 89.906104 -286.752939) (xy 89.954323 -286.743095) (xy 90.003498 -286.741114) (xy 90.052353 -286.747046)
			(xy 90.099624 -286.760738) (xy 90.144086 -286.781836) (xy 90.184589 -286.809792) (xy 90.220082 -286.843884)
			(xy 90.249647 -286.883228) (xy 90.272518 -286.926805) (xy 90.288102 -286.973486) (xy 90.295997 -287.022063)
			(xy 90.296482 -287.046162) (xy 90.614749 -287.046162) (xy 90.618844 -286.995434) (xy 90.631023 -286.94602)
			(xy 90.650971 -286.8992) (xy 90.678172 -286.856186) (xy 90.71192 -286.818092) (xy 90.751342 -286.785905)
			(xy 90.795416 -286.760459) (xy 90.843002 -286.742412) (xy 90.892866 -286.732232) (xy 90.943718 -286.730183)
			(xy 90.994239 -286.736317) (xy 91.043123 -286.750477) (xy 91.089102 -286.772294) (xy 91.130986 -286.801204)
			(xy 91.16769 -286.836459) (xy 91.198263 -286.877145) (xy 91.221914 -286.922208) (xy 91.23803 -286.970482)
			(xy 91.246194 -287.020716) (xy 91.246706 -287.046162) (xy 91.565234 -287.046162) (xy 91.569194 -286.997108)
			(xy 91.580971 -286.949324) (xy 91.600262 -286.904048) (xy 91.626565 -286.862452) (xy 91.6592 -286.825615)
			(xy 91.697321 -286.79449) (xy 91.739942 -286.769883) (xy 91.785958 -286.752431) (xy 91.834177 -286.742587)
			(xy 91.883352 -286.740606) (xy 91.932207 -286.746538) (xy 91.979478 -286.76023) (xy 92.02394 -286.781328)
			(xy 92.064443 -286.809284) (xy 92.099936 -286.843376) (xy 92.129501 -286.88272) (xy 92.152372 -286.926297)
			(xy 92.167956 -286.972978) (xy 92.175851 -287.021555) (xy 92.176346 -287.046162) (xy 92.494857 -287.046162)
			(xy 92.498952 -286.995434) (xy 92.511131 -286.94602) (xy 92.531079 -286.8992) (xy 92.55828 -286.856186)
			(xy 92.592028 -286.818092) (xy 92.63145 -286.785905) (xy 92.675524 -286.760459) (xy 92.72311 -286.742412)
			(xy 92.772974 -286.732232) (xy 92.823826 -286.730183) (xy 92.874347 -286.736317) (xy 92.923231 -286.750477)
			(xy 92.96921 -286.772294) (xy 93.011094 -286.801204) (xy 93.047798 -286.836459) (xy 93.078371 -286.877145)
			(xy 93.102022 -286.922208) (xy 93.118138 -286.970482) (xy 93.126302 -287.020716) (xy 93.126814 -287.046162)
			(xy 93.445342 -287.046162) (xy 93.449302 -286.997108) (xy 93.461079 -286.949324) (xy 93.48037 -286.904048)
			(xy 93.506673 -286.862452) (xy 93.539308 -286.825615) (xy 93.577429 -286.79449) (xy 93.62005 -286.769883)
			(xy 93.666066 -286.752431) (xy 93.714285 -286.742587) (xy 93.76346 -286.740606) (xy 93.812315 -286.746538)
			(xy 93.859586 -286.76023) (xy 93.904048 -286.781328) (xy 93.944551 -286.809284) (xy 93.980044 -286.843376)
			(xy 94.009609 -286.88272) (xy 94.03248 -286.926297) (xy 94.048064 -286.972978) (xy 94.055959 -287.021555)
			(xy 94.056454 -287.046162) (xy 94.374711 -287.046162) (xy 94.378806 -286.995434) (xy 94.390985 -286.94602)
			(xy 94.410933 -286.8992) (xy 94.438134 -286.856186) (xy 94.471882 -286.818092) (xy 94.511304 -286.785905)
			(xy 94.555378 -286.760459) (xy 94.602964 -286.742412) (xy 94.652828 -286.732232) (xy 94.70368 -286.730183)
			(xy 94.754201 -286.736317) (xy 94.803085 -286.750477) (xy 94.849064 -286.772294) (xy 94.890948 -286.801204)
			(xy 94.927652 -286.836459) (xy 94.958225 -286.877145) (xy 94.981876 -286.922208) (xy 94.997992 -286.970482)
			(xy 95.006156 -287.020716) (xy 95.006668 -287.046162) (xy 95.314765 -287.046162) (xy 95.31886 -286.995434)
			(xy 95.331039 -286.94602) (xy 95.350987 -286.8992) (xy 95.378188 -286.856186) (xy 95.411936 -286.818092)
			(xy 95.451358 -286.785905) (xy 95.495432 -286.760459) (xy 95.543018 -286.742412) (xy 95.592882 -286.732232)
			(xy 95.643734 -286.730183) (xy 95.694255 -286.736317) (xy 95.743139 -286.750477) (xy 95.789118 -286.772294)
			(xy 95.831002 -286.801204) (xy 95.867706 -286.836459) (xy 95.898279 -286.877145) (xy 95.92193 -286.922208)
			(xy 95.938046 -286.970482) (xy 95.94621 -287.020716) (xy 95.946722 -287.046162) (xy 95.94621 -287.071608)
			(xy 95.938046 -287.121842) (xy 95.92193 -287.170116) (xy 95.898279 -287.215179) (xy 95.867706 -287.255865)
			(xy 95.831002 -287.29112) (xy 95.789118 -287.32003) (xy 95.743139 -287.341847) (xy 95.694255 -287.356007)
			(xy 95.643734 -287.362141) (xy 95.592882 -287.360092) (xy 95.543018 -287.349912) (xy 95.495432 -287.331865)
			(xy 95.451358 -287.306419) (xy 95.411936 -287.274232) (xy 95.378188 -287.236138) (xy 95.350987 -287.193124)
			(xy 95.331039 -287.146304) (xy 95.31886 -287.09689) (xy 95.314765 -287.046162) (xy 95.006668 -287.046162)
			(xy 95.006156 -287.071608) (xy 94.997992 -287.121842) (xy 94.981876 -287.170116) (xy 94.958225 -287.215179)
			(xy 94.927652 -287.255865) (xy 94.890948 -287.29112) (xy 94.849064 -287.32003) (xy 94.803085 -287.341847)
			(xy 94.754201 -287.356007) (xy 94.70368 -287.362141) (xy 94.652828 -287.360092) (xy 94.602964 -287.349912)
			(xy 94.555378 -287.331865) (xy 94.511304 -287.306419) (xy 94.471882 -287.274232) (xy 94.438134 -287.236138)
			(xy 94.410933 -287.193124) (xy 94.390985 -287.146304) (xy 94.378806 -287.09689) (xy 94.374711 -287.046162)
			(xy 94.056454 -287.046162) (xy 94.055959 -287.070769) (xy 94.048064 -287.119346) (xy 94.03248 -287.166027)
			(xy 94.009609 -287.209604) (xy 93.980044 -287.248948) (xy 93.944551 -287.28304) (xy 93.904048 -287.310996)
			(xy 93.859586 -287.332094) (xy 93.812315 -287.345786) (xy 93.76346 -287.351718) (xy 93.714285 -287.349737)
			(xy 93.666066 -287.339893) (xy 93.62005 -287.322441) (xy 93.577429 -287.297834) (xy 93.539308 -287.266709)
			(xy 93.506673 -287.229872) (xy 93.48037 -287.188276) (xy 93.461079 -287.143) (xy 93.449302 -287.095216)
			(xy 93.445342 -287.046162) (xy 93.126814 -287.046162) (xy 93.126302 -287.071608) (xy 93.118138 -287.121842)
			(xy 93.102022 -287.170116) (xy 93.078371 -287.215179) (xy 93.047798 -287.255865) (xy 93.011094 -287.29112)
			(xy 92.96921 -287.32003) (xy 92.923231 -287.341847) (xy 92.874347 -287.356007) (xy 92.823826 -287.362141)
			(xy 92.772974 -287.360092) (xy 92.72311 -287.349912) (xy 92.675524 -287.331865) (xy 92.63145 -287.306419)
			(xy 92.592028 -287.274232) (xy 92.55828 -287.236138) (xy 92.531079 -287.193124) (xy 92.511131 -287.146304)
			(xy 92.498952 -287.09689) (xy 92.494857 -287.046162) (xy 92.176346 -287.046162) (xy 92.175851 -287.070769)
			(xy 92.167956 -287.119346) (xy 92.152372 -287.166027) (xy 92.129501 -287.209604) (xy 92.099936 -287.248948)
			(xy 92.064443 -287.28304) (xy 92.02394 -287.310996) (xy 91.979478 -287.332094) (xy 91.932207 -287.345786)
			(xy 91.883352 -287.351718) (xy 91.834177 -287.349737) (xy 91.785958 -287.339893) (xy 91.739942 -287.322441)
			(xy 91.697321 -287.297834) (xy 91.6592 -287.266709) (xy 91.626565 -287.229872) (xy 91.600262 -287.188276)
			(xy 91.580971 -287.143) (xy 91.569194 -287.095216) (xy 91.565234 -287.046162) (xy 91.246706 -287.046162)
			(xy 91.246194 -287.071608) (xy 91.23803 -287.121842) (xy 91.221914 -287.170116) (xy 91.198263 -287.215179)
			(xy 91.16769 -287.255865) (xy 91.130986 -287.29112) (xy 91.089102 -287.32003) (xy 91.043123 -287.341847)
			(xy 90.994239 -287.356007) (xy 90.943718 -287.362141) (xy 90.892866 -287.360092) (xy 90.843002 -287.349912)
			(xy 90.795416 -287.331865) (xy 90.751342 -287.306419) (xy 90.71192 -287.274232) (xy 90.678172 -287.236138)
			(xy 90.650971 -287.193124) (xy 90.631023 -287.146304) (xy 90.618844 -287.09689) (xy 90.614749 -287.046162)
			(xy 90.296482 -287.046162) (xy 90.296492 -287.04667) (xy 90.295997 -287.071277) (xy 90.288102 -287.119854)
			(xy 90.272518 -287.166535) (xy 90.249647 -287.210112) (xy 90.220082 -287.249456) (xy 90.184589 -287.283548)
			(xy 90.144086 -287.311504) (xy 90.099624 -287.332602) (xy 90.052353 -287.346294) (xy 90.003498 -287.352226)
			(xy 89.954323 -287.350245) (xy 89.906104 -287.340401) (xy 89.860088 -287.322949) (xy 89.817467 -287.298342)
			(xy 89.779346 -287.267217) (xy 89.746711 -287.23038) (xy 89.720408 -287.188784) (xy 89.701117 -287.143508)
			(xy 89.68934 -287.095724) (xy 89.68538 -287.04667) (xy 89.356428 -287.04667) (xy 89.355943 -287.070769)
			(xy 89.348048 -287.119346) (xy 89.332464 -287.166027) (xy 89.309593 -287.209604) (xy 89.280028 -287.248948)
			(xy 89.244535 -287.28304) (xy 89.204032 -287.310996) (xy 89.15957 -287.332094) (xy 89.112299 -287.345786)
			(xy 89.063444 -287.351718) (xy 89.014269 -287.349737) (xy 88.96605 -287.339893) (xy 88.920034 -287.322441)
			(xy 88.877413 -287.297834) (xy 88.839292 -287.266709) (xy 88.806657 -287.229872) (xy 88.780354 -287.188276)
			(xy 88.761063 -287.143) (xy 88.749286 -287.095216) (xy 88.745326 -287.046162) (xy 88.416384 -287.046162)
			(xy 88.415889 -287.070769) (xy 88.407994 -287.119346) (xy 88.39241 -287.166027) (xy 88.369539 -287.209604)
			(xy 88.339974 -287.248948) (xy 88.304481 -287.28304) (xy 88.263978 -287.310996) (xy 88.219516 -287.332094)
			(xy 88.172245 -287.345786) (xy 88.12339 -287.351718) (xy 88.074215 -287.349737) (xy 88.025996 -287.339893)
			(xy 87.97998 -287.322441) (xy 87.937359 -287.297834) (xy 87.899238 -287.266709) (xy 87.866603 -287.229872)
			(xy 87.8403 -287.188276) (xy 87.821009 -287.143) (xy 87.809232 -287.095216) (xy 87.805272 -287.046162)
			(xy 87.47633 -287.046162) (xy 87.475887 -287.070158) (xy 87.468385 -287.117559) (xy 87.45356 -287.163203)
			(xy 87.431777 -287.205966) (xy 87.403572 -287.244795) (xy 87.369641 -287.278733) (xy 87.330817 -287.306946)
			(xy 87.288059 -287.328737) (xy 87.242418 -287.343571) (xy 87.195018 -287.351082) (xy 87.171022 -287.35147)
			(xy 87.159613 -287.351395) (xy 87.136856 -287.34974) (xy 87.125556 -287.348168) (xy 87.114634 -287.34639)
			(xy 87.09279 -287.35274) (xy 87.065358 -287.376616) (xy 87.06485 -287.377124) (xy 87.030814 -287.406334)
			(xy 87.02929 -287.407604) (xy 87.024972 -287.411922) (xy 87.017606 -287.419034) (xy 87.009986 -287.43783)
			(xy 87.009986 -287.737804) (xy 87.01278 -287.746186) (xy 87.021612 -287.772889) (xy 87.031193 -287.828304)
			(xy 87.03183 -287.856422) (xy 87.335118 -287.856422) (xy 87.339078 -287.807368) (xy 87.350855 -287.759584)
			(xy 87.370146 -287.714308) (xy 87.396449 -287.672712) (xy 87.429084 -287.635875) (xy 87.467205 -287.60475)
			(xy 87.509826 -287.580143) (xy 87.555842 -287.562691) (xy 87.604061 -287.552847) (xy 87.653236 -287.550866)
			(xy 87.702091 -287.556798) (xy 87.749362 -287.57049) (xy 87.793824 -287.591588) (xy 87.834327 -287.619544)
			(xy 87.86982 -287.653636) (xy 87.899385 -287.69298) (xy 87.922256 -287.736557) (xy 87.93784 -287.783238)
			(xy 87.945735 -287.831815) (xy 87.94623 -287.856422) (xy 88.275172 -287.856422) (xy 88.279132 -287.807368)
			(xy 88.290909 -287.759584) (xy 88.3102 -287.714308) (xy 88.336503 -287.672712) (xy 88.369138 -287.635875)
			(xy 88.407259 -287.60475) (xy 88.44988 -287.580143) (xy 88.495896 -287.562691) (xy 88.544115 -287.552847)
			(xy 88.59329 -287.550866) (xy 88.642145 -287.556798) (xy 88.689416 -287.57049) (xy 88.733878 -287.591588)
			(xy 88.774381 -287.619544) (xy 88.809874 -287.653636) (xy 88.839439 -287.69298) (xy 88.86231 -287.736557)
			(xy 88.877894 -287.783238) (xy 88.885789 -287.831815) (xy 88.886284 -287.856422) (xy 89.215226 -287.856422)
			(xy 89.219186 -287.807368) (xy 89.230963 -287.759584) (xy 89.250254 -287.714308) (xy 89.276557 -287.672712)
			(xy 89.309192 -287.635875) (xy 89.347313 -287.60475) (xy 89.389934 -287.580143) (xy 89.43595 -287.562691)
			(xy 89.484169 -287.552847) (xy 89.533344 -287.550866) (xy 89.582199 -287.556798) (xy 89.62947 -287.57049)
			(xy 89.673932 -287.591588) (xy 89.714435 -287.619544) (xy 89.749928 -287.653636) (xy 89.779493 -287.69298)
			(xy 89.802364 -287.736557) (xy 89.817948 -287.783238) (xy 89.825843 -287.831815) (xy 89.826338 -287.856422)
			(xy 90.15528 -287.856422) (xy 90.15924 -287.807368) (xy 90.171017 -287.759584) (xy 90.190308 -287.714308)
			(xy 90.216611 -287.672712) (xy 90.249246 -287.635875) (xy 90.287367 -287.60475) (xy 90.329988 -287.580143)
			(xy 90.376004 -287.562691) (xy 90.424223 -287.552847) (xy 90.473398 -287.550866) (xy 90.522253 -287.556798)
			(xy 90.569524 -287.57049) (xy 90.613986 -287.591588) (xy 90.654489 -287.619544) (xy 90.689982 -287.653636)
			(xy 90.719547 -287.69298) (xy 90.742418 -287.736557) (xy 90.758002 -287.783238) (xy 90.765897 -287.831815)
			(xy 90.766392 -287.856422) (xy 91.084903 -287.856422) (xy 91.088998 -287.805694) (xy 91.101177 -287.75628)
			(xy 91.121125 -287.70946) (xy 91.148326 -287.666446) (xy 91.182074 -287.628352) (xy 91.221496 -287.596165)
			(xy 91.26557 -287.570719) (xy 91.313156 -287.552672) (xy 91.36302 -287.542492) (xy 91.413872 -287.540443)
			(xy 91.464393 -287.546577) (xy 91.513277 -287.560737) (xy 91.559256 -287.582554) (xy 91.60114 -287.611464)
			(xy 91.637844 -287.646719) (xy 91.668417 -287.687405) (xy 91.692068 -287.732468) (xy 91.708184 -287.780742)
			(xy 91.716348 -287.830976) (xy 91.71686 -287.856422) (xy 92.024703 -287.856422) (xy 92.028798 -287.805694)
			(xy 92.040977 -287.75628) (xy 92.060925 -287.70946) (xy 92.088126 -287.666446) (xy 92.121874 -287.628352)
			(xy 92.161296 -287.596165) (xy 92.20537 -287.570719) (xy 92.252956 -287.552672) (xy 92.30282 -287.542492)
			(xy 92.353672 -287.540443) (xy 92.404193 -287.546577) (xy 92.453077 -287.560737) (xy 92.499056 -287.582554)
			(xy 92.54094 -287.611464) (xy 92.577644 -287.646719) (xy 92.608217 -287.687405) (xy 92.631868 -287.732468)
			(xy 92.647984 -287.780742) (xy 92.656148 -287.830976) (xy 92.65666 -287.856422) (xy 93.904811 -287.856422)
			(xy 93.908906 -287.805694) (xy 93.921085 -287.75628) (xy 93.941033 -287.70946) (xy 93.968234 -287.666446)
			(xy 94.001982 -287.628352) (xy 94.041404 -287.596165) (xy 94.085478 -287.570719) (xy 94.133064 -287.552672)
			(xy 94.182928 -287.542492) (xy 94.23378 -287.540443) (xy 94.284301 -287.546577) (xy 94.333185 -287.560737)
			(xy 94.379164 -287.582554) (xy 94.421048 -287.611464) (xy 94.457752 -287.646719) (xy 94.488325 -287.687405)
			(xy 94.511976 -287.732468) (xy 94.528092 -287.780742) (xy 94.536256 -287.830976) (xy 94.536768 -287.856422)
			(xy 94.855296 -287.856422) (xy 94.859256 -287.807368) (xy 94.871033 -287.759584) (xy 94.890324 -287.714308)
			(xy 94.916627 -287.672712) (xy 94.949262 -287.635875) (xy 94.987383 -287.60475) (xy 95.030004 -287.580143)
			(xy 95.07602 -287.562691) (xy 95.124239 -287.552847) (xy 95.173414 -287.550866) (xy 95.222269 -287.556798)
			(xy 95.26954 -287.57049) (xy 95.314002 -287.591588) (xy 95.354505 -287.619544) (xy 95.389998 -287.653636)
			(xy 95.419563 -287.69298) (xy 95.442434 -287.736557) (xy 95.458018 -287.783238) (xy 95.465913 -287.831815)
			(xy 95.466408 -287.856422) (xy 95.465913 -287.881029) (xy 95.458018 -287.929606) (xy 95.442434 -287.976287)
			(xy 95.419563 -288.019864) (xy 95.389998 -288.059208) (xy 95.354505 -288.0933) (xy 95.314002 -288.121256)
			(xy 95.26954 -288.142354) (xy 95.222269 -288.156046) (xy 95.173414 -288.161978) (xy 95.124239 -288.159997)
			(xy 95.07602 -288.150153) (xy 95.030004 -288.132701) (xy 94.987383 -288.108094) (xy 94.949262 -288.076969)
			(xy 94.916627 -288.040132) (xy 94.890324 -287.998536) (xy 94.871033 -287.95326) (xy 94.859256 -287.905476)
			(xy 94.855296 -287.856422) (xy 94.536768 -287.856422) (xy 94.536256 -287.881868) (xy 94.528092 -287.932102)
			(xy 94.511976 -287.980376) (xy 94.488325 -288.025439) (xy 94.457752 -288.066125) (xy 94.421048 -288.10138)
			(xy 94.379164 -288.13029) (xy 94.333185 -288.152107) (xy 94.284301 -288.166267) (xy 94.23378 -288.172401)
			(xy 94.182928 -288.170352) (xy 94.133064 -288.160172) (xy 94.085478 -288.142125) (xy 94.041404 -288.116679)
			(xy 94.001982 -288.084492) (xy 93.968234 -288.046398) (xy 93.941033 -288.003384) (xy 93.921085 -287.956564)
			(xy 93.908906 -287.90715) (xy 93.904811 -287.856422) (xy 92.65666 -287.856422) (xy 92.656148 -287.881868)
			(xy 92.647984 -287.932102) (xy 92.631868 -287.980376) (xy 92.608217 -288.025439) (xy 92.577644 -288.066125)
			(xy 92.54094 -288.10138) (xy 92.499056 -288.13029) (xy 92.453077 -288.152107) (xy 92.404193 -288.166267)
			(xy 92.353672 -288.172401) (xy 92.30282 -288.170352) (xy 92.252956 -288.160172) (xy 92.20537 -288.142125)
			(xy 92.161296 -288.116679) (xy 92.121874 -288.084492) (xy 92.088126 -288.046398) (xy 92.060925 -288.003384)
			(xy 92.040977 -287.956564) (xy 92.028798 -287.90715) (xy 92.024703 -287.856422) (xy 91.71686 -287.856422)
			(xy 91.716348 -287.881868) (xy 91.708184 -287.932102) (xy 91.692068 -287.980376) (xy 91.668417 -288.025439)
			(xy 91.637844 -288.066125) (xy 91.60114 -288.10138) (xy 91.559256 -288.13029) (xy 91.513277 -288.152107)
			(xy 91.464393 -288.166267) (xy 91.413872 -288.172401) (xy 91.36302 -288.170352) (xy 91.313156 -288.160172)
			(xy 91.26557 -288.142125) (xy 91.221496 -288.116679) (xy 91.182074 -288.084492) (xy 91.148326 -288.046398)
			(xy 91.121125 -288.003384) (xy 91.101177 -287.956564) (xy 91.088998 -287.90715) (xy 91.084903 -287.856422)
			(xy 90.766392 -287.856422) (xy 90.765897 -287.881029) (xy 90.758002 -287.929606) (xy 90.742418 -287.976287)
			(xy 90.719547 -288.019864) (xy 90.689982 -288.059208) (xy 90.654489 -288.0933) (xy 90.613986 -288.121256)
			(xy 90.569524 -288.142354) (xy 90.522253 -288.156046) (xy 90.473398 -288.161978) (xy 90.424223 -288.159997)
			(xy 90.376004 -288.150153) (xy 90.329988 -288.132701) (xy 90.287367 -288.108094) (xy 90.249246 -288.076969)
			(xy 90.216611 -288.040132) (xy 90.190308 -287.998536) (xy 90.171017 -287.95326) (xy 90.15924 -287.905476)
			(xy 90.15528 -287.856422) (xy 89.826338 -287.856422) (xy 89.825843 -287.881029) (xy 89.817948 -287.929606)
			(xy 89.802364 -287.976287) (xy 89.779493 -288.019864) (xy 89.749928 -288.059208) (xy 89.714435 -288.0933)
			(xy 89.673932 -288.121256) (xy 89.62947 -288.142354) (xy 89.582199 -288.156046) (xy 89.533344 -288.161978)
			(xy 89.484169 -288.159997) (xy 89.43595 -288.150153) (xy 89.389934 -288.132701) (xy 89.347313 -288.108094)
			(xy 89.309192 -288.076969) (xy 89.276557 -288.040132) (xy 89.250254 -287.998536) (xy 89.230963 -287.95326)
			(xy 89.219186 -287.905476) (xy 89.215226 -287.856422) (xy 88.886284 -287.856422) (xy 88.885789 -287.881029)
			(xy 88.877894 -287.929606) (xy 88.86231 -287.976287) (xy 88.839439 -288.019864) (xy 88.809874 -288.059208)
			(xy 88.774381 -288.0933) (xy 88.733878 -288.121256) (xy 88.689416 -288.142354) (xy 88.642145 -288.156046)
			(xy 88.59329 -288.161978) (xy 88.544115 -288.159997) (xy 88.495896 -288.150153) (xy 88.44988 -288.132701)
			(xy 88.407259 -288.108094) (xy 88.369138 -288.076969) (xy 88.336503 -288.040132) (xy 88.3102 -287.998536)
			(xy 88.290909 -287.95326) (xy 88.279132 -287.905476) (xy 88.275172 -287.856422) (xy 87.94623 -287.856422)
			(xy 87.945735 -287.881029) (xy 87.93784 -287.929606) (xy 87.922256 -287.976287) (xy 87.899385 -288.019864)
			(xy 87.86982 -288.059208) (xy 87.834327 -288.0933) (xy 87.793824 -288.121256) (xy 87.749362 -288.142354)
			(xy 87.702091 -288.156046) (xy 87.653236 -288.161978) (xy 87.604061 -288.159997) (xy 87.555842 -288.150153)
			(xy 87.509826 -288.132701) (xy 87.467205 -288.108094) (xy 87.429084 -288.076969) (xy 87.396449 -288.040132)
			(xy 87.370146 -287.998536) (xy 87.350855 -287.95326) (xy 87.339078 -287.905476) (xy 87.335118 -287.856422)
			(xy 87.03183 -287.856422) (xy 87.031247 -287.884545) (xy 87.021667 -287.93997) (xy 87.01278 -287.966658)
			(xy 87.009986 -287.97504) (xy 87.009986 -288.264854) (xy 87.010358 -288.273959) (xy 87.016734 -288.291017)
			(xy 87.022432 -288.298128) (xy 87.024972 -288.300922) (xy 87.065104 -288.335466) (xy 87.080344 -288.348674)
			(xy 87.081614 -288.34969) (xy 87.088578 -288.354891) (xy 87.104935 -288.360732) (xy 87.113618 -288.36112)
			(xy 87.159592 -288.36112) (xy 87.171022 -288.360866) (xy 87.171276 -288.360866) (xy 87.195254 -288.361357)
			(xy 87.242614 -288.368897) (xy 87.288212 -288.383749) (xy 87.330929 -288.405547) (xy 87.369712 -288.433754)
			(xy 87.403608 -288.467679) (xy 87.431784 -288.506485) (xy 87.453547 -288.549219) (xy 87.468361 -288.59483)
			(xy 87.475863 -288.642196) (xy 87.47633 -288.666174) (xy 87.805272 -288.666174) (xy 87.809232 -288.61712)
			(xy 87.821009 -288.569336) (xy 87.8403 -288.52406) (xy 87.866603 -288.482464) (xy 87.899238 -288.445627)
			(xy 87.937359 -288.414502) (xy 87.97998 -288.389895) (xy 88.025996 -288.372443) (xy 88.074215 -288.362599)
			(xy 88.12339 -288.360618) (xy 88.172245 -288.36655) (xy 88.219516 -288.380242) (xy 88.263978 -288.40134)
			(xy 88.304481 -288.429296) (xy 88.339974 -288.463388) (xy 88.369539 -288.502732) (xy 88.39241 -288.546309)
			(xy 88.407994 -288.59299) (xy 88.415889 -288.641567) (xy 88.416384 -288.666174) (xy 88.745326 -288.666174)
			(xy 88.749286 -288.61712) (xy 88.761063 -288.569336) (xy 88.780354 -288.52406) (xy 88.806657 -288.482464)
			(xy 88.839292 -288.445627) (xy 88.877413 -288.414502) (xy 88.920034 -288.389895) (xy 88.96605 -288.372443)
			(xy 89.014269 -288.362599) (xy 89.063444 -288.360618) (xy 89.112299 -288.36655) (xy 89.15957 -288.380242)
			(xy 89.204032 -288.40134) (xy 89.244535 -288.429296) (xy 89.280028 -288.463388) (xy 89.309593 -288.502732)
			(xy 89.332464 -288.546309) (xy 89.348048 -288.59299) (xy 89.355943 -288.641567) (xy 89.356438 -288.666174)
			(xy 89.685126 -288.666174) (xy 89.689086 -288.61712) (xy 89.700863 -288.569336) (xy 89.720154 -288.52406)
			(xy 89.746457 -288.482464) (xy 89.779092 -288.445627) (xy 89.817213 -288.414502) (xy 89.859834 -288.389895)
			(xy 89.90585 -288.372443) (xy 89.954069 -288.362599) (xy 90.003244 -288.360618) (xy 90.052099 -288.36655)
			(xy 90.09937 -288.380242) (xy 90.143832 -288.40134) (xy 90.184335 -288.429296) (xy 90.219828 -288.463388)
			(xy 90.249393 -288.502732) (xy 90.272264 -288.546309) (xy 90.287848 -288.59299) (xy 90.295743 -288.641567)
			(xy 90.296238 -288.666174) (xy 90.614749 -288.666174) (xy 90.618844 -288.615446) (xy 90.631023 -288.566032)
			(xy 90.650971 -288.519212) (xy 90.678172 -288.476198) (xy 90.71192 -288.438104) (xy 90.751342 -288.405917)
			(xy 90.795416 -288.380471) (xy 90.843002 -288.362424) (xy 90.892866 -288.352244) (xy 90.943718 -288.350195)
			(xy 90.994239 -288.356329) (xy 91.043123 -288.370489) (xy 91.089102 -288.392306) (xy 91.130986 -288.421216)
			(xy 91.16769 -288.456471) (xy 91.198263 -288.497157) (xy 91.221914 -288.54222) (xy 91.23803 -288.590494)
			(xy 91.246194 -288.640728) (xy 91.246706 -288.666174) (xy 91.565234 -288.666174) (xy 91.569194 -288.61712)
			(xy 91.580971 -288.569336) (xy 91.600262 -288.52406) (xy 91.626565 -288.482464) (xy 91.6592 -288.445627)
			(xy 91.697321 -288.414502) (xy 91.739942 -288.389895) (xy 91.785958 -288.372443) (xy 91.834177 -288.362599)
			(xy 91.883352 -288.360618) (xy 91.932207 -288.36655) (xy 91.979478 -288.380242) (xy 92.02394 -288.40134)
			(xy 92.064443 -288.429296) (xy 92.099936 -288.463388) (xy 92.129501 -288.502732) (xy 92.152372 -288.546309)
			(xy 92.167956 -288.59299) (xy 92.175851 -288.641567) (xy 92.176346 -288.666174) (xy 92.494857 -288.666174)
			(xy 92.498952 -288.615446) (xy 92.511131 -288.566032) (xy 92.531079 -288.519212) (xy 92.55828 -288.476198)
			(xy 92.592028 -288.438104) (xy 92.63145 -288.405917) (xy 92.675524 -288.380471) (xy 92.72311 -288.362424)
			(xy 92.772974 -288.352244) (xy 92.823826 -288.350195) (xy 92.874347 -288.356329) (xy 92.923231 -288.370489)
			(xy 92.96921 -288.392306) (xy 93.011094 -288.421216) (xy 93.047798 -288.456471) (xy 93.078371 -288.497157)
			(xy 93.102022 -288.54222) (xy 93.118138 -288.590494) (xy 93.126302 -288.640728) (xy 93.126814 -288.666174)
			(xy 93.445342 -288.666174) (xy 93.449302 -288.61712) (xy 93.461079 -288.569336) (xy 93.48037 -288.52406)
			(xy 93.506673 -288.482464) (xy 93.539308 -288.445627) (xy 93.577429 -288.414502) (xy 93.62005 -288.389895)
			(xy 93.666066 -288.372443) (xy 93.714285 -288.362599) (xy 93.76346 -288.360618) (xy 93.812315 -288.36655)
			(xy 93.859586 -288.380242) (xy 93.904048 -288.40134) (xy 93.944551 -288.429296) (xy 93.980044 -288.463388)
			(xy 94.009609 -288.502732) (xy 94.03248 -288.546309) (xy 94.048064 -288.59299) (xy 94.055959 -288.641567)
			(xy 94.056454 -288.666174) (xy 94.374711 -288.666174) (xy 94.378806 -288.615446) (xy 94.390985 -288.566032)
			(xy 94.410933 -288.519212) (xy 94.438134 -288.476198) (xy 94.471882 -288.438104) (xy 94.511304 -288.405917)
			(xy 94.555378 -288.380471) (xy 94.602964 -288.362424) (xy 94.652828 -288.352244) (xy 94.70368 -288.350195)
			(xy 94.754201 -288.356329) (xy 94.803085 -288.370489) (xy 94.849064 -288.392306) (xy 94.890948 -288.421216)
			(xy 94.927652 -288.456471) (xy 94.958225 -288.497157) (xy 94.981876 -288.54222) (xy 94.997992 -288.590494)
			(xy 95.006156 -288.640728) (xy 95.006668 -288.666174) (xy 95.314765 -288.666174) (xy 95.31886 -288.615446)
			(xy 95.331039 -288.566032) (xy 95.350987 -288.519212) (xy 95.378188 -288.476198) (xy 95.411936 -288.438104)
			(xy 95.451358 -288.405917) (xy 95.495432 -288.380471) (xy 95.543018 -288.362424) (xy 95.592882 -288.352244)
			(xy 95.643734 -288.350195) (xy 95.694255 -288.356329) (xy 95.743139 -288.370489) (xy 95.789118 -288.392306)
			(xy 95.831002 -288.421216) (xy 95.867706 -288.456471) (xy 95.898279 -288.497157) (xy 95.92193 -288.54222)
			(xy 95.938046 -288.590494) (xy 95.94621 -288.640728) (xy 95.946722 -288.666174) (xy 95.94621 -288.69162)
			(xy 95.938046 -288.741854) (xy 95.92193 -288.790128) (xy 95.898279 -288.835191) (xy 95.867706 -288.875877)
			(xy 95.831002 -288.911132) (xy 95.789118 -288.940042) (xy 95.743139 -288.961859) (xy 95.694255 -288.976019)
			(xy 95.643734 -288.982153) (xy 95.592882 -288.980104) (xy 95.543018 -288.969924) (xy 95.495432 -288.951877)
			(xy 95.451358 -288.926431) (xy 95.411936 -288.894244) (xy 95.378188 -288.85615) (xy 95.350987 -288.813136)
			(xy 95.331039 -288.766316) (xy 95.31886 -288.716902) (xy 95.314765 -288.666174) (xy 95.006668 -288.666174)
			(xy 95.006156 -288.69162) (xy 94.997992 -288.741854) (xy 94.981876 -288.790128) (xy 94.958225 -288.835191)
			(xy 94.927652 -288.875877) (xy 94.890948 -288.911132) (xy 94.849064 -288.940042) (xy 94.803085 -288.961859)
			(xy 94.754201 -288.976019) (xy 94.70368 -288.982153) (xy 94.652828 -288.980104) (xy 94.602964 -288.969924)
			(xy 94.555378 -288.951877) (xy 94.511304 -288.926431) (xy 94.471882 -288.894244) (xy 94.438134 -288.85615)
			(xy 94.410933 -288.813136) (xy 94.390985 -288.766316) (xy 94.378806 -288.716902) (xy 94.374711 -288.666174)
			(xy 94.056454 -288.666174) (xy 94.055959 -288.690781) (xy 94.048064 -288.739358) (xy 94.03248 -288.786039)
			(xy 94.009609 -288.829616) (xy 93.980044 -288.86896) (xy 93.944551 -288.903052) (xy 93.904048 -288.931008)
			(xy 93.859586 -288.952106) (xy 93.812315 -288.965798) (xy 93.76346 -288.97173) (xy 93.714285 -288.969749)
			(xy 93.666066 -288.959905) (xy 93.62005 -288.942453) (xy 93.577429 -288.917846) (xy 93.539308 -288.886721)
			(xy 93.506673 -288.849884) (xy 93.48037 -288.808288) (xy 93.461079 -288.763012) (xy 93.449302 -288.715228)
			(xy 93.445342 -288.666174) (xy 93.126814 -288.666174) (xy 93.126302 -288.69162) (xy 93.118138 -288.741854)
			(xy 93.102022 -288.790128) (xy 93.078371 -288.835191) (xy 93.047798 -288.875877) (xy 93.011094 -288.911132)
			(xy 92.96921 -288.940042) (xy 92.923231 -288.961859) (xy 92.874347 -288.976019) (xy 92.823826 -288.982153)
			(xy 92.772974 -288.980104) (xy 92.72311 -288.969924) (xy 92.675524 -288.951877) (xy 92.63145 -288.926431)
			(xy 92.592028 -288.894244) (xy 92.55828 -288.85615) (xy 92.531079 -288.813136) (xy 92.511131 -288.766316)
			(xy 92.498952 -288.716902) (xy 92.494857 -288.666174) (xy 92.176346 -288.666174) (xy 92.175851 -288.690781)
			(xy 92.167956 -288.739358) (xy 92.152372 -288.786039) (xy 92.129501 -288.829616) (xy 92.099936 -288.86896)
			(xy 92.064443 -288.903052) (xy 92.02394 -288.931008) (xy 91.979478 -288.952106) (xy 91.932207 -288.965798)
			(xy 91.883352 -288.97173) (xy 91.834177 -288.969749) (xy 91.785958 -288.959905) (xy 91.739942 -288.942453)
			(xy 91.697321 -288.917846) (xy 91.6592 -288.886721) (xy 91.626565 -288.849884) (xy 91.600262 -288.808288)
			(xy 91.580971 -288.763012) (xy 91.569194 -288.715228) (xy 91.565234 -288.666174) (xy 91.246706 -288.666174)
			(xy 91.246194 -288.69162) (xy 91.23803 -288.741854) (xy 91.221914 -288.790128) (xy 91.198263 -288.835191)
			(xy 91.16769 -288.875877) (xy 91.130986 -288.911132) (xy 91.089102 -288.940042) (xy 91.043123 -288.961859)
			(xy 90.994239 -288.976019) (xy 90.943718 -288.982153) (xy 90.892866 -288.980104) (xy 90.843002 -288.969924)
			(xy 90.795416 -288.951877) (xy 90.751342 -288.926431) (xy 90.71192 -288.894244) (xy 90.678172 -288.85615)
			(xy 90.650971 -288.813136) (xy 90.631023 -288.766316) (xy 90.618844 -288.716902) (xy 90.614749 -288.666174)
			(xy 90.296238 -288.666174) (xy 90.295743 -288.690781) (xy 90.287848 -288.739358) (xy 90.272264 -288.786039)
			(xy 90.249393 -288.829616) (xy 90.219828 -288.86896) (xy 90.184335 -288.903052) (xy 90.143832 -288.931008)
			(xy 90.09937 -288.952106) (xy 90.052099 -288.965798) (xy 90.003244 -288.97173) (xy 89.954069 -288.969749)
			(xy 89.90585 -288.959905) (xy 89.859834 -288.942453) (xy 89.817213 -288.917846) (xy 89.779092 -288.886721)
			(xy 89.746457 -288.849884) (xy 89.720154 -288.808288) (xy 89.700863 -288.763012) (xy 89.689086 -288.715228)
			(xy 89.685126 -288.666174) (xy 89.356438 -288.666174) (xy 89.355943 -288.690781) (xy 89.348048 -288.739358)
			(xy 89.332464 -288.786039) (xy 89.309593 -288.829616) (xy 89.280028 -288.86896) (xy 89.244535 -288.903052)
			(xy 89.204032 -288.931008) (xy 89.15957 -288.952106) (xy 89.112299 -288.965798) (xy 89.063444 -288.97173)
			(xy 89.014269 -288.969749) (xy 88.96605 -288.959905) (xy 88.920034 -288.942453) (xy 88.877413 -288.917846)
			(xy 88.839292 -288.886721) (xy 88.806657 -288.849884) (xy 88.780354 -288.808288) (xy 88.761063 -288.763012)
			(xy 88.749286 -288.715228) (xy 88.745326 -288.666174) (xy 88.416384 -288.666174) (xy 88.415889 -288.690781)
			(xy 88.407994 -288.739358) (xy 88.39241 -288.786039) (xy 88.369539 -288.829616) (xy 88.339974 -288.86896)
			(xy 88.304481 -288.903052) (xy 88.263978 -288.931008) (xy 88.219516 -288.952106) (xy 88.172245 -288.965798)
			(xy 88.12339 -288.97173) (xy 88.074215 -288.969749) (xy 88.025996 -288.959905) (xy 87.97998 -288.942453)
			(xy 87.937359 -288.917846) (xy 87.899238 -288.886721) (xy 87.866603 -288.849884) (xy 87.8403 -288.808288)
			(xy 87.821009 -288.763012) (xy 87.809232 -288.715228) (xy 87.805272 -288.666174) (xy 87.47633 -288.666174)
			(xy 87.475886 -288.690169) (xy 87.468382 -288.737569) (xy 87.453556 -288.783212) (xy 87.431773 -288.825973)
			(xy 87.403568 -288.8648) (xy 87.369637 -288.898737) (xy 87.330814 -288.926948) (xy 87.288056 -288.948738)
			(xy 87.242416 -288.963571) (xy 87.195017 -288.971082) (xy 87.171022 -288.971482) (xy 87.159613 -288.971407)
			(xy 87.136856 -288.969753) (xy 87.125556 -288.96818) (xy 87.114634 -288.966402) (xy 87.09279 -288.972752)
			(xy 87.065358 -288.996628) (xy 87.06485 -288.997136) (xy 87.030814 -289.026346) (xy 87.02929 -289.027616)
			(xy 87.024972 -289.031934) (xy 87.017606 -289.039046) (xy 87.009986 -289.057842) (xy 87.009986 -289.47618)
			(xy 87.335118 -289.47618) (xy 87.339078 -289.427126) (xy 87.350855 -289.379342) (xy 87.370146 -289.334066)
			(xy 87.396449 -289.29247) (xy 87.429084 -289.255633) (xy 87.467205 -289.224508) (xy 87.509826 -289.199901)
			(xy 87.555842 -289.182449) (xy 87.604061 -289.172605) (xy 87.653236 -289.170624) (xy 87.702091 -289.176556)
			(xy 87.749362 -289.190248) (xy 87.793824 -289.211346) (xy 87.834327 -289.239302) (xy 87.86982 -289.273394)
			(xy 87.899385 -289.312738) (xy 87.922256 -289.356315) (xy 87.93784 -289.402996) (xy 87.945735 -289.451573)
			(xy 87.94623 -289.47618) (xy 88.275172 -289.47618) (xy 88.279132 -289.427126) (xy 88.290909 -289.379342)
			(xy 88.3102 -289.334066) (xy 88.336503 -289.29247) (xy 88.369138 -289.255633) (xy 88.407259 -289.224508)
			(xy 88.44988 -289.199901) (xy 88.495896 -289.182449) (xy 88.544115 -289.172605) (xy 88.59329 -289.170624)
			(xy 88.642145 -289.176556) (xy 88.689416 -289.190248) (xy 88.733878 -289.211346) (xy 88.774381 -289.239302)
			(xy 88.809874 -289.273394) (xy 88.839439 -289.312738) (xy 88.86231 -289.356315) (xy 88.877894 -289.402996)
			(xy 88.885789 -289.451573) (xy 88.886284 -289.47618) (xy 89.215226 -289.47618) (xy 89.219186 -289.427126)
			(xy 89.230963 -289.379342) (xy 89.250254 -289.334066) (xy 89.276557 -289.29247) (xy 89.309192 -289.255633)
			(xy 89.347313 -289.224508) (xy 89.389934 -289.199901) (xy 89.43595 -289.182449) (xy 89.484169 -289.172605)
			(xy 89.533344 -289.170624) (xy 89.582199 -289.176556) (xy 89.62947 -289.190248) (xy 89.673932 -289.211346)
			(xy 89.714435 -289.239302) (xy 89.749928 -289.273394) (xy 89.779493 -289.312738) (xy 89.802364 -289.356315)
			(xy 89.817948 -289.402996) (xy 89.825843 -289.451573) (xy 89.826338 -289.47618) (xy 90.15528 -289.47618)
			(xy 90.15924 -289.427126) (xy 90.171017 -289.379342) (xy 90.190308 -289.334066) (xy 90.216611 -289.29247)
			(xy 90.249246 -289.255633) (xy 90.287367 -289.224508) (xy 90.329988 -289.199901) (xy 90.376004 -289.182449)
			(xy 90.424223 -289.172605) (xy 90.473398 -289.170624) (xy 90.522253 -289.176556) (xy 90.569524 -289.190248)
			(xy 90.613986 -289.211346) (xy 90.654489 -289.239302) (xy 90.689982 -289.273394) (xy 90.719547 -289.312738)
			(xy 90.742418 -289.356315) (xy 90.758002 -289.402996) (xy 90.765897 -289.451573) (xy 90.766392 -289.47618)
			(xy 91.084903 -289.47618) (xy 91.088998 -289.425452) (xy 91.101177 -289.376038) (xy 91.121125 -289.329218)
			(xy 91.148326 -289.286204) (xy 91.182074 -289.24811) (xy 91.221496 -289.215923) (xy 91.26557 -289.190477)
			(xy 91.313156 -289.17243) (xy 91.36302 -289.16225) (xy 91.413872 -289.160201) (xy 91.464393 -289.166335)
			(xy 91.513277 -289.180495) (xy 91.559256 -289.202312) (xy 91.60114 -289.231222) (xy 91.637844 -289.266477)
			(xy 91.668417 -289.307163) (xy 91.692068 -289.352226) (xy 91.708184 -289.4005) (xy 91.716348 -289.450734)
			(xy 91.71686 -289.47618) (xy 92.024703 -289.47618) (xy 92.028798 -289.425452) (xy 92.040977 -289.376038)
			(xy 92.060925 -289.329218) (xy 92.088126 -289.286204) (xy 92.121874 -289.24811) (xy 92.161296 -289.215923)
			(xy 92.20537 -289.190477) (xy 92.252956 -289.17243) (xy 92.30282 -289.16225) (xy 92.353672 -289.160201)
			(xy 92.404193 -289.166335) (xy 92.453077 -289.180495) (xy 92.499056 -289.202312) (xy 92.54094 -289.231222)
			(xy 92.577644 -289.266477) (xy 92.608217 -289.307163) (xy 92.631868 -289.352226) (xy 92.647984 -289.4005)
			(xy 92.656148 -289.450734) (xy 92.65666 -289.47618) (xy 92.975188 -289.47618) (xy 92.979148 -289.427126)
			(xy 92.990925 -289.379342) (xy 93.010216 -289.334066) (xy 93.036519 -289.29247) (xy 93.069154 -289.255633)
			(xy 93.107275 -289.224508) (xy 93.149896 -289.199901) (xy 93.195912 -289.182449) (xy 93.244131 -289.172605)
			(xy 93.293306 -289.170624) (xy 93.342161 -289.176556) (xy 93.389432 -289.190248) (xy 93.433894 -289.211346)
			(xy 93.474397 -289.239302) (xy 93.50989 -289.273394) (xy 93.539455 -289.312738) (xy 93.562326 -289.356315)
			(xy 93.57791 -289.402996) (xy 93.585805 -289.451573) (xy 93.5863 -289.47618) (xy 93.904811 -289.47618)
			(xy 93.908906 -289.425452) (xy 93.921085 -289.376038) (xy 93.941033 -289.329218) (xy 93.968234 -289.286204)
			(xy 94.001982 -289.24811) (xy 94.041404 -289.215923) (xy 94.085478 -289.190477) (xy 94.133064 -289.17243)
			(xy 94.182928 -289.16225) (xy 94.23378 -289.160201) (xy 94.284301 -289.166335) (xy 94.333185 -289.180495)
			(xy 94.379164 -289.202312) (xy 94.421048 -289.231222) (xy 94.457752 -289.266477) (xy 94.488325 -289.307163)
			(xy 94.511976 -289.352226) (xy 94.528092 -289.4005) (xy 94.536256 -289.450734) (xy 94.536768 -289.47618)
			(xy 94.855296 -289.47618) (xy 94.859256 -289.427126) (xy 94.871033 -289.379342) (xy 94.890324 -289.334066)
			(xy 94.916627 -289.29247) (xy 94.949262 -289.255633) (xy 94.987383 -289.224508) (xy 95.030004 -289.199901)
			(xy 95.07602 -289.182449) (xy 95.124239 -289.172605) (xy 95.173414 -289.170624) (xy 95.222269 -289.176556)
			(xy 95.26954 -289.190248) (xy 95.314002 -289.211346) (xy 95.354505 -289.239302) (xy 95.389998 -289.273394)
			(xy 95.419563 -289.312738) (xy 95.442434 -289.356315) (xy 95.458018 -289.402996) (xy 95.465913 -289.451573)
			(xy 95.466408 -289.47618) (xy 95.465913 -289.500787) (xy 95.458018 -289.549364) (xy 95.442434 -289.596045)
			(xy 95.419563 -289.639622) (xy 95.389998 -289.678966) (xy 95.354505 -289.713058) (xy 95.314002 -289.741014)
			(xy 95.26954 -289.762112) (xy 95.222269 -289.775804) (xy 95.173414 -289.781736) (xy 95.124239 -289.779755)
			(xy 95.07602 -289.769911) (xy 95.030004 -289.752459) (xy 94.987383 -289.727852) (xy 94.949262 -289.696727)
			(xy 94.916627 -289.65989) (xy 94.890324 -289.618294) (xy 94.871033 -289.573018) (xy 94.859256 -289.525234)
			(xy 94.855296 -289.47618) (xy 94.536768 -289.47618) (xy 94.536256 -289.501626) (xy 94.528092 -289.55186)
			(xy 94.511976 -289.600134) (xy 94.488325 -289.645197) (xy 94.457752 -289.685883) (xy 94.421048 -289.721138)
			(xy 94.379164 -289.750048) (xy 94.333185 -289.771865) (xy 94.284301 -289.786025) (xy 94.23378 -289.792159)
			(xy 94.182928 -289.79011) (xy 94.133064 -289.77993) (xy 94.085478 -289.761883) (xy 94.041404 -289.736437)
			(xy 94.001982 -289.70425) (xy 93.968234 -289.666156) (xy 93.941033 -289.623142) (xy 93.921085 -289.576322)
			(xy 93.908906 -289.526908) (xy 93.904811 -289.47618) (xy 93.5863 -289.47618) (xy 93.585805 -289.500787)
			(xy 93.57791 -289.549364) (xy 93.562326 -289.596045) (xy 93.539455 -289.639622) (xy 93.50989 -289.678966)
			(xy 93.474397 -289.713058) (xy 93.433894 -289.741014) (xy 93.389432 -289.762112) (xy 93.342161 -289.775804)
			(xy 93.293306 -289.781736) (xy 93.244131 -289.779755) (xy 93.195912 -289.769911) (xy 93.149896 -289.752459)
			(xy 93.107275 -289.727852) (xy 93.069154 -289.696727) (xy 93.036519 -289.65989) (xy 93.010216 -289.618294)
			(xy 92.990925 -289.573018) (xy 92.979148 -289.525234) (xy 92.975188 -289.47618) (xy 92.65666 -289.47618)
			(xy 92.656148 -289.501626) (xy 92.647984 -289.55186) (xy 92.631868 -289.600134) (xy 92.608217 -289.645197)
			(xy 92.577644 -289.685883) (xy 92.54094 -289.721138) (xy 92.499056 -289.750048) (xy 92.453077 -289.771865)
			(xy 92.404193 -289.786025) (xy 92.353672 -289.792159) (xy 92.30282 -289.79011) (xy 92.252956 -289.77993)
			(xy 92.20537 -289.761883) (xy 92.161296 -289.736437) (xy 92.121874 -289.70425) (xy 92.088126 -289.666156)
			(xy 92.060925 -289.623142) (xy 92.040977 -289.576322) (xy 92.028798 -289.526908) (xy 92.024703 -289.47618)
			(xy 91.71686 -289.47618) (xy 91.716348 -289.501626) (xy 91.708184 -289.55186) (xy 91.692068 -289.600134)
			(xy 91.668417 -289.645197) (xy 91.637844 -289.685883) (xy 91.60114 -289.721138) (xy 91.559256 -289.750048)
			(xy 91.513277 -289.771865) (xy 91.464393 -289.786025) (xy 91.413872 -289.792159) (xy 91.36302 -289.79011)
			(xy 91.313156 -289.77993) (xy 91.26557 -289.761883) (xy 91.221496 -289.736437) (xy 91.182074 -289.70425)
			(xy 91.148326 -289.666156) (xy 91.121125 -289.623142) (xy 91.101177 -289.576322) (xy 91.088998 -289.526908)
			(xy 91.084903 -289.47618) (xy 90.766392 -289.47618) (xy 90.765897 -289.500787) (xy 90.758002 -289.549364)
			(xy 90.742418 -289.596045) (xy 90.719547 -289.639622) (xy 90.689982 -289.678966) (xy 90.654489 -289.713058)
			(xy 90.613986 -289.741014) (xy 90.569524 -289.762112) (xy 90.522253 -289.775804) (xy 90.473398 -289.781736)
			(xy 90.424223 -289.779755) (xy 90.376004 -289.769911) (xy 90.329988 -289.752459) (xy 90.287367 -289.727852)
			(xy 90.249246 -289.696727) (xy 90.216611 -289.65989) (xy 90.190308 -289.618294) (xy 90.171017 -289.573018)
			(xy 90.15924 -289.525234) (xy 90.15528 -289.47618) (xy 89.826338 -289.47618) (xy 89.825843 -289.500787)
			(xy 89.817948 -289.549364) (xy 89.802364 -289.596045) (xy 89.779493 -289.639622) (xy 89.749928 -289.678966)
			(xy 89.714435 -289.713058) (xy 89.673932 -289.741014) (xy 89.62947 -289.762112) (xy 89.582199 -289.775804)
			(xy 89.533344 -289.781736) (xy 89.484169 -289.779755) (xy 89.43595 -289.769911) (xy 89.389934 -289.752459)
			(xy 89.347313 -289.727852) (xy 89.309192 -289.696727) (xy 89.276557 -289.65989) (xy 89.250254 -289.618294)
			(xy 89.230963 -289.573018) (xy 89.219186 -289.525234) (xy 89.215226 -289.47618) (xy 88.886284 -289.47618)
			(xy 88.885789 -289.500787) (xy 88.877894 -289.549364) (xy 88.86231 -289.596045) (xy 88.839439 -289.639622)
			(xy 88.809874 -289.678966) (xy 88.774381 -289.713058) (xy 88.733878 -289.741014) (xy 88.689416 -289.762112)
			(xy 88.642145 -289.775804) (xy 88.59329 -289.781736) (xy 88.544115 -289.779755) (xy 88.495896 -289.769911)
			(xy 88.44988 -289.752459) (xy 88.407259 -289.727852) (xy 88.369138 -289.696727) (xy 88.336503 -289.65989)
			(xy 88.3102 -289.618294) (xy 88.290909 -289.573018) (xy 88.279132 -289.525234) (xy 88.275172 -289.47618)
			(xy 87.94623 -289.47618) (xy 87.945735 -289.500787) (xy 87.93784 -289.549364) (xy 87.922256 -289.596045)
			(xy 87.899385 -289.639622) (xy 87.86982 -289.678966) (xy 87.834327 -289.713058) (xy 87.793824 -289.741014)
			(xy 87.749362 -289.762112) (xy 87.702091 -289.775804) (xy 87.653236 -289.781736) (xy 87.604061 -289.779755)
			(xy 87.555842 -289.769911) (xy 87.509826 -289.752459) (xy 87.467205 -289.727852) (xy 87.429084 -289.696727)
			(xy 87.396449 -289.65989) (xy 87.370146 -289.618294) (xy 87.350855 -289.573018) (xy 87.339078 -289.525234)
			(xy 87.335118 -289.47618) (xy 87.009986 -289.47618) (xy 87.009986 -290.286186) (xy 87.805272 -290.286186)
			(xy 87.809232 -290.237132) (xy 87.821009 -290.189348) (xy 87.8403 -290.144072) (xy 87.866603 -290.102476)
			(xy 87.899238 -290.065639) (xy 87.937359 -290.034514) (xy 87.97998 -290.009907) (xy 88.025996 -289.992455)
			(xy 88.074215 -289.982611) (xy 88.12339 -289.98063) (xy 88.172245 -289.986562) (xy 88.219516 -290.000254)
			(xy 88.263978 -290.021352) (xy 88.304481 -290.049308) (xy 88.339974 -290.0834) (xy 88.369539 -290.122744)
			(xy 88.39241 -290.166321) (xy 88.407994 -290.213002) (xy 88.415889 -290.261579) (xy 88.416384 -290.286186)
			(xy 88.745326 -290.286186) (xy 88.749286 -290.237132) (xy 88.761063 -290.189348) (xy 88.780354 -290.144072)
			(xy 88.806657 -290.102476) (xy 88.839292 -290.065639) (xy 88.877413 -290.034514) (xy 88.920034 -290.009907)
			(xy 88.96605 -289.992455) (xy 89.014269 -289.982611) (xy 89.063444 -289.98063) (xy 89.112299 -289.986562)
			(xy 89.15957 -290.000254) (xy 89.204032 -290.021352) (xy 89.244535 -290.049308) (xy 89.280028 -290.0834)
			(xy 89.309593 -290.122744) (xy 89.332464 -290.166321) (xy 89.348048 -290.213002) (xy 89.355943 -290.261579)
			(xy 89.356438 -290.286186) (xy 89.685126 -290.286186) (xy 89.689086 -290.237132) (xy 89.700863 -290.189348)
			(xy 89.720154 -290.144072) (xy 89.746457 -290.102476) (xy 89.779092 -290.065639) (xy 89.817213 -290.034514)
			(xy 89.859834 -290.009907) (xy 89.90585 -289.992455) (xy 89.954069 -289.982611) (xy 90.003244 -289.98063)
			(xy 90.052099 -289.986562) (xy 90.09937 -290.000254) (xy 90.143832 -290.021352) (xy 90.184335 -290.049308)
			(xy 90.219828 -290.0834) (xy 90.249393 -290.122744) (xy 90.272264 -290.166321) (xy 90.287848 -290.213002)
			(xy 90.295743 -290.261579) (xy 90.296238 -290.286186) (xy 90.614749 -290.286186) (xy 90.618844 -290.235458)
			(xy 90.631023 -290.186044) (xy 90.650971 -290.139224) (xy 90.678172 -290.09621) (xy 90.71192 -290.058116)
			(xy 90.751342 -290.025929) (xy 90.795416 -290.000483) (xy 90.843002 -289.982436) (xy 90.892866 -289.972256)
			(xy 90.943718 -289.970207) (xy 90.994239 -289.976341) (xy 91.043123 -289.990501) (xy 91.089102 -290.012318)
			(xy 91.130986 -290.041228) (xy 91.16769 -290.076483) (xy 91.198263 -290.117169) (xy 91.221914 -290.162232)
			(xy 91.23803 -290.210506) (xy 91.246194 -290.26074) (xy 91.246706 -290.286186) (xy 91.565234 -290.286186)
			(xy 91.569194 -290.237132) (xy 91.580971 -290.189348) (xy 91.600262 -290.144072) (xy 91.626565 -290.102476)
			(xy 91.6592 -290.065639) (xy 91.697321 -290.034514) (xy 91.739942 -290.009907) (xy 91.785958 -289.992455)
			(xy 91.834177 -289.982611) (xy 91.883352 -289.98063) (xy 91.932207 -289.986562) (xy 91.979478 -290.000254)
			(xy 92.02394 -290.021352) (xy 92.064443 -290.049308) (xy 92.099936 -290.0834) (xy 92.129501 -290.122744)
			(xy 92.152372 -290.166321) (xy 92.167956 -290.213002) (xy 92.175851 -290.261579) (xy 92.176346 -290.286186)
			(xy 92.494857 -290.286186) (xy 92.498952 -290.235458) (xy 92.511131 -290.186044) (xy 92.531079 -290.139224)
			(xy 92.55828 -290.09621) (xy 92.592028 -290.058116) (xy 92.63145 -290.025929) (xy 92.675524 -290.000483)
			(xy 92.72311 -289.982436) (xy 92.772974 -289.972256) (xy 92.823826 -289.970207) (xy 92.874347 -289.976341)
			(xy 92.923231 -289.990501) (xy 92.96921 -290.012318) (xy 93.011094 -290.041228) (xy 93.047798 -290.076483)
			(xy 93.078371 -290.117169) (xy 93.102022 -290.162232) (xy 93.118138 -290.210506) (xy 93.126302 -290.26074)
			(xy 93.126814 -290.286186) (xy 94.374711 -290.286186) (xy 94.378806 -290.235458) (xy 94.390985 -290.186044)
			(xy 94.410933 -290.139224) (xy 94.438134 -290.09621) (xy 94.471882 -290.058116) (xy 94.511304 -290.025929)
			(xy 94.555378 -290.000483) (xy 94.602964 -289.982436) (xy 94.652828 -289.972256) (xy 94.70368 -289.970207)
			(xy 94.754201 -289.976341) (xy 94.803085 -289.990501) (xy 94.849064 -290.012318) (xy 94.890948 -290.041228)
			(xy 94.927652 -290.076483) (xy 94.958225 -290.117169) (xy 94.981876 -290.162232) (xy 94.997992 -290.210506)
			(xy 95.006156 -290.26074) (xy 95.006668 -290.286186) (xy 95.314765 -290.286186) (xy 95.31886 -290.235458)
			(xy 95.331039 -290.186044) (xy 95.350987 -290.139224) (xy 95.378188 -290.09621) (xy 95.411936 -290.058116)
			(xy 95.451358 -290.025929) (xy 95.495432 -290.000483) (xy 95.543018 -289.982436) (xy 95.592882 -289.972256)
			(xy 95.643734 -289.970207) (xy 95.694255 -289.976341) (xy 95.743139 -289.990501) (xy 95.789118 -290.012318)
			(xy 95.831002 -290.041228) (xy 95.867706 -290.076483) (xy 95.898279 -290.117169) (xy 95.92193 -290.162232)
			(xy 95.938046 -290.210506) (xy 95.94621 -290.26074) (xy 95.946722 -290.286186) (xy 95.94621 -290.311632)
			(xy 95.938046 -290.361866) (xy 95.92193 -290.41014) (xy 95.898279 -290.455203) (xy 95.867706 -290.495889)
			(xy 95.831002 -290.531144) (xy 95.789118 -290.560054) (xy 95.743139 -290.581871) (xy 95.694255 -290.596031)
			(xy 95.643734 -290.602165) (xy 95.592882 -290.600116) (xy 95.543018 -290.589936) (xy 95.495432 -290.571889)
			(xy 95.451358 -290.546443) (xy 95.411936 -290.514256) (xy 95.378188 -290.476162) (xy 95.350987 -290.433148)
			(xy 95.331039 -290.386328) (xy 95.31886 -290.336914) (xy 95.314765 -290.286186) (xy 95.006668 -290.286186)
			(xy 95.006156 -290.311632) (xy 94.997992 -290.361866) (xy 94.981876 -290.41014) (xy 94.958225 -290.455203)
			(xy 94.927652 -290.495889) (xy 94.890948 -290.531144) (xy 94.849064 -290.560054) (xy 94.803085 -290.581871)
			(xy 94.754201 -290.596031) (xy 94.70368 -290.602165) (xy 94.652828 -290.600116) (xy 94.602964 -290.589936)
			(xy 94.555378 -290.571889) (xy 94.511304 -290.546443) (xy 94.471882 -290.514256) (xy 94.438134 -290.476162)
			(xy 94.410933 -290.433148) (xy 94.390985 -290.386328) (xy 94.378806 -290.336914) (xy 94.374711 -290.286186)
			(xy 93.126814 -290.286186) (xy 93.126302 -290.311632) (xy 93.118138 -290.361866) (xy 93.102022 -290.41014)
			(xy 93.078371 -290.455203) (xy 93.047798 -290.495889) (xy 93.011094 -290.531144) (xy 92.96921 -290.560054)
			(xy 92.923231 -290.581871) (xy 92.874347 -290.596031) (xy 92.823826 -290.602165) (xy 92.772974 -290.600116)
			(xy 92.72311 -290.589936) (xy 92.675524 -290.571889) (xy 92.63145 -290.546443) (xy 92.592028 -290.514256)
			(xy 92.55828 -290.476162) (xy 92.531079 -290.433148) (xy 92.511131 -290.386328) (xy 92.498952 -290.336914)
			(xy 92.494857 -290.286186) (xy 92.176346 -290.286186) (xy 92.175851 -290.310793) (xy 92.167956 -290.35937)
			(xy 92.152372 -290.406051) (xy 92.129501 -290.449628) (xy 92.099936 -290.488972) (xy 92.064443 -290.523064)
			(xy 92.02394 -290.55102) (xy 91.979478 -290.572118) (xy 91.932207 -290.58581) (xy 91.883352 -290.591742)
			(xy 91.834177 -290.589761) (xy 91.785958 -290.579917) (xy 91.739942 -290.562465) (xy 91.697321 -290.537858)
			(xy 91.6592 -290.506733) (xy 91.626565 -290.469896) (xy 91.600262 -290.4283) (xy 91.580971 -290.383024)
			(xy 91.569194 -290.33524) (xy 91.565234 -290.286186) (xy 91.246706 -290.286186) (xy 91.246194 -290.311632)
			(xy 91.23803 -290.361866) (xy 91.221914 -290.41014) (xy 91.198263 -290.455203) (xy 91.16769 -290.495889)
			(xy 91.130986 -290.531144) (xy 91.089102 -290.560054) (xy 91.043123 -290.581871) (xy 90.994239 -290.596031)
			(xy 90.943718 -290.602165) (xy 90.892866 -290.600116) (xy 90.843002 -290.589936) (xy 90.795416 -290.571889)
			(xy 90.751342 -290.546443) (xy 90.71192 -290.514256) (xy 90.678172 -290.476162) (xy 90.650971 -290.433148)
			(xy 90.631023 -290.386328) (xy 90.618844 -290.336914) (xy 90.614749 -290.286186) (xy 90.296238 -290.286186)
			(xy 90.295743 -290.310793) (xy 90.287848 -290.35937) (xy 90.272264 -290.406051) (xy 90.249393 -290.449628)
			(xy 90.219828 -290.488972) (xy 90.184335 -290.523064) (xy 90.143832 -290.55102) (xy 90.09937 -290.572118)
			(xy 90.052099 -290.58581) (xy 90.003244 -290.591742) (xy 89.954069 -290.589761) (xy 89.90585 -290.579917)
			(xy 89.859834 -290.562465) (xy 89.817213 -290.537858) (xy 89.779092 -290.506733) (xy 89.746457 -290.469896)
			(xy 89.720154 -290.4283) (xy 89.700863 -290.383024) (xy 89.689086 -290.33524) (xy 89.685126 -290.286186)
			(xy 89.356438 -290.286186) (xy 89.355943 -290.310793) (xy 89.348048 -290.35937) (xy 89.332464 -290.406051)
			(xy 89.309593 -290.449628) (xy 89.280028 -290.488972) (xy 89.244535 -290.523064) (xy 89.204032 -290.55102)
			(xy 89.15957 -290.572118) (xy 89.112299 -290.58581) (xy 89.063444 -290.591742) (xy 89.014269 -290.589761)
			(xy 88.96605 -290.579917) (xy 88.920034 -290.562465) (xy 88.877413 -290.537858) (xy 88.839292 -290.506733)
			(xy 88.806657 -290.469896) (xy 88.780354 -290.4283) (xy 88.761063 -290.383024) (xy 88.749286 -290.33524)
			(xy 88.745326 -290.286186) (xy 88.416384 -290.286186) (xy 88.415889 -290.310793) (xy 88.407994 -290.35937)
			(xy 88.39241 -290.406051) (xy 88.369539 -290.449628) (xy 88.339974 -290.488972) (xy 88.304481 -290.523064)
			(xy 88.263978 -290.55102) (xy 88.219516 -290.572118) (xy 88.172245 -290.58581) (xy 88.12339 -290.591742)
			(xy 88.074215 -290.589761) (xy 88.025996 -290.579917) (xy 87.97998 -290.562465) (xy 87.937359 -290.537858)
			(xy 87.899238 -290.506733) (xy 87.866603 -290.469896) (xy 87.8403 -290.4283) (xy 87.821009 -290.383024)
			(xy 87.809232 -290.33524) (xy 87.805272 -290.286186) (xy 87.009986 -290.286186) (xy 87.009986 -291.096192)
			(xy 87.335118 -291.096192) (xy 87.339078 -291.047138) (xy 87.350855 -290.999354) (xy 87.370146 -290.954078)
			(xy 87.396449 -290.912482) (xy 87.429084 -290.875645) (xy 87.467205 -290.84452) (xy 87.509826 -290.819913)
			(xy 87.555842 -290.802461) (xy 87.604061 -290.792617) (xy 87.653236 -290.790636) (xy 87.702091 -290.796568)
			(xy 87.749362 -290.81026) (xy 87.793824 -290.831358) (xy 87.834327 -290.859314) (xy 87.86982 -290.893406)
			(xy 87.899385 -290.93275) (xy 87.922256 -290.976327) (xy 87.93784 -291.023008) (xy 87.945735 -291.071585)
			(xy 87.94623 -291.096192) (xy 88.275172 -291.096192) (xy 88.279132 -291.047138) (xy 88.290909 -290.999354)
			(xy 88.3102 -290.954078) (xy 88.336503 -290.912482) (xy 88.369138 -290.875645) (xy 88.407259 -290.84452)
			(xy 88.44988 -290.819913) (xy 88.495896 -290.802461) (xy 88.544115 -290.792617) (xy 88.59329 -290.790636)
			(xy 88.642145 -290.796568) (xy 88.689416 -290.81026) (xy 88.733878 -290.831358) (xy 88.774381 -290.859314)
			(xy 88.809874 -290.893406) (xy 88.839439 -290.93275) (xy 88.86231 -290.976327) (xy 88.877894 -291.023008)
			(xy 88.885789 -291.071585) (xy 88.886284 -291.096192) (xy 89.215226 -291.096192) (xy 89.219186 -291.047138)
			(xy 89.230963 -290.999354) (xy 89.250254 -290.954078) (xy 89.276557 -290.912482) (xy 89.309192 -290.875645)
			(xy 89.347313 -290.84452) (xy 89.389934 -290.819913) (xy 89.43595 -290.802461) (xy 89.484169 -290.792617)
			(xy 89.533344 -290.790636) (xy 89.582199 -290.796568) (xy 89.62947 -290.81026) (xy 89.673932 -290.831358)
			(xy 89.714435 -290.859314) (xy 89.749928 -290.893406) (xy 89.779493 -290.93275) (xy 89.802364 -290.976327)
			(xy 89.817948 -291.023008) (xy 89.825843 -291.071585) (xy 89.826338 -291.096192) (xy 90.15528 -291.096192)
			(xy 90.15924 -291.047138) (xy 90.171017 -290.999354) (xy 90.190308 -290.954078) (xy 90.216611 -290.912482)
			(xy 90.249246 -290.875645) (xy 90.287367 -290.84452) (xy 90.329988 -290.819913) (xy 90.376004 -290.802461)
			(xy 90.424223 -290.792617) (xy 90.473398 -290.790636) (xy 90.522253 -290.796568) (xy 90.569524 -290.81026)
			(xy 90.613986 -290.831358) (xy 90.654489 -290.859314) (xy 90.689982 -290.893406) (xy 90.719547 -290.93275)
			(xy 90.742418 -290.976327) (xy 90.758002 -291.023008) (xy 90.765897 -291.071585) (xy 90.766392 -291.096192)
			(xy 91.084903 -291.096192) (xy 91.088998 -291.045464) (xy 91.101177 -290.99605) (xy 91.121125 -290.94923)
			(xy 91.148326 -290.906216) (xy 91.182074 -290.868122) (xy 91.221496 -290.835935) (xy 91.26557 -290.810489)
			(xy 91.313156 -290.792442) (xy 91.36302 -290.782262) (xy 91.413872 -290.780213) (xy 91.464393 -290.786347)
			(xy 91.513277 -290.800507) (xy 91.559256 -290.822324) (xy 91.60114 -290.851234) (xy 91.637844 -290.886489)
			(xy 91.668417 -290.927175) (xy 91.692068 -290.972238) (xy 91.708184 -291.020512) (xy 91.716348 -291.070746)
			(xy 91.71686 -291.096192) (xy 92.024703 -291.096192) (xy 92.028798 -291.045464) (xy 92.040977 -290.99605)
			(xy 92.060925 -290.94923) (xy 92.088126 -290.906216) (xy 92.121874 -290.868122) (xy 92.161296 -290.835935)
			(xy 92.20537 -290.810489) (xy 92.252956 -290.792442) (xy 92.30282 -290.782262) (xy 92.353672 -290.780213)
			(xy 92.404193 -290.786347) (xy 92.453077 -290.800507) (xy 92.499056 -290.822324) (xy 92.54094 -290.851234)
			(xy 92.577644 -290.886489) (xy 92.608217 -290.927175) (xy 92.631868 -290.972238) (xy 92.647984 -291.020512)
			(xy 92.656148 -291.070746) (xy 92.65666 -291.096192) (xy 92.975188 -291.096192) (xy 92.979148 -291.047138)
			(xy 92.990925 -290.999354) (xy 93.010216 -290.954078) (xy 93.036519 -290.912482) (xy 93.069154 -290.875645)
			(xy 93.107275 -290.84452) (xy 93.149896 -290.819913) (xy 93.195912 -290.802461) (xy 93.244131 -290.792617)
			(xy 93.293306 -290.790636) (xy 93.342161 -290.796568) (xy 93.389432 -290.81026) (xy 93.433894 -290.831358)
			(xy 93.474397 -290.859314) (xy 93.50989 -290.893406) (xy 93.539455 -290.93275) (xy 93.562326 -290.976327)
			(xy 93.57791 -291.023008) (xy 93.585805 -291.071585) (xy 93.5863 -291.096192) (xy 93.904811 -291.096192)
			(xy 93.908906 -291.045464) (xy 93.921085 -290.99605) (xy 93.941033 -290.94923) (xy 93.968234 -290.906216)
			(xy 94.001982 -290.868122) (xy 94.041404 -290.835935) (xy 94.085478 -290.810489) (xy 94.133064 -290.792442)
			(xy 94.182928 -290.782262) (xy 94.23378 -290.780213) (xy 94.284301 -290.786347) (xy 94.333185 -290.800507)
			(xy 94.379164 -290.822324) (xy 94.421048 -290.851234) (xy 94.457752 -290.886489) (xy 94.488325 -290.927175)
			(xy 94.511976 -290.972238) (xy 94.528092 -291.020512) (xy 94.536256 -291.070746) (xy 94.536768 -291.096192)
			(xy 94.855296 -291.096192) (xy 94.859256 -291.047138) (xy 94.871033 -290.999354) (xy 94.890324 -290.954078)
			(xy 94.916627 -290.912482) (xy 94.949262 -290.875645) (xy 94.987383 -290.84452) (xy 95.030004 -290.819913)
			(xy 95.07602 -290.802461) (xy 95.124239 -290.792617) (xy 95.173414 -290.790636) (xy 95.222269 -290.796568)
			(xy 95.26954 -290.81026) (xy 95.314002 -290.831358) (xy 95.354505 -290.859314) (xy 95.389998 -290.893406)
			(xy 95.419563 -290.93275) (xy 95.442434 -290.976327) (xy 95.458018 -291.023008) (xy 95.465913 -291.071585)
			(xy 95.466408 -291.096192) (xy 95.465913 -291.120799) (xy 95.458018 -291.169376) (xy 95.442434 -291.216057)
			(xy 95.419563 -291.259634) (xy 95.389998 -291.298978) (xy 95.354505 -291.33307) (xy 95.314002 -291.361026)
			(xy 95.26954 -291.382124) (xy 95.222269 -291.395816) (xy 95.173414 -291.401748) (xy 95.124239 -291.399767)
			(xy 95.07602 -291.389923) (xy 95.030004 -291.372471) (xy 94.987383 -291.347864) (xy 94.949262 -291.316739)
			(xy 94.916627 -291.279902) (xy 94.890324 -291.238306) (xy 94.871033 -291.19303) (xy 94.859256 -291.145246)
			(xy 94.855296 -291.096192) (xy 94.536768 -291.096192) (xy 94.536256 -291.121638) (xy 94.528092 -291.171872)
			(xy 94.511976 -291.220146) (xy 94.488325 -291.265209) (xy 94.457752 -291.305895) (xy 94.421048 -291.34115)
			(xy 94.379164 -291.37006) (xy 94.333185 -291.391877) (xy 94.284301 -291.406037) (xy 94.23378 -291.412171)
			(xy 94.182928 -291.410122) (xy 94.133064 -291.399942) (xy 94.085478 -291.381895) (xy 94.041404 -291.356449)
			(xy 94.001982 -291.324262) (xy 93.968234 -291.286168) (xy 93.941033 -291.243154) (xy 93.921085 -291.196334)
			(xy 93.908906 -291.14692) (xy 93.904811 -291.096192) (xy 93.5863 -291.096192) (xy 93.585805 -291.120799)
			(xy 93.57791 -291.169376) (xy 93.562326 -291.216057) (xy 93.539455 -291.259634) (xy 93.50989 -291.298978)
			(xy 93.474397 -291.33307) (xy 93.433894 -291.361026) (xy 93.389432 -291.382124) (xy 93.342161 -291.395816)
			(xy 93.293306 -291.401748) (xy 93.244131 -291.399767) (xy 93.195912 -291.389923) (xy 93.149896 -291.372471)
			(xy 93.107275 -291.347864) (xy 93.069154 -291.316739) (xy 93.036519 -291.279902) (xy 93.010216 -291.238306)
			(xy 92.990925 -291.19303) (xy 92.979148 -291.145246) (xy 92.975188 -291.096192) (xy 92.65666 -291.096192)
			(xy 92.656148 -291.121638) (xy 92.647984 -291.171872) (xy 92.631868 -291.220146) (xy 92.608217 -291.265209)
			(xy 92.577644 -291.305895) (xy 92.54094 -291.34115) (xy 92.499056 -291.37006) (xy 92.453077 -291.391877)
			(xy 92.404193 -291.406037) (xy 92.353672 -291.412171) (xy 92.30282 -291.410122) (xy 92.252956 -291.399942)
			(xy 92.20537 -291.381895) (xy 92.161296 -291.356449) (xy 92.121874 -291.324262) (xy 92.088126 -291.286168)
			(xy 92.060925 -291.243154) (xy 92.040977 -291.196334) (xy 92.028798 -291.14692) (xy 92.024703 -291.096192)
			(xy 91.71686 -291.096192) (xy 91.716348 -291.121638) (xy 91.708184 -291.171872) (xy 91.692068 -291.220146)
			(xy 91.668417 -291.265209) (xy 91.637844 -291.305895) (xy 91.60114 -291.34115) (xy 91.559256 -291.37006)
			(xy 91.513277 -291.391877) (xy 91.464393 -291.406037) (xy 91.413872 -291.412171) (xy 91.36302 -291.410122)
			(xy 91.313156 -291.399942) (xy 91.26557 -291.381895) (xy 91.221496 -291.356449) (xy 91.182074 -291.324262)
			(xy 91.148326 -291.286168) (xy 91.121125 -291.243154) (xy 91.101177 -291.196334) (xy 91.088998 -291.14692)
			(xy 91.084903 -291.096192) (xy 90.766392 -291.096192) (xy 90.765897 -291.120799) (xy 90.758002 -291.169376)
			(xy 90.742418 -291.216057) (xy 90.719547 -291.259634) (xy 90.689982 -291.298978) (xy 90.654489 -291.33307)
			(xy 90.613986 -291.361026) (xy 90.569524 -291.382124) (xy 90.522253 -291.395816) (xy 90.473398 -291.401748)
			(xy 90.424223 -291.399767) (xy 90.376004 -291.389923) (xy 90.329988 -291.372471) (xy 90.287367 -291.347864)
			(xy 90.249246 -291.316739) (xy 90.216611 -291.279902) (xy 90.190308 -291.238306) (xy 90.171017 -291.19303)
			(xy 90.15924 -291.145246) (xy 90.15528 -291.096192) (xy 89.826338 -291.096192) (xy 89.825843 -291.120799)
			(xy 89.817948 -291.169376) (xy 89.802364 -291.216057) (xy 89.779493 -291.259634) (xy 89.749928 -291.298978)
			(xy 89.714435 -291.33307) (xy 89.673932 -291.361026) (xy 89.62947 -291.382124) (xy 89.582199 -291.395816)
			(xy 89.533344 -291.401748) (xy 89.484169 -291.399767) (xy 89.43595 -291.389923) (xy 89.389934 -291.372471)
			(xy 89.347313 -291.347864) (xy 89.309192 -291.316739) (xy 89.276557 -291.279902) (xy 89.250254 -291.238306)
			(xy 89.230963 -291.19303) (xy 89.219186 -291.145246) (xy 89.215226 -291.096192) (xy 88.886284 -291.096192)
			(xy 88.885789 -291.120799) (xy 88.877894 -291.169376) (xy 88.86231 -291.216057) (xy 88.839439 -291.259634)
			(xy 88.809874 -291.298978) (xy 88.774381 -291.33307) (xy 88.733878 -291.361026) (xy 88.689416 -291.382124)
			(xy 88.642145 -291.395816) (xy 88.59329 -291.401748) (xy 88.544115 -291.399767) (xy 88.495896 -291.389923)
			(xy 88.44988 -291.372471) (xy 88.407259 -291.347864) (xy 88.369138 -291.316739) (xy 88.336503 -291.279902)
			(xy 88.3102 -291.238306) (xy 88.290909 -291.19303) (xy 88.279132 -291.145246) (xy 88.275172 -291.096192)
			(xy 87.94623 -291.096192) (xy 87.945735 -291.120799) (xy 87.93784 -291.169376) (xy 87.922256 -291.216057)
			(xy 87.899385 -291.259634) (xy 87.86982 -291.298978) (xy 87.834327 -291.33307) (xy 87.793824 -291.361026)
			(xy 87.749362 -291.382124) (xy 87.702091 -291.395816) (xy 87.653236 -291.401748) (xy 87.604061 -291.399767)
			(xy 87.555842 -291.389923) (xy 87.509826 -291.372471) (xy 87.467205 -291.347864) (xy 87.429084 -291.316739)
			(xy 87.396449 -291.279902) (xy 87.370146 -291.238306) (xy 87.350855 -291.19303) (xy 87.339078 -291.145246)
			(xy 87.335118 -291.096192) (xy 87.009986 -291.096192) (xy 87.009986 -291.504878) (xy 87.010362 -291.513982)
			(xy 87.016744 -291.531034) (xy 87.022432 -291.538152) (xy 87.024972 -291.540946) (xy 87.065104 -291.57549)
			(xy 87.080344 -291.588698) (xy 87.081614 -291.589714) (xy 87.088575 -291.594921) (xy 87.104933 -291.600771)
			(xy 87.113618 -291.601144) (xy 87.159592 -291.601144) (xy 87.171022 -291.60089) (xy 87.171276 -291.60089)
			(xy 87.195253 -291.601381) (xy 87.242612 -291.608922) (xy 87.288209 -291.623773) (xy 87.330923 -291.645571)
			(xy 87.369705 -291.67378) (xy 87.403599 -291.707704) (xy 87.431772 -291.746511) (xy 87.453532 -291.789245)
			(xy 87.468343 -291.834855) (xy 87.47584 -291.88222) (xy 87.47633 -291.906198) (xy 87.805272 -291.906198)
			(xy 87.809232 -291.857144) (xy 87.821009 -291.80936) (xy 87.8403 -291.764084) (xy 87.866603 -291.722488)
			(xy 87.899238 -291.685651) (xy 87.937359 -291.654526) (xy 87.97998 -291.629919) (xy 88.025996 -291.612467)
			(xy 88.074215 -291.602623) (xy 88.12339 -291.600642) (xy 88.172245 -291.606574) (xy 88.219516 -291.620266)
			(xy 88.263978 -291.641364) (xy 88.304481 -291.66932) (xy 88.339974 -291.703412) (xy 88.369539 -291.742756)
			(xy 88.39241 -291.786333) (xy 88.407994 -291.833014) (xy 88.415889 -291.881591) (xy 88.416384 -291.906198)
			(xy 88.745326 -291.906198) (xy 88.749286 -291.857144) (xy 88.761063 -291.80936) (xy 88.780354 -291.764084)
			(xy 88.806657 -291.722488) (xy 88.839292 -291.685651) (xy 88.877413 -291.654526) (xy 88.920034 -291.629919)
			(xy 88.96605 -291.612467) (xy 89.014269 -291.602623) (xy 89.063444 -291.600642) (xy 89.112299 -291.606574)
			(xy 89.15957 -291.620266) (xy 89.204032 -291.641364) (xy 89.244535 -291.66932) (xy 89.280028 -291.703412)
			(xy 89.309593 -291.742756) (xy 89.332464 -291.786333) (xy 89.348048 -291.833014) (xy 89.355943 -291.881591)
			(xy 89.356438 -291.906198) (xy 89.685126 -291.906198) (xy 89.689086 -291.857144) (xy 89.700863 -291.80936)
			(xy 89.720154 -291.764084) (xy 89.746457 -291.722488) (xy 89.779092 -291.685651) (xy 89.817213 -291.654526)
			(xy 89.859834 -291.629919) (xy 89.90585 -291.612467) (xy 89.954069 -291.602623) (xy 90.003244 -291.600642)
			(xy 90.052099 -291.606574) (xy 90.09937 -291.620266) (xy 90.143832 -291.641364) (xy 90.184335 -291.66932)
			(xy 90.219828 -291.703412) (xy 90.249393 -291.742756) (xy 90.272264 -291.786333) (xy 90.287848 -291.833014)
			(xy 90.295743 -291.881591) (xy 90.296238 -291.906198) (xy 90.614749 -291.906198) (xy 90.618844 -291.85547)
			(xy 90.631023 -291.806056) (xy 90.650971 -291.759236) (xy 90.678172 -291.716222) (xy 90.71192 -291.678128)
			(xy 90.751342 -291.645941) (xy 90.795416 -291.620495) (xy 90.843002 -291.602448) (xy 90.892866 -291.592268)
			(xy 90.943718 -291.590219) (xy 90.994239 -291.596353) (xy 91.043123 -291.610513) (xy 91.089102 -291.63233)
			(xy 91.130986 -291.66124) (xy 91.16769 -291.696495) (xy 91.198263 -291.737181) (xy 91.221914 -291.782244)
			(xy 91.23803 -291.830518) (xy 91.246194 -291.880752) (xy 91.246706 -291.906198) (xy 91.565234 -291.906198)
			(xy 91.569194 -291.857144) (xy 91.580971 -291.80936) (xy 91.600262 -291.764084) (xy 91.626565 -291.722488)
			(xy 91.6592 -291.685651) (xy 91.697321 -291.654526) (xy 91.739942 -291.629919) (xy 91.785958 -291.612467)
			(xy 91.834177 -291.602623) (xy 91.883352 -291.600642) (xy 91.932207 -291.606574) (xy 91.979478 -291.620266)
			(xy 92.02394 -291.641364) (xy 92.064443 -291.66932) (xy 92.099936 -291.703412) (xy 92.129501 -291.742756)
			(xy 92.152372 -291.786333) (xy 92.167956 -291.833014) (xy 92.175851 -291.881591) (xy 92.176346 -291.906198)
			(xy 92.494857 -291.906198) (xy 92.498952 -291.85547) (xy 92.511131 -291.806056) (xy 92.531079 -291.759236)
			(xy 92.55828 -291.716222) (xy 92.592028 -291.678128) (xy 92.63145 -291.645941) (xy 92.675524 -291.620495)
			(xy 92.72311 -291.602448) (xy 92.772974 -291.592268) (xy 92.823826 -291.590219) (xy 92.874347 -291.596353)
			(xy 92.923231 -291.610513) (xy 92.96921 -291.63233) (xy 93.011094 -291.66124) (xy 93.047798 -291.696495)
			(xy 93.078371 -291.737181) (xy 93.102022 -291.782244) (xy 93.118138 -291.830518) (xy 93.126302 -291.880752)
			(xy 93.126814 -291.906198) (xy 93.445342 -291.906198) (xy 93.449302 -291.857144) (xy 93.461079 -291.80936)
			(xy 93.48037 -291.764084) (xy 93.506673 -291.722488) (xy 93.539308 -291.685651) (xy 93.577429 -291.654526)
			(xy 93.62005 -291.629919) (xy 93.666066 -291.612467) (xy 93.714285 -291.602623) (xy 93.76346 -291.600642)
			(xy 93.812315 -291.606574) (xy 93.859586 -291.620266) (xy 93.904048 -291.641364) (xy 93.944551 -291.66932)
			(xy 93.980044 -291.703412) (xy 94.009609 -291.742756) (xy 94.03248 -291.786333) (xy 94.048064 -291.833014)
			(xy 94.055959 -291.881591) (xy 94.056454 -291.906198) (xy 94.374711 -291.906198) (xy 94.378806 -291.85547)
			(xy 94.390985 -291.806056) (xy 94.410933 -291.759236) (xy 94.438134 -291.716222) (xy 94.471882 -291.678128)
			(xy 94.511304 -291.645941) (xy 94.555378 -291.620495) (xy 94.602964 -291.602448) (xy 94.652828 -291.592268)
			(xy 94.70368 -291.590219) (xy 94.754201 -291.596353) (xy 94.803085 -291.610513) (xy 94.849064 -291.63233)
			(xy 94.890948 -291.66124) (xy 94.927652 -291.696495) (xy 94.958225 -291.737181) (xy 94.981876 -291.782244)
			(xy 94.997992 -291.830518) (xy 95.006156 -291.880752) (xy 95.006668 -291.906198) (xy 95.314765 -291.906198)
			(xy 95.31886 -291.85547) (xy 95.331039 -291.806056) (xy 95.350987 -291.759236) (xy 95.378188 -291.716222)
			(xy 95.411936 -291.678128) (xy 95.451358 -291.645941) (xy 95.495432 -291.620495) (xy 95.543018 -291.602448)
			(xy 95.592882 -291.592268) (xy 95.643734 -291.590219) (xy 95.694255 -291.596353) (xy 95.743139 -291.610513)
			(xy 95.789118 -291.63233) (xy 95.831002 -291.66124) (xy 95.867706 -291.696495) (xy 95.898279 -291.737181)
			(xy 95.92193 -291.782244) (xy 95.938046 -291.830518) (xy 95.94621 -291.880752) (xy 95.946722 -291.906198)
			(xy 95.94621 -291.931644) (xy 95.938046 -291.981878) (xy 95.92193 -292.030152) (xy 95.898279 -292.075215)
			(xy 95.867706 -292.115901) (xy 95.831002 -292.151156) (xy 95.789118 -292.180066) (xy 95.743139 -292.201883)
			(xy 95.694255 -292.216043) (xy 95.643734 -292.222177) (xy 95.592882 -292.220128) (xy 95.543018 -292.209948)
			(xy 95.495432 -292.191901) (xy 95.451358 -292.166455) (xy 95.411936 -292.134268) (xy 95.378188 -292.096174)
			(xy 95.350987 -292.05316) (xy 95.331039 -292.00634) (xy 95.31886 -291.956926) (xy 95.314765 -291.906198)
			(xy 95.006668 -291.906198) (xy 95.006156 -291.931644) (xy 94.997992 -291.981878) (xy 94.981876 -292.030152)
			(xy 94.958225 -292.075215) (xy 94.927652 -292.115901) (xy 94.890948 -292.151156) (xy 94.849064 -292.180066)
			(xy 94.803085 -292.201883) (xy 94.754201 -292.216043) (xy 94.70368 -292.222177) (xy 94.652828 -292.220128)
			(xy 94.602964 -292.209948) (xy 94.555378 -292.191901) (xy 94.511304 -292.166455) (xy 94.471882 -292.134268)
			(xy 94.438134 -292.096174) (xy 94.410933 -292.05316) (xy 94.390985 -292.00634) (xy 94.378806 -291.956926)
			(xy 94.374711 -291.906198) (xy 94.056454 -291.906198) (xy 94.055959 -291.930805) (xy 94.048064 -291.979382)
			(xy 94.03248 -292.026063) (xy 94.009609 -292.06964) (xy 93.980044 -292.108984) (xy 93.944551 -292.143076)
			(xy 93.904048 -292.171032) (xy 93.859586 -292.19213) (xy 93.812315 -292.205822) (xy 93.76346 -292.211754)
			(xy 93.714285 -292.209773) (xy 93.666066 -292.199929) (xy 93.62005 -292.182477) (xy 93.577429 -292.15787)
			(xy 93.539308 -292.126745) (xy 93.506673 -292.089908) (xy 93.48037 -292.048312) (xy 93.461079 -292.003036)
			(xy 93.449302 -291.955252) (xy 93.445342 -291.906198) (xy 93.126814 -291.906198) (xy 93.126302 -291.931644)
			(xy 93.118138 -291.981878) (xy 93.102022 -292.030152) (xy 93.078371 -292.075215) (xy 93.047798 -292.115901)
			(xy 93.011094 -292.151156) (xy 92.96921 -292.180066) (xy 92.923231 -292.201883) (xy 92.874347 -292.216043)
			(xy 92.823826 -292.222177) (xy 92.772974 -292.220128) (xy 92.72311 -292.209948) (xy 92.675524 -292.191901)
			(xy 92.63145 -292.166455) (xy 92.592028 -292.134268) (xy 92.55828 -292.096174) (xy 92.531079 -292.05316)
			(xy 92.511131 -292.00634) (xy 92.498952 -291.956926) (xy 92.494857 -291.906198) (xy 92.176346 -291.906198)
			(xy 92.175851 -291.930805) (xy 92.167956 -291.979382) (xy 92.152372 -292.026063) (xy 92.129501 -292.06964)
			(xy 92.099936 -292.108984) (xy 92.064443 -292.143076) (xy 92.02394 -292.171032) (xy 91.979478 -292.19213)
			(xy 91.932207 -292.205822) (xy 91.883352 -292.211754) (xy 91.834177 -292.209773) (xy 91.785958 -292.199929)
			(xy 91.739942 -292.182477) (xy 91.697321 -292.15787) (xy 91.6592 -292.126745) (xy 91.626565 -292.089908)
			(xy 91.600262 -292.048312) (xy 91.580971 -292.003036) (xy 91.569194 -291.955252) (xy 91.565234 -291.906198)
			(xy 91.246706 -291.906198) (xy 91.246194 -291.931644) (xy 91.23803 -291.981878) (xy 91.221914 -292.030152)
			(xy 91.198263 -292.075215) (xy 91.16769 -292.115901) (xy 91.130986 -292.151156) (xy 91.089102 -292.180066)
			(xy 91.043123 -292.201883) (xy 90.994239 -292.216043) (xy 90.943718 -292.222177) (xy 90.892866 -292.220128)
			(xy 90.843002 -292.209948) (xy 90.795416 -292.191901) (xy 90.751342 -292.166455) (xy 90.71192 -292.134268)
			(xy 90.678172 -292.096174) (xy 90.650971 -292.05316) (xy 90.631023 -292.00634) (xy 90.618844 -291.956926)
			(xy 90.614749 -291.906198) (xy 90.296238 -291.906198) (xy 90.295743 -291.930805) (xy 90.287848 -291.979382)
			(xy 90.272264 -292.026063) (xy 90.249393 -292.06964) (xy 90.219828 -292.108984) (xy 90.184335 -292.143076)
			(xy 90.143832 -292.171032) (xy 90.09937 -292.19213) (xy 90.052099 -292.205822) (xy 90.003244 -292.211754)
			(xy 89.954069 -292.209773) (xy 89.90585 -292.199929) (xy 89.859834 -292.182477) (xy 89.817213 -292.15787)
			(xy 89.779092 -292.126745) (xy 89.746457 -292.089908) (xy 89.720154 -292.048312) (xy 89.700863 -292.003036)
			(xy 89.689086 -291.955252) (xy 89.685126 -291.906198) (xy 89.356438 -291.906198) (xy 89.355943 -291.930805)
			(xy 89.348048 -291.979382) (xy 89.332464 -292.026063) (xy 89.309593 -292.06964) (xy 89.280028 -292.108984)
			(xy 89.244535 -292.143076) (xy 89.204032 -292.171032) (xy 89.15957 -292.19213) (xy 89.112299 -292.205822)
			(xy 89.063444 -292.211754) (xy 89.014269 -292.209773) (xy 88.96605 -292.199929) (xy 88.920034 -292.182477)
			(xy 88.877413 -292.15787) (xy 88.839292 -292.126745) (xy 88.806657 -292.089908) (xy 88.780354 -292.048312)
			(xy 88.761063 -292.003036) (xy 88.749286 -291.955252) (xy 88.745326 -291.906198) (xy 88.416384 -291.906198)
			(xy 88.415889 -291.930805) (xy 88.407994 -291.979382) (xy 88.39241 -292.026063) (xy 88.369539 -292.06964)
			(xy 88.339974 -292.108984) (xy 88.304481 -292.143076) (xy 88.263978 -292.171032) (xy 88.219516 -292.19213)
			(xy 88.172245 -292.205822) (xy 88.12339 -292.211754) (xy 88.074215 -292.209773) (xy 88.025996 -292.199929)
			(xy 87.97998 -292.182477) (xy 87.937359 -292.15787) (xy 87.899238 -292.126745) (xy 87.866603 -292.089908)
			(xy 87.8403 -292.048312) (xy 87.821009 -292.003036) (xy 87.809232 -291.955252) (xy 87.805272 -291.906198)
			(xy 87.47633 -291.906198) (xy 87.47586 -291.93019) (xy 87.468354 -291.977583) (xy 87.453527 -292.023219)
			(xy 87.431744 -292.065973) (xy 87.403541 -292.104794) (xy 87.369612 -292.138725) (xy 87.330794 -292.166931)
			(xy 87.288041 -292.188718) (xy 87.242407 -292.203548) (xy 87.195014 -292.211058) (xy 87.171022 -292.211506)
			(xy 87.159613 -292.211431) (xy 87.136856 -292.209777) (xy 87.125556 -292.208204) (xy 87.114634 -292.206426)
			(xy 87.09279 -292.212776) (xy 87.065358 -292.236652) (xy 87.06485 -292.23716) (xy 87.030814 -292.26637)
			(xy 87.02929 -292.26764) (xy 87.024972 -292.271958) (xy 87.017606 -292.27907) (xy 87.009986 -292.297866)
			(xy 87.009986 -292.597586) (xy 87.01278 -292.605968) (xy 87.021613 -292.63267) (xy 87.031197 -292.688086)
			(xy 87.03183 -292.716204) (xy 87.335118 -292.716204) (xy 87.339078 -292.66715) (xy 87.350855 -292.619366)
			(xy 87.370146 -292.57409) (xy 87.396449 -292.532494) (xy 87.429084 -292.495657) (xy 87.467205 -292.464532)
			(xy 87.509826 -292.439925) (xy 87.555842 -292.422473) (xy 87.604061 -292.412629) (xy 87.653236 -292.410648)
			(xy 87.702091 -292.41658) (xy 87.749362 -292.430272) (xy 87.793824 -292.45137) (xy 87.834327 -292.479326)
			(xy 87.86982 -292.513418) (xy 87.899385 -292.552762) (xy 87.922256 -292.596339) (xy 87.93784 -292.64302)
			(xy 87.945735 -292.691597) (xy 87.94623 -292.716204) (xy 88.275172 -292.716204) (xy 88.279132 -292.66715)
			(xy 88.290909 -292.619366) (xy 88.3102 -292.57409) (xy 88.336503 -292.532494) (xy 88.369138 -292.495657)
			(xy 88.407259 -292.464532) (xy 88.44988 -292.439925) (xy 88.495896 -292.422473) (xy 88.544115 -292.412629)
			(xy 88.59329 -292.410648) (xy 88.642145 -292.41658) (xy 88.689416 -292.430272) (xy 88.733878 -292.45137)
			(xy 88.774381 -292.479326) (xy 88.809874 -292.513418) (xy 88.839439 -292.552762) (xy 88.86231 -292.596339)
			(xy 88.877894 -292.64302) (xy 88.885789 -292.691597) (xy 88.886284 -292.716204) (xy 89.215226 -292.716204)
			(xy 89.219186 -292.66715) (xy 89.230963 -292.619366) (xy 89.250254 -292.57409) (xy 89.276557 -292.532494)
			(xy 89.309192 -292.495657) (xy 89.347313 -292.464532) (xy 89.389934 -292.439925) (xy 89.43595 -292.422473)
			(xy 89.484169 -292.412629) (xy 89.533344 -292.410648) (xy 89.582199 -292.41658) (xy 89.62947 -292.430272)
			(xy 89.673932 -292.45137) (xy 89.714435 -292.479326) (xy 89.749928 -292.513418) (xy 89.779493 -292.552762)
			(xy 89.802364 -292.596339) (xy 89.817948 -292.64302) (xy 89.825843 -292.691597) (xy 89.826338 -292.716204)
			(xy 90.15528 -292.716204) (xy 90.15924 -292.66715) (xy 90.171017 -292.619366) (xy 90.190308 -292.57409)
			(xy 90.216611 -292.532494) (xy 90.249246 -292.495657) (xy 90.287367 -292.464532) (xy 90.329988 -292.439925)
			(xy 90.376004 -292.422473) (xy 90.424223 -292.412629) (xy 90.473398 -292.410648) (xy 90.522253 -292.41658)
			(xy 90.569524 -292.430272) (xy 90.613986 -292.45137) (xy 90.654489 -292.479326) (xy 90.689982 -292.513418)
			(xy 90.719547 -292.552762) (xy 90.742418 -292.596339) (xy 90.758002 -292.64302) (xy 90.765897 -292.691597)
			(xy 90.766392 -292.716204) (xy 91.084903 -292.716204) (xy 91.088998 -292.665476) (xy 91.101177 -292.616062)
			(xy 91.121125 -292.569242) (xy 91.148326 -292.526228) (xy 91.182074 -292.488134) (xy 91.221496 -292.455947)
			(xy 91.26557 -292.430501) (xy 91.313156 -292.412454) (xy 91.36302 -292.402274) (xy 91.413872 -292.400225)
			(xy 91.464393 -292.406359) (xy 91.513277 -292.420519) (xy 91.559256 -292.442336) (xy 91.60114 -292.471246)
			(xy 91.637844 -292.506501) (xy 91.668417 -292.547187) (xy 91.692068 -292.59225) (xy 91.708184 -292.640524)
			(xy 91.716348 -292.690758) (xy 91.71686 -292.716204) (xy 92.024703 -292.716204) (xy 92.028798 -292.665476)
			(xy 92.040977 -292.616062) (xy 92.060925 -292.569242) (xy 92.088126 -292.526228) (xy 92.121874 -292.488134)
			(xy 92.161296 -292.455947) (xy 92.20537 -292.430501) (xy 92.252956 -292.412454) (xy 92.30282 -292.402274)
			(xy 92.353672 -292.400225) (xy 92.404193 -292.406359) (xy 92.453077 -292.420519) (xy 92.499056 -292.442336)
			(xy 92.54094 -292.471246) (xy 92.577644 -292.506501) (xy 92.608217 -292.547187) (xy 92.631868 -292.59225)
			(xy 92.647984 -292.640524) (xy 92.656148 -292.690758) (xy 92.65666 -292.716204) (xy 93.904811 -292.716204)
			(xy 93.908906 -292.665476) (xy 93.921085 -292.616062) (xy 93.941033 -292.569242) (xy 93.968234 -292.526228)
			(xy 94.001982 -292.488134) (xy 94.041404 -292.455947) (xy 94.085478 -292.430501) (xy 94.133064 -292.412454)
			(xy 94.182928 -292.402274) (xy 94.23378 -292.400225) (xy 94.284301 -292.406359) (xy 94.333185 -292.420519)
			(xy 94.379164 -292.442336) (xy 94.421048 -292.471246) (xy 94.457752 -292.506501) (xy 94.488325 -292.547187)
			(xy 94.511976 -292.59225) (xy 94.528092 -292.640524) (xy 94.536256 -292.690758) (xy 94.536768 -292.716204)
			(xy 94.855296 -292.716204) (xy 94.859256 -292.66715) (xy 94.871033 -292.619366) (xy 94.890324 -292.57409)
			(xy 94.916627 -292.532494) (xy 94.949262 -292.495657) (xy 94.987383 -292.464532) (xy 95.030004 -292.439925)
			(xy 95.07602 -292.422473) (xy 95.124239 -292.412629) (xy 95.173414 -292.410648) (xy 95.222269 -292.41658)
			(xy 95.26954 -292.430272) (xy 95.314002 -292.45137) (xy 95.354505 -292.479326) (xy 95.389998 -292.513418)
			(xy 95.419563 -292.552762) (xy 95.442434 -292.596339) (xy 95.458018 -292.64302) (xy 95.465913 -292.691597)
			(xy 95.466408 -292.716204) (xy 95.465913 -292.740811) (xy 95.458018 -292.789388) (xy 95.442434 -292.836069)
			(xy 95.419563 -292.879646) (xy 95.389998 -292.91899) (xy 95.354505 -292.953082) (xy 95.314002 -292.981038)
			(xy 95.26954 -293.002136) (xy 95.222269 -293.015828) (xy 95.173414 -293.02176) (xy 95.124239 -293.019779)
			(xy 95.07602 -293.009935) (xy 95.030004 -292.992483) (xy 94.987383 -292.967876) (xy 94.949262 -292.936751)
			(xy 94.916627 -292.899914) (xy 94.890324 -292.858318) (xy 94.871033 -292.813042) (xy 94.859256 -292.765258)
			(xy 94.855296 -292.716204) (xy 94.536768 -292.716204) (xy 94.536256 -292.74165) (xy 94.528092 -292.791884)
			(xy 94.511976 -292.840158) (xy 94.488325 -292.885221) (xy 94.457752 -292.925907) (xy 94.421048 -292.961162)
			(xy 94.379164 -292.990072) (xy 94.333185 -293.011889) (xy 94.284301 -293.026049) (xy 94.23378 -293.032183)
			(xy 94.182928 -293.030134) (xy 94.133064 -293.019954) (xy 94.085478 -293.001907) (xy 94.041404 -292.976461)
			(xy 94.001982 -292.944274) (xy 93.968234 -292.90618) (xy 93.941033 -292.863166) (xy 93.921085 -292.816346)
			(xy 93.908906 -292.766932) (xy 93.904811 -292.716204) (xy 92.65666 -292.716204) (xy 92.656148 -292.74165)
			(xy 92.647984 -292.791884) (xy 92.631868 -292.840158) (xy 92.608217 -292.885221) (xy 92.577644 -292.925907)
			(xy 92.54094 -292.961162) (xy 92.499056 -292.990072) (xy 92.453077 -293.011889) (xy 92.404193 -293.026049)
			(xy 92.353672 -293.032183) (xy 92.30282 -293.030134) (xy 92.252956 -293.019954) (xy 92.20537 -293.001907)
			(xy 92.161296 -292.976461) (xy 92.121874 -292.944274) (xy 92.088126 -292.90618) (xy 92.060925 -292.863166)
			(xy 92.040977 -292.816346) (xy 92.028798 -292.766932) (xy 92.024703 -292.716204) (xy 91.71686 -292.716204)
			(xy 91.716348 -292.74165) (xy 91.708184 -292.791884) (xy 91.692068 -292.840158) (xy 91.668417 -292.885221)
			(xy 91.637844 -292.925907) (xy 91.60114 -292.961162) (xy 91.559256 -292.990072) (xy 91.513277 -293.011889)
			(xy 91.464393 -293.026049) (xy 91.413872 -293.032183) (xy 91.36302 -293.030134) (xy 91.313156 -293.019954)
			(xy 91.26557 -293.001907) (xy 91.221496 -292.976461) (xy 91.182074 -292.944274) (xy 91.148326 -292.90618)
			(xy 91.121125 -292.863166) (xy 91.101177 -292.816346) (xy 91.088998 -292.766932) (xy 91.084903 -292.716204)
			(xy 90.766392 -292.716204) (xy 90.765897 -292.740811) (xy 90.758002 -292.789388) (xy 90.742418 -292.836069)
			(xy 90.719547 -292.879646) (xy 90.689982 -292.91899) (xy 90.654489 -292.953082) (xy 90.613986 -292.981038)
			(xy 90.569524 -293.002136) (xy 90.522253 -293.015828) (xy 90.473398 -293.02176) (xy 90.424223 -293.019779)
			(xy 90.376004 -293.009935) (xy 90.329988 -292.992483) (xy 90.287367 -292.967876) (xy 90.249246 -292.936751)
			(xy 90.216611 -292.899914) (xy 90.190308 -292.858318) (xy 90.171017 -292.813042) (xy 90.15924 -292.765258)
			(xy 90.15528 -292.716204) (xy 89.826338 -292.716204) (xy 89.825843 -292.740811) (xy 89.817948 -292.789388)
			(xy 89.802364 -292.836069) (xy 89.779493 -292.879646) (xy 89.749928 -292.91899) (xy 89.714435 -292.953082)
			(xy 89.673932 -292.981038) (xy 89.62947 -293.002136) (xy 89.582199 -293.015828) (xy 89.533344 -293.02176)
			(xy 89.484169 -293.019779) (xy 89.43595 -293.009935) (xy 89.389934 -292.992483) (xy 89.347313 -292.967876)
			(xy 89.309192 -292.936751) (xy 89.276557 -292.899914) (xy 89.250254 -292.858318) (xy 89.230963 -292.813042)
			(xy 89.219186 -292.765258) (xy 89.215226 -292.716204) (xy 88.886284 -292.716204) (xy 88.885789 -292.740811)
			(xy 88.877894 -292.789388) (xy 88.86231 -292.836069) (xy 88.839439 -292.879646) (xy 88.809874 -292.91899)
			(xy 88.774381 -292.953082) (xy 88.733878 -292.981038) (xy 88.689416 -293.002136) (xy 88.642145 -293.015828)
			(xy 88.59329 -293.02176) (xy 88.544115 -293.019779) (xy 88.495896 -293.009935) (xy 88.44988 -292.992483)
			(xy 88.407259 -292.967876) (xy 88.369138 -292.936751) (xy 88.336503 -292.899914) (xy 88.3102 -292.858318)
			(xy 88.290909 -292.813042) (xy 88.279132 -292.765258) (xy 88.275172 -292.716204) (xy 87.94623 -292.716204)
			(xy 87.945735 -292.740811) (xy 87.93784 -292.789388) (xy 87.922256 -292.836069) (xy 87.899385 -292.879646)
			(xy 87.86982 -292.91899) (xy 87.834327 -292.953082) (xy 87.793824 -292.981038) (xy 87.749362 -293.002136)
			(xy 87.702091 -293.015828) (xy 87.653236 -293.02176) (xy 87.604061 -293.019779) (xy 87.555842 -293.009935)
			(xy 87.509826 -292.992483) (xy 87.467205 -292.967876) (xy 87.429084 -292.936751) (xy 87.396449 -292.899914)
			(xy 87.370146 -292.858318) (xy 87.350855 -292.813042) (xy 87.339078 -292.765258) (xy 87.335118 -292.716204)
			(xy 87.03183 -292.716204) (xy 87.031248 -292.744327) (xy 87.021672 -292.799753) (xy 87.01278 -292.82644)
			(xy 87.009986 -292.834822) (xy 87.009986 -293.12489) (xy 87.010364 -293.133993) (xy 87.016749 -293.151042)
			(xy 87.022432 -293.158164) (xy 87.024972 -293.160958) (xy 87.065104 -293.195502) (xy 87.080344 -293.20871)
			(xy 87.081614 -293.209726) (xy 87.088576 -293.214932) (xy 87.104934 -293.22078) (xy 87.113618 -293.221156)
			(xy 87.159592 -293.221156) (xy 87.171022 -293.220902) (xy 87.171276 -293.220902) (xy 87.195253 -293.221393)
			(xy 87.242611 -293.228934) (xy 87.288207 -293.243786) (xy 87.330921 -293.265584) (xy 87.369701 -293.293792)
			(xy 87.403594 -293.327717) (xy 87.431766 -293.366524) (xy 87.453524 -293.409258) (xy 87.468333 -293.454868)
			(xy 87.475829 -293.502233) (xy 87.47633 -293.52621) (xy 87.805272 -293.52621) (xy 87.809232 -293.477156)
			(xy 87.821009 -293.429372) (xy 87.8403 -293.384096) (xy 87.866603 -293.3425) (xy 87.899238 -293.305663)
			(xy 87.937359 -293.274538) (xy 87.97998 -293.249931) (xy 88.025996 -293.232479) (xy 88.074215 -293.222635)
			(xy 88.12339 -293.220654) (xy 88.172245 -293.226586) (xy 88.219516 -293.240278) (xy 88.263978 -293.261376)
			(xy 88.304481 -293.289332) (xy 88.339974 -293.323424) (xy 88.369539 -293.362768) (xy 88.39241 -293.406345)
			(xy 88.407994 -293.453026) (xy 88.415889 -293.501603) (xy 88.416384 -293.52621) (xy 88.745326 -293.52621)
			(xy 88.749286 -293.477156) (xy 88.761063 -293.429372) (xy 88.780354 -293.384096) (xy 88.806657 -293.3425)
			(xy 88.839292 -293.305663) (xy 88.877413 -293.274538) (xy 88.920034 -293.249931) (xy 88.96605 -293.232479)
			(xy 89.014269 -293.222635) (xy 89.063444 -293.220654) (xy 89.112299 -293.226586) (xy 89.15957 -293.240278)
			(xy 89.204032 -293.261376) (xy 89.244535 -293.289332) (xy 89.280028 -293.323424) (xy 89.309593 -293.362768)
			(xy 89.332464 -293.406345) (xy 89.348048 -293.453026) (xy 89.355943 -293.501603) (xy 89.356438 -293.52621)
			(xy 89.685126 -293.52621) (xy 89.689086 -293.477156) (xy 89.700863 -293.429372) (xy 89.720154 -293.384096)
			(xy 89.746457 -293.3425) (xy 89.779092 -293.305663) (xy 89.817213 -293.274538) (xy 89.859834 -293.249931)
			(xy 89.90585 -293.232479) (xy 89.954069 -293.222635) (xy 90.003244 -293.220654) (xy 90.052099 -293.226586)
			(xy 90.09937 -293.240278) (xy 90.143832 -293.261376) (xy 90.184335 -293.289332) (xy 90.219828 -293.323424)
			(xy 90.249393 -293.362768) (xy 90.272264 -293.406345) (xy 90.287848 -293.453026) (xy 90.295743 -293.501603)
			(xy 90.296238 -293.52621) (xy 90.614749 -293.52621) (xy 90.618844 -293.475482) (xy 90.631023 -293.426068)
			(xy 90.650971 -293.379248) (xy 90.678172 -293.336234) (xy 90.71192 -293.29814) (xy 90.751342 -293.265953)
			(xy 90.795416 -293.240507) (xy 90.843002 -293.22246) (xy 90.892866 -293.21228) (xy 90.943718 -293.210231)
			(xy 90.994239 -293.216365) (xy 91.043123 -293.230525) (xy 91.089102 -293.252342) (xy 91.130986 -293.281252)
			(xy 91.16769 -293.316507) (xy 91.198263 -293.357193) (xy 91.221914 -293.402256) (xy 91.23803 -293.45053)
			(xy 91.246194 -293.500764) (xy 91.246706 -293.52621) (xy 91.565234 -293.52621) (xy 91.569194 -293.477156)
			(xy 91.580971 -293.429372) (xy 91.600262 -293.384096) (xy 91.626565 -293.3425) (xy 91.6592 -293.305663)
			(xy 91.697321 -293.274538) (xy 91.739942 -293.249931) (xy 91.785958 -293.232479) (xy 91.834177 -293.222635)
			(xy 91.883352 -293.220654) (xy 91.932207 -293.226586) (xy 91.979478 -293.240278) (xy 92.02394 -293.261376)
			(xy 92.064443 -293.289332) (xy 92.099936 -293.323424) (xy 92.129501 -293.362768) (xy 92.152372 -293.406345)
			(xy 92.167956 -293.453026) (xy 92.175851 -293.501603) (xy 92.176346 -293.52621) (xy 92.505288 -293.52621)
			(xy 92.509248 -293.477156) (xy 92.521025 -293.429372) (xy 92.540316 -293.384096) (xy 92.566619 -293.3425)
			(xy 92.599254 -293.305663) (xy 92.637375 -293.274538) (xy 92.679996 -293.249931) (xy 92.726012 -293.232479)
			(xy 92.774231 -293.222635) (xy 92.823406 -293.220654) (xy 92.872261 -293.226586) (xy 92.919532 -293.240278)
			(xy 92.963994 -293.261376) (xy 93.004497 -293.289332) (xy 93.03999 -293.323424) (xy 93.069555 -293.362768)
			(xy 93.092426 -293.406345) (xy 93.10801 -293.453026) (xy 93.115905 -293.501603) (xy 93.1164 -293.52621)
			(xy 93.445342 -293.52621) (xy 93.449302 -293.477156) (xy 93.461079 -293.429372) (xy 93.48037 -293.384096)
			(xy 93.506673 -293.3425) (xy 93.539308 -293.305663) (xy 93.577429 -293.274538) (xy 93.62005 -293.249931)
			(xy 93.666066 -293.232479) (xy 93.714285 -293.222635) (xy 93.76346 -293.220654) (xy 93.812315 -293.226586)
			(xy 93.859586 -293.240278) (xy 93.904048 -293.261376) (xy 93.944551 -293.289332) (xy 93.980044 -293.323424)
			(xy 94.009609 -293.362768) (xy 94.03248 -293.406345) (xy 94.048064 -293.453026) (xy 94.055959 -293.501603)
			(xy 94.056454 -293.52621) (xy 94.385142 -293.52621) (xy 94.389102 -293.477156) (xy 94.400879 -293.429372)
			(xy 94.42017 -293.384096) (xy 94.446473 -293.3425) (xy 94.479108 -293.305663) (xy 94.517229 -293.274538)
			(xy 94.55985 -293.249931) (xy 94.605866 -293.232479) (xy 94.654085 -293.222635) (xy 94.70326 -293.220654)
			(xy 94.752115 -293.226586) (xy 94.799386 -293.240278) (xy 94.843848 -293.261376) (xy 94.884351 -293.289332)
			(xy 94.919844 -293.323424) (xy 94.949409 -293.362768) (xy 94.97228 -293.406345) (xy 94.987864 -293.453026)
			(xy 94.995759 -293.501603) (xy 94.996254 -293.52621) (xy 95.314765 -293.52621) (xy 95.31886 -293.475482)
			(xy 95.331039 -293.426068) (xy 95.350987 -293.379248) (xy 95.378188 -293.336234) (xy 95.411936 -293.29814)
			(xy 95.451358 -293.265953) (xy 95.495432 -293.240507) (xy 95.543018 -293.22246) (xy 95.592882 -293.21228)
			(xy 95.643734 -293.210231) (xy 95.694255 -293.216365) (xy 95.743139 -293.230525) (xy 95.789118 -293.252342)
			(xy 95.831002 -293.281252) (xy 95.867706 -293.316507) (xy 95.898279 -293.357193) (xy 95.92193 -293.402256)
			(xy 95.938046 -293.45053) (xy 95.94621 -293.500764) (xy 95.946722 -293.52621) (xy 95.94621 -293.551656)
			(xy 95.938046 -293.60189) (xy 95.92193 -293.650164) (xy 95.898279 -293.695227) (xy 95.867706 -293.735913)
			(xy 95.831002 -293.771168) (xy 95.789118 -293.800078) (xy 95.743139 -293.821895) (xy 95.694255 -293.836055)
			(xy 95.643734 -293.842189) (xy 95.592882 -293.84014) (xy 95.543018 -293.82996) (xy 95.495432 -293.811913)
			(xy 95.451358 -293.786467) (xy 95.411936 -293.75428) (xy 95.378188 -293.716186) (xy 95.350987 -293.673172)
			(xy 95.331039 -293.626352) (xy 95.31886 -293.576938) (xy 95.314765 -293.52621) (xy 94.996254 -293.52621)
			(xy 94.995759 -293.550817) (xy 94.987864 -293.599394) (xy 94.97228 -293.646075) (xy 94.949409 -293.689652)
			(xy 94.919844 -293.728996) (xy 94.884351 -293.763088) (xy 94.843848 -293.791044) (xy 94.799386 -293.812142)
			(xy 94.752115 -293.825834) (xy 94.70326 -293.831766) (xy 94.654085 -293.829785) (xy 94.605866 -293.819941)
			(xy 94.55985 -293.802489) (xy 94.517229 -293.777882) (xy 94.479108 -293.746757) (xy 94.446473 -293.70992)
			(xy 94.42017 -293.668324) (xy 94.400879 -293.623048) (xy 94.389102 -293.575264) (xy 94.385142 -293.52621)
			(xy 94.056454 -293.52621) (xy 94.055959 -293.550817) (xy 94.048064 -293.599394) (xy 94.03248 -293.646075)
			(xy 94.009609 -293.689652) (xy 93.980044 -293.728996) (xy 93.944551 -293.763088) (xy 93.904048 -293.791044)
			(xy 93.859586 -293.812142) (xy 93.812315 -293.825834) (xy 93.76346 -293.831766) (xy 93.714285 -293.829785)
			(xy 93.666066 -293.819941) (xy 93.62005 -293.802489) (xy 93.577429 -293.777882) (xy 93.539308 -293.746757)
			(xy 93.506673 -293.70992) (xy 93.48037 -293.668324) (xy 93.461079 -293.623048) (xy 93.449302 -293.575264)
			(xy 93.445342 -293.52621) (xy 93.1164 -293.52621) (xy 93.115905 -293.550817) (xy 93.10801 -293.599394)
			(xy 93.092426 -293.646075) (xy 93.069555 -293.689652) (xy 93.03999 -293.728996) (xy 93.004497 -293.763088)
			(xy 92.963994 -293.791044) (xy 92.919532 -293.812142) (xy 92.872261 -293.825834) (xy 92.823406 -293.831766)
			(xy 92.774231 -293.829785) (xy 92.726012 -293.819941) (xy 92.679996 -293.802489) (xy 92.637375 -293.777882)
			(xy 92.599254 -293.746757) (xy 92.566619 -293.70992) (xy 92.540316 -293.668324) (xy 92.521025 -293.623048)
			(xy 92.509248 -293.575264) (xy 92.505288 -293.52621) (xy 92.176346 -293.52621) (xy 92.175851 -293.550817)
			(xy 92.167956 -293.599394) (xy 92.152372 -293.646075) (xy 92.129501 -293.689652) (xy 92.099936 -293.728996)
			(xy 92.064443 -293.763088) (xy 92.02394 -293.791044) (xy 91.979478 -293.812142) (xy 91.932207 -293.825834)
			(xy 91.883352 -293.831766) (xy 91.834177 -293.829785) (xy 91.785958 -293.819941) (xy 91.739942 -293.802489)
			(xy 91.697321 -293.777882) (xy 91.6592 -293.746757) (xy 91.626565 -293.70992) (xy 91.600262 -293.668324)
			(xy 91.580971 -293.623048) (xy 91.569194 -293.575264) (xy 91.565234 -293.52621) (xy 91.246706 -293.52621)
			(xy 91.246194 -293.551656) (xy 91.23803 -293.60189) (xy 91.221914 -293.650164) (xy 91.198263 -293.695227)
			(xy 91.16769 -293.735913) (xy 91.130986 -293.771168) (xy 91.089102 -293.800078) (xy 91.043123 -293.821895)
			(xy 90.994239 -293.836055) (xy 90.943718 -293.842189) (xy 90.892866 -293.84014) (xy 90.843002 -293.82996)
			(xy 90.795416 -293.811913) (xy 90.751342 -293.786467) (xy 90.71192 -293.75428) (xy 90.678172 -293.716186)
			(xy 90.650971 -293.673172) (xy 90.631023 -293.626352) (xy 90.618844 -293.576938) (xy 90.614749 -293.52621)
			(xy 90.296238 -293.52621) (xy 90.295743 -293.550817) (xy 90.287848 -293.599394) (xy 90.272264 -293.646075)
			(xy 90.249393 -293.689652) (xy 90.219828 -293.728996) (xy 90.184335 -293.763088) (xy 90.143832 -293.791044)
			(xy 90.09937 -293.812142) (xy 90.052099 -293.825834) (xy 90.003244 -293.831766) (xy 89.954069 -293.829785)
			(xy 89.90585 -293.819941) (xy 89.859834 -293.802489) (xy 89.817213 -293.777882) (xy 89.779092 -293.746757)
			(xy 89.746457 -293.70992) (xy 89.720154 -293.668324) (xy 89.700863 -293.623048) (xy 89.689086 -293.575264)
			(xy 89.685126 -293.52621) (xy 89.356438 -293.52621) (xy 89.355943 -293.550817) (xy 89.348048 -293.599394)
			(xy 89.332464 -293.646075) (xy 89.309593 -293.689652) (xy 89.280028 -293.728996) (xy 89.244535 -293.763088)
			(xy 89.204032 -293.791044) (xy 89.15957 -293.812142) (xy 89.112299 -293.825834) (xy 89.063444 -293.831766)
			(xy 89.014269 -293.829785) (xy 88.96605 -293.819941) (xy 88.920034 -293.802489) (xy 88.877413 -293.777882)
			(xy 88.839292 -293.746757) (xy 88.806657 -293.70992) (xy 88.780354 -293.668324) (xy 88.761063 -293.623048)
			(xy 88.749286 -293.575264) (xy 88.745326 -293.52621) (xy 88.416384 -293.52621) (xy 88.415889 -293.550817)
			(xy 88.407994 -293.599394) (xy 88.39241 -293.646075) (xy 88.369539 -293.689652) (xy 88.339974 -293.728996)
			(xy 88.304481 -293.763088) (xy 88.263978 -293.791044) (xy 88.219516 -293.812142) (xy 88.172245 -293.825834)
			(xy 88.12339 -293.831766) (xy 88.074215 -293.829785) (xy 88.025996 -293.819941) (xy 87.97998 -293.802489)
			(xy 87.937359 -293.777882) (xy 87.899238 -293.746757) (xy 87.866603 -293.70992) (xy 87.8403 -293.668324)
			(xy 87.821009 -293.623048) (xy 87.809232 -293.575264) (xy 87.805272 -293.52621) (xy 87.47633 -293.52621)
			(xy 87.475859 -293.550201) (xy 87.468351 -293.597593) (xy 87.453523 -293.643227) (xy 87.43174 -293.68598)
			(xy 87.403537 -293.724799) (xy 87.369608 -293.758729) (xy 87.33079 -293.786933) (xy 87.288038 -293.808719)
			(xy 87.242405 -293.823549) (xy 87.195013 -293.831058) (xy 87.171022 -293.831518) (xy 87.170768 -293.831518)
			(xy 87.148268 -293.831098) (xy 87.103761 -293.82445) (xy 87.060714 -293.811333) (xy 87.040212 -293.802054)
			(xy 87.030052 -293.797228) (xy 87.001604 -293.797228) (xy 86.991534 -293.797651) (xy 86.972931 -293.805368)
			(xy 86.965536 -293.812214) (xy 86.853776 -293.923974) (xy 86.853014 -293.924736) (xy 86.841076 -293.936674)
			(xy 86.835234 -293.966392) (xy 86.838282 -293.974012) (xy 86.84514 -294.042592) (xy 86.846062 -294.049445)
			(xy 86.851086 -294.062323) (xy 86.855046 -294.067992) (xy 86.86038 -294.075358) (xy 86.868 -294.080184)
			(xy 86.888868 -294.094478) (xy 86.926043 -294.128771) (xy 86.957078 -294.168707) (xy 86.981127 -294.2132)
			(xy 86.997538 -294.261041) (xy 87.005863 -294.310928) (xy 87.00643 -294.336216) (xy 88.275172 -294.336216)
			(xy 88.279132 -294.287162) (xy 88.290909 -294.239378) (xy 88.3102 -294.194102) (xy 88.336503 -294.152506)
			(xy 88.369138 -294.115669) (xy 88.407259 -294.084544) (xy 88.44988 -294.059937) (xy 88.495896 -294.042485)
			(xy 88.544115 -294.032641) (xy 88.59329 -294.03066) (xy 88.642145 -294.036592) (xy 88.689416 -294.050284)
			(xy 88.733878 -294.071382) (xy 88.774381 -294.099338) (xy 88.809874 -294.13343) (xy 88.839439 -294.172774)
			(xy 88.86231 -294.216351) (xy 88.877894 -294.263032) (xy 88.885789 -294.311609) (xy 88.886284 -294.336216)
			(xy 89.215226 -294.336216) (xy 89.219186 -294.287162) (xy 89.230963 -294.239378) (xy 89.250254 -294.194102)
			(xy 89.276557 -294.152506) (xy 89.309192 -294.115669) (xy 89.347313 -294.084544) (xy 89.389934 -294.059937)
			(xy 89.43595 -294.042485) (xy 89.484169 -294.032641) (xy 89.533344 -294.03066) (xy 89.582199 -294.036592)
			(xy 89.62947 -294.050284) (xy 89.673932 -294.071382) (xy 89.714435 -294.099338) (xy 89.749928 -294.13343)
			(xy 89.779493 -294.172774) (xy 89.802364 -294.216351) (xy 89.817948 -294.263032) (xy 89.825843 -294.311609)
			(xy 89.826338 -294.336216) (xy 90.15528 -294.336216) (xy 90.15924 -294.287162) (xy 90.171017 -294.239378)
			(xy 90.190308 -294.194102) (xy 90.216611 -294.152506) (xy 90.249246 -294.115669) (xy 90.287367 -294.084544)
			(xy 90.329988 -294.059937) (xy 90.376004 -294.042485) (xy 90.424223 -294.032641) (xy 90.473398 -294.03066)
			(xy 90.522253 -294.036592) (xy 90.569524 -294.050284) (xy 90.613986 -294.071382) (xy 90.654489 -294.099338)
			(xy 90.689982 -294.13343) (xy 90.719547 -294.172774) (xy 90.742418 -294.216351) (xy 90.758002 -294.263032)
			(xy 90.765897 -294.311609) (xy 90.766392 -294.336216) (xy 91.095334 -294.336216) (xy 91.099294 -294.287162)
			(xy 91.111071 -294.239378) (xy 91.130362 -294.194102) (xy 91.156665 -294.152506) (xy 91.1893 -294.115669)
			(xy 91.227421 -294.084544) (xy 91.270042 -294.059937) (xy 91.316058 -294.042485) (xy 91.364277 -294.032641)
			(xy 91.413452 -294.03066) (xy 91.462307 -294.036592) (xy 91.509578 -294.050284) (xy 91.55404 -294.071382)
			(xy 91.594543 -294.099338) (xy 91.630036 -294.13343) (xy 91.659601 -294.172774) (xy 91.682472 -294.216351)
			(xy 91.698056 -294.263032) (xy 91.705951 -294.311609) (xy 91.706446 -294.336216) (xy 92.035134 -294.336216)
			(xy 92.039094 -294.287162) (xy 92.050871 -294.239378) (xy 92.070162 -294.194102) (xy 92.096465 -294.152506)
			(xy 92.1291 -294.115669) (xy 92.167221 -294.084544) (xy 92.209842 -294.059937) (xy 92.255858 -294.042485)
			(xy 92.304077 -294.032641) (xy 92.353252 -294.03066) (xy 92.402107 -294.036592) (xy 92.449378 -294.050284)
			(xy 92.49384 -294.071382) (xy 92.534343 -294.099338) (xy 92.569836 -294.13343) (xy 92.599401 -294.172774)
			(xy 92.622272 -294.216351) (xy 92.637856 -294.263032) (xy 92.645751 -294.311609) (xy 92.646246 -294.336216)
			(xy 92.975188 -294.336216) (xy 92.979148 -294.287162) (xy 92.990925 -294.239378) (xy 93.010216 -294.194102)
			(xy 93.036519 -294.152506) (xy 93.069154 -294.115669) (xy 93.107275 -294.084544) (xy 93.149896 -294.059937)
			(xy 93.195912 -294.042485) (xy 93.244131 -294.032641) (xy 93.293306 -294.03066) (xy 93.342161 -294.036592)
			(xy 93.389432 -294.050284) (xy 93.433894 -294.071382) (xy 93.474397 -294.099338) (xy 93.50989 -294.13343)
			(xy 93.539455 -294.172774) (xy 93.562326 -294.216351) (xy 93.57791 -294.263032) (xy 93.585805 -294.311609)
			(xy 93.5863 -294.336216) (xy 93.915242 -294.336216) (xy 93.919202 -294.287162) (xy 93.930979 -294.239378)
			(xy 93.95027 -294.194102) (xy 93.976573 -294.152506) (xy 94.009208 -294.115669) (xy 94.047329 -294.084544)
			(xy 94.08995 -294.059937) (xy 94.135966 -294.042485) (xy 94.184185 -294.032641) (xy 94.23336 -294.03066)
			(xy 94.282215 -294.036592) (xy 94.329486 -294.050284) (xy 94.373948 -294.071382) (xy 94.414451 -294.099338)
			(xy 94.449944 -294.13343) (xy 94.479509 -294.172774) (xy 94.50238 -294.216351) (xy 94.517964 -294.263032)
			(xy 94.525859 -294.311609) (xy 94.526354 -294.336216) (xy 94.855296 -294.336216) (xy 94.859256 -294.287162)
			(xy 94.871033 -294.239378) (xy 94.890324 -294.194102) (xy 94.916627 -294.152506) (xy 94.949262 -294.115669)
			(xy 94.987383 -294.084544) (xy 95.030004 -294.059937) (xy 95.07602 -294.042485) (xy 95.124239 -294.032641)
			(xy 95.173414 -294.03066) (xy 95.222269 -294.036592) (xy 95.26954 -294.050284) (xy 95.314002 -294.071382)
			(xy 95.354505 -294.099338) (xy 95.389998 -294.13343) (xy 95.419563 -294.172774) (xy 95.442434 -294.216351)
			(xy 95.458018 -294.263032) (xy 95.465913 -294.311609) (xy 95.466408 -294.336216) (xy 95.465913 -294.360823)
			(xy 95.458018 -294.4094) (xy 95.442434 -294.456081) (xy 95.419563 -294.499658) (xy 95.389998 -294.539002)
			(xy 95.354505 -294.573094) (xy 95.314002 -294.60105) (xy 95.26954 -294.622148) (xy 95.222269 -294.63584)
			(xy 95.173414 -294.641772) (xy 95.124239 -294.639791) (xy 95.07602 -294.629947) (xy 95.030004 -294.612495)
			(xy 94.987383 -294.587888) (xy 94.949262 -294.556763) (xy 94.916627 -294.519926) (xy 94.890324 -294.47833)
			(xy 94.871033 -294.433054) (xy 94.859256 -294.38527) (xy 94.855296 -294.336216) (xy 94.526354 -294.336216)
			(xy 94.525859 -294.360823) (xy 94.517964 -294.4094) (xy 94.50238 -294.456081) (xy 94.479509 -294.499658)
			(xy 94.449944 -294.539002) (xy 94.414451 -294.573094) (xy 94.373948 -294.60105) (xy 94.329486 -294.622148)
			(xy 94.282215 -294.63584) (xy 94.23336 -294.641772) (xy 94.184185 -294.639791) (xy 94.135966 -294.629947)
			(xy 94.08995 -294.612495) (xy 94.047329 -294.587888) (xy 94.009208 -294.556763) (xy 93.976573 -294.519926)
			(xy 93.95027 -294.47833) (xy 93.930979 -294.433054) (xy 93.919202 -294.38527) (xy 93.915242 -294.336216)
			(xy 93.5863 -294.336216) (xy 93.585805 -294.360823) (xy 93.57791 -294.4094) (xy 93.562326 -294.456081)
			(xy 93.539455 -294.499658) (xy 93.50989 -294.539002) (xy 93.474397 -294.573094) (xy 93.433894 -294.60105)
			(xy 93.389432 -294.622148) (xy 93.342161 -294.63584) (xy 93.293306 -294.641772) (xy 93.244131 -294.639791)
			(xy 93.195912 -294.629947) (xy 93.149896 -294.612495) (xy 93.107275 -294.587888) (xy 93.069154 -294.556763)
			(xy 93.036519 -294.519926) (xy 93.010216 -294.47833) (xy 92.990925 -294.433054) (xy 92.979148 -294.38527)
			(xy 92.975188 -294.336216) (xy 92.646246 -294.336216) (xy 92.645751 -294.360823) (xy 92.637856 -294.4094)
			(xy 92.622272 -294.456081) (xy 92.599401 -294.499658) (xy 92.569836 -294.539002) (xy 92.534343 -294.573094)
			(xy 92.49384 -294.60105) (xy 92.449378 -294.622148) (xy 92.402107 -294.63584) (xy 92.353252 -294.641772)
			(xy 92.304077 -294.639791) (xy 92.255858 -294.629947) (xy 92.209842 -294.612495) (xy 92.167221 -294.587888)
			(xy 92.1291 -294.556763) (xy 92.096465 -294.519926) (xy 92.070162 -294.47833) (xy 92.050871 -294.433054)
			(xy 92.039094 -294.38527) (xy 92.035134 -294.336216) (xy 91.706446 -294.336216) (xy 91.705951 -294.360823)
			(xy 91.698056 -294.4094) (xy 91.682472 -294.456081) (xy 91.659601 -294.499658) (xy 91.630036 -294.539002)
			(xy 91.594543 -294.573094) (xy 91.55404 -294.60105) (xy 91.509578 -294.622148) (xy 91.462307 -294.63584)
			(xy 91.413452 -294.641772) (xy 91.364277 -294.639791) (xy 91.316058 -294.629947) (xy 91.270042 -294.612495)
			(xy 91.227421 -294.587888) (xy 91.1893 -294.556763) (xy 91.156665 -294.519926) (xy 91.130362 -294.47833)
			(xy 91.111071 -294.433054) (xy 91.099294 -294.38527) (xy 91.095334 -294.336216) (xy 90.766392 -294.336216)
			(xy 90.765897 -294.360823) (xy 90.758002 -294.4094) (xy 90.742418 -294.456081) (xy 90.719547 -294.499658)
			(xy 90.689982 -294.539002) (xy 90.654489 -294.573094) (xy 90.613986 -294.60105) (xy 90.569524 -294.622148)
			(xy 90.522253 -294.63584) (xy 90.473398 -294.641772) (xy 90.424223 -294.639791) (xy 90.376004 -294.629947)
			(xy 90.329988 -294.612495) (xy 90.287367 -294.587888) (xy 90.249246 -294.556763) (xy 90.216611 -294.519926)
			(xy 90.190308 -294.47833) (xy 90.171017 -294.433054) (xy 90.15924 -294.38527) (xy 90.15528 -294.336216)
			(xy 89.826338 -294.336216) (xy 89.825843 -294.360823) (xy 89.817948 -294.4094) (xy 89.802364 -294.456081)
			(xy 89.779493 -294.499658) (xy 89.749928 -294.539002) (xy 89.714435 -294.573094) (xy 89.673932 -294.60105)
			(xy 89.62947 -294.622148) (xy 89.582199 -294.63584) (xy 89.533344 -294.641772) (xy 89.484169 -294.639791)
			(xy 89.43595 -294.629947) (xy 89.389934 -294.612495) (xy 89.347313 -294.587888) (xy 89.309192 -294.556763)
			(xy 89.276557 -294.519926) (xy 89.250254 -294.47833) (xy 89.230963 -294.433054) (xy 89.219186 -294.38527)
			(xy 89.215226 -294.336216) (xy 88.886284 -294.336216) (xy 88.885789 -294.360823) (xy 88.877894 -294.4094)
			(xy 88.86231 -294.456081) (xy 88.839439 -294.499658) (xy 88.809874 -294.539002) (xy 88.774381 -294.573094)
			(xy 88.733878 -294.60105) (xy 88.689416 -294.622148) (xy 88.642145 -294.63584) (xy 88.59329 -294.641772)
			(xy 88.544115 -294.639791) (xy 88.495896 -294.629947) (xy 88.44988 -294.612495) (xy 88.407259 -294.587888)
			(xy 88.369138 -294.556763) (xy 88.336503 -294.519926) (xy 88.3102 -294.47833) (xy 88.290909 -294.433054)
			(xy 88.279132 -294.38527) (xy 88.275172 -294.336216) (xy 87.00643 -294.336216) (xy 87.005958 -294.360207)
			(xy 86.99845 -294.407598) (xy 86.983622 -294.453231) (xy 86.961838 -294.495983) (xy 86.933634 -294.534802)
			(xy 86.899706 -294.56873) (xy 86.860889 -294.596935) (xy 86.818137 -294.618719) (xy 86.772504 -294.633549)
			(xy 86.725113 -294.641058) (xy 86.701122 -294.641524) (xy 86.67583 -294.641004) (xy 86.625935 -294.632687)
			(xy 86.578088 -294.616275) (xy 86.533592 -294.592216) (xy 86.493661 -294.561165) (xy 86.459381 -294.523968)
			(xy 86.44509 -294.503094) (xy 86.43874 -294.493442) (xy 86.41969 -294.481758) (xy 86.369906 -294.476424)
			(xy 86.369398 -294.476424) (xy 86.33079 -294.472868) (xy 86.319575 -294.472451) (xy 86.298505 -294.480104)
			(xy 86.29015 -294.4876) (xy 85.631528 -295.146222) (xy 85.925164 -295.146222) (xy 85.929124 -295.097168)
			(xy 85.940901 -295.049384) (xy 85.960192 -295.004108) (xy 85.986495 -294.962512) (xy 86.01913 -294.925675)
			(xy 86.057251 -294.89455) (xy 86.099872 -294.869943) (xy 86.145888 -294.852491) (xy 86.194107 -294.842647)
			(xy 86.243282 -294.840666) (xy 86.292137 -294.846598) (xy 86.339408 -294.86029) (xy 86.38387 -294.881388)
			(xy 86.424373 -294.909344) (xy 86.459866 -294.943436) (xy 86.489431 -294.98278) (xy 86.512302 -295.026357)
			(xy 86.527886 -295.073038) (xy 86.535781 -295.121615) (xy 86.536276 -295.146222) (xy 86.865218 -295.146222)
			(xy 86.869178 -295.097168) (xy 86.880955 -295.049384) (xy 86.900246 -295.004108) (xy 86.926549 -294.962512)
			(xy 86.959184 -294.925675) (xy 86.997305 -294.89455) (xy 87.039926 -294.869943) (xy 87.085942 -294.852491)
			(xy 87.134161 -294.842647) (xy 87.183336 -294.840666) (xy 87.232191 -294.846598) (xy 87.279462 -294.86029)
			(xy 87.323924 -294.881388) (xy 87.364427 -294.909344) (xy 87.39992 -294.943436) (xy 87.429485 -294.98278)
			(xy 87.452356 -295.026357) (xy 87.46794 -295.073038) (xy 87.475835 -295.121615) (xy 87.47633 -295.146222)
			(xy 87.805272 -295.146222) (xy 87.809232 -295.097168) (xy 87.821009 -295.049384) (xy 87.8403 -295.004108)
			(xy 87.866603 -294.962512) (xy 87.899238 -294.925675) (xy 87.937359 -294.89455) (xy 87.97998 -294.869943)
			(xy 88.025996 -294.852491) (xy 88.074215 -294.842647) (xy 88.12339 -294.840666) (xy 88.172245 -294.846598)
			(xy 88.219516 -294.86029) (xy 88.263978 -294.881388) (xy 88.304481 -294.909344) (xy 88.339974 -294.943436)
			(xy 88.369539 -294.98278) (xy 88.39241 -295.026357) (xy 88.407994 -295.073038) (xy 88.415889 -295.121615)
			(xy 88.416384 -295.146222) (xy 88.745326 -295.146222) (xy 88.749286 -295.097168) (xy 88.761063 -295.049384)
			(xy 88.780354 -295.004108) (xy 88.806657 -294.962512) (xy 88.839292 -294.925675) (xy 88.877413 -294.89455)
			(xy 88.920034 -294.869943) (xy 88.96605 -294.852491) (xy 89.014269 -294.842647) (xy 89.063444 -294.840666)
			(xy 89.112299 -294.846598) (xy 89.15957 -294.86029) (xy 89.204032 -294.881388) (xy 89.244535 -294.909344)
			(xy 89.280028 -294.943436) (xy 89.309593 -294.98278) (xy 89.332464 -295.026357) (xy 89.348048 -295.073038)
			(xy 89.355943 -295.121615) (xy 89.356438 -295.146222) (xy 89.685126 -295.146222) (xy 89.689086 -295.097168)
			(xy 89.700863 -295.049384) (xy 89.720154 -295.004108) (xy 89.746457 -294.962512) (xy 89.779092 -294.925675)
			(xy 89.817213 -294.89455) (xy 89.859834 -294.869943) (xy 89.90585 -294.852491) (xy 89.954069 -294.842647)
			(xy 90.003244 -294.840666) (xy 90.052099 -294.846598) (xy 90.09937 -294.86029) (xy 90.143832 -294.881388)
			(xy 90.184335 -294.909344) (xy 90.219828 -294.943436) (xy 90.249393 -294.98278) (xy 90.272264 -295.026357)
			(xy 90.287848 -295.073038) (xy 90.295743 -295.121615) (xy 90.296238 -295.146222) (xy 90.62518 -295.146222)
			(xy 90.62914 -295.097168) (xy 90.640917 -295.049384) (xy 90.660208 -295.004108) (xy 90.686511 -294.962512)
			(xy 90.719146 -294.925675) (xy 90.757267 -294.89455) (xy 90.799888 -294.869943) (xy 90.845904 -294.852491)
			(xy 90.894123 -294.842647) (xy 90.943298 -294.840666) (xy 90.992153 -294.846598) (xy 91.039424 -294.86029)
			(xy 91.083886 -294.881388) (xy 91.124389 -294.909344) (xy 91.159882 -294.943436) (xy 91.189447 -294.98278)
			(xy 91.212318 -295.026357) (xy 91.227902 -295.073038) (xy 91.235797 -295.121615) (xy 91.236292 -295.146222)
			(xy 91.565234 -295.146222) (xy 91.569194 -295.097168) (xy 91.580971 -295.049384) (xy 91.600262 -295.004108)
			(xy 91.626565 -294.962512) (xy 91.6592 -294.925675) (xy 91.697321 -294.89455) (xy 91.739942 -294.869943)
			(xy 91.785958 -294.852491) (xy 91.834177 -294.842647) (xy 91.883352 -294.840666) (xy 91.932207 -294.846598)
			(xy 91.979478 -294.86029) (xy 92.02394 -294.881388) (xy 92.064443 -294.909344) (xy 92.099936 -294.943436)
			(xy 92.129501 -294.98278) (xy 92.152372 -295.026357) (xy 92.167956 -295.073038) (xy 92.175851 -295.121615)
			(xy 92.176346 -295.146222) (xy 92.505288 -295.146222) (xy 92.509248 -295.097168) (xy 92.521025 -295.049384)
			(xy 92.540316 -295.004108) (xy 92.566619 -294.962512) (xy 92.599254 -294.925675) (xy 92.637375 -294.89455)
			(xy 92.679996 -294.869943) (xy 92.726012 -294.852491) (xy 92.774231 -294.842647) (xy 92.823406 -294.840666)
			(xy 92.872261 -294.846598) (xy 92.919532 -294.86029) (xy 92.963994 -294.881388) (xy 93.004497 -294.909344)
			(xy 93.03999 -294.943436) (xy 93.069555 -294.98278) (xy 93.092426 -295.026357) (xy 93.10801 -295.073038)
			(xy 93.115905 -295.121615) (xy 93.1164 -295.146222) (xy 93.445342 -295.146222) (xy 93.449302 -295.097168)
			(xy 93.461079 -295.049384) (xy 93.48037 -295.004108) (xy 93.506673 -294.962512) (xy 93.539308 -294.925675)
			(xy 93.577429 -294.89455) (xy 93.62005 -294.869943) (xy 93.666066 -294.852491) (xy 93.714285 -294.842647)
			(xy 93.76346 -294.840666) (xy 93.812315 -294.846598) (xy 93.859586 -294.86029) (xy 93.904048 -294.881388)
			(xy 93.944551 -294.909344) (xy 93.980044 -294.943436) (xy 94.009609 -294.98278) (xy 94.03248 -295.026357)
			(xy 94.048064 -295.073038) (xy 94.055959 -295.121615) (xy 94.056454 -295.146222) (xy 94.385142 -295.146222)
			(xy 94.389102 -295.097168) (xy 94.400879 -295.049384) (xy 94.42017 -295.004108) (xy 94.446473 -294.962512)
			(xy 94.479108 -294.925675) (xy 94.517229 -294.89455) (xy 94.55985 -294.869943) (xy 94.605866 -294.852491)
			(xy 94.654085 -294.842647) (xy 94.70326 -294.840666) (xy 94.752115 -294.846598) (xy 94.799386 -294.86029)
			(xy 94.843848 -294.881388) (xy 94.884351 -294.909344) (xy 94.919844 -294.943436) (xy 94.949409 -294.98278)
			(xy 94.97228 -295.026357) (xy 94.987864 -295.073038) (xy 94.995759 -295.121615) (xy 94.996254 -295.146222)
			(xy 95.325196 -295.146222) (xy 95.329156 -295.097168) (xy 95.340933 -295.049384) (xy 95.360224 -295.004108)
			(xy 95.386527 -294.962512) (xy 95.419162 -294.925675) (xy 95.457283 -294.89455) (xy 95.499904 -294.869943)
			(xy 95.54592 -294.852491) (xy 95.594139 -294.842647) (xy 95.643314 -294.840666) (xy 95.692169 -294.846598)
			(xy 95.73944 -294.86029) (xy 95.783902 -294.881388) (xy 95.824405 -294.909344) (xy 95.859898 -294.943436)
			(xy 95.889463 -294.98278) (xy 95.912334 -295.026357) (xy 95.927918 -295.073038) (xy 95.935813 -295.121615)
			(xy 95.936308 -295.146222) (xy 95.935813 -295.170829) (xy 95.927918 -295.219406) (xy 95.912334 -295.266087)
			(xy 95.889463 -295.309664) (xy 95.859898 -295.349008) (xy 95.824405 -295.3831) (xy 95.783902 -295.411056)
			(xy 95.73944 -295.432154) (xy 95.692169 -295.445846) (xy 95.643314 -295.451778) (xy 95.594139 -295.449797)
			(xy 95.54592 -295.439953) (xy 95.499904 -295.422501) (xy 95.457283 -295.397894) (xy 95.419162 -295.366769)
			(xy 95.386527 -295.329932) (xy 95.360224 -295.288336) (xy 95.340933 -295.24306) (xy 95.329156 -295.195276)
			(xy 95.325196 -295.146222) (xy 94.996254 -295.146222) (xy 94.995759 -295.170829) (xy 94.987864 -295.219406)
			(xy 94.97228 -295.266087) (xy 94.949409 -295.309664) (xy 94.919844 -295.349008) (xy 94.884351 -295.3831)
			(xy 94.843848 -295.411056) (xy 94.799386 -295.432154) (xy 94.752115 -295.445846) (xy 94.70326 -295.451778)
			(xy 94.654085 -295.449797) (xy 94.605866 -295.439953) (xy 94.55985 -295.422501) (xy 94.517229 -295.397894)
			(xy 94.479108 -295.366769) (xy 94.446473 -295.329932) (xy 94.42017 -295.288336) (xy 94.400879 -295.24306)
			(xy 94.389102 -295.195276) (xy 94.385142 -295.146222) (xy 94.056454 -295.146222) (xy 94.055959 -295.170829)
			(xy 94.048064 -295.219406) (xy 94.03248 -295.266087) (xy 94.009609 -295.309664) (xy 93.980044 -295.349008)
			(xy 93.944551 -295.3831) (xy 93.904048 -295.411056) (xy 93.859586 -295.432154) (xy 93.812315 -295.445846)
			(xy 93.76346 -295.451778) (xy 93.714285 -295.449797) (xy 93.666066 -295.439953) (xy 93.62005 -295.422501)
			(xy 93.577429 -295.397894) (xy 93.539308 -295.366769) (xy 93.506673 -295.329932) (xy 93.48037 -295.288336)
			(xy 93.461079 -295.24306) (xy 93.449302 -295.195276) (xy 93.445342 -295.146222) (xy 93.1164 -295.146222)
			(xy 93.115905 -295.170829) (xy 93.10801 -295.219406) (xy 93.092426 -295.266087) (xy 93.069555 -295.309664)
			(xy 93.03999 -295.349008) (xy 93.004497 -295.3831) (xy 92.963994 -295.411056) (xy 92.919532 -295.432154)
			(xy 92.872261 -295.445846) (xy 92.823406 -295.451778) (xy 92.774231 -295.449797) (xy 92.726012 -295.439953)
			(xy 92.679996 -295.422501) (xy 92.637375 -295.397894) (xy 92.599254 -295.366769) (xy 92.566619 -295.329932)
			(xy 92.540316 -295.288336) (xy 92.521025 -295.24306) (xy 92.509248 -295.195276) (xy 92.505288 -295.146222)
			(xy 92.176346 -295.146222) (xy 92.175851 -295.170829) (xy 92.167956 -295.219406) (xy 92.152372 -295.266087)
			(xy 92.129501 -295.309664) (xy 92.099936 -295.349008) (xy 92.064443 -295.3831) (xy 92.02394 -295.411056)
			(xy 91.979478 -295.432154) (xy 91.932207 -295.445846) (xy 91.883352 -295.451778) (xy 91.834177 -295.449797)
			(xy 91.785958 -295.439953) (xy 91.739942 -295.422501) (xy 91.697321 -295.397894) (xy 91.6592 -295.366769)
			(xy 91.626565 -295.329932) (xy 91.600262 -295.288336) (xy 91.580971 -295.24306) (xy 91.569194 -295.195276)
			(xy 91.565234 -295.146222) (xy 91.236292 -295.146222) (xy 91.235797 -295.170829) (xy 91.227902 -295.219406)
			(xy 91.212318 -295.266087) (xy 91.189447 -295.309664) (xy 91.159882 -295.349008) (xy 91.124389 -295.3831)
			(xy 91.083886 -295.411056) (xy 91.039424 -295.432154) (xy 90.992153 -295.445846) (xy 90.943298 -295.451778)
			(xy 90.894123 -295.449797) (xy 90.845904 -295.439953) (xy 90.799888 -295.422501) (xy 90.757267 -295.397894)
			(xy 90.719146 -295.366769) (xy 90.686511 -295.329932) (xy 90.660208 -295.288336) (xy 90.640917 -295.24306)
			(xy 90.62914 -295.195276) (xy 90.62518 -295.146222) (xy 90.296238 -295.146222) (xy 90.295743 -295.170829)
			(xy 90.287848 -295.219406) (xy 90.272264 -295.266087) (xy 90.249393 -295.309664) (xy 90.219828 -295.349008)
			(xy 90.184335 -295.3831) (xy 90.143832 -295.411056) (xy 90.09937 -295.432154) (xy 90.052099 -295.445846)
			(xy 90.003244 -295.451778) (xy 89.954069 -295.449797) (xy 89.90585 -295.439953) (xy 89.859834 -295.422501)
			(xy 89.817213 -295.397894) (xy 89.779092 -295.366769) (xy 89.746457 -295.329932) (xy 89.720154 -295.288336)
			(xy 89.700863 -295.24306) (xy 89.689086 -295.195276) (xy 89.685126 -295.146222) (xy 89.356438 -295.146222)
			(xy 89.355943 -295.170829) (xy 89.348048 -295.219406) (xy 89.332464 -295.266087) (xy 89.309593 -295.309664)
			(xy 89.280028 -295.349008) (xy 89.244535 -295.3831) (xy 89.204032 -295.411056) (xy 89.15957 -295.432154)
			(xy 89.112299 -295.445846) (xy 89.063444 -295.451778) (xy 89.014269 -295.449797) (xy 88.96605 -295.439953)
			(xy 88.920034 -295.422501) (xy 88.877413 -295.397894) (xy 88.839292 -295.366769) (xy 88.806657 -295.329932)
			(xy 88.780354 -295.288336) (xy 88.761063 -295.24306) (xy 88.749286 -295.195276) (xy 88.745326 -295.146222)
			(xy 88.416384 -295.146222) (xy 88.415889 -295.170829) (xy 88.407994 -295.219406) (xy 88.39241 -295.266087)
			(xy 88.369539 -295.309664) (xy 88.339974 -295.349008) (xy 88.304481 -295.3831) (xy 88.263978 -295.411056)
			(xy 88.219516 -295.432154) (xy 88.172245 -295.445846) (xy 88.12339 -295.451778) (xy 88.074215 -295.449797)
			(xy 88.025996 -295.439953) (xy 87.97998 -295.422501) (xy 87.937359 -295.397894) (xy 87.899238 -295.366769)
			(xy 87.866603 -295.329932) (xy 87.8403 -295.288336) (xy 87.821009 -295.24306) (xy 87.809232 -295.195276)
			(xy 87.805272 -295.146222) (xy 87.47633 -295.146222) (xy 87.475835 -295.170829) (xy 87.46794 -295.219406)
			(xy 87.452356 -295.266087) (xy 87.429485 -295.309664) (xy 87.39992 -295.349008) (xy 87.364427 -295.3831)
			(xy 87.323924 -295.411056) (xy 87.279462 -295.432154) (xy 87.232191 -295.445846) (xy 87.183336 -295.451778)
			(xy 87.134161 -295.449797) (xy 87.085942 -295.439953) (xy 87.039926 -295.422501) (xy 86.997305 -295.397894)
			(xy 86.959184 -295.366769) (xy 86.926549 -295.329932) (xy 86.900246 -295.288336) (xy 86.880955 -295.24306)
			(xy 86.869178 -295.195276) (xy 86.865218 -295.146222) (xy 86.536276 -295.146222) (xy 86.535781 -295.170829)
			(xy 86.527886 -295.219406) (xy 86.512302 -295.266087) (xy 86.489431 -295.309664) (xy 86.459866 -295.349008)
			(xy 86.424373 -295.3831) (xy 86.38387 -295.411056) (xy 86.339408 -295.432154) (xy 86.292137 -295.445846)
			(xy 86.243282 -295.451778) (xy 86.194107 -295.449797) (xy 86.145888 -295.439953) (xy 86.099872 -295.422501)
			(xy 86.057251 -295.397894) (xy 86.01913 -295.366769) (xy 85.986495 -295.329932) (xy 85.960192 -295.288336)
			(xy 85.940901 -295.24306) (xy 85.929124 -295.195276) (xy 85.925164 -295.146222) (xy 85.631528 -295.146222)
			(xy 85.611208 -295.166542) (xy 85.608502 -295.169322) (xy 85.603916 -295.175579) (xy 85.602064 -295.178988)
			(xy 85.591904 -295.1988) (xy 85.59038 -295.205912) (xy 85.584791 -295.231286) (xy 85.566165 -295.279785)
			(xy 85.539603 -295.324435) (xy 85.505872 -295.363949) (xy 85.465944 -295.397188) (xy 85.420969 -295.423196)
			(xy 85.372243 -295.441221) (xy 85.346794 -295.44645) (xy 85.34654 -295.44645) (xy 85.34273 -295.447212)
			(xy 85.33003 -295.45153) (xy 85.320124 -295.457626) (xy 85.315806 -295.461944) (xy 85.119718 -295.658032)
			(xy 85.112606 -295.663874) (xy 85.101454 -295.672113) (xy 85.083685 -295.693382) (xy 85.072291 -295.718647)
			(xy 85.068112 -295.746044) (xy 85.071455 -295.773557) (xy 85.076284 -295.786556) (xy 85.080094 -295.793668)
			(xy 85.082634 -295.79824) (xy 85.084412 -295.80205) (xy 85.097343 -295.82523) (xy 85.115868 -295.874966)
			(xy 85.125511 -295.927157) (xy 85.126322 -295.953688) (xy 85.126322 -295.955466) (xy 85.126322 -295.956228)
			(xy 85.455264 -295.956228) (xy 85.459224 -295.907174) (xy 85.471001 -295.85939) (xy 85.490292 -295.814114)
			(xy 85.516595 -295.772518) (xy 85.54923 -295.735681) (xy 85.587351 -295.704556) (xy 85.629972 -295.679949)
			(xy 85.675988 -295.662497) (xy 85.724207 -295.652653) (xy 85.773382 -295.650672) (xy 85.822237 -295.656604)
			(xy 85.869508 -295.670296) (xy 85.91397 -295.691394) (xy 85.954473 -295.71935) (xy 85.989966 -295.753442)
			(xy 86.019531 -295.792786) (xy 86.042402 -295.836363) (xy 86.057986 -295.883044) (xy 86.065881 -295.931621)
			(xy 86.066376 -295.956228) (xy 86.395318 -295.956228) (xy 86.399278 -295.907174) (xy 86.411055 -295.85939)
			(xy 86.430346 -295.814114) (xy 86.456649 -295.772518) (xy 86.489284 -295.735681) (xy 86.527405 -295.704556)
			(xy 86.570026 -295.679949) (xy 86.616042 -295.662497) (xy 86.664261 -295.652653) (xy 86.713436 -295.650672)
			(xy 86.762291 -295.656604) (xy 86.809562 -295.670296) (xy 86.854024 -295.691394) (xy 86.894527 -295.71935)
			(xy 86.93002 -295.753442) (xy 86.959585 -295.792786) (xy 86.982456 -295.836363) (xy 86.99804 -295.883044)
			(xy 87.005935 -295.931621) (xy 87.00643 -295.956228) (xy 88.275172 -295.956228) (xy 88.279132 -295.907174)
			(xy 88.290909 -295.85939) (xy 88.3102 -295.814114) (xy 88.336503 -295.772518) (xy 88.369138 -295.735681)
			(xy 88.407259 -295.704556) (xy 88.44988 -295.679949) (xy 88.495896 -295.662497) (xy 88.544115 -295.652653)
			(xy 88.59329 -295.650672) (xy 88.642145 -295.656604) (xy 88.689416 -295.670296) (xy 88.733878 -295.691394)
			(xy 88.774381 -295.71935) (xy 88.809874 -295.753442) (xy 88.839439 -295.792786) (xy 88.86231 -295.836363)
			(xy 88.877894 -295.883044) (xy 88.885789 -295.931621) (xy 88.886284 -295.956228) (xy 89.215226 -295.956228)
			(xy 89.219186 -295.907174) (xy 89.230963 -295.85939) (xy 89.250254 -295.814114) (xy 89.276557 -295.772518)
			(xy 89.309192 -295.735681) (xy 89.347313 -295.704556) (xy 89.389934 -295.679949) (xy 89.43595 -295.662497)
			(xy 89.484169 -295.652653) (xy 89.533344 -295.650672) (xy 89.582199 -295.656604) (xy 89.62947 -295.670296)
			(xy 89.673932 -295.691394) (xy 89.714435 -295.71935) (xy 89.749928 -295.753442) (xy 89.779493 -295.792786)
			(xy 89.802364 -295.836363) (xy 89.817948 -295.883044) (xy 89.825843 -295.931621) (xy 89.826338 -295.956228)
			(xy 90.15528 -295.956228) (xy 90.15924 -295.907174) (xy 90.171017 -295.85939) (xy 90.190308 -295.814114)
			(xy 90.216611 -295.772518) (xy 90.249246 -295.735681) (xy 90.287367 -295.704556) (xy 90.329988 -295.679949)
			(xy 90.376004 -295.662497) (xy 90.424223 -295.652653) (xy 90.473398 -295.650672) (xy 90.522253 -295.656604)
			(xy 90.569524 -295.670296) (xy 90.613986 -295.691394) (xy 90.654489 -295.71935) (xy 90.689982 -295.753442)
			(xy 90.719547 -295.792786) (xy 90.742418 -295.836363) (xy 90.758002 -295.883044) (xy 90.765897 -295.931621)
			(xy 90.766392 -295.956228) (xy 91.095334 -295.956228) (xy 91.099294 -295.907174) (xy 91.111071 -295.85939)
			(xy 91.130362 -295.814114) (xy 91.156665 -295.772518) (xy 91.1893 -295.735681) (xy 91.227421 -295.704556)
			(xy 91.270042 -295.679949) (xy 91.316058 -295.662497) (xy 91.364277 -295.652653) (xy 91.413452 -295.650672)
			(xy 91.462307 -295.656604) (xy 91.509578 -295.670296) (xy 91.55404 -295.691394) (xy 91.594543 -295.71935)
			(xy 91.630036 -295.753442) (xy 91.659601 -295.792786) (xy 91.682472 -295.836363) (xy 91.698056 -295.883044)
			(xy 91.705951 -295.931621) (xy 91.706446 -295.956228) (xy 92.035134 -295.956228) (xy 92.039094 -295.907174)
			(xy 92.050871 -295.85939) (xy 92.070162 -295.814114) (xy 92.096465 -295.772518) (xy 92.1291 -295.735681)
			(xy 92.167221 -295.704556) (xy 92.209842 -295.679949) (xy 92.255858 -295.662497) (xy 92.304077 -295.652653)
			(xy 92.353252 -295.650672) (xy 92.402107 -295.656604) (xy 92.449378 -295.670296) (xy 92.49384 -295.691394)
			(xy 92.534343 -295.71935) (xy 92.569836 -295.753442) (xy 92.599401 -295.792786) (xy 92.622272 -295.836363)
			(xy 92.637856 -295.883044) (xy 92.645751 -295.931621) (xy 92.646246 -295.956228) (xy 94.855296 -295.956228)
			(xy 94.859256 -295.907174) (xy 94.871033 -295.85939) (xy 94.890324 -295.814114) (xy 94.916627 -295.772518)
			(xy 94.949262 -295.735681) (xy 94.987383 -295.704556) (xy 95.030004 -295.679949) (xy 95.07602 -295.662497)
			(xy 95.124239 -295.652653) (xy 95.173414 -295.650672) (xy 95.222269 -295.656604) (xy 95.26954 -295.670296)
			(xy 95.314002 -295.691394) (xy 95.354505 -295.71935) (xy 95.389998 -295.753442) (xy 95.419563 -295.792786)
			(xy 95.442434 -295.836363) (xy 95.458018 -295.883044) (xy 95.465913 -295.931621) (xy 95.466408 -295.956228)
			(xy 95.465913 -295.980835) (xy 95.458018 -296.029412) (xy 95.442434 -296.076093) (xy 95.419563 -296.11967)
			(xy 95.389998 -296.159014) (xy 95.354505 -296.193106) (xy 95.314002 -296.221062) (xy 95.26954 -296.24216)
			(xy 95.222269 -296.255852) (xy 95.173414 -296.261784) (xy 95.124239 -296.259803) (xy 95.07602 -296.249959)
			(xy 95.030004 -296.232507) (xy 94.987383 -296.2079) (xy 94.949262 -296.176775) (xy 94.916627 -296.139938)
			(xy 94.890324 -296.098342) (xy 94.871033 -296.053066) (xy 94.859256 -296.005282) (xy 94.855296 -295.956228)
			(xy 92.646246 -295.956228) (xy 92.645751 -295.980835) (xy 92.637856 -296.029412) (xy 92.622272 -296.076093)
			(xy 92.599401 -296.11967) (xy 92.569836 -296.159014) (xy 92.534343 -296.193106) (xy 92.49384 -296.221062)
			(xy 92.449378 -296.24216) (xy 92.402107 -296.255852) (xy 92.353252 -296.261784) (xy 92.304077 -296.259803)
			(xy 92.255858 -296.249959) (xy 92.209842 -296.232507) (xy 92.167221 -296.2079) (xy 92.1291 -296.176775)
			(xy 92.096465 -296.139938) (xy 92.070162 -296.098342) (xy 92.050871 -296.053066) (xy 92.039094 -296.005282)
			(xy 92.035134 -295.956228) (xy 91.706446 -295.956228) (xy 91.705951 -295.980835) (xy 91.698056 -296.029412)
			(xy 91.682472 -296.076093) (xy 91.659601 -296.11967) (xy 91.630036 -296.159014) (xy 91.594543 -296.193106)
			(xy 91.55404 -296.221062) (xy 91.509578 -296.24216) (xy 91.462307 -296.255852) (xy 91.413452 -296.261784)
			(xy 91.364277 -296.259803) (xy 91.316058 -296.249959) (xy 91.270042 -296.232507) (xy 91.227421 -296.2079)
			(xy 91.1893 -296.176775) (xy 91.156665 -296.139938) (xy 91.130362 -296.098342) (xy 91.111071 -296.053066)
			(xy 91.099294 -296.005282) (xy 91.095334 -295.956228) (xy 90.766392 -295.956228) (xy 90.765897 -295.980835)
			(xy 90.758002 -296.029412) (xy 90.742418 -296.076093) (xy 90.719547 -296.11967) (xy 90.689982 -296.159014)
			(xy 90.654489 -296.193106) (xy 90.613986 -296.221062) (xy 90.569524 -296.24216) (xy 90.522253 -296.255852)
			(xy 90.473398 -296.261784) (xy 90.424223 -296.259803) (xy 90.376004 -296.249959) (xy 90.329988 -296.232507)
			(xy 90.287367 -296.2079) (xy 90.249246 -296.176775) (xy 90.216611 -296.139938) (xy 90.190308 -296.098342)
			(xy 90.171017 -296.053066) (xy 90.15924 -296.005282) (xy 90.15528 -295.956228) (xy 89.826338 -295.956228)
			(xy 89.825843 -295.980835) (xy 89.817948 -296.029412) (xy 89.802364 -296.076093) (xy 89.779493 -296.11967)
			(xy 89.749928 -296.159014) (xy 89.714435 -296.193106) (xy 89.673932 -296.221062) (xy 89.62947 -296.24216)
			(xy 89.582199 -296.255852) (xy 89.533344 -296.261784) (xy 89.484169 -296.259803) (xy 89.43595 -296.249959)
			(xy 89.389934 -296.232507) (xy 89.347313 -296.2079) (xy 89.309192 -296.176775) (xy 89.276557 -296.139938)
			(xy 89.250254 -296.098342) (xy 89.230963 -296.053066) (xy 89.219186 -296.005282) (xy 89.215226 -295.956228)
			(xy 88.886284 -295.956228) (xy 88.885789 -295.980835) (xy 88.877894 -296.029412) (xy 88.86231 -296.076093)
			(xy 88.839439 -296.11967) (xy 88.809874 -296.159014) (xy 88.774381 -296.193106) (xy 88.733878 -296.221062)
			(xy 88.689416 -296.24216) (xy 88.642145 -296.255852) (xy 88.59329 -296.261784) (xy 88.544115 -296.259803)
			(xy 88.495896 -296.249959) (xy 88.44988 -296.232507) (xy 88.407259 -296.2079) (xy 88.369138 -296.176775)
			(xy 88.336503 -296.139938) (xy 88.3102 -296.098342) (xy 88.290909 -296.053066) (xy 88.279132 -296.005282)
			(xy 88.275172 -295.956228) (xy 87.00643 -295.956228) (xy 87.005935 -295.980835) (xy 86.99804 -296.029412)
			(xy 86.982456 -296.076093) (xy 86.959585 -296.11967) (xy 86.93002 -296.159014) (xy 86.894527 -296.193106)
			(xy 86.854024 -296.221062) (xy 86.809562 -296.24216) (xy 86.762291 -296.255852) (xy 86.713436 -296.261784)
			(xy 86.664261 -296.259803) (xy 86.616042 -296.249959) (xy 86.570026 -296.232507) (xy 86.527405 -296.2079)
			(xy 86.489284 -296.176775) (xy 86.456649 -296.139938) (xy 86.430346 -296.098342) (xy 86.411055 -296.053066)
			(xy 86.399278 -296.005282) (xy 86.395318 -295.956228) (xy 86.066376 -295.956228) (xy 86.065881 -295.980835)
			(xy 86.057986 -296.029412) (xy 86.042402 -296.076093) (xy 86.019531 -296.11967) (xy 85.989966 -296.159014)
			(xy 85.954473 -296.193106) (xy 85.91397 -296.221062) (xy 85.869508 -296.24216) (xy 85.822237 -296.255852)
			(xy 85.773382 -296.261784) (xy 85.724207 -296.259803) (xy 85.675988 -296.249959) (xy 85.629972 -296.232507)
			(xy 85.587351 -296.2079) (xy 85.54923 -296.176775) (xy 85.516595 -296.139938) (xy 85.490292 -296.098342)
			(xy 85.471001 -296.053066) (xy 85.459224 -296.005282) (xy 85.455264 -295.956228) (xy 85.126322 -295.956228)
			(xy 85.126322 -295.958006) (xy 85.126322 -295.962324) (xy 85.125407 -295.986003) (xy 85.117163 -296.032666)
			(xy 85.101808 -296.077494) (xy 85.079711 -296.119412) (xy 85.051402 -296.157412) (xy 85.017562 -296.190581)
			(xy 84.979003 -296.218124) (xy 84.936652 -296.239378) (xy 84.891525 -296.253832) (xy 84.844707 -296.261141)
			(xy 84.821014 -296.261536) (xy 84.797021 -296.261066) (xy 84.749626 -296.253562) (xy 84.703989 -296.238736)
			(xy 84.661232 -296.216954) (xy 84.622409 -296.188751) (xy 84.588476 -296.154823) (xy 84.560268 -296.116004)
			(xy 84.53848 -296.07325) (xy 84.523648 -296.027615) (xy 84.516137 -295.980221) (xy 84.515706 -295.956228)
			(xy 84.515706 -295.94302) (xy 84.516987 -295.92136) (xy 84.524904 -295.8787) (xy 84.538779 -295.837589)
			(xy 84.548218 -295.818052) (xy 84.554314 -295.806114) (xy 84.553298 -295.779952) (xy 84.502498 -295.696894)
			(xy 84.502244 -295.69664) (xy 84.498434 -295.688512) (xy 84.473796 -295.672764) (xy 84.242656 -295.672764)
			(xy 84.234016 -295.673101) (xy 84.217722 -295.678849) (xy 84.20428 -295.689706) (xy 84.199476 -295.696894)
			(xy 84.19211 -295.708832) (xy 84.176108 -295.73474) (xy 84.174019 -295.737969) (xy 84.169041 -295.743829)
			(xy 84.166202 -295.746424) (xy 84.165948 -295.746678) (xy 84.158533 -295.753727) (xy 84.1495 -295.772064)
			(xy 84.148422 -295.782238) (xy 84.147914 -295.792398) (xy 84.147793 -295.79897) (xy 84.150496 -295.811829)
			(xy 84.153248 -295.817798) (xy 84.154264 -295.820084) (xy 84.15528 -295.82237) (xy 84.157312 -295.826434)
			(xy 84.158074 -295.827958) (xy 84.166858 -295.84784) (xy 84.179332 -295.889477) (xy 84.185756 -295.932466)
			(xy 84.186268 -295.954196) (xy 84.186268 -295.956482) (xy 84.185776 -295.980458) (xy 84.178235 -296.027813)
			(xy 84.163382 -296.073407) (xy 84.141583 -296.116117) (xy 84.113374 -296.154894) (xy 84.079449 -296.188783)
			(xy 84.040642 -296.216952) (xy 83.997909 -296.238706) (xy 83.952299 -296.25351) (xy 83.904936 -296.261002)
			(xy 83.88096 -296.261536) (xy 83.85731 -296.261089) (xy 83.810575 -296.253791) (xy 83.765524 -296.239376)
			(xy 83.723235 -296.218187) (xy 83.684717 -296.190733) (xy 83.650892 -296.157669) (xy 83.622568 -296.119785)
			(xy 83.600424 -296.077988) (xy 83.584987 -296.033277) (xy 83.576628 -295.98672) (xy 83.575652 -295.963086)
			(xy 83.575652 -295.953942) (xy 83.576228 -295.931268) (xy 83.583265 -295.886462) (xy 83.596863 -295.843193)
			(xy 83.616721 -295.802417) (xy 83.629246 -295.783508) (xy 83.633564 -295.777158) (xy 83.638644 -295.761156)
			(xy 83.638644 -295.760648) (xy 83.641692 -295.752012) (xy 83.640422 -295.731692) (xy 83.63331 -295.717722)
			(xy 83.626706 -295.702736) (xy 83.622299 -295.694043) (xy 83.608257 -295.68055) (xy 83.590213 -295.673228)
			(xy 83.580478 -295.672764) (xy 83.525868 -295.672764) (xy 83.515802 -295.673195) (xy 83.497212 -295.680924)
			(xy 83.4898 -295.68775) (xy 83.2612 -295.91635) (xy 83.254088 -295.924986) (xy 83.254088 -295.92524)
			(xy 83.25045 -295.931438) (xy 83.246445 -295.945235) (xy 83.246214 -295.952418) (xy 83.246214 -295.956228)
			(xy 83.245741 -295.980218) (xy 83.238232 -296.027607) (xy 83.223402 -296.073237) (xy 83.201617 -296.115986)
			(xy 83.173413 -296.154802) (xy 83.139485 -296.188728) (xy 83.100668 -296.216929) (xy 83.057917 -296.23871)
			(xy 83.012285 -296.253537) (xy 82.964896 -296.261043) (xy 82.940906 -296.261536) (xy 82.937096 -296.261536)
			(xy 82.929914 -296.261782) (xy 82.916118 -296.265778) (xy 82.909918 -296.26941) (xy 82.905092 -296.272458)
			(xy 80.862467 -298.315083) (xy 87.657172 -298.315083) (xy 87.657172 -298.251161) (xy 87.665183 -298.187743)
			(xy 87.68108 -298.125829) (xy 87.704612 -298.066396) (xy 87.735406 -298.010381) (xy 87.772979 -297.958666)
			(xy 87.816736 -297.912069) (xy 87.865989 -297.871324) (xy 87.91996 -297.837073) (xy 87.977799 -297.809856)
			(xy 88.038592 -297.790103) (xy 88.101382 -297.778125) (xy 88.165178 -297.774112) (xy 88.228974 -297.778125)
			(xy 88.291764 -297.790103) (xy 88.352557 -297.809856) (xy 88.410396 -297.837073) (xy 88.464367 -297.871324)
			(xy 88.51362 -297.912069) (xy 88.557377 -297.958666) (xy 88.59495 -298.010381) (xy 88.625744 -298.066396)
			(xy 88.649276 -298.125829) (xy 88.665173 -298.187743) (xy 88.673184 -298.251161) (xy 88.673686 -298.283122)
			(xy 88.673184 -298.315083) (xy 88.665173 -298.378501) (xy 88.649276 -298.440415) (xy 88.625744 -298.499848)
			(xy 88.59495 -298.555863) (xy 88.557377 -298.607578) (xy 88.51362 -298.654175) (xy 88.464367 -298.69492)
			(xy 88.410396 -298.729171) (xy 88.352557 -298.756388) (xy 88.291764 -298.776141) (xy 88.228974 -298.788119)
			(xy 88.165178 -298.792133) (xy 88.101382 -298.788119) (xy 88.038592 -298.776141) (xy 87.977799 -298.756388)
			(xy 87.91996 -298.729171) (xy 87.865989 -298.69492) (xy 87.816736 -298.654175) (xy 87.772979 -298.607578)
			(xy 87.735406 -298.555863) (xy 87.704612 -298.499848) (xy 87.68108 -298.440415) (xy 87.665183 -298.378501)
			(xy 87.657172 -298.315083) (xy 80.862467 -298.315083) (xy 77.397864 -301.779686) (xy 92.19006 -301.779686)
			(xy 92.194131 -301.724064) (xy 92.206257 -301.669627) (xy 92.22618 -301.617536) (xy 92.253476 -301.568901)
			(xy 92.287562 -301.524758) (xy 92.327711 -301.486049) (xy 92.373069 -301.453598) (xy 92.422669 -301.428097)
			(xy 92.475453 -301.41009) (xy 92.530296 -301.39996) (xy 92.58603 -301.397923) (xy 92.641467 -301.404023)
			(xy 92.695424 -301.418129) (xy 92.746753 -301.439941) (xy 92.794359 -301.468995) (xy 92.837227 -301.50467)
			(xy 92.874444 -301.546207) (xy 92.905217 -301.59272) (xy 92.928889 -301.643217) (xy 92.944957 -301.696624)
			(xy 92.953077 -301.7518) (xy 92.953586 -301.779686) (xy 92.953077 -301.807572) (xy 92.944957 -301.862748)
			(xy 92.928889 -301.916155) (xy 92.905217 -301.966652) (xy 92.874444 -302.013165) (xy 92.837227 -302.054702)
			(xy 92.794359 -302.090377) (xy 92.746753 -302.119431) (xy 92.695424 -302.141243) (xy 92.641467 -302.155349)
			(xy 92.58603 -302.161449) (xy 92.530296 -302.159412) (xy 92.475453 -302.149282) (xy 92.422669 -302.131275)
			(xy 92.373069 -302.105774) (xy 92.327711 -302.073323) (xy 92.287562 -302.034614) (xy 92.253476 -301.990471)
			(xy 92.22618 -301.941836) (xy 92.206257 -301.889745) (xy 92.194131 -301.835308) (xy 92.19006 -301.779686)
			(xy 77.397864 -301.779686) (xy 74.397108 -304.780442) (xy 78.812394 -304.780442) (xy 78.816423 -304.638121)
			(xy 78.828498 -304.496256) (xy 78.848579 -304.355302) (xy 78.876602 -304.215709) (xy 78.912478 -304.077925)
			(xy 78.956092 -303.942392) (xy 79.007304 -303.809543) (xy 79.06595 -303.679804) (xy 79.131841 -303.553591)
			(xy 79.204768 -303.431308) (xy 79.284496 -303.313346) (xy 79.37077 -303.200084) (xy 79.463314 -303.091885)
			(xy 79.56183 -302.989094) (xy 79.666005 -302.892042) (xy 79.775503 -302.801038) (xy 79.889974 -302.716376)
			(xy 80.009052 -302.638325) (xy 80.132355 -302.567136) (xy 80.259488 -302.503037) (xy 80.390044 -302.446233)
			(xy 80.523604 -302.396907) (xy 80.659741 -302.355215) (xy 80.798019 -302.321292) (xy 80.937994 -302.295247)
			(xy 81.079219 -302.277162) (xy 81.22124 -302.267097) (xy 81.363604 -302.265082) (xy 81.505854 -302.271125)
			(xy 81.647534 -302.285205) (xy 81.78819 -302.307279) (xy 81.927372 -302.337275) (xy 82.064634 -302.375097)
			(xy 82.199537 -302.420625) (xy 82.331648 -302.473711) (xy 82.460544 -302.534187) (xy 82.585812 -302.601858)
			(xy 82.707051 -302.676508) (xy 82.823872 -302.757897) (xy 82.872963 -302.7964) (xy 84.778634 -302.7964)
			(xy 84.782549 -302.719211) (xy 84.794252 -302.642815) (xy 84.813625 -302.567994) (xy 84.840468 -302.495517)
			(xy 84.874505 -302.426128) (xy 84.915388 -302.360538) (xy 84.962697 -302.299421) (xy 85.015946 -302.243403)
			(xy 85.074589 -302.193061) (xy 85.138025 -302.148909) (xy 85.205602 -302.111402) (xy 85.276627 -302.080924)
			(xy 85.35037 -302.057788) (xy 85.426076 -302.042231) (xy 85.502968 -302.034413) (xy 85.541612 -302.03394)
			(xy 85.579846 -302.034398) (xy 85.655931 -302.042053) (xy 85.73087 -302.057274) (xy 85.803911 -302.07991)
			(xy 85.8393 -302.094392) (xy 85.848891 -302.097957) (xy 85.869333 -302.097957) (xy 85.878924 -302.094392)
			(xy 85.914302 -302.079881) (xy 85.987342 -302.05723) (xy 86.062285 -302.042016) (xy 86.138376 -302.03439)
			(xy 86.176612 -302.03394) (xy 86.215259 -302.034334) (xy 86.292157 -302.042155) (xy 86.367869 -302.057715)
			(xy 86.441619 -302.080855) (xy 86.512649 -302.111338) (xy 86.58023 -302.148849) (xy 86.643671 -302.193006)
			(xy 86.702318 -302.243354) (xy 86.755571 -302.299377) (xy 86.802883 -302.3605) (xy 86.843769 -302.426096)
			(xy 86.877808 -302.495491) (xy 86.904653 -302.567974) (xy 86.924027 -302.642801) (xy 86.935731 -302.719205)
			(xy 86.939646 -302.7964) (xy 86.935731 -302.873595) (xy 86.924027 -302.949999) (xy 86.904653 -303.024826)
			(xy 86.877808 -303.097309) (xy 86.843769 -303.166704) (xy 86.802883 -303.2323) (xy 86.785179 -303.255172)
			(xy 92.274134 -303.255172) (xy 92.278205 -303.19955) (xy 92.290331 -303.145113) (xy 92.310254 -303.093022)
			(xy 92.33755 -303.044387) (xy 92.371636 -303.000244) (xy 92.411785 -302.961535) (xy 92.457143 -302.929084)
			(xy 92.506743 -302.903583) (xy 92.559527 -302.885576) (xy 92.61437 -302.875446) (xy 92.670104 -302.873409)
			(xy 92.725541 -302.879509) (xy 92.779498 -302.893615) (xy 92.830827 -302.915427) (xy 92.878433 -302.944481)
			(xy 92.921301 -302.980156) (xy 92.958518 -303.021693) (xy 92.989291 -303.068206) (xy 93.012963 -303.118703)
			(xy 93.029031 -303.17211) (xy 93.037151 -303.227286) (xy 93.03766 -303.255172) (xy 93.037151 -303.283058)
			(xy 93.029031 -303.338234) (xy 93.012963 -303.391641) (xy 92.989291 -303.442138) (xy 92.958518 -303.488651)
			(xy 92.921301 -303.530188) (xy 92.878433 -303.565863) (xy 92.830827 -303.594917) (xy 92.779498 -303.616729)
			(xy 92.725541 -303.630835) (xy 92.670104 -303.636935) (xy 92.61437 -303.634898) (xy 92.559527 -303.624768)
			(xy 92.506743 -303.606761) (xy 92.457143 -303.58126) (xy 92.411785 -303.548809) (xy 92.371636 -303.5101)
			(xy 92.33755 -303.465957) (xy 92.310254 -303.417322) (xy 92.290331 -303.365231) (xy 92.278205 -303.310794)
			(xy 92.274134 -303.255172) (xy 86.785179 -303.255172) (xy 86.755571 -303.293423) (xy 86.702318 -303.349446)
			(xy 86.643671 -303.399794) (xy 86.58023 -303.443951) (xy 86.512649 -303.481462) (xy 86.441619 -303.511945)
			(xy 86.367869 -303.535085) (xy 86.292157 -303.550645) (xy 86.215259 -303.558466) (xy 86.176612 -303.558956)
			(xy 86.138378 -303.55849) (xy 86.062293 -303.550838) (xy 85.987355 -303.535619) (xy 85.914313 -303.512985)
			(xy 85.878924 -303.498504) (xy 85.869333 -303.494939) (xy 85.848891 -303.494939) (xy 85.8393 -303.498504)
			(xy 85.803918 -303.513007) (xy 85.73088 -303.53566) (xy 85.655938 -303.550877) (xy 85.579848 -303.558504)
			(xy 85.541612 -303.558956) (xy 85.502968 -303.558387) (xy 85.426076 -303.550569) (xy 85.35037 -303.535012)
			(xy 85.276627 -303.511876) (xy 85.205602 -303.481398) (xy 85.138025 -303.443891) (xy 85.074589 -303.399739)
			(xy 85.015946 -303.349397) (xy 84.962697 -303.293379) (xy 84.915388 -303.232262) (xy 84.874505 -303.166672)
			(xy 84.840468 -303.097283) (xy 84.813625 -303.024806) (xy 84.794252 -302.949985) (xy 84.782549 -302.873589)
			(xy 84.778634 -302.7964) (xy 82.872963 -302.7964) (xy 82.935902 -302.845765) (xy 83.042781 -302.939831)
			(xy 83.144167 -303.039792) (xy 83.239736 -303.14533) (xy 83.329181 -303.256105) (xy 83.412215 -303.371763)
			(xy 83.488573 -303.491933) (xy 83.55801 -303.616231) (xy 83.620303 -303.744258) (xy 83.675254 -303.875605)
			(xy 83.722686 -304.00985) (xy 83.729469 -304.033174) (xy 92.945966 -304.033174) (xy 92.946468 -304.001213)
			(xy 92.954479 -303.937795) (xy 92.970376 -303.875881) (xy 92.993908 -303.816448) (xy 93.024702 -303.760433)
			(xy 93.062275 -303.708718) (xy 93.106032 -303.662121) (xy 93.155285 -303.621376) (xy 93.209256 -303.587125)
			(xy 93.267095 -303.559908) (xy 93.327888 -303.540155) (xy 93.390678 -303.528177) (xy 93.454474 -303.524164)
			(xy 93.51827 -303.528177) (xy 93.58106 -303.540155) (xy 93.641853 -303.559908) (xy 93.699692 -303.587125)
			(xy 93.753663 -303.621376) (xy 93.802916 -303.662121) (xy 93.846673 -303.708718) (xy 93.884246 -303.760433)
			(xy 93.91504 -303.816448) (xy 93.938572 -303.875881) (xy 93.954469 -303.937795) (xy 93.96248 -304.001213)
			(xy 93.962982 -304.033174) (xy 93.962469 -304.065957) (xy 93.954045 -304.13098) (xy 93.937332 -304.19438)
			(xy 93.912609 -304.255106) (xy 93.880284 -304.312151) (xy 93.840896 -304.364567) (xy 93.795096 -304.411486)
			(xy 93.769688 -304.432208) (xy 93.762771 -304.438106) (xy 93.753283 -304.453598) (xy 93.751146 -304.462434)
			(xy 93.745304 -304.492152) (xy 93.743945 -304.500955) (xy 93.746815 -304.518523) (xy 93.750892 -304.526442)
			(xy 93.765777 -304.554826) (xy 93.786845 -304.615352) (xy 93.797504 -304.678548) (xy 93.798136 -304.710592)
			(xy 93.79765 -304.737843) (xy 93.789894 -304.791791) (xy 93.774539 -304.844086) (xy 93.751897 -304.893663)
			(xy 93.722431 -304.939513) (xy 93.68674 -304.980704) (xy 93.645549 -305.016395) (xy 93.599699 -305.045861)
			(xy 93.550122 -305.068503) (xy 93.497827 -305.083858) (xy 93.443879 -305.091614) (xy 93.389377 -305.091614)
			(xy 93.335429 -305.083858) (xy 93.283134 -305.068503) (xy 93.233557 -305.045861) (xy 93.187707 -305.016395)
			(xy 93.146516 -304.980704) (xy 93.110825 -304.939513) (xy 93.081359 -304.893663) (xy 93.058717 -304.844086)
			(xy 93.043362 -304.791791) (xy 93.035606 -304.737843) (xy 93.03512 -304.710592) (xy 93.035637 -304.681237)
			(xy 93.044621 -304.623217) (xy 93.062377 -304.567256) (xy 93.088485 -304.51467) (xy 93.10497 -304.490374)
			(xy 93.109845 -304.482918) (xy 93.114534 -304.465744) (xy 93.114114 -304.456846) (xy 93.111828 -304.42662)
			(xy 93.11075 -304.417618) (xy 93.103064 -304.401211) (xy 93.096842 -304.394616) (xy 93.073395 -304.370658)
			(xy 93.032348 -304.317659) (xy 92.99862 -304.259726) (xy 92.972796 -304.197864) (xy 92.955324 -304.133145)
			(xy 92.946506 -304.066692) (xy 92.945966 -304.033174) (xy 83.729469 -304.033174) (xy 83.762447 -304.146563)
			(xy 83.794409 -304.285307) (xy 83.818471 -304.425637) (xy 83.834555 -304.567103) (xy 83.842611 -304.709253)
			(xy 83.842818 -304.738489) (xy 91.753938 -304.738489) (xy 91.753938 -304.674567) (xy 91.761949 -304.611149)
			(xy 91.777846 -304.549235) (xy 91.801378 -304.489802) (xy 91.832172 -304.433787) (xy 91.869745 -304.382072)
			(xy 91.913502 -304.335475) (xy 91.962755 -304.29473) (xy 92.016726 -304.260479) (xy 92.074565 -304.233262)
			(xy 92.135358 -304.213509) (xy 92.198148 -304.201531) (xy 92.261944 -304.197518) (xy 92.32574 -304.201531)
			(xy 92.38853 -304.213509) (xy 92.449323 -304.233262) (xy 92.507162 -304.260479) (xy 92.561133 -304.29473)
			(xy 92.610386 -304.335475) (xy 92.654143 -304.382072) (xy 92.691716 -304.433787) (xy 92.72251 -304.489802)
			(xy 92.746042 -304.549235) (xy 92.761939 -304.611149) (xy 92.76995 -304.674567) (xy 92.770452 -304.706528)
			(xy 92.76995 -304.738489) (xy 92.761939 -304.801907) (xy 92.746042 -304.863821) (xy 92.72251 -304.923254)
			(xy 92.691716 -304.979269) (xy 92.654143 -305.030984) (xy 92.610386 -305.077581) (xy 92.561133 -305.118326)
			(xy 92.507162 -305.152577) (xy 92.449323 -305.179794) (xy 92.38853 -305.199547) (xy 92.32574 -305.211525)
			(xy 92.261944 -305.215539) (xy 92.198148 -305.211525) (xy 92.135358 -305.199547) (xy 92.074565 -305.179794)
			(xy 92.016726 -305.152577) (xy 91.962755 -305.118326) (xy 91.913502 -305.077581) (xy 91.869745 -305.030984)
			(xy 91.832172 -304.979269) (xy 91.801378 -304.923254) (xy 91.777846 -304.863821) (xy 91.761949 -304.801907)
			(xy 91.753938 -304.738489) (xy 83.842818 -304.738489) (xy 83.843114 -304.780442) (xy 83.842611 -304.851631)
			(xy 83.834555 -304.993781) (xy 83.818471 -305.135247) (xy 83.794409 -305.275577) (xy 83.762447 -305.414321)
			(xy 83.722686 -305.551034) (xy 83.675254 -305.685279) (xy 83.620303 -305.816626) (xy 83.55801 -305.944653)
			(xy 83.488573 -306.068951) (xy 83.412215 -306.189121) (xy 83.329181 -306.304779) (xy 83.239736 -306.415554)
			(xy 83.195717 -306.464165) (xy 87.854784 -306.464165) (xy 87.854784 -306.400243) (xy 87.862795 -306.336825)
			(xy 87.878692 -306.274911) (xy 87.902224 -306.215478) (xy 87.933018 -306.159463) (xy 87.970591 -306.107748)
			(xy 88.014348 -306.061151) (xy 88.063601 -306.020406) (xy 88.117572 -305.986155) (xy 88.175411 -305.958938)
			(xy 88.236204 -305.939185) (xy 88.298994 -305.927207) (xy 88.36279 -305.923194) (xy 88.426586 -305.927207)
			(xy 88.489376 -305.939185) (xy 88.550169 -305.958938) (xy 88.608008 -305.986155) (xy 88.659611 -306.018903)
			(xy 93.552258 -306.018903) (xy 93.552258 -305.954981) (xy 93.560269 -305.891563) (xy 93.576166 -305.829649)
			(xy 93.599698 -305.770216) (xy 93.630492 -305.714201) (xy 93.668065 -305.662486) (xy 93.711822 -305.615889)
			(xy 93.761075 -305.575144) (xy 93.815046 -305.540893) (xy 93.872885 -305.513676) (xy 93.933678 -305.493923)
			(xy 93.996468 -305.481945) (xy 94.060264 -305.477932) (xy 94.12406 -305.481945) (xy 94.18685 -305.493923)
			(xy 94.247643 -305.513676) (xy 94.305482 -305.540893) (xy 94.359453 -305.575144) (xy 94.408706 -305.615889)
			(xy 94.452463 -305.662486) (xy 94.490036 -305.714201) (xy 94.52083 -305.770216) (xy 94.544362 -305.829649)
			(xy 94.560259 -305.891563) (xy 94.56827 -305.954981) (xy 94.568772 -305.986942) (xy 94.56827 -306.018903)
			(xy 94.560259 -306.082321) (xy 94.544362 -306.144235) (xy 94.52083 -306.203668) (xy 94.490036 -306.259683)
			(xy 94.452463 -306.311398) (xy 94.408706 -306.357995) (xy 94.359453 -306.39874) (xy 94.305482 -306.432991)
			(xy 94.247643 -306.460208) (xy 94.18685 -306.479961) (xy 94.12406 -306.491939) (xy 94.060264 -306.495953)
			(xy 93.996468 -306.491939) (xy 93.933678 -306.479961) (xy 93.872885 -306.460208) (xy 93.815046 -306.432991)
			(xy 93.761075 -306.39874) (xy 93.711822 -306.357995) (xy 93.668065 -306.311398) (xy 93.630492 -306.259683)
			(xy 93.599698 -306.203668) (xy 93.576166 -306.144235) (xy 93.560269 -306.082321) (xy 93.552258 -306.018903)
			(xy 88.659611 -306.018903) (xy 88.661979 -306.020406) (xy 88.711232 -306.061151) (xy 88.754989 -306.107748)
			(xy 88.792562 -306.159463) (xy 88.823356 -306.215478) (xy 88.846888 -306.274911) (xy 88.862785 -306.336825)
			(xy 88.870796 -306.400243) (xy 88.871298 -306.432204) (xy 88.870796 -306.464165) (xy 88.862785 -306.527583)
			(xy 88.846888 -306.589497) (xy 88.823356 -306.64893) (xy 88.792562 -306.704945) (xy 88.754989 -306.75666)
			(xy 88.711232 -306.803257) (xy 88.661979 -306.844002) (xy 88.608008 -306.878253) (xy 88.550169 -306.90547)
			(xy 88.489376 -306.925223) (xy 88.426586 -306.937201) (xy 88.36279 -306.941215) (xy 88.298994 -306.937201)
			(xy 88.236204 -306.925223) (xy 88.175411 -306.90547) (xy 88.117572 -306.878253) (xy 88.063601 -306.844002)
			(xy 88.014348 -306.803257) (xy 87.970591 -306.75666) (xy 87.933018 -306.704945) (xy 87.902224 -306.64893)
			(xy 87.878692 -306.589497) (xy 87.862795 -306.527583) (xy 87.854784 -306.464165) (xy 83.195717 -306.464165)
			(xy 83.144167 -306.521092) (xy 83.042781 -306.621053) (xy 82.935902 -306.715119) (xy 82.823872 -306.802987)
			(xy 82.707051 -306.884376) (xy 82.585812 -306.959026) (xy 82.460544 -307.026697) (xy 82.331648 -307.087173)
			(xy 82.199537 -307.140259) (xy 82.064634 -307.185787) (xy 81.927372 -307.223609) (xy 81.78819 -307.253605)
			(xy 81.647534 -307.275679) (xy 81.505854 -307.289759) (xy 81.363604 -307.295802) (xy 81.22124 -307.293787)
			(xy 81.079219 -307.283722) (xy 80.937994 -307.265637) (xy 80.798019 -307.239592) (xy 80.659741 -307.205669)
			(xy 80.523604 -307.163977) (xy 80.390044 -307.114651) (xy 80.259488 -307.057847) (xy 80.132355 -306.993748)
			(xy 80.009052 -306.922559) (xy 79.889974 -306.844508) (xy 79.775503 -306.759846) (xy 79.666005 -306.668842)
			(xy 79.56183 -306.57179) (xy 79.463314 -306.468999) (xy 79.37077 -306.3608) (xy 79.284496 -306.247538)
			(xy 79.204768 -306.129576) (xy 79.131841 -306.007293) (xy 79.06595 -305.88108) (xy 79.007304 -305.751341)
			(xy 78.956092 -305.618492) (xy 78.912478 -305.482959) (xy 78.876602 -305.345175) (xy 78.848579 -305.205582)
			(xy 78.828498 -305.064628) (xy 78.816423 -304.922763) (xy 78.812394 -304.780442) (xy 74.397108 -304.780442)
			(xy 71.792381 -307.385169) (xy 88.750896 -307.385169) (xy 88.750896 -307.321247) (xy 88.758907 -307.257829)
			(xy 88.774804 -307.195915) (xy 88.798336 -307.136482) (xy 88.82913 -307.080467) (xy 88.866703 -307.028752)
			(xy 88.91046 -306.982155) (xy 88.959713 -306.94141) (xy 89.013684 -306.907159) (xy 89.071523 -306.879942)
			(xy 89.132316 -306.860189) (xy 89.195106 -306.848211) (xy 89.258902 -306.844198) (xy 89.322698 -306.848211)
			(xy 89.385488 -306.860189) (xy 89.446281 -306.879942) (xy 89.50412 -306.907159) (xy 89.558091 -306.94141)
			(xy 89.607344 -306.982155) (xy 89.651101 -307.028752) (xy 89.688674 -307.080467) (xy 89.707611 -307.114913)
			(xy 90.238828 -307.114913) (xy 90.238828 -307.050991) (xy 90.246839 -306.987573) (xy 90.262736 -306.925659)
			(xy 90.286268 -306.866226) (xy 90.317062 -306.810211) (xy 90.354635 -306.758496) (xy 90.398392 -306.711899)
			(xy 90.447645 -306.671154) (xy 90.501616 -306.636903) (xy 90.559455 -306.609686) (xy 90.620248 -306.589933)
			(xy 90.683038 -306.577955) (xy 90.746834 -306.573942) (xy 90.81063 -306.577955) (xy 90.833276 -306.582275)
			(xy 91.420182 -306.582275) (xy 91.420182 -306.518353) (xy 91.428193 -306.454935) (xy 91.44409 -306.393021)
			(xy 91.467622 -306.333588) (xy 91.498416 -306.277573) (xy 91.535989 -306.225858) (xy 91.579746 -306.179261)
			(xy 91.628999 -306.138516) (xy 91.68297 -306.104265) (xy 91.740809 -306.077048) (xy 91.801602 -306.057295)
			(xy 91.864392 -306.045317) (xy 91.928188 -306.041304) (xy 91.991984 -306.045317) (xy 92.054774 -306.057295)
			(xy 92.115567 -306.077048) (xy 92.173406 -306.104265) (xy 92.227377 -306.138516) (xy 92.27663 -306.179261)
			(xy 92.320387 -306.225858) (xy 92.35796 -306.277573) (xy 92.388754 -306.333588) (xy 92.412286 -306.393021)
			(xy 92.428183 -306.454935) (xy 92.436194 -306.518353) (xy 92.436696 -306.550314) (xy 92.436194 -306.582275)
			(xy 92.428183 -306.645693) (xy 92.412286 -306.707607) (xy 92.40187 -306.733913) (xy 95.064828 -306.733913)
			(xy 95.064828 -306.669991) (xy 95.072839 -306.606573) (xy 95.088736 -306.544659) (xy 95.112268 -306.485226)
			(xy 95.143062 -306.429211) (xy 95.180635 -306.377496) (xy 95.224392 -306.330899) (xy 95.273645 -306.290154)
			(xy 95.327616 -306.255903) (xy 95.385455 -306.228686) (xy 95.446248 -306.208933) (xy 95.509038 -306.196955)
			(xy 95.572834 -306.192942) (xy 95.63663 -306.196955) (xy 95.69942 -306.208933) (xy 95.760213 -306.228686)
			(xy 95.818052 -306.255903) (xy 95.872023 -306.290154) (xy 95.921276 -306.330899) (xy 95.965033 -306.377496)
			(xy 96.002606 -306.429211) (xy 96.0334 -306.485226) (xy 96.056932 -306.544659) (xy 96.072829 -306.606573)
			(xy 96.08084 -306.669991) (xy 96.081342 -306.701952) (xy 96.08084 -306.733913) (xy 96.072829 -306.797331)
			(xy 96.056932 -306.859245) (xy 96.0334 -306.918678) (xy 96.002606 -306.974693) (xy 95.965033 -307.026408)
			(xy 95.921276 -307.073005) (xy 95.872023 -307.11375) (xy 95.818052 -307.148001) (xy 95.760213 -307.175218)
			(xy 95.69942 -307.194971) (xy 95.63663 -307.206949) (xy 95.572834 -307.210963) (xy 95.509038 -307.206949)
			(xy 95.446248 -307.194971) (xy 95.385455 -307.175218) (xy 95.327616 -307.148001) (xy 95.273645 -307.11375)
			(xy 95.224392 -307.073005) (xy 95.180635 -307.026408) (xy 95.143062 -306.974693) (xy 95.112268 -306.918678)
			(xy 95.088736 -306.859245) (xy 95.072839 -306.797331) (xy 95.064828 -306.733913) (xy 92.40187 -306.733913)
			(xy 92.388754 -306.76704) (xy 92.35796 -306.823055) (xy 92.320387 -306.87477) (xy 92.27663 -306.921367)
			(xy 92.227377 -306.962112) (xy 92.173406 -306.996363) (xy 92.115567 -307.02358) (xy 92.054774 -307.043333)
			(xy 91.991984 -307.055311) (xy 91.928188 -307.059325) (xy 91.864392 -307.055311) (xy 91.801602 -307.043333)
			(xy 91.740809 -307.02358) (xy 91.68297 -306.996363) (xy 91.628999 -306.962112) (xy 91.579746 -306.921367)
			(xy 91.535989 -306.87477) (xy 91.498416 -306.823055) (xy 91.467622 -306.76704) (xy 91.44409 -306.707607)
			(xy 91.428193 -306.645693) (xy 91.420182 -306.582275) (xy 90.833276 -306.582275) (xy 90.87342 -306.589933)
			(xy 90.934213 -306.609686) (xy 90.992052 -306.636903) (xy 91.046023 -306.671154) (xy 91.095276 -306.711899)
			(xy 91.139033 -306.758496) (xy 91.176606 -306.810211) (xy 91.2074 -306.866226) (xy 91.230932 -306.925659)
			(xy 91.246829 -306.987573) (xy 91.25484 -307.050991) (xy 91.255342 -307.082952) (xy 91.25484 -307.114913)
			(xy 91.246829 -307.178331) (xy 91.237536 -307.214524) (xy 93.048326 -307.214524) (xy 93.052397 -307.158902)
			(xy 93.064523 -307.104465) (xy 93.084446 -307.052374) (xy 93.111742 -307.003739) (xy 93.145828 -306.959596)
			(xy 93.185977 -306.920887) (xy 93.231335 -306.888436) (xy 93.280935 -306.862935) (xy 93.333719 -306.844928)
			(xy 93.388562 -306.834798) (xy 93.444296 -306.832761) (xy 93.499733 -306.838861) (xy 93.55369 -306.852967)
			(xy 93.605019 -306.874779) (xy 93.652625 -306.903833) (xy 93.695493 -306.939508) (xy 93.73271 -306.981045)
			(xy 93.763483 -307.027558) (xy 93.787155 -307.078055) (xy 93.803223 -307.131462) (xy 93.811343 -307.186638)
			(xy 93.811852 -307.214524) (xy 93.811343 -307.24241) (xy 93.803223 -307.297586) (xy 93.787155 -307.350993)
			(xy 93.763483 -307.40149) (xy 93.73271 -307.448003) (xy 93.695493 -307.48954) (xy 93.652625 -307.525215)
			(xy 93.605019 -307.554269) (xy 93.55369 -307.576081) (xy 93.499733 -307.590187) (xy 93.444296 -307.596287)
			(xy 93.388562 -307.59425) (xy 93.333719 -307.58412) (xy 93.280935 -307.566113) (xy 93.231335 -307.540612)
			(xy 93.185977 -307.508161) (xy 93.145828 -307.469452) (xy 93.111742 -307.425309) (xy 93.084446 -307.376674)
			(xy 93.064523 -307.324583) (xy 93.052397 -307.270146) (xy 93.048326 -307.214524) (xy 91.237536 -307.214524)
			(xy 91.230932 -307.240245) (xy 91.2074 -307.299678) (xy 91.176606 -307.355693) (xy 91.139033 -307.407408)
			(xy 91.095276 -307.454005) (xy 91.046023 -307.49475) (xy 90.992052 -307.529001) (xy 90.934213 -307.556218)
			(xy 90.87342 -307.575971) (xy 90.81063 -307.587949) (xy 90.746834 -307.591963) (xy 90.683038 -307.587949)
			(xy 90.620248 -307.575971) (xy 90.559455 -307.556218) (xy 90.501616 -307.529001) (xy 90.447645 -307.49475)
			(xy 90.398392 -307.454005) (xy 90.354635 -307.407408) (xy 90.317062 -307.355693) (xy 90.286268 -307.299678)
			(xy 90.262736 -307.240245) (xy 90.246839 -307.178331) (xy 90.238828 -307.114913) (xy 89.707611 -307.114913)
			(xy 89.719468 -307.136482) (xy 89.743 -307.195915) (xy 89.758897 -307.257829) (xy 89.766908 -307.321247)
			(xy 89.76741 -307.353208) (xy 89.766908 -307.385169) (xy 89.758897 -307.448587) (xy 89.743 -307.510501)
			(xy 89.719468 -307.569934) (xy 89.688674 -307.625949) (xy 89.651101 -307.677664) (xy 89.607344 -307.724261)
			(xy 89.558091 -307.765006) (xy 89.50412 -307.799257) (xy 89.446281 -307.826474) (xy 89.385488 -307.846227)
			(xy 89.322698 -307.858205) (xy 89.258902 -307.862219) (xy 89.195106 -307.858205) (xy 89.132316 -307.846227)
			(xy 89.071523 -307.826474) (xy 89.013684 -307.799257) (xy 88.959713 -307.765006) (xy 88.91046 -307.724261)
			(xy 88.866703 -307.677664) (xy 88.82913 -307.625949) (xy 88.798336 -307.569934) (xy 88.774804 -307.510501)
			(xy 88.758907 -307.448587) (xy 88.750896 -307.385169) (xy 71.792381 -307.385169) (xy 69.493564 -309.683986)
			(xy 78.652905 -309.683986) (xy 78.652905 -309.632014) (xy 78.661035 -309.580682) (xy 78.677095 -309.531254)
			(xy 78.700688 -309.484947) (xy 78.731235 -309.4429) (xy 78.767984 -309.40615) (xy 78.810028 -309.3756)
			(xy 78.856334 -309.352003) (xy 78.905761 -309.33594) (xy 78.957092 -309.327807) (xy 78.983078 -309.327296)
			(xy 78.999899 -309.32751) (xy 79.033366 -309.330946) (xy 79.04988 -309.334154) (xy 79.061407 -309.335998)
			(xy 79.083983 -309.330144) (xy 79.101664 -309.314933) (xy 79.106776 -309.304436) (xy 79.121446 -309.271641)
			(xy 79.15867 -309.210196) (xy 79.180944 -309.182008) (xy 79.186241 -309.175009) (xy 79.192215 -309.158518)
			(xy 79.192628 -309.14975) (xy 79.192628 -308.995826) (xy 79.192249 -308.987051) (xy 79.186275 -308.970548)
			(xy 79.180944 -308.963568) (xy 79.162315 -308.940151) (xy 79.130081 -308.889735) (xy 79.103988 -308.835883)
			(xy 79.084398 -308.779341) (xy 79.077566 -308.750208) (xy 79.074502 -308.738946) (xy 79.06001 -308.720689)
			(xy 79.038937 -308.710723) (xy 79.027274 -308.71033) (xy 79.02321 -308.71033) (xy 78.997222 -308.709804)
			(xy 78.945886 -308.701674) (xy 78.896453 -308.685614) (xy 78.850141 -308.662018) (xy 78.808091 -308.631468)
			(xy 78.771338 -308.594716) (xy 78.740787 -308.552667) (xy 78.71719 -308.506356) (xy 78.701128 -308.456924)
			(xy 78.692997 -308.405588) (xy 78.692997 -308.353612) (xy 78.701128 -308.302276) (xy 78.71719 -308.252844)
			(xy 78.740787 -308.206533) (xy 78.771338 -308.164484) (xy 78.808091 -308.127732) (xy 78.850141 -308.097182)
			(xy 78.896453 -308.073586) (xy 78.945886 -308.057526) (xy 78.997222 -308.049396) (xy 79.02321 -308.048914)
			(xy 79.04797 -308.049377) (xy 79.096935 -308.056768) (xy 79.144249 -308.071381) (xy 79.188853 -308.092891)
			(xy 79.229749 -308.120815) (xy 79.26602 -308.154529) (xy 79.281782 -308.173628) (xy 79.289481 -308.182391)
			(xy 79.310551 -308.192349) (xy 79.333854 -308.192071) (xy 79.34452 -308.187344) (xy 79.371294 -308.174276)
			(xy 79.427231 -308.153763) (xy 79.485179 -308.139917) (xy 79.544347 -308.132924) (xy 79.574136 -308.13248)
			(xy 79.604867 -308.132922) (xy 79.665881 -308.140334) (xy 79.725557 -308.155046) (xy 79.783025 -308.176844)
			(xy 79.837446 -308.20541) (xy 79.888028 -308.240326) (xy 79.934032 -308.281085) (xy 79.974789 -308.327091)
			(xy 80.009703 -308.377674) (xy 80.038266 -308.432097) (xy 80.060061 -308.489566) (xy 80.062386 -308.499)
			(xy 88.375291 -308.499) (xy 88.379305 -308.435208) (xy 88.391281 -308.372422) (xy 88.411032 -308.311632)
			(xy 88.438245 -308.253797) (xy 88.472492 -308.199828) (xy 88.513233 -308.150577) (xy 88.559825 -308.106819)
			(xy 88.611534 -308.069246) (xy 88.667543 -308.03845) (xy 88.726971 -308.014916) (xy 88.78888 -307.999015)
			(xy 88.852293 -307.990999) (xy 88.884252 -307.990494) (xy 88.915807 -307.990985) (xy 88.978432 -307.998793)
			(xy 89.039608 -308.014296) (xy 89.098393 -308.037255) (xy 89.153883 -308.067316) (xy 89.205224 -308.104017)
			(xy 89.251626 -308.146792) (xy 89.272364 -308.17058) (xy 89.278968 -308.1782) (xy 89.295986 -308.187344)
			(xy 89.386156 -308.196488) (xy 89.404698 -308.191154) (xy 89.412572 -308.185058) (xy 89.432771 -308.169776)
			(xy 89.476437 -308.144108) (xy 89.523118 -308.124452) (xy 89.571992 -308.111153) (xy 89.622197 -308.104446)
			(xy 89.647522 -308.104032) (xy 89.674775 -308.104439) (xy 89.728726 -308.112199) (xy 89.781024 -308.127558)
			(xy 89.830603 -308.150203) (xy 89.876456 -308.179673) (xy 89.917648 -308.215368) (xy 89.953341 -308.256562)
			(xy 89.982808 -308.302416) (xy 90.00545 -308.351997) (xy 90.020805 -308.404295) (xy 90.028562 -308.458247)
			(xy 90.028562 -308.512753) (xy 90.020805 -308.566705) (xy 90.00545 -308.619003) (xy 89.982808 -308.668584)
			(xy 89.953341 -308.714438) (xy 89.917648 -308.755632) (xy 89.876456 -308.791327) (xy 89.830603 -308.820797)
			(xy 89.781024 -308.843442) (xy 89.728726 -308.858801) (xy 89.674775 -308.866561) (xy 89.647522 -308.867048)
			(xy 89.617533 -308.866515) (xy 89.558297 -308.85712) (xy 89.501259 -308.838573) (xy 89.447825 -308.811331)
			(xy 89.42324 -308.79415) (xy 89.415112 -308.788308) (xy 89.396316 -308.783736) (xy 89.306654 -308.795928)
			(xy 89.28989 -308.80558) (xy 89.283794 -308.813454) (xy 89.263071 -308.838942) (xy 89.216142 -308.884911)
			(xy 89.163684 -308.924452) (xy 89.10657 -308.956907) (xy 89.045751 -308.981735) (xy 88.982241 -308.998523)
			(xy 88.917098 -309.006991) (xy 88.884252 -309.00751) (xy 88.852293 -309.007001) (xy 88.78888 -308.998985)
			(xy 88.726971 -308.983084) (xy 88.667543 -308.95955) (xy 88.611534 -308.928754) (xy 88.559825 -308.891181)
			(xy 88.513233 -308.847423) (xy 88.472492 -308.798172) (xy 88.438245 -308.744203) (xy 88.411032 -308.686368)
			(xy 88.391281 -308.625578) (xy 88.379305 -308.562792) (xy 88.375291 -308.499) (xy 80.062386 -308.499)
			(xy 80.07477 -308.549242) (xy 80.08218 -308.610257) (xy 80.082644 -308.640988) (xy 80.082046 -308.675943)
			(xy 80.072487 -308.745195) (xy 80.053533 -308.812485) (xy 80.025542 -308.876546) (xy 79.989041 -308.936169)
			(xy 79.967328 -308.963568) (xy 79.962038 -308.970571) (xy 79.95606 -308.98706) (xy 79.955644 -308.995826)
			(xy 79.955644 -309.14975) (xy 79.95604 -309.158524) (xy 79.962003 -309.175026) (xy 79.967328 -309.182008)
			(xy 79.989049 -309.209401) (xy 80.025544 -309.269029) (xy 80.053535 -309.333091) (xy 80.072494 -309.400381)
			(xy 80.082064 -309.469633) (xy 80.082644 -309.504588) (xy 80.082133 -309.535317) (xy 80.079424 -309.557631)
			(xy 85.733122 -309.557631) (xy 85.733122 -309.493709) (xy 85.741133 -309.430291) (xy 85.75703 -309.368377)
			(xy 85.780562 -309.308944) (xy 85.811356 -309.252929) (xy 85.848929 -309.201214) (xy 85.892686 -309.154617)
			(xy 85.941939 -309.113872) (xy 85.99591 -309.079621) (xy 86.053749 -309.052404) (xy 86.114542 -309.032651)
			(xy 86.177332 -309.020673) (xy 86.241128 -309.01666) (xy 86.304924 -309.020673) (xy 86.31448 -309.022496)
			(xy 93.06433 -309.022496) (xy 93.064758 -308.997735) (xy 93.07216 -308.94877) (xy 93.086783 -308.901457)
			(xy 93.108299 -308.856853) (xy 93.136228 -308.815959) (xy 93.169944 -308.779687) (xy 93.189044 -308.763924)
			(xy 93.197803 -308.756222) (xy 93.20776 -308.735153) (xy 93.207484 -308.711852) (xy 93.20276 -308.701186)
			(xy 93.189695 -308.674411) (xy 93.169182 -308.618474) (xy 93.155334 -308.560527) (xy 93.148341 -308.501359)
			(xy 93.147896 -308.47157) (xy 93.148328 -308.440838) (xy 93.15574 -308.379823) (xy 93.170452 -308.320146)
			(xy 93.19225 -308.262678) (xy 93.220816 -308.208256) (xy 93.255733 -308.157674) (xy 93.296493 -308.111669)
			(xy 93.3425 -308.070912) (xy 93.393085 -308.035998) (xy 93.447509 -308.007436) (xy 93.504979 -307.985642)
			(xy 93.564657 -307.970934) (xy 93.625672 -307.963526) (xy 93.656404 -307.963062) (xy 93.691359 -307.96365)
			(xy 93.760612 -307.973211) (xy 93.827902 -307.992167) (xy 93.891963 -308.020161) (xy 93.951585 -308.056664)
			(xy 93.978984 -308.078378) (xy 93.985982 -308.083651) (xy 94.002486 -308.089494) (xy 94.011242 -308.089808)
			(xy 94.165166 -308.089808) (xy 94.173916 -308.089472) (xy 94.190407 -308.083616) (xy 94.197424 -308.078378)
			(xy 94.224812 -308.056651) (xy 94.284441 -308.020156) (xy 94.348505 -307.992167) (xy 94.415796 -307.973209)
			(xy 94.485049 -307.963641) (xy 94.520004 -307.963062) (xy 94.550734 -307.963552) (xy 94.611746 -307.970961)
			(xy 94.67142 -307.985669) (xy 94.728886 -308.007462) (xy 94.783306 -308.036023) (xy 94.833887 -308.070936)
			(xy 94.879892 -308.11169) (xy 94.920648 -308.157692) (xy 94.955563 -308.208272) (xy 94.984127 -308.26269)
			(xy 95.005923 -308.320156) (xy 95.020635 -308.379829) (xy 95.028046 -308.44084) (xy 95.028512 -308.47157)
			(xy 95.027975 -308.505036) (xy 95.019193 -308.57139) (xy 95.001776 -308.636017) (xy 94.976026 -308.697798)
			(xy 94.942389 -308.755665) (xy 94.92234 -308.782466) (xy 94.915623 -308.792041) (xy 94.910947 -308.814933)
			(xy 94.916893 -308.837529) (xy 94.924118 -308.846728) (xy 94.939171 -308.864816) (xy 94.964496 -308.904478)
			(xy 94.983939 -308.947332) (xy 94.997108 -308.99251) (xy 95.003736 -309.039099) (xy 95.004128 -309.062628)
			(xy 95.003618 -309.088615) (xy 94.995488 -309.13995) (xy 94.979427 -309.18938) (xy 94.955831 -309.23569)
			(xy 94.925281 -309.277738) (xy 94.88853 -309.314489) (xy 94.846482 -309.345039) (xy 94.800172 -309.368635)
			(xy 94.750742 -309.384696) (xy 94.699407 -309.392826) (xy 94.647433 -309.392826) (xy 94.596098 -309.384696)
			(xy 94.546668 -309.368635) (xy 94.500358 -309.345039) (xy 94.45831 -309.314489) (xy 94.421559 -309.277738)
			(xy 94.391009 -309.23569) (xy 94.367413 -309.18938) (xy 94.351352 -309.13995) (xy 94.343222 -309.088615)
			(xy 94.342712 -309.062628) (xy 94.342928 -309.045807) (xy 94.346363 -309.01234) (xy 94.34957 -308.995826)
			(xy 94.351399 -308.984299) (xy 94.345549 -308.961725) (xy 94.330346 -308.944044) (xy 94.319852 -308.93893)
			(xy 94.287059 -308.924257) (xy 94.225612 -308.887035) (xy 94.197424 -308.864762) (xy 94.190421 -308.859497)
			(xy 94.173921 -308.853648) (xy 94.165166 -308.853332) (xy 94.011242 -308.853332) (xy 94.002492 -308.853663)
			(xy 93.986001 -308.859522) (xy 93.978984 -308.864762) (xy 93.955564 -308.883387) (xy 93.905149 -308.915622)
			(xy 93.851298 -308.941716) (xy 93.794756 -308.961308) (xy 93.765624 -308.96814) (xy 93.754345 -308.971151)
			(xy 93.736094 -308.985673) (xy 93.726136 -309.006763) (xy 93.725746 -309.018432) (xy 93.725746 -309.022496)
			(xy 93.725236 -309.048483) (xy 93.717106 -309.099818) (xy 93.701045 -309.149248) (xy 93.677449 -309.195558)
			(xy 93.646899 -309.237606) (xy 93.610148 -309.274357) (xy 93.5681 -309.304907) (xy 93.52179 -309.328503)
			(xy 93.47236 -309.344564) (xy 93.421025 -309.352694) (xy 93.369051 -309.352694) (xy 93.317716 -309.344564)
			(xy 93.268286 -309.328503) (xy 93.221976 -309.304907) (xy 93.179928 -309.274357) (xy 93.143177 -309.237606)
			(xy 93.112627 -309.195558) (xy 93.089031 -309.149248) (xy 93.07297 -309.099818) (xy 93.06484 -309.048483)
			(xy 93.06433 -309.022496) (xy 86.31448 -309.022496) (xy 86.367714 -309.032651) (xy 86.428507 -309.052404)
			(xy 86.486346 -309.079621) (xy 86.540317 -309.113872) (xy 86.58957 -309.154617) (xy 86.633327 -309.201214)
			(xy 86.6709 -309.252929) (xy 86.701694 -309.308944) (xy 86.725226 -309.368377) (xy 86.741123 -309.430291)
			(xy 86.749134 -309.493709) (xy 86.749636 -309.52567) (xy 86.749134 -309.557631) (xy 86.741123 -309.621049)
			(xy 86.725226 -309.682963) (xy 86.701694 -309.742396) (xy 86.6709 -309.798411) (xy 86.633327 -309.850126)
			(xy 86.58957 -309.896723) (xy 86.540317 -309.937468) (xy 86.486346 -309.971719) (xy 86.428507 -309.998936)
			(xy 86.367714 -310.018689) (xy 86.304924 -310.030667) (xy 86.241128 -310.034681) (xy 86.177332 -310.030667)
			(xy 86.114542 -310.018689) (xy 86.053749 -309.998936) (xy 85.99591 -309.971719) (xy 85.941939 -309.937468)
			(xy 85.892686 -309.896723) (xy 85.848929 -309.850126) (xy 85.811356 -309.798411) (xy 85.780562 -309.742396)
			(xy 85.75703 -309.682963) (xy 85.741133 -309.621049) (xy 85.733122 -309.557631) (xy 80.079424 -309.557631)
			(xy 80.074726 -309.596328) (xy 80.06002 -309.656001) (xy 80.038229 -309.713467) (xy 80.009669 -309.767887)
			(xy 79.974759 -309.818468) (xy 79.934006 -309.864472) (xy 79.888006 -309.905229) (xy 79.837428 -309.940145)
			(xy 79.783011 -309.968709) (xy 79.725547 -309.990506) (xy 79.665875 -310.005218) (xy 79.604865 -310.01263)
			(xy 79.574136 -310.013096) (xy 79.54067 -310.012559) (xy 79.474316 -310.003777) (xy 79.409689 -309.986361)
			(xy 79.347907 -309.960611) (xy 79.290041 -309.926973) (xy 79.26324 -309.906924) (xy 79.253661 -309.900215)
			(xy 79.230771 -309.895538) (xy 79.208178 -309.90148) (xy 79.198978 -309.908702) (xy 79.180886 -309.92375)
			(xy 79.141225 -309.949076) (xy 79.098372 -309.96852) (xy 79.053195 -309.98169) (xy 79.006607 -309.988319)
			(xy 78.983078 -309.988712) (xy 78.957092 -309.988193) (xy 78.905761 -309.98006) (xy 78.856334 -309.963997)
			(xy 78.810028 -309.9404) (xy 78.767984 -309.90985) (xy 78.731235 -309.8731) (xy 78.700688 -309.831053)
			(xy 78.677095 -309.784746) (xy 78.661035 -309.735318) (xy 78.652905 -309.683986) (xy 69.493564 -309.683986)
			(xy 68.719954 -310.457596) (xy 95.560134 -310.457596) (xy 95.560638 -310.430439) (xy 95.569513 -310.376856)
			(xy 95.587025 -310.325444) (xy 95.612702 -310.277583) (xy 95.645854 -310.234562) (xy 95.68559 -310.197535)
			(xy 95.730842 -310.1675) (xy 95.780394 -310.145262) (xy 95.806514 -310.13781) (xy 95.81769 -310.134762)
			(xy 95.835216 -310.12003) (xy 95.876872 -310.026304) (xy 95.87611 -310.003444) (xy 95.870776 -309.99303)
			(xy 95.857253 -309.965923) (xy 95.836061 -309.90917) (xy 95.821766 -309.8503) (xy 95.81457 -309.790148)
			(xy 95.814134 -309.759858) (xy 95.814636 -309.727897) (xy 95.822647 -309.664479) (xy 95.838544 -309.602565)
			(xy 95.862076 -309.543132) (xy 95.89287 -309.487117) (xy 95.930443 -309.435402) (xy 95.9742 -309.388805)
			(xy 96.023453 -309.34806) (xy 96.077424 -309.313809) (xy 96.135263 -309.286592) (xy 96.196056 -309.266839)
			(xy 96.258846 -309.254861) (xy 96.322642 -309.250848) (xy 96.386438 -309.254861) (xy 96.449228 -309.266839)
			(xy 96.510021 -309.286592) (xy 96.56786 -309.313809) (xy 96.621831 -309.34806) (xy 96.671084 -309.388805)
			(xy 96.714841 -309.435402) (xy 96.752414 -309.487117) (xy 96.783208 -309.543132) (xy 96.80674 -309.602565)
			(xy 96.822637 -309.664479) (xy 96.830648 -309.727897) (xy 96.83115 -309.759858) (xy 96.831021 -309.77648)
			(xy 96.828857 -309.809653) (xy 96.826832 -309.826152) (xy 96.825881 -309.837923) (xy 96.833544 -309.860231)
			(xy 96.850353 -309.876779) (xy 96.861376 -309.881016) (xy 96.891482 -309.891474) (xy 96.949052 -309.918815)
			(xy 97.002755 -309.953135) (xy 97.051749 -309.993896) (xy 97.095266 -310.04046) (xy 97.132624 -310.092095)
			(xy 97.163238 -310.147994) (xy 97.186627 -310.20728) (xy 97.202426 -310.269024) (xy 97.210386 -310.332258)
			(xy 97.21088 -310.364124) (xy 97.210485 -310.394858) (xy 97.203073 -310.455877) (xy 97.18836 -310.515557)
			(xy 97.16656 -310.573029) (xy 97.137992 -310.627454) (xy 97.103072 -310.678039) (xy 97.06231 -310.724046)
			(xy 97.016298 -310.764804) (xy 96.989798 -310.783094) (xy 98.386037 -310.783094) (xy 98.386037 -310.731106)
			(xy 98.394171 -310.679758) (xy 98.410237 -310.630314) (xy 98.433841 -310.583993) (xy 98.464401 -310.541935)
			(xy 98.501164 -310.505176) (xy 98.543226 -310.474621) (xy 98.589549 -310.451023) (xy 98.638995 -310.434962)
			(xy 98.690344 -310.426834) (xy 98.716338 -310.426354) (xy 98.733159 -310.426574) (xy 98.766626 -310.430006)
			(xy 98.78314 -310.433212) (xy 98.794671 -310.434985) (xy 98.817233 -310.429154) (xy 98.834916 -310.413976)
			(xy 98.840036 -310.403494) (xy 98.854703 -310.370698) (xy 98.891929 -310.309253) (xy 98.914204 -310.281066)
			(xy 98.919525 -310.274083) (xy 98.925483 -310.257579) (xy 98.925888 -310.248808) (xy 98.925888 -310.094884)
			(xy 98.925537 -310.086106) (xy 98.919545 -310.069603) (xy 98.914204 -310.062626) (xy 98.895571 -310.039212)
			(xy 98.863337 -309.988795) (xy 98.837245 -309.934943) (xy 98.817657 -309.878399) (xy 98.810826 -309.849266)
			(xy 98.807821 -309.837984) (xy 98.793301 -309.819727) (xy 98.772205 -309.809772) (xy 98.760534 -309.809388)
			(xy 98.75647 -309.809388) (xy 98.730483 -309.808916) (xy 98.679149 -309.800781) (xy 98.629719 -309.784717)
			(xy 98.583411 -309.761118) (xy 98.541365 -309.730566) (xy 98.504615 -309.693813) (xy 98.474066 -309.651763)
			(xy 98.450472 -309.605453) (xy 98.434412 -309.556022) (xy 98.426281 -309.504687) (xy 98.426281 -309.452713)
			(xy 98.434412 -309.401378) (xy 98.450472 -309.351947) (xy 98.474066 -309.305637) (xy 98.504615 -309.263587)
			(xy 98.541365 -309.226834) (xy 98.583411 -309.196282) (xy 98.629719 -309.172683) (xy 98.679149 -309.156619)
			(xy 98.730483 -309.148484) (xy 98.75647 -309.147972) (xy 98.781231 -309.148409) (xy 98.830196 -309.155807)
			(xy 98.87751 -309.170427) (xy 98.922114 -309.191941) (xy 98.963009 -309.219869) (xy 98.999279 -309.253586)
			(xy 99.015042 -309.272686) (xy 99.022765 -309.281422) (xy 99.043823 -309.291378) (xy 99.067115 -309.291116)
			(xy 99.07778 -309.286402) (xy 99.104559 -309.273345) (xy 99.160494 -309.252831) (xy 99.218441 -309.238981)
			(xy 99.277607 -309.231985) (xy 99.307396 -309.231538) (xy 99.33813 -309.231941) (xy 99.399149 -309.239351)
			(xy 99.458831 -309.254061) (xy 99.516303 -309.275859) (xy 99.57073 -309.304425) (xy 99.621315 -309.339344)
			(xy 99.667323 -309.380107) (xy 99.708081 -309.426118) (xy 99.742996 -309.476706) (xy 99.771559 -309.531135)
			(xy 99.793351 -309.58861) (xy 99.808057 -309.648292) (xy 99.815461 -309.709312) (xy 99.815904 -309.740046)
			(xy 99.815348 -309.775002) (xy 99.80578 -309.844256) (xy 99.786817 -309.911548) (xy 99.758816 -309.975608)
			(xy 99.722306 -310.035229) (xy 99.700588 -310.062626) (xy 99.695281 -310.069618) (xy 99.689312 -310.086115)
			(xy 99.688904 -310.094884) (xy 99.688904 -310.248808) (xy 99.68926 -310.257586) (xy 99.695249 -310.274088)
			(xy 99.700588 -310.281066) (xy 99.722284 -310.308478) (xy 99.758784 -310.3681) (xy 99.786781 -310.432157)
			(xy 99.805745 -310.499443) (xy 99.815321 -310.568692) (xy 99.815904 -310.603646) (xy 99.815488 -310.634378)
			(xy 99.808074 -310.695394) (xy 99.79336 -310.755071) (xy 99.77156 -310.81254) (xy 99.742993 -310.866962)
			(xy 99.708074 -310.917544) (xy 99.667313 -310.963548) (xy 99.621304 -311.004305) (xy 99.570719 -311.039219)
			(xy 99.516294 -311.067781) (xy 99.458823 -311.089575) (xy 99.399145 -311.104283) (xy 99.338128 -311.111691)
			(xy 99.307396 -311.112154) (xy 99.273929 -311.111627) (xy 99.207575 -311.102841) (xy 99.142949 -311.085422)
			(xy 99.081168 -311.05967) (xy 99.023301 -311.026032) (xy 98.9965 -311.005982) (xy 98.986941 -310.999241)
			(xy 98.964039 -310.99458) (xy 98.94144 -311.000533) (xy 98.932238 -311.00776) (xy 98.914131 -311.022789)
			(xy 98.874473 -311.048116) (xy 98.831624 -311.067563) (xy 98.786451 -311.080738) (xy 98.739866 -311.087373)
			(xy 98.716338 -311.08777) (xy 98.690344 -311.087366) (xy 98.638995 -311.079238) (xy 98.589549 -311.063177)
			(xy 98.543226 -311.039579) (xy 98.501164 -311.009024) (xy 98.464401 -310.972265) (xy 98.433841 -310.930207)
			(xy 98.410237 -310.883886) (xy 98.394171 -310.834442) (xy 98.386037 -310.783094) (xy 96.989798 -310.783094)
			(xy 96.96571 -310.799719) (xy 96.911282 -310.828282) (xy 96.853807 -310.850075) (xy 96.794125 -310.864782)
			(xy 96.733106 -310.872188) (xy 96.702372 -310.872632) (xy 96.669241 -310.872089) (xy 96.603542 -310.863473)
			(xy 96.539516 -310.846403) (xy 96.478248 -310.821168) (xy 96.420773 -310.788194) (xy 96.368063 -310.74804)
			(xy 96.321011 -310.701385) (xy 96.30029 -310.675528) (xy 96.293432 -310.666384) (xy 96.272858 -310.656224)
			(xy 96.171004 -310.653684) (xy 96.150176 -310.663082) (xy 96.14281 -310.671972) (xy 96.126999 -310.689866)
			(xy 96.091127 -310.721383) (xy 96.0511 -310.747419) (xy 96.007748 -310.767436) (xy 95.961971 -310.781018)
			(xy 95.914717 -310.787883) (xy 95.890842 -310.788304) (xy 95.864854 -310.787786) (xy 95.813516 -310.779661)
			(xy 95.764082 -310.763604) (xy 95.717769 -310.740011) (xy 95.675716 -310.709463) (xy 95.638961 -310.672713)
			(xy 95.608408 -310.630664) (xy 95.58481 -310.584353) (xy 95.568748 -310.534921) (xy 95.560617 -310.483584)
			(xy 95.560134 -310.457596) (xy 68.719954 -310.457596) (xy 64.000761 -315.176789) (xy 97.790756 -315.176789)
			(xy 97.790756 -315.124811) (xy 97.798886 -315.073473) (xy 97.814947 -315.024039) (xy 97.838543 -314.977726)
			(xy 97.869093 -314.935673) (xy 97.905844 -314.898917) (xy 97.947893 -314.868363) (xy 97.994204 -314.844762)
			(xy 98.043636 -314.828695) (xy 98.094973 -314.820559) (xy 98.120962 -314.820046) (xy 98.137783 -314.820263)
			(xy 98.17125 -314.823697) (xy 98.187764 -314.826904) (xy 98.199293 -314.828703) (xy 98.221859 -314.822862)
			(xy 98.239541 -314.807673) (xy 98.24466 -314.797186) (xy 98.259324 -314.764388) (xy 98.296552 -314.702945)
			(xy 98.318828 -314.674758) (xy 98.324103 -314.667744) (xy 98.330091 -314.651264) (xy 98.330512 -314.6425)
			(xy 98.330512 -314.488576) (xy 98.33016 -314.479798) (xy 98.324168 -314.463295) (xy 98.318828 -314.456318)
			(xy 98.300195 -314.432904) (xy 98.267961 -314.382487) (xy 98.241869 -314.328635) (xy 98.222281 -314.272091)
			(xy 98.21545 -314.242958) (xy 98.212428 -314.231682) (xy 98.197914 -314.213428) (xy 98.176827 -314.203469)
			(xy 98.165158 -314.20308) (xy 98.161094 -314.20308) (xy 98.135105 -314.202626) (xy 98.083767 -314.194494)
			(xy 98.034333 -314.178431) (xy 97.98802 -314.154833) (xy 97.945969 -314.12428) (xy 97.909216 -314.087526)
			(xy 97.878664 -314.045475) (xy 97.855067 -313.999162) (xy 97.839005 -313.949727) (xy 97.830874 -313.898389)
			(xy 97.830874 -313.846411) (xy 97.839005 -313.795073) (xy 97.855067 -313.745638) (xy 97.878664 -313.699325)
			(xy 97.909216 -313.657274) (xy 97.945969 -313.62052) (xy 97.98802 -313.589967) (xy 98.034333 -313.566369)
			(xy 98.083767 -313.550306) (xy 98.135105 -313.542174) (xy 98.161094 -313.541664) (xy 98.185855 -313.542087)
			(xy 98.234821 -313.549488) (xy 98.282135 -313.564111) (xy 98.326739 -313.585628) (xy 98.367633 -313.613559)
			(xy 98.403904 -313.647277) (xy 98.419666 -313.666378) (xy 98.427372 -313.675132) (xy 98.448439 -313.685085)
			(xy 98.471738 -313.684814) (xy 98.482404 -313.680094) (xy 98.509178 -313.667028) (xy 98.565116 -313.646516)
			(xy 98.623063 -313.632669) (xy 98.682231 -313.625675) (xy 98.71202 -313.62523) (xy 98.742754 -313.625619)
			(xy 98.803774 -313.633031) (xy 98.863455 -313.647744) (xy 98.920927 -313.669543) (xy 98.975353 -313.698112)
			(xy 99.025938 -313.733032) (xy 99.071946 -313.773795) (xy 99.112704 -313.819807) (xy 99.147619 -313.870397)
			(xy 99.176181 -313.924826) (xy 99.197974 -313.982301) (xy 99.21268 -314.041984) (xy 99.220085 -314.103004)
			(xy 99.220528 -314.133738) (xy 99.219962 -314.168694) (xy 99.210395 -314.237947) (xy 99.191434 -314.305238)
			(xy 99.163436 -314.369298) (xy 99.126928 -314.42892) (xy 99.105212 -314.456318) (xy 99.099899 -314.463306)
			(xy 99.093935 -314.479806) (xy 99.093528 -314.488576) (xy 99.093528 -314.6425) (xy 99.093904 -314.651275)
			(xy 99.099881 -314.667777) (xy 99.105212 -314.674758) (xy 99.126907 -314.70217) (xy 99.163407 -314.761793)
			(xy 99.191403 -314.82585) (xy 99.210368 -314.893136) (xy 99.219945 -314.962384) (xy 99.220528 -314.997338)
			(xy 99.22008 -315.028069) (xy 99.212668 -315.089083) (xy 99.197955 -315.148758) (xy 99.176158 -315.206225)
			(xy 99.147593 -315.260646) (xy 99.112677 -315.311227) (xy 99.071919 -315.357232) (xy 99.025913 -315.397988)
			(xy 98.975331 -315.432902) (xy 98.920909 -315.461465) (xy 98.863441 -315.483261) (xy 98.803765 -315.497971)
			(xy 98.742751 -315.505381) (xy 98.71202 -315.505846) (xy 98.678554 -315.505308) (xy 98.6122 -315.496524)
			(xy 98.547574 -315.479108) (xy 98.485792 -315.453358) (xy 98.427926 -315.419722) (xy 98.401124 -315.399674)
			(xy 98.391556 -315.392943) (xy 98.368659 -315.388266) (xy 98.34606 -315.394221) (xy 98.336862 -315.401452)
			(xy 98.318745 -315.416468) (xy 98.27909 -315.441797) (xy 98.236244 -315.461247) (xy 98.191073 -315.474425)
			(xy 98.144489 -315.481064) (xy 98.120962 -315.481462) (xy 98.094973 -315.481041) (xy 98.043636 -315.472905)
			(xy 97.994204 -315.456838) (xy 97.947893 -315.433237) (xy 97.905844 -315.402683) (xy 97.869093 -315.365927)
			(xy 97.838543 -315.323874) (xy 97.814947 -315.277561) (xy 97.798886 -315.228127) (xy 97.790756 -315.176789)
			(xy 64.000761 -315.176789) (xy 63.349378 -315.828172) (xy 63.343312 -315.834826) (xy 63.335911 -315.851227)
			(xy 63.3349 -315.860176) (xy 63.3349 -316.017148) (xy 63.334646 -316.031372) (xy 63.334646 -316.236604)
			(xy 63.334106 -316.24659) (xy 63.326386 -316.265016) (xy 63.31966 -316.272418) (xy 63.175388 -316.416944)
			(xy 63.173864 -316.418468) (xy 63.173356 -316.418976) (xy 63.16472 -316.427866) (xy 60.721494 -318.871092)
			(xy 60.71108 -318.881252) (xy 60.710572 -318.88176) (xy 60.566046 -319.026032) (xy 60.558701 -319.032842)
			(xy 60.540238 -319.040565) (xy 60.530232 -319.041018) (xy 60.325 -319.041018) (xy 60.310776 -319.041272)
			(xy 60.156852 -319.041272) (xy 60.147101 -319.041785) (xy 60.129069 -319.049231) (xy 60.1218 -319.05575)
			(xy 59.76747 -319.41008) (xy 59.760233 -319.416794) (xy 59.742027 -319.424386) (xy 59.732164 -319.424812)
			(xy 26.01341 -319.424812) (xy 26.003339 -319.425234) (xy 25.984733 -319.432947) (xy 25.977342 -319.439798)
			(xy 25.201626 -320.215514) (xy 25.194779 -320.222912) (xy 25.187046 -320.24151) (xy 25.18664 -320.251582)
			(xy 25.18664 -323.030342) (xy 67.354958 -323.030342) (xy 67.355428 -322.999646) (xy 67.362832 -322.938701)
			(xy 67.377526 -322.879092) (xy 67.399294 -322.821689) (xy 67.42782 -322.767326) (xy 67.444874 -322.741798)
			(xy 67.450313 -322.733028) (xy 67.454455 -322.712835) (xy 67.45034 -322.692637) (xy 67.444874 -322.683886)
			(xy 67.427844 -322.658345) (xy 67.399332 -322.603979) (xy 67.377567 -322.546577) (xy 67.362865 -322.486975)
			(xy 67.355439 -322.426036) (xy 67.354958 -322.395342) (xy 67.355428 -322.364646) (xy 67.362832 -322.303701)
			(xy 67.377526 -322.244092) (xy 67.399294 -322.186689) (xy 67.42782 -322.132326) (xy 67.444874 -322.106798)
			(xy 67.450313 -322.098028) (xy 67.454455 -322.077835) (xy 67.45034 -322.057637) (xy 67.444874 -322.048886)
			(xy 67.427844 -322.023345) (xy 67.399332 -321.968979) (xy 67.377567 -321.911577) (xy 67.362865 -321.851975)
			(xy 67.355439 -321.791036) (xy 67.354958 -321.760342) (xy 67.355428 -321.729646) (xy 67.362832 -321.668701)
			(xy 67.377526 -321.609092) (xy 67.399294 -321.551689) (xy 67.42782 -321.497326) (xy 67.444874 -321.471798)
			(xy 67.450313 -321.463028) (xy 67.454455 -321.442835) (xy 67.45034 -321.422637) (xy 67.444874 -321.413886)
			(xy 67.427844 -321.388345) (xy 67.399332 -321.333979) (xy 67.377567 -321.276577) (xy 67.362865 -321.216975)
			(xy 67.355439 -321.156036) (xy 67.354958 -321.125342) (xy 67.355428 -321.094646) (xy 67.362832 -321.033701)
			(xy 67.377526 -320.974092) (xy 67.399294 -320.916689) (xy 67.42782 -320.862326) (xy 67.444874 -320.836798)
			(xy 67.450313 -320.828028) (xy 67.454455 -320.807835) (xy 67.45034 -320.787637) (xy 67.444874 -320.778886)
			(xy 67.427844 -320.753345) (xy 67.399332 -320.698979) (xy 67.377567 -320.641577) (xy 67.362865 -320.581975)
			(xy 67.355439 -320.521036) (xy 67.354958 -320.490342) (xy 67.355477 -320.459612) (xy 67.36288 -320.3986)
			(xy 67.377584 -320.338925) (xy 67.399373 -320.281457) (xy 67.427931 -320.227035) (xy 67.46284 -320.176452)
			(xy 67.503592 -320.130446) (xy 67.549592 -320.089687) (xy 67.60017 -320.05477) (xy 67.654588 -320.026204)
			(xy 67.712052 -320.004406) (xy 67.771725 -319.989694) (xy 67.832736 -319.982282) (xy 67.863466 -319.981834)
			(xy 67.882262 -319.982088) (xy 67.893184 -319.982596) (xy 67.912996 -319.974722) (xy 67.980814 -319.904872)
			(xy 67.98818 -319.884806) (xy 67.987418 -319.874138) (xy 67.986402 -319.840864) (xy 67.986822 -319.810132)
			(xy 67.994235 -319.749116) (xy 68.008948 -319.689439) (xy 68.030747 -319.63197) (xy 68.059314 -319.577547)
			(xy 68.094232 -319.526965) (xy 68.134993 -319.48096) (xy 68.181001 -319.440204) (xy 68.231587 -319.40529)
			(xy 68.286012 -319.376728) (xy 68.343483 -319.354934) (xy 68.403161 -319.340226) (xy 68.464178 -319.332819)
			(xy 68.49491 -319.332356) (xy 68.515992 -319.332864) (xy 68.526914 -319.333372) (xy 68.546472 -319.325752)
			(xy 68.614798 -319.257426) (xy 68.622418 -319.237868) (xy 68.62191 -319.226946) (xy 68.621402 -319.205864)
			(xy 68.621904 -319.173903) (xy 68.629915 -319.110485) (xy 68.645812 -319.048571) (xy 68.669344 -318.989138)
			(xy 68.700138 -318.933123) (xy 68.737711 -318.881408) (xy 68.781468 -318.834811) (xy 68.830721 -318.794066)
			(xy 68.884692 -318.759815) (xy 68.942531 -318.732598) (xy 69.003324 -318.712845) (xy 69.066114 -318.700867)
			(xy 69.12991 -318.696854) (xy 69.193706 -318.700867) (xy 69.256496 -318.712845) (xy 69.317289 -318.732598)
			(xy 69.375128 -318.759815) (xy 69.429099 -318.794066) (xy 69.478352 -318.834811) (xy 69.522109 -318.881408)
			(xy 69.559682 -318.933123) (xy 69.590476 -318.989138) (xy 69.614008 -319.048571) (xy 69.629905 -319.110485)
			(xy 69.637916 -319.173903) (xy 69.638418 -319.205864) (xy 69.637955 -319.236561) (xy 69.63055 -319.297506)
			(xy 69.615855 -319.357114) (xy 69.594085 -319.414518) (xy 69.565557 -319.468881) (xy 69.548502 -319.494408)
			(xy 69.543061 -319.503176) (xy 69.538922 -319.52337) (xy 69.543037 -319.543569) (xy 69.548502 -319.55232)
			(xy 69.565544 -319.577853) (xy 69.594052 -319.632223) (xy 69.615814 -319.689626) (xy 69.630513 -319.74923)
			(xy 69.637937 -319.810169) (xy 69.638418 -319.840864) (xy 69.637985 -319.869817) (xy 69.631376 -319.927346)
			(xy 69.618284 -319.983754) (xy 69.59888 -320.038313) (xy 69.573412 -320.09032) (xy 69.558154 -320.11493)
			(xy 69.552969 -320.123931) (xy 69.549566 -320.144399) (xy 69.554553 -320.164539) (xy 69.56044 -320.173096)
			(xy 69.579954 -320.19973) (xy 69.612715 -320.257056) (xy 69.637783 -320.318139) (xy 69.654736 -320.381952)
			(xy 69.663288 -320.447423) (xy 69.663818 -320.480436) (xy 69.663341 -320.511132) (xy 69.655939 -320.572077)
			(xy 69.641247 -320.631685) (xy 69.61948 -320.689089) (xy 69.590955 -320.743452) (xy 69.573902 -320.76898)
			(xy 69.568399 -320.777715) (xy 69.56428 -320.79793) (xy 69.568422 -320.81814) (xy 69.573902 -320.826892)
			(xy 69.590932 -320.852433) (xy 69.619442 -320.9068) (xy 69.641206 -320.964202) (xy 69.655909 -321.023804)
			(xy 69.663336 -321.084742) (xy 69.663818 -321.115436) (xy 69.663341 -321.146132) (xy 69.655939 -321.207077)
			(xy 69.641247 -321.266685) (xy 69.61948 -321.324089) (xy 69.590955 -321.378452) (xy 69.573902 -321.40398)
			(xy 69.568399 -321.412715) (xy 69.56428 -321.43293) (xy 69.568422 -321.45314) (xy 69.573902 -321.461892)
			(xy 69.590932 -321.487433) (xy 69.619442 -321.5418) (xy 69.641206 -321.599202) (xy 69.655909 -321.658804)
			(xy 69.663336 -321.719742) (xy 69.663818 -321.750436) (xy 69.663341 -321.781132) (xy 69.655939 -321.842077)
			(xy 69.641247 -321.901685) (xy 69.61948 -321.959089) (xy 69.590955 -322.013452) (xy 69.573902 -322.03898)
			(xy 69.568399 -322.047715) (xy 69.56428 -322.06793) (xy 69.568422 -322.08814) (xy 69.573902 -322.096892)
			(xy 69.590932 -322.122433) (xy 69.619442 -322.1768) (xy 69.641206 -322.234202) (xy 69.655909 -322.293804)
			(xy 69.663336 -322.354742) (xy 69.663818 -322.385436) (xy 69.663283 -322.41845) (xy 69.654743 -322.483924)
			(xy 69.637799 -322.547741) (xy 69.612735 -322.608828) (xy 69.579974 -322.666156) (xy 69.56044 -322.692776)
			(xy 69.554544 -322.70138) (xy 69.549648 -322.721639) (xy 69.553152 -322.742184) (xy 69.558408 -322.751196)
			(xy 69.574273 -322.776142) (xy 69.600784 -322.828984) (xy 69.620996 -322.884541) (xy 69.634638 -322.942065)
			(xy 69.641527 -323.000782) (xy 69.641974 -323.030342) (xy 71.368158 -323.030342) (xy 71.368686 -322.997328)
			(xy 71.377228 -322.931854) (xy 71.394174 -322.868036) (xy 71.41924 -322.80695) (xy 71.452002 -322.749622)
			(xy 71.471536 -322.723002) (xy 71.477367 -322.71436) (xy 71.482286 -322.694124) (xy 71.478809 -322.673592)
			(xy 71.473568 -322.664582) (xy 71.457691 -322.639644) (xy 71.431183 -322.586799) (xy 71.410973 -322.53124)
			(xy 71.397334 -322.473714) (xy 71.390448 -322.414996) (xy 71.390002 -322.385436) (xy 71.390462 -322.354739)
			(xy 71.397867 -322.293794) (xy 71.412562 -322.234185) (xy 71.434333 -322.176781) (xy 71.462863 -322.122419)
			(xy 71.479918 -322.096892) (xy 71.485358 -322.088123) (xy 71.489495 -322.06793) (xy 71.485382 -322.047732)
			(xy 71.479918 -322.03898) (xy 71.462878 -322.013445) (xy 71.434369 -321.959076) (xy 71.412607 -321.901673)
			(xy 71.397907 -321.84207) (xy 71.390483 -321.781131) (xy 71.390002 -321.750436) (xy 71.390462 -321.719739)
			(xy 71.397867 -321.658794) (xy 71.412562 -321.599185) (xy 71.434333 -321.541781) (xy 71.462863 -321.487419)
			(xy 71.479918 -321.461892) (xy 71.485358 -321.453123) (xy 71.489495 -321.43293) (xy 71.485382 -321.412732)
			(xy 71.479918 -321.40398) (xy 71.462878 -321.378445) (xy 71.434369 -321.324076) (xy 71.412607 -321.266673)
			(xy 71.397907 -321.20707) (xy 71.390483 -321.146131) (xy 71.390002 -321.115436) (xy 71.390462 -321.084739)
			(xy 71.397867 -321.023794) (xy 71.412562 -320.964185) (xy 71.434333 -320.906781) (xy 71.462863 -320.852419)
			(xy 71.479918 -320.826892) (xy 71.485358 -320.818123) (xy 71.489495 -320.79793) (xy 71.485382 -320.777732)
			(xy 71.479918 -320.76898) (xy 71.462878 -320.743445) (xy 71.434369 -320.689076) (xy 71.412607 -320.631673)
			(xy 71.397907 -320.57207) (xy 71.390483 -320.511131) (xy 71.390002 -320.480436) (xy 71.390444 -320.449462)
			(xy 71.39798 -320.387974) (xy 71.412933 -320.327858) (xy 71.43508 -320.270004) (xy 71.464094 -320.21527)
			(xy 71.481442 -320.189606) (xy 71.486868 -320.18083) (xy 71.491007 -320.160642) (xy 71.486901 -320.140446)
			(xy 71.481442 -320.131694) (xy 71.464082 -320.106038) (xy 71.435072 -320.051302) (xy 71.412931 -319.993446)
			(xy 71.397987 -319.933327) (xy 71.390461 -319.871838) (xy 71.390002 -319.840864) (xy 71.390476 -319.810168)
			(xy 71.397878 -319.749223) (xy 71.41257 -319.689614) (xy 71.434338 -319.63221) (xy 71.462864 -319.577847)
			(xy 71.479918 -319.55232) (xy 71.48542 -319.543584) (xy 71.489537 -319.52337) (xy 71.485396 -319.503161)
			(xy 71.479918 -319.494408) (xy 71.462891 -319.468865) (xy 71.43438 -319.414499) (xy 71.412615 -319.357098)
			(xy 71.397912 -319.297496) (xy 71.390484 -319.236558) (xy 71.390002 -319.205864) (xy 71.390476 -319.175168)
			(xy 71.397878 -319.114223) (xy 71.41257 -319.054614) (xy 71.434338 -318.99721) (xy 71.462864 -318.942847)
			(xy 71.479918 -318.91732) (xy 71.48542 -318.908584) (xy 71.489537 -318.88837) (xy 71.485396 -318.868161)
			(xy 71.479918 -318.859408) (xy 71.462891 -318.833865) (xy 71.43438 -318.779499) (xy 71.412615 -318.722098)
			(xy 71.397912 -318.662496) (xy 71.390484 -318.601558) (xy 71.390002 -318.570864) (xy 71.390476 -318.540168)
			(xy 71.397878 -318.479223) (xy 71.41257 -318.419614) (xy 71.434338 -318.36221) (xy 71.462864 -318.307847)
			(xy 71.479918 -318.28232) (xy 71.48542 -318.273584) (xy 71.489537 -318.25337) (xy 71.485396 -318.233161)
			(xy 71.479918 -318.224408) (xy 71.462891 -318.198865) (xy 71.43438 -318.144499) (xy 71.412615 -318.087098)
			(xy 71.397912 -318.027496) (xy 71.390484 -317.966558) (xy 71.390002 -317.935864) (xy 71.390476 -317.905168)
			(xy 71.397878 -317.844223) (xy 71.41257 -317.784614) (xy 71.434338 -317.72721) (xy 71.462864 -317.672847)
			(xy 71.479918 -317.64732) (xy 71.48542 -317.638584) (xy 71.489537 -317.61837) (xy 71.485396 -317.598161)
			(xy 71.479918 -317.589408) (xy 71.462891 -317.563865) (xy 71.43438 -317.509499) (xy 71.412615 -317.452098)
			(xy 71.397912 -317.392496) (xy 71.390484 -317.331558) (xy 71.390002 -317.300864) (xy 71.390476 -317.270168)
			(xy 71.397878 -317.209223) (xy 71.41257 -317.149614) (xy 71.434338 -317.09221) (xy 71.462864 -317.037847)
			(xy 71.479918 -317.01232) (xy 71.48542 -317.003584) (xy 71.489537 -316.98337) (xy 71.485396 -316.963161)
			(xy 71.479918 -316.954408) (xy 71.462891 -316.928865) (xy 71.43438 -316.874499) (xy 71.412615 -316.817098)
			(xy 71.397912 -316.757496) (xy 71.390484 -316.696558) (xy 71.390002 -316.665864) (xy 71.390422 -316.635132)
			(xy 71.397835 -316.574116) (xy 71.412548 -316.514439) (xy 71.434347 -316.45697) (xy 71.462914 -316.402547)
			(xy 71.497832 -316.351965) (xy 71.538593 -316.30596) (xy 71.584601 -316.265204) (xy 71.635187 -316.23029)
			(xy 71.689612 -316.201728) (xy 71.747083 -316.179934) (xy 71.806761 -316.165226) (xy 71.867778 -316.157819)
			(xy 71.89851 -316.157356) (xy 71.929206 -316.157851) (xy 71.990149 -316.165249) (xy 72.049758 -316.179937)
			(xy 72.107162 -316.2017) (xy 72.161526 -316.230221) (xy 72.187054 -316.247272) (xy 72.195806 -316.252743)
			(xy 72.21601 -316.256871) (xy 72.236214 -316.252743) (xy 72.244966 -316.247272) (xy 72.270492 -316.230219)
			(xy 72.324863 -316.201711) (xy 72.382268 -316.179951) (xy 72.441874 -316.165254) (xy 72.502815 -316.157834)
			(xy 72.53351 -316.157356) (xy 72.564206 -316.157851) (xy 72.625149 -316.165249) (xy 72.684758 -316.179937)
			(xy 72.742162 -316.2017) (xy 72.796526 -316.230221) (xy 72.822054 -316.247272) (xy 72.830806 -316.252743)
			(xy 72.85101 -316.256871) (xy 72.871214 -316.252743) (xy 72.879966 -316.247272) (xy 72.905492 -316.230219)
			(xy 72.959863 -316.201711) (xy 73.017268 -316.179951) (xy 73.076874 -316.165254) (xy 73.137815 -316.157834)
			(xy 73.16851 -316.157356) (xy 73.19924 -316.157847) (xy 73.260251 -316.165256) (xy 73.319925 -316.179964)
			(xy 73.377391 -316.201758) (xy 73.431811 -316.230319) (xy 73.482392 -316.265232) (xy 73.528396 -316.305986)
			(xy 73.569152 -316.351988) (xy 73.604067 -316.402567) (xy 73.632631 -316.456986) (xy 73.654428 -316.51445)
			(xy 73.66914 -316.574123) (xy 73.676552 -316.635134) (xy 73.677018 -316.665864) (xy 73.676555 -316.696561)
			(xy 73.66915 -316.757506) (xy 73.654455 -316.817114) (xy 73.632685 -316.874518) (xy 73.604157 -316.928881)
			(xy 73.587102 -316.954408) (xy 73.581661 -316.963176) (xy 73.577522 -316.98337) (xy 73.581637 -317.003569)
			(xy 73.587102 -317.01232) (xy 73.604144 -317.037853) (xy 73.632652 -317.092223) (xy 73.654414 -317.149626)
			(xy 73.669113 -317.20923) (xy 73.676537 -317.270169) (xy 73.677018 -317.300864) (xy 73.676555 -317.331561)
			(xy 73.66915 -317.392506) (xy 73.654455 -317.452114) (xy 73.632685 -317.509518) (xy 73.604157 -317.563881)
			(xy 73.587102 -317.589408) (xy 73.581661 -317.598176) (xy 73.577522 -317.61837) (xy 73.581637 -317.638569)
			(xy 73.587102 -317.64732) (xy 73.604144 -317.672853) (xy 73.632652 -317.727223) (xy 73.654414 -317.784626)
			(xy 73.669113 -317.84423) (xy 73.676537 -317.905169) (xy 73.677018 -317.935864) (xy 73.676555 -317.966561)
			(xy 73.66915 -318.027506) (xy 73.654455 -318.087114) (xy 73.632685 -318.144518) (xy 73.604157 -318.198881)
			(xy 73.587102 -318.224408) (xy 73.581661 -318.233176) (xy 73.577522 -318.25337) (xy 73.581637 -318.273569)
			(xy 73.587102 -318.28232) (xy 73.604144 -318.307853) (xy 73.632652 -318.362223) (xy 73.654414 -318.419626)
			(xy 73.669113 -318.47923) (xy 73.676537 -318.540169) (xy 73.677018 -318.570864) (xy 73.676555 -318.601561)
			(xy 73.66915 -318.662506) (xy 73.654455 -318.722114) (xy 73.632685 -318.779518) (xy 73.604157 -318.833881)
			(xy 73.587102 -318.859408) (xy 73.581661 -318.868176) (xy 73.577522 -318.88837) (xy 73.581637 -318.908569)
			(xy 73.587102 -318.91732) (xy 73.604144 -318.942853) (xy 73.632652 -318.997223) (xy 73.654414 -319.054626)
			(xy 73.669113 -319.11423) (xy 73.676537 -319.175169) (xy 73.677018 -319.205864) (xy 73.676555 -319.236561)
			(xy 73.66915 -319.297506) (xy 73.654455 -319.357114) (xy 73.632685 -319.414518) (xy 73.604157 -319.468881)
			(xy 73.587102 -319.494408) (xy 73.581661 -319.503176) (xy 73.577522 -319.52337) (xy 73.581637 -319.543569)
			(xy 73.587102 -319.55232) (xy 73.604144 -319.577853) (xy 73.632652 -319.632223) (xy 73.654414 -319.689626)
			(xy 73.669113 -319.74923) (xy 73.676537 -319.810169) (xy 73.677018 -319.840864) (xy 73.676555 -319.871561)
			(xy 73.66915 -319.932506) (xy 73.654455 -319.992114) (xy 73.632685 -320.049518) (xy 73.604157 -320.103881)
			(xy 73.587102 -320.129408) (xy 73.581661 -320.138176) (xy 73.577522 -320.15837) (xy 73.581637 -320.178569)
			(xy 73.587102 -320.18732) (xy 73.604144 -320.212853) (xy 73.632652 -320.267223) (xy 73.654414 -320.324626)
			(xy 73.669113 -320.38423) (xy 73.676537 -320.445169) (xy 73.677018 -320.475864) (xy 73.676555 -320.506561)
			(xy 73.66915 -320.567506) (xy 73.654455 -320.627114) (xy 73.632685 -320.684518) (xy 73.604157 -320.738881)
			(xy 73.587102 -320.764408) (xy 73.581661 -320.773176) (xy 73.577522 -320.79337) (xy 73.581637 -320.813569)
			(xy 73.587102 -320.82232) (xy 73.604144 -320.847853) (xy 73.632652 -320.902223) (xy 73.654414 -320.959626)
			(xy 73.669113 -321.01923) (xy 73.676537 -321.080169) (xy 73.677018 -321.110864) (xy 73.676555 -321.141561)
			(xy 73.66915 -321.202506) (xy 73.654455 -321.262114) (xy 73.632685 -321.319518) (xy 73.604157 -321.373881)
			(xy 73.587102 -321.399408) (xy 73.581661 -321.408176) (xy 73.577522 -321.42837) (xy 73.581637 -321.448569)
			(xy 73.587102 -321.45732) (xy 73.604144 -321.482853) (xy 73.632652 -321.537223) (xy 73.654414 -321.594626)
			(xy 73.669113 -321.65423) (xy 73.676537 -321.715169) (xy 73.677018 -321.745864) (xy 73.676555 -321.776561)
			(xy 73.66915 -321.837506) (xy 73.654455 -321.897114) (xy 73.632685 -321.954518) (xy 73.604157 -322.008881)
			(xy 73.587102 -322.034408) (xy 73.581661 -322.043176) (xy 73.577522 -322.06337) (xy 73.581637 -322.083569)
			(xy 73.587102 -322.09232) (xy 73.604144 -322.117853) (xy 73.632652 -322.172223) (xy 73.654414 -322.229626)
			(xy 73.669113 -322.28923) (xy 73.676537 -322.350169) (xy 73.67668 -322.359274) (xy 75.706986 -322.359274)
			(xy 75.707468 -322.328578) (xy 75.714868 -322.267634) (xy 75.729559 -322.208025) (xy 75.751325 -322.150621)
			(xy 75.779849 -322.096258) (xy 75.796902 -322.07073) (xy 75.802396 -322.06199) (xy 75.806517 -322.041778)
			(xy 75.802379 -322.02157) (xy 75.796902 -322.012818) (xy 75.779877 -321.987274) (xy 75.751366 -321.932908)
			(xy 75.729601 -321.875507) (xy 75.714897 -321.815905) (xy 75.707469 -321.754968) (xy 75.706986 -321.724274)
			(xy 75.707468 -321.693578) (xy 75.714868 -321.632634) (xy 75.729559 -321.573025) (xy 75.751325 -321.515621)
			(xy 75.779849 -321.461258) (xy 75.796902 -321.43573) (xy 75.802396 -321.42699) (xy 75.806517 -321.406778)
			(xy 75.802379 -321.38657) (xy 75.796902 -321.377818) (xy 75.779877 -321.352274) (xy 75.751366 -321.297908)
			(xy 75.729601 -321.240507) (xy 75.714897 -321.180905) (xy 75.707469 -321.119968) (xy 75.706986 -321.089274)
			(xy 75.707468 -321.058578) (xy 75.714868 -320.997634) (xy 75.729559 -320.938025) (xy 75.751325 -320.880621)
			(xy 75.779849 -320.826258) (xy 75.796902 -320.80073) (xy 75.802396 -320.79199) (xy 75.806517 -320.771778)
			(xy 75.802379 -320.75157) (xy 75.796902 -320.742818) (xy 75.779877 -320.717274) (xy 75.751366 -320.662908)
			(xy 75.729601 -320.605507) (xy 75.714897 -320.545905) (xy 75.707469 -320.484968) (xy 75.706986 -320.454274)
			(xy 75.707468 -320.423578) (xy 75.714868 -320.362634) (xy 75.729559 -320.303025) (xy 75.751325 -320.245621)
			(xy 75.779849 -320.191258) (xy 75.796902 -320.16573) (xy 75.802396 -320.15699) (xy 75.806517 -320.136778)
			(xy 75.802379 -320.11657) (xy 75.796902 -320.107818) (xy 75.779877 -320.082274) (xy 75.751366 -320.027908)
			(xy 75.729601 -319.970507) (xy 75.714897 -319.910905) (xy 75.707469 -319.849968) (xy 75.706986 -319.819274)
			(xy 75.707468 -319.788578) (xy 75.714868 -319.727634) (xy 75.729559 -319.668025) (xy 75.751325 -319.610621)
			(xy 75.779849 -319.556258) (xy 75.796902 -319.53073) (xy 75.802396 -319.52199) (xy 75.806517 -319.501778)
			(xy 75.802379 -319.48157) (xy 75.796902 -319.472818) (xy 75.779877 -319.447274) (xy 75.751366 -319.392908)
			(xy 75.729601 -319.335507) (xy 75.714897 -319.275905) (xy 75.707469 -319.214968) (xy 75.706986 -319.184274)
			(xy 75.707468 -319.153578) (xy 75.714868 -319.092634) (xy 75.729559 -319.033025) (xy 75.751325 -318.975621)
			(xy 75.779849 -318.921258) (xy 75.796902 -318.89573) (xy 75.802396 -318.88699) (xy 75.806517 -318.866778)
			(xy 75.802379 -318.84657) (xy 75.796902 -318.837818) (xy 75.779877 -318.812274) (xy 75.751366 -318.757908)
			(xy 75.729601 -318.700507) (xy 75.714897 -318.640905) (xy 75.707469 -318.579968) (xy 75.706986 -318.549274)
			(xy 75.707468 -318.518578) (xy 75.714868 -318.457634) (xy 75.729559 -318.398025) (xy 75.751325 -318.340621)
			(xy 75.779849 -318.286258) (xy 75.796902 -318.26073) (xy 75.802396 -318.25199) (xy 75.806517 -318.231778)
			(xy 75.802379 -318.21157) (xy 75.796902 -318.202818) (xy 75.779877 -318.177274) (xy 75.751366 -318.122908)
			(xy 75.729601 -318.065507) (xy 75.714897 -318.005905) (xy 75.707469 -317.944968) (xy 75.706986 -317.914274)
			(xy 75.707468 -317.883578) (xy 75.714868 -317.822634) (xy 75.729559 -317.763025) (xy 75.751325 -317.705621)
			(xy 75.779849 -317.651258) (xy 75.796902 -317.62573) (xy 75.802396 -317.61699) (xy 75.806517 -317.596778)
			(xy 75.802379 -317.57657) (xy 75.796902 -317.567818) (xy 75.779877 -317.542274) (xy 75.751366 -317.487908)
			(xy 75.729601 -317.430507) (xy 75.714897 -317.370905) (xy 75.707469 -317.309968) (xy 75.706986 -317.279274)
			(xy 75.707468 -317.248578) (xy 75.714868 -317.187634) (xy 75.729559 -317.128025) (xy 75.751325 -317.070621)
			(xy 75.779849 -317.016258) (xy 75.796902 -316.99073) (xy 75.802396 -316.98199) (xy 75.806517 -316.961778)
			(xy 75.802379 -316.94157) (xy 75.796902 -316.932818) (xy 75.779877 -316.907274) (xy 75.751366 -316.852908)
			(xy 75.729601 -316.795507) (xy 75.714897 -316.735905) (xy 75.707469 -316.674968) (xy 75.706986 -316.644274)
			(xy 75.707432 -316.613543) (xy 75.714843 -316.552528) (xy 75.729554 -316.492852) (xy 75.751351 -316.435385)
			(xy 75.779916 -316.380963) (xy 75.814832 -316.330381) (xy 75.855591 -316.284377) (xy 75.901597 -316.24362)
			(xy 75.95218 -316.208706) (xy 76.006603 -316.180143) (xy 76.064072 -316.158348) (xy 76.123748 -316.143639)
			(xy 76.184763 -316.13623) (xy 76.215494 -316.135766) (xy 76.246191 -316.136217) (xy 76.307136 -316.143625)
			(xy 76.366745 -316.158323) (xy 76.424149 -316.180096) (xy 76.478511 -316.208626) (xy 76.504038 -316.225682)
			(xy 76.51279 -316.231153) (xy 76.532994 -316.235281) (xy 76.553198 -316.231153) (xy 76.56195 -316.225682)
			(xy 76.587482 -316.208637) (xy 76.641851 -316.180127) (xy 76.699254 -316.158365) (xy 76.758859 -316.143667)
			(xy 76.819799 -316.136245) (xy 76.850494 -316.135766) (xy 76.881191 -316.136217) (xy 76.942136 -316.143625)
			(xy 77.001745 -316.158323) (xy 77.059149 -316.180096) (xy 77.113511 -316.208626) (xy 77.139038 -316.225682)
			(xy 77.14779 -316.231153) (xy 77.167994 -316.235281) (xy 77.188198 -316.231153) (xy 77.19695 -316.225682)
			(xy 77.222482 -316.208637) (xy 77.276851 -316.180127) (xy 77.334254 -316.158365) (xy 77.393859 -316.143667)
			(xy 77.454799 -316.136245) (xy 77.485494 -316.135766) (xy 77.516224 -316.136262) (xy 77.577236 -316.143669)
			(xy 77.63691 -316.158376) (xy 77.694376 -316.180169) (xy 77.748797 -316.208729) (xy 77.799378 -316.243641)
			(xy 77.845382 -316.284395) (xy 77.886139 -316.330397) (xy 77.921054 -316.380976) (xy 77.949618 -316.435395)
			(xy 77.971414 -316.49286) (xy 77.986125 -316.552533) (xy 77.993536 -316.613544) (xy 77.994002 -316.644274)
			(xy 77.993547 -316.674971) (xy 77.98614 -316.735916) (xy 77.971444 -316.795525) (xy 77.949672 -316.852929)
			(xy 77.921142 -316.907291) (xy 77.904086 -316.932818) (xy 77.898637 -316.941582) (xy 77.894502 -316.961778)
			(xy 77.89862 -316.981978) (xy 77.904086 -316.99073) (xy 77.92113 -317.016262) (xy 77.949638 -317.070631)
			(xy 77.9714 -317.128035) (xy 77.986099 -317.18764) (xy 77.993522 -317.248579) (xy 77.994002 -317.279274)
			(xy 77.993547 -317.309971) (xy 77.98614 -317.370916) (xy 77.971444 -317.430525) (xy 77.949672 -317.487929)
			(xy 77.921142 -317.542291) (xy 77.904086 -317.567818) (xy 77.898637 -317.576582) (xy 77.894502 -317.596778)
			(xy 77.89862 -317.616978) (xy 77.904086 -317.62573) (xy 77.92113 -317.651262) (xy 77.949638 -317.705631)
			(xy 77.9714 -317.763035) (xy 77.986099 -317.82264) (xy 77.993522 -317.883579) (xy 77.994002 -317.914274)
			(xy 77.993547 -317.944971) (xy 77.98614 -318.005916) (xy 77.971444 -318.065525) (xy 77.949672 -318.122929)
			(xy 77.921142 -318.177291) (xy 77.904086 -318.202818) (xy 77.898637 -318.211582) (xy 77.894502 -318.231778)
			(xy 77.89862 -318.251978) (xy 77.904086 -318.26073) (xy 77.92113 -318.286262) (xy 77.949638 -318.340631)
			(xy 77.9714 -318.398035) (xy 77.986099 -318.45764) (xy 77.993522 -318.518579) (xy 77.994002 -318.549274)
			(xy 77.993547 -318.579971) (xy 77.98614 -318.640916) (xy 77.971444 -318.700525) (xy 77.949672 -318.757929)
			(xy 77.921142 -318.812291) (xy 77.904086 -318.837818) (xy 77.898637 -318.846582) (xy 77.894502 -318.866778)
			(xy 77.89862 -318.886978) (xy 77.904086 -318.89573) (xy 77.92113 -318.921262) (xy 77.949638 -318.975631)
			(xy 77.9714 -319.033035) (xy 77.986099 -319.09264) (xy 77.993522 -319.153579) (xy 77.994002 -319.184274)
			(xy 77.993547 -319.214971) (xy 77.98614 -319.275916) (xy 77.971444 -319.335525) (xy 77.949672 -319.392929)
			(xy 77.921142 -319.447291) (xy 77.904086 -319.472818) (xy 77.898637 -319.481582) (xy 77.894502 -319.501778)
			(xy 77.89862 -319.521978) (xy 77.904086 -319.53073) (xy 77.92113 -319.556262) (xy 77.949638 -319.610631)
			(xy 77.9714 -319.668035) (xy 77.986099 -319.72764) (xy 77.993522 -319.788579) (xy 77.994002 -319.819274)
			(xy 77.99356 -319.848227) (xy 77.986951 -319.905755) (xy 77.973861 -319.962163) (xy 77.954459 -320.016722)
			(xy 77.928994 -320.068729) (xy 77.913738 -320.09334) (xy 77.908534 -320.102333) (xy 77.905128 -320.122807)
			(xy 77.910127 -320.142952) (xy 77.916024 -320.151506) (xy 77.93554 -320.178139) (xy 77.968302 -320.235465)
			(xy 77.993369 -320.296548) (xy 78.010321 -320.360362) (xy 78.018873 -320.425833) (xy 78.019402 -320.458846)
			(xy 78.018933 -320.489542) (xy 78.011529 -320.550487) (xy 77.996836 -320.610096) (xy 77.975067 -320.6675)
			(xy 77.94654 -320.721863) (xy 77.929486 -320.74739) (xy 77.923975 -320.756121) (xy 77.919861 -320.776338)
			(xy 77.924006 -320.796549) (xy 77.929486 -320.805302) (xy 77.946518 -320.830842) (xy 77.975028 -320.885209)
			(xy 77.996792 -320.942611) (xy 78.011494 -321.002213) (xy 78.01892 -321.063152) (xy 78.019402 -321.093846)
			(xy 78.018933 -321.124542) (xy 78.011529 -321.185487) (xy 77.996836 -321.245096) (xy 77.975067 -321.3025)
			(xy 77.94654 -321.356863) (xy 77.929486 -321.38239) (xy 77.923975 -321.391121) (xy 77.919861 -321.411338)
			(xy 77.924006 -321.431549) (xy 77.929486 -321.440302) (xy 77.946518 -321.465842) (xy 77.975028 -321.520209)
			(xy 77.996792 -321.577611) (xy 78.011494 -321.637213) (xy 78.01892 -321.698152) (xy 78.019402 -321.728846)
			(xy 78.018933 -321.759542) (xy 78.011529 -321.820487) (xy 77.996836 -321.880096) (xy 77.975067 -321.9375)
			(xy 77.94654 -321.991863) (xy 77.929486 -322.01739) (xy 77.923975 -322.026121) (xy 77.919861 -322.046338)
			(xy 77.924006 -322.066549) (xy 77.929486 -322.075302) (xy 77.946518 -322.100842) (xy 77.975028 -322.155209)
			(xy 77.996792 -322.212611) (xy 78.011494 -322.272213) (xy 78.01892 -322.333152) (xy 78.019402 -322.363846)
			(xy 78.018876 -322.396861) (xy 78.010334 -322.462335) (xy 77.993388 -322.526152) (xy 77.968322 -322.587239)
			(xy 77.935559 -322.644566) (xy 77.916024 -322.671186) (xy 77.910205 -322.679835) (xy 77.905286 -322.700066)
			(xy 77.908756 -322.720595) (xy 77.913992 -322.729606) (xy 77.929859 -322.75455) (xy 77.95637 -322.807393)
			(xy 77.976582 -322.86295) (xy 77.990224 -322.920475) (xy 77.997111 -322.979192) (xy 77.997558 -323.008752)
			(xy 79.723742 -323.008752) (xy 79.724279 -322.975738) (xy 79.732819 -322.910264) (xy 79.749764 -322.846447)
			(xy 79.774827 -322.785361) (xy 79.807587 -322.728033) (xy 79.82712 -322.701412) (xy 79.832939 -322.692764)
			(xy 79.837852 -322.672533) (xy 79.834385 -322.652004) (xy 79.829152 -322.642992) (xy 79.813278 -322.618052)
			(xy 79.786769 -322.565208) (xy 79.766559 -322.509649) (xy 79.752919 -322.452124) (xy 79.746033 -322.393406)
			(xy 79.745586 -322.363846) (xy 79.746053 -322.33315) (xy 79.753457 -322.272205) (xy 79.768151 -322.212596)
			(xy 79.78992 -322.155192) (xy 79.818448 -322.100829) (xy 79.835502 -322.075302) (xy 79.840935 -322.066529)
			(xy 79.845076 -322.046338) (xy 79.840965 -322.026141) (xy 79.835502 -322.01739) (xy 79.818465 -321.991853)
			(xy 79.789956 -321.937485) (xy 79.768193 -321.880083) (xy 79.753492 -321.820479) (xy 79.746067 -321.75954)
			(xy 79.745586 -321.728846) (xy 79.746053 -321.69815) (xy 79.753457 -321.637205) (xy 79.768151 -321.577596)
			(xy 79.78992 -321.520192) (xy 79.818448 -321.465829) (xy 79.835502 -321.440302) (xy 79.840935 -321.431529)
			(xy 79.845076 -321.411338) (xy 79.840965 -321.391141) (xy 79.835502 -321.38239) (xy 79.818465 -321.356853)
			(xy 79.789956 -321.302485) (xy 79.768193 -321.245083) (xy 79.753492 -321.185479) (xy 79.746067 -321.12454)
			(xy 79.745586 -321.093846) (xy 79.746053 -321.06315) (xy 79.753457 -321.002205) (xy 79.768151 -320.942596)
			(xy 79.78992 -320.885192) (xy 79.818448 -320.830829) (xy 79.835502 -320.805302) (xy 79.840935 -320.796529)
			(xy 79.845076 -320.776338) (xy 79.840965 -320.756141) (xy 79.835502 -320.74739) (xy 79.818465 -320.721853)
			(xy 79.789956 -320.667485) (xy 79.768193 -320.610083) (xy 79.753492 -320.550479) (xy 79.746067 -320.48954)
			(xy 79.745586 -320.458846) (xy 79.746036 -320.427872) (xy 79.75357 -320.366385) (xy 79.768521 -320.306268)
			(xy 79.790667 -320.248415) (xy 79.819679 -320.193681) (xy 79.837026 -320.168016) (xy 79.84253 -320.159282)
			(xy 79.846646 -320.139067) (xy 79.842504 -320.118857) (xy 79.837026 -320.110104) (xy 79.819669 -320.084446)
			(xy 79.790659 -320.029711) (xy 79.768517 -319.971855) (xy 79.753572 -319.911737) (xy 79.746045 -319.850248)
			(xy 79.745586 -319.819274) (xy 79.746068 -319.788578) (xy 79.753468 -319.727634) (xy 79.768159 -319.668025)
			(xy 79.789925 -319.610621) (xy 79.818449 -319.556258) (xy 79.835502 -319.53073) (xy 79.840996 -319.52199)
			(xy 79.845117 -319.501778) (xy 79.840979 -319.48157) (xy 79.835502 -319.472818) (xy 79.818477 -319.447274)
			(xy 79.789966 -319.392908) (xy 79.768201 -319.335507) (xy 79.753497 -319.275905) (xy 79.746069 -319.214968)
			(xy 79.745586 -319.184274) (xy 79.746068 -319.153578) (xy 79.753468 -319.092634) (xy 79.768159 -319.033025)
			(xy 79.789925 -318.975621) (xy 79.818449 -318.921258) (xy 79.835502 -318.89573) (xy 79.840996 -318.88699)
			(xy 79.845117 -318.866778) (xy 79.840979 -318.84657) (xy 79.835502 -318.837818) (xy 79.818477 -318.812274)
			(xy 79.789966 -318.757908) (xy 79.768201 -318.700507) (xy 79.753497 -318.640905) (xy 79.746069 -318.579968)
			(xy 79.745586 -318.549274) (xy 79.746068 -318.518578) (xy 79.753468 -318.457634) (xy 79.768159 -318.398025)
			(xy 79.789925 -318.340621) (xy 79.818449 -318.286258) (xy 79.835502 -318.26073) (xy 79.840996 -318.25199)
			(xy 79.845117 -318.231778) (xy 79.840979 -318.21157) (xy 79.835502 -318.202818) (xy 79.818477 -318.177274)
			(xy 79.789966 -318.122908) (xy 79.768201 -318.065507) (xy 79.753497 -318.005905) (xy 79.746069 -317.944968)
			(xy 79.745586 -317.914274) (xy 79.746068 -317.883578) (xy 79.753468 -317.822634) (xy 79.768159 -317.763025)
			(xy 79.789925 -317.705621) (xy 79.818449 -317.651258) (xy 79.835502 -317.62573) (xy 79.840996 -317.61699)
			(xy 79.845117 -317.596778) (xy 79.840979 -317.57657) (xy 79.835502 -317.567818) (xy 79.818477 -317.542274)
			(xy 79.789966 -317.487908) (xy 79.768201 -317.430507) (xy 79.753497 -317.370905) (xy 79.746069 -317.309968)
			(xy 79.745586 -317.279274) (xy 79.746068 -317.248578) (xy 79.753468 -317.187634) (xy 79.768159 -317.128025)
			(xy 79.789925 -317.070621) (xy 79.818449 -317.016258) (xy 79.835502 -316.99073) (xy 79.840996 -316.98199)
			(xy 79.845117 -316.961778) (xy 79.840979 -316.94157) (xy 79.835502 -316.932818) (xy 79.818477 -316.907274)
			(xy 79.789966 -316.852908) (xy 79.768201 -316.795507) (xy 79.753497 -316.735905) (xy 79.746069 -316.674968)
			(xy 79.745586 -316.644274) (xy 79.746032 -316.613543) (xy 79.753443 -316.552528) (xy 79.768154 -316.492852)
			(xy 79.789951 -316.435385) (xy 79.818516 -316.380963) (xy 79.853432 -316.330381) (xy 79.894191 -316.284377)
			(xy 79.940197 -316.24362) (xy 79.99078 -316.208706) (xy 80.045203 -316.180143) (xy 80.102672 -316.158348)
			(xy 80.162348 -316.143639) (xy 80.223363 -316.13623) (xy 80.254094 -316.135766) (xy 80.284791 -316.136217)
			(xy 80.345736 -316.143625) (xy 80.405345 -316.158323) (xy 80.462749 -316.180096) (xy 80.517111 -316.208626)
			(xy 80.542638 -316.225682) (xy 80.55139 -316.231153) (xy 80.571594 -316.235281) (xy 80.591798 -316.231153)
			(xy 80.60055 -316.225682) (xy 80.626082 -316.208637) (xy 80.680451 -316.180127) (xy 80.737854 -316.158365)
			(xy 80.797459 -316.143667) (xy 80.858399 -316.136245) (xy 80.889094 -316.135766) (xy 80.919791 -316.136217)
			(xy 80.980736 -316.143625) (xy 81.040345 -316.158323) (xy 81.097749 -316.180096) (xy 81.152111 -316.208626)
			(xy 81.177638 -316.225682) (xy 81.18639 -316.231153) (xy 81.206594 -316.235281) (xy 81.226798 -316.231153)
			(xy 81.23555 -316.225682) (xy 81.261082 -316.208637) (xy 81.315451 -316.180127) (xy 81.372854 -316.158365)
			(xy 81.432459 -316.143667) (xy 81.493399 -316.136245) (xy 81.524094 -316.135766) (xy 81.554824 -316.136262)
			(xy 81.615836 -316.143669) (xy 81.67551 -316.158376) (xy 81.732976 -316.180169) (xy 81.787397 -316.208729)
			(xy 81.837978 -316.243641) (xy 81.883982 -316.284395) (xy 81.924739 -316.330397) (xy 81.959654 -316.380976)
			(xy 81.988218 -316.435395) (xy 82.010014 -316.49286) (xy 82.024725 -316.552533) (xy 82.032136 -316.613544)
			(xy 82.032602 -316.644274) (xy 82.032147 -316.674971) (xy 82.02474 -316.735916) (xy 82.010044 -316.795525)
			(xy 81.988272 -316.852929) (xy 81.959742 -316.907291) (xy 81.942686 -316.932818) (xy 81.937237 -316.941582)
			(xy 81.933102 -316.961778) (xy 81.93722 -316.981978) (xy 81.942686 -316.99073) (xy 81.95973 -317.016262)
			(xy 81.988238 -317.070631) (xy 82.01 -317.128035) (xy 82.024699 -317.18764) (xy 82.032122 -317.248579)
			(xy 82.032602 -317.279274) (xy 82.032147 -317.309971) (xy 82.02474 -317.370916) (xy 82.010044 -317.430525)
			(xy 81.988272 -317.487929) (xy 81.959742 -317.542291) (xy 81.942686 -317.567818) (xy 81.937237 -317.576582)
			(xy 81.933102 -317.596778) (xy 81.93722 -317.616978) (xy 81.942686 -317.62573) (xy 81.95973 -317.651262)
			(xy 81.988238 -317.705631) (xy 82.01 -317.763035) (xy 82.024699 -317.82264) (xy 82.032122 -317.883579)
			(xy 82.032602 -317.914274) (xy 82.032147 -317.944971) (xy 82.02474 -318.005916) (xy 82.010044 -318.065525)
			(xy 81.988272 -318.122929) (xy 81.959742 -318.177291) (xy 81.942686 -318.202818) (xy 81.937237 -318.211582)
			(xy 81.933102 -318.231778) (xy 81.93722 -318.251978) (xy 81.942686 -318.26073) (xy 81.95973 -318.286262)
			(xy 81.988238 -318.340631) (xy 82.01 -318.398035) (xy 82.024699 -318.45764) (xy 82.032122 -318.518579)
			(xy 82.032602 -318.549274) (xy 82.032147 -318.579971) (xy 82.02474 -318.640916) (xy 82.010044 -318.700525)
			(xy 81.988272 -318.757929) (xy 81.959742 -318.812291) (xy 81.942686 -318.837818) (xy 81.937237 -318.846582)
			(xy 81.933102 -318.866778) (xy 81.93722 -318.886978) (xy 81.942686 -318.89573) (xy 81.95973 -318.921262)
			(xy 81.988238 -318.975631) (xy 82.01 -319.033035) (xy 82.024699 -319.09264) (xy 82.032122 -319.153579)
			(xy 82.032602 -319.184274) (xy 82.032147 -319.214971) (xy 82.02474 -319.275916) (xy 82.010044 -319.335525)
			(xy 81.988272 -319.392929) (xy 81.959742 -319.447291) (xy 81.942686 -319.472818) (xy 81.937237 -319.481582)
			(xy 81.933102 -319.501778) (xy 81.93722 -319.521978) (xy 81.942686 -319.53073) (xy 81.95973 -319.556262)
			(xy 81.988238 -319.610631) (xy 82.01 -319.668035) (xy 82.024699 -319.72764) (xy 82.032122 -319.788579)
			(xy 82.032602 -319.819274) (xy 82.032147 -319.849971) (xy 82.02474 -319.910916) (xy 82.010044 -319.970525)
			(xy 81.988272 -320.027929) (xy 81.959742 -320.082291) (xy 81.942686 -320.107818) (xy 81.937237 -320.116582)
			(xy 81.933102 -320.136778) (xy 81.93722 -320.156978) (xy 81.942686 -320.16573) (xy 81.95973 -320.191262)
			(xy 81.988238 -320.245631) (xy 82.01 -320.303035) (xy 82.024699 -320.36264) (xy 82.032122 -320.423579)
			(xy 82.032602 -320.454274) (xy 82.032147 -320.484971) (xy 82.02474 -320.545916) (xy 82.010044 -320.605525)
			(xy 81.988272 -320.662929) (xy 81.959742 -320.717291) (xy 81.942686 -320.742818) (xy 81.937237 -320.751582)
			(xy 81.933102 -320.771778) (xy 81.93722 -320.791978) (xy 81.942686 -320.80073) (xy 81.95973 -320.826262)
			(xy 81.988238 -320.880631) (xy 82.01 -320.938035) (xy 82.024699 -320.99764) (xy 82.032122 -321.058579)
			(xy 82.032602 -321.089274) (xy 82.032147 -321.119971) (xy 82.02474 -321.180916) (xy 82.010044 -321.240525)
			(xy 81.988272 -321.297929) (xy 81.959742 -321.352291) (xy 81.942686 -321.377818) (xy 81.937237 -321.386582)
			(xy 81.933102 -321.406778) (xy 81.93722 -321.426978) (xy 81.942686 -321.43573) (xy 81.95973 -321.461262)
			(xy 81.988238 -321.515631) (xy 82.01 -321.573035) (xy 82.024699 -321.63264) (xy 82.032122 -321.693579)
			(xy 82.032602 -321.724274) (xy 82.032147 -321.754971) (xy 82.02474 -321.815916) (xy 82.010044 -321.875525)
			(xy 81.988272 -321.932929) (xy 81.959742 -321.987291) (xy 81.942686 -322.012818) (xy 81.937237 -322.021582)
			(xy 81.933102 -322.041778) (xy 81.93722 -322.061978) (xy 81.942686 -322.07073) (xy 81.95973 -322.096262)
			(xy 81.988238 -322.150631) (xy 82.01 -322.208035) (xy 82.024699 -322.26764) (xy 82.032122 -322.328579)
			(xy 82.032602 -322.359274) (xy 82.032083 -322.392511) (xy 82.023453 -322.458421) (xy 82.006299 -322.522642)
			(xy 81.980913 -322.584076) (xy 81.94773 -322.641674) (xy 81.927954 -322.668392) (xy 81.921991 -322.677077)
			(xy 81.916975 -322.697515) (xy 81.920561 -322.718251) (xy 81.925922 -322.72732) (xy 81.942048 -322.752417)
			(xy 81.969005 -322.805636) (xy 81.989547 -322.861645) (xy 82.00339 -322.919673) (xy 82.010345 -322.978923)
			(xy 82.010758 -323.008752) (xy 84.063586 -323.008752) (xy 84.064056 -322.978056) (xy 84.07146 -322.917111)
			(xy 84.086153 -322.857502) (xy 84.107921 -322.800098) (xy 84.136448 -322.745735) (xy 84.153502 -322.720208)
			(xy 84.159015 -322.711478) (xy 84.16313 -322.69126) (xy 84.158984 -322.671048) (xy 84.153502 -322.662296)
			(xy 84.136467 -322.636758) (xy 84.107958 -322.58239) (xy 84.086195 -322.524988) (xy 84.071493 -322.465385)
			(xy 84.064068 -322.404446) (xy 84.063586 -322.373752) (xy 84.064056 -322.343056) (xy 84.07146 -322.282111)
			(xy 84.086153 -322.222502) (xy 84.107921 -322.165098) (xy 84.136448 -322.110735) (xy 84.153502 -322.085208)
			(xy 84.159015 -322.076478) (xy 84.16313 -322.05626) (xy 84.158984 -322.036048) (xy 84.153502 -322.027296)
			(xy 84.136467 -322.001758) (xy 84.107958 -321.94739) (xy 84.086195 -321.889988) (xy 84.071493 -321.830385)
			(xy 84.064068 -321.769446) (xy 84.063586 -321.738752) (xy 84.064056 -321.708056) (xy 84.07146 -321.647111)
			(xy 84.086153 -321.587502) (xy 84.107921 -321.530098) (xy 84.136448 -321.475735) (xy 84.153502 -321.450208)
			(xy 84.159015 -321.441478) (xy 84.16313 -321.42126) (xy 84.158984 -321.401048) (xy 84.153502 -321.392296)
			(xy 84.136467 -321.366758) (xy 84.107958 -321.31239) (xy 84.086195 -321.254988) (xy 84.071493 -321.195385)
			(xy 84.064068 -321.134446) (xy 84.063586 -321.103752) (xy 84.064056 -321.073056) (xy 84.07146 -321.012111)
			(xy 84.086153 -320.952502) (xy 84.107921 -320.895098) (xy 84.136448 -320.840735) (xy 84.153502 -320.815208)
			(xy 84.159015 -320.806478) (xy 84.16313 -320.78626) (xy 84.158984 -320.766048) (xy 84.153502 -320.757296)
			(xy 84.136467 -320.731758) (xy 84.107958 -320.67739) (xy 84.086195 -320.619988) (xy 84.071493 -320.560385)
			(xy 84.064068 -320.499446) (xy 84.063586 -320.468752) (xy 84.064078 -320.437157) (xy 84.071897 -320.374453)
			(xy 84.087432 -320.313202) (xy 84.110444 -320.254352) (xy 84.140578 -320.19881) (xy 84.158582 -320.172842)
			(xy 84.164278 -320.163981) (xy 84.16858 -320.143382) (xy 84.164263 -320.122786) (xy 84.158582 -320.113914)
			(xy 84.140777 -320.088004) (xy 84.110968 -320.032654) (xy 84.088202 -319.974053) (xy 84.072826 -319.913095)
			(xy 84.065074 -319.850708) (xy 84.064602 -319.819274) (xy 84.065081 -319.788578) (xy 84.072482 -319.727633)
			(xy 84.087173 -319.668025) (xy 84.108939 -319.61062) (xy 84.137465 -319.556258) (xy 84.154518 -319.53073)
			(xy 84.160011 -319.52199) (xy 84.164131 -319.501778) (xy 84.159994 -319.481571) (xy 84.154518 -319.472818)
			(xy 84.137495 -319.447272) (xy 84.108983 -319.392907) (xy 84.087217 -319.335507) (xy 84.072513 -319.275905)
			(xy 84.065085 -319.214968) (xy 84.064602 -319.184274) (xy 84.065081 -319.153578) (xy 84.072482 -319.092633)
			(xy 84.087173 -319.033025) (xy 84.108939 -318.97562) (xy 84.137465 -318.921258) (xy 84.154518 -318.89573)
			(xy 84.160011 -318.88699) (xy 84.164131 -318.866778) (xy 84.159994 -318.846571) (xy 84.154518 -318.837818)
			(xy 84.137495 -318.812272) (xy 84.108983 -318.757907) (xy 84.087217 -318.700507) (xy 84.072513 -318.640905)
			(xy 84.065085 -318.579968) (xy 84.064602 -318.549274) (xy 84.065081 -318.518578) (xy 84.072482 -318.457633)
			(xy 84.087173 -318.398025) (xy 84.108939 -318.34062) (xy 84.137465 -318.286258) (xy 84.154518 -318.26073)
			(xy 84.160011 -318.25199) (xy 84.164131 -318.231778) (xy 84.159994 -318.211571) (xy 84.154518 -318.202818)
			(xy 84.137495 -318.177272) (xy 84.108983 -318.122907) (xy 84.087217 -318.065507) (xy 84.072513 -318.005905)
			(xy 84.065085 -317.944968) (xy 84.064602 -317.914274) (xy 84.065081 -317.883578) (xy 84.072482 -317.822633)
			(xy 84.087173 -317.763025) (xy 84.108939 -317.70562) (xy 84.137465 -317.651258) (xy 84.154518 -317.62573)
			(xy 84.160011 -317.61699) (xy 84.164131 -317.596778) (xy 84.159994 -317.576571) (xy 84.154518 -317.567818)
			(xy 84.137495 -317.542272) (xy 84.108983 -317.487907) (xy 84.087217 -317.430507) (xy 84.072513 -317.370905)
			(xy 84.065085 -317.309968) (xy 84.064602 -317.279274) (xy 84.065081 -317.248578) (xy 84.072482 -317.187633)
			(xy 84.087173 -317.128025) (xy 84.108939 -317.07062) (xy 84.137465 -317.016258) (xy 84.154518 -316.99073)
			(xy 84.160011 -316.98199) (xy 84.164131 -316.961778) (xy 84.159994 -316.941571) (xy 84.154518 -316.932818)
			(xy 84.137495 -316.907272) (xy 84.108983 -316.852907) (xy 84.087217 -316.795507) (xy 84.072513 -316.735905)
			(xy 84.065085 -316.674968) (xy 84.064602 -316.644274) (xy 84.065032 -316.613542) (xy 84.072443 -316.552527)
			(xy 84.087155 -316.492849) (xy 84.108953 -316.435381) (xy 84.137519 -316.380958) (xy 84.172437 -316.330376)
			(xy 84.213196 -316.284371) (xy 84.259204 -316.243614) (xy 84.309789 -316.208701) (xy 84.364214 -316.180138)
			(xy 84.421684 -316.158345) (xy 84.481362 -316.143637) (xy 84.542378 -316.136229) (xy 84.57311 -316.135766)
			(xy 84.603806 -316.136259) (xy 84.66475 -316.143658) (xy 84.724358 -316.158346) (xy 84.781762 -316.180109)
			(xy 84.836126 -316.208631) (xy 84.861654 -316.225682) (xy 84.870406 -316.231153) (xy 84.89061 -316.235281)
			(xy 84.910814 -316.231153) (xy 84.919566 -316.225682) (xy 84.945093 -316.20863) (xy 84.999463 -316.180122)
			(xy 85.056868 -316.158361) (xy 85.116474 -316.143664) (xy 85.177415 -316.136244) (xy 85.20811 -316.135766)
			(xy 85.238806 -316.136259) (xy 85.29975 -316.143658) (xy 85.359358 -316.158346) (xy 85.416762 -316.180109)
			(xy 85.471126 -316.208631) (xy 85.496654 -316.225682) (xy 85.505406 -316.231153) (xy 85.52561 -316.235281)
			(xy 85.545814 -316.231153) (xy 85.554566 -316.225682) (xy 85.580093 -316.20863) (xy 85.634463 -316.180122)
			(xy 85.691868 -316.158361) (xy 85.751474 -316.143664) (xy 85.812415 -316.136244) (xy 85.84311 -316.135766)
			(xy 85.87384 -316.136247) (xy 85.934852 -316.143656) (xy 85.994527 -316.158365) (xy 86.051993 -316.180159)
			(xy 86.106414 -316.208721) (xy 86.156995 -316.243634) (xy 86.202999 -316.284389) (xy 86.243756 -316.330392)
			(xy 86.278671 -316.380973) (xy 86.307234 -316.435392) (xy 86.329031 -316.492858) (xy 86.343741 -316.552532)
			(xy 86.351152 -316.613544) (xy 86.351618 -316.644274) (xy 86.35116 -316.674971) (xy 86.343754 -316.735916)
			(xy 86.329058 -316.795525) (xy 86.307286 -316.852929) (xy 86.278757 -316.907291) (xy 86.261702 -316.932818)
			(xy 86.256252 -316.941582) (xy 86.252116 -316.961778) (xy 86.256235 -316.981978) (xy 86.261702 -316.99073)
			(xy 86.278748 -317.016261) (xy 86.307256 -317.070631) (xy 86.329016 -317.128035) (xy 86.343715 -317.187639)
			(xy 86.351138 -317.248579) (xy 86.351618 -317.279274) (xy 86.35116 -317.309971) (xy 86.343754 -317.370916)
			(xy 86.329058 -317.430525) (xy 86.307286 -317.487929) (xy 86.278757 -317.542291) (xy 86.261702 -317.567818)
			(xy 86.256252 -317.576582) (xy 86.252116 -317.596778) (xy 86.256235 -317.616978) (xy 86.261702 -317.62573)
			(xy 86.278748 -317.651261) (xy 86.307256 -317.705631) (xy 86.329016 -317.763035) (xy 86.343715 -317.822639)
			(xy 86.351138 -317.883579) (xy 86.351618 -317.914274) (xy 86.35116 -317.944971) (xy 86.343754 -318.005916)
			(xy 86.329058 -318.065525) (xy 86.307286 -318.122929) (xy 86.278757 -318.177291) (xy 86.261702 -318.202818)
			(xy 86.256252 -318.211582) (xy 86.252116 -318.231778) (xy 86.256235 -318.251978) (xy 86.261702 -318.26073)
			(xy 86.278748 -318.286261) (xy 86.307256 -318.340631) (xy 86.329016 -318.398035) (xy 86.343715 -318.457639)
			(xy 86.351138 -318.518579) (xy 86.351618 -318.549274) (xy 86.35116 -318.579971) (xy 86.343754 -318.640916)
			(xy 86.329058 -318.700525) (xy 86.307286 -318.757929) (xy 86.278757 -318.812291) (xy 86.261702 -318.837818)
			(xy 86.256252 -318.846582) (xy 86.252116 -318.866778) (xy 86.256235 -318.886978) (xy 86.261702 -318.89573)
			(xy 86.278748 -318.921261) (xy 86.307256 -318.975631) (xy 86.329016 -319.033035) (xy 86.343715 -319.092639)
			(xy 86.351138 -319.153579) (xy 86.351618 -319.184274) (xy 86.35116 -319.214971) (xy 86.343754 -319.275916)
			(xy 86.329058 -319.335525) (xy 86.307286 -319.392929) (xy 86.278757 -319.447291) (xy 86.261702 -319.472818)
			(xy 86.256252 -319.481582) (xy 86.252116 -319.501778) (xy 86.256235 -319.521978) (xy 86.261702 -319.53073)
			(xy 86.278748 -319.556261) (xy 86.307256 -319.610631) (xy 86.329016 -319.668035) (xy 86.343715 -319.727639)
			(xy 86.351138 -319.788579) (xy 86.351618 -319.819274) (xy 86.351189 -319.848227) (xy 86.344579 -319.905756)
			(xy 86.331487 -319.962165) (xy 86.312081 -320.016724) (xy 86.286613 -320.06873) (xy 86.271354 -320.09334)
			(xy 86.26616 -320.102336) (xy 86.26276 -320.122807) (xy 86.267751 -320.142949) (xy 86.27364 -320.151506)
			(xy 86.293158 -320.178137) (xy 86.325919 -320.235464) (xy 86.350986 -320.296547) (xy 86.367937 -320.360361)
			(xy 86.376489 -320.425833) (xy 86.377018 -320.458846) (xy 86.376546 -320.489542) (xy 86.369143 -320.550487)
			(xy 86.35445 -320.610096) (xy 86.332682 -320.6675) (xy 86.304156 -320.721862) (xy 86.287102 -320.74739)
			(xy 86.28159 -320.756121) (xy 86.277475 -320.776338) (xy 86.28162 -320.79655) (xy 86.287102 -320.805302)
			(xy 86.304136 -320.83084) (xy 86.332646 -320.885208) (xy 86.354409 -320.94261) (xy 86.36911 -321.002213)
			(xy 86.376536 -321.063152) (xy 86.377018 -321.093846) (xy 86.376546 -321.124542) (xy 86.369143 -321.185487)
			(xy 86.35445 -321.245096) (xy 86.332682 -321.3025) (xy 86.304156 -321.356862) (xy 86.287102 -321.38239)
			(xy 86.28159 -321.391121) (xy 86.277475 -321.411338) (xy 86.28162 -321.43155) (xy 86.287102 -321.440302)
			(xy 86.304136 -321.46584) (xy 86.332646 -321.520208) (xy 86.354409 -321.57761) (xy 86.36911 -321.637213)
			(xy 86.376536 -321.698152) (xy 86.377018 -321.728846) (xy 86.376546 -321.759542) (xy 86.369143 -321.820487)
			(xy 86.35445 -321.880096) (xy 86.332682 -321.9375) (xy 86.304156 -321.991862) (xy 86.287102 -322.01739)
			(xy 86.28159 -322.026121) (xy 86.277475 -322.046338) (xy 86.28162 -322.06655) (xy 86.287102 -322.075302)
			(xy 86.304136 -322.10084) (xy 86.332646 -322.155208) (xy 86.354409 -322.21261) (xy 86.36911 -322.272213)
			(xy 86.376536 -322.333152) (xy 86.377018 -322.363846) (xy 86.376485 -322.397219) (xy 86.367739 -322.46339)
			(xy 86.350406 -322.527846) (xy 86.324782 -322.589478) (xy 86.291309 -322.647225) (xy 86.271354 -322.67398)
			(xy 86.26536 -322.682586) (xy 86.260315 -322.702925) (xy 86.263787 -322.723591) (xy 86.269068 -322.732654)
			(xy 86.284604 -322.757378) (xy 86.310496 -322.809719) (xy 86.330218 -322.864682) (xy 86.34351 -322.921544)
			(xy 86.350197 -322.979555) (xy 86.350602 -323.008752) (xy 88.102186 -323.008752) (xy 88.102661 -322.977411)
			(xy 88.110367 -322.915203) (xy 88.125656 -322.854414) (xy 88.148297 -322.795963) (xy 88.177947 -322.740736)
			(xy 88.195658 -322.714874) (xy 88.201288 -322.706087) (xy 88.20552 -322.68567) (xy 88.201264 -322.665258)
			(xy 88.195658 -322.656454) (xy 88.178122 -322.630665) (xy 88.14877 -322.575639) (xy 88.12637 -322.517436)
			(xy 88.111257 -322.456929) (xy 88.10366 -322.395029) (xy 88.103202 -322.363846) (xy 88.103667 -322.333149)
			(xy 88.111071 -322.272204) (xy 88.125765 -322.212595) (xy 88.147535 -322.155192) (xy 88.176063 -322.100829)
			(xy 88.193118 -322.075302) (xy 88.19855 -322.066529) (xy 88.20269 -322.046338) (xy 88.19858 -322.026142)
			(xy 88.193118 -322.01739) (xy 88.176083 -321.991852) (xy 88.147573 -321.937484) (xy 88.12581 -321.880082)
			(xy 88.111109 -321.820479) (xy 88.103683 -321.75954) (xy 88.103202 -321.728846) (xy 88.103667 -321.698149)
			(xy 88.111071 -321.637204) (xy 88.125765 -321.577595) (xy 88.147535 -321.520192) (xy 88.176063 -321.465829)
			(xy 88.193118 -321.440302) (xy 88.19855 -321.431529) (xy 88.20269 -321.411338) (xy 88.19858 -321.391142)
			(xy 88.193118 -321.38239) (xy 88.176083 -321.356852) (xy 88.147573 -321.302484) (xy 88.12581 -321.245082)
			(xy 88.111109 -321.185479) (xy 88.103683 -321.12454) (xy 88.103202 -321.093846) (xy 88.103667 -321.063149)
			(xy 88.111071 -321.002204) (xy 88.125765 -320.942595) (xy 88.147535 -320.885192) (xy 88.176063 -320.830829)
			(xy 88.193118 -320.805302) (xy 88.19855 -320.796529) (xy 88.20269 -320.776338) (xy 88.19858 -320.756142)
			(xy 88.193118 -320.74739) (xy 88.176083 -320.721852) (xy 88.147573 -320.667484) (xy 88.12581 -320.610082)
			(xy 88.111109 -320.550479) (xy 88.103683 -320.48954) (xy 88.103202 -320.458846) (xy 88.103649 -320.427872)
			(xy 88.111184 -320.366384) (xy 88.126135 -320.306268) (xy 88.148282 -320.248414) (xy 88.177295 -320.193681)
			(xy 88.194642 -320.168016) (xy 88.200145 -320.159281) (xy 88.204259 -320.139067) (xy 88.200119 -320.118857)
			(xy 88.194642 -320.110104) (xy 88.177287 -320.084445) (xy 88.148276 -320.02971) (xy 88.126134 -319.971855)
			(xy 88.111188 -319.911737) (xy 88.103661 -319.850248) (xy 88.103202 -319.819274) (xy 88.103681 -319.788578)
			(xy 88.111082 -319.727633) (xy 88.125773 -319.668025) (xy 88.147539 -319.61062) (xy 88.176065 -319.556258)
			(xy 88.193118 -319.53073) (xy 88.198611 -319.52199) (xy 88.202731 -319.501778) (xy 88.198594 -319.481571)
			(xy 88.193118 -319.472818) (xy 88.176095 -319.447272) (xy 88.147583 -319.392907) (xy 88.125817 -319.335507)
			(xy 88.111113 -319.275905) (xy 88.103685 -319.214968) (xy 88.103202 -319.184274) (xy 88.103681 -319.153578)
			(xy 88.111082 -319.092633) (xy 88.125773 -319.033025) (xy 88.147539 -318.97562) (xy 88.176065 -318.921258)
			(xy 88.193118 -318.89573) (xy 88.198611 -318.88699) (xy 88.202731 -318.866778) (xy 88.198594 -318.846571)
			(xy 88.193118 -318.837818) (xy 88.176095 -318.812272) (xy 88.147583 -318.757907) (xy 88.125817 -318.700507)
			(xy 88.111113 -318.640905) (xy 88.103685 -318.579968) (xy 88.103202 -318.549274) (xy 88.103681 -318.518578)
			(xy 88.111082 -318.457633) (xy 88.125773 -318.398025) (xy 88.147539 -318.34062) (xy 88.176065 -318.286258)
			(xy 88.193118 -318.26073) (xy 88.198611 -318.25199) (xy 88.202731 -318.231778) (xy 88.198594 -318.211571)
			(xy 88.193118 -318.202818) (xy 88.176095 -318.177272) (xy 88.147583 -318.122907) (xy 88.125817 -318.065507)
			(xy 88.111113 -318.005905) (xy 88.103685 -317.944968) (xy 88.103202 -317.914274) (xy 88.103681 -317.883578)
			(xy 88.111082 -317.822633) (xy 88.125773 -317.763025) (xy 88.147539 -317.70562) (xy 88.176065 -317.651258)
			(xy 88.193118 -317.62573) (xy 88.198611 -317.61699) (xy 88.202731 -317.596778) (xy 88.198594 -317.576571)
			(xy 88.193118 -317.567818) (xy 88.176095 -317.542272) (xy 88.147583 -317.487907) (xy 88.125817 -317.430507)
			(xy 88.111113 -317.370905) (xy 88.103685 -317.309968) (xy 88.103202 -317.279274) (xy 88.103681 -317.248578)
			(xy 88.111082 -317.187633) (xy 88.125773 -317.128025) (xy 88.147539 -317.07062) (xy 88.176065 -317.016258)
			(xy 88.193118 -316.99073) (xy 88.198611 -316.98199) (xy 88.202731 -316.961778) (xy 88.198594 -316.941571)
			(xy 88.193118 -316.932818) (xy 88.176095 -316.907272) (xy 88.147583 -316.852907) (xy 88.125817 -316.795507)
			(xy 88.111113 -316.735905) (xy 88.103685 -316.674968) (xy 88.103202 -316.644274) (xy 88.103632 -316.613542)
			(xy 88.111043 -316.552527) (xy 88.125755 -316.492849) (xy 88.147553 -316.435381) (xy 88.176119 -316.380958)
			(xy 88.211037 -316.330376) (xy 88.251796 -316.284371) (xy 88.297804 -316.243614) (xy 88.348389 -316.208701)
			(xy 88.402814 -316.180138) (xy 88.460284 -316.158345) (xy 88.519962 -316.143637) (xy 88.580978 -316.136229)
			(xy 88.61171 -316.135766) (xy 88.642406 -316.136259) (xy 88.70335 -316.143658) (xy 88.762958 -316.158346)
			(xy 88.820362 -316.180109) (xy 88.874726 -316.208631) (xy 88.900254 -316.225682) (xy 88.909006 -316.231153)
			(xy 88.92921 -316.235281) (xy 88.949414 -316.231153) (xy 88.958166 -316.225682) (xy 88.983693 -316.20863)
			(xy 89.038063 -316.180122) (xy 89.095468 -316.158361) (xy 89.155074 -316.143664) (xy 89.216015 -316.136244)
			(xy 89.24671 -316.135766) (xy 89.277406 -316.136259) (xy 89.33835 -316.143658) (xy 89.397958 -316.158346)
			(xy 89.455362 -316.180109) (xy 89.509726 -316.208631) (xy 89.535254 -316.225682) (xy 89.544006 -316.231153)
			(xy 89.56421 -316.235281) (xy 89.584414 -316.231153) (xy 89.593166 -316.225682) (xy 89.618693 -316.20863)
			(xy 89.673063 -316.180122) (xy 89.730468 -316.158361) (xy 89.790074 -316.143664) (xy 89.851015 -316.136244)
			(xy 89.88171 -316.135766) (xy 89.91244 -316.136247) (xy 89.973452 -316.143656) (xy 90.033127 -316.158365)
			(xy 90.090593 -316.180159) (xy 90.145014 -316.208721) (xy 90.195595 -316.243634) (xy 90.241599 -316.284389)
			(xy 90.282356 -316.330392) (xy 90.317271 -316.380973) (xy 90.345834 -316.435392) (xy 90.367631 -316.492858)
			(xy 90.382341 -316.552532) (xy 90.389752 -316.613544) (xy 90.390218 -316.644274) (xy 90.38976 -316.674971)
			(xy 90.382354 -316.735916) (xy 90.367658 -316.795525) (xy 90.345886 -316.852929) (xy 90.317357 -316.907291)
			(xy 90.300302 -316.932818) (xy 90.294852 -316.941582) (xy 90.290716 -316.961778) (xy 90.294835 -316.981978)
			(xy 90.300302 -316.99073) (xy 90.317348 -317.016261) (xy 90.345856 -317.070631) (xy 90.367616 -317.128035)
			(xy 90.382315 -317.187639) (xy 90.389738 -317.248579) (xy 90.390218 -317.279274) (xy 90.38976 -317.309971)
			(xy 90.382354 -317.370916) (xy 90.367658 -317.430525) (xy 90.345886 -317.487929) (xy 90.317357 -317.542291)
			(xy 90.300302 -317.567818) (xy 90.294852 -317.576582) (xy 90.290716 -317.596778) (xy 90.294835 -317.616978)
			(xy 90.300302 -317.62573) (xy 90.317348 -317.651261) (xy 90.345856 -317.705631) (xy 90.367616 -317.763035)
			(xy 90.382315 -317.822639) (xy 90.389738 -317.883579) (xy 90.390218 -317.914274) (xy 90.38976 -317.944971)
			(xy 90.382354 -318.005916) (xy 90.367658 -318.065525) (xy 90.345886 -318.122929) (xy 90.317357 -318.177291)
			(xy 90.300302 -318.202818) (xy 90.294852 -318.211582) (xy 90.290716 -318.231778) (xy 90.294835 -318.251978)
			(xy 90.300302 -318.26073) (xy 90.317348 -318.286261) (xy 90.345856 -318.340631) (xy 90.367616 -318.398035)
			(xy 90.382315 -318.457639) (xy 90.389738 -318.518579) (xy 90.390218 -318.549274) (xy 90.38976 -318.579971)
			(xy 90.382354 -318.640916) (xy 90.367658 -318.700525) (xy 90.345886 -318.757929) (xy 90.317357 -318.812291)
			(xy 90.300302 -318.837818) (xy 90.294852 -318.846582) (xy 90.290716 -318.866778) (xy 90.294835 -318.886978)
			(xy 90.300302 -318.89573) (xy 90.317348 -318.921261) (xy 90.345856 -318.975631) (xy 90.367616 -319.033035)
			(xy 90.382315 -319.092639) (xy 90.389738 -319.153579) (xy 90.390218 -319.184274) (xy 90.38976 -319.214971)
			(xy 90.382354 -319.275916) (xy 90.367658 -319.335525) (xy 90.345886 -319.392929) (xy 90.317357 -319.447291)
			(xy 90.300302 -319.472818) (xy 90.294852 -319.481582) (xy 90.290716 -319.501778) (xy 90.294835 -319.521978)
			(xy 90.300302 -319.53073) (xy 90.317348 -319.556261) (xy 90.345856 -319.610631) (xy 90.367616 -319.668035)
			(xy 90.382315 -319.727639) (xy 90.389738 -319.788579) (xy 90.390218 -319.819274) (xy 90.390002 -319.833752)
			(xy 92.318586 -319.833752) (xy 92.319056 -319.803056) (xy 92.32646 -319.742111) (xy 92.341153 -319.682502)
			(xy 92.362921 -319.625098) (xy 92.391448 -319.570735) (xy 92.408502 -319.545208) (xy 92.414015 -319.536478)
			(xy 92.41813 -319.51626) (xy 92.413984 -319.496048) (xy 92.408502 -319.487296) (xy 92.391467 -319.461758)
			(xy 92.362958 -319.40739) (xy 92.341195 -319.349988) (xy 92.326493 -319.290385) (xy 92.319068 -319.229446)
			(xy 92.318586 -319.198752) (xy 92.319056 -319.168056) (xy 92.32646 -319.107111) (xy 92.341153 -319.047502)
			(xy 92.362921 -318.990098) (xy 92.391448 -318.935735) (xy 92.408502 -318.910208) (xy 92.414015 -318.901478)
			(xy 92.41813 -318.88126) (xy 92.413984 -318.861048) (xy 92.408502 -318.852296) (xy 92.391467 -318.826758)
			(xy 92.362958 -318.77239) (xy 92.341195 -318.714988) (xy 92.326493 -318.655385) (xy 92.319068 -318.594446)
			(xy 92.318586 -318.563752) (xy 92.319056 -318.533056) (xy 92.32646 -318.472111) (xy 92.341153 -318.412502)
			(xy 92.362921 -318.355098) (xy 92.391448 -318.300735) (xy 92.408502 -318.275208) (xy 92.414015 -318.266478)
			(xy 92.41813 -318.24626) (xy 92.413984 -318.226048) (xy 92.408502 -318.217296) (xy 92.391467 -318.191758)
			(xy 92.362958 -318.13739) (xy 92.341195 -318.079988) (xy 92.326493 -318.020385) (xy 92.319068 -317.959446)
			(xy 92.318586 -317.928752) (xy 92.319056 -317.898056) (xy 92.32646 -317.837111) (xy 92.341153 -317.777502)
			(xy 92.362921 -317.720098) (xy 92.391448 -317.665735) (xy 92.408502 -317.640208) (xy 92.414015 -317.631478)
			(xy 92.41813 -317.61126) (xy 92.413984 -317.591048) (xy 92.408502 -317.582296) (xy 92.391467 -317.556758)
			(xy 92.362958 -317.50239) (xy 92.341195 -317.444988) (xy 92.326493 -317.385385) (xy 92.319068 -317.324446)
			(xy 92.318586 -317.293752) (xy 92.319056 -317.263056) (xy 92.32646 -317.202111) (xy 92.341153 -317.142502)
			(xy 92.362921 -317.085098) (xy 92.391448 -317.030735) (xy 92.408502 -317.005208) (xy 92.414015 -316.996478)
			(xy 92.41813 -316.97626) (xy 92.413984 -316.956048) (xy 92.408502 -316.947296) (xy 92.391467 -316.921758)
			(xy 92.362958 -316.86739) (xy 92.341195 -316.809988) (xy 92.326493 -316.750385) (xy 92.319068 -316.689446)
			(xy 92.318586 -316.658752) (xy 92.31901 -316.62802) (xy 92.326424 -316.567005) (xy 92.341138 -316.507329)
			(xy 92.362938 -316.449861) (xy 92.391505 -316.395439) (xy 92.426423 -316.344857) (xy 92.467183 -316.298853)
			(xy 92.51319 -316.258097) (xy 92.563775 -316.223183) (xy 92.618199 -316.19462) (xy 92.675669 -316.172826)
			(xy 92.735347 -316.158117) (xy 92.796362 -316.150708) (xy 92.827094 -316.150244) (xy 92.857792 -316.150681)
			(xy 92.918738 -316.158091) (xy 92.978347 -316.172791) (xy 93.035751 -316.194567) (xy 93.090112 -316.223102)
			(xy 93.115638 -316.24016) (xy 93.12439 -316.245631) (xy 93.144594 -316.249759) (xy 93.164798 -316.245631)
			(xy 93.17355 -316.24016) (xy 93.19908 -316.223112) (xy 93.25345 -316.194604) (xy 93.310854 -316.172843)
			(xy 93.370459 -316.158144) (xy 93.431399 -316.150723) (xy 93.462094 -316.150244) (xy 93.492792 -316.150681)
			(xy 93.553738 -316.158091) (xy 93.613347 -316.172791) (xy 93.670751 -316.194567) (xy 93.725112 -316.223102)
			(xy 93.750638 -316.24016) (xy 93.75939 -316.245631) (xy 93.779594 -316.249759) (xy 93.799798 -316.245631)
			(xy 93.80855 -316.24016) (xy 93.83408 -316.223112) (xy 93.88845 -316.194604) (xy 93.945854 -316.172843)
			(xy 94.005459 -316.158144) (xy 94.066399 -316.150723) (xy 94.097094 -316.150244) (xy 94.127823 -316.150762)
			(xy 94.188833 -316.158168) (xy 94.248506 -316.172875) (xy 94.305971 -316.194666) (xy 94.36039 -316.223225)
			(xy 94.410971 -316.258135) (xy 94.456975 -316.298887) (xy 94.497731 -316.344887) (xy 94.532647 -316.395464)
			(xy 94.561211 -316.44988) (xy 94.583009 -316.507343) (xy 94.597722 -316.567014) (xy 94.605135 -316.628023)
			(xy 94.605602 -316.658752) (xy 94.605136 -316.689449) (xy 94.597732 -316.750394) (xy 94.583038 -316.810002)
			(xy 94.561268 -316.867406) (xy 94.53274 -316.921769) (xy 94.515686 -316.947296) (xy 94.510256 -316.95607)
			(xy 94.506115 -316.97626) (xy 94.510225 -316.996456) (xy 94.515686 -317.005208) (xy 94.532721 -317.030746)
			(xy 94.561231 -317.085114) (xy 94.582994 -317.142516) (xy 94.597695 -317.202119) (xy 94.605121 -317.263058)
			(xy 94.605602 -317.293752) (xy 94.605136 -317.324449) (xy 94.597732 -317.385394) (xy 94.583038 -317.445002)
			(xy 94.561268 -317.502406) (xy 94.53274 -317.556769) (xy 94.515686 -317.582296) (xy 94.510256 -317.59107)
			(xy 94.506115 -317.61126) (xy 94.510225 -317.631456) (xy 94.515686 -317.640208) (xy 94.532721 -317.665746)
			(xy 94.561231 -317.720114) (xy 94.582994 -317.777516) (xy 94.597695 -317.837119) (xy 94.605121 -317.898058)
			(xy 94.605602 -317.928752) (xy 94.605136 -317.959449) (xy 94.597732 -318.020394) (xy 94.583038 -318.080002)
			(xy 94.561268 -318.137406) (xy 94.53274 -318.191769) (xy 94.515686 -318.217296) (xy 94.510256 -318.22607)
			(xy 94.506115 -318.24626) (xy 94.510225 -318.266456) (xy 94.515686 -318.275208) (xy 94.532721 -318.300746)
			(xy 94.561231 -318.355114) (xy 94.582994 -318.412516) (xy 94.597695 -318.472119) (xy 94.605121 -318.533058)
			(xy 94.605602 -318.563752) (xy 94.605136 -318.594449) (xy 94.597732 -318.655394) (xy 94.583038 -318.715002)
			(xy 94.561268 -318.772406) (xy 94.53274 -318.826769) (xy 94.515686 -318.852296) (xy 94.510256 -318.86107)
			(xy 94.506115 -318.88126) (xy 94.510225 -318.901456) (xy 94.515686 -318.910208) (xy 94.532721 -318.935746)
			(xy 94.561231 -318.990114) (xy 94.582994 -319.047516) (xy 94.597695 -319.107119) (xy 94.605121 -319.168058)
			(xy 94.605602 -319.198752) (xy 94.605136 -319.229449) (xy 94.597732 -319.290394) (xy 94.583038 -319.350002)
			(xy 94.561268 -319.407406) (xy 94.53274 -319.461769) (xy 94.515686 -319.487296) (xy 94.510256 -319.49607)
			(xy 94.506115 -319.51626) (xy 94.510225 -319.536456) (xy 94.515686 -319.545208) (xy 94.532721 -319.570746)
			(xy 94.561231 -319.625114) (xy 94.582994 -319.682516) (xy 94.597695 -319.742119) (xy 94.605121 -319.803058)
			(xy 94.605602 -319.833752) (xy 94.60515 -319.862705) (xy 94.598543 -319.920232) (xy 94.585456 -319.97664)
			(xy 94.566055 -320.031199) (xy 94.540593 -320.083207) (xy 94.525338 -320.107818) (xy 94.520153 -320.11682)
			(xy 94.51674 -320.137288) (xy 94.521732 -320.15743) (xy 94.527624 -320.165984) (xy 94.547175 -320.192592)
			(xy 94.579931 -320.249925) (xy 94.604992 -320.311014) (xy 94.621935 -320.374834) (xy 94.630478 -320.440309)
			(xy 94.631002 -320.473324) (xy 94.630521 -320.50402) (xy 94.623121 -320.564965) (xy 94.60843 -320.624573)
			(xy 94.586664 -320.681977) (xy 94.558139 -320.73634) (xy 94.541086 -320.761868) (xy 94.535595 -320.770609)
			(xy 94.531474 -320.79082) (xy 94.53561 -320.811028) (xy 94.541086 -320.81978) (xy 94.558152 -320.845298)
			(xy 94.586656 -320.899671) (xy 94.608413 -320.957079) (xy 94.623107 -321.016686) (xy 94.630525 -321.077628)
			(xy 94.631002 -321.108324) (xy 94.630521 -321.13902) (xy 94.623121 -321.199965) (xy 94.60843 -321.259573)
			(xy 94.586664 -321.316977) (xy 94.558139 -321.37134) (xy 94.541086 -321.396868) (xy 94.535595 -321.405609)
			(xy 94.531474 -321.42582) (xy 94.53561 -321.446028) (xy 94.541086 -321.45478) (xy 94.558152 -321.480298)
			(xy 94.586656 -321.534671) (xy 94.608413 -321.592079) (xy 94.623107 -321.651686) (xy 94.630525 -321.712628)
			(xy 94.631002 -321.743324) (xy 94.630521 -321.77402) (xy 94.623121 -321.834965) (xy 94.60843 -321.894573)
			(xy 94.586664 -321.951977) (xy 94.558139 -322.00634) (xy 94.541086 -322.031868) (xy 94.535595 -322.040609)
			(xy 94.531474 -322.06082) (xy 94.53561 -322.081028) (xy 94.541086 -322.08978) (xy 94.558152 -322.115298)
			(xy 94.586656 -322.169671) (xy 94.608413 -322.227079) (xy 94.623107 -322.286686) (xy 94.630525 -322.347628)
			(xy 94.631002 -322.378324) (xy 94.630514 -322.410197) (xy 94.622582 -322.473448) (xy 94.606796 -322.535209)
			(xy 94.583403 -322.594508) (xy 94.552772 -322.650412) (xy 94.534482 -322.67652) (xy 94.528667 -322.685432)
			(xy 94.524278 -322.706231) (xy 94.528693 -322.727025) (xy 94.534482 -322.735956) (xy 94.552743 -322.76208)
			(xy 94.583343 -322.817995) (xy 94.606726 -322.877292) (xy 94.622527 -322.939042) (xy 94.630499 -323.002282)
			(xy 94.631002 -323.034152) (xy 96.357186 -323.034152) (xy 96.357664 -323.002278) (xy 96.365598 -322.939027)
			(xy 96.381387 -322.877267) (xy 96.404782 -322.817968) (xy 96.435415 -322.762064) (xy 96.453706 -322.735956)
			(xy 96.459455 -322.727008) (xy 96.463868 -322.706231) (xy 96.459481 -322.685449) (xy 96.453706 -322.67652)
			(xy 96.435445 -322.650395) (xy 96.404843 -322.594481) (xy 96.381459 -322.535185) (xy 96.365658 -322.473434)
			(xy 96.357688 -322.410194) (xy 96.357186 -322.378324) (xy 96.357642 -322.347627) (xy 96.365049 -322.286682)
			(xy 96.379745 -322.227073) (xy 96.401517 -322.169669) (xy 96.430047 -322.115307) (xy 96.447102 -322.08978)
			(xy 96.452554 -322.081017) (xy 96.456689 -322.06082) (xy 96.452569 -322.04062) (xy 96.447102 -322.031868)
			(xy 96.430055 -322.006338) (xy 96.401548 -321.951968) (xy 96.379787 -321.894563) (xy 96.365089 -321.834959)
			(xy 96.357666 -321.774019) (xy 96.357186 -321.743324) (xy 96.357642 -321.712627) (xy 96.365049 -321.651682)
			(xy 96.379745 -321.592073) (xy 96.401517 -321.534669) (xy 96.430047 -321.480307) (xy 96.447102 -321.45478)
			(xy 96.452554 -321.446017) (xy 96.456689 -321.42582) (xy 96.452569 -321.40562) (xy 96.447102 -321.396868)
			(xy 96.430055 -321.371338) (xy 96.401548 -321.316968) (xy 96.379787 -321.259563) (xy 96.365089 -321.199959)
			(xy 96.357666 -321.139019) (xy 96.357186 -321.108324) (xy 96.357642 -321.077627) (xy 96.365049 -321.016682)
			(xy 96.379745 -320.957073) (xy 96.401517 -320.899669) (xy 96.430047 -320.845307) (xy 96.447102 -320.81978)
			(xy 96.452554 -320.811017) (xy 96.456689 -320.79082) (xy 96.452569 -320.77062) (xy 96.447102 -320.761868)
			(xy 96.430055 -320.736338) (xy 96.401548 -320.681968) (xy 96.379787 -320.624563) (xy 96.365089 -320.564959)
			(xy 96.357666 -320.504019) (xy 96.357186 -320.473324) (xy 96.357625 -320.44235) (xy 96.365162 -320.380862)
			(xy 96.380115 -320.320746) (xy 96.402264 -320.262892) (xy 96.431278 -320.208159) (xy 96.448626 -320.182494)
			(xy 96.454064 -320.173724) (xy 96.458201 -320.153532) (xy 96.454088 -320.133334) (xy 96.448626 -320.124582)
			(xy 96.431259 -320.098931) (xy 96.402251 -320.044193) (xy 96.380111 -319.986336) (xy 96.365168 -319.926217)
			(xy 96.357644 -319.864726) (xy 96.357186 -319.833752) (xy 96.357656 -319.803056) (xy 96.36506 -319.742111)
			(xy 96.379753 -319.682502) (xy 96.401521 -319.625098) (xy 96.430048 -319.570735) (xy 96.447102 -319.545208)
			(xy 96.452615 -319.536478) (xy 96.45673 -319.51626) (xy 96.452584 -319.496048) (xy 96.447102 -319.487296)
			(xy 96.430067 -319.461758) (xy 96.401558 -319.40739) (xy 96.379795 -319.349988) (xy 96.365093 -319.290385)
			(xy 96.357668 -319.229446) (xy 96.357186 -319.198752) (xy 96.357656 -319.168056) (xy 96.36506 -319.107111)
			(xy 96.379753 -319.047502) (xy 96.401521 -318.990098) (xy 96.430048 -318.935735) (xy 96.447102 -318.910208)
			(xy 96.452615 -318.901478) (xy 96.45673 -318.88126) (xy 96.452584 -318.861048) (xy 96.447102 -318.852296)
			(xy 96.430067 -318.826758) (xy 96.401558 -318.77239) (xy 96.379795 -318.714988) (xy 96.365093 -318.655385)
			(xy 96.357668 -318.594446) (xy 96.357186 -318.563752) (xy 96.357656 -318.533056) (xy 96.36506 -318.472111)
			(xy 96.379753 -318.412502) (xy 96.401521 -318.355098) (xy 96.430048 -318.300735) (xy 96.447102 -318.275208)
			(xy 96.452615 -318.266478) (xy 96.45673 -318.24626) (xy 96.452584 -318.226048) (xy 96.447102 -318.217296)
			(xy 96.430067 -318.191758) (xy 96.401558 -318.13739) (xy 96.379795 -318.079988) (xy 96.365093 -318.020385)
			(xy 96.357668 -317.959446) (xy 96.357186 -317.928752) (xy 96.357656 -317.898056) (xy 96.36506 -317.837111)
			(xy 96.379753 -317.777502) (xy 96.401521 -317.720098) (xy 96.430048 -317.665735) (xy 96.447102 -317.640208)
			(xy 96.452615 -317.631478) (xy 96.45673 -317.61126) (xy 96.452584 -317.591048) (xy 96.447102 -317.582296)
			(xy 96.430067 -317.556758) (xy 96.401558 -317.50239) (xy 96.379795 -317.444988) (xy 96.365093 -317.385385)
			(xy 96.357668 -317.324446) (xy 96.357186 -317.293752) (xy 96.357656 -317.263056) (xy 96.36506 -317.202111)
			(xy 96.379753 -317.142502) (xy 96.401521 -317.085098) (xy 96.430048 -317.030735) (xy 96.447102 -317.005208)
			(xy 96.452615 -316.996478) (xy 96.45673 -316.97626) (xy 96.452584 -316.956048) (xy 96.447102 -316.947296)
			(xy 96.430067 -316.921758) (xy 96.401558 -316.86739) (xy 96.379795 -316.809988) (xy 96.365093 -316.750385)
			(xy 96.357668 -316.689446) (xy 96.357186 -316.658752) (xy 96.35761 -316.62802) (xy 96.365024 -316.567005)
			(xy 96.379738 -316.507329) (xy 96.401538 -316.449861) (xy 96.430105 -316.395439) (xy 96.465023 -316.344857)
			(xy 96.505783 -316.298853) (xy 96.55179 -316.258097) (xy 96.602375 -316.223183) (xy 96.656799 -316.19462)
			(xy 96.714269 -316.172826) (xy 96.773947 -316.158117) (xy 96.834962 -316.150708) (xy 96.865694 -316.150244)
			(xy 96.896392 -316.150681) (xy 96.957338 -316.158091) (xy 97.016947 -316.172791) (xy 97.074351 -316.194567)
			(xy 97.128712 -316.223102) (xy 97.154238 -316.24016) (xy 97.16299 -316.245631) (xy 97.183194 -316.249759)
			(xy 97.203398 -316.245631) (xy 97.21215 -316.24016) (xy 97.23768 -316.223112) (xy 97.29205 -316.194604)
			(xy 97.349454 -316.172843) (xy 97.409059 -316.158144) (xy 97.469999 -316.150723) (xy 97.500694 -316.150244)
			(xy 97.531392 -316.150681) (xy 97.592338 -316.158091) (xy 97.651947 -316.172791) (xy 97.709351 -316.194567)
			(xy 97.763712 -316.223102) (xy 97.789238 -316.24016) (xy 97.79799 -316.245631) (xy 97.818194 -316.249759)
			(xy 97.838398 -316.245631) (xy 97.84715 -316.24016) (xy 97.87268 -316.223112) (xy 97.92705 -316.194604)
			(xy 97.984454 -316.172843) (xy 98.044059 -316.158144) (xy 98.104999 -316.150723) (xy 98.135694 -316.150244)
			(xy 98.166423 -316.150762) (xy 98.227433 -316.158168) (xy 98.287106 -316.172875) (xy 98.344571 -316.194666)
			(xy 98.39899 -316.223225) (xy 98.449571 -316.258135) (xy 98.495575 -316.298887) (xy 98.536331 -316.344887)
			(xy 98.571247 -316.395464) (xy 98.599811 -316.44988) (xy 98.621609 -316.507343) (xy 98.636322 -316.567014)
			(xy 98.643735 -316.628023) (xy 98.644202 -316.658752) (xy 98.643736 -316.689449) (xy 98.636332 -316.750394)
			(xy 98.621638 -316.810002) (xy 98.599868 -316.867406) (xy 98.57134 -316.921769) (xy 98.554286 -316.947296)
			(xy 98.548856 -316.95607) (xy 98.544715 -316.97626) (xy 98.548825 -316.996456) (xy 98.554286 -317.005208)
			(xy 98.571321 -317.030746) (xy 98.599831 -317.085114) (xy 98.621594 -317.142516) (xy 98.636295 -317.202119)
			(xy 98.643721 -317.263058) (xy 98.644202 -317.293752) (xy 98.643736 -317.324449) (xy 98.636332 -317.385394)
			(xy 98.621638 -317.445002) (xy 98.599868 -317.502406) (xy 98.57134 -317.556769) (xy 98.554286 -317.582296)
			(xy 98.548856 -317.59107) (xy 98.544715 -317.61126) (xy 98.548825 -317.631456) (xy 98.554286 -317.640208)
			(xy 98.571321 -317.665746) (xy 98.599831 -317.720114) (xy 98.621594 -317.777516) (xy 98.636295 -317.837119)
			(xy 98.643721 -317.898058) (xy 98.644202 -317.928752) (xy 98.643736 -317.959449) (xy 98.636332 -318.020394)
			(xy 98.621638 -318.080002) (xy 98.599868 -318.137406) (xy 98.57134 -318.191769) (xy 98.554286 -318.217296)
			(xy 98.548856 -318.22607) (xy 98.544715 -318.24626) (xy 98.548825 -318.266456) (xy 98.554286 -318.275208)
			(xy 98.571321 -318.300746) (xy 98.599831 -318.355114) (xy 98.621594 -318.412516) (xy 98.636295 -318.472119)
			(xy 98.643721 -318.533058) (xy 98.644202 -318.563752) (xy 98.643736 -318.594449) (xy 98.636332 -318.655394)
			(xy 98.621638 -318.715002) (xy 98.599868 -318.772406) (xy 98.57134 -318.826769) (xy 98.554286 -318.852296)
			(xy 98.548856 -318.86107) (xy 98.544715 -318.88126) (xy 98.548825 -318.901456) (xy 98.554286 -318.910208)
			(xy 98.571321 -318.935746) (xy 98.599831 -318.990114) (xy 98.621594 -319.047516) (xy 98.636295 -319.107119)
			(xy 98.643721 -319.168058) (xy 98.644202 -319.198752) (xy 98.643736 -319.229449) (xy 98.636332 -319.290394)
			(xy 98.621638 -319.350002) (xy 98.599868 -319.407406) (xy 98.57134 -319.461769) (xy 98.554286 -319.487296)
			(xy 98.548856 -319.49607) (xy 98.544715 -319.51626) (xy 98.548825 -319.536456) (xy 98.554286 -319.545208)
			(xy 98.571321 -319.570746) (xy 98.599831 -319.625114) (xy 98.621594 -319.682516) (xy 98.636295 -319.742119)
			(xy 98.643721 -319.803058) (xy 98.644202 -319.833752) (xy 98.6437 -319.865877) (xy 98.635606 -319.929614)
			(xy 98.619554 -319.991826) (xy 98.595799 -320.051523) (xy 98.564718 -320.107755) (xy 98.546158 -320.13398)
			(xy 98.540243 -320.14296) (xy 98.535736 -320.163961) (xy 98.540211 -320.184968) (xy 98.546158 -320.193924)
			(xy 98.564733 -320.22014) (xy 98.59582 -320.276371) (xy 98.619578 -320.336069) (xy 98.635628 -320.398285)
			(xy 98.643714 -320.462026) (xy 98.644202 -320.494152) (xy 98.643736 -320.524849) (xy 98.636332 -320.585794)
			(xy 98.621638 -320.645402) (xy 98.599868 -320.702806) (xy 98.57134 -320.757169) (xy 98.554286 -320.782696)
			(xy 98.548856 -320.79147) (xy 98.544715 -320.81166) (xy 98.548825 -320.831856) (xy 98.554286 -320.840608)
			(xy 98.571321 -320.866146) (xy 98.599831 -320.920514) (xy 98.621594 -320.977916) (xy 98.636295 -321.037519)
			(xy 98.643721 -321.098458) (xy 98.644202 -321.129152) (xy 98.643736 -321.159849) (xy 98.636332 -321.220794)
			(xy 98.621638 -321.280402) (xy 98.599868 -321.337806) (xy 98.57134 -321.392169) (xy 98.554286 -321.417696)
			(xy 98.548856 -321.42647) (xy 98.544715 -321.44666) (xy 98.548825 -321.466856) (xy 98.554286 -321.475608)
			(xy 98.571321 -321.501146) (xy 98.599831 -321.555514) (xy 98.621594 -321.612916) (xy 98.636295 -321.672519)
			(xy 98.643721 -321.733458) (xy 98.644202 -321.764152) (xy 98.643736 -321.794849) (xy 98.636332 -321.855794)
			(xy 98.621638 -321.915402) (xy 98.599868 -321.972806) (xy 98.57134 -322.027169) (xy 98.554286 -322.052696)
			(xy 98.548856 -322.06147) (xy 98.544715 -322.08166) (xy 98.548825 -322.101856) (xy 98.554286 -322.110608)
			(xy 98.571321 -322.136146) (xy 98.599831 -322.190514) (xy 98.621594 -322.247916) (xy 98.636295 -322.307519)
			(xy 98.643721 -322.368458) (xy 98.644202 -322.399152) (xy 98.643736 -322.429849) (xy 98.636332 -322.490794)
			(xy 98.621638 -322.550402) (xy 98.599868 -322.607806) (xy 98.57134 -322.662169) (xy 98.554286 -322.687696)
			(xy 98.548856 -322.69647) (xy 98.544715 -322.71666) (xy 98.548825 -322.736856) (xy 98.554286 -322.745608)
			(xy 98.571321 -322.771146) (xy 98.599831 -322.825514) (xy 98.621594 -322.882916) (xy 98.636295 -322.942519)
			(xy 98.643721 -323.003458) (xy 98.644202 -323.034152) (xy 98.643717 -323.064883) (xy 98.636314 -323.125898)
			(xy 98.62161 -323.185576) (xy 98.599819 -323.243046) (xy 98.571259 -323.29747) (xy 98.536347 -323.348055)
			(xy 98.495592 -323.394062) (xy 98.449588 -323.434821) (xy 98.399006 -323.469737) (xy 98.344585 -323.498302)
			(xy 98.287116 -323.520097) (xy 98.22744 -323.534806) (xy 98.166425 -323.542215) (xy 98.135694 -323.54266)
			(xy 98.104998 -323.542178) (xy 98.044053 -323.534779) (xy 97.984444 -323.520089) (xy 97.92704 -323.498323)
			(xy 97.872677 -323.469797) (xy 97.84715 -323.452744) (xy 97.838398 -323.447273) (xy 97.818194 -323.443145)
			(xy 97.79799 -323.447273) (xy 97.789238 -323.452744) (xy 97.763712 -323.469797) (xy 97.709341 -323.498305)
			(xy 97.651936 -323.520065) (xy 97.59233 -323.534762) (xy 97.531389 -323.542182) (xy 97.500694 -323.54266)
			(xy 97.469998 -323.542178) (xy 97.409053 -323.534779) (xy 97.349444 -323.520089) (xy 97.29204 -323.498323)
			(xy 97.237677 -323.469797) (xy 97.21215 -323.452744) (xy 97.203398 -323.447273) (xy 97.183194 -323.443145)
			(xy 97.16299 -323.447273) (xy 97.154238 -323.452744) (xy 97.128712 -323.469797) (xy 97.074341 -323.498305)
			(xy 97.016936 -323.520065) (xy 96.95733 -323.534762) (xy 96.896389 -323.542182) (xy 96.865694 -323.54266)
			(xy 96.83496 -323.542268) (xy 96.77394 -323.534858) (xy 96.714258 -323.520146) (xy 96.656785 -323.498347)
			(xy 96.602359 -323.469779) (xy 96.551773 -323.434859) (xy 96.505766 -323.394096) (xy 96.465007 -323.348084)
			(xy 96.430093 -323.297495) (xy 96.401531 -323.243065) (xy 96.379738 -323.18559) (xy 96.365033 -323.125907)
			(xy 96.357629 -323.064886) (xy 96.357186 -323.034152) (xy 94.631002 -323.034152) (xy 94.630517 -323.064883)
			(xy 94.623114 -323.125898) (xy 94.60841 -323.185576) (xy 94.586619 -323.243046) (xy 94.558059 -323.29747)
			(xy 94.523147 -323.348055) (xy 94.482392 -323.394062) (xy 94.436388 -323.434821) (xy 94.385806 -323.469737)
			(xy 94.331385 -323.498302) (xy 94.273916 -323.520097) (xy 94.21424 -323.534806) (xy 94.153225 -323.542215)
			(xy 94.122494 -323.54266) (xy 94.091798 -323.542178) (xy 94.030853 -323.534779) (xy 93.971244 -323.520089)
			(xy 93.91384 -323.498323) (xy 93.859477 -323.469797) (xy 93.83395 -323.452744) (xy 93.825198 -323.447273)
			(xy 93.804994 -323.443145) (xy 93.78479 -323.447273) (xy 93.776038 -323.452744) (xy 93.750512 -323.469797)
			(xy 93.696141 -323.498305) (xy 93.638736 -323.520065) (xy 93.57913 -323.534762) (xy 93.518189 -323.542182)
			(xy 93.487494 -323.54266) (xy 93.456798 -323.542178) (xy 93.395853 -323.534779) (xy 93.336244 -323.520089)
			(xy 93.27884 -323.498323) (xy 93.224477 -323.469797) (xy 93.19895 -323.452744) (xy 93.190198 -323.447273)
			(xy 93.169994 -323.443145) (xy 93.14979 -323.447273) (xy 93.141038 -323.452744) (xy 93.115512 -323.469797)
			(xy 93.061141 -323.498305) (xy 93.003736 -323.520065) (xy 92.94413 -323.534762) (xy 92.883189 -323.542182)
			(xy 92.852494 -323.54266) (xy 92.82176 -323.542268) (xy 92.76074 -323.534858) (xy 92.701058 -323.520146)
			(xy 92.643585 -323.498347) (xy 92.589159 -323.469779) (xy 92.538573 -323.434859) (xy 92.492566 -323.394096)
			(xy 92.451807 -323.348084) (xy 92.416893 -323.297495) (xy 92.388331 -323.243065) (xy 92.366538 -323.18559)
			(xy 92.351833 -323.125907) (xy 92.344429 -323.064886) (xy 92.343986 -323.034152) (xy 92.344456 -323.003456)
			(xy 92.35186 -322.942511) (xy 92.366553 -322.882902) (xy 92.388321 -322.825498) (xy 92.416848 -322.771135)
			(xy 92.433902 -322.745608) (xy 92.439415 -322.736878) (xy 92.44353 -322.71666) (xy 92.439384 -322.696448)
			(xy 92.433902 -322.687696) (xy 92.416867 -322.662158) (xy 92.388358 -322.60779) (xy 92.366595 -322.550388)
			(xy 92.351893 -322.490785) (xy 92.344468 -322.429846) (xy 92.343986 -322.399152) (xy 92.344456 -322.368456)
			(xy 92.35186 -322.307511) (xy 92.366553 -322.247902) (xy 92.388321 -322.190498) (xy 92.416848 -322.136135)
			(xy 92.433902 -322.110608) (xy 92.439415 -322.101878) (xy 92.44353 -322.08166) (xy 92.439384 -322.061448)
			(xy 92.433902 -322.052696) (xy 92.416867 -322.027158) (xy 92.388358 -321.97279) (xy 92.366595 -321.915388)
			(xy 92.351893 -321.855785) (xy 92.344468 -321.794846) (xy 92.343986 -321.764152) (xy 92.344456 -321.733456)
			(xy 92.35186 -321.672511) (xy 92.366553 -321.612902) (xy 92.388321 -321.555498) (xy 92.416848 -321.501135)
			(xy 92.433902 -321.475608) (xy 92.439415 -321.466878) (xy 92.44353 -321.44666) (xy 92.439384 -321.426448)
			(xy 92.433902 -321.417696) (xy 92.416867 -321.392158) (xy 92.388358 -321.33779) (xy 92.366595 -321.280388)
			(xy 92.351893 -321.220785) (xy 92.344468 -321.159846) (xy 92.343986 -321.129152) (xy 92.344456 -321.098456)
			(xy 92.35186 -321.037511) (xy 92.366553 -320.977902) (xy 92.388321 -320.920498) (xy 92.416848 -320.866135)
			(xy 92.433902 -320.840608) (xy 92.439415 -320.831878) (xy 92.44353 -320.81166) (xy 92.439384 -320.791448)
			(xy 92.433902 -320.782696) (xy 92.416867 -320.757158) (xy 92.388358 -320.70279) (xy 92.366595 -320.645388)
			(xy 92.351893 -320.585785) (xy 92.344468 -320.524846) (xy 92.343986 -320.494152) (xy 92.344402 -320.463956)
			(xy 92.351534 -320.403987) (xy 92.365716 -320.345285) (xy 92.386748 -320.288674) (xy 92.414335 -320.234952)
			(xy 92.430854 -320.209672) (xy 92.436521 -320.200513) (xy 92.440212 -320.179308) (xy 92.434888 -320.158453)
			(xy 92.428568 -320.149728) (xy 92.407844 -320.122637) (xy 92.373019 -320.063991) (xy 92.346335 -320.00122)
			(xy 92.328268 -319.935449) (xy 92.319143 -319.867855) (xy 92.318586 -319.833752) (xy 90.390002 -319.833752)
			(xy 90.38976 -319.849971) (xy 90.382354 -319.910916) (xy 90.367658 -319.970525) (xy 90.345886 -320.027929)
			(xy 90.317357 -320.082291) (xy 90.300302 -320.107818) (xy 90.294852 -320.116582) (xy 90.290716 -320.136778)
			(xy 90.294835 -320.156978) (xy 90.300302 -320.16573) (xy 90.317348 -320.191261) (xy 90.345856 -320.245631)
			(xy 90.367616 -320.303035) (xy 90.382315 -320.362639) (xy 90.389738 -320.423579) (xy 90.390218 -320.454274)
			(xy 90.38976 -320.484971) (xy 90.382354 -320.545916) (xy 90.367658 -320.605525) (xy 90.345886 -320.662929)
			(xy 90.317357 -320.717291) (xy 90.300302 -320.742818) (xy 90.294852 -320.751582) (xy 90.290716 -320.771778)
			(xy 90.294835 -320.791978) (xy 90.300302 -320.80073) (xy 90.317348 -320.826261) (xy 90.345856 -320.880631)
			(xy 90.367616 -320.938035) (xy 90.382315 -320.997639) (xy 90.389738 -321.058579) (xy 90.390218 -321.089274)
			(xy 90.38976 -321.119971) (xy 90.382354 -321.180916) (xy 90.367658 -321.240525) (xy 90.345886 -321.297929)
			(xy 90.317357 -321.352291) (xy 90.300302 -321.377818) (xy 90.294852 -321.386582) (xy 90.290716 -321.406778)
			(xy 90.294835 -321.426978) (xy 90.300302 -321.43573) (xy 90.317348 -321.461261) (xy 90.345856 -321.515631)
			(xy 90.367616 -321.573035) (xy 90.382315 -321.632639) (xy 90.389738 -321.693579) (xy 90.390218 -321.724274)
			(xy 90.38976 -321.754971) (xy 90.382354 -321.815916) (xy 90.367658 -321.875525) (xy 90.345886 -321.932929)
			(xy 90.317357 -321.987291) (xy 90.300302 -322.012818) (xy 90.294852 -322.021582) (xy 90.290716 -322.041778)
			(xy 90.294835 -322.061978) (xy 90.300302 -322.07073) (xy 90.317348 -322.096261) (xy 90.345856 -322.150631)
			(xy 90.367616 -322.208035) (xy 90.382315 -322.267639) (xy 90.389738 -322.328579) (xy 90.390218 -322.359274)
			(xy 90.389738 -322.390869) (xy 90.381917 -322.453574) (xy 90.366379 -322.514825) (xy 90.343364 -322.573675)
			(xy 90.313227 -322.629217) (xy 90.295222 -322.655184) (xy 90.289504 -322.664032) (xy 90.285208 -322.68464)
			(xy 90.289535 -322.70524) (xy 90.295222 -322.714112) (xy 90.313026 -322.740022) (xy 90.342838 -322.795372)
			(xy 90.365606 -322.853972) (xy 90.380981 -322.91493) (xy 90.388731 -322.977318) (xy 90.389202 -323.008752)
			(xy 90.388717 -323.039483) (xy 90.381314 -323.100498) (xy 90.36661 -323.160176) (xy 90.344819 -323.217646)
			(xy 90.316259 -323.27207) (xy 90.281347 -323.322655) (xy 90.240592 -323.368662) (xy 90.194588 -323.409421)
			(xy 90.144006 -323.444337) (xy 90.089585 -323.472902) (xy 90.032116 -323.494697) (xy 89.97244 -323.509406)
			(xy 89.911425 -323.516815) (xy 89.880694 -323.51726) (xy 89.849998 -323.516778) (xy 89.789053 -323.509379)
			(xy 89.729444 -323.494689) (xy 89.67204 -323.472923) (xy 89.617677 -323.444397) (xy 89.59215 -323.427344)
			(xy 89.583398 -323.421873) (xy 89.563194 -323.417745) (xy 89.54299 -323.421873) (xy 89.534238 -323.427344)
			(xy 89.508712 -323.444397) (xy 89.454341 -323.472905) (xy 89.396936 -323.494665) (xy 89.33733 -323.509362)
			(xy 89.276389 -323.516782) (xy 89.245694 -323.51726) (xy 89.214998 -323.516778) (xy 89.154053 -323.509379)
			(xy 89.094444 -323.494689) (xy 89.03704 -323.472923) (xy 88.982677 -323.444397) (xy 88.95715 -323.427344)
			(xy 88.948398 -323.421873) (xy 88.928194 -323.417745) (xy 88.90799 -323.421873) (xy 88.899238 -323.427344)
			(xy 88.873712 -323.444397) (xy 88.819341 -323.472905) (xy 88.761936 -323.494665) (xy 88.70233 -323.509362)
			(xy 88.641389 -323.516782) (xy 88.610694 -323.51726) (xy 88.57996 -323.516868) (xy 88.51894 -323.509458)
			(xy 88.459258 -323.494746) (xy 88.401785 -323.472947) (xy 88.347359 -323.444379) (xy 88.296773 -323.409459)
			(xy 88.250766 -323.368696) (xy 88.210007 -323.322684) (xy 88.175093 -323.272095) (xy 88.146531 -323.217665)
			(xy 88.124738 -323.16019) (xy 88.110033 -323.100507) (xy 88.102629 -323.039486) (xy 88.102186 -323.008752)
			(xy 86.350602 -323.008752) (xy 86.350117 -323.039483) (xy 86.342714 -323.100498) (xy 86.32801 -323.160176)
			(xy 86.306219 -323.217646) (xy 86.277659 -323.27207) (xy 86.242747 -323.322655) (xy 86.201992 -323.368662)
			(xy 86.155988 -323.409421) (xy 86.105406 -323.444337) (xy 86.050985 -323.472902) (xy 85.993516 -323.494697)
			(xy 85.93384 -323.509406) (xy 85.872825 -323.516815) (xy 85.842094 -323.51726) (xy 85.811398 -323.516778)
			(xy 85.750453 -323.509379) (xy 85.690844 -323.494689) (xy 85.63344 -323.472923) (xy 85.579077 -323.444397)
			(xy 85.55355 -323.427344) (xy 85.544798 -323.421873) (xy 85.524594 -323.417745) (xy 85.50439 -323.421873)
			(xy 85.495638 -323.427344) (xy 85.470112 -323.444397) (xy 85.415741 -323.472905) (xy 85.358336 -323.494665)
			(xy 85.29873 -323.509362) (xy 85.237789 -323.516782) (xy 85.207094 -323.51726) (xy 85.176398 -323.516778)
			(xy 85.115453 -323.509379) (xy 85.055844 -323.494689) (xy 84.99844 -323.472923) (xy 84.944077 -323.444397)
			(xy 84.91855 -323.427344) (xy 84.909798 -323.421873) (xy 84.889594 -323.417745) (xy 84.86939 -323.421873)
			(xy 84.860638 -323.427344) (xy 84.835112 -323.444397) (xy 84.780741 -323.472905) (xy 84.723336 -323.494665)
			(xy 84.66373 -323.509362) (xy 84.602789 -323.516782) (xy 84.572094 -323.51726) (xy 84.54136 -323.516868)
			(xy 84.48034 -323.509458) (xy 84.420658 -323.494746) (xy 84.363185 -323.472947) (xy 84.308759 -323.444379)
			(xy 84.258173 -323.409459) (xy 84.212166 -323.368696) (xy 84.171407 -323.322684) (xy 84.136493 -323.272095)
			(xy 84.107931 -323.217665) (xy 84.086138 -323.16019) (xy 84.071433 -323.100507) (xy 84.064029 -323.039486)
			(xy 84.063586 -323.008752) (xy 82.010758 -323.008752) (xy 82.010199 -323.03948) (xy 82.002797 -323.100489)
			(xy 81.988095 -323.16016) (xy 81.966308 -323.217625) (xy 81.937753 -323.272044) (xy 81.902847 -323.322625)
			(xy 81.862099 -323.368629) (xy 81.816102 -323.409387) (xy 81.765528 -323.444303) (xy 81.711114 -323.472868)
			(xy 81.653654 -323.494666) (xy 81.593985 -323.509379) (xy 81.532978 -323.516793) (xy 81.50225 -323.51726)
			(xy 81.471553 -323.5168) (xy 81.410608 -323.509396) (xy 81.350999 -323.494701) (xy 81.293595 -323.47293)
			(xy 81.239233 -323.4444) (xy 81.213706 -323.427344) (xy 81.204954 -323.421873) (xy 81.18475 -323.417745)
			(xy 81.164546 -323.421873) (xy 81.155794 -323.427344) (xy 81.130252 -323.444373) (xy 81.075886 -323.472885)
			(xy 81.018485 -323.49465) (xy 80.958882 -323.509352) (xy 80.897944 -323.516778) (xy 80.86725 -323.51726)
			(xy 80.836553 -323.5168) (xy 80.775608 -323.509396) (xy 80.715999 -323.494701) (xy 80.658595 -323.47293)
			(xy 80.604233 -323.4444) (xy 80.578706 -323.427344) (xy 80.569954 -323.421873) (xy 80.54975 -323.417745)
			(xy 80.529546 -323.421873) (xy 80.520794 -323.427344) (xy 80.495252 -323.444373) (xy 80.440886 -323.472885)
			(xy 80.383485 -323.49465) (xy 80.323882 -323.509352) (xy 80.262944 -323.516778) (xy 80.23225 -323.51726)
			(xy 80.201516 -323.516891) (xy 80.140497 -323.509476) (xy 80.080817 -323.49476) (xy 80.023345 -323.472958)
			(xy 79.968921 -323.444387) (xy 79.918337 -323.409464) (xy 79.872332 -323.368699) (xy 79.831575 -323.322686)
			(xy 79.796662 -323.272095) (xy 79.768102 -323.217665) (xy 79.746311 -323.16019) (xy 79.731606 -323.100506)
			(xy 79.724203 -323.039486) (xy 79.723742 -323.008752) (xy 77.997558 -323.008752) (xy 77.996999 -323.03948)
			(xy 77.989597 -323.100489) (xy 77.974895 -323.16016) (xy 77.953108 -323.217625) (xy 77.924553 -323.272044)
			(xy 77.889647 -323.322625) (xy 77.848899 -323.368629) (xy 77.802902 -323.409387) (xy 77.752328 -323.444303)
			(xy 77.697914 -323.472868) (xy 77.640454 -323.494666) (xy 77.580785 -323.509379) (xy 77.519778 -323.516793)
			(xy 77.48905 -323.51726) (xy 77.458353 -323.5168) (xy 77.397408 -323.509396) (xy 77.337799 -323.494701)
			(xy 77.280395 -323.47293) (xy 77.226033 -323.4444) (xy 77.200506 -323.427344) (xy 77.191754 -323.421873)
			(xy 77.17155 -323.417745) (xy 77.151346 -323.421873) (xy 77.142594 -323.427344) (xy 77.117052 -323.444373)
			(xy 77.062686 -323.472885) (xy 77.005285 -323.49465) (xy 76.945682 -323.509352) (xy 76.884744 -323.516778)
			(xy 76.85405 -323.51726) (xy 76.823353 -323.5168) (xy 76.762408 -323.509396) (xy 76.702799 -323.494701)
			(xy 76.645395 -323.47293) (xy 76.591033 -323.4444) (xy 76.565506 -323.427344) (xy 76.556754 -323.421873)
			(xy 76.53655 -323.417745) (xy 76.516346 -323.421873) (xy 76.507594 -323.427344) (xy 76.482052 -323.444373)
			(xy 76.427686 -323.472885) (xy 76.370285 -323.49465) (xy 76.310682 -323.509352) (xy 76.249744 -323.516778)
			(xy 76.21905 -323.51726) (xy 76.188316 -323.516891) (xy 76.127297 -323.509476) (xy 76.067617 -323.49476)
			(xy 76.010145 -323.472958) (xy 75.955721 -323.444387) (xy 75.905137 -323.409464) (xy 75.859132 -323.368699)
			(xy 75.818375 -323.322686) (xy 75.783462 -323.272095) (xy 75.754902 -323.217665) (xy 75.733111 -323.16019)
			(xy 75.718406 -323.100506) (xy 75.711003 -323.039486) (xy 75.710542 -323.008752) (xy 75.711048 -322.977528)
			(xy 75.718715 -322.915553) (xy 75.733917 -322.854985) (xy 75.756424 -322.796734) (xy 75.785897 -322.741679)
			(xy 75.803506 -322.71589) (xy 75.80919 -322.706959) (xy 75.813344 -322.686221) (xy 75.808804 -322.665563)
			(xy 75.802998 -322.656708) (xy 75.784803 -322.630648) (xy 75.754357 -322.574856) (xy 75.731098 -322.515705)
			(xy 75.715389 -322.454118) (xy 75.707474 -322.391054) (xy 75.706986 -322.359274) (xy 73.67668 -322.359274)
			(xy 73.677018 -322.380864) (xy 73.67649 -322.4141) (xy 73.667862 -322.48001) (xy 73.65071 -322.544231)
			(xy 73.625326 -322.605665) (xy 73.592145 -322.663264) (xy 73.57237 -322.689982) (xy 73.566414 -322.698672)
			(xy 73.561395 -322.719107) (xy 73.564978 -322.739842) (xy 73.570338 -322.74891) (xy 73.586505 -322.773982)
			(xy 73.613454 -322.827209) (xy 73.633987 -322.883224) (xy 73.647821 -322.941257) (xy 73.654766 -323.000512)
			(xy 73.655174 -323.030342) (xy 73.654784 -323.061075) (xy 73.64737 -323.122093) (xy 73.632655 -323.181772)
			(xy 73.610854 -323.239243) (xy 73.582285 -323.293666) (xy 73.547364 -323.34425) (xy 73.506601 -323.390255)
			(xy 73.46059 -323.431011) (xy 73.410001 -323.465925) (xy 73.355573 -323.494486) (xy 73.2981 -323.516278)
			(xy 73.238418 -323.530984) (xy 73.177399 -323.538388) (xy 73.146666 -323.53885) (xy 73.115969 -323.538384)
			(xy 73.055024 -323.530981) (xy 72.995415 -323.516288) (xy 72.938011 -323.494518) (xy 72.883649 -323.465989)
			(xy 72.858122 -323.448934) (xy 72.84937 -323.443463) (xy 72.829166 -323.439335) (xy 72.808962 -323.443463)
			(xy 72.80021 -323.448934) (xy 72.774663 -323.465955) (xy 72.720298 -323.494468) (xy 72.662898 -323.516235)
			(xy 72.603297 -323.530939) (xy 72.54236 -323.538367) (xy 72.511666 -323.53885) (xy 72.480969 -323.538384)
			(xy 72.420024 -323.530981) (xy 72.360415 -323.516288) (xy 72.303011 -323.494518) (xy 72.248649 -323.465989)
			(xy 72.223122 -323.448934) (xy 72.21437 -323.443463) (xy 72.194166 -323.439335) (xy 72.173962 -323.443463)
			(xy 72.16521 -323.448934) (xy 72.139663 -323.465955) (xy 72.085298 -323.494468) (xy 72.027898 -323.516235)
			(xy 71.968297 -323.530939) (xy 71.90736 -323.538367) (xy 71.876666 -323.53885) (xy 71.845936 -323.538376)
			(xy 71.784924 -323.530965) (xy 71.72525 -323.516254) (xy 71.667785 -323.494458) (xy 71.613365 -323.465895)
			(xy 71.562784 -323.430981) (xy 71.516781 -323.390225) (xy 71.476024 -323.344222) (xy 71.441109 -323.293642)
			(xy 71.412545 -323.239223) (xy 71.390749 -323.181757) (xy 71.376037 -323.122084) (xy 71.368624 -323.061072)
			(xy 71.368158 -323.030342) (xy 69.641974 -323.030342) (xy 69.641584 -323.061075) (xy 69.63417 -323.122093)
			(xy 69.619455 -323.181772) (xy 69.597654 -323.239243) (xy 69.569085 -323.293666) (xy 69.534164 -323.34425)
			(xy 69.493401 -323.390255) (xy 69.44739 -323.431011) (xy 69.396801 -323.465925) (xy 69.342373 -323.494486)
			(xy 69.2849 -323.516278) (xy 69.225218 -323.530984) (xy 69.164199 -323.538388) (xy 69.133466 -323.53885)
			(xy 69.102769 -323.538384) (xy 69.041824 -323.530981) (xy 68.982215 -323.516288) (xy 68.924811 -323.494518)
			(xy 68.870449 -323.465989) (xy 68.844922 -323.448934) (xy 68.83617 -323.443463) (xy 68.815966 -323.439335)
			(xy 68.795762 -323.443463) (xy 68.78701 -323.448934) (xy 68.761463 -323.465955) (xy 68.707098 -323.494468)
			(xy 68.649698 -323.516235) (xy 68.590097 -323.530939) (xy 68.52916 -323.538367) (xy 68.498466 -323.53885)
			(xy 68.467769 -323.538384) (xy 68.406824 -323.530981) (xy 68.347215 -323.516288) (xy 68.289811 -323.494518)
			(xy 68.235449 -323.465989) (xy 68.209922 -323.448934) (xy 68.20117 -323.443463) (xy 68.180966 -323.439335)
			(xy 68.160762 -323.443463) (xy 68.15201 -323.448934) (xy 68.126463 -323.465955) (xy 68.072098 -323.494468)
			(xy 68.014698 -323.516235) (xy 67.955097 -323.530939) (xy 67.89416 -323.538367) (xy 67.863466 -323.53885)
			(xy 67.832736 -323.538376) (xy 67.771724 -323.530965) (xy 67.71205 -323.516254) (xy 67.654585 -323.494458)
			(xy 67.600165 -323.465895) (xy 67.549584 -323.430981) (xy 67.503581 -323.390225) (xy 67.462824 -323.344222)
			(xy 67.427909 -323.293642) (xy 67.399345 -323.239223) (xy 67.377549 -323.181757) (xy 67.362837 -323.122084)
			(xy 67.355424 -323.061072) (xy 67.354958 -323.030342) (xy 25.18664 -323.030342) (xy 25.18664 -324.53529)
			(xy 25.334225 -324.53529) (xy 25.338216 -324.446403) (xy 25.35016 -324.358232) (xy 25.369959 -324.271486)
			(xy 25.397454 -324.186865) (xy 25.432424 -324.105048) (xy 25.474587 -324.026696) (xy 25.523604 -323.952439)
			(xy 25.57908 -323.882874) (xy 25.640568 -323.818563) (xy 25.707574 -323.760022) (xy 25.779558 -323.707723)
			(xy 25.855939 -323.662087) (xy 25.936104 -323.623481) (xy 26.019407 -323.592217) (xy 26.105177 -323.568546)
			(xy 26.192724 -323.552659) (xy 26.281342 -323.544683) (xy 26.32583 -323.544184) (xy 28.07843 -323.544184)
			(xy 28.122918 -323.544679) (xy 28.211537 -323.552655) (xy 28.299084 -323.568542) (xy 28.384854 -323.592213)
			(xy 28.468157 -323.623478) (xy 28.548323 -323.662083) (xy 28.624705 -323.707719) (xy 28.696688 -323.760018)
			(xy 28.763694 -323.81856) (xy 28.825183 -323.882872) (xy 28.880659 -323.952437) (xy 28.929676 -324.026694)
			(xy 28.971839 -324.105047) (xy 29.006809 -324.186863) (xy 29.034305 -324.271485) (xy 29.054104 -324.358231)
			(xy 29.066048 -324.446403) (xy 29.07004 -324.53529) (xy 32.878025 -324.53529) (xy 32.882016 -324.446403)
			(xy 32.89396 -324.358232) (xy 32.913759 -324.271486) (xy 32.941254 -324.186865) (xy 32.976224 -324.105048)
			(xy 33.018387 -324.026696) (xy 33.067404 -323.952439) (xy 33.12288 -323.882874) (xy 33.184368 -323.818563)
			(xy 33.251374 -323.760022) (xy 33.323358 -323.707723) (xy 33.399739 -323.662087) (xy 33.479904 -323.623481)
			(xy 33.563207 -323.592217) (xy 33.648977 -323.568546) (xy 33.736524 -323.552659) (xy 33.825142 -323.544683)
			(xy 33.86963 -323.544184) (xy 35.62223 -323.544184) (xy 35.666718 -323.544679) (xy 35.755337 -323.552655)
			(xy 35.842884 -323.568542) (xy 35.928654 -323.592213) (xy 36.011957 -323.623478) (xy 36.092123 -323.662083)
			(xy 36.168505 -323.707719) (xy 36.240488 -323.760018) (xy 36.307494 -323.81856) (xy 36.368983 -323.882872)
			(xy 36.424459 -323.952437) (xy 36.473476 -324.026694) (xy 36.515639 -324.105047) (xy 36.550609 -324.186863)
			(xy 36.578105 -324.271485) (xy 36.597904 -324.358231) (xy 36.609848 -324.446403) (xy 36.61384 -324.53529)
			(xy 36.61384 -324.5353) (xy 40.422084 -324.5353) (xy 40.426076 -324.446413) (xy 40.43802 -324.358242)
			(xy 40.457819 -324.271496) (xy 40.485314 -324.186875) (xy 40.520283 -324.105058) (xy 40.562446 -324.026706)
			(xy 40.611462 -323.952448) (xy 40.666938 -323.882883) (xy 40.728426 -323.818571) (xy 40.795431 -323.760029)
			(xy 40.867414 -323.70773) (xy 40.943795 -323.662093) (xy 41.023959 -323.623487) (xy 41.107262 -323.592222)
			(xy 41.193031 -323.568549) (xy 41.280578 -323.552661) (xy 41.369196 -323.544684) (xy 41.413684 -323.544184)
			(xy 43.166284 -323.544184) (xy 43.210773 -323.544684) (xy 43.299393 -323.552658) (xy 43.386941 -323.568545)
			(xy 43.472713 -323.592215) (xy 43.556018 -323.623479) (xy 43.636185 -323.662084) (xy 43.712569 -323.70772)
			(xy 43.784554 -323.760019) (xy 43.851561 -323.818561) (xy 43.913051 -323.882873) (xy 43.968529 -323.952439)
			(xy 44.017547 -324.026697) (xy 44.059711 -324.105051) (xy 44.094682 -324.186868) (xy 44.122178 -324.271491)
			(xy 44.141978 -324.358239) (xy 44.153922 -324.446411) (xy 44.157914 -324.53529) (xy 47.966134 -324.53529)
			(xy 47.970126 -324.446403) (xy 47.98207 -324.358232) (xy 48.001869 -324.271487) (xy 48.029364 -324.186865)
			(xy 48.064334 -324.105049) (xy 48.106497 -324.026697) (xy 48.155514 -323.95244) (xy 48.21099 -323.882875)
			(xy 48.272478 -323.818563) (xy 48.339483 -323.760022) (xy 48.411466 -323.707723) (xy 48.487848 -323.662087)
			(xy 48.568013 -323.623482) (xy 48.651316 -323.592218) (xy 48.737085 -323.568547) (xy 48.824632 -323.552659)
			(xy 48.91325 -323.544683) (xy 48.957738 -323.544184) (xy 50.710338 -323.544184) (xy 50.754827 -323.544664)
			(xy 50.843447 -323.55264) (xy 50.930995 -323.568528) (xy 51.016767 -323.592199) (xy 51.100072 -323.623464)
			(xy 51.180238 -323.66207) (xy 51.256622 -323.707706) (xy 51.328607 -323.760006) (xy 51.395614 -323.818549)
			(xy 51.457103 -323.882861) (xy 51.51258 -323.952427) (xy 51.561598 -324.026686) (xy 51.603762 -324.10504)
			(xy 51.638733 -324.186858) (xy 51.666229 -324.271481) (xy 51.686028 -324.358228) (xy 51.697972 -324.446401)
			(xy 51.701964 -324.53529) (xy 51.701964 -324.5353) (xy 55.510184 -324.5353) (xy 55.514176 -324.446413)
			(xy 55.52612 -324.358241) (xy 55.545919 -324.271495) (xy 55.573414 -324.186873) (xy 55.608384 -324.105056)
			(xy 55.650547 -324.026703) (xy 55.699564 -323.952446) (xy 55.75504 -323.882881) (xy 55.816529 -323.818568)
			(xy 55.883534 -323.760027) (xy 55.955518 -323.707727) (xy 56.0319 -323.66209) (xy 56.112065 -323.623484)
			(xy 56.195368 -323.59222) (xy 56.281138 -323.568548) (xy 56.368685 -323.55266) (xy 56.457304 -323.544683)
			(xy 56.501792 -323.544184) (xy 58.254392 -323.544184) (xy 58.298881 -323.544684) (xy 58.3875 -323.552659)
			(xy 58.475048 -323.568546) (xy 58.560819 -323.592217) (xy 58.644124 -323.623481) (xy 58.72429 -323.662087)
			(xy 58.800673 -323.707723) (xy 58.872658 -323.760022) (xy 58.939664 -323.818564) (xy 59.001154 -323.882876)
			(xy 59.056631 -323.952441) (xy 59.105648 -324.0267) (xy 59.147812 -324.105053) (xy 59.182783 -324.18687)
			(xy 59.210279 -324.271493) (xy 59.230078 -324.35824) (xy 59.242022 -324.446412) (xy 59.246014 -324.5353)
			(xy 59.242022 -324.624188) (xy 59.230078 -324.71236) (xy 59.210279 -324.799107) (xy 59.182783 -324.88373)
			(xy 59.147812 -324.965547) (xy 59.105648 -325.0439) (xy 59.056631 -325.118159) (xy 59.001154 -325.187724)
			(xy 58.939664 -325.252036) (xy 58.872658 -325.310578) (xy 58.800673 -325.362877) (xy 58.72429 -325.408513)
			(xy 58.644124 -325.447119) (xy 58.560819 -325.478383) (xy 58.475048 -325.502054) (xy 58.3875 -325.517941)
			(xy 58.298881 -325.525916) (xy 58.254392 -325.5264) (xy 56.501792 -325.5264) (xy 56.457304 -325.525917)
			(xy 56.368685 -325.51794) (xy 56.281138 -325.502052) (xy 56.195368 -325.47838) (xy 56.112065 -325.447116)
			(xy 56.0319 -325.40851) (xy 55.955518 -325.362873) (xy 55.883534 -325.310573) (xy 55.816529 -325.252032)
			(xy 55.75504 -325.187719) (xy 55.699564 -325.118154) (xy 55.650547 -325.043897) (xy 55.608384 -324.965544)
			(xy 55.573414 -324.883727) (xy 55.545919 -324.799105) (xy 55.52612 -324.712359) (xy 55.514176 -324.624187)
			(xy 55.510184 -324.5353) (xy 51.701964 -324.5353) (xy 51.697972 -324.624179) (xy 51.686028 -324.712352)
			(xy 51.666229 -324.799099) (xy 51.638733 -324.883722) (xy 51.603762 -324.96554) (xy 51.561598 -325.043894)
			(xy 51.51258 -325.118153) (xy 51.457103 -325.187719) (xy 51.395614 -325.252031) (xy 51.328607 -325.310574)
			(xy 51.256622 -325.362874) (xy 51.180238 -325.40851) (xy 51.100072 -325.447116) (xy 51.016767 -325.478381)
			(xy 50.930995 -325.502052) (xy 50.843447 -325.51794) (xy 50.754827 -325.525916) (xy 50.710338 -325.5264)
			(xy 48.957738 -325.5264) (xy 48.91325 -325.525897) (xy 48.824632 -325.517921) (xy 48.737085 -325.502033)
			(xy 48.651316 -325.478362) (xy 48.568013 -325.447098) (xy 48.487848 -325.408493) (xy 48.411466 -325.362857)
			(xy 48.339483 -325.310558) (xy 48.272478 -325.252017) (xy 48.21099 -325.187705) (xy 48.155514 -325.11814)
			(xy 48.106497 -325.043883) (xy 48.064334 -324.965531) (xy 48.029364 -324.883715) (xy 48.001869 -324.799093)
			(xy 47.98207 -324.712348) (xy 47.970126 -324.624177) (xy 47.966134 -324.53529) (xy 44.157914 -324.53529)
			(xy 44.157914 -324.5353) (xy 44.153922 -324.624189) (xy 44.141978 -324.712361) (xy 44.122178 -324.799109)
			(xy 44.094682 -324.883732) (xy 44.059711 -324.965549) (xy 44.017547 -325.043903) (xy 43.968529 -325.118161)
			(xy 43.913051 -325.187727) (xy 43.851561 -325.252039) (xy 43.784554 -325.310581) (xy 43.712569 -325.36288)
			(xy 43.636185 -325.408516) (xy 43.556018 -325.447121) (xy 43.472713 -325.478385) (xy 43.386941 -325.502055)
			(xy 43.299393 -325.517942) (xy 43.210773 -325.525916) (xy 43.166284 -325.5264) (xy 41.413684 -325.5264)
			(xy 41.369196 -325.525916) (xy 41.280578 -325.517939) (xy 41.193031 -325.502051) (xy 41.107262 -325.478378)
			(xy 41.023959 -325.447113) (xy 40.943795 -325.408507) (xy 40.867414 -325.36287) (xy 40.795431 -325.310571)
			(xy 40.728426 -325.252029) (xy 40.666938 -325.187717) (xy 40.611462 -325.118152) (xy 40.562446 -325.043894)
			(xy 40.520283 -324.965542) (xy 40.485314 -324.883725) (xy 40.457819 -324.799104) (xy 40.43802 -324.712358)
			(xy 40.426076 -324.624187) (xy 40.422084 -324.5353) (xy 36.61384 -324.5353) (xy 36.609848 -324.624177)
			(xy 36.597904 -324.712349) (xy 36.578105 -324.799095) (xy 36.550609 -324.883717) (xy 36.515639 -324.965533)
			(xy 36.473476 -325.043886) (xy 36.424459 -325.118143) (xy 36.368983 -325.187708) (xy 36.307494 -325.25202)
			(xy 36.240488 -325.310562) (xy 36.168505 -325.362861) (xy 36.092123 -325.408497) (xy 36.011957 -325.447102)
			(xy 35.928654 -325.478367) (xy 35.842884 -325.502038) (xy 35.755337 -325.517925) (xy 35.666718 -325.525901)
			(xy 35.62223 -325.5264) (xy 33.86963 -325.5264) (xy 33.825142 -325.525897) (xy 33.736524 -325.517921)
			(xy 33.648977 -325.502034) (xy 33.563207 -325.478363) (xy 33.479904 -325.447099) (xy 33.399739 -325.408493)
			(xy 33.323358 -325.362857) (xy 33.251374 -325.310558) (xy 33.184368 -325.252017) (xy 33.12288 -325.187706)
			(xy 33.067404 -325.118141) (xy 33.018387 -325.043884) (xy 32.976224 -324.965532) (xy 32.941254 -324.883715)
			(xy 32.913759 -324.799094) (xy 32.89396 -324.712348) (xy 32.882016 -324.624177) (xy 32.878025 -324.53529)
			(xy 29.07004 -324.53529) (xy 29.066048 -324.624177) (xy 29.054104 -324.712349) (xy 29.034305 -324.799095)
			(xy 29.006809 -324.883717) (xy 28.971839 -324.965533) (xy 28.929676 -325.043886) (xy 28.880659 -325.118143)
			(xy 28.825183 -325.187708) (xy 28.763694 -325.25202) (xy 28.696688 -325.310562) (xy 28.624705 -325.362861)
			(xy 28.548323 -325.408497) (xy 28.468157 -325.447102) (xy 28.384854 -325.478367) (xy 28.299084 -325.502038)
			(xy 28.211537 -325.517925) (xy 28.122918 -325.525901) (xy 28.07843 -325.5264) (xy 26.32583 -325.5264)
			(xy 26.281342 -325.525897) (xy 26.192724 -325.517921) (xy 26.105177 -325.502034) (xy 26.019407 -325.478363)
			(xy 25.936104 -325.447099) (xy 25.855939 -325.408493) (xy 25.779558 -325.362857) (xy 25.707574 -325.310558)
			(xy 25.640568 -325.252017) (xy 25.57908 -325.187706) (xy 25.523604 -325.118141) (xy 25.474587 -325.043884)
			(xy 25.432424 -324.965532) (xy 25.397454 -324.883715) (xy 25.369959 -324.799094) (xy 25.35016 -324.712348)
			(xy 25.338216 -324.624177) (xy 25.334225 -324.53529) (xy 25.18664 -324.53529) (xy 25.18664 -334.10652)
			(xy 58.664602 -334.10652) (xy 58.665053 -334.075823) (xy 58.672461 -334.014877) (xy 58.687158 -333.955268)
			(xy 58.708931 -333.897865) (xy 58.737462 -333.843503) (xy 58.754518 -333.817976) (xy 58.759972 -333.809215)
			(xy 58.764104 -333.789017) (xy 58.759985 -333.768816) (xy 58.754518 -333.760064) (xy 58.737471 -333.734533)
			(xy 58.708964 -333.680164) (xy 58.687203 -333.62276) (xy 58.672504 -333.563155) (xy 58.665082 -333.502215)
			(xy 58.664602 -333.47152) (xy 58.665053 -333.440823) (xy 58.672461 -333.379877) (xy 58.687158 -333.320268)
			(xy 58.708931 -333.262865) (xy 58.737462 -333.208503) (xy 58.754518 -333.182976) (xy 58.759972 -333.174215)
			(xy 58.764104 -333.154017) (xy 58.759985 -333.133816) (xy 58.754518 -333.125064) (xy 58.737471 -333.099533)
			(xy 58.708964 -333.045164) (xy 58.687203 -332.98776) (xy 58.672504 -332.928155) (xy 58.665082 -332.867215)
			(xy 58.664602 -332.83652) (xy 58.665053 -332.805823) (xy 58.672461 -332.744877) (xy 58.687158 -332.685268)
			(xy 58.708931 -332.627865) (xy 58.737462 -332.573503) (xy 58.754518 -332.547976) (xy 58.759972 -332.539215)
			(xy 58.764104 -332.519017) (xy 58.759985 -332.498816) (xy 58.754518 -332.490064) (xy 58.737471 -332.464533)
			(xy 58.708964 -332.410164) (xy 58.687203 -332.35276) (xy 58.672504 -332.293155) (xy 58.665082 -332.232215)
			(xy 58.664602 -332.20152) (xy 58.665053 -332.170823) (xy 58.672461 -332.109877) (xy 58.687158 -332.050268)
			(xy 58.708931 -331.992865) (xy 58.737462 -331.938503) (xy 58.754518 -331.912976) (xy 58.759972 -331.904215)
			(xy 58.764104 -331.884017) (xy 58.759985 -331.863816) (xy 58.754518 -331.855064) (xy 58.737471 -331.829533)
			(xy 58.708964 -331.775164) (xy 58.687203 -331.71776) (xy 58.672504 -331.658155) (xy 58.665082 -331.597215)
			(xy 58.664602 -331.56652) (xy 58.665053 -331.535823) (xy 58.672461 -331.474877) (xy 58.687158 -331.415268)
			(xy 58.708931 -331.357865) (xy 58.737462 -331.303503) (xy 58.754518 -331.277976) (xy 58.759972 -331.269215)
			(xy 58.764104 -331.249017) (xy 58.759985 -331.228816) (xy 58.754518 -331.220064) (xy 58.737471 -331.194533)
			(xy 58.708964 -331.140164) (xy 58.687203 -331.08276) (xy 58.672504 -331.023155) (xy 58.665082 -330.962215)
			(xy 58.664602 -330.93152) (xy 58.665053 -330.900823) (xy 58.672461 -330.839877) (xy 58.687158 -330.780268)
			(xy 58.708931 -330.722865) (xy 58.737462 -330.668503) (xy 58.754518 -330.642976) (xy 58.759972 -330.634215)
			(xy 58.764104 -330.614017) (xy 58.759985 -330.593816) (xy 58.754518 -330.585064) (xy 58.737471 -330.559533)
			(xy 58.708964 -330.505164) (xy 58.687203 -330.44776) (xy 58.672504 -330.388155) (xy 58.665082 -330.327215)
			(xy 58.664602 -330.29652) (xy 58.665053 -330.265823) (xy 58.672461 -330.204877) (xy 58.687158 -330.145268)
			(xy 58.708931 -330.087865) (xy 58.737462 -330.033503) (xy 58.754518 -330.007976) (xy 58.759972 -329.999215)
			(xy 58.764104 -329.979017) (xy 58.759985 -329.958816) (xy 58.754518 -329.950064) (xy 58.737471 -329.924533)
			(xy 58.708964 -329.870164) (xy 58.687203 -329.81276) (xy 58.672504 -329.753155) (xy 58.665082 -329.692215)
			(xy 58.664602 -329.66152) (xy 58.665056 -329.630788) (xy 58.672463 -329.569772) (xy 58.687171 -329.510093)
			(xy 58.708965 -329.452623) (xy 58.737527 -329.398198) (xy 58.772442 -329.347614) (xy 58.8132 -329.301607)
			(xy 58.859206 -329.260848) (xy 58.90979 -329.225932) (xy 58.964214 -329.197369) (xy 59.021684 -329.175574)
			(xy 59.081362 -329.160865) (xy 59.142378 -329.153457) (xy 59.17311 -329.153012) (xy 59.203806 -329.153497)
			(xy 59.26475 -329.160896) (xy 59.324359 -329.175586) (xy 59.381763 -329.197351) (xy 59.436126 -329.225875)
			(xy 59.461654 -329.242928) (xy 59.470406 -329.248399) (xy 59.49061 -329.252527) (xy 59.510814 -329.248399)
			(xy 59.519566 -329.242928) (xy 59.545089 -329.22587) (xy 59.599461 -329.197364) (xy 59.656867 -329.175605)
			(xy 59.716473 -329.160909) (xy 59.777415 -329.15349) (xy 59.80811 -329.153012) (xy 59.838806 -329.153497)
			(xy 59.89975 -329.160896) (xy 59.959359 -329.175586) (xy 60.016763 -329.197351) (xy 60.071126 -329.225875)
			(xy 60.096654 -329.242928) (xy 60.105406 -329.248399) (xy 60.12561 -329.252527) (xy 60.145814 -329.248399)
			(xy 60.154566 -329.242928) (xy 60.180089 -329.22587) (xy 60.234461 -329.197364) (xy 60.291867 -329.175605)
			(xy 60.351473 -329.160909) (xy 60.412415 -329.15349) (xy 60.44311 -329.153012) (xy 60.473843 -329.153428)
			(xy 60.534861 -329.160838) (xy 60.594541 -329.17555) (xy 60.652012 -329.197347) (xy 60.706437 -329.225913)
			(xy 60.757022 -329.260832) (xy 60.803029 -329.301593) (xy 60.843787 -329.347602) (xy 60.878702 -329.398189)
			(xy 60.907265 -329.452615) (xy 60.929059 -329.510088) (xy 60.943767 -329.569769) (xy 60.951174 -329.630787)
			(xy 60.951618 -329.66152) (xy 60.951133 -329.692216) (xy 60.943733 -329.75316) (xy 60.929043 -329.812769)
			(xy 60.907278 -329.870173) (xy 60.878754 -329.924536) (xy 60.861702 -329.950064) (xy 60.856213 -329.958807)
			(xy 60.852089 -329.979017) (xy 60.856226 -329.999224) (xy 60.861702 -330.007976) (xy 60.878768 -330.033494)
			(xy 60.907272 -330.087867) (xy 60.929029 -330.145275) (xy 60.943723 -330.204882) (xy 60.951141 -330.265824)
			(xy 60.951618 -330.29652) (xy 60.951133 -330.327216) (xy 60.943733 -330.38816) (xy 60.929043 -330.447769)
			(xy 60.907278 -330.505173) (xy 60.878754 -330.559536) (xy 60.861702 -330.585064) (xy 60.856213 -330.593807)
			(xy 60.852089 -330.614017) (xy 60.856226 -330.634224) (xy 60.861702 -330.642976) (xy 60.878768 -330.668494)
			(xy 60.907272 -330.722867) (xy 60.929029 -330.780275) (xy 60.943723 -330.839882) (xy 60.951141 -330.900824)
			(xy 60.951618 -330.93152) (xy 60.951133 -330.962216) (xy 60.943733 -331.02316) (xy 60.929043 -331.082769)
			(xy 60.907278 -331.140173) (xy 60.878754 -331.194536) (xy 60.861702 -331.220064) (xy 60.856213 -331.228807)
			(xy 60.852089 -331.249017) (xy 60.856226 -331.269224) (xy 60.861702 -331.277976) (xy 60.878768 -331.303494)
			(xy 60.907272 -331.357867) (xy 60.929029 -331.415275) (xy 60.943723 -331.474882) (xy 60.951141 -331.535824)
			(xy 60.951618 -331.56652) (xy 60.951133 -331.597216) (xy 60.943733 -331.65816) (xy 60.929043 -331.717769)
			(xy 60.907278 -331.775173) (xy 60.878754 -331.829536) (xy 60.861702 -331.855064) (xy 60.856213 -331.863807)
			(xy 60.852089 -331.884017) (xy 60.856226 -331.904224) (xy 60.861702 -331.912976) (xy 60.878768 -331.938494)
			(xy 60.907272 -331.992867) (xy 60.929029 -332.050275) (xy 60.943723 -332.109882) (xy 60.951141 -332.170824)
			(xy 60.951618 -332.20152) (xy 60.951133 -332.232216) (xy 60.943733 -332.29316) (xy 60.929043 -332.352769)
			(xy 60.907278 -332.410173) (xy 60.878754 -332.464536) (xy 60.861702 -332.490064) (xy 60.856213 -332.498807)
			(xy 60.852089 -332.519017) (xy 60.856226 -332.539224) (xy 60.861702 -332.547976) (xy 60.878768 -332.573494)
			(xy 60.907272 -332.627867) (xy 60.929029 -332.685275) (xy 60.943723 -332.744882) (xy 60.951141 -332.805824)
			(xy 60.951618 -332.83652) (xy 60.951133 -332.867216) (xy 60.943733 -332.92816) (xy 60.929043 -332.987769)
			(xy 60.907278 -333.045173) (xy 60.878754 -333.099536) (xy 60.861702 -333.125064) (xy 60.856213 -333.133807)
			(xy 60.852089 -333.154017) (xy 60.856226 -333.174224) (xy 60.861702 -333.182976) (xy 60.878768 -333.208494)
			(xy 60.907272 -333.262867) (xy 60.929029 -333.320275) (xy 60.943723 -333.379882) (xy 60.951141 -333.440824)
			(xy 60.951618 -333.47152) (xy 60.951133 -333.502216) (xy 60.943733 -333.56316) (xy 60.929043 -333.622769)
			(xy 60.907278 -333.680173) (xy 60.878754 -333.734536) (xy 60.861702 -333.760064) (xy 60.856213 -333.768807)
			(xy 60.852089 -333.789017) (xy 60.856226 -333.809224) (xy 60.861702 -333.817976) (xy 60.878768 -333.843494)
			(xy 60.907272 -333.897867) (xy 60.929029 -333.955275) (xy 60.943723 -334.014882) (xy 60.951141 -334.075824)
			(xy 60.951618 -334.10652) (xy 60.951163 -334.137251) (xy 60.943752 -334.198265) (xy 60.929042 -334.25794)
			(xy 60.907245 -334.315408) (xy 60.878681 -334.369829) (xy 60.843766 -334.420411) (xy 60.803009 -334.466416)
			(xy 60.757003 -334.507172) (xy 60.706421 -334.542086) (xy 60.651999 -334.570649) (xy 60.594531 -334.592445)
			(xy 60.534855 -334.607154) (xy 60.473841 -334.614563) (xy 60.44311 -334.615028) (xy 60.412413 -334.614576)
			(xy 60.351468 -334.607168) (xy 60.291859 -334.592471) (xy 60.234455 -334.570698) (xy 60.180093 -334.542168)
			(xy 60.154566 -334.525112) (xy 60.145814 -334.519641) (xy 60.12561 -334.515513) (xy 60.105406 -334.519641)
			(xy 60.096654 -334.525112) (xy 60.071121 -334.542155) (xy 60.016752 -334.570665) (xy 59.959349 -334.592427)
			(xy 59.899745 -334.607126) (xy 59.838805 -334.614549) (xy 59.80811 -334.615028) (xy 59.777413 -334.614576)
			(xy 59.716468 -334.607168) (xy 59.656859 -334.592471) (xy 59.599455 -334.570698) (xy 59.545093 -334.542168)
			(xy 59.519566 -334.525112) (xy 59.510814 -334.519641) (xy 59.49061 -334.515513) (xy 59.470406 -334.519641)
			(xy 59.461654 -334.525112) (xy 59.436121 -334.542155) (xy 59.381752 -334.570665) (xy 59.324349 -334.592427)
			(xy 59.264745 -334.607126) (xy 59.203805 -334.614549) (xy 59.17311 -334.615028) (xy 59.14238 -334.614535)
			(xy 59.081368 -334.607128) (xy 59.021693 -334.592421) (xy 58.964227 -334.570628) (xy 58.909806 -334.542068)
			(xy 58.859224 -334.507156) (xy 58.81322 -334.466401) (xy 58.772463 -334.420399) (xy 58.737548 -334.36982)
			(xy 58.708984 -334.315401) (xy 58.687188 -334.257935) (xy 58.672478 -334.198262) (xy 58.665067 -334.13725)
			(xy 58.664602 -334.10652) (xy 25.18664 -334.10652) (xy 25.18664 -334.74152) (xy 62.677802 -334.74152)
			(xy 62.678253 -334.710823) (xy 62.685661 -334.649877) (xy 62.700358 -334.590268) (xy 62.722131 -334.532865)
			(xy 62.750662 -334.478503) (xy 62.767718 -334.452976) (xy 62.773172 -334.444215) (xy 62.777304 -334.424017)
			(xy 62.773185 -334.403816) (xy 62.767718 -334.395064) (xy 62.750671 -334.369533) (xy 62.722164 -334.315164)
			(xy 62.700403 -334.25776) (xy 62.685704 -334.198155) (xy 62.678282 -334.137215) (xy 62.677802 -334.10652)
			(xy 62.678253 -334.075823) (xy 62.685661 -334.014877) (xy 62.700358 -333.955268) (xy 62.722131 -333.897865)
			(xy 62.750662 -333.843503) (xy 62.767718 -333.817976) (xy 62.773172 -333.809215) (xy 62.777304 -333.789017)
			(xy 62.773185 -333.768816) (xy 62.767718 -333.760064) (xy 62.750671 -333.734533) (xy 62.722164 -333.680164)
			(xy 62.700403 -333.62276) (xy 62.685704 -333.563155) (xy 62.678282 -333.502215) (xy 62.677802 -333.47152)
			(xy 62.678253 -333.440823) (xy 62.685661 -333.379877) (xy 62.700358 -333.320268) (xy 62.722131 -333.262865)
			(xy 62.750662 -333.208503) (xy 62.767718 -333.182976) (xy 62.773172 -333.174215) (xy 62.777304 -333.154017)
			(xy 62.773185 -333.133816) (xy 62.767718 -333.125064) (xy 62.750671 -333.099533) (xy 62.722164 -333.045164)
			(xy 62.700403 -332.98776) (xy 62.685704 -332.928155) (xy 62.678282 -332.867215) (xy 62.677802 -332.83652)
			(xy 62.678253 -332.805823) (xy 62.685661 -332.744877) (xy 62.700358 -332.685268) (xy 62.722131 -332.627865)
			(xy 62.750662 -332.573503) (xy 62.767718 -332.547976) (xy 62.773172 -332.539215) (xy 62.777304 -332.519017)
			(xy 62.773185 -332.498816) (xy 62.767718 -332.490064) (xy 62.750671 -332.464533) (xy 62.722164 -332.410164)
			(xy 62.700403 -332.35276) (xy 62.685704 -332.293155) (xy 62.678282 -332.232215) (xy 62.677802 -332.20152)
			(xy 62.678253 -332.170823) (xy 62.685661 -332.109877) (xy 62.700358 -332.050268) (xy 62.722131 -331.992865)
			(xy 62.750662 -331.938503) (xy 62.767718 -331.912976) (xy 62.773172 -331.904215) (xy 62.777304 -331.884017)
			(xy 62.773185 -331.863816) (xy 62.767718 -331.855064) (xy 62.750671 -331.829533) (xy 62.722164 -331.775164)
			(xy 62.700403 -331.71776) (xy 62.685704 -331.658155) (xy 62.678282 -331.597215) (xy 62.677802 -331.56652)
			(xy 62.678253 -331.535823) (xy 62.685661 -331.474877) (xy 62.700358 -331.415268) (xy 62.722131 -331.357865)
			(xy 62.750662 -331.303503) (xy 62.767718 -331.277976) (xy 62.773172 -331.269215) (xy 62.777304 -331.249017)
			(xy 62.773185 -331.228816) (xy 62.767718 -331.220064) (xy 62.750671 -331.194533) (xy 62.722164 -331.140164)
			(xy 62.700403 -331.08276) (xy 62.685704 -331.023155) (xy 62.678282 -330.962215) (xy 62.677802 -330.93152)
			(xy 62.678253 -330.900823) (xy 62.685661 -330.839877) (xy 62.700358 -330.780268) (xy 62.722131 -330.722865)
			(xy 62.750662 -330.668503) (xy 62.767718 -330.642976) (xy 62.773172 -330.634215) (xy 62.777304 -330.614017)
			(xy 62.773185 -330.593816) (xy 62.767718 -330.585064) (xy 62.750671 -330.559533) (xy 62.722164 -330.505164)
			(xy 62.700403 -330.44776) (xy 62.685704 -330.388155) (xy 62.678282 -330.327215) (xy 62.677802 -330.29652)
			(xy 62.678253 -330.265823) (xy 62.685661 -330.204877) (xy 62.700358 -330.145268) (xy 62.722131 -330.087865)
			(xy 62.750662 -330.033503) (xy 62.767718 -330.007976) (xy 62.773172 -329.999215) (xy 62.777304 -329.979017)
			(xy 62.773185 -329.958816) (xy 62.767718 -329.950064) (xy 62.750671 -329.924533) (xy 62.722164 -329.870164)
			(xy 62.700403 -329.81276) (xy 62.685704 -329.753155) (xy 62.678282 -329.692215) (xy 62.677802 -329.66152)
			(xy 62.678253 -329.630823) (xy 62.685661 -329.569877) (xy 62.700358 -329.510268) (xy 62.722131 -329.452865)
			(xy 62.750662 -329.398503) (xy 62.767718 -329.372976) (xy 62.773172 -329.364215) (xy 62.777304 -329.344017)
			(xy 62.773185 -329.323816) (xy 62.767718 -329.315064) (xy 62.750671 -329.289533) (xy 62.722164 -329.235164)
			(xy 62.700403 -329.17776) (xy 62.685704 -329.118155) (xy 62.678282 -329.057215) (xy 62.677802 -329.02652)
			(xy 62.678253 -328.995823) (xy 62.685661 -328.934877) (xy 62.700358 -328.875268) (xy 62.722131 -328.817865)
			(xy 62.750662 -328.763503) (xy 62.767718 -328.737976) (xy 62.773172 -328.729215) (xy 62.777304 -328.709017)
			(xy 62.773185 -328.688816) (xy 62.767718 -328.680064) (xy 62.750671 -328.654533) (xy 62.722164 -328.600164)
			(xy 62.700403 -328.54276) (xy 62.685704 -328.483155) (xy 62.678282 -328.422215) (xy 62.677802 -328.39152)
			(xy 62.678256 -328.360788) (xy 62.685663 -328.299772) (xy 62.700371 -328.240093) (xy 62.722165 -328.182623)
			(xy 62.750727 -328.128198) (xy 62.785642 -328.077614) (xy 62.8264 -328.031607) (xy 62.872406 -327.990848)
			(xy 62.92299 -327.955932) (xy 62.977414 -327.927369) (xy 63.034884 -327.905574) (xy 63.094562 -327.890865)
			(xy 63.155578 -327.883457) (xy 63.18631 -327.883012) (xy 63.217006 -327.883497) (xy 63.27795 -327.890896)
			(xy 63.337559 -327.905586) (xy 63.394963 -327.927351) (xy 63.449326 -327.955875) (xy 63.474854 -327.972928)
			(xy 63.483606 -327.978399) (xy 63.50381 -327.982527) (xy 63.524014 -327.978399) (xy 63.532766 -327.972928)
			(xy 63.558289 -327.95587) (xy 63.612661 -327.927364) (xy 63.670067 -327.905605) (xy 63.729673 -327.890909)
			(xy 63.790615 -327.88349) (xy 63.82131 -327.883012) (xy 63.852043 -327.883428) (xy 63.913061 -327.890838)
			(xy 63.972741 -327.90555) (xy 64.030212 -327.927347) (xy 64.084637 -327.955913) (xy 64.135222 -327.990832)
			(xy 64.181229 -328.031593) (xy 64.221987 -328.077602) (xy 64.256902 -328.128189) (xy 64.257462 -328.129256)
			(xy 68.577615 -328.129256) (xy 68.577615 -328.074744) (xy 68.585373 -328.020786) (xy 68.600732 -327.968481)
			(xy 68.623377 -327.918895) (xy 68.65285 -327.873036) (xy 68.688549 -327.831839) (xy 68.729748 -327.796141)
			(xy 68.775607 -327.766671) (xy 68.825194 -327.744027) (xy 68.877499 -327.72867) (xy 68.931458 -327.720914)
			(xy 68.958714 -327.720452) (xy 68.987453 -327.72098) (xy 69.044279 -327.729604) (xy 69.099169 -327.746653)
			(xy 69.150881 -327.771744) (xy 69.198244 -327.804307) (xy 69.219572 -327.823576) (xy 69.226684 -327.83018)
			(xy 69.24421 -327.837292) (xy 69.333618 -327.837292) (xy 69.351144 -327.83018) (xy 69.358256 -327.823576)
			(xy 69.379583 -327.804305) (xy 69.426944 -327.771737) (xy 69.478656 -327.746644) (xy 69.533547 -327.729594)
			(xy 69.590375 -327.720972) (xy 69.619114 -327.720452) (xy 69.646362 -327.721019) (xy 69.700302 -327.728776)
			(xy 69.75259 -327.744131) (xy 69.80216 -327.766771) (xy 69.848004 -327.796234) (xy 69.889188 -327.831922)
			(xy 69.924874 -327.873107) (xy 69.954336 -327.918952) (xy 69.976974 -327.968523) (xy 69.992327 -328.020811)
			(xy 70.000082 -328.074752) (xy 70.000082 -328.129248) (xy 70.000081 -328.129257) (xy 71.074415 -328.129257)
			(xy 71.074415 -328.074743) (xy 71.082174 -328.020783) (xy 71.097533 -327.968477) (xy 71.12018 -327.918889)
			(xy 71.149655 -327.87303) (xy 71.185356 -327.831832) (xy 71.226557 -327.796134) (xy 71.272419 -327.766664)
			(xy 71.322009 -327.744021) (xy 71.374316 -327.728666) (xy 71.428277 -327.720913) (xy 71.455534 -327.720452)
			(xy 71.484273 -327.720968) (xy 71.5411 -327.729594) (xy 71.595991 -327.746647) (xy 71.647702 -327.77174)
			(xy 71.695065 -327.804305) (xy 71.716392 -327.823576) (xy 71.723504 -327.83018) (xy 71.74103 -327.837292)
			(xy 71.830438 -327.837292) (xy 71.847964 -327.83018) (xy 71.855076 -327.823576) (xy 71.876395 -327.804295)
			(xy 71.923758 -327.771729) (xy 71.975472 -327.746638) (xy 72.030365 -327.72959) (xy 72.087194 -327.720971)
			(xy 72.115934 -327.720452) (xy 72.143181 -327.72102) (xy 72.197119 -327.72878) (xy 72.249404 -327.744137)
			(xy 72.298972 -327.766777) (xy 72.344813 -327.796241) (xy 72.385995 -327.831929) (xy 72.421679 -327.873114)
			(xy 72.451139 -327.918958) (xy 72.473775 -327.968528) (xy 72.489127 -328.020814) (xy 72.49149 -328.037253)
			(xy 73.771967 -328.037253) (xy 73.771967 -327.982747) (xy 73.779724 -327.928797) (xy 73.795081 -327.8765)
			(xy 73.817723 -327.82692) (xy 73.847192 -327.781068) (xy 73.882886 -327.739876) (xy 73.924079 -327.704183)
			(xy 73.969932 -327.674717) (xy 74.019513 -327.652076) (xy 74.071811 -327.636721) (xy 74.125761 -327.628966)
			(xy 74.153014 -327.628504) (xy 74.181753 -327.629018) (xy 74.238581 -327.637643) (xy 74.293472 -327.654695)
			(xy 74.345184 -327.679789) (xy 74.392546 -327.712356) (xy 74.413872 -327.731628) (xy 74.420984 -327.738232)
			(xy 74.43851 -327.745344) (xy 74.527918 -327.745344) (xy 74.545444 -327.738232) (xy 74.552556 -327.731628)
			(xy 74.573876 -327.712349) (xy 74.62124 -327.679784) (xy 74.672953 -327.654694) (xy 74.727846 -327.637645)
			(xy 74.784675 -327.629024) (xy 74.813414 -327.628504) (xy 74.840665 -327.628967) (xy 74.894613 -327.636725)
			(xy 74.946908 -327.652082) (xy 74.996485 -327.674725) (xy 75.042335 -327.704192) (xy 75.083525 -327.739885)
			(xy 75.119216 -327.781076) (xy 75.148682 -327.826927) (xy 75.171323 -327.876505) (xy 75.186678 -327.9288)
			(xy 75.194434 -327.982749) (xy 75.194434 -328.037251) (xy 75.186678 -328.0912) (xy 75.171323 -328.143495)
			(xy 75.148682 -328.193073) (xy 75.119216 -328.238924) (xy 75.083525 -328.280115) (xy 75.042335 -328.315808)
			(xy 74.996485 -328.345275) (xy 74.946908 -328.367918) (xy 74.894613 -328.383275) (xy 74.840665 -328.391033)
			(xy 74.813414 -328.39152) (xy 74.784676 -328.390982) (xy 74.727849 -328.382362) (xy 74.672959 -328.365315)
			(xy 74.621247 -328.340227) (xy 74.573883 -328.307665) (xy 74.552556 -328.288396) (xy 74.545444 -328.281792)
			(xy 74.527918 -328.27468) (xy 74.43851 -328.27468) (xy 74.420984 -328.281792) (xy 74.413872 -328.288396)
			(xy 74.392529 -328.307649) (xy 74.345173 -328.34022) (xy 74.293465 -328.365317) (xy 74.238577 -328.382371)
			(xy 74.181752 -328.390997) (xy 74.153014 -328.39152) (xy 74.125761 -328.391034) (xy 74.071811 -328.383279)
			(xy 74.019513 -328.367924) (xy 73.969932 -328.345283) (xy 73.924079 -328.315817) (xy 73.882886 -328.280124)
			(xy 73.847192 -328.238932) (xy 73.817723 -328.19308) (xy 73.795081 -328.1435) (xy 73.779724 -328.091203)
			(xy 73.771967 -328.037253) (xy 72.49149 -328.037253) (xy 72.496882 -328.074753) (xy 72.496882 -328.129247)
			(xy 72.489127 -328.183186) (xy 72.473775 -328.235472) (xy 72.451139 -328.285042) (xy 72.421679 -328.330886)
			(xy 72.385995 -328.372071) (xy 72.344813 -328.407759) (xy 72.298972 -328.437223) (xy 72.249404 -328.459863)
			(xy 72.197119 -328.47522) (xy 72.143181 -328.48298) (xy 72.115934 -328.483468) (xy 72.087194 -328.482966)
			(xy 72.030367 -328.474336) (xy 71.975477 -328.457279) (xy 71.923765 -328.432183) (xy 71.876403 -328.399616)
			(xy 71.855076 -328.380344) (xy 71.847964 -328.37374) (xy 71.830438 -328.366628) (xy 71.74103 -328.366628)
			(xy 71.723504 -328.37374) (xy 71.716392 -328.380344) (xy 71.695048 -328.399596) (xy 71.647691 -328.432165)
			(xy 71.595984 -328.457262) (xy 71.541097 -328.474317) (xy 71.484272 -328.482945) (xy 71.455534 -328.483468)
			(xy 71.428277 -328.483087) (xy 71.374316 -328.475334) (xy 71.322009 -328.459979) (xy 71.272419 -328.437336)
			(xy 71.226557 -328.407866) (xy 71.185356 -328.372168) (xy 71.149655 -328.33097) (xy 71.12018 -328.285111)
			(xy 71.097533 -328.235523) (xy 71.082174 -328.183217) (xy 71.074415 -328.129257) (xy 70.000081 -328.129257)
			(xy 69.992327 -328.183189) (xy 69.976974 -328.235477) (xy 69.954336 -328.285048) (xy 69.924874 -328.330893)
			(xy 69.889188 -328.372078) (xy 69.848004 -328.407766) (xy 69.80216 -328.437229) (xy 69.75259 -328.459869)
			(xy 69.700302 -328.475224) (xy 69.646362 -328.482981) (xy 69.619114 -328.483468) (xy 69.590376 -328.482918)
			(xy 69.533551 -328.474299) (xy 69.478661 -328.457254) (xy 69.426949 -328.432169) (xy 69.379585 -328.399611)
			(xy 69.358256 -328.380344) (xy 69.351144 -328.37374) (xy 69.333618 -328.366628) (xy 69.24421 -328.366628)
			(xy 69.226684 -328.37374) (xy 69.219572 -328.380344) (xy 69.198237 -328.399605) (xy 69.150877 -328.432173)
			(xy 69.099168 -328.457268) (xy 69.044279 -328.474321) (xy 68.987452 -328.482946) (xy 68.958714 -328.483468)
			(xy 68.931458 -328.483086) (xy 68.877499 -328.47533) (xy 68.825194 -328.459973) (xy 68.775607 -328.437329)
			(xy 68.729748 -328.407859) (xy 68.688549 -328.372161) (xy 68.65285 -328.330964) (xy 68.623377 -328.285105)
			(xy 68.600732 -328.235519) (xy 68.585373 -328.183214) (xy 68.577615 -328.129256) (xy 64.257462 -328.129256)
			(xy 64.285465 -328.182615) (xy 64.307259 -328.240088) (xy 64.321967 -328.299769) (xy 64.329374 -328.360787)
			(xy 64.329818 -328.39152) (xy 64.329333 -328.422216) (xy 64.321933 -328.48316) (xy 64.307243 -328.542769)
			(xy 64.285478 -328.600173) (xy 64.256954 -328.654536) (xy 64.239902 -328.680064) (xy 64.234413 -328.688807)
			(xy 64.230289 -328.709017) (xy 64.234426 -328.729224) (xy 64.239902 -328.737976) (xy 64.256968 -328.763494)
			(xy 64.285472 -328.817867) (xy 64.307229 -328.875275) (xy 64.321923 -328.934882) (xy 64.329341 -328.995824)
			(xy 64.329818 -329.02652) (xy 64.329333 -329.057216) (xy 64.321933 -329.11816) (xy 64.307243 -329.177769)
			(xy 64.285478 -329.235173) (xy 64.256954 -329.289536) (xy 64.239902 -329.315064) (xy 64.234413 -329.323807)
			(xy 64.230289 -329.344017) (xy 64.234426 -329.364224) (xy 64.239902 -329.372976) (xy 64.256968 -329.398494)
			(xy 64.285472 -329.452867) (xy 64.307229 -329.510275) (xy 64.321923 -329.569882) (xy 64.329341 -329.630824)
			(xy 64.329818 -329.66152) (xy 64.329333 -329.692216) (xy 64.321933 -329.75316) (xy 64.307243 -329.812769)
			(xy 64.285478 -329.870173) (xy 64.256954 -329.924536) (xy 64.239902 -329.950064) (xy 64.234413 -329.958807)
			(xy 64.230289 -329.979017) (xy 64.234426 -329.999224) (xy 64.239902 -330.007976) (xy 64.256968 -330.033494)
			(xy 64.285472 -330.087867) (xy 64.307229 -330.145275) (xy 64.321923 -330.204882) (xy 64.329341 -330.265824)
			(xy 64.329818 -330.29652) (xy 64.329333 -330.327216) (xy 64.321933 -330.38816) (xy 64.307243 -330.447769)
			(xy 64.285478 -330.505173) (xy 64.256954 -330.559536) (xy 64.239902 -330.585064) (xy 64.234413 -330.593807)
			(xy 64.230289 -330.614017) (xy 64.234426 -330.634224) (xy 64.239902 -330.642976) (xy 64.256968 -330.668494)
			(xy 64.285472 -330.722867) (xy 64.307229 -330.780275) (xy 64.321923 -330.839882) (xy 64.329341 -330.900824)
			(xy 64.329818 -330.93152) (xy 64.329333 -330.962216) (xy 64.321933 -331.02316) (xy 64.307243 -331.082769)
			(xy 64.285478 -331.140173) (xy 64.256954 -331.194536) (xy 64.239902 -331.220064) (xy 64.234413 -331.228807)
			(xy 64.230289 -331.249017) (xy 64.234426 -331.269224) (xy 64.239902 -331.277976) (xy 64.256968 -331.303494)
			(xy 64.285472 -331.357867) (xy 64.307229 -331.415275) (xy 64.321923 -331.474882) (xy 64.329341 -331.535824)
			(xy 64.329818 -331.56652) (xy 64.329333 -331.597216) (xy 64.321933 -331.65816) (xy 64.307243 -331.717769)
			(xy 64.285478 -331.775173) (xy 64.256954 -331.829536) (xy 64.239902 -331.855064) (xy 64.234413 -331.863807)
			(xy 64.230289 -331.884017) (xy 64.234426 -331.904224) (xy 64.239902 -331.912976) (xy 64.256968 -331.938494)
			(xy 64.285472 -331.992867) (xy 64.307229 -332.050275) (xy 64.321923 -332.109882) (xy 64.329341 -332.170824)
			(xy 64.329818 -332.20152) (xy 64.329333 -332.232216) (xy 64.321933 -332.29316) (xy 64.307243 -332.352769)
			(xy 64.285478 -332.410173) (xy 64.256954 -332.464536) (xy 64.239902 -332.490064) (xy 64.234413 -332.498807)
			(xy 64.230289 -332.519017) (xy 64.234426 -332.539224) (xy 64.239902 -332.547976) (xy 64.256968 -332.573494)
			(xy 64.285472 -332.627867) (xy 64.307229 -332.685275) (xy 64.321923 -332.744882) (xy 64.329341 -332.805824)
			(xy 64.329818 -332.83652) (xy 64.329333 -332.867216) (xy 64.321933 -332.92816) (xy 64.307243 -332.987769)
			(xy 64.285478 -333.045173) (xy 64.256954 -333.099536) (xy 64.239902 -333.125064) (xy 64.234413 -333.133807)
			(xy 64.230289 -333.154017) (xy 64.234426 -333.174224) (xy 64.239902 -333.182976) (xy 64.256968 -333.208494)
			(xy 64.285472 -333.262867) (xy 64.307229 -333.320275) (xy 64.321923 -333.379882) (xy 64.329341 -333.440824)
			(xy 64.329818 -333.47152) (xy 64.329333 -333.502216) (xy 64.321933 -333.56316) (xy 64.307243 -333.622769)
			(xy 64.285478 -333.680173) (xy 64.256954 -333.734536) (xy 64.239902 -333.760064) (xy 64.234413 -333.768807)
			(xy 64.230289 -333.789017) (xy 64.234426 -333.809224) (xy 64.239902 -333.817976) (xy 64.256968 -333.843494)
			(xy 64.285472 -333.897867) (xy 64.307229 -333.955275) (xy 64.321923 -334.014882) (xy 64.329341 -334.075824)
			(xy 64.329818 -334.10652) (xy 64.329333 -334.137216) (xy 64.321933 -334.19816) (xy 64.307243 -334.257769)
			(xy 64.285478 -334.315173) (xy 64.256954 -334.369536) (xy 64.239902 -334.395064) (xy 64.234413 -334.403807)
			(xy 64.230289 -334.424017) (xy 64.234426 -334.444224) (xy 64.239902 -334.452976) (xy 64.256968 -334.478494)
			(xy 64.285472 -334.532867) (xy 64.307229 -334.590275) (xy 64.321923 -334.649882) (xy 64.329341 -334.710824)
			(xy 64.329818 -334.74152) (xy 64.329363 -334.772251) (xy 64.321952 -334.833265) (xy 64.307242 -334.89294)
			(xy 64.285445 -334.950408) (xy 64.256881 -335.004829) (xy 64.221966 -335.055411) (xy 64.181209 -335.101416)
			(xy 64.135203 -335.142172) (xy 64.084621 -335.177086) (xy 64.030199 -335.205649) (xy 63.972731 -335.227445)
			(xy 63.913055 -335.242154) (xy 63.852041 -335.249563) (xy 63.82131 -335.250028) (xy 63.790613 -335.249576)
			(xy 63.729668 -335.242168) (xy 63.670059 -335.227471) (xy 63.612655 -335.205698) (xy 63.558293 -335.177168)
			(xy 63.532766 -335.160112) (xy 63.524014 -335.154641) (xy 63.50381 -335.150513) (xy 63.483606 -335.154641)
			(xy 63.474854 -335.160112) (xy 63.449321 -335.177155) (xy 63.394952 -335.205665) (xy 63.337549 -335.227427)
			(xy 63.277945 -335.242126) (xy 63.217005 -335.249549) (xy 63.18631 -335.250028) (xy 63.15558 -335.249535)
			(xy 63.094568 -335.242128) (xy 63.034893 -335.227421) (xy 62.977427 -335.205628) (xy 62.923006 -335.177068)
			(xy 62.872424 -335.142156) (xy 62.82642 -335.101401) (xy 62.785663 -335.055399) (xy 62.750748 -335.00482)
			(xy 62.722184 -334.950401) (xy 62.700388 -334.892935) (xy 62.685678 -334.833262) (xy 62.678267 -334.77225)
			(xy 62.677802 -334.74152) (xy 25.18664 -334.74152) (xy 25.18664 -335.96961) (xy 25.187066 -335.979678)
			(xy 25.194788 -335.998276) (xy 25.201626 -336.005678) (xy 26.063194 -336.867246) (xy 26.07059 -336.874099)
			(xy 26.089188 -336.881844) (xy 26.099262 -336.882232) (xy 55.91429 -336.882232) (xy 55.923207 -336.881831)
			(xy 55.939959 -336.875709) (xy 55.947056 -336.870294) (xy 55.975504 -336.846418) (xy 55.98414 -336.832448)
			(xy 55.985918 -336.82432) (xy 55.993153 -336.79571) (xy 56.015223 -336.740979) (xy 56.02986 -336.715354)
			(xy 56.036581 -336.704254) (xy 56.051328 -336.682902) (xy 56.059324 -336.672682) (xy 56.064658 -336.665824)
			(xy 56.070246 -336.649822) (xy 56.070246 -336.619596) (xy 56.070246 -336.619342) (xy 56.070392 -336.613903)
			(xy 56.072707 -336.603275) (xy 56.074818 -336.59826) (xy 56.087772 -336.570828) (xy 56.083454 -336.540602)
			(xy 56.07304 -336.529172) (xy 56.054915 -336.508082) (xy 56.024328 -336.461643) (xy 56.000801 -336.411258)
			(xy 55.98483 -336.357993) (xy 55.976754 -336.302976) (xy 55.976266 -336.275172) (xy 55.976702 -336.249523)
			(xy 55.983611 -336.198693) (xy 55.997259 -336.149244) (xy 56.017401 -336.102066) (xy 56.043675 -336.058008)
			(xy 56.059324 -336.037682) (xy 56.064658 -336.030824) (xy 56.070246 -336.014822) (xy 56.070246 -335.984596)
			(xy 56.070246 -335.984342) (xy 56.070392 -335.978903) (xy 56.072707 -335.968275) (xy 56.074818 -335.96326)
			(xy 56.087772 -335.935828) (xy 56.083454 -335.905602) (xy 56.07304 -335.894172) (xy 56.054915 -335.873082)
			(xy 56.024328 -335.826643) (xy 56.000801 -335.776258) (xy 55.98483 -335.722993) (xy 55.976754 -335.667976)
			(xy 55.976266 -335.640172) (xy 55.976754 -335.612921) (xy 55.984513 -335.558975) (xy 55.999871 -335.506682)
			(xy 56.022513 -335.457107) (xy 56.05198 -335.411258) (xy 56.087671 -335.370069) (xy 56.12886 -335.334378)
			(xy 56.174709 -335.304912) (xy 56.224284 -335.28227) (xy 56.276577 -335.266913) (xy 56.330523 -335.259154)
			(xy 56.357774 -335.258664) (xy 56.386513 -335.259183) (xy 56.443342 -335.267804) (xy 56.498234 -335.284853)
			(xy 56.549946 -335.309946) (xy 56.597308 -335.342513) (xy 56.618632 -335.361788) (xy 56.625744 -335.368646)
			(xy 56.643524 -335.375504) (xy 56.732424 -335.375504) (xy 56.750204 -335.368646) (xy 56.757316 -335.361788)
			(xy 56.778643 -335.342517) (xy 56.826006 -335.309952) (xy 56.877717 -335.284859) (xy 56.932608 -335.267807)
			(xy 56.989435 -335.259182) (xy 57.018174 -335.258664) (xy 57.045427 -335.259148) (xy 57.099379 -335.266901)
			(xy 57.151679 -335.282254) (xy 57.201261 -335.304893) (xy 57.247117 -335.334358) (xy 57.288312 -335.370049)
			(xy 57.324009 -335.41124) (xy 57.353481 -335.457092) (xy 57.376127 -335.506671) (xy 57.391487 -335.558968)
			(xy 57.399248 -335.612919) (xy 57.399682 -335.640172) (xy 57.399243 -335.66582) (xy 57.39233 -335.716648)
			(xy 57.378679 -335.766095) (xy 57.358534 -335.81327) (xy 57.332259 -335.857326) (xy 57.316624 -335.877662)
			(xy 57.31129 -335.88452) (xy 57.305702 -335.900522) (xy 57.305702 -335.930748) (xy 57.305702 -335.931002)
			(xy 57.305562 -335.936442) (xy 57.303261 -335.947077) (xy 57.30113 -335.952084) (xy 57.288176 -335.979516)
			(xy 57.292494 -336.009742) (xy 57.302908 -336.021172) (xy 57.321029 -336.042264) (xy 57.351606 -336.088705)
			(xy 57.375125 -336.139091) (xy 57.391087 -336.192354) (xy 57.399156 -336.24737) (xy 57.399615 -336.271616)
			(xy 58.081926 -336.271616) (xy 58.082395 -336.244246) (xy 58.090211 -336.190067) (xy 58.105699 -336.137563)
			(xy 58.12854 -336.087816) (xy 58.158265 -336.04185) (xy 58.175906 -336.020918) (xy 58.182002 -336.013806)
			(xy 58.188352 -335.996788) (xy 58.188352 -335.911444) (xy 58.182002 -335.894426) (xy 58.175906 -335.887314)
			(xy 58.158261 -335.866387) (xy 58.12855 -335.820413) (xy 58.105715 -335.770664) (xy 58.090225 -335.718162)
			(xy 58.082399 -335.663986) (xy 58.081926 -335.636616) (xy 58.08237 -335.609362) (xy 58.090126 -335.555409)
			(xy 58.105482 -335.503108) (xy 58.128125 -335.453526) (xy 58.157594 -335.407671) (xy 58.19329 -335.366477)
			(xy 58.234486 -335.330784) (xy 58.280342 -335.301316) (xy 58.329925 -335.278675) (xy 58.382226 -335.263322)
			(xy 58.43618 -335.255569) (xy 58.463434 -335.255108) (xy 58.489629 -335.255538) (xy 58.541526 -335.262706)
			(xy 58.591956 -335.276902) (xy 58.639971 -335.297861) (xy 58.68467 -335.325188) (xy 58.725212 -335.358369)
			(xy 58.743342 -335.377282) (xy 58.750843 -335.384574) (xy 58.769981 -335.39297) (xy 58.780426 -335.393538)
			(xy 58.855102 -335.393538) (xy 58.86556 -335.393015) (xy 58.884716 -335.384619) (xy 58.892186 -335.377282)
			(xy 58.910325 -335.358378) (xy 58.950863 -335.325193) (xy 58.995559 -335.297863) (xy 59.043573 -335.276903)
			(xy 59.094002 -335.262707) (xy 59.145899 -335.255541) (xy 59.172094 -335.255108) (xy 59.199347 -335.255561)
			(xy 59.2533 -335.263318) (xy 59.305599 -335.278674) (xy 59.35518 -335.301317) (xy 59.401034 -335.330785)
			(xy 59.442227 -335.36648) (xy 59.477921 -335.407674) (xy 59.507388 -335.453529) (xy 59.53003 -335.503111)
			(xy 59.545385 -335.55541) (xy 59.55314 -335.609363) (xy 59.553602 -335.636616) (xy 59.553145 -335.663987)
			(xy 59.545325 -335.718166) (xy 59.529834 -335.770669) (xy 59.50699 -335.820416) (xy 59.477264 -335.866382)
			(xy 59.459622 -335.887314) (xy 59.453526 -335.894426) (xy 59.447176 -335.911444) (xy 59.447176 -335.996788)
			(xy 59.453526 -336.013806) (xy 59.459622 -336.020918) (xy 59.47724 -336.041867) (xy 59.506954 -336.087836)
			(xy 59.529794 -336.137579) (xy 59.54529 -336.190076) (xy 59.553124 -336.244248) (xy 59.553602 -336.271616)
			(xy 59.553137 -336.298868) (xy 59.545378 -336.352817) (xy 59.530021 -336.405112) (xy 59.507377 -336.45469)
			(xy 59.477909 -336.500541) (xy 59.442215 -336.541731) (xy 59.401023 -336.577422) (xy 59.355171 -336.606888)
			(xy 59.305592 -336.629528) (xy 59.253295 -336.644883) (xy 59.199346 -336.652639) (xy 59.172094 -336.653124)
			(xy 59.1459 -336.652665) (xy 59.094004 -336.645502) (xy 59.043575 -336.63131) (xy 58.99556 -336.610357)
			(xy 58.950861 -336.583036) (xy 58.910317 -336.54986) (xy 58.892186 -336.53095) (xy 58.884707 -336.523631)
			(xy 58.865553 -336.51525) (xy 58.855102 -336.514694) (xy 58.780426 -336.514694) (xy 58.769973 -336.515252)
			(xy 58.750818 -336.523626) (xy 58.743342 -336.53095) (xy 58.725196 -336.549846) (xy 58.684658 -336.583031)
			(xy 58.639964 -336.610361) (xy 58.591951 -336.631322) (xy 58.541524 -336.64552) (xy 58.489628 -336.652689)
			(xy 58.463434 -336.653124) (xy 58.436183 -336.652613) (xy 58.382234 -336.644861) (xy 58.329938 -336.62951)
			(xy 58.280359 -336.606873) (xy 58.234507 -336.57741) (xy 58.193314 -336.541721) (xy 58.15762 -336.500533)
			(xy 58.128151 -336.454685) (xy 58.105507 -336.405109) (xy 58.090149 -336.352815) (xy 58.08239 -336.298867)
			(xy 58.081926 -336.271616) (xy 57.399615 -336.271616) (xy 57.399682 -336.275172) (xy 57.399243 -336.30082)
			(xy 57.39233 -336.351648) (xy 57.378679 -336.401095) (xy 57.358534 -336.44827) (xy 57.332259 -336.492326)
			(xy 57.316624 -336.512662) (xy 57.31129 -336.51952) (xy 57.305702 -336.535522) (xy 57.305702 -336.565748)
			(xy 57.305702 -336.566002) (xy 57.305562 -336.571442) (xy 57.303261 -336.582077) (xy 57.30113 -336.587084)
			(xy 57.288176 -336.614516) (xy 57.292494 -336.644742) (xy 57.302908 -336.656172) (xy 57.319887 -336.675871)
			(xy 57.348909 -336.719025) (xy 57.3718 -336.765721) (xy 57.388135 -336.815094) (xy 57.393332 -336.840576)
			(xy 57.394856 -336.849466) (xy 57.404 -336.864706) (xy 57.410858 -336.870548) (xy 57.41787 -336.875954)
			(xy 57.434521 -336.881937) (xy 57.44337 -336.882232) (xy 61.934598 -336.882232) (xy 61.944668 -336.882655)
			(xy 61.96327 -336.890373) (xy 61.970666 -336.897218) (xy 61.971682 -336.898234) (xy 61.979082 -336.905075)
			(xy 61.997681 -336.91279) (xy 62.00775 -336.91322)
		)
		(stroke
			(width 0)
			(type solid)
		)
		(fill yes)
		(layer "In11.Cu")
		(net "PVDDIO_P1")
	)
	(gr_poly
		(pts
			(xy 105.035604 -424.727878) (xy 105.039414 -424.710098) (xy 105.046379 -424.679357) (xy 105.066906 -424.619759)
			(xy 105.094641 -424.563155) (xy 105.129159 -424.510414) (xy 105.169931 -424.462342) (xy 105.216331 -424.419678)
			(xy 105.267649 -424.383077) (xy 105.323097 -424.353098) (xy 105.381825 -424.330203) (xy 105.442933 -424.314741)
			(xy 105.505483 -424.306951) (xy 105.568517 -424.306951) (xy 105.631067 -424.314741) (xy 105.692175 -424.330203)
			(xy 105.750903 -424.353098) (xy 105.806351 -424.383077) (xy 105.857669 -424.419678) (xy 105.904069 -424.462342)
			(xy 105.944841 -424.510414) (xy 105.979359 -424.563155) (xy 106.007094 -424.619759) (xy 106.027621 -424.679357)
			(xy 106.034586 -424.710098) (xy 106.038396 -424.727878) (xy 106.066082 -424.750484) (xy 107.15244 -424.750484)
			(xy 107.162507 -424.750053) (xy 107.181099 -424.742327) (xy 107.188508 -424.735498) (xy 112.768888 -419.155118)
			(xy 112.776508 -419.135306) (xy 112.776 -419.124384) (xy 112.775492 -419.1) (xy 112.775936 -419.069612)
			(xy 112.783181 -419.009271) (xy 112.797569 -418.950223) (xy 112.818893 -418.893312) (xy 112.84685 -418.839349)
			(xy 112.881041 -418.789104) (xy 112.920979 -418.743294) (xy 112.966093 -418.702571) (xy 113.01574 -418.667517)
			(xy 113.069212 -418.638632) (xy 113.09731 -418.627052) (xy 113.112042 -418.62121) (xy 113.129568 -418.595556)
			(xy 113.129568 -416.064446) (xy 113.109248 -416.037522) (xy 113.092738 -416.032696) (xy 113.061322 -416.023133)
			(xy 113.001065 -415.997022) (xy 112.944671 -415.963372) (xy 112.893077 -415.922743) (xy 112.847142 -415.875811)
			(xy 112.80763 -415.823357) (xy 112.775198 -415.766253) (xy 112.750387 -415.705449) (xy 112.733609 -415.641958)
			(xy 112.725143 -415.576835) (xy 112.724692 -415.544) (xy 112.725281 -415.508941) (xy 112.734918 -415.439489)
			(xy 112.75401 -415.37202) (xy 112.782195 -415.307816) (xy 112.818937 -415.248095) (xy 112.84077 -415.220658)
			(xy 112.847744 -415.211224) (xy 112.853059 -415.1884) (xy 112.847744 -415.165576) (xy 112.84077 -415.156142)
			(xy 112.818932 -415.12871) (xy 112.782206 -415.068982) (xy 112.75403 -415.004775) (xy 112.73494 -414.937308)
			(xy 112.725297 -414.867858) (xy 112.724692 -414.8328) (xy 112.725207 -414.799967) (xy 112.733661 -414.734848)
			(xy 112.75043 -414.671359) (xy 112.775233 -414.610558) (xy 112.807658 -414.553456) (xy 112.847165 -414.501005)
			(xy 112.893097 -414.454076) (xy 112.944688 -414.413452) (xy 113.001081 -414.379809) (xy 113.061336 -414.353706)
			(xy 113.092738 -414.344104) (xy 113.109248 -414.339278) (xy 113.129568 -414.312354) (xy 113.129568 -413.390334)
			(xy 113.12909 -413.380996) (xy 113.122302 -413.363592) (xy 113.109753 -413.349752) (xy 113.101628 -413.345122)
			(xy 113.073967 -413.330668) (xy 113.022071 -413.295994) (xy 112.974811 -413.255228) (xy 112.932896 -413.208983)
			(xy 112.896958 -413.157955) (xy 112.867537 -413.102911) (xy 112.845076 -413.04468) (xy 112.829911 -412.984137)
			(xy 112.822273 -412.922193) (xy 112.822274 -412.85978) (xy 112.829916 -412.797836) (xy 112.845084 -412.737294)
			(xy 112.867548 -412.679064) (xy 112.896973 -412.624022) (xy 112.932913 -412.572996) (xy 112.97483 -412.526753)
			(xy 113.022093 -412.48599) (xy 113.07399 -412.451319) (xy 113.101628 -412.436818) (xy 113.109802 -412.43225)
			(xy 113.122388 -412.418408) (xy 113.129136 -412.40096) (xy 113.129568 -412.391606) (xy 113.129568 -407.897076)
			(xy 113.129171 -407.888423) (xy 113.123317 -407.872133) (xy 113.112384 -407.858713) (xy 113.105184 -407.853896)
			(xy 113.01984 -407.801572) (xy 112.993932 -407.800556) (xy 112.98174 -407.806652) (xy 112.954755 -407.819739)
			(xy 112.897723 -407.838279) (xy 112.838496 -407.847689) (xy 112.808512 -407.848308) (xy 112.781259 -407.847845)
			(xy 112.727306 -407.84009) (xy 112.675007 -407.824735) (xy 112.625425 -407.802093) (xy 112.579571 -407.772625)
			(xy 112.538377 -407.736932) (xy 112.502682 -407.695739) (xy 112.473213 -407.649885) (xy 112.450569 -407.600304)
			(xy 112.435213 -407.548005) (xy 112.427455 -407.494053) (xy 112.427455 -407.439547) (xy 112.435213 -407.385595)
			(xy 112.450569 -407.333296) (xy 112.473213 -407.283715) (xy 112.502682 -407.237861) (xy 112.538377 -407.196668)
			(xy 112.579571 -407.160975) (xy 112.625425 -407.131507) (xy 112.675007 -407.108865) (xy 112.727306 -407.09351)
			(xy 112.781259 -407.085755) (xy 112.808512 -407.085292) (xy 112.838502 -407.085848) (xy 112.89774 -407.095244)
			(xy 112.954771 -407.113817) (xy 112.98174 -407.126948) (xy 112.993932 -407.133044) (xy 113.01984 -407.132028)
			(xy 113.105184 -407.079704) (xy 113.112406 -407.074912) (xy 113.123355 -407.061492) (xy 113.129186 -407.045183)
			(xy 113.129568 -407.036524) (xy 113.129568 -406.881076) (xy 113.129171 -406.872423) (xy 113.123317 -406.856133)
			(xy 113.112384 -406.842713) (xy 113.105184 -406.837896) (xy 113.01984 -406.785572) (xy 112.993932 -406.784556)
			(xy 112.98174 -406.790652) (xy 112.954755 -406.803739) (xy 112.897723 -406.822279) (xy 112.838496 -406.831689)
			(xy 112.808512 -406.832308) (xy 112.781259 -406.831845) (xy 112.727306 -406.82409) (xy 112.675007 -406.808735)
			(xy 112.625425 -406.786093) (xy 112.579571 -406.756625) (xy 112.538377 -406.720932) (xy 112.502682 -406.679739)
			(xy 112.473213 -406.633885) (xy 112.450569 -406.584304) (xy 112.435213 -406.532005) (xy 112.427455 -406.478053)
			(xy 112.427455 -406.423547) (xy 112.435213 -406.369595) (xy 112.450569 -406.317296) (xy 112.473213 -406.267715)
			(xy 112.502682 -406.221861) (xy 112.538377 -406.180668) (xy 112.579571 -406.144975) (xy 112.625425 -406.115507)
			(xy 112.675007 -406.092865) (xy 112.727306 -406.07751) (xy 112.781259 -406.069755) (xy 112.808512 -406.069292)
			(xy 112.838502 -406.069848) (xy 112.89774 -406.079244) (xy 112.954771 -406.097817) (xy 112.98174 -406.110948)
			(xy 112.993932 -406.117044) (xy 113.01984 -406.116028) (xy 113.105184 -406.063704) (xy 113.112406 -406.058912)
			(xy 113.123355 -406.045492) (xy 113.129186 -406.029183) (xy 113.129568 -406.020524) (xy 113.129568 -405.34082)
			(xy 113.129155 -405.331493) (xy 113.12248 -405.314074) (xy 113.110009 -405.300202) (xy 113.101882 -405.295608)
			(xy 113.008664 -405.247856) (xy 112.98047 -405.249888) (xy 112.968786 -405.258524) (xy 112.939806 -405.278611)
			(xy 112.877405 -405.311445) (xy 112.81106 -405.335323) (xy 112.742047 -405.349785) (xy 112.706912 -405.352758)
			(xy 112.697782 -405.353782) (xy 112.681116 -405.361475) (xy 112.6744 -405.367744) (xy 112.653064 -405.389334)
			(xy 112.638332 -405.421846) (xy 112.635777 -405.453676) (xy 112.623718 -405.516383) (xy 112.603903 -405.577087)
			(xy 112.576643 -405.634832) (xy 112.542367 -405.68871) (xy 112.501615 -405.737871) (xy 112.455028 -405.781544)
			(xy 112.403339 -405.819039) (xy 112.347362 -405.849768) (xy 112.287979 -405.873246) (xy 112.226123 -405.889103)
			(xy 112.162768 -405.897091) (xy 112.13084 -405.897588) (xy 112.100107 -405.897145) (xy 112.039088 -405.88974)
			(xy 111.979407 -405.875034) (xy 111.921934 -405.85324) (xy 111.867507 -405.824678) (xy 111.816919 -405.789763)
			(xy 111.77091 -405.749004) (xy 111.73015 -405.702996) (xy 111.695233 -405.652411) (xy 111.666668 -405.597985)
			(xy 111.644872 -405.540512) (xy 111.630164 -405.480832) (xy 111.622757 -405.419813) (xy 111.622332 -405.38908)
			(xy 111.622821 -405.357249) (xy 111.63076 -405.294085) (xy 111.646523 -405.232405) (xy 111.669864 -405.173177)
			(xy 111.700418 -405.117327) (xy 111.737706 -405.065728) (xy 111.781144 -405.019189) (xy 111.830054 -404.978438)
			(xy 111.883668 -404.944113) (xy 111.94115 -404.91675) (xy 112.001597 -404.896779) (xy 112.064066 -404.884511)
			(xy 112.095788 -404.881842) (xy 112.104918 -404.880818) (xy 112.121584 -404.873125) (xy 112.1283 -404.866856)
			(xy 112.149636 -404.845266) (xy 112.164368 -404.812754) (xy 112.166923 -404.780924) (xy 112.178982 -404.718217)
			(xy 112.198797 -404.657513) (xy 112.226057 -404.599768) (xy 112.260333 -404.54589) (xy 112.301085 -404.496729)
			(xy 112.347672 -404.453056) (xy 112.399361 -404.415561) (xy 112.455338 -404.384832) (xy 112.514721 -404.361354)
			(xy 112.576577 -404.345497) (xy 112.639932 -404.337509) (xy 112.67186 -404.337012) (xy 112.672368 -404.337012)
			(xy 112.704029 -404.337511) (xy 112.766858 -404.345405) (xy 112.828221 -404.361038) (xy 112.887169 -404.384168)
			(xy 112.942789 -404.414437) (xy 112.968786 -404.432516) (xy 112.98047 -404.441152) (xy 113.008664 -404.443184)
			(xy 113.101882 -404.395432) (xy 113.109987 -404.390813) (xy 113.122438 -404.376944) (xy 113.129109 -404.359539)
			(xy 113.129568 -404.35022) (xy 113.129568 -402.497036) (xy 113.130071 -402.486984) (xy 113.137787 -402.468419)
			(xy 113.144554 -402.460968) (xy 113.482628 -402.122894) (xy 113.490028 -402.116053) (xy 113.508626 -402.108329)
			(xy 113.518696 -402.107908) (xy 117.719348 -402.107908) (xy 117.729415 -402.107477) (xy 117.748007 -402.099751)
			(xy 117.755416 -402.092922) (xy 117.955314 -401.893024) (xy 117.962158 -401.885626) (xy 117.969878 -401.867026)
			(xy 117.9703 -401.856956) (xy 117.9703 -392.596116) (xy 117.970739 -392.586053) (xy 117.978474 -392.56747)
			(xy 117.985286 -392.560048) (xy 118.128288 -392.417046) (xy 118.135654 -392.401552) (xy 118.13667 -392.392408)
			(xy 118.139829 -392.364653) (xy 118.153232 -392.310424) (xy 118.174403 -392.258731) (xy 118.202891 -392.21068)
			(xy 118.238084 -392.167301) (xy 118.258336 -392.14806) (xy 118.265448 -392.14171) (xy 118.273576 -392.124946)
			(xy 118.281958 -392.038332) (xy 118.276878 -392.020552) (xy 118.27129 -392.012678) (xy 118.257131 -391.992834)
			(xy 118.234642 -391.949586) (xy 118.219322 -391.903311) (xy 118.211562 -391.855187) (xy 118.211092 -391.830814)
			(xy 118.211537 -391.80682) (xy 118.219042 -391.759423) (xy 118.233869 -391.713783) (xy 118.255654 -391.671025)
			(xy 118.283859 -391.632202) (xy 118.317791 -391.598269) (xy 118.356613 -391.570061) (xy 118.39937 -391.548275)
			(xy 118.445009 -391.533445) (xy 118.492406 -391.525938) (xy 118.5164 -391.525506) (xy 118.516654 -391.525506)
			(xy 118.543529 -391.526069) (xy 118.59645 -391.535478) (xy 118.646903 -391.554013) (xy 118.693329 -391.581101)
			(xy 118.734291 -391.615903) (xy 118.751858 -391.63625) (xy 118.758716 -391.644632) (xy 118.777766 -391.654284)
			(xy 118.863618 -391.658348) (xy 118.87427 -391.658278) (xy 118.894084 -391.650523) (xy 118.901972 -391.643362)
			(xy 119.151146 -391.394188) (xy 119.158543 -391.387339) (xy 119.177142 -391.379607) (xy 119.187214 -391.379202)
			(xy 135.200898 -391.379202) (xy 135.210968 -391.378779) (xy 135.229573 -391.371066) (xy 135.236966 -391.364216)
			(xy 135.292084 -391.309098) (xy 135.29877 -391.301689) (xy 135.306354 -391.283253) (xy 135.306816 -391.273284)
			(xy 135.306816 -390.976104) (xy 135.306297 -390.966205) (xy 135.29872 -390.947908) (xy 135.292084 -390.940544)
			(xy 135.269732 -390.917938) (xy 135.260418 -390.909524) (xy 135.23644 -390.902206) (xy 135.224012 -390.903968)
			(xy 135.129016 -390.922256) (xy 135.109458 -390.938004) (xy 135.104378 -390.949688) (xy 135.092999 -390.974761)
			(xy 135.063172 -391.021041) (xy 135.026095 -391.061743) (xy 134.98279 -391.095745) (xy 134.934453 -391.122107)
			(xy 134.882419 -391.140102) (xy 134.828123 -391.149233) (xy 134.800594 -391.14984) (xy 134.774606 -391.14933)
			(xy 134.723271 -391.141199) (xy 134.673839 -391.125138) (xy 134.627528 -391.101542) (xy 134.585478 -391.070993)
			(xy 134.548724 -391.034242) (xy 134.518171 -390.992194) (xy 134.494572 -390.945885) (xy 134.478507 -390.896455)
			(xy 134.470372 -390.84512) (xy 134.469886 -390.819132) (xy 134.470364 -390.793634) (xy 134.478207 -390.743244)
			(xy 134.493697 -390.694658) (xy 134.516466 -390.649027) (xy 134.545974 -390.607434) (xy 134.58152 -390.570868)
			(xy 134.62226 -390.540195) (xy 134.667229 -390.516144) (xy 134.69112 -390.50722) (xy 134.699756 -390.504172)
			(xy 134.713472 -390.492488) (xy 134.75589 -390.419082) (xy 134.758938 -390.401302) (xy 134.75716 -390.392158)
			(xy 134.753363 -390.370962) (xy 134.749289 -390.328092) (xy 134.749032 -390.30656) (xy 134.749503 -390.27744)
			(xy 134.756922 -390.219673) (xy 134.77161 -390.163314) (xy 134.782052 -390.136126) (xy 134.785218 -390.12708)
			(xy 134.785296 -390.107929) (xy 134.778365 -390.090077) (xy 134.772146 -390.082786) (xy 134.753282 -390.06162)
			(xy 134.720378 -390.015448) (xy 134.693428 -389.965566) (xy 134.672844 -389.912737) (xy 134.658941 -389.857771)
			(xy 134.651932 -389.801509) (xy 134.651496 -389.77316) (xy 134.651908 -389.745641) (xy 134.658518 -389.691001)
			(xy 134.671636 -389.63755) (xy 134.691074 -389.586058) (xy 134.71655 -389.537272) (xy 134.73176 -389.514334)
			(xy 134.737094 -389.50646) (xy 134.741412 -389.488426) (xy 134.729982 -389.402066) (xy 134.721092 -389.38581)
			(xy 134.713726 -389.37946) (xy 134.692448 -389.360788) (xy 134.654198 -389.319053) (xy 134.621384 -389.272922)
			(xy 134.594506 -389.223098) (xy 134.573975 -389.170341) (xy 134.560105 -389.115455) (xy 134.553105 -389.059278)
			(xy 134.55269 -389.030972) (xy 134.553116 -389.002648) (xy 134.560112 -388.946432) (xy 134.573993 -388.89151)
			(xy 134.594547 -388.838722) (xy 134.62146 -388.788874) (xy 134.637526 -388.765542) (xy 134.64286 -388.757922)
			(xy 134.647686 -388.739888) (xy 134.63778 -388.653782) (xy 134.629398 -388.637272) (xy 134.622286 -388.630922)
			(xy 134.598649 -388.609116) (xy 134.557112 -388.560019) (xy 134.522854 -388.505594) (xy 134.496549 -388.44691)
			(xy 134.478715 -388.385122) (xy 134.469703 -388.321447) (xy 134.469124 -388.289292) (xy 134.469594 -388.259324)
			(xy 134.477418 -388.199901) (xy 134.492932 -388.142008) (xy 134.51587 -388.086635) (xy 134.54584 -388.03473)
			(xy 134.582329 -387.987181) (xy 134.624711 -387.944802) (xy 134.672264 -387.908318) (xy 134.724171 -387.878353)
			(xy 134.779546 -387.855419) (xy 134.83744 -387.83991) (xy 134.896864 -387.832091) (xy 134.926832 -387.831584)
			(xy 134.95638 -387.832049) (xy 134.98018 -387.83514) (xy 139.455142 -387.83514) (xy 139.459213 -387.779518)
			(xy 139.471339 -387.725081) (xy 139.491262 -387.67299) (xy 139.518558 -387.624355) (xy 139.552644 -387.580212)
			(xy 139.592793 -387.541503) (xy 139.638151 -387.509052) (xy 139.687751 -387.483551) (xy 139.740535 -387.465544)
			(xy 139.795378 -387.455414) (xy 139.851112 -387.453377) (xy 139.906549 -387.459477) (xy 139.960506 -387.473583)
			(xy 140.011835 -387.495395) (xy 140.059441 -387.524449) (xy 140.102309 -387.560124) (xy 140.139526 -387.601661)
			(xy 140.170299 -387.648174) (xy 140.193971 -387.698671) (xy 140.210039 -387.752078) (xy 140.218159 -387.807254)
			(xy 140.218668 -387.83514) (xy 140.218159 -387.863026) (xy 140.210039 -387.918202) (xy 140.193971 -387.971609)
			(xy 140.170299 -388.022106) (xy 140.139526 -388.068619) (xy 140.102309 -388.110156) (xy 140.059441 -388.145831)
			(xy 140.011835 -388.174885) (xy 139.960506 -388.196697) (xy 139.906549 -388.210803) (xy 139.851112 -388.216903)
			(xy 139.795378 -388.214866) (xy 139.740535 -388.204736) (xy 139.687751 -388.186729) (xy 139.638151 -388.161228)
			(xy 139.592793 -388.128777) (xy 139.552644 -388.090068) (xy 139.518558 -388.045925) (xy 139.491262 -387.99729)
			(xy 139.471339 -387.945199) (xy 139.459213 -387.890762) (xy 139.455142 -387.83514) (xy 134.98018 -387.83514)
			(xy 135.014983 -387.83966) (xy 135.072118 -387.854752) (xy 135.126836 -387.877074) (xy 135.178224 -387.906254)
			(xy 135.225429 -387.941806) (xy 135.246872 -387.96214) (xy 135.282178 -387.976364) (xy 137.486644 -387.976364)
			(xy 137.511234 -387.976825) (xy 137.559807 -387.984527) (xy 137.606577 -387.999734) (xy 137.650391 -388.022072)
			(xy 137.690171 -388.05099) (xy 137.707878 -388.068058) (xy 138.621516 -388.981696) (xy 138.628873 -388.988343)
			(xy 138.647174 -388.995918) (xy 138.657076 -388.996428) (xy 138.755374 -388.996428) (xy 138.767042 -388.99586)
			(xy 138.787966 -388.985537) (xy 138.795506 -388.976616) (xy 138.851894 -388.903464) (xy 138.856466 -388.880604)
			(xy 138.853418 -388.86892) (xy 138.847486 -388.844973) (xy 138.841111 -388.796051) (xy 138.840718 -388.771384)
			(xy 138.840718 -388.77113) (xy 138.841179 -388.743876) (xy 138.848933 -388.689924) (xy 138.864287 -388.637624)
			(xy 138.886928 -388.588041) (xy 138.916395 -388.542186) (xy 138.952089 -388.500992) (xy 138.993283 -388.465298)
			(xy 139.039138 -388.43583) (xy 139.08872 -388.413188) (xy 139.14102 -388.397834) (xy 139.194972 -388.39008)
			(xy 139.222226 -388.389622) (xy 139.249595 -388.390096) (xy 139.303771 -388.397923) (xy 139.356272 -388.413414)
			(xy 139.40602 -388.436249) (xy 139.451993 -388.465961) (xy 139.472924 -388.483602) (xy 139.480036 -388.489698)
			(xy 139.497054 -388.496048) (xy 139.582398 -388.496048) (xy 139.599416 -388.489698) (xy 139.606528 -388.483602)
			(xy 139.62746 -388.465962) (xy 139.673427 -388.436239) (xy 139.723174 -388.413399) (xy 139.775677 -388.397913)
			(xy 139.829856 -388.390098) (xy 139.857226 -388.389622) (xy 139.884477 -388.390087) (xy 139.938423 -388.397847)
			(xy 139.990716 -388.413206) (xy 140.040291 -388.43585) (xy 140.086139 -388.465319) (xy 140.127326 -388.501014)
			(xy 140.163014 -388.542206) (xy 140.192477 -388.588058) (xy 140.215114 -388.637636) (xy 140.230465 -388.689931)
			(xy 140.238217 -388.743879) (xy 140.238734 -388.77113) (xy 140.238734 -388.771384) (xy 140.238349 -388.796052)
			(xy 140.231983 -388.844977) (xy 140.226034 -388.86892) (xy 140.222986 -388.880604) (xy 140.227558 -388.903464)
			(xy 140.283946 -388.976616) (xy 140.291532 -388.985478) (xy 140.31243 -388.99579) (xy 140.324078 -388.996428)
			(xy 140.385038 -388.996428) (xy 140.418566 -388.99846) (xy 140.427964 -388.999476) (xy 140.44549 -388.994904)
			(xy 140.51534 -388.94639) (xy 140.525754 -388.931658) (xy 140.52804 -388.922514) (xy 140.535464 -388.895521)
			(xy 140.557134 -388.843904) (xy 140.586115 -388.796008) (xy 140.621785 -388.752862) (xy 140.663377 -388.715392)
			(xy 140.709998 -388.684403) (xy 140.760648 -388.660559) (xy 140.814239 -388.644374) (xy 140.869619 -388.636194)
			(xy 140.89761 -388.635748) (xy 140.9065 -388.635748) (xy 140.91793 -388.636002) (xy 140.93825 -388.627366)
			(xy 141.004798 -388.552182) (xy 141.011148 -388.530846) (xy 141.009624 -388.51967) (xy 141.007736 -388.506032)
			(xy 141.005703 -388.478573) (xy 141.00556 -388.464806) (xy 141.005696 -388.451938) (xy 141.007477 -388.426262)
			(xy 141.009116 -388.413498) (xy 141.01064 -388.402576) (xy 141.00429 -388.381748) (xy 140.93952 -388.307326)
			(xy 140.919708 -388.298182) (xy 140.908786 -388.298182) (xy 140.87557 -388.297524) (xy 140.809732 -388.288637)
			(xy 140.745612 -388.271251) (xy 140.684302 -388.245662) (xy 140.626847 -388.212307) (xy 140.574225 -388.171752)
			(xy 140.527333 -388.12469) (xy 140.486969 -388.071922) (xy 140.453822 -388.014347) (xy 140.428455 -387.952945)
			(xy 140.411301 -387.888762) (xy 140.402653 -387.822892) (xy 140.402056 -387.789674) (xy 140.402637 -387.754719)
			(xy 140.412209 -387.685468) (xy 140.431169 -387.618179) (xy 140.459161 -387.554119) (xy 140.495658 -387.494492)
			(xy 140.517372 -387.467094) (xy 140.52271 -387.460115) (xy 140.5287 -387.443614) (xy 140.529056 -387.434836)
			(xy 140.529056 -387.280912) (xy 140.528638 -387.272146) (xy 140.522656 -387.255661) (xy 140.517372 -387.248654)
			(xy 140.49566 -387.221255) (xy 140.459161 -387.161631) (xy 140.431171 -387.097571) (xy 140.412219 -387.03028)
			(xy 140.402662 -386.961028) (xy 140.402056 -386.926074) (xy 140.402521 -386.895343) (xy 140.409932 -386.83433)
			(xy 140.424643 -386.774655) (xy 140.446439 -386.717188) (xy 140.475002 -386.662767) (xy 140.509916 -386.612185)
			(xy 140.550673 -386.56618) (xy 140.596677 -386.525423) (xy 140.647258 -386.490507) (xy 140.701679 -386.461943)
			(xy 140.759145 -386.440146) (xy 140.81882 -386.425434) (xy 140.879833 -386.418022) (xy 140.910564 -386.417566)
			(xy 140.910818 -386.417566) (xy 140.931679 -386.417787) (xy 140.973261 -386.421219) (xy 140.993876 -386.424424)
			(xy 141.00302 -386.425948) (xy 141.0208 -386.422646) (xy 141.092936 -386.378958) (xy 141.104112 -386.364988)
			(xy 141.10716 -386.356352) (xy 141.115928 -386.331332) (xy 141.13941 -386.283802) (xy 141.169252 -386.239984)
			(xy 141.204879 -386.200724) (xy 141.245603 -386.16678) (xy 141.290637 -386.138808) (xy 141.339114 -386.117346)
			(xy 141.390097 -386.102809) (xy 141.442602 -386.095477) (xy 141.46911 -386.094986) (xy 141.496361 -386.095472)
			(xy 141.550308 -386.10323) (xy 141.602602 -386.118586) (xy 141.652178 -386.141228) (xy 141.698028 -386.170694)
			(xy 141.739217 -386.206386) (xy 141.774908 -386.247575) (xy 141.804374 -386.293425) (xy 141.827015 -386.343002)
			(xy 141.842371 -386.395296) (xy 141.850128 -386.449243) (xy 141.850618 -386.476494) (xy 141.850122 -386.504462)
			(xy 141.841944 -386.559799) (xy 141.825779 -386.613349) (xy 141.801971 -386.663967) (xy 141.77103 -386.710568)
			(xy 141.73362 -386.752155) (xy 141.690541 -386.787836) (xy 141.642716 -386.816849) (xy 141.591169 -386.838571)
			(xy 141.537003 -386.852537) (xy 141.509242 -386.85597) (xy 141.500098 -386.856732) (xy 141.483842 -386.86486)
			(xy 141.42593 -386.926074) (xy 141.418818 -386.942584) (xy 141.41831 -386.951728) (xy 141.416179 -386.984041)
			(xy 141.404748 -387.047783) (xy 141.385321 -387.109558) (xy 141.358212 -387.168369) (xy 141.323858 -387.223265)
			(xy 141.303756 -387.248654) (xy 141.298423 -387.255634) (xy 141.292444 -387.272136) (xy 141.292072 -387.280912)
			(xy 141.292072 -387.434836) (xy 141.292482 -387.443604) (xy 141.298454 -387.460099) (xy 141.303756 -387.467094)
			(xy 141.32547 -387.494493) (xy 141.361973 -387.554116) (xy 141.389968 -387.618176) (xy 141.408925 -387.685466)
			(xy 141.418489 -387.754719) (xy 141.419072 -387.789674) (xy 141.419072 -387.790182) (xy 141.418674 -387.818756)
			(xy 141.412243 -387.875541) (xy 141.399484 -387.931246) (xy 141.39037 -387.95833) (xy 141.38656 -387.968744)
			(xy 141.388592 -387.990334) (xy 141.436852 -388.076186) (xy 141.454378 -388.08914) (xy 141.4653 -388.091426)
			(xy 141.4935 -388.097887) (xy 141.547678 -388.118173) (xy 141.598172 -388.146407) (xy 141.643825 -388.181942)
			(xy 141.683588 -388.223961) (xy 141.716552 -388.271503) (xy 141.729345 -388.297674) (xy 143.436592 -388.297674)
			(xy 143.440663 -388.242052) (xy 143.452789 -388.187615) (xy 143.472712 -388.135524) (xy 143.500008 -388.086889)
			(xy 143.534094 -388.042746) (xy 143.574243 -388.004037) (xy 143.619601 -387.971586) (xy 143.669201 -387.946085)
			(xy 143.721985 -387.928078) (xy 143.776828 -387.917948) (xy 143.832562 -387.915911) (xy 143.887999 -387.922011)
			(xy 143.941956 -387.936117) (xy 143.993285 -387.957929) (xy 144.040891 -387.986983) (xy 144.083759 -388.022658)
			(xy 144.120976 -388.064195) (xy 144.151749 -388.110708) (xy 144.175421 -388.161205) (xy 144.191489 -388.214612)
			(xy 144.199609 -388.269788) (xy 144.200118 -388.297674) (xy 144.199671 -388.322137) (xy 144.402558 -388.322137)
			(xy 144.402558 -388.270163) (xy 144.410688 -388.218828) (xy 144.426749 -388.169398) (xy 144.450345 -388.123088)
			(xy 144.480895 -388.08104) (xy 144.517646 -388.044289) (xy 144.559694 -388.013739) (xy 144.606004 -387.990143)
			(xy 144.655434 -387.974082) (xy 144.706769 -387.965952) (xy 144.758743 -387.965952) (xy 144.810078 -387.974082)
			(xy 144.859508 -387.990143) (xy 144.905818 -388.013739) (xy 144.947866 -388.044289) (xy 144.984617 -388.08104)
			(xy 145.015167 -388.123088) (xy 145.038763 -388.169398) (xy 145.054824 -388.218828) (xy 145.062954 -388.270163)
			(xy 145.063464 -388.29615) (xy 145.062954 -388.322137) (xy 145.054824 -388.373472) (xy 145.038763 -388.422902)
			(xy 145.015167 -388.469212) (xy 144.984617 -388.51126) (xy 144.947866 -388.548011) (xy 144.905818 -388.578561)
			(xy 144.859508 -388.602157) (xy 144.810078 -388.618218) (xy 144.758743 -388.626348) (xy 144.706769 -388.626348)
			(xy 144.655434 -388.618218) (xy 144.606004 -388.602157) (xy 144.559694 -388.578561) (xy 144.517646 -388.548011)
			(xy 144.480895 -388.51126) (xy 144.450345 -388.469212) (xy 144.426749 -388.422902) (xy 144.410688 -388.373472)
			(xy 144.402558 -388.322137) (xy 144.199671 -388.322137) (xy 144.199609 -388.32556) (xy 144.191489 -388.380736)
			(xy 144.175421 -388.434143) (xy 144.151749 -388.48464) (xy 144.120976 -388.531153) (xy 144.083759 -388.57269)
			(xy 144.040891 -388.608365) (xy 143.993285 -388.637419) (xy 143.941956 -388.659231) (xy 143.887999 -388.673337)
			(xy 143.832562 -388.679437) (xy 143.776828 -388.6774) (xy 143.721985 -388.66727) (xy 143.669201 -388.649263)
			(xy 143.619601 -388.623762) (xy 143.574243 -388.591311) (xy 143.534094 -388.552602) (xy 143.500008 -388.508459)
			(xy 143.472712 -388.459824) (xy 143.452789 -388.407733) (xy 143.440663 -388.353296) (xy 143.436592 -388.297674)
			(xy 141.729345 -388.297674) (xy 141.741959 -388.323477) (xy 141.759227 -388.378692) (xy 141.767961 -388.43588)
			(xy 141.768576 -388.464806) (xy 141.768112 -388.492058) (xy 141.760354 -388.546006) (xy 141.744998 -388.598302)
			(xy 141.722354 -388.647879) (xy 141.692886 -388.693729) (xy 141.657191 -388.734918) (xy 141.615999 -388.770608)
			(xy 141.570146 -388.800072) (xy 141.520566 -388.822711) (xy 141.468269 -388.838062) (xy 141.41432 -388.845815)
			(xy 141.387068 -388.846314) (xy 141.378178 -388.846314) (xy 141.366748 -388.84606) (xy 141.346428 -388.854696)
			(xy 141.27988 -388.92988) (xy 141.27353 -388.951216) (xy 141.275054 -388.962392) (xy 141.276943 -388.97603)
			(xy 141.278979 -389.003489) (xy 141.279118 -389.017256) (xy 141.279118 -389.017764) (xy 141.278968 -389.032493)
			(xy 141.276682 -389.061864) (xy 141.274546 -389.076438) (xy 141.272768 -389.08736) (xy 141.278864 -389.108696)
			(xy 141.336268 -389.176006) (xy 141.343875 -389.183952) (xy 141.363887 -389.19303) (xy 141.374876 -389.193532)
			(xy 142.498572 -389.193532) (xy 142.523161 -389.193995) (xy 142.57173 -389.201702) (xy 142.618495 -389.216915)
			(xy 142.662303 -389.239259) (xy 142.702075 -389.268183) (xy 142.719806 -389.285226) (xy 143.814292 -390.379966)
			(xy 143.82167 -390.386779) (xy 143.8402 -390.394481) (xy 143.860266 -390.394481) (xy 143.878796 -390.386779)
			(xy 143.886174 -390.379966) (xy 144.14754 -390.1186) (xy 144.15516 -390.099296) (xy 144.154652 -390.088374)
			(xy 144.154144 -390.067292) (xy 144.154662 -390.03303) (xy 144.162922 -389.965006) (xy 144.179321 -389.898474)
			(xy 144.20362 -389.834403) (xy 144.235464 -389.773728) (xy 144.274389 -389.717334) (xy 144.319828 -389.666042)
			(xy 144.371118 -389.620602) (xy 144.427511 -389.581674) (xy 144.488185 -389.549828) (xy 144.552255 -389.525527)
			(xy 144.618786 -389.509126) (xy 144.68681 -389.500863) (xy 144.721072 -389.500364) (xy 145.151094 -389.500364)
			(xy 145.18821 -389.500941) (xy 145.261806 -389.510632) (xy 145.333503 -389.529861) (xy 145.36801 -389.543544)
			(xy 145.666968 -389.667496) (xy 145.671596 -389.669271) (xy 145.681317 -389.671196) (xy 145.686272 -389.671306)
			(xy 146.67611 -389.671306) (xy 146.686179 -389.671731) (xy 146.70478 -389.679449) (xy 146.712178 -389.686292)
			(xy 146.89074 -389.864854) (xy 146.917664 -389.871458) (xy 146.931126 -389.867648) (xy 146.952534 -389.861635)
			(xy 146.996523 -389.855136) (xy 147.018756 -389.854694) (xy 147.042751 -389.855137) (xy 147.090152 -389.862638)
			(xy 147.135795 -389.877463) (xy 147.178558 -389.899246) (xy 147.217385 -389.927451) (xy 147.251322 -389.961383)
			(xy 147.279532 -390.000207) (xy 147.301321 -390.042966) (xy 147.316152 -390.088607) (xy 147.32366 -390.136007)
			(xy 147.324064 -390.160002) (xy 147.32381 -390.17321) (xy 147.323302 -390.183878) (xy 147.330668 -390.202928)
			(xy 147.38858 -390.263634) (xy 147.396033 -390.270682) (xy 147.414908 -390.278665) (xy 147.425156 -390.279128)
			(xy 147.812506 -390.279128) (xy 147.822755 -390.278669) (xy 147.841633 -390.270686) (xy 147.849082 -390.263634)
			(xy 147.906994 -390.202928) (xy 147.91436 -390.183878) (xy 147.913852 -390.17321) (xy 147.913598 -390.160002)
			(xy 147.91412 -390.134747) (xy 147.922433 -390.084925) (xy 147.938834 -390.037151) (xy 147.962875 -389.992728)
			(xy 147.993899 -389.952868) (xy 148.031061 -389.918658) (xy 148.073347 -389.891032) (xy 148.119603 -389.870742)
			(xy 148.168568 -389.858342) (xy 148.218906 -389.854171) (xy 148.269244 -389.858342) (xy 148.318209 -389.870742)
			(xy 148.364465 -389.891032) (xy 148.406751 -389.918658) (xy 148.443913 -389.952868) (xy 148.474937 -389.992728)
			(xy 148.498978 -390.037151) (xy 148.515379 -390.084925) (xy 148.523692 -390.134747) (xy 148.524214 -390.160002)
			(xy 148.52396 -390.17321) (xy 148.523452 -390.183878) (xy 148.530818 -390.202928) (xy 148.58873 -390.263634)
			(xy 148.596181 -390.270689) (xy 148.615055 -390.278691) (xy 148.625306 -390.279128) (xy 148.767292 -390.279128)
			(xy 148.804408 -390.279704) (xy 148.878004 -390.289395) (xy 148.949702 -390.308623) (xy 148.984208 -390.322308)
			(xy 149.07895 -390.361678) (xy 149.088374 -390.365026) (xy 149.108352 -390.365001) (xy 149.126817 -390.357374)
			(xy 149.140989 -390.343293) (xy 149.145244 -390.334246) (xy 149.149562 -390.323832) (xy 149.1488 -390.302496)
			(xy 149.143974 -390.29259) (xy 149.134465 -390.271837) (xy 149.121013 -390.228215) (xy 149.114185 -390.18308)
			(xy 149.113748 -390.160256) (xy 149.113748 -390.160002) (xy 149.11427 -390.134747) (xy 149.122583 -390.084925)
			(xy 149.138984 -390.037151) (xy 149.163025 -389.992728) (xy 149.194049 -389.952868) (xy 149.231211 -389.918658)
			(xy 149.273497 -389.891032) (xy 149.319753 -389.870742) (xy 149.368718 -389.858342) (xy 149.419056 -389.854171)
			(xy 149.469394 -389.858342) (xy 149.518359 -389.870742) (xy 149.564615 -389.891032) (xy 149.606901 -389.918658)
			(xy 149.644063 -389.952868) (xy 149.675087 -389.992728) (xy 149.699128 -390.037151) (xy 149.715529 -390.084925)
			(xy 149.723842 -390.134747) (xy 149.724364 -390.160002) (xy 150.313148 -390.160002) (xy 150.317108 -390.110948)
			(xy 150.328885 -390.063164) (xy 150.348176 -390.017888) (xy 150.374479 -389.976292) (xy 150.407114 -389.939455)
			(xy 150.445235 -389.90833) (xy 150.487856 -389.883723) (xy 150.533872 -389.866271) (xy 150.582091 -389.856427)
			(xy 150.631266 -389.854446) (xy 150.680121 -389.860378) (xy 150.727392 -389.87407) (xy 150.771854 -389.895168)
			(xy 150.812357 -389.923124) (xy 150.84785 -389.957216) (xy 150.877415 -389.99656) (xy 150.900286 -390.040137)
			(xy 150.91587 -390.086818) (xy 150.923765 -390.135395) (xy 150.92426 -390.160002) (xy 151.513298 -390.160002)
			(xy 151.517258 -390.110948) (xy 151.529035 -390.063164) (xy 151.548326 -390.017888) (xy 151.574629 -389.976292)
			(xy 151.607264 -389.939455) (xy 151.645385 -389.90833) (xy 151.688006 -389.883723) (xy 151.734022 -389.866271)
			(xy 151.782241 -389.856427) (xy 151.831416 -389.854446) (xy 151.880271 -389.860378) (xy 151.927542 -389.87407)
			(xy 151.972004 -389.895168) (xy 152.012507 -389.923124) (xy 152.048 -389.957216) (xy 152.077565 -389.99656)
			(xy 152.100436 -390.040137) (xy 152.11602 -390.086818) (xy 152.123915 -390.135395) (xy 152.12441 -390.160002)
			(xy 152.713194 -390.160002) (xy 152.717154 -390.110948) (xy 152.728931 -390.063164) (xy 152.748222 -390.017888)
			(xy 152.774525 -389.976292) (xy 152.80716 -389.939455) (xy 152.845281 -389.90833) (xy 152.887902 -389.883723)
			(xy 152.933918 -389.866271) (xy 152.982137 -389.856427) (xy 153.031312 -389.854446) (xy 153.080167 -389.860378)
			(xy 153.127438 -389.87407) (xy 153.1719 -389.895168) (xy 153.212403 -389.923124) (xy 153.247896 -389.957216)
			(xy 153.277461 -389.99656) (xy 153.300332 -390.040137) (xy 153.315916 -390.086818) (xy 153.323811 -390.135395)
			(xy 153.324306 -390.160002) (xy 153.91309 -390.160002) (xy 153.91705 -390.110948) (xy 153.928827 -390.063164)
			(xy 153.948118 -390.017888) (xy 153.974421 -389.976292) (xy 154.007056 -389.939455) (xy 154.045177 -389.90833)
			(xy 154.087798 -389.883723) (xy 154.133814 -389.866271) (xy 154.182033 -389.856427) (xy 154.231208 -389.854446)
			(xy 154.280063 -389.860378) (xy 154.327334 -389.87407) (xy 154.371796 -389.895168) (xy 154.412299 -389.923124)
			(xy 154.447792 -389.957216) (xy 154.477357 -389.99656) (xy 154.500228 -390.040137) (xy 154.515812 -390.086818)
			(xy 154.523707 -390.135395) (xy 154.524202 -390.160002) (xy 155.11324 -390.160002) (xy 155.1172 -390.110948)
			(xy 155.128977 -390.063164) (xy 155.148268 -390.017888) (xy 155.174571 -389.976292) (xy 155.207206 -389.939455)
			(xy 155.245327 -389.90833) (xy 155.287948 -389.883723) (xy 155.333964 -389.866271) (xy 155.382183 -389.856427)
			(xy 155.431358 -389.854446) (xy 155.480213 -389.860378) (xy 155.527484 -389.87407) (xy 155.571946 -389.895168)
			(xy 155.612449 -389.923124) (xy 155.647942 -389.957216) (xy 155.677507 -389.99656) (xy 155.700378 -390.040137)
			(xy 155.715962 -390.086818) (xy 155.723857 -390.135395) (xy 155.724352 -390.160002) (xy 156.313136 -390.160002)
			(xy 156.317096 -390.110948) (xy 156.328873 -390.063164) (xy 156.348164 -390.017888) (xy 156.374467 -389.976292)
			(xy 156.407102 -389.939455) (xy 156.445223 -389.90833) (xy 156.487844 -389.883723) (xy 156.53386 -389.866271)
			(xy 156.582079 -389.856427) (xy 156.631254 -389.854446) (xy 156.680109 -389.860378) (xy 156.72738 -389.87407)
			(xy 156.771842 -389.895168) (xy 156.812345 -389.923124) (xy 156.847838 -389.957216) (xy 156.877403 -389.99656)
			(xy 156.900274 -390.040137) (xy 156.915858 -390.086818) (xy 156.923753 -390.135395) (xy 156.924248 -390.160002)
			(xy 157.513286 -390.160002) (xy 157.517246 -390.110948) (xy 157.529023 -390.063164) (xy 157.548314 -390.017888)
			(xy 157.574617 -389.976292) (xy 157.607252 -389.939455) (xy 157.645373 -389.90833) (xy 157.687994 -389.883723)
			(xy 157.73401 -389.866271) (xy 157.782229 -389.856427) (xy 157.831404 -389.854446) (xy 157.880259 -389.860378)
			(xy 157.92753 -389.87407) (xy 157.971992 -389.895168) (xy 158.012495 -389.923124) (xy 158.047988 -389.957216)
			(xy 158.077553 -389.99656) (xy 158.100424 -390.040137) (xy 158.116008 -390.086818) (xy 158.123903 -390.135395)
			(xy 158.124398 -390.160002) (xy 158.713182 -390.160002) (xy 158.717142 -390.110948) (xy 158.728919 -390.063164)
			(xy 158.74821 -390.017888) (xy 158.774513 -389.976292) (xy 158.807148 -389.939455) (xy 158.845269 -389.90833)
			(xy 158.88789 -389.883723) (xy 158.933906 -389.866271) (xy 158.982125 -389.856427) (xy 159.0313 -389.854446)
			(xy 159.080155 -389.860378) (xy 159.127426 -389.87407) (xy 159.171888 -389.895168) (xy 159.212391 -389.923124)
			(xy 159.247884 -389.957216) (xy 159.277449 -389.99656) (xy 159.30032 -390.040137) (xy 159.315904 -390.086818)
			(xy 159.323799 -390.135395) (xy 159.324294 -390.160002) (xy 159.913078 -390.160002) (xy 159.917038 -390.110948)
			(xy 159.928815 -390.063164) (xy 159.948106 -390.017888) (xy 159.974409 -389.976292) (xy 160.007044 -389.939455)
			(xy 160.045165 -389.90833) (xy 160.087786 -389.883723) (xy 160.133802 -389.866271) (xy 160.182021 -389.856427)
			(xy 160.231196 -389.854446) (xy 160.280051 -389.860378) (xy 160.327322 -389.87407) (xy 160.371784 -389.895168)
			(xy 160.412287 -389.923124) (xy 160.44778 -389.957216) (xy 160.477345 -389.99656) (xy 160.500216 -390.040137)
			(xy 160.5158 -390.086818) (xy 160.523695 -390.135395) (xy 160.52419 -390.160002) (xy 161.113228 -390.160002)
			(xy 161.117188 -390.110948) (xy 161.128965 -390.063164) (xy 161.148256 -390.017888) (xy 161.174559 -389.976292)
			(xy 161.207194 -389.939455) (xy 161.245315 -389.90833) (xy 161.287936 -389.883723) (xy 161.333952 -389.866271)
			(xy 161.382171 -389.856427) (xy 161.431346 -389.854446) (xy 161.480201 -389.860378) (xy 161.527472 -389.87407)
			(xy 161.571934 -389.895168) (xy 161.612437 -389.923124) (xy 161.64793 -389.957216) (xy 161.677495 -389.99656)
			(xy 161.700366 -390.040137) (xy 161.71595 -390.086818) (xy 161.723845 -390.135395) (xy 161.72434 -390.160002)
			(xy 162.313124 -390.160002) (xy 162.317084 -390.110948) (xy 162.328861 -390.063164) (xy 162.348152 -390.017888)
			(xy 162.374455 -389.976292) (xy 162.40709 -389.939455) (xy 162.445211 -389.90833) (xy 162.487832 -389.883723)
			(xy 162.533848 -389.866271) (xy 162.582067 -389.856427) (xy 162.631242 -389.854446) (xy 162.680097 -389.860378)
			(xy 162.727368 -389.87407) (xy 162.77183 -389.895168) (xy 162.812333 -389.923124) (xy 162.847826 -389.957216)
			(xy 162.877391 -389.99656) (xy 162.900262 -390.040137) (xy 162.915846 -390.086818) (xy 162.923741 -390.135395)
			(xy 162.924236 -390.160002) (xy 163.513274 -390.160002) (xy 163.517234 -390.110948) (xy 163.529011 -390.063164)
			(xy 163.548302 -390.017888) (xy 163.574605 -389.976292) (xy 163.60724 -389.939455) (xy 163.645361 -389.90833)
			(xy 163.687982 -389.883723) (xy 163.733998 -389.866271) (xy 163.782217 -389.856427) (xy 163.831392 -389.854446)
			(xy 163.880247 -389.860378) (xy 163.927518 -389.87407) (xy 163.97198 -389.895168) (xy 164.012483 -389.923124)
			(xy 164.047976 -389.957216) (xy 164.077541 -389.99656) (xy 164.100412 -390.040137) (xy 164.115996 -390.086818)
			(xy 164.123891 -390.135395) (xy 164.124386 -390.160002) (xy 164.71317 -390.160002) (xy 164.71713 -390.110948)
			(xy 164.728907 -390.063164) (xy 164.748198 -390.017888) (xy 164.774501 -389.976292) (xy 164.807136 -389.939455)
			(xy 164.845257 -389.90833) (xy 164.887878 -389.883723) (xy 164.933894 -389.866271) (xy 164.982113 -389.856427)
			(xy 165.031288 -389.854446) (xy 165.080143 -389.860378) (xy 165.127414 -389.87407) (xy 165.171876 -389.895168)
			(xy 165.212379 -389.923124) (xy 165.247872 -389.957216) (xy 165.277437 -389.99656) (xy 165.300308 -390.040137)
			(xy 165.315892 -390.086818) (xy 165.323787 -390.135395) (xy 165.324282 -390.160002) (xy 165.323787 -390.184609)
			(xy 165.323563 -390.185989) (xy 166.04285 -390.185989) (xy 166.04285 -390.134015) (xy 166.05098 -390.08268)
			(xy 166.067041 -390.03325) (xy 166.090637 -389.98694) (xy 166.121187 -389.944892) (xy 166.157938 -389.908141)
			(xy 166.199986 -389.877591) (xy 166.246296 -389.853995) (xy 166.295726 -389.837934) (xy 166.347061 -389.829804)
			(xy 166.399035 -389.829804) (xy 166.45037 -389.837934) (xy 166.4998 -389.853995) (xy 166.54611 -389.877591)
			(xy 166.588158 -389.908141) (xy 166.624909 -389.944892) (xy 166.655459 -389.98694) (xy 166.679055 -390.03325)
			(xy 166.695116 -390.08268) (xy 166.703246 -390.134015) (xy 166.703756 -390.160002) (xy 166.703246 -390.185989)
			(xy 166.695116 -390.237324) (xy 166.679055 -390.286754) (xy 166.655459 -390.333064) (xy 166.624909 -390.375112)
			(xy 166.588158 -390.411863) (xy 166.54611 -390.442413) (xy 166.4998 -390.466009) (xy 166.45037 -390.48207)
			(xy 166.399035 -390.4902) (xy 166.347061 -390.4902) (xy 166.295726 -390.48207) (xy 166.246296 -390.466009)
			(xy 166.199986 -390.442413) (xy 166.157938 -390.411863) (xy 166.121187 -390.375112) (xy 166.090637 -390.333064)
			(xy 166.067041 -390.286754) (xy 166.05098 -390.237324) (xy 166.04285 -390.185989) (xy 165.323563 -390.185989)
			(xy 165.315892 -390.233186) (xy 165.300308 -390.279867) (xy 165.277437 -390.323444) (xy 165.247872 -390.362788)
			(xy 165.212379 -390.39688) (xy 165.171876 -390.424836) (xy 165.127414 -390.445934) (xy 165.080143 -390.459626)
			(xy 165.031288 -390.465558) (xy 164.982113 -390.463577) (xy 164.933894 -390.453733) (xy 164.887878 -390.436281)
			(xy 164.845257 -390.411674) (xy 164.807136 -390.380549) (xy 164.774501 -390.343712) (xy 164.748198 -390.302116)
			(xy 164.728907 -390.25684) (xy 164.71713 -390.209056) (xy 164.71317 -390.160002) (xy 164.124386 -390.160002)
			(xy 164.123891 -390.184609) (xy 164.115996 -390.233186) (xy 164.100412 -390.279867) (xy 164.077541 -390.323444)
			(xy 164.047976 -390.362788) (xy 164.012483 -390.39688) (xy 163.97198 -390.424836) (xy 163.927518 -390.445934)
			(xy 163.880247 -390.459626) (xy 163.831392 -390.465558) (xy 163.782217 -390.463577) (xy 163.733998 -390.453733)
			(xy 163.687982 -390.436281) (xy 163.645361 -390.411674) (xy 163.60724 -390.380549) (xy 163.574605 -390.343712)
			(xy 163.548302 -390.302116) (xy 163.529011 -390.25684) (xy 163.517234 -390.209056) (xy 163.513274 -390.160002)
			(xy 162.924236 -390.160002) (xy 162.923741 -390.184609) (xy 162.915846 -390.233186) (xy 162.900262 -390.279867)
			(xy 162.877391 -390.323444) (xy 162.847826 -390.362788) (xy 162.812333 -390.39688) (xy 162.77183 -390.424836)
			(xy 162.727368 -390.445934) (xy 162.680097 -390.459626) (xy 162.631242 -390.465558) (xy 162.582067 -390.463577)
			(xy 162.533848 -390.453733) (xy 162.487832 -390.436281) (xy 162.445211 -390.411674) (xy 162.40709 -390.380549)
			(xy 162.374455 -390.343712) (xy 162.348152 -390.302116) (xy 162.328861 -390.25684) (xy 162.317084 -390.209056)
			(xy 162.313124 -390.160002) (xy 161.72434 -390.160002) (xy 161.723845 -390.184609) (xy 161.71595 -390.233186)
			(xy 161.700366 -390.279867) (xy 161.677495 -390.323444) (xy 161.64793 -390.362788) (xy 161.612437 -390.39688)
			(xy 161.571934 -390.424836) (xy 161.527472 -390.445934) (xy 161.480201 -390.459626) (xy 161.431346 -390.465558)
			(xy 161.382171 -390.463577) (xy 161.333952 -390.453733) (xy 161.287936 -390.436281) (xy 161.245315 -390.411674)
			(xy 161.207194 -390.380549) (xy 161.174559 -390.343712) (xy 161.148256 -390.302116) (xy 161.128965 -390.25684)
			(xy 161.117188 -390.209056) (xy 161.113228 -390.160002) (xy 160.52419 -390.160002) (xy 160.523695 -390.184609)
			(xy 160.5158 -390.233186) (xy 160.500216 -390.279867) (xy 160.477345 -390.323444) (xy 160.44778 -390.362788)
			(xy 160.412287 -390.39688) (xy 160.371784 -390.424836) (xy 160.327322 -390.445934) (xy 160.280051 -390.459626)
			(xy 160.231196 -390.465558) (xy 160.182021 -390.463577) (xy 160.133802 -390.453733) (xy 160.087786 -390.436281)
			(xy 160.045165 -390.411674) (xy 160.007044 -390.380549) (xy 159.974409 -390.343712) (xy 159.948106 -390.302116)
			(xy 159.928815 -390.25684) (xy 159.917038 -390.209056) (xy 159.913078 -390.160002) (xy 159.324294 -390.160002)
			(xy 159.323799 -390.184609) (xy 159.315904 -390.233186) (xy 159.30032 -390.279867) (xy 159.277449 -390.323444)
			(xy 159.247884 -390.362788) (xy 159.212391 -390.39688) (xy 159.171888 -390.424836) (xy 159.127426 -390.445934)
			(xy 159.080155 -390.459626) (xy 159.0313 -390.465558) (xy 158.982125 -390.463577) (xy 158.933906 -390.453733)
			(xy 158.88789 -390.436281) (xy 158.845269 -390.411674) (xy 158.807148 -390.380549) (xy 158.774513 -390.343712)
			(xy 158.74821 -390.302116) (xy 158.728919 -390.25684) (xy 158.717142 -390.209056) (xy 158.713182 -390.160002)
			(xy 158.124398 -390.160002) (xy 158.123903 -390.184609) (xy 158.116008 -390.233186) (xy 158.100424 -390.279867)
			(xy 158.077553 -390.323444) (xy 158.047988 -390.362788) (xy 158.012495 -390.39688) (xy 157.971992 -390.424836)
			(xy 157.92753 -390.445934) (xy 157.880259 -390.459626) (xy 157.831404 -390.465558) (xy 157.782229 -390.463577)
			(xy 157.73401 -390.453733) (xy 157.687994 -390.436281) (xy 157.645373 -390.411674) (xy 157.607252 -390.380549)
			(xy 157.574617 -390.343712) (xy 157.548314 -390.302116) (xy 157.529023 -390.25684) (xy 157.517246 -390.209056)
			(xy 157.513286 -390.160002) (xy 156.924248 -390.160002) (xy 156.923753 -390.184609) (xy 156.915858 -390.233186)
			(xy 156.900274 -390.279867) (xy 156.877403 -390.323444) (xy 156.847838 -390.362788) (xy 156.812345 -390.39688)
			(xy 156.771842 -390.424836) (xy 156.72738 -390.445934) (xy 156.680109 -390.459626) (xy 156.631254 -390.465558)
			(xy 156.582079 -390.463577) (xy 156.53386 -390.453733) (xy 156.487844 -390.436281) (xy 156.445223 -390.411674)
			(xy 156.407102 -390.380549) (xy 156.374467 -390.343712) (xy 156.348164 -390.302116) (xy 156.328873 -390.25684)
			(xy 156.317096 -390.209056) (xy 156.313136 -390.160002) (xy 155.724352 -390.160002) (xy 155.723857 -390.184609)
			(xy 155.715962 -390.233186) (xy 155.700378 -390.279867) (xy 155.677507 -390.323444) (xy 155.647942 -390.362788)
			(xy 155.612449 -390.39688) (xy 155.571946 -390.424836) (xy 155.527484 -390.445934) (xy 155.480213 -390.459626)
			(xy 155.431358 -390.465558) (xy 155.382183 -390.463577) (xy 155.333964 -390.453733) (xy 155.287948 -390.436281)
			(xy 155.245327 -390.411674) (xy 155.207206 -390.380549) (xy 155.174571 -390.343712) (xy 155.148268 -390.302116)
			(xy 155.128977 -390.25684) (xy 155.1172 -390.209056) (xy 155.11324 -390.160002) (xy 154.524202 -390.160002)
			(xy 154.523707 -390.184609) (xy 154.515812 -390.233186) (xy 154.500228 -390.279867) (xy 154.477357 -390.323444)
			(xy 154.447792 -390.362788) (xy 154.412299 -390.39688) (xy 154.371796 -390.424836) (xy 154.327334 -390.445934)
			(xy 154.280063 -390.459626) (xy 154.231208 -390.465558) (xy 154.182033 -390.463577) (xy 154.133814 -390.453733)
			(xy 154.087798 -390.436281) (xy 154.045177 -390.411674) (xy 154.007056 -390.380549) (xy 153.974421 -390.343712)
			(xy 153.948118 -390.302116) (xy 153.928827 -390.25684) (xy 153.91705 -390.209056) (xy 153.91309 -390.160002)
			(xy 153.324306 -390.160002) (xy 153.323811 -390.184609) (xy 153.315916 -390.233186) (xy 153.300332 -390.279867)
			(xy 153.277461 -390.323444) (xy 153.247896 -390.362788) (xy 153.212403 -390.39688) (xy 153.1719 -390.424836)
			(xy 153.127438 -390.445934) (xy 153.080167 -390.459626) (xy 153.031312 -390.465558) (xy 152.982137 -390.463577)
			(xy 152.933918 -390.453733) (xy 152.887902 -390.436281) (xy 152.845281 -390.411674) (xy 152.80716 -390.380549)
			(xy 152.774525 -390.343712) (xy 152.748222 -390.302116) (xy 152.728931 -390.25684) (xy 152.717154 -390.209056)
			(xy 152.713194 -390.160002) (xy 152.12441 -390.160002) (xy 152.123915 -390.184609) (xy 152.11602 -390.233186)
			(xy 152.100436 -390.279867) (xy 152.077565 -390.323444) (xy 152.048 -390.362788) (xy 152.012507 -390.39688)
			(xy 151.972004 -390.424836) (xy 151.927542 -390.445934) (xy 151.880271 -390.459626) (xy 151.831416 -390.465558)
			(xy 151.782241 -390.463577) (xy 151.734022 -390.453733) (xy 151.688006 -390.436281) (xy 151.645385 -390.411674)
			(xy 151.607264 -390.380549) (xy 151.574629 -390.343712) (xy 151.548326 -390.302116) (xy 151.529035 -390.25684)
			(xy 151.517258 -390.209056) (xy 151.513298 -390.160002) (xy 150.92426 -390.160002) (xy 150.923765 -390.184609)
			(xy 150.91587 -390.233186) (xy 150.900286 -390.279867) (xy 150.877415 -390.323444) (xy 150.84785 -390.362788)
			(xy 150.812357 -390.39688) (xy 150.771854 -390.424836) (xy 150.727392 -390.445934) (xy 150.680121 -390.459626)
			(xy 150.631266 -390.465558) (xy 150.582091 -390.463577) (xy 150.533872 -390.453733) (xy 150.487856 -390.436281)
			(xy 150.445235 -390.411674) (xy 150.407114 -390.380549) (xy 150.374479 -390.343712) (xy 150.348176 -390.302116)
			(xy 150.328885 -390.25684) (xy 150.317108 -390.209056) (xy 150.313148 -390.160002) (xy 149.724364 -390.160002)
			(xy 149.723904 -390.184162) (xy 149.716289 -390.231877) (xy 149.70125 -390.277796) (xy 149.679163 -390.320772)
			(xy 149.65058 -390.359729) (xy 149.616214 -390.393696) (xy 149.596856 -390.40816) (xy 149.58568 -390.416288)
			(xy 149.574504 -390.441434) (xy 149.586188 -390.543542) (xy 149.58758 -390.552475) (xy 149.595736 -390.568598)
			(xy 149.608968 -390.580901) (xy 149.617176 -390.58469) (xy 150.183596 -390.819132) (xy 150.217673 -390.833867)
			(xy 150.28197 -390.870988) (xy 150.340856 -390.916205) (xy 150.367492 -390.942068) (xy 150.657306 -391.231882)
			(xy 150.683116 -391.258563) (xy 150.728305 -391.317458) (xy 150.76544 -391.381735) (xy 150.780242 -391.415778)
			(xy 150.80996 -391.48766) (xy 150.814098 -391.496548) (xy 150.827828 -391.510516) (xy 150.83663 -391.514838)
			(xy 150.910036 -391.547096) (xy 150.92934 -391.547604) (xy 150.938738 -391.544302) (xy 150.964204 -391.535533)
			(xy 151.017221 -391.526077) (xy 151.044148 -391.525506) (xy 151.068136 -391.52598) (xy 151.115521 -391.533492)
			(xy 151.161148 -391.548324) (xy 151.203893 -391.570111) (xy 151.242704 -391.598315) (xy 151.276625 -391.632243)
			(xy 151.304822 -391.67106) (xy 151.3266 -391.713809) (xy 151.341422 -391.759439) (xy 151.348925 -391.806826)
			(xy 151.349456 -391.830814) (xy 151.348958 -391.855184) (xy 151.341178 -391.9033) (xy 151.325866 -391.949573)
			(xy 151.303409 -391.992832) (xy 151.289258 -392.012678) (xy 151.28367 -392.020552) (xy 151.27859 -392.038332)
			(xy 151.286972 -392.124946) (xy 151.2951 -392.14171) (xy 151.302212 -392.14806) (xy 151.321295 -392.166199)
			(xy 151.354793 -392.206817) (xy 151.382392 -392.251653) (xy 151.403567 -392.299856) (xy 151.417917 -392.350512)
			(xy 151.425168 -392.40266) (xy 151.425656 -392.428984) (xy 151.425656 -393.293092) (xy 151.425131 -393.321975)
			(xy 151.41643 -393.379082) (xy 151.399212 -393.434222) (xy 151.37387 -393.486133) (xy 151.340985 -393.533625)
			(xy 151.321516 -393.554966) (xy 151.31542 -393.56157) (xy 151.308308 -393.577572) (xy 151.30272 -393.659868)
			(xy 151.307546 -393.676886) (xy 151.312626 -393.683998) (xy 151.32928 -393.708213) (xy 151.354659 -393.761214)
			(xy 151.37028 -393.817864) (xy 151.373586 -393.847066) (xy 151.374856 -393.86256) (xy 151.394668 -393.88669)
			(xy 151.783542 -394.002514) (xy 151.794803 -394.005352) (xy 151.817706 -394.001664) (xy 151.827484 -393.995402)
			(xy 151.90216 -393.94257) (xy 151.913336 -393.92225) (xy 151.914098 -393.910566) (xy 151.916031 -393.88354)
			(xy 151.9276 -393.830612) (xy 151.947651 -393.78028) (xy 151.975646 -393.733896) (xy 151.992838 -393.712954)
			(xy 151.999442 -393.705334) (xy 152.005538 -393.687046) (xy 152.000204 -393.596876) (xy 151.992076 -393.57935)
			(xy 151.98471 -393.572492) (xy 151.965808 -393.554379) (xy 151.932641 -393.513876) (xy 151.905318 -393.46922)
			(xy 151.884353 -393.421251) (xy 151.870138 -393.370867) (xy 151.86294 -393.319013) (xy 151.862536 -393.292838)
			(xy 151.862536 -392.429238) (xy 151.862979 -392.40288) (xy 151.870234 -392.350665) (xy 151.884613 -392.299947)
			(xy 151.905839 -392.251693) (xy 151.93351 -392.206822) (xy 151.967097 -392.166191) (xy 151.986234 -392.14806)
			(xy 151.993346 -392.14171) (xy 152.001474 -392.124946) (xy 152.009856 -392.038332) (xy 152.004776 -392.020552)
			(xy 151.999188 -392.012678) (xy 151.985029 -391.992834) (xy 151.96254 -391.949586) (xy 151.94722 -391.903311)
			(xy 151.93946 -391.855187) (xy 151.93899 -391.830814) (xy 151.939512 -391.805559) (xy 151.947825 -391.755737)
			(xy 151.964226 -391.707963) (xy 151.988267 -391.66354) (xy 152.019291 -391.62368) (xy 152.056453 -391.58947)
			(xy 152.098739 -391.561844) (xy 152.144995 -391.541554) (xy 152.19396 -391.529154) (xy 152.244298 -391.524983)
			(xy 152.294636 -391.529154) (xy 152.343601 -391.541554) (xy 152.389857 -391.561844) (xy 152.432143 -391.58947)
			(xy 152.469305 -391.62368) (xy 152.500329 -391.66354) (xy 152.52437 -391.707963) (xy 152.540771 -391.755737)
			(xy 152.549084 -391.805559) (xy 152.549606 -391.830814) (xy 152.549107 -391.855184) (xy 152.541327 -391.903299)
			(xy 152.526013 -391.949571) (xy 152.503553 -391.992828) (xy 152.489408 -392.012678) (xy 152.48382 -392.020552)
			(xy 152.47874 -392.038332) (xy 152.487122 -392.124946) (xy 152.49525 -392.14171) (xy 152.502362 -392.14806)
			(xy 152.521485 -392.166202) (xy 152.555057 -392.20684) (xy 152.582717 -392.251711) (xy 152.603938 -392.299962)
			(xy 152.618317 -392.350674) (xy 152.62558 -392.402882) (xy 152.62606 -392.429238) (xy 152.62606 -393.292838)
			(xy 153.062432 -393.292838) (xy 153.062432 -392.429238) (xy 153.062914 -392.402883) (xy 153.070177 -392.350674)
			(xy 153.084556 -392.299962) (xy 153.105777 -392.251711) (xy 153.133436 -392.20684) (xy 153.167008 -392.166203)
			(xy 153.18613 -392.14806) (xy 153.193242 -392.14171) (xy 153.20137 -392.124946) (xy 153.209752 -392.038332)
			(xy 153.204672 -392.020552) (xy 153.199084 -392.012678) (xy 153.184938 -391.992828) (xy 153.162479 -391.949571)
			(xy 153.147165 -391.903299) (xy 153.139385 -391.855184) (xy 153.138886 -391.830814) (xy 153.139408 -391.805559)
			(xy 153.147721 -391.755737) (xy 153.164122 -391.707963) (xy 153.188163 -391.66354) (xy 153.219187 -391.62368)
			(xy 153.256349 -391.58947) (xy 153.298635 -391.561844) (xy 153.344891 -391.541554) (xy 153.393856 -391.529154)
			(xy 153.444194 -391.524983) (xy 153.494532 -391.529154) (xy 153.543497 -391.541554) (xy 153.589753 -391.561844)
			(xy 153.632039 -391.58947) (xy 153.669201 -391.62368) (xy 153.700225 -391.66354) (xy 153.724266 -391.707963)
			(xy 153.740667 -391.755737) (xy 153.74898 -391.805559) (xy 153.749502 -391.830814) (xy 153.749033 -391.855187)
			(xy 153.741273 -391.903311) (xy 153.725953 -391.949586) (xy 153.703463 -391.992834) (xy 153.689304 -392.012678)
			(xy 153.683716 -392.020552) (xy 153.678636 -392.038332) (xy 153.687018 -392.124946) (xy 153.695146 -392.14171)
			(xy 153.702258 -392.14806) (xy 153.721393 -392.166192) (xy 153.754981 -392.206824) (xy 153.782652 -392.251694)
			(xy 153.803879 -392.299947) (xy 153.818258 -392.350665) (xy 153.825513 -392.40288) (xy 153.825956 -392.429238)
			(xy 153.825956 -393.292838) (xy 154.262836 -393.292838) (xy 154.262836 -392.429238) (xy 154.26331 -392.402892)
			(xy 154.270539 -392.350699) (xy 154.284877 -392.299996) (xy 154.306052 -392.251747) (xy 154.333663 -392.206869)
			(xy 154.367183 -392.166215) (xy 154.38628 -392.14806) (xy 154.393392 -392.14171) (xy 154.40152 -392.124946)
			(xy 154.409902 -392.038332) (xy 154.404822 -392.020552) (xy 154.399234 -392.012678) (xy 154.385082 -391.992833)
			(xy 154.362625 -391.949573) (xy 154.347314 -391.9033) (xy 154.339534 -391.855184) (xy 154.339036 -391.830814)
			(xy 154.339558 -391.805559) (xy 154.347871 -391.755737) (xy 154.364272 -391.707963) (xy 154.388313 -391.66354)
			(xy 154.419337 -391.62368) (xy 154.456499 -391.58947) (xy 154.498785 -391.561844) (xy 154.545041 -391.541554)
			(xy 154.594006 -391.529154) (xy 154.644344 -391.524983) (xy 154.694682 -391.529154) (xy 154.743647 -391.541554)
			(xy 154.789903 -391.561844) (xy 154.832189 -391.58947) (xy 154.869351 -391.62368) (xy 154.900375 -391.66354)
			(xy 154.924416 -391.707963) (xy 154.940817 -391.755737) (xy 154.94913 -391.805559) (xy 154.949652 -391.830814)
			(xy 154.949173 -391.855186) (xy 154.941415 -391.903309) (xy 154.926097 -391.949585) (xy 154.903611 -391.992833)
			(xy 154.889454 -392.012678) (xy 154.883866 -392.020552) (xy 154.878786 -392.038332) (xy 154.887168 -392.124946)
			(xy 154.895296 -392.14171) (xy 154.902408 -392.14806) (xy 154.921533 -392.166191) (xy 154.955077 -392.206836)
			(xy 154.982703 -392.251715) (xy 155.003885 -392.299971) (xy 155.018218 -392.350684) (xy 155.02543 -392.402888)
			(xy 155.025852 -392.429238) (xy 155.025852 -393.292838) (xy 155.462732 -393.292838) (xy 155.462732 -392.429238)
			(xy 155.463176 -392.402891) (xy 155.470406 -392.350695) (xy 155.484748 -392.29999) (xy 155.505929 -392.251741)
			(xy 155.533546 -392.206864) (xy 155.567075 -392.166212) (xy 155.586176 -392.14806) (xy 155.593288 -392.14171)
			(xy 155.601416 -392.124946) (xy 155.609798 -392.038332) (xy 155.604718 -392.020552) (xy 155.59913 -392.012678)
			(xy 155.584977 -391.992833) (xy 155.562521 -391.949573) (xy 155.54721 -391.9033) (xy 155.53943 -391.855184)
			(xy 155.538932 -391.830814) (xy 155.539454 -391.805559) (xy 155.547767 -391.755737) (xy 155.564168 -391.707963)
			(xy 155.588209 -391.66354) (xy 155.619233 -391.62368) (xy 155.656395 -391.58947) (xy 155.698681 -391.561844)
			(xy 155.744937 -391.541554) (xy 155.793902 -391.529154) (xy 155.84424 -391.524983) (xy 155.894578 -391.529154)
			(xy 155.943543 -391.541554) (xy 155.989799 -391.561844) (xy 156.032085 -391.58947) (xy 156.069247 -391.62368)
			(xy 156.100271 -391.66354) (xy 156.124312 -391.707963) (xy 156.140713 -391.755737) (xy 156.149026 -391.805559)
			(xy 156.149548 -391.830814) (xy 156.14907 -391.855186) (xy 156.141311 -391.90331) (xy 156.125993 -391.949585)
			(xy 156.103507 -391.992833) (xy 156.08935 -392.012678) (xy 156.083762 -392.020552) (xy 156.078682 -392.038332)
			(xy 156.087064 -392.124946) (xy 156.095192 -392.14171) (xy 156.102304 -392.14806) (xy 156.121429 -392.166191)
			(xy 156.154973 -392.206837) (xy 156.182599 -392.251715) (xy 156.203781 -392.299971) (xy 156.218114 -392.350684)
			(xy 156.225326 -392.402888) (xy 156.225748 -392.429238) (xy 156.225748 -393.292838) (xy 156.662628 -393.292838)
			(xy 156.662628 -392.429238) (xy 156.663061 -392.402911) (xy 156.670311 -392.350757) (xy 156.684665 -392.300096)
			(xy 156.70585 -392.251891) (xy 156.733463 -392.207057) (xy 156.76698 -392.166447) (xy 156.786072 -392.148314)
			(xy 156.793184 -392.14171) (xy 156.801566 -392.1252) (xy 156.809694 -392.038332) (xy 156.804614 -392.020552)
			(xy 156.799026 -392.012932) (xy 156.784874 -391.993048) (xy 156.762385 -391.949735) (xy 156.747066 -391.903398)
			(xy 156.739306 -391.855216) (xy 156.738828 -391.830814) (xy 156.73935 -391.805559) (xy 156.747663 -391.755737)
			(xy 156.764064 -391.707963) (xy 156.788105 -391.66354) (xy 156.819129 -391.62368) (xy 156.856291 -391.58947)
			(xy 156.898577 -391.561844) (xy 156.944833 -391.541554) (xy 156.993798 -391.529154) (xy 157.044136 -391.524983)
			(xy 157.094474 -391.529154) (xy 157.143439 -391.541554) (xy 157.189695 -391.561844) (xy 157.231981 -391.58947)
			(xy 157.269143 -391.62368) (xy 157.300167 -391.66354) (xy 157.324208 -391.707963) (xy 157.340609 -391.755737)
			(xy 157.348922 -391.805559) (xy 157.349444 -391.830814) (xy 157.348948 -391.855172) (xy 157.341235 -391.903275)
			(xy 157.325992 -391.949545) (xy 157.303603 -391.992812) (xy 157.2895 -392.012678) (xy 157.283658 -392.020298)
			(xy 157.278832 -392.038078) (xy 157.28696 -392.124946) (xy 157.295342 -392.141456) (xy 157.302454 -392.14806)
			(xy 157.321589 -392.166193) (xy 157.355176 -392.206824) (xy 157.382848 -392.251694) (xy 157.404075 -392.299948)
			(xy 157.418453 -392.350665) (xy 157.425709 -392.40288) (xy 157.426152 -392.429238) (xy 157.426152 -393.292838)
			(xy 157.862524 -393.292838) (xy 157.862524 -392.429238) (xy 157.863009 -392.402883) (xy 157.870272 -392.350674)
			(xy 157.88465 -392.299963) (xy 157.90587 -392.251712) (xy 157.933529 -392.206841) (xy 157.9671 -392.166203)
			(xy 157.986222 -392.14806) (xy 157.993334 -392.14171) (xy 158.001462 -392.124946) (xy 158.009844 -392.038332)
			(xy 158.004764 -392.020552) (xy 157.999176 -392.012678) (xy 157.985029 -391.992829) (xy 157.96257 -391.949571)
			(xy 157.947257 -391.903299) (xy 157.939476 -391.855184) (xy 157.938978 -391.830814) (xy 157.9395 -391.805559)
			(xy 157.947813 -391.755737) (xy 157.964214 -391.707963) (xy 157.988255 -391.66354) (xy 158.019279 -391.62368)
			(xy 158.056441 -391.58947) (xy 158.098727 -391.561844) (xy 158.144983 -391.541554) (xy 158.193948 -391.529154)
			(xy 158.244286 -391.524983) (xy 158.294624 -391.529154) (xy 158.343589 -391.541554) (xy 158.389845 -391.561844)
			(xy 158.432131 -391.58947) (xy 158.469293 -391.62368) (xy 158.500317 -391.66354) (xy 158.524358 -391.707963)
			(xy 158.540759 -391.755737) (xy 158.549072 -391.805559) (xy 158.549594 -391.830814) (xy 158.549127 -391.855187)
			(xy 158.541366 -391.903311) (xy 158.526046 -391.949587) (xy 158.503555 -391.992834) (xy 158.489396 -392.012678)
			(xy 158.483808 -392.020552) (xy 158.478728 -392.038332) (xy 158.48711 -392.124946) (xy 158.495238 -392.14171)
			(xy 158.50235 -392.14806) (xy 158.521484 -392.166194) (xy 158.555072 -392.206825) (xy 158.582743 -392.251694)
			(xy 158.603971 -392.299948) (xy 158.618349 -392.350665) (xy 158.625605 -392.40288) (xy 158.626048 -392.429238)
			(xy 158.626048 -393.292838) (xy 159.062928 -393.292838) (xy 159.062928 -392.429238) (xy 159.063351 -392.402921)
			(xy 159.070576 -392.350785) (xy 159.084894 -392.300136) (xy 159.106034 -392.251934) (xy 159.133595 -392.207093)
			(xy 159.167055 -392.166463) (xy 159.186118 -392.148314) (xy 159.19323 -392.14171) (xy 159.201612 -392.1252)
			(xy 159.20974 -392.038332) (xy 159.20466 -392.020552) (xy 159.199072 -392.012932) (xy 159.184913 -391.993052)
			(xy 159.162427 -391.949737) (xy 159.14711 -391.903399) (xy 159.139352 -391.855216) (xy 159.138874 -391.830814)
			(xy 159.139396 -391.805559) (xy 159.147709 -391.755737) (xy 159.16411 -391.707963) (xy 159.188151 -391.66354)
			(xy 159.219175 -391.62368) (xy 159.256337 -391.58947) (xy 159.298623 -391.561844) (xy 159.344879 -391.541554)
			(xy 159.393844 -391.529154) (xy 159.444182 -391.524983) (xy 159.49452 -391.529154) (xy 159.543485 -391.541554)
			(xy 159.589741 -391.561844) (xy 159.632027 -391.58947) (xy 159.669189 -391.62368) (xy 159.700213 -391.66354)
			(xy 159.724254 -391.707963) (xy 159.740655 -391.755737) (xy 159.748968 -391.805559) (xy 159.74949 -391.830814)
			(xy 159.749004 -391.855173) (xy 159.74129 -391.903276) (xy 159.726044 -391.949546) (xy 159.703651 -391.992813)
			(xy 159.689546 -392.012678) (xy 159.683704 -392.020298) (xy 159.678878 -392.038078) (xy 159.687006 -392.124946)
			(xy 159.695388 -392.141456) (xy 159.7025 -392.14806) (xy 159.721624 -392.166192) (xy 159.755168 -392.206837)
			(xy 159.782795 -392.251715) (xy 159.803976 -392.299971) (xy 159.81831 -392.350684) (xy 159.825522 -392.402888)
			(xy 159.825944 -392.429238) (xy 159.825944 -393.292838) (xy 160.262824 -393.292838) (xy 160.262824 -392.429238)
			(xy 160.26327 -392.402891) (xy 160.2705 -392.350695) (xy 160.284842 -392.299991) (xy 160.306023 -392.251741)
			(xy 160.333639 -392.206864) (xy 160.367167 -392.166213) (xy 160.386268 -392.14806) (xy 160.39338 -392.14171)
			(xy 160.401508 -392.124946) (xy 160.40989 -392.038332) (xy 160.40481 -392.020552) (xy 160.399222 -392.012678)
			(xy 160.385068 -391.992834) (xy 160.362612 -391.949574) (xy 160.347301 -391.9033) (xy 160.339522 -391.855184)
			(xy 160.339024 -391.830814) (xy 160.339546 -391.805559) (xy 160.347859 -391.755737) (xy 160.36426 -391.707963)
			(xy 160.388301 -391.66354) (xy 160.419325 -391.62368) (xy 160.456487 -391.58947) (xy 160.498773 -391.561844)
			(xy 160.545029 -391.541554) (xy 160.593994 -391.529154) (xy 160.644332 -391.524983) (xy 160.69467 -391.529154)
			(xy 160.743635 -391.541554) (xy 160.789891 -391.561844) (xy 160.832177 -391.58947) (xy 160.869339 -391.62368)
			(xy 160.900363 -391.66354) (xy 160.924404 -391.707963) (xy 160.940805 -391.755737) (xy 160.949118 -391.805559)
			(xy 160.94964 -391.830814) (xy 160.949164 -391.855186) (xy 160.941405 -391.90331) (xy 160.926086 -391.949585)
			(xy 160.903599 -391.992833) (xy 160.889442 -392.012678) (xy 160.883854 -392.020552) (xy 160.878774 -392.038332)
			(xy 160.887156 -392.124946) (xy 160.895284 -392.14171) (xy 160.902396 -392.14806) (xy 160.921519 -392.166193)
			(xy 160.955064 -392.206838) (xy 160.98269 -392.251716) (xy 161.003872 -392.299971) (xy 161.018206 -392.350684)
			(xy 161.025418 -392.402888) (xy 161.02584 -392.429238) (xy 161.02584 -393.292838) (xy 161.46272 -393.292838)
			(xy 161.46272 -392.429238) (xy 161.463167 -392.402891) (xy 161.470397 -392.350696) (xy 161.484739 -392.299991)
			(xy 161.505919 -392.251741) (xy 161.533536 -392.206864) (xy 161.567063 -392.166213) (xy 161.586164 -392.14806)
			(xy 161.593276 -392.14171) (xy 161.601404 -392.124946) (xy 161.609786 -392.038332) (xy 161.604706 -392.020552)
			(xy 161.599118 -392.012678) (xy 161.584964 -391.992834) (xy 161.562508 -391.949574) (xy 161.547197 -391.9033)
			(xy 161.539418 -391.855184) (xy 161.53892 -391.830814) (xy 161.539442 -391.805559) (xy 161.547755 -391.755737)
			(xy 161.564156 -391.707963) (xy 161.588197 -391.66354) (xy 161.619221 -391.62368) (xy 161.656383 -391.58947)
			(xy 161.698669 -391.561844) (xy 161.744925 -391.541554) (xy 161.79389 -391.529154) (xy 161.844228 -391.524983)
			(xy 161.894566 -391.529154) (xy 161.943531 -391.541554) (xy 161.989787 -391.561844) (xy 162.032073 -391.58947)
			(xy 162.069235 -391.62368) (xy 162.100259 -391.66354) (xy 162.1243 -391.707963) (xy 162.140701 -391.755737)
			(xy 162.149014 -391.805559) (xy 162.149536 -391.830814) (xy 162.14906 -391.855186) (xy 162.141301 -391.90331)
			(xy 162.125983 -391.949585) (xy 162.103496 -391.992833) (xy 162.089338 -392.012678) (xy 162.08375 -392.020552)
			(xy 162.07867 -392.038332) (xy 162.087052 -392.124946) (xy 162.09518 -392.14171) (xy 162.102292 -392.14806)
			(xy 162.121414 -392.166194) (xy 162.154959 -392.206838) (xy 162.182586 -392.251716) (xy 162.203768 -392.299971)
			(xy 162.218102 -392.350684) (xy 162.225314 -392.402888) (xy 162.225736 -392.429238) (xy 162.225736 -393.292838)
			(xy 162.662616 -393.292838) (xy 162.662616 -392.429238) (xy 162.663065 -392.402891) (xy 162.670295 -392.350696)
			(xy 162.684636 -392.299991) (xy 162.705816 -392.251742) (xy 162.733432 -392.206864) (xy 162.76696 -392.166213)
			(xy 162.78606 -392.14806) (xy 162.793172 -392.14171) (xy 162.8013 -392.124946) (xy 162.809682 -392.038332)
			(xy 162.804602 -392.020552) (xy 162.799014 -392.012678) (xy 162.784859 -391.992834) (xy 162.762404 -391.949574)
			(xy 162.747093 -391.9033) (xy 162.739314 -391.855184) (xy 162.738816 -391.830814) (xy 162.739338 -391.805559)
			(xy 162.747651 -391.755737) (xy 162.764052 -391.707963) (xy 162.788093 -391.66354) (xy 162.819117 -391.62368)
			(xy 162.856279 -391.58947) (xy 162.898565 -391.561844) (xy 162.944821 -391.541554) (xy 162.993786 -391.529154)
			(xy 163.044124 -391.524983) (xy 163.094462 -391.529154) (xy 163.143427 -391.541554) (xy 163.189683 -391.561844)
			(xy 163.231969 -391.58947) (xy 163.269131 -391.62368) (xy 163.300155 -391.66354) (xy 163.324196 -391.707963)
			(xy 163.340597 -391.755737) (xy 163.34891 -391.805559) (xy 163.349432 -391.830814) (xy 163.348957 -391.855186)
			(xy 163.341198 -391.90331) (xy 163.325879 -391.949585) (xy 163.303392 -391.992833) (xy 163.289234 -392.012678)
			(xy 163.283646 -392.020552) (xy 163.278566 -392.038332) (xy 163.286948 -392.124946) (xy 163.295076 -392.14171)
			(xy 163.302188 -392.14806) (xy 163.32131 -392.166194) (xy 163.354855 -392.206839) (xy 163.382482 -392.251716)
			(xy 163.403664 -392.299972) (xy 163.417998 -392.350684) (xy 163.42521 -392.402888) (xy 163.425632 -392.429238)
			(xy 163.425632 -393.292838) (xy 163.862512 -393.292838) (xy 163.862512 -392.429238) (xy 163.863001 -392.402883)
			(xy 163.870263 -392.350675) (xy 163.884641 -392.299963) (xy 163.905861 -392.251713) (xy 163.933519 -392.206841)
			(xy 163.967089 -392.166203) (xy 163.98621 -392.14806) (xy 163.993322 -392.14171) (xy 164.00145 -392.124946)
			(xy 164.009832 -392.038332) (xy 164.004752 -392.020552) (xy 163.999164 -392.012678) (xy 163.985015 -391.99283)
			(xy 163.962557 -391.949572) (xy 163.947244 -391.903299) (xy 163.939464 -391.855184) (xy 163.938966 -391.830814)
			(xy 163.939488 -391.805559) (xy 163.947801 -391.755737) (xy 163.964202 -391.707963) (xy 163.988243 -391.66354)
			(xy 164.019267 -391.62368) (xy 164.056429 -391.58947) (xy 164.098715 -391.561844) (xy 164.144971 -391.541554)
			(xy 164.193936 -391.529154) (xy 164.244274 -391.524983) (xy 164.294612 -391.529154) (xy 164.343577 -391.541554)
			(xy 164.389833 -391.561844) (xy 164.432119 -391.58947) (xy 164.469281 -391.62368) (xy 164.500305 -391.66354)
			(xy 164.524346 -391.707963) (xy 164.540747 -391.755737) (xy 164.54906 -391.805559) (xy 164.549582 -391.830814)
			(xy 164.549117 -391.855187) (xy 164.541356 -391.903311) (xy 164.526035 -391.949587) (xy 164.503544 -391.992834)
			(xy 164.489384 -392.012678) (xy 164.483796 -392.020552) (xy 164.478716 -392.038332) (xy 164.487098 -392.124946)
			(xy 164.495226 -392.14171) (xy 164.502338 -392.14806) (xy 164.52147 -392.166196) (xy 164.555058 -392.206826)
			(xy 164.58273 -392.251695) (xy 164.603958 -392.299948) (xy 164.618337 -392.350666) (xy 164.625593 -392.40288)
			(xy 164.626036 -392.429238) (xy 164.626036 -393.292838) (xy 165.062408 -393.292838) (xy 165.062408 -392.429238)
			(xy 165.062866 -392.402881) (xy 165.07013 -392.350671) (xy 165.084512 -392.299957) (xy 165.105737 -392.251706)
			(xy 165.133402 -392.206836) (xy 165.16698 -392.166201) (xy 165.186106 -392.14806) (xy 165.193218 -392.14171)
			(xy 165.201346 -392.124946) (xy 165.209728 -392.038332) (xy 165.204648 -392.020552) (xy 165.19906 -392.012678)
			(xy 165.184911 -391.99283) (xy 165.162453 -391.949572) (xy 165.14714 -391.903299) (xy 165.13936 -391.855184)
			(xy 165.138862 -391.830814) (xy 165.139384 -391.805559) (xy 165.147697 -391.755737) (xy 165.164098 -391.707963)
			(xy 165.188139 -391.66354) (xy 165.219163 -391.62368) (xy 165.256325 -391.58947) (xy 165.298611 -391.561844)
			(xy 165.344867 -391.541554) (xy 165.393832 -391.529154) (xy 165.44417 -391.524983) (xy 165.494508 -391.529154)
			(xy 165.543473 -391.541554) (xy 165.589729 -391.561844) (xy 165.632015 -391.58947) (xy 165.669177 -391.62368)
			(xy 165.700201 -391.66354) (xy 165.724242 -391.707963) (xy 165.740643 -391.755737) (xy 165.748956 -391.805559)
			(xy 165.749478 -391.830814) (xy 165.749014 -391.855187) (xy 165.741253 -391.903311) (xy 165.725932 -391.949587)
			(xy 165.70344 -391.992834) (xy 165.68928 -392.012678) (xy 165.683692 -392.020552) (xy 165.678612 -392.038332)
			(xy 165.686994 -392.124946) (xy 165.695122 -392.14171) (xy 165.702234 -392.14806) (xy 165.721365 -392.166197)
			(xy 165.754954 -392.206827) (xy 165.782626 -392.251696) (xy 165.803854 -392.299949) (xy 165.818233 -392.350666)
			(xy 165.825489 -392.40288) (xy 165.825932 -392.429238) (xy 165.825932 -393.0015) (xy 165.826569 -393.014106)
			(xy 165.838432 -393.036354) (xy 165.848538 -393.043918) (xy 165.930072 -393.097766) (xy 165.955472 -393.100052)
			(xy 165.96741 -393.094972) (xy 165.991187 -393.08526) (xy 166.040696 -393.071593) (xy 166.09159 -393.064675)
			(xy 166.11727 -393.064238) (xy 166.144528 -393.064607) (xy 166.198488 -393.072361) (xy 166.250796 -393.087717)
			(xy 166.300386 -393.11036) (xy 166.346249 -393.139831) (xy 166.38745 -393.175529) (xy 166.423151 -393.216727)
			(xy 166.452625 -393.262588) (xy 166.475273 -393.312176) (xy 166.490632 -393.364482) (xy 166.498391 -393.418442)
			(xy 166.498391 -393.472958) (xy 166.490632 -393.526918) (xy 166.475273 -393.579224) (xy 166.452625 -393.628812)
			(xy 166.423151 -393.674673) (xy 166.38745 -393.715871) (xy 166.346249 -393.751569) (xy 166.300386 -393.78104)
			(xy 166.250796 -393.803683) (xy 166.198488 -393.819039) (xy 166.144528 -393.826793) (xy 166.11727 -393.827254)
			(xy 166.09218 -393.826856) (xy 166.042434 -393.820274) (xy 165.993979 -393.807228) (xy 165.947653 -393.787943)
			(xy 165.925754 -393.775692) (xy 165.913308 -393.768326) (xy 165.885114 -393.769088) (xy 165.784784 -393.833096)
			(xy 165.772338 -393.858242) (xy 165.773608 -393.87272) (xy 165.774878 -393.902438) (xy 165.774368 -393.928425)
			(xy 165.766238 -393.97976) (xy 165.750177 -394.02919) (xy 165.726581 -394.0755) (xy 165.696031 -394.117548)
			(xy 165.65928 -394.154299) (xy 165.617232 -394.184849) (xy 165.570922 -394.208445) (xy 165.521492 -394.224506)
			(xy 165.470157 -394.232636) (xy 165.418183 -394.232636) (xy 165.366848 -394.224506) (xy 165.317418 -394.208445)
			(xy 165.271108 -394.184849) (xy 165.22906 -394.154299) (xy 165.192309 -394.117548) (xy 165.161759 -394.0755)
			(xy 165.138163 -394.02919) (xy 165.122102 -393.97976) (xy 165.113972 -393.928425) (xy 165.113462 -393.902438)
			(xy 165.114023 -393.874948) (xy 165.123098 -393.820723) (xy 165.14102 -393.768746) (xy 165.167297 -393.720453)
			(xy 165.18382 -393.698476) (xy 165.189662 -393.69111) (xy 165.194996 -393.67333) (xy 165.189662 -393.587224)
			(xy 165.182042 -393.57046) (xy 165.175438 -393.563856) (xy 165.154388 -393.542248) (xy 165.118745 -393.493581)
			(xy 165.091207 -393.43991) (xy 165.072461 -393.382573) (xy 165.062975 -393.323) (xy 165.062408 -393.292838)
			(xy 164.626036 -393.292838) (xy 164.625609 -393.319012) (xy 164.618413 -393.370864) (xy 164.6042 -393.421247)
			(xy 164.583239 -393.469216) (xy 164.555922 -393.513872) (xy 164.522761 -393.554378) (xy 164.503862 -393.572492)
			(xy 164.496496 -393.57935) (xy 164.488368 -393.596876) (xy 164.483034 -393.687046) (xy 164.48913 -393.705334)
			(xy 164.495734 -393.712954) (xy 164.510639 -393.730994) (xy 164.535702 -393.770513) (xy 164.554948 -393.813169)
			(xy 164.567994 -393.858109) (xy 164.57458 -393.90444) (xy 164.574982 -393.927838) (xy 164.574472 -393.953825)
			(xy 164.566342 -394.00516) (xy 164.550281 -394.05459) (xy 164.526685 -394.1009) (xy 164.496135 -394.142948)
			(xy 164.459384 -394.179699) (xy 164.417336 -394.210249) (xy 164.371026 -394.233845) (xy 164.321596 -394.249906)
			(xy 164.270261 -394.258036) (xy 164.218287 -394.258036) (xy 164.166952 -394.249906) (xy 164.117522 -394.233845)
			(xy 164.071212 -394.210249) (xy 164.029164 -394.179699) (xy 163.992413 -394.142948) (xy 163.961863 -394.1009)
			(xy 163.938267 -394.05459) (xy 163.922206 -394.00516) (xy 163.914076 -393.953825) (xy 163.913566 -393.927838)
			(xy 163.913987 -393.904441) (xy 163.920574 -393.858114) (xy 163.933621 -393.813177) (xy 163.952868 -393.770526)
			(xy 163.977932 -393.731011) (xy 163.992814 -393.712954) (xy 163.999418 -393.705334) (xy 164.005514 -393.687046)
			(xy 164.00018 -393.596876) (xy 163.992052 -393.57935) (xy 163.984686 -393.572492) (xy 163.965787 -393.554378)
			(xy 163.932624 -393.513874) (xy 163.905308 -393.469218) (xy 163.884351 -393.421248) (xy 163.870146 -393.370864)
			(xy 163.86296 -393.319012) (xy 163.862512 -393.292838) (xy 163.425632 -393.292838) (xy 163.425181 -393.319002)
			(xy 163.41803 -393.370838) (xy 163.403867 -393.421213) (xy 163.382957 -393.469181) (xy 163.355693 -393.513844)
			(xy 163.322585 -393.554366) (xy 163.303712 -393.572492) (xy 163.296346 -393.57935) (xy 163.288218 -393.596876)
			(xy 163.282884 -393.687046) (xy 163.28898 -393.705334) (xy 163.295584 -393.712954) (xy 163.310482 -393.731)
			(xy 163.335547 -393.770517) (xy 163.354795 -393.813171) (xy 163.367843 -393.85811) (xy 163.37443 -393.90444)
			(xy 163.374832 -393.927838) (xy 163.374322 -393.953825) (xy 163.366192 -394.00516) (xy 163.350131 -394.05459)
			(xy 163.326535 -394.1009) (xy 163.295985 -394.142948) (xy 163.259234 -394.179699) (xy 163.217186 -394.210249)
			(xy 163.170876 -394.233845) (xy 163.121446 -394.249906) (xy 163.070111 -394.258036) (xy 163.018137 -394.258036)
			(xy 162.966802 -394.249906) (xy 162.917372 -394.233845) (xy 162.871062 -394.210249) (xy 162.829014 -394.179699)
			(xy 162.792263 -394.142948) (xy 162.761713 -394.1009) (xy 162.738117 -394.05459) (xy 162.722056 -394.00516)
			(xy 162.713926 -393.953825) (xy 162.713416 -393.927838) (xy 162.713849 -393.904442) (xy 162.720434 -393.858116)
			(xy 162.733479 -393.813179) (xy 162.752724 -393.770528) (xy 162.777784 -393.731012) (xy 162.792664 -393.712954)
			(xy 162.799268 -393.705334) (xy 162.805364 -393.687046) (xy 162.80003 -393.596876) (xy 162.791902 -393.57935)
			(xy 162.784536 -393.572492) (xy 162.765648 -393.554379) (xy 162.732529 -393.513861) (xy 162.705258 -393.469197)
			(xy 162.684346 -393.421225) (xy 162.670186 -393.370846) (xy 162.663043 -393.319004) (xy 162.662616 -393.292838)
			(xy 162.225736 -393.292838) (xy 162.225202 -393.321743) (xy 162.216497 -393.378893) (xy 162.199276 -393.434077)
			(xy 162.173933 -393.486035) (xy 162.141048 -393.533579) (xy 162.121596 -393.554966) (xy 162.1155 -393.56157)
			(xy 162.108388 -393.577572) (xy 162.1028 -393.659868) (xy 162.107626 -393.676886) (xy 162.112706 -393.683998)
			(xy 162.127349 -393.705223) (xy 162.150599 -393.751246) (xy 162.166423 -393.800321) (xy 162.174437 -393.851257)
			(xy 162.174936 -393.877038) (xy 162.174426 -393.903025) (xy 162.166296 -393.95436) (xy 162.150235 -394.00379)
			(xy 162.126639 -394.0501) (xy 162.096089 -394.092148) (xy 162.059338 -394.128899) (xy 162.01729 -394.159449)
			(xy 161.97098 -394.183045) (xy 161.92155 -394.199106) (xy 161.870215 -394.207236) (xy 161.818241 -394.207236)
			(xy 161.766906 -394.199106) (xy 161.717476 -394.183045) (xy 161.671166 -394.159449) (xy 161.629118 -394.128899)
			(xy 161.592367 -394.092148) (xy 161.561817 -394.0501) (xy 161.538221 -394.00379) (xy 161.52216 -393.95436)
			(xy 161.51403 -393.903025) (xy 161.51352 -393.877038) (xy 161.513989 -393.851254) (xy 161.521997 -393.800313)
			(xy 161.537824 -393.751234) (xy 161.561087 -393.705212) (xy 161.57575 -393.683998) (xy 161.58083 -393.676886)
			(xy 161.585656 -393.659868) (xy 161.580068 -393.577572) (xy 161.572956 -393.56157) (xy 161.56686 -393.554966)
			(xy 161.54737 -393.533609) (xy 161.514465 -393.486069) (xy 161.489116 -393.434106) (xy 161.471905 -393.378909)
			(xy 161.463228 -393.321747) (xy 161.46272 -393.292838) (xy 161.02584 -393.292838) (xy 161.025386 -393.319002)
			(xy 161.018235 -393.370838) (xy 161.004073 -393.421212) (xy 160.983164 -393.46918) (xy 160.9559 -393.513844)
			(xy 160.922793 -393.554366) (xy 160.90392 -393.572492) (xy 160.896554 -393.57935) (xy 160.888426 -393.596876)
			(xy 160.883092 -393.687046) (xy 160.889188 -393.705334) (xy 160.895792 -393.712954) (xy 160.910691 -393.730999)
			(xy 160.935756 -393.770516) (xy 160.955004 -393.81317) (xy 160.968051 -393.85811) (xy 160.974638 -393.90444)
			(xy 160.97504 -393.927838) (xy 160.97453 -393.953825) (xy 160.9664 -394.00516) (xy 160.950339 -394.05459)
			(xy 160.926743 -394.1009) (xy 160.896193 -394.142948) (xy 160.859442 -394.179699) (xy 160.817394 -394.210249)
			(xy 160.771084 -394.233845) (xy 160.721654 -394.249906) (xy 160.670319 -394.258036) (xy 160.618345 -394.258036)
			(xy 160.56701 -394.249906) (xy 160.51758 -394.233845) (xy 160.47127 -394.210249) (xy 160.429222 -394.179699)
			(xy 160.392471 -394.142948) (xy 160.361921 -394.1009) (xy 160.338325 -394.05459) (xy 160.322264 -394.00516)
			(xy 160.314134 -393.953825) (xy 160.313624 -393.927838) (xy 160.314055 -393.904442) (xy 160.320641 -393.858116)
			(xy 160.333686 -393.813179) (xy 160.352931 -393.770528) (xy 160.377991 -393.731012) (xy 160.392872 -393.712954)
			(xy 160.399476 -393.705334) (xy 160.405572 -393.687046) (xy 160.400238 -393.596876) (xy 160.39211 -393.57935)
			(xy 160.384744 -393.572492) (xy 160.365858 -393.554377) (xy 160.332738 -393.51386) (xy 160.305467 -393.469196)
			(xy 160.284554 -393.421225) (xy 160.270394 -393.370845) (xy 160.263251 -393.319004) (xy 160.262824 -393.292838)
			(xy 159.825944 -393.292838) (xy 159.825489 -393.319002) (xy 159.818338 -393.370838) (xy 159.804176 -393.421212)
			(xy 159.783267 -393.46918) (xy 159.756004 -393.513844) (xy 159.722896 -393.554366) (xy 159.704024 -393.572492)
			(xy 159.696658 -393.57935) (xy 159.68853 -393.596876) (xy 159.683196 -393.687046) (xy 159.689292 -393.705334)
			(xy 159.695896 -393.712954) (xy 159.710795 -393.730999) (xy 159.73586 -393.770516) (xy 159.755108 -393.81317)
			(xy 159.768155 -393.85811) (xy 159.774742 -393.90444) (xy 159.775144 -393.927838) (xy 159.774634 -393.953825)
			(xy 159.766504 -394.00516) (xy 159.750443 -394.05459) (xy 159.726847 -394.1009) (xy 159.696297 -394.142948)
			(xy 159.659546 -394.179699) (xy 159.617498 -394.210249) (xy 159.571188 -394.233845) (xy 159.521758 -394.249906)
			(xy 159.470423 -394.258036) (xy 159.418449 -394.258036) (xy 159.367114 -394.249906) (xy 159.317684 -394.233845)
			(xy 159.271374 -394.210249) (xy 159.229326 -394.179699) (xy 159.192575 -394.142948) (xy 159.162025 -394.1009)
			(xy 159.138429 -394.05459) (xy 159.122368 -394.00516) (xy 159.114238 -393.953825) (xy 159.113728 -393.927838)
			(xy 159.114158 -393.904442) (xy 159.120744 -393.858116) (xy 159.133789 -393.813179) (xy 159.153034 -393.770527)
			(xy 159.178095 -393.731012) (xy 159.192976 -393.712954) (xy 159.19958 -393.705334) (xy 159.205676 -393.687046)
			(xy 159.200342 -393.596876) (xy 159.192214 -393.57935) (xy 159.184848 -393.572492) (xy 159.165963 -393.554377)
			(xy 159.132843 -393.513859) (xy 159.105571 -393.469196) (xy 159.084659 -393.421224) (xy 159.070498 -393.370845)
			(xy 159.063355 -393.319004) (xy 159.062928 -393.292838) (xy 158.626048 -393.292838) (xy 158.625618 -393.319012)
			(xy 158.618421 -393.370863) (xy 158.604209 -393.421246) (xy 158.583249 -393.469215) (xy 158.555932 -393.513871)
			(xy 158.522772 -393.554377) (xy 158.503874 -393.572492) (xy 158.496508 -393.57935) (xy 158.48838 -393.596876)
			(xy 158.483046 -393.687046) (xy 158.489142 -393.705334) (xy 158.495746 -393.712954) (xy 158.510653 -393.730993)
			(xy 158.535715 -393.770512) (xy 158.55496 -393.813168) (xy 158.568006 -393.858109) (xy 158.574592 -393.90444)
			(xy 158.574994 -393.927838) (xy 158.574484 -393.953825) (xy 158.566354 -394.00516) (xy 158.550293 -394.05459)
			(xy 158.526697 -394.1009) (xy 158.496147 -394.142948) (xy 158.459396 -394.179699) (xy 158.417348 -394.210249)
			(xy 158.371038 -394.233845) (xy 158.321608 -394.249906) (xy 158.270273 -394.258036) (xy 158.218299 -394.258036)
			(xy 158.166964 -394.249906) (xy 158.117534 -394.233845) (xy 158.071224 -394.210249) (xy 158.029176 -394.179699)
			(xy 157.992425 -394.142948) (xy 157.961875 -394.1009) (xy 157.938279 -394.05459) (xy 157.922218 -394.00516)
			(xy 157.914088 -393.953825) (xy 157.913578 -393.927838) (xy 157.913996 -393.904441) (xy 157.920583 -393.858114)
			(xy 157.93363 -393.813177) (xy 157.952878 -393.770525) (xy 157.977943 -393.731011) (xy 157.992826 -393.712954)
			(xy 157.99943 -393.705334) (xy 158.005526 -393.687046) (xy 158.000192 -393.596876) (xy 157.992064 -393.57935)
			(xy 157.984698 -393.572492) (xy 157.965801 -393.554376) (xy 157.932638 -393.513873) (xy 157.905321 -393.469218)
			(xy 157.884364 -393.421248) (xy 157.870158 -393.370864) (xy 157.862972 -393.319012) (xy 157.862524 -393.292838)
			(xy 157.426152 -393.292838) (xy 157.42572 -393.319012) (xy 157.418524 -393.370863) (xy 157.404312 -393.421246)
			(xy 157.383352 -393.469215) (xy 157.356036 -393.513871) (xy 157.322876 -393.554377) (xy 157.303978 -393.572492)
			(xy 157.296612 -393.57935) (xy 157.288484 -393.596876) (xy 157.28315 -393.687046) (xy 157.289246 -393.705334)
			(xy 157.29585 -393.712954) (xy 157.310758 -393.730992) (xy 157.335819 -393.770512) (xy 157.355065 -393.813168)
			(xy 157.36811 -393.858109) (xy 157.374696 -393.90444) (xy 157.375098 -393.927838) (xy 157.374588 -393.953825)
			(xy 157.366458 -394.00516) (xy 157.350397 -394.05459) (xy 157.326801 -394.1009) (xy 157.296251 -394.142948)
			(xy 157.2595 -394.179699) (xy 157.217452 -394.210249) (xy 157.171142 -394.233845) (xy 157.121712 -394.249906)
			(xy 157.070377 -394.258036) (xy 157.018403 -394.258036) (xy 156.967068 -394.249906) (xy 156.917638 -394.233845)
			(xy 156.871328 -394.210249) (xy 156.82928 -394.179699) (xy 156.792529 -394.142948) (xy 156.761979 -394.1009)
			(xy 156.738383 -394.05459) (xy 156.722322 -394.00516) (xy 156.714192 -393.953825) (xy 156.713682 -393.927838)
			(xy 156.714123 -393.904442) (xy 156.720708 -393.858117) (xy 156.733751 -393.813181) (xy 156.752993 -393.770529)
			(xy 156.778051 -393.731013) (xy 156.79293 -393.712954) (xy 156.799534 -393.705334) (xy 156.80563 -393.687046)
			(xy 156.800296 -393.596876) (xy 156.792168 -393.57935) (xy 156.784802 -393.572492) (xy 156.765906 -393.554375)
			(xy 156.732743 -393.513872) (xy 156.705426 -393.469217) (xy 156.684468 -393.421248) (xy 156.670262 -393.370864)
			(xy 156.663076 -393.319012) (xy 156.662628 -393.292838) (xy 156.225748 -393.292838) (xy 156.225191 -393.322987)
			(xy 156.215735 -393.382538) (xy 156.197032 -393.439862) (xy 156.169548 -393.493532) (xy 156.133967 -393.542212)
			(xy 156.112972 -393.563856) (xy 156.106368 -393.57046) (xy 156.098748 -393.587224) (xy 156.093414 -393.67333)
			(xy 156.098748 -393.69111) (xy 156.10459 -393.698476) (xy 156.121101 -393.720461) (xy 156.147374 -393.768756)
			(xy 156.165304 -393.820728) (xy 156.1744 -393.874949) (xy 156.174948 -393.902438) (xy 156.174438 -393.928425)
			(xy 156.166308 -393.97976) (xy 156.150247 -394.02919) (xy 156.126651 -394.0755) (xy 156.096101 -394.117548)
			(xy 156.05935 -394.154299) (xy 156.017302 -394.184849) (xy 155.970992 -394.208445) (xy 155.921562 -394.224506)
			(xy 155.870227 -394.232636) (xy 155.818253 -394.232636) (xy 155.766918 -394.224506) (xy 155.717488 -394.208445)
			(xy 155.671178 -394.184849) (xy 155.62913 -394.154299) (xy 155.592379 -394.117548) (xy 155.561829 -394.0755)
			(xy 155.538233 -394.02919) (xy 155.522172 -393.97976) (xy 155.514042 -393.928425) (xy 155.513532 -393.902438)
			(xy 155.514078 -393.874947) (xy 155.523155 -393.82072) (xy 155.541082 -393.768744) (xy 155.567364 -393.720451)
			(xy 155.58389 -393.698476) (xy 155.589732 -393.69111) (xy 155.595066 -393.67333) (xy 155.589732 -393.587224)
			(xy 155.582112 -393.57046) (xy 155.575508 -393.563856) (xy 155.554514 -393.542209) (xy 155.518922 -393.493535)
			(xy 155.491432 -393.439867) (xy 155.47273 -393.382542) (xy 155.463282 -393.322988) (xy 155.462732 -393.292838)
			(xy 155.025852 -393.292838) (xy 155.025314 -393.321742) (xy 155.016609 -393.378892) (xy 154.999389 -393.434076)
			(xy 154.974047 -393.486034) (xy 154.941163 -393.533579) (xy 154.921712 -393.554966) (xy 154.915616 -393.56157)
			(xy 154.908504 -393.577572) (xy 154.902916 -393.659868) (xy 154.907742 -393.676886) (xy 154.912822 -393.683998)
			(xy 154.927455 -393.70523) (xy 154.95071 -393.75125) (xy 154.966537 -393.800322) (xy 154.974553 -393.851257)
			(xy 154.975052 -393.877038) (xy 154.974542 -393.903025) (xy 154.966412 -393.95436) (xy 154.950351 -394.00379)
			(xy 154.926755 -394.0501) (xy 154.896205 -394.092148) (xy 154.859454 -394.128899) (xy 154.817406 -394.159449)
			(xy 154.771096 -394.183045) (xy 154.721666 -394.199106) (xy 154.670331 -394.207236) (xy 154.618357 -394.207236)
			(xy 154.567022 -394.199106) (xy 154.517592 -394.183045) (xy 154.471282 -394.159449) (xy 154.429234 -394.128899)
			(xy 154.392483 -394.092148) (xy 154.361933 -394.0501) (xy 154.338337 -394.00379) (xy 154.322276 -393.95436)
			(xy 154.314146 -393.903025) (xy 154.313636 -393.877038) (xy 154.31412 -393.851255) (xy 154.322126 -393.800315)
			(xy 154.337949 -393.751237) (xy 154.361206 -393.705213) (xy 154.375866 -393.683998) (xy 154.380946 -393.676886)
			(xy 154.385772 -393.659868) (xy 154.380184 -393.577572) (xy 154.373072 -393.56157) (xy 154.366976 -393.554966)
			(xy 154.347489 -393.533607) (xy 154.314582 -393.486068) (xy 154.289233 -393.434105) (xy 154.272021 -393.378909)
			(xy 154.263344 -393.321747) (xy 154.262836 -393.292838) (xy 153.825956 -393.292838) (xy 153.825524 -393.319012)
			(xy 153.818327 -393.370863) (xy 153.804116 -393.421246) (xy 153.783156 -393.469215) (xy 153.75584 -393.513871)
			(xy 153.72268 -393.554378) (xy 153.703782 -393.572492) (xy 153.696416 -393.57935) (xy 153.688288 -393.596876)
			(xy 153.682954 -393.687046) (xy 153.68905 -393.705334) (xy 153.695654 -393.712954) (xy 153.710547 -393.731004)
			(xy 153.735614 -393.770519) (xy 153.754864 -393.813172) (xy 153.767913 -393.858111) (xy 153.7745 -393.90444)
			(xy 153.774902 -393.927838) (xy 153.774392 -393.953825) (xy 153.766262 -394.00516) (xy 153.750201 -394.05459)
			(xy 153.726605 -394.1009) (xy 153.696055 -394.142948) (xy 153.659304 -394.179699) (xy 153.617256 -394.210249)
			(xy 153.570946 -394.233845) (xy 153.521516 -394.249906) (xy 153.470181 -394.258036) (xy 153.418207 -394.258036)
			(xy 153.366872 -394.249906) (xy 153.317442 -394.233845) (xy 153.271132 -394.210249) (xy 153.229084 -394.179699)
			(xy 153.192333 -394.142948) (xy 153.161783 -394.1009) (xy 153.138187 -394.05459) (xy 153.122126 -394.00516)
			(xy 153.113996 -393.953825) (xy 153.113486 -393.927838) (xy 153.113926 -393.904442) (xy 153.120511 -393.858117)
			(xy 153.133554 -393.81318) (xy 153.152797 -393.770529) (xy 153.177855 -393.731013) (xy 153.192734 -393.712954)
			(xy 153.199338 -393.705334) (xy 153.205434 -393.687046) (xy 153.2001 -393.596876) (xy 153.191972 -393.57935)
			(xy 153.184606 -393.572492) (xy 153.165711 -393.554375) (xy 153.132547 -393.513872) (xy 153.10523 -393.469217)
			(xy 153.084272 -393.421247) (xy 153.070066 -393.370864) (xy 153.06288 -393.319012) (xy 153.062432 -393.292838)
			(xy 152.62606 -393.292838) (xy 152.625612 -393.319012) (xy 152.618426 -393.370864) (xy 152.60422 -393.421247)
			(xy 152.583261 -393.469216) (xy 152.555944 -393.513871) (xy 152.52278 -393.554373) (xy 152.503886 -393.572492)
			(xy 152.49652 -393.57935) (xy 152.488392 -393.596876) (xy 152.483058 -393.687046) (xy 152.489154 -393.705334)
			(xy 152.495758 -393.712954) (xy 152.510638 -393.731013) (xy 152.535696 -393.770529) (xy 152.554939 -393.81318)
			(xy 152.567983 -393.858117) (xy 152.574568 -393.904442) (xy 152.575006 -393.927838) (xy 152.574396 -393.956918)
			(xy 152.564214 -394.01418) (xy 152.544155 -394.068771) (xy 152.530048 -394.094208) (xy 152.524206 -394.104368)
			(xy 152.522428 -394.127482) (xy 152.55621 -394.212572) (xy 152.560993 -394.223113) (xy 152.578049 -394.238729)
			(xy 152.588976 -394.242544) (xy 154.435556 -394.792962) (xy 154.439097 -394.793927) (xy 154.446364 -394.794948)
			(xy 154.450034 -394.794994) (xy 166.505382 -394.794994) (xy 166.514185 -394.794564) (xy 166.530721 -394.788505)
			(xy 166.544248 -394.777228) (xy 166.54907 -394.769848) (xy 166.565242 -394.74331) (xy 166.603073 -394.694003)
			(xy 166.646632 -394.649674) (xy 166.695268 -394.610985) (xy 166.748258 -394.578511) (xy 166.804809 -394.552738)
			(xy 166.864081 -394.534049) (xy 166.925188 -394.522723) (xy 166.98722 -394.518929) (xy 167.049252 -394.522723)
			(xy 167.110359 -394.534049) (xy 167.169631 -394.552738) (xy 167.226182 -394.578511) (xy 167.279172 -394.610985)
			(xy 167.327808 -394.649674) (xy 167.371367 -394.694003) (xy 167.409198 -394.74331) (xy 167.42537 -394.769848)
			(xy 167.430132 -394.777279) (xy 167.443664 -394.788588) (xy 167.46024 -394.79461) (xy 167.469058 -394.794994)
			(xy 168.58107 -394.794994) (xy 168.591697 -394.794393) (xy 168.611118 -394.785738) (xy 168.618662 -394.77823)
			(xy 168.676574 -394.713714) (xy 168.683178 -394.693394) (xy 168.681908 -394.682472) (xy 168.680481 -394.668673)
			(xy 168.678954 -394.640972) (xy 168.67886 -394.6271) (xy 168.679362 -394.595139) (xy 168.687373 -394.531721)
			(xy 168.70327 -394.469807) (xy 168.726802 -394.410374) (xy 168.757596 -394.354359) (xy 168.795169 -394.302644)
			(xy 168.838926 -394.256047) (xy 168.888179 -394.215302) (xy 168.94215 -394.181051) (xy 168.999989 -394.153834)
			(xy 169.060782 -394.134081) (xy 169.123572 -394.122103) (xy 169.187368 -394.11809) (xy 169.251164 -394.122103)
			(xy 169.313954 -394.134081) (xy 169.374747 -394.153834) (xy 169.432586 -394.181051) (xy 169.486557 -394.215302)
			(xy 169.53581 -394.256047) (xy 169.579567 -394.302644) (xy 169.61714 -394.354359) (xy 169.647934 -394.410374)
			(xy 169.671466 -394.469807) (xy 169.687363 -394.531721) (xy 169.695374 -394.595139) (xy 169.695876 -394.6271)
			(xy 169.695774 -394.640972) (xy 169.694248 -394.668673) (xy 169.692828 -394.682472) (xy 169.691558 -394.693394)
			(xy 169.698162 -394.713714) (xy 169.756074 -394.77823) (xy 169.763536 -394.78586) (xy 169.783004 -394.794557)
			(xy 169.793666 -394.794994) (xy 172.210476 -394.794994) (xy 172.239178 -394.769086) (xy 172.24121 -394.749274)
			(xy 172.244964 -394.716725) (xy 172.259769 -394.652897) (xy 172.282637 -394.591494) (xy 172.313189 -394.53353)
			(xy 172.331634 -394.50645) (xy 172.340778 -394.47724) (xy 172.325792 -394.441172) (xy 172.302257 -394.417188)
			(xy 172.261058 -394.364101) (xy 172.227208 -394.306053) (xy 172.201296 -394.244053) (xy 172.183772 -394.179181)
			(xy 172.174942 -394.112567) (xy 172.174408 -394.078968) (xy 172.174867 -394.047751) (xy 172.182478 -393.985782)
			(xy 172.19762 -393.925212) (xy 172.220063 -393.866951) (xy 172.234352 -393.839192) (xy 172.240194 -393.815316)
			(xy 172.224192 -393.778232) (xy 172.202673 -393.757583) (xy 172.164109 -393.712087) (xy 172.13113 -393.662393)
			(xy 172.104189 -393.609183) (xy 172.083655 -393.553188) (xy 172.06981 -393.495176) (xy 172.062844 -393.435943)
			(xy 172.062394 -393.406122) (xy 172.062896 -393.374161) (xy 172.070907 -393.310743) (xy 172.086804 -393.248829)
			(xy 172.110336 -393.189396) (xy 172.14113 -393.133381) (xy 172.178703 -393.081666) (xy 172.22246 -393.035069)
			(xy 172.271713 -392.994324) (xy 172.325684 -392.960073) (xy 172.383523 -392.932856) (xy 172.444316 -392.913103)
			(xy 172.507106 -392.901125) (xy 172.570902 -392.897112) (xy 172.634698 -392.901125) (xy 172.697488 -392.913103)
			(xy 172.758281 -392.932856) (xy 172.81612 -392.960073) (xy 172.870091 -392.994324) (xy 172.919344 -393.035069)
			(xy 172.963101 -393.081666) (xy 173.000674 -393.133381) (xy 173.031468 -393.189396) (xy 173.055 -393.248829)
			(xy 173.070897 -393.310743) (xy 173.078908 -393.374161) (xy 173.07941 -393.406122) (xy 173.07941 -393.40663)
			(xy 173.078925 -393.437784) (xy 173.071284 -393.499621) (xy 173.056144 -393.560062) (xy 173.033734 -393.618199)
			(xy 173.019466 -393.645898) (xy 173.013624 -393.669774) (xy 173.029626 -393.706858) (xy 173.051145 -393.727507)
			(xy 173.089708 -393.773004) (xy 173.122687 -393.822698) (xy 173.149629 -393.875907) (xy 173.170163 -393.931902)
			(xy 173.184008 -393.989914) (xy 173.190975 -394.049147) (xy 173.191424 -394.078968) (xy 173.191424 -394.079476)
			(xy 173.190932 -394.110699) (xy 173.188317 -394.1318) (xy 178.126689 -394.1318) (xy 178.130703 -394.068007)
			(xy 178.142679 -394.00522) (xy 178.16243 -393.94443) (xy 178.189645 -393.886594) (xy 178.223892 -393.832624)
			(xy 178.264634 -393.783372) (xy 178.311227 -393.739615) (xy 178.362937 -393.702042) (xy 178.418948 -393.671246)
			(xy 178.478377 -393.647712) (xy 178.540286 -393.631812) (xy 178.603701 -393.623796) (xy 178.63566 -393.623292)
			(xy 178.667258 -393.623793) (xy 178.729966 -393.631619) (xy 178.791222 -393.647156) (xy 178.85008 -393.670164)
			(xy 178.905634 -393.700288) (xy 178.957026 -393.737064) (xy 179.003465 -393.779925) (xy 179.044234 -393.828211)
			(xy 179.061872 -393.854432) (xy 179.067206 -393.86256) (xy 179.082192 -393.873482) (xy 179.16652 -393.895834)
			(xy 179.184808 -393.893802) (xy 179.193444 -393.889484) (xy 179.205851 -393.883279) (xy 179.231403 -393.872473)
			(xy 179.244498 -393.867894) (xy 179.257706 -393.863322) (xy 179.27574 -393.84224) (xy 179.295552 -393.726416)
			(xy 179.2859 -393.700762) (xy 179.274724 -393.692126) (xy 179.24941 -393.671389) (xy 179.203784 -393.624479)
			(xy 179.16455 -393.572106) (xy 179.132356 -393.515134) (xy 179.107734 -393.454505) (xy 179.09109 -393.391218)
			(xy 179.082698 -393.326319) (xy 179.082192 -393.2936) (xy 179.082694 -393.261639) (xy 179.090705 -393.198221)
			(xy 179.106602 -393.136307) (xy 179.130134 -393.076874) (xy 179.160928 -393.020859) (xy 179.198501 -392.969144)
			(xy 179.242258 -392.922547) (xy 179.291511 -392.881802) (xy 179.345482 -392.847551) (xy 179.403321 -392.820334)
			(xy 179.464114 -392.800581) (xy 179.526904 -392.788603) (xy 179.5907 -392.78459) (xy 179.654496 -392.788603)
			(xy 179.717286 -392.800581) (xy 179.778079 -392.820334) (xy 179.835918 -392.847551) (xy 179.889889 -392.881802)
			(xy 179.939142 -392.922547) (xy 179.982899 -392.969144) (xy 180.020472 -393.020859) (xy 180.051266 -393.076874)
			(xy 180.074798 -393.136307) (xy 180.090695 -393.198221) (xy 180.098706 -393.261639) (xy 180.099208 -393.2936)
			(xy 180.098683 -393.32524) (xy 180.090819 -393.388031) (xy 180.075227 -393.449361) (xy 180.052145 -393.508282)
			(xy 180.021932 -393.563885) (xy 179.985054 -393.615309) (xy 179.942081 -393.661762) (xy 179.893677 -393.702523)
			(xy 179.84059 -393.736965) (xy 179.783639 -393.764554) (xy 179.723706 -393.784864) (xy 179.692808 -393.791694)
			(xy 179.679092 -393.794488) (xy 179.658772 -393.81303) (xy 179.624228 -393.925298) (xy 179.630832 -393.952222)
			(xy 179.640484 -393.962128) (xy 179.660757 -393.983632) (xy 179.695059 -394.031758) (xy 179.721529 -394.084597)
			(xy 179.739534 -394.140886) (xy 179.748644 -394.199279) (xy 179.749196 -394.228828) (xy 179.748748 -394.25608)
			(xy 179.740988 -394.31003) (xy 179.725628 -394.362326) (xy 179.702983 -394.411905) (xy 179.673513 -394.457755)
			(xy 179.637817 -394.498946) (xy 179.596623 -394.534637) (xy 179.550769 -394.564102) (xy 179.501189 -394.586742)
			(xy 179.448891 -394.602096) (xy 179.394941 -394.609851) (xy 179.367688 -394.610336) (xy 179.33953 -394.609835)
			(xy 179.283828 -394.601534) (xy 179.229954 -394.585129) (xy 179.179079 -394.560977) (xy 179.13231 -394.529604)
			(xy 179.111148 -394.511022) (xy 179.104036 -394.504672) (xy 179.086764 -394.497814) (xy 178.999388 -394.49756)
			(xy 178.982116 -394.504164) (xy 178.975004 -394.510514) (xy 178.951648 -394.53086) (xy 178.900833 -394.566284)
			(xy 178.846092 -394.595273) (xy 178.788234 -394.617398) (xy 178.728117 -394.632331) (xy 178.666632 -394.63985)
			(xy 178.63566 -394.640308) (xy 178.603701 -394.639804) (xy 178.540286 -394.631788) (xy 178.478377 -394.615888)
			(xy 178.418948 -394.592354) (xy 178.362937 -394.561558) (xy 178.311227 -394.523985) (xy 178.264634 -394.480228)
			(xy 178.223892 -394.430976) (xy 178.189645 -394.377006) (xy 178.16243 -394.31917) (xy 178.142679 -394.25838)
			(xy 178.130703 -394.195593) (xy 178.126689 -394.1318) (xy 173.188317 -394.1318) (xy 173.183253 -394.172673)
			(xy 173.168044 -394.23324) (xy 173.145535 -394.29149) (xy 173.116063 -394.346545) (xy 173.09846 -394.372338)
			(xy 173.089316 -394.401548) (xy 173.104302 -394.437616) (xy 173.12492 -394.458543) (xy 173.161708 -394.504348)
			(xy 173.19297 -394.554089) (xy 173.21829 -394.607102) (xy 173.237329 -394.662681) (xy 173.249835 -394.720084)
			(xy 173.253146 -394.749274) (xy 173.255178 -394.769086) (xy 173.28388 -394.794994) (xy 183.449468 -394.794994)
			(xy 183.459533 -394.794558) (xy 183.478118 -394.786826) (xy 183.485536 -394.780008) (xy 183.869584 -394.39596)
			(xy 183.876264 -394.388549) (xy 183.883834 -394.370113) (xy 183.884316 -394.360146) (xy 183.884316 -394.35278)
			(xy 183.884743 -394.342712) (xy 183.892464 -394.324114) (xy 183.899302 -394.316712) (xy 188.831728 -389.384286)
			(xy 188.839124 -389.377435) (xy 188.857723 -389.369697) (xy 188.867796 -389.3693) (xy 188.875162 -389.3693)
			(xy 188.885125 -389.368814) (xy 188.90355 -389.361228) (xy 188.910976 -389.354568) (xy 189.01918 -389.246364)
			(xy 189.02658 -389.239523) (xy 189.045179 -389.231808) (xy 189.055248 -389.231378) (xy 193.904108 -389.231378)
			(xy 193.912749 -389.231046) (xy 193.929047 -389.225301) (xy 193.942489 -389.214441) (xy 193.947288 -389.207248)
			(xy 193.999866 -389.122412) (xy 194.000882 -389.09625) (xy 193.994786 -389.084312) (xy 193.976315 -389.046436)
			(xy 193.945783 -388.967887) (xy 193.922816 -388.886802) (xy 193.90762 -388.80391) (xy 193.900331 -388.719951)
			(xy 193.901014 -388.63568) (xy 193.909664 -388.551851) (xy 193.926202 -388.469215) (xy 193.95048 -388.388514)
			(xy 193.982282 -388.31047) (xy 194.021321 -388.235784) (xy 194.067248 -388.165124) (xy 194.119652 -388.099124)
			(xy 194.178062 -388.038375) (xy 194.241955 -387.983422) (xy 194.310759 -387.934758) (xy 194.383856 -387.892818)
			(xy 194.460592 -387.857979) (xy 194.540278 -387.830553) (xy 194.622201 -387.810785) (xy 194.705626 -387.798853)
			(xy 194.789806 -387.794864) (xy 194.873986 -387.798853) (xy 194.957411 -387.810785) (xy 195.039334 -387.830553)
			(xy 195.11902 -387.857979) (xy 195.195756 -387.892818) (xy 195.268853 -387.934758) (xy 195.337657 -387.983422)
			(xy 195.40155 -388.038375) (xy 195.45996 -388.099124) (xy 195.512364 -388.165124) (xy 195.558291 -388.235784)
			(xy 195.59733 -388.31047) (xy 195.629132 -388.388514) (xy 195.65341 -388.469215) (xy 195.669948 -388.551851)
			(xy 195.678598 -388.63568) (xy 195.679281 -388.719951) (xy 195.671992 -388.80391) (xy 195.656796 -388.886802)
			(xy 195.633829 -388.967887) (xy 195.603297 -389.046436) (xy 195.584826 -389.084312) (xy 195.57873 -389.09625)
			(xy 195.58 -389.122412) (xy 195.632324 -389.207248) (xy 195.637188 -389.214434) (xy 195.650716 -389.225284)
			(xy 195.667086 -389.231009) (xy 195.675758 -389.231378) (xy 198.932038 -389.231378) (xy 198.942105 -389.230947)
			(xy 198.960697 -389.223221) (xy 198.968106 -389.216392) (xy 199.537828 -388.64667) (xy 199.544678 -388.639273)
			(xy 199.552412 -388.620674) (xy 199.552814 -388.610602) (xy 199.552814 -388.57682) (xy 199.552381 -388.567917)
			(xy 199.546212 -388.551209) (xy 199.534713 -388.537609) (xy 199.52716 -388.532878) (xy 199.438768 -388.482332)
			(xy 199.41159 -388.482332) (xy 199.399652 -388.489444) (xy 199.37759 -388.501931) (xy 199.330869 -388.521604)
			(xy 199.281953 -388.534914) (xy 199.231705 -388.541625) (xy 199.206358 -388.542022) (xy 199.179108 -388.541533)
			(xy 199.125163 -388.533772) (xy 199.072871 -388.518412) (xy 199.023297 -388.495768) (xy 198.97745 -388.466299)
			(xy 198.936264 -388.430607) (xy 198.900575 -388.389416) (xy 198.871112 -388.343566) (xy 198.848473 -388.29399)
			(xy 198.833119 -388.241696) (xy 198.825364 -388.18775) (xy 198.825364 -388.13325) (xy 198.833119 -388.079304)
			(xy 198.848473 -388.02701) (xy 198.871112 -387.977434) (xy 198.900575 -387.931584) (xy 198.936264 -387.890393)
			(xy 198.97745 -387.854701) (xy 199.023297 -387.825232) (xy 199.072871 -387.802588) (xy 199.125163 -387.787228)
			(xy 199.179108 -387.779467) (xy 199.206358 -387.779006) (xy 199.231703 -387.779424) (xy 199.281947 -387.786142)
			(xy 199.33086 -387.79945) (xy 199.377581 -387.819116) (xy 199.399652 -387.831584) (xy 199.41159 -387.838696)
			(xy 199.438768 -387.838696) (xy 199.52716 -387.78815) (xy 199.534736 -387.783444) (xy 199.546261 -387.769847)
			(xy 199.552416 -387.753119) (xy 199.552814 -387.744208) (xy 199.552814 -384.719322) (xy 199.552078 -384.706647)
			(xy 199.539967 -384.684368) (xy 199.5297 -384.676904) (xy 199.447658 -384.623056) (xy 199.422258 -384.621024)
			(xy 199.410574 -384.626358) (xy 199.378326 -384.639846) (xy 199.311056 -384.658845) (xy 199.241816 -384.668439)
			(xy 199.206866 -384.66903) (xy 199.206358 -384.66903) (xy 199.175628 -384.668563) (xy 199.114617 -384.661151)
			(xy 199.054944 -384.646439) (xy 198.99748 -384.624642) (xy 198.943061 -384.596078) (xy 198.892482 -384.561163)
			(xy 198.846479 -384.520406) (xy 198.805725 -384.474403) (xy 198.770812 -384.423822) (xy 198.74225 -384.369402)
			(xy 198.720455 -384.311937) (xy 198.705746 -384.252263) (xy 198.698335 -384.191252) (xy 198.69785 -384.160522)
			(xy 198.698307 -384.129979) (xy 198.705632 -384.069332) (xy 198.720169 -384.01) (xy 198.741707 -383.952836)
			(xy 198.769937 -383.898663) (xy 198.804452 -383.848261) (xy 198.844755 -383.802356) (xy 198.890267 -383.761608)
			(xy 198.91502 -383.743708) (xy 198.93661 -383.702306) (xy 198.93661 -383.61874) (xy 198.91502 -383.577338)
			(xy 198.888612 -383.558243) (xy 198.840406 -383.514389) (xy 198.798198 -383.464737) (xy 198.762678 -383.410099)
			(xy 198.734429 -383.351372) (xy 198.713913 -383.289517) (xy 198.701467 -383.225548) (xy 198.697294 -383.160514)
			(xy 198.701463 -383.095479) (xy 198.713906 -383.031509) (xy 198.734418 -382.969653) (xy 198.762665 -382.910925)
			(xy 198.798182 -382.856285) (xy 198.840387 -382.80663) (xy 198.88859 -382.762774) (xy 198.91502 -382.74371)
			(xy 198.93661 -382.702308) (xy 198.93661 -382.618742) (xy 198.91502 -382.57734) (xy 198.888612 -382.558245)
			(xy 198.840406 -382.514391) (xy 198.798197 -382.464739) (xy 198.762677 -382.410101) (xy 198.734428 -382.351374)
			(xy 198.713912 -382.289519) (xy 198.701465 -382.22555) (xy 198.697292 -382.160515) (xy 198.701461 -382.09548)
			(xy 198.713904 -382.03151) (xy 198.734417 -381.969654) (xy 198.762663 -381.910925) (xy 198.79818 -381.856285)
			(xy 198.840385 -381.80663) (xy 198.888588 -381.762773) (xy 198.91502 -381.743712) (xy 198.93661 -381.70231)
			(xy 198.93661 -381.618744) (xy 198.91502 -381.577342) (xy 198.890243 -381.559472) (xy 198.844725 -381.518726)
			(xy 198.804417 -381.472819) (xy 198.769901 -381.422414) (xy 198.741673 -381.368235) (xy 198.720141 -381.311064)
			(xy 198.705614 -381.251726) (xy 198.698302 -381.191074) (xy 198.69785 -381.160528) (xy 198.698352 -381.128567)
			(xy 198.706363 -381.065149) (xy 198.72226 -381.003235) (xy 198.745792 -380.943802) (xy 198.776586 -380.887787)
			(xy 198.814159 -380.836072) (xy 198.857916 -380.789475) (xy 198.907169 -380.74873) (xy 198.96114 -380.714479)
			(xy 199.018979 -380.687262) (xy 199.079772 -380.667509) (xy 199.142562 -380.655531) (xy 199.206358 -380.651518)
			(xy 199.270154 -380.655531) (xy 199.332944 -380.667509) (xy 199.393737 -380.687262) (xy 199.451576 -380.714479)
			(xy 199.505547 -380.74873) (xy 199.5548 -380.789475) (xy 199.598557 -380.836072) (xy 199.63613 -380.887787)
			(xy 199.666924 -380.943802) (xy 199.690456 -381.003235) (xy 199.706353 -381.065149) (xy 199.710572 -381.098552)
			(xy 206.93761 -381.098552) (xy 206.938056 -381.067865) (xy 206.945438 -381.006938) (xy 206.960102 -380.947342)
			(xy 206.981834 -380.889945) (xy 207.010317 -380.835582) (xy 207.045138 -380.785043) (xy 207.065118 -380.761748)
			(xy 207.070921 -380.754608) (xy 207.077431 -380.737413) (xy 207.077818 -380.72822) (xy 207.078072 -380.69774)
			(xy 207.077723 -380.688573) (xy 207.07134 -380.671389) (xy 207.065626 -380.664212) (xy 207.046023 -380.641033)
			(xy 207.011887 -380.590832) (xy 206.983975 -380.536922) (xy 206.962688 -380.480069) (xy 206.948327 -380.421085)
			(xy 206.941098 -380.36081) (xy 206.940658 -380.330456) (xy 206.94116 -380.298495) (xy 206.949171 -380.235077)
			(xy 206.965068 -380.173163) (xy 206.9886 -380.11373) (xy 207.019394 -380.057715) (xy 207.056967 -380.006)
			(xy 207.100724 -379.959403) (xy 207.149977 -379.918658) (xy 207.203948 -379.884407) (xy 207.261787 -379.85719)
			(xy 207.32258 -379.837437) (xy 207.38537 -379.825459) (xy 207.449166 -379.821446) (xy 207.512962 -379.825459)
			(xy 207.575752 -379.837437) (xy 207.636545 -379.85719) (xy 207.694384 -379.884407) (xy 207.748355 -379.918658)
			(xy 207.797608 -379.959403) (xy 207.841365 -380.006) (xy 207.878938 -380.057715) (xy 207.909732 -380.11373)
			(xy 207.933264 -380.173163) (xy 207.949161 -380.235077) (xy 207.957172 -380.298495) (xy 207.957674 -380.330456)
			(xy 207.957237 -380.361143) (xy 207.949853 -380.422071) (xy 207.935188 -380.481667) (xy 207.913455 -380.539064)
			(xy 207.88497 -380.593427) (xy 207.850147 -380.643965) (xy 207.830166 -380.66726) (xy 207.824357 -380.674396)
			(xy 207.817851 -380.691594) (xy 207.817466 -380.700788) (xy 207.817212 -380.731268) (xy 207.81756 -380.740435)
			(xy 207.823944 -380.757619) (xy 207.829658 -380.764796) (xy 207.849278 -380.787961) (xy 207.88341 -380.838166)
			(xy 207.911317 -380.89208) (xy 207.932601 -380.948935) (xy 207.94696 -381.007921) (xy 207.954187 -381.068198)
			(xy 207.954626 -381.098552) (xy 207.954124 -381.130513) (xy 207.946113 -381.193931) (xy 207.930216 -381.255845)
			(xy 207.906684 -381.315278) (xy 207.87589 -381.371293) (xy 207.838317 -381.423008) (xy 207.79456 -381.469605)
			(xy 207.745307 -381.51035) (xy 207.691336 -381.544601) (xy 207.633497 -381.571818) (xy 207.572704 -381.591571)
			(xy 207.509914 -381.603549) (xy 207.446118 -381.607563) (xy 207.382322 -381.603549) (xy 207.319532 -381.591571)
			(xy 207.258739 -381.571818) (xy 207.2009 -381.544601) (xy 207.146929 -381.51035) (xy 207.097676 -381.469605)
			(xy 207.053919 -381.423008) (xy 207.016346 -381.371293) (xy 206.985552 -381.315278) (xy 206.96202 -381.255845)
			(xy 206.946123 -381.193931) (xy 206.938112 -381.130513) (xy 206.93761 -381.098552) (xy 199.710572 -381.098552)
			(xy 199.714364 -381.128567) (xy 199.714866 -381.160528) (xy 199.714412 -381.191073) (xy 199.707092 -381.251723)
			(xy 199.69256 -381.311059) (xy 199.671026 -381.368228) (xy 199.6428 -381.422406) (xy 199.608288 -381.472814)
			(xy 199.567986 -381.518725) (xy 199.522477 -381.559478) (xy 199.497696 -381.577342) (xy 199.476106 -381.618744)
			(xy 199.476106 -381.70231) (xy 199.497696 -381.743712) (xy 199.524105 -381.762804) (xy 199.572311 -381.806654)
			(xy 199.61452 -381.856302) (xy 199.65004 -381.910937) (xy 199.678289 -381.969662) (xy 199.698803 -382.031515)
			(xy 199.711247 -382.095482) (xy 199.715417 -382.160515) (xy 199.711244 -382.225547) (xy 199.698796 -382.289514)
			(xy 199.678278 -382.351365) (xy 199.650026 -382.410089) (xy 199.614502 -382.464721) (xy 199.57229 -382.514368)
			(xy 199.524081 -382.558214) (xy 199.497696 -382.57734) (xy 199.476106 -382.618742) (xy 199.476106 -382.702308)
			(xy 199.497696 -382.74371) (xy 199.524105 -382.762802) (xy 199.572311 -382.806652) (xy 199.614521 -382.856301)
			(xy 199.650041 -382.910935) (xy 199.67829 -382.969661) (xy 199.698805 -383.031514) (xy 199.711249 -383.095481)
			(xy 199.715419 -383.160514) (xy 199.711245 -383.225546) (xy 199.698798 -383.289513) (xy 199.67828 -383.351365)
			(xy 199.650028 -383.410089) (xy 199.614504 -383.464721) (xy 199.572292 -383.514368) (xy 199.524083 -383.558215)
			(xy 199.497696 -383.577338) (xy 199.476106 -383.61874) (xy 199.476106 -383.702306) (xy 199.497696 -383.743708)
			(xy 199.525433 -383.76384) (xy 199.575768 -383.810356) (xy 199.598026 -383.836418) (xy 199.604884 -383.844546)
			(xy 199.624188 -383.854198) (xy 199.71004 -383.858262) (xy 199.720601 -383.858202) (xy 199.740272 -383.850578)
			(xy 199.74814 -383.84353) (xy 201.147426 -382.444244) (xy 201.154824 -382.437397) (xy 201.173422 -382.429665)
			(xy 201.183494 -382.429258) (xy 204.97292 -382.429258) (xy 205.012798 -382.4097) (xy 205.033526 -382.384078)
			(xy 205.08052 -382.337872) (xy 205.133088 -382.298121) (xy 205.190348 -382.265491) (xy 205.251343 -382.240528)
			(xy 205.31505 -382.22365) (xy 205.380403 -382.21514) (xy 205.446309 -382.21514) (xy 205.511662 -382.22365)
			(xy 205.575369 -382.240528) (xy 205.636364 -382.265491) (xy 205.693624 -382.298121) (xy 205.746192 -382.337872)
			(xy 205.793186 -382.384078) (xy 205.813914 -382.4097) (xy 205.853792 -382.429258) (xy 206.999586 -382.429258)
			(xy 207.039464 -382.4097) (xy 207.057864 -382.386852) (xy 207.099091 -382.345116) (xy 207.144852 -382.308408)
			(xy 207.194538 -382.277217) (xy 207.247487 -382.251958) (xy 207.302994 -382.232969) (xy 207.331564 -382.226312)
			(xy 207.33893 -382.224788) (xy 207.351376 -382.21793) (xy 209.004408 -380.564898) (xy 209.010504 -380.535434)
			(xy 209.004662 -380.52121) (xy 208.993323 -380.491318) (xy 208.977385 -380.429403) (xy 208.969333 -380.365978)
			(xy 208.968848 -380.334012) (xy 208.968848 -380.333504) (xy 208.969311 -380.302772) (xy 208.976719 -380.241756)
			(xy 208.991427 -380.182077) (xy 209.013221 -380.124606) (xy 209.041784 -380.070182) (xy 209.076697 -380.019596)
			(xy 209.117454 -379.973588) (xy 209.163458 -379.932827) (xy 209.21404 -379.897908) (xy 209.268463 -379.869341)
			(xy 209.325931 -379.847542) (xy 209.385608 -379.832828) (xy 209.446624 -379.825414) (xy 209.477356 -379.824996)
			(xy 209.477864 -379.824996) (xy 209.50983 -379.825494) (xy 209.573253 -379.833542) (xy 209.635168 -379.849479)
			(xy 209.665062 -379.86081) (xy 209.679286 -379.866652) (xy 209.70875 -379.860556) (xy 210.540854 -379.028452)
			(xy 210.548253 -379.021608) (xy 210.566852 -379.013885) (xy 210.576922 -379.013466) (xy 221.702122 -379.013466)
			(xy 221.71219 -379.013038) (xy 221.730785 -379.005314) (xy 221.73819 -378.99848) (xy 225.375724 -375.360946)
			(xy 225.383121 -375.354098) (xy 225.40172 -375.346365) (xy 225.411792 -375.34596) (xy 225.465132 -375.34596)
			(xy 225.475116 -375.345415) (xy 225.493536 -375.33769) (xy 225.500946 -375.330974) (xy 225.574098 -375.257822)
			(xy 225.581495 -375.250973) (xy 225.600094 -375.243234) (xy 225.610166 -375.242836) (xy 230.417116 -375.242836)
			(xy 230.427184 -375.243263) (xy 230.445781 -375.250985) (xy 230.453184 -375.257822) (xy 230.467916 -375.272554)
			(xy 230.47526 -375.279367) (xy 230.493723 -375.287101) (xy 230.50373 -375.28754) (xy 235.109004 -375.28754)
			(xy 235.11899 -375.287) (xy 235.137415 -375.279279) (xy 235.144818 -375.272554) (xy 237.11916 -373.298212)
			(xy 237.126013 -373.290816) (xy 237.133758 -373.272218) (xy 237.134146 -373.262144) (xy 237.134146 -372.474236)
			(xy 237.130844 -372.471188) (xy 237.130844 -357.85933) (xy 237.130387 -357.848837) (xy 237.122138 -357.829545)
			(xy 237.114842 -357.821992) (xy 237.052612 -357.76408) (xy 237.0328 -357.757222) (xy 237.022132 -357.757984)
			(xy 236.929229 -357.764164) (xy 236.74313 -357.770771) (xy 236.650022 -357.771192) (xy 236.547795 -357.770703)
			(xy 236.343494 -357.762776) (xy 236.139654 -357.746933) (xy 235.936581 -357.723198) (xy 235.734582 -357.691607)
			(xy 235.533959 -357.652207) (xy 235.335016 -357.605057) (xy 235.13805 -357.550229) (xy 234.943358 -357.487804)
			(xy 234.751233 -357.417877) (xy 234.561964 -357.340553) (xy 234.375836 -357.255948) (xy 234.193128 -357.164189)
			(xy 234.014116 -357.065415) (xy 233.839068 -356.959774) (xy 233.668248 -356.847424) (xy 233.501913 -356.728536)
			(xy 233.340314 -356.603287) (xy 233.183692 -356.471867) (xy 233.032284 -356.334472) (xy 232.886317 -356.191309)
			(xy 232.746011 -356.042595) (xy 232.611578 -355.888551) (xy 232.483218 -355.729411) (xy 232.361126 -355.565413)
			(xy 232.245485 -355.396805) (xy 232.136468 -355.223839) (xy 232.034241 -355.046776) (xy 231.938956 -354.865883)
			(xy 231.850757 -354.68143) (xy 231.769776 -354.493697) (xy 231.696136 -354.302964) (xy 231.629947 -354.10952)
			(xy 231.571308 -353.913654) (xy 231.520309 -353.715663) (xy 231.477025 -353.515842) (xy 231.441521 -353.314493)
			(xy 231.413852 -353.11192) (xy 231.394059 -352.908425) (xy 231.382171 -352.704316) (xy 231.378206 -352.4999)
			(xy 231.382171 -352.295484) (xy 231.394059 -352.091375) (xy 231.413852 -351.88788) (xy 231.441521 -351.685307)
			(xy 231.477025 -351.483958) (xy 231.520309 -351.284137) (xy 231.571308 -351.086146) (xy 231.629947 -350.89028)
			(xy 231.696136 -350.696836) (xy 231.769776 -350.506103) (xy 231.850757 -350.31837) (xy 231.938956 -350.133917)
			(xy 232.034241 -349.953024) (xy 232.136468 -349.775961) (xy 232.245485 -349.602995) (xy 232.361126 -349.434387)
			(xy 232.483218 -349.270389) (xy 232.611578 -349.111249) (xy 232.746011 -348.957205) (xy 232.886317 -348.808491)
			(xy 233.032284 -348.665328) (xy 233.183692 -348.527933) (xy 233.340314 -348.396513) (xy 233.501913 -348.271264)
			(xy 233.668248 -348.152376) (xy 233.839068 -348.040026) (xy 234.014116 -347.934385) (xy 234.193128 -347.835611)
			(xy 234.375836 -347.743852) (xy 234.561964 -347.659247) (xy 234.751233 -347.581923) (xy 234.943358 -347.511996)
			(xy 235.13805 -347.449571) (xy 235.335016 -347.394743) (xy 235.533959 -347.347593) (xy 235.734582 -347.308193)
			(xy 235.936581 -347.276602) (xy 236.139654 -347.252867) (xy 236.343494 -347.237024) (xy 236.547795 -347.229097)
			(xy 236.650022 -347.228668) (xy 236.74313 -347.229088) (xy 236.929229 -347.235694) (xy 237.022132 -347.241876)
			(xy 237.0328 -347.242638) (xy 237.052612 -347.23578) (xy 237.114842 -347.177868) (xy 237.122139 -347.170313)
			(xy 237.130393 -347.151025) (xy 237.130844 -347.14053) (xy 237.130844 -337.816444) (xy 237.130354 -337.806037)
			(xy 237.122104 -337.78693) (xy 237.106943 -337.772671) (xy 237.097316 -337.768692) (xy 236.991652 -337.7311)
			(xy 236.960918 -337.739736) (xy 236.950758 -337.752182) (xy 236.930011 -337.776815) (xy 236.883312 -337.821165)
			(xy 236.831385 -337.859262) (xy 236.775063 -337.890496) (xy 236.715247 -337.914367) (xy 236.652895 -337.930492)
			(xy 236.589006 -337.938614) (xy 236.556804 -337.939126) (xy 236.52484 -337.938645) (xy 236.461417 -337.930633)
			(xy 236.399498 -337.914736) (xy 236.34006 -337.891203) (xy 236.28404 -337.860406) (xy 236.232321 -337.822831)
			(xy 236.18572 -337.77907) (xy 236.144971 -337.729813) (xy 236.110717 -337.675838) (xy 236.083498 -337.617995)
			(xy 236.063743 -337.557196) (xy 236.051765 -337.494401) (xy 236.04775 -337.4306) (xy 236.051765 -337.366799)
			(xy 236.063743 -337.304004) (xy 236.083498 -337.243205) (xy 236.110717 -337.185362) (xy 236.144971 -337.131387)
			(xy 236.18572 -337.08213) (xy 236.232321 -337.038369) (xy 236.28404 -337.000794) (xy 236.34006 -336.969997)
			(xy 236.399498 -336.946464) (xy 236.461417 -336.930567) (xy 236.52484 -336.922555) (xy 236.556804 -336.92211)
			(xy 236.581217 -336.922409) (xy 236.629816 -336.927114) (xy 236.653832 -336.931508) (xy 236.667294 -336.934048)
			(xy 236.692694 -336.925412) (xy 236.768386 -336.838544) (xy 236.77372 -336.812128) (xy 236.769402 -336.799174)
			(xy 236.760033 -336.769568) (xy 236.749945 -336.7083) (xy 236.749336 -336.677254) (xy 236.749844 -336.658204)
			(xy 236.750352 -336.646266) (xy 236.741208 -336.62493) (xy 236.662722 -336.556858) (xy 236.640116 -336.551016)
			(xy 236.628432 -336.553302) (xy 236.6038 -336.557927) (xy 236.553925 -336.562892) (xy 236.528864 -336.563208)
			(xy 236.496904 -336.562704) (xy 236.43349 -336.554689) (xy 236.37158 -336.538789) (xy 236.31215 -336.515255)
			(xy 236.256139 -336.484459) (xy 236.204429 -336.446886) (xy 236.157835 -336.403129) (xy 236.117093 -336.353877)
			(xy 236.082845 -336.299908) (xy 236.055631 -336.242071) (xy 236.03588 -336.18128) (xy 236.023903 -336.118493)
			(xy 236.019889 -336.0547) (xy 236.023903 -335.990907) (xy 236.03588 -335.92812) (xy 236.055631 -335.867329)
			(xy 236.082845 -335.809492) (xy 236.117093 -335.755523) (xy 236.157835 -335.706271) (xy 236.204429 -335.662514)
			(xy 236.256139 -335.624941) (xy 236.31215 -335.594145) (xy 236.37158 -335.570611) (xy 236.43349 -335.554711)
			(xy 236.496904 -335.546696) (xy 236.528864 -335.546192) (xy 236.559443 -335.546645) (xy 236.620159 -335.553979)
			(xy 236.679556 -335.568545) (xy 236.736776 -335.590133) (xy 236.790993 -335.61843) (xy 236.841423 -335.653029)
			(xy 236.887337 -335.693429) (xy 236.928071 -335.739045) (xy 236.945932 -335.76387) (xy 236.955584 -335.777586)
			(xy 236.98708 -335.788254) (xy 237.095284 -335.754218) (xy 237.105393 -335.750541) (xy 237.121477 -335.736287)
			(xy 237.130326 -335.716702) (xy 237.130844 -335.705958) (xy 237.130844 -334.927956) (xy 237.12424 -334.903064)
			(xy 237.106557 -334.870575) (xy 237.079725 -334.801645) (xy 237.063141 -334.72956) (xy 237.05947 -334.692752)
			(xy 237.058284 -334.683364) (xy 237.049929 -334.6664) (xy 237.043214 -334.659732) (xy 237.020354 -334.63865)
			(xy 236.986826 -334.625188) (xy 236.959838 -334.624325) (xy 236.906499 -334.61593) (xy 236.854876 -334.600096)
			(xy 236.806003 -334.57714) (xy 236.760856 -334.547522) (xy 236.720337 -334.511832) (xy 236.685256 -334.470785)
			(xy 236.656314 -334.4252) (xy 236.634091 -334.37599) (xy 236.619029 -334.324137) (xy 236.611431 -334.270678)
			(xy 236.610906 -334.24368) (xy 236.611436 -334.214835) (xy 236.620124 -334.157801) (xy 236.637297 -334.102726)
			(xy 236.662566 -334.050863) (xy 236.695353 -334.003395) (xy 236.734913 -333.961403) (xy 236.780342 -333.925845)
			(xy 236.830607 -333.89753) (xy 236.884561 -333.877105) (xy 236.912658 -333.870554) (xy 236.922056 -333.868522)
			(xy 236.937804 -333.858108) (xy 236.988858 -333.786734) (xy 236.99343 -333.768446) (xy 236.992414 -333.759048)
			(xy 236.990634 -333.74368) (xy 236.988727 -333.712797) (xy 236.988604 -333.697326) (xy 236.989077 -333.666406)
			(xy 236.996607 -333.605025) (xy 237.011522 -333.545009) (xy 237.033603 -333.487245) (xy 237.062524 -333.432583)
			(xy 237.097859 -333.38183) (xy 237.118144 -333.35849) (xy 237.123976 -333.35122) (xy 237.130474 -333.333768)
			(xy 237.130844 -333.324454) (xy 237.130844 -307.116226) (xy 237.130357 -307.106264) (xy 237.122773 -307.087837)
			(xy 237.116112 -307.080412) (xy 236.332014 -306.296314) (xy 236.324611 -306.28948) (xy 236.306013 -306.281774)
			(xy 236.295946 -306.281328) (xy 220.411802 -306.281328) (xy 220.401815 -306.281866) (xy 220.383385 -306.289582)
			(xy 220.375988 -306.296314) (xy 219.776548 -306.895754) (xy 219.769741 -306.9031) (xy 219.76202 -306.921563)
			(xy 219.761562 -306.931568) (xy 219.761562 -317.206376) (xy 222.497902 -317.206376) (xy 222.501973 -317.150754)
			(xy 222.514099 -317.096317) (xy 222.534022 -317.044226) (xy 222.561318 -316.995591) (xy 222.595404 -316.951448)
			(xy 222.635553 -316.912739) (xy 222.680911 -316.880288) (xy 222.730511 -316.854787) (xy 222.783295 -316.83678)
			(xy 222.838138 -316.82665) (xy 222.893872 -316.824613) (xy 222.949309 -316.830713) (xy 223.003266 -316.844819)
			(xy 223.054595 -316.866631) (xy 223.102201 -316.895685) (xy 223.145069 -316.93136) (xy 223.182286 -316.972897)
			(xy 223.213059 -317.01941) (xy 223.236731 -317.069907) (xy 223.252799 -317.123314) (xy 223.260919 -317.17849)
			(xy 223.261428 -317.206376) (xy 223.261076 -317.22568) (xy 223.59747 -317.22568) (xy 223.598019 -317.196764)
			(xy 223.606738 -317.139593) (xy 223.623988 -317.084394) (xy 223.649374 -317.032431) (xy 223.682314 -316.984897)
			(xy 223.722052 -316.94288) (xy 223.744536 -316.92469) (xy 223.753304 -316.917134) (xy 223.763483 -316.896371)
			(xy 223.764094 -316.884812) (xy 223.764094 -316.804548) (xy 223.763498 -316.792983) (xy 223.753322 -316.772212)
			(xy 223.744536 -316.76467) (xy 223.722046 -316.746487) (xy 223.682309 -316.704467) (xy 223.64937 -316.65693)
			(xy 223.623982 -316.604967) (xy 223.606728 -316.549768) (xy 223.598003 -316.492597) (xy 223.59747 -316.46368)
			(xy 223.597956 -316.436429) (xy 223.605712 -316.382481) (xy 223.621067 -316.330186) (xy 223.643709 -316.280609)
			(xy 223.673175 -316.234759) (xy 223.708866 -316.193568) (xy 223.750057 -316.157877) (xy 223.795907 -316.128411)
			(xy 223.845484 -316.105769) (xy 223.897779 -316.090414) (xy 223.951727 -316.082658) (xy 224.006229 -316.082658)
			(xy 224.060177 -316.090414) (xy 224.112472 -316.105769) (xy 224.162049 -316.128411) (xy 224.207899 -316.157877)
			(xy 224.24909 -316.193568) (xy 224.284781 -316.234759) (xy 224.314247 -316.280609) (xy 224.336889 -316.330186)
			(xy 224.352244 -316.382481) (xy 224.36 -316.436429) (xy 224.360486 -316.46368) (xy 224.359959 -316.492597)
			(xy 224.351232 -316.549768) (xy 224.333976 -316.604966) (xy 224.308586 -316.656928) (xy 224.275644 -316.704462)
			(xy 224.235905 -316.74648) (xy 224.21342 -316.76467) (xy 224.204663 -316.772236) (xy 224.19448 -316.792992)
			(xy 224.193862 -316.804548) (xy 224.193862 -316.884812) (xy 224.194404 -316.896384) (xy 224.204617 -316.917156)
			(xy 224.21342 -316.92469) (xy 224.235903 -316.942882) (xy 224.275637 -316.984902) (xy 224.308576 -317.032437)
			(xy 224.333964 -317.084398) (xy 224.351221 -317.139595) (xy 224.35995 -317.196764) (xy 224.360486 -317.22568)
			(xy 224.360097 -317.252376) (xy 224.352672 -317.305248) (xy 224.33795 -317.35657) (xy 224.316218 -317.405338)
			(xy 224.287901 -317.450601) (xy 224.253551 -317.491476) (xy 224.233994 -317.509652) (xy 224.225358 -317.517272)
			(xy 224.216468 -317.5381) (xy 224.22104 -317.6397) (xy 224.231454 -317.659512) (xy 224.240852 -317.66637)
			(xy 224.264132 -317.684509) (xy 224.305326 -317.726766) (xy 224.339526 -317.77486) (xy 224.365916 -317.827644)
			(xy 224.383868 -317.883861) (xy 224.392954 -317.942171) (xy 224.393506 -317.971678) (xy 224.39302 -317.998929)
			(xy 224.385264 -318.052877) (xy 224.369909 -318.105172) (xy 224.347267 -318.154749) (xy 224.317801 -318.200599)
			(xy 224.28211 -318.24179) (xy 224.240919 -318.277481) (xy 224.195069 -318.306947) (xy 224.145492 -318.329589)
			(xy 224.093197 -318.344944) (xy 224.039249 -318.3527) (xy 223.984747 -318.3527) (xy 223.930799 -318.344944)
			(xy 223.878504 -318.329589) (xy 223.828927 -318.306947) (xy 223.783077 -318.277481) (xy 223.741886 -318.24179)
			(xy 223.706195 -318.200599) (xy 223.676729 -318.154749) (xy 223.654087 -318.105172) (xy 223.638732 -318.052877)
			(xy 223.630976 -317.998929) (xy 223.63049 -317.971678) (xy 223.630926 -317.944984) (xy 223.638343 -317.892114)
			(xy 223.653056 -317.840794) (xy 223.674779 -317.792025) (xy 223.703087 -317.746761) (xy 223.737429 -317.705884)
			(xy 223.756982 -317.687706) (xy 223.765618 -317.680086) (xy 223.774508 -317.659258) (xy 223.769936 -317.557658)
			(xy 223.759522 -317.537846) (xy 223.750124 -317.530988) (xy 223.726862 -317.512827) (xy 223.685658 -317.47058)
			(xy 223.651451 -317.422493) (xy 223.625056 -317.369712) (xy 223.607103 -317.313496) (xy 223.598019 -317.255186)
			(xy 223.59747 -317.22568) (xy 223.261076 -317.22568) (xy 223.260919 -317.234262) (xy 223.252799 -317.289438)
			(xy 223.236731 -317.342845) (xy 223.213059 -317.393342) (xy 223.182286 -317.439855) (xy 223.145069 -317.481392)
			(xy 223.102201 -317.517067) (xy 223.054595 -317.546121) (xy 223.003266 -317.567933) (xy 222.949309 -317.582039)
			(xy 222.893872 -317.588139) (xy 222.838138 -317.586102) (xy 222.783295 -317.575972) (xy 222.730511 -317.557965)
			(xy 222.680911 -317.532464) (xy 222.635553 -317.500013) (xy 222.595404 -317.461304) (xy 222.561318 -317.417161)
			(xy 222.534022 -317.368526) (xy 222.514099 -317.316435) (xy 222.501973 -317.261998) (xy 222.497902 -317.206376)
			(xy 219.761562 -317.206376) (xy 219.761562 -318.415162) (xy 219.762261 -318.427027) (xy 219.773 -318.448197)
			(xy 219.782136 -318.455802) (xy 219.857066 -318.511682) (xy 219.880942 -318.515746) (xy 219.892372 -318.512444)
			(xy 219.928111 -318.502388) (xy 220.001556 -318.491543) (xy 220.038676 -318.490854) (xy 220.070642 -318.491334)
			(xy 220.134069 -318.499344) (xy 220.195993 -318.51524) (xy 220.255436 -318.538773) (xy 220.31146 -318.56957)
			(xy 220.363183 -318.607147) (xy 220.409788 -318.65091) (xy 220.45054 -318.700169) (xy 220.453276 -318.70448)
			(xy 224.841553 -318.70448) (xy 224.845286 -318.651226) (xy 224.856405 -318.599012) (xy 224.874694 -318.548858)
			(xy 224.899795 -318.501743) (xy 224.931219 -318.458587) (xy 224.968352 -318.420232) (xy 224.989136 -318.403478)
			(xy 224.997909 -318.395927) (xy 225.008085 -318.37516) (xy 225.008694 -318.3636) (xy 225.008694 -318.283336)
			(xy 225.008105 -318.271771) (xy 224.997924 -318.250999) (xy 224.989136 -318.243458) (xy 224.96664 -318.225282)
			(xy 224.926904 -318.18326) (xy 224.893965 -318.135722) (xy 224.868579 -318.083758) (xy 224.851326 -318.028557)
			(xy 224.842602 -317.971385) (xy 224.84207 -317.942468) (xy 224.842556 -317.915217) (xy 224.850312 -317.861269)
			(xy 224.865667 -317.808974) (xy 224.888309 -317.759397) (xy 224.917775 -317.713547) (xy 224.953466 -317.672356)
			(xy 224.994657 -317.636665) (xy 225.040507 -317.607199) (xy 225.090084 -317.584557) (xy 225.142379 -317.569202)
			(xy 225.196327 -317.561446) (xy 225.250829 -317.561446) (xy 225.304777 -317.569202) (xy 225.357072 -317.584557)
			(xy 225.406649 -317.607199) (xy 225.452499 -317.636665) (xy 225.49369 -317.672356) (xy 225.529381 -317.713547)
			(xy 225.558847 -317.759397) (xy 225.581489 -317.808974) (xy 225.596844 -317.861269) (xy 225.6046 -317.915217)
			(xy 225.605086 -317.942468) (xy 225.60455 -317.971384) (xy 225.595825 -318.028555) (xy 225.578571 -318.083754)
			(xy 225.553183 -318.135715) (xy 225.520242 -318.18325) (xy 225.480504 -318.225267) (xy 225.45802 -318.243458)
			(xy 225.449268 -318.251029) (xy 225.439083 -318.271781) (xy 225.438462 -318.283336) (xy 225.438462 -318.3636)
			(xy 225.439011 -318.375171) (xy 225.449218 -318.395943) (xy 225.45802 -318.403478) (xy 225.478772 -318.420269)
			(xy 225.515904 -318.458617) (xy 225.547327 -318.501766) (xy 225.572428 -318.548875) (xy 225.590717 -318.599024)
			(xy 225.601836 -318.651232) (xy 225.605569 -318.70448) (xy 227.229153 -318.70448) (xy 227.232886 -318.651226)
			(xy 227.244005 -318.599012) (xy 227.262294 -318.548858) (xy 227.287395 -318.501743) (xy 227.318819 -318.458587)
			(xy 227.355952 -318.420232) (xy 227.376736 -318.403478) (xy 227.385509 -318.395927) (xy 227.395685 -318.37516)
			(xy 227.396294 -318.3636) (xy 227.396294 -318.283336) (xy 227.395705 -318.271771) (xy 227.385524 -318.250999)
			(xy 227.376736 -318.243458) (xy 227.35424 -318.225282) (xy 227.314504 -318.18326) (xy 227.281565 -318.135722)
			(xy 227.256179 -318.083758) (xy 227.238926 -318.028557) (xy 227.230202 -317.971385) (xy 227.22967 -317.942468)
			(xy 227.230166 -317.914873) (xy 227.238135 -317.860261) (xy 227.253888 -317.807366) (xy 227.277095 -317.757293)
			(xy 227.307274 -317.711084) (xy 227.343794 -317.669704) (xy 227.385893 -317.634017) (xy 227.432695 -317.604766)
			(xy 227.457762 -317.593218) (xy 227.468176 -317.588646) (xy 227.482908 -317.571628) (xy 227.510594 -317.474092)
			(xy 227.507038 -317.451994) (xy 227.500434 -317.442342) (xy 227.484484 -317.418332) (xy 227.459233 -317.366514)
			(xy 227.442074 -317.311486) (xy 227.433397 -317.254501) (xy 227.43287 -317.22568) (xy 227.433419 -317.196764)
			(xy 227.442138 -317.139593) (xy 227.459388 -317.084394) (xy 227.484774 -317.032431) (xy 227.517714 -316.984897)
			(xy 227.557452 -316.94288) (xy 227.579936 -316.92469) (xy 227.588704 -316.917134) (xy 227.598883 -316.896371)
			(xy 227.599494 -316.884812) (xy 227.599494 -316.804548) (xy 227.598898 -316.792983) (xy 227.588722 -316.772212)
			(xy 227.579936 -316.76467) (xy 227.557446 -316.746487) (xy 227.517709 -316.704467) (xy 227.48477 -316.65693)
			(xy 227.459382 -316.604967) (xy 227.442128 -316.549768) (xy 227.433403 -316.492597) (xy 227.43287 -316.46368)
			(xy 227.433356 -316.436429) (xy 227.441112 -316.382481) (xy 227.456467 -316.330186) (xy 227.479109 -316.280609)
			(xy 227.508575 -316.234759) (xy 227.544266 -316.193568) (xy 227.585457 -316.157877) (xy 227.631307 -316.128411)
			(xy 227.680884 -316.105769) (xy 227.733179 -316.090414) (xy 227.787127 -316.082658) (xy 227.841629 -316.082658)
			(xy 227.895577 -316.090414) (xy 227.947872 -316.105769) (xy 227.997449 -316.128411) (xy 228.043299 -316.157877)
			(xy 228.08449 -316.193568) (xy 228.120181 -316.234759) (xy 228.149647 -316.280609) (xy 228.172289 -316.330186)
			(xy 228.187644 -316.382481) (xy 228.1954 -316.436429) (xy 228.195886 -316.46368) (xy 228.195359 -316.492597)
			(xy 228.186632 -316.549768) (xy 228.169376 -316.604966) (xy 228.143986 -316.656928) (xy 228.111044 -316.704462)
			(xy 228.071305 -316.74648) (xy 228.04882 -316.76467) (xy 228.040063 -316.772236) (xy 228.02988 -316.792992)
			(xy 228.029262 -316.804548) (xy 228.029262 -316.884812) (xy 228.029804 -316.896384) (xy 228.040017 -316.917156)
			(xy 228.04882 -316.92469) (xy 228.071303 -316.942882) (xy 228.111037 -316.984902) (xy 228.143976 -317.032437)
			(xy 228.169364 -317.084398) (xy 228.186621 -317.139595) (xy 228.19535 -317.196764) (xy 228.195886 -317.22568)
			(xy 229.49027 -317.22568) (xy 229.490819 -317.196764) (xy 229.499538 -317.139593) (xy 229.516788 -317.084394)
			(xy 229.542174 -317.032431) (xy 229.575114 -316.984897) (xy 229.614852 -316.94288) (xy 229.637336 -316.92469)
			(xy 229.646104 -316.917134) (xy 229.656283 -316.896371) (xy 229.656894 -316.884812) (xy 229.656894 -316.804548)
			(xy 229.656298 -316.792983) (xy 229.646122 -316.772212) (xy 229.637336 -316.76467) (xy 229.614846 -316.746487)
			(xy 229.575109 -316.704467) (xy 229.54217 -316.65693) (xy 229.516782 -316.604967) (xy 229.499528 -316.549768)
			(xy 229.490803 -316.492597) (xy 229.49027 -316.46368) (xy 229.490756 -316.436429) (xy 229.498512 -316.382481)
			(xy 229.513867 -316.330186) (xy 229.536509 -316.280609) (xy 229.565975 -316.234759) (xy 229.601666 -316.193568)
			(xy 229.642857 -316.157877) (xy 229.688707 -316.128411) (xy 229.738284 -316.105769) (xy 229.790579 -316.090414)
			(xy 229.844527 -316.082658) (xy 229.899029 -316.082658) (xy 229.952977 -316.090414) (xy 230.005272 -316.105769)
			(xy 230.054849 -316.128411) (xy 230.100699 -316.157877) (xy 230.14189 -316.193568) (xy 230.177581 -316.234759)
			(xy 230.207047 -316.280609) (xy 230.229689 -316.330186) (xy 230.245044 -316.382481) (xy 230.2528 -316.436429)
			(xy 230.253286 -316.46368) (xy 230.252759 -316.492597) (xy 230.244032 -316.549768) (xy 230.226776 -316.604966)
			(xy 230.201386 -316.656928) (xy 230.168444 -316.704462) (xy 230.128705 -316.74648) (xy 230.10622 -316.76467)
			(xy 230.097463 -316.772236) (xy 230.08728 -316.792992) (xy 230.086662 -316.804548) (xy 230.086662 -316.884812)
			(xy 230.087204 -316.896384) (xy 230.097417 -316.917156) (xy 230.10622 -316.92469) (xy 230.128703 -316.942882)
			(xy 230.168437 -316.984902) (xy 230.201376 -317.032437) (xy 230.226764 -317.084398) (xy 230.244021 -317.139595)
			(xy 230.25275 -317.196764) (xy 230.253286 -317.22568) (xy 230.25281 -317.25315) (xy 230.244932 -317.307521)
			(xy 230.229336 -317.3602) (xy 230.206345 -317.410097) (xy 230.176434 -317.456179) (xy 230.140221 -317.497495)
			(xy 230.098457 -317.533188) (xy 230.075486 -317.54826) (xy 230.064056 -317.555372) (xy 230.05161 -317.57874)
			(xy 230.053896 -317.692786) (xy 230.067358 -317.715646) (xy 230.079042 -317.72225) (xy 230.103569 -317.736959)
			(xy 230.148324 -317.772561) (xy 230.187265 -317.814443) (xy 230.219521 -317.861668) (xy 230.244368 -317.913176)
			(xy 230.261251 -317.967816) (xy 230.269791 -318.024364) (xy 230.270304 -318.052958) (xy 230.269818 -318.080209)
			(xy 230.262062 -318.134157) (xy 230.246707 -318.186452) (xy 230.224065 -318.236029) (xy 230.194599 -318.281879)
			(xy 230.158908 -318.32307) (xy 230.117717 -318.358761) (xy 230.071867 -318.388227) (xy 230.02229 -318.410869)
			(xy 229.969995 -318.426224) (xy 229.916047 -318.43398) (xy 229.861545 -318.43398) (xy 229.807597 -318.426224)
			(xy 229.755302 -318.410869) (xy 229.705725 -318.388227) (xy 229.659875 -318.358761) (xy 229.618684 -318.32307)
			(xy 229.582993 -318.281879) (xy 229.553527 -318.236029) (xy 229.530885 -318.186452) (xy 229.51553 -318.134157)
			(xy 229.507774 -318.080209) (xy 229.507288 -318.052958) (xy 229.507805 -318.02549) (xy 229.515677 -317.971121)
			(xy 229.531267 -317.918444) (xy 229.554252 -317.868547) (xy 229.584156 -317.822464) (xy 229.620362 -317.781147)
			(xy 229.66212 -317.745451) (xy 229.685088 -317.730378) (xy 229.696518 -317.723266) (xy 229.708964 -317.699898)
			(xy 229.706678 -317.585852) (xy 229.693216 -317.562992) (xy 229.681532 -317.556388) (xy 229.656995 -317.541695)
			(xy 229.612236 -317.506093) (xy 229.573292 -317.46421) (xy 229.541036 -317.416983) (xy 229.51619 -317.365471)
			(xy 229.499312 -317.310827) (xy 229.490779 -317.254276) (xy 229.49027 -317.22568) (xy 228.195886 -317.22568)
			(xy 228.195372 -317.253275) (xy 228.187409 -317.307887) (xy 228.171662 -317.360783) (xy 228.148458 -317.410858)
			(xy 228.118281 -317.457067) (xy 228.081763 -317.498447) (xy 228.039663 -317.534134) (xy 227.992862 -317.563383)
			(xy 227.967794 -317.57493) (xy 227.95738 -317.579502) (xy 227.942648 -317.59652) (xy 227.914962 -317.694056)
			(xy 227.918518 -317.716154) (xy 227.925122 -317.725806) (xy 227.941088 -317.749807) (xy 227.966335 -317.801627)
			(xy 227.98349 -317.856659) (xy 227.992162 -317.913646) (xy 227.992686 -317.942468) (xy 227.99215 -317.971384)
			(xy 227.983425 -318.028555) (xy 227.966171 -318.083754) (xy 227.940783 -318.135715) (xy 227.907842 -318.18325)
			(xy 227.868104 -318.225267) (xy 227.84562 -318.243458) (xy 227.836868 -318.251029) (xy 227.826683 -318.271781)
			(xy 227.826062 -318.283336) (xy 227.826062 -318.3636) (xy 227.826611 -318.375171) (xy 227.836818 -318.395943)
			(xy 227.84562 -318.403478) (xy 227.866372 -318.420269) (xy 227.903504 -318.458617) (xy 227.934927 -318.501766)
			(xy 227.960028 -318.548875) (xy 227.978317 -318.599024) (xy 227.989436 -318.651232) (xy 227.993169 -318.70448)
			(xy 230.937553 -318.70448) (xy 230.941286 -318.651226) (xy 230.952405 -318.599012) (xy 230.970694 -318.548858)
			(xy 230.995795 -318.501743) (xy 231.027219 -318.458587) (xy 231.064352 -318.420232) (xy 231.085136 -318.403478)
			(xy 231.093909 -318.395927) (xy 231.104085 -318.37516) (xy 231.104694 -318.3636) (xy 231.104694 -318.283336)
			(xy 231.104105 -318.271771) (xy 231.093924 -318.250999) (xy 231.085136 -318.243458) (xy 231.06264 -318.225282)
			(xy 231.022904 -318.18326) (xy 230.989965 -318.135722) (xy 230.964579 -318.083758) (xy 230.947326 -318.028557)
			(xy 230.938602 -317.971385) (xy 230.93807 -317.942468) (xy 230.938556 -317.915217) (xy 230.946312 -317.861269)
			(xy 230.961667 -317.808974) (xy 230.984309 -317.759397) (xy 231.013775 -317.713547) (xy 231.049466 -317.672356)
			(xy 231.090657 -317.636665) (xy 231.136507 -317.607199) (xy 231.186084 -317.584557) (xy 231.238379 -317.569202)
			(xy 231.292327 -317.561446) (xy 231.346829 -317.561446) (xy 231.400777 -317.569202) (xy 231.453072 -317.584557)
			(xy 231.502649 -317.607199) (xy 231.548499 -317.636665) (xy 231.58969 -317.672356) (xy 231.625381 -317.713547)
			(xy 231.654847 -317.759397) (xy 231.677489 -317.808974) (xy 231.692844 -317.861269) (xy 231.7006 -317.915217)
			(xy 231.701086 -317.942468) (xy 231.70055 -317.971384) (xy 231.691825 -318.028555) (xy 231.674571 -318.083754)
			(xy 231.649183 -318.135715) (xy 231.616242 -318.18325) (xy 231.576504 -318.225267) (xy 231.55402 -318.243458)
			(xy 231.545268 -318.251029) (xy 231.535083 -318.271781) (xy 231.534462 -318.283336) (xy 231.534462 -318.3636)
			(xy 231.535011 -318.375171) (xy 231.545218 -318.395943) (xy 231.55402 -318.403478) (xy 231.574772 -318.420269)
			(xy 231.611904 -318.458617) (xy 231.643327 -318.501766) (xy 231.668428 -318.548875) (xy 231.686717 -318.599024)
			(xy 231.697836 -318.651232) (xy 231.701569 -318.70448) (xy 233.325153 -318.70448) (xy 233.328886 -318.651226)
			(xy 233.340005 -318.599012) (xy 233.358294 -318.548858) (xy 233.383395 -318.501743) (xy 233.414819 -318.458587)
			(xy 233.451952 -318.420232) (xy 233.472736 -318.403478) (xy 233.481509 -318.395927) (xy 233.491685 -318.37516)
			(xy 233.492294 -318.3636) (xy 233.492294 -318.283336) (xy 233.491705 -318.271771) (xy 233.481524 -318.250999)
			(xy 233.472736 -318.243458) (xy 233.45024 -318.225282) (xy 233.410504 -318.18326) (xy 233.377565 -318.135722)
			(xy 233.352179 -318.083758) (xy 233.334926 -318.028557) (xy 233.326202 -317.971385) (xy 233.32567 -317.942468)
			(xy 233.326099 -317.915886) (xy 233.33349 -317.863237) (xy 233.348124 -317.812126) (xy 233.369717 -317.763544)
			(xy 233.397851 -317.718433) (xy 233.431979 -317.677668) (xy 233.4514 -317.659512) (xy 233.458918 -317.651892)
			(xy 233.467592 -317.632353) (xy 233.468164 -317.621666) (xy 233.468164 -317.546482) (xy 233.467712 -317.535762)
			(xy 233.459049 -317.516158) (xy 233.4514 -317.508636) (xy 233.431978 -317.490482) (xy 233.397855 -317.449715)
			(xy 233.369728 -317.404603) (xy 233.348141 -317.35602) (xy 233.333514 -317.304909) (xy 233.32613 -317.252261)
			(xy 233.32567 -317.22568) (xy 233.326219 -317.196764) (xy 233.334938 -317.139593) (xy 233.352188 -317.084394)
			(xy 233.377574 -317.032431) (xy 233.410514 -316.984897) (xy 233.450252 -316.94288) (xy 233.472736 -316.92469)
			(xy 233.481504 -316.917134) (xy 233.491683 -316.896371) (xy 233.492294 -316.884812) (xy 233.492294 -316.804548)
			(xy 233.491698 -316.792983) (xy 233.481522 -316.772212) (xy 233.472736 -316.76467) (xy 233.450246 -316.746487)
			(xy 233.410509 -316.704467) (xy 233.37757 -316.65693) (xy 233.352182 -316.604967) (xy 233.334928 -316.549768)
			(xy 233.326203 -316.492597) (xy 233.32567 -316.46368) (xy 233.326156 -316.436429) (xy 233.333912 -316.382481)
			(xy 233.349267 -316.330186) (xy 233.371909 -316.280609) (xy 233.401375 -316.234759) (xy 233.437066 -316.193568)
			(xy 233.478257 -316.157877) (xy 233.524107 -316.128411) (xy 233.573684 -316.105769) (xy 233.625979 -316.090414)
			(xy 233.679927 -316.082658) (xy 233.734429 -316.082658) (xy 233.788377 -316.090414) (xy 233.840672 -316.105769)
			(xy 233.890249 -316.128411) (xy 233.936099 -316.157877) (xy 233.97729 -316.193568) (xy 234.012981 -316.234759)
			(xy 234.042447 -316.280609) (xy 234.065089 -316.330186) (xy 234.080444 -316.382481) (xy 234.0882 -316.436429)
			(xy 234.088686 -316.46368) (xy 234.088159 -316.492597) (xy 234.079432 -316.549768) (xy 234.062176 -316.604966)
			(xy 234.036786 -316.656928) (xy 234.003844 -316.704462) (xy 233.964105 -316.74648) (xy 233.94162 -316.76467)
			(xy 233.932863 -316.772236) (xy 233.92268 -316.792992) (xy 233.922062 -316.804548) (xy 233.922062 -316.884812)
			(xy 233.922604 -316.896384) (xy 233.932817 -316.917156) (xy 233.94162 -316.92469) (xy 233.964103 -316.942882)
			(xy 234.003837 -316.984902) (xy 234.036776 -317.032437) (xy 234.062164 -317.084398) (xy 234.079421 -317.139595)
			(xy 234.08815 -317.196764) (xy 234.088686 -317.22568) (xy 234.088204 -317.25226) (xy 234.080821 -317.304906)
			(xy 234.066196 -317.356015) (xy 234.044613 -317.404597) (xy 234.01649 -317.449709) (xy 233.982372 -317.490477)
			(xy 233.962956 -317.508636) (xy 233.955411 -317.516232) (xy 233.946754 -317.53579) (xy 233.946192 -317.546482)
			(xy 233.946192 -317.621666) (xy 233.946601 -317.632392) (xy 233.955292 -317.651997) (xy 233.962956 -317.659512)
			(xy 233.982363 -317.677681) (xy 234.016485 -317.718445) (xy 234.044614 -317.763555) (xy 234.066202 -317.812135)
			(xy 234.080833 -317.863243) (xy 234.088223 -317.915888) (xy 234.088686 -317.942468) (xy 234.08815 -317.971384)
			(xy 234.079425 -318.028555) (xy 234.062171 -318.083754) (xy 234.036783 -318.135715) (xy 234.003842 -318.18325)
			(xy 233.964104 -318.225267) (xy 233.94162 -318.243458) (xy 233.932868 -318.251029) (xy 233.922683 -318.271781)
			(xy 233.922062 -318.283336) (xy 233.922062 -318.3636) (xy 233.922611 -318.375171) (xy 233.932818 -318.395943)
			(xy 233.94162 -318.403478) (xy 233.962372 -318.420269) (xy 233.999504 -318.458617) (xy 234.030927 -318.501766)
			(xy 234.056028 -318.548875) (xy 234.074317 -318.599024) (xy 234.085436 -318.651232) (xy 234.089169 -318.70448)
			(xy 234.085442 -318.757729) (xy 234.074328 -318.809938) (xy 234.056044 -318.860089) (xy 234.030948 -318.9072)
			(xy 233.999529 -318.950353) (xy 233.962401 -318.988705) (xy 233.94162 -319.005458) (xy 233.932868 -319.013029)
			(xy 233.922683 -319.033781) (xy 233.922062 -319.045336) (xy 233.922062 -319.1256) (xy 233.922611 -319.137171)
			(xy 233.932818 -319.157943) (xy 233.94162 -319.165478) (xy 233.964097 -319.183676) (xy 234.003832 -319.225695)
			(xy 234.036771 -319.273229) (xy 234.06216 -319.325188) (xy 234.079418 -319.380384) (xy 234.08815 -319.437553)
			(xy 234.088686 -319.466468) (xy 234.0882 -319.493719) (xy 234.080444 -319.547667) (xy 234.065089 -319.599962)
			(xy 234.042447 -319.649539) (xy 234.012981 -319.695389) (xy 233.97729 -319.73658) (xy 233.936099 -319.772271)
			(xy 233.890249 -319.801737) (xy 233.840672 -319.824379) (xy 233.788377 -319.839734) (xy 233.734429 -319.84749)
			(xy 233.679927 -319.84749) (xy 233.625979 -319.839734) (xy 233.573684 -319.824379) (xy 233.524107 -319.801737)
			(xy 233.478257 -319.772271) (xy 233.437066 -319.73658) (xy 233.401375 -319.695389) (xy 233.371909 -319.649539)
			(xy 233.349267 -319.599962) (xy 233.333912 -319.547667) (xy 233.326156 -319.493719) (xy 233.32567 -319.466468)
			(xy 233.326211 -319.437552) (xy 233.334931 -319.38038) (xy 233.352183 -319.325181) (xy 233.377571 -319.273218)
			(xy 233.410512 -319.225684) (xy 233.450251 -319.183668) (xy 233.472736 -319.165478) (xy 233.481509 -319.157927)
			(xy 233.491685 -319.13716) (xy 233.492294 -319.1256) (xy 233.492294 -319.045336) (xy 233.491705 -319.033771)
			(xy 233.481524 -319.012999) (xy 233.472736 -319.005458) (xy 233.451923 -318.988742) (xy 233.414794 -318.950383)
			(xy 233.383374 -318.907224) (xy 233.358278 -318.860106) (xy 233.339994 -318.80995) (xy 233.32888 -318.757735)
			(xy 233.325153 -318.70448) (xy 231.701569 -318.70448) (xy 231.697842 -318.757729) (xy 231.686728 -318.809938)
			(xy 231.668444 -318.860089) (xy 231.643348 -318.9072) (xy 231.611929 -318.950353) (xy 231.574801 -318.988705)
			(xy 231.55402 -319.005458) (xy 231.545268 -319.013029) (xy 231.535083 -319.033781) (xy 231.534462 -319.045336)
			(xy 231.534462 -319.1256) (xy 231.535011 -319.137171) (xy 231.545218 -319.157943) (xy 231.55402 -319.165478)
			(xy 231.576497 -319.183676) (xy 231.616232 -319.225695) (xy 231.649171 -319.273229) (xy 231.67456 -319.325188)
			(xy 231.691818 -319.380384) (xy 231.70055 -319.437553) (xy 231.701086 -319.466468) (xy 231.7006 -319.493719)
			(xy 231.692844 -319.547667) (xy 231.677489 -319.599962) (xy 231.654847 -319.649539) (xy 231.625381 -319.695389)
			(xy 231.58969 -319.73658) (xy 231.548499 -319.772271) (xy 231.502649 -319.801737) (xy 231.453072 -319.824379)
			(xy 231.400777 -319.839734) (xy 231.346829 -319.84749) (xy 231.292327 -319.84749) (xy 231.238379 -319.839734)
			(xy 231.186084 -319.824379) (xy 231.136507 -319.801737) (xy 231.090657 -319.772271) (xy 231.049466 -319.73658)
			(xy 231.013775 -319.695389) (xy 230.984309 -319.649539) (xy 230.961667 -319.599962) (xy 230.946312 -319.547667)
			(xy 230.938556 -319.493719) (xy 230.93807 -319.466468) (xy 230.938611 -319.437552) (xy 230.947331 -319.38038)
			(xy 230.964583 -319.325181) (xy 230.989971 -319.273218) (xy 231.022912 -319.225684) (xy 231.062651 -319.183668)
			(xy 231.085136 -319.165478) (xy 231.093909 -319.157927) (xy 231.104085 -319.13716) (xy 231.104694 -319.1256)
			(xy 231.104694 -319.045336) (xy 231.104105 -319.033771) (xy 231.093924 -319.012999) (xy 231.085136 -319.005458)
			(xy 231.064323 -318.988742) (xy 231.027194 -318.950383) (xy 230.995774 -318.907224) (xy 230.970678 -318.860106)
			(xy 230.952394 -318.80995) (xy 230.94128 -318.757735) (xy 230.937553 -318.70448) (xy 227.993169 -318.70448)
			(xy 227.989442 -318.757729) (xy 227.978328 -318.809938) (xy 227.960044 -318.860089) (xy 227.934948 -318.9072)
			(xy 227.903529 -318.950353) (xy 227.866401 -318.988705) (xy 227.84562 -319.005458) (xy 227.836868 -319.013029)
			(xy 227.826683 -319.033781) (xy 227.826062 -319.045336) (xy 227.826062 -319.1256) (xy 227.826611 -319.137171)
			(xy 227.836818 -319.157943) (xy 227.84562 -319.165478) (xy 227.868097 -319.183676) (xy 227.907832 -319.225695)
			(xy 227.940771 -319.273229) (xy 227.96616 -319.325188) (xy 227.983418 -319.380384) (xy 227.99215 -319.437553)
			(xy 227.992686 -319.466468) (xy 227.9922 -319.493719) (xy 227.984444 -319.547667) (xy 227.969089 -319.599962)
			(xy 227.946447 -319.649539) (xy 227.916981 -319.695389) (xy 227.88129 -319.73658) (xy 227.840099 -319.772271)
			(xy 227.794249 -319.801737) (xy 227.744672 -319.824379) (xy 227.692377 -319.839734) (xy 227.638429 -319.84749)
			(xy 227.583927 -319.84749) (xy 227.529979 -319.839734) (xy 227.477684 -319.824379) (xy 227.428107 -319.801737)
			(xy 227.382257 -319.772271) (xy 227.341066 -319.73658) (xy 227.305375 -319.695389) (xy 227.275909 -319.649539)
			(xy 227.253267 -319.599962) (xy 227.237912 -319.547667) (xy 227.230156 -319.493719) (xy 227.22967 -319.466468)
			(xy 227.230211 -319.437552) (xy 227.238931 -319.38038) (xy 227.256183 -319.325181) (xy 227.281571 -319.273218)
			(xy 227.314512 -319.225684) (xy 227.354251 -319.183668) (xy 227.376736 -319.165478) (xy 227.385509 -319.157927)
			(xy 227.395685 -319.13716) (xy 227.396294 -319.1256) (xy 227.396294 -319.045336) (xy 227.395705 -319.033771)
			(xy 227.385524 -319.012999) (xy 227.376736 -319.005458) (xy 227.355923 -318.988742) (xy 227.318794 -318.950383)
			(xy 227.287374 -318.907224) (xy 227.262278 -318.860106) (xy 227.243994 -318.80995) (xy 227.23288 -318.757735)
			(xy 227.229153 -318.70448) (xy 225.605569 -318.70448) (xy 225.601842 -318.757729) (xy 225.590728 -318.809938)
			(xy 225.572444 -318.860089) (xy 225.547348 -318.9072) (xy 225.515929 -318.950353) (xy 225.478801 -318.988705)
			(xy 225.45802 -319.005458) (xy 225.449268 -319.013029) (xy 225.439083 -319.033781) (xy 225.438462 -319.045336)
			(xy 225.438462 -319.1256) (xy 225.439011 -319.137171) (xy 225.449218 -319.157943) (xy 225.45802 -319.165478)
			(xy 225.480497 -319.183676) (xy 225.520232 -319.225695) (xy 225.553171 -319.273229) (xy 225.57856 -319.325188)
			(xy 225.595818 -319.380384) (xy 225.60455 -319.437553) (xy 225.605086 -319.466468) (xy 225.6046 -319.493719)
			(xy 225.596844 -319.547667) (xy 225.581489 -319.599962) (xy 225.558847 -319.649539) (xy 225.529381 -319.695389)
			(xy 225.49369 -319.73658) (xy 225.452499 -319.772271) (xy 225.406649 -319.801737) (xy 225.357072 -319.824379)
			(xy 225.304777 -319.839734) (xy 225.250829 -319.84749) (xy 225.196327 -319.84749) (xy 225.142379 -319.839734)
			(xy 225.090084 -319.824379) (xy 225.040507 -319.801737) (xy 224.994657 -319.772271) (xy 224.953466 -319.73658)
			(xy 224.917775 -319.695389) (xy 224.888309 -319.649539) (xy 224.865667 -319.599962) (xy 224.850312 -319.547667)
			(xy 224.842556 -319.493719) (xy 224.84207 -319.466468) (xy 224.842611 -319.437552) (xy 224.851331 -319.38038)
			(xy 224.868583 -319.325181) (xy 224.893971 -319.273218) (xy 224.926912 -319.225684) (xy 224.966651 -319.183668)
			(xy 224.989136 -319.165478) (xy 224.997909 -319.157927) (xy 225.008085 -319.13716) (xy 225.008694 -319.1256)
			(xy 225.008694 -319.045336) (xy 225.008105 -319.033771) (xy 224.997924 -319.012999) (xy 224.989136 -319.005458)
			(xy 224.968323 -318.988742) (xy 224.931194 -318.950383) (xy 224.899774 -318.907224) (xy 224.874678 -318.860106)
			(xy 224.856394 -318.80995) (xy 224.84528 -318.757735) (xy 224.841553 -318.70448) (xy 220.453276 -318.70448)
			(xy 220.484797 -318.754147) (xy 220.512019 -318.811994) (xy 220.531775 -318.872796) (xy 220.543755 -318.935595)
			(xy 220.54777 -318.9994) (xy 220.543755 -319.063205) (xy 220.531775 -319.126004) (xy 220.512019 -319.186806)
			(xy 220.484797 -319.244653) (xy 220.45054 -319.298631) (xy 220.409788 -319.34789) (xy 220.363183 -319.391653)
			(xy 220.31146 -319.42923) (xy 220.255436 -319.460027) (xy 220.195993 -319.48356) (xy 220.134069 -319.499456)
			(xy 220.070642 -319.507466) (xy 220.038676 -319.50787) (xy 220.001556 -319.507177) (xy 219.92811 -319.496337)
			(xy 219.892372 -319.48628) (xy 219.880942 -319.482978) (xy 219.857066 -319.487042) (xy 219.782136 -319.542922)
			(xy 219.772948 -319.550483) (xy 219.762204 -319.571681) (xy 219.761562 -319.583562) (xy 219.761562 -321.672161)
			(xy 232.438442 -321.672161) (xy 232.438442 -321.608239) (xy 232.446453 -321.544821) (xy 232.46235 -321.482907)
			(xy 232.485882 -321.423474) (xy 232.516676 -321.367459) (xy 232.554249 -321.315744) (xy 232.598006 -321.269147)
			(xy 232.647259 -321.228402) (xy 232.70123 -321.194151) (xy 232.759069 -321.166934) (xy 232.819862 -321.147181)
			(xy 232.882652 -321.135203) (xy 232.946448 -321.13119) (xy 233.010244 -321.135203) (xy 233.073034 -321.147181)
			(xy 233.133827 -321.166934) (xy 233.191666 -321.194151) (xy 233.245637 -321.228402) (xy 233.29489 -321.269147)
			(xy 233.338647 -321.315744) (xy 233.37622 -321.367459) (xy 233.407014 -321.423474) (xy 233.430546 -321.482907)
			(xy 233.446443 -321.544821) (xy 233.454454 -321.608239) (xy 233.454956 -321.6402) (xy 233.454768 -321.652138)
			(xy 235.520736 -321.652138) (xy 235.524807 -321.596516) (xy 235.536933 -321.542079) (xy 235.556856 -321.489988)
			(xy 235.584152 -321.441353) (xy 235.618238 -321.39721) (xy 235.658387 -321.358501) (xy 235.703745 -321.32605)
			(xy 235.753345 -321.300549) (xy 235.806129 -321.282542) (xy 235.860972 -321.272412) (xy 235.916706 -321.270375)
			(xy 235.972143 -321.276475) (xy 236.0261 -321.290581) (xy 236.077429 -321.312393) (xy 236.125035 -321.341447)
			(xy 236.167903 -321.377122) (xy 236.20512 -321.418659) (xy 236.235893 -321.465172) (xy 236.259565 -321.515669)
			(xy 236.275633 -321.569076) (xy 236.283753 -321.624252) (xy 236.284262 -321.652138) (xy 236.283753 -321.680024)
			(xy 236.275633 -321.7352) (xy 236.259565 -321.788607) (xy 236.235893 -321.839104) (xy 236.20512 -321.885617)
			(xy 236.167903 -321.927154) (xy 236.125035 -321.962829) (xy 236.077429 -321.991883) (xy 236.0261 -322.013695)
			(xy 235.972143 -322.027801) (xy 235.916706 -322.033901) (xy 235.860972 -322.031864) (xy 235.806129 -322.021734)
			(xy 235.753345 -322.003727) (xy 235.703745 -321.978226) (xy 235.658387 -321.945775) (xy 235.618238 -321.907066)
			(xy 235.584152 -321.862923) (xy 235.556856 -321.814288) (xy 235.536933 -321.762197) (xy 235.524807 -321.70776)
			(xy 235.520736 -321.652138) (xy 233.454768 -321.652138) (xy 233.454454 -321.672161) (xy 233.446443 -321.735579)
			(xy 233.430546 -321.797493) (xy 233.407014 -321.856926) (xy 233.37622 -321.912941) (xy 233.338647 -321.964656)
			(xy 233.29489 -322.011253) (xy 233.245637 -322.051998) (xy 233.191666 -322.086249) (xy 233.133827 -322.113466)
			(xy 233.073034 -322.133219) (xy 233.010244 -322.145197) (xy 232.946448 -322.149211) (xy 232.882652 -322.145197)
			(xy 232.819862 -322.133219) (xy 232.759069 -322.113466) (xy 232.70123 -322.086249) (xy 232.647259 -322.051998)
			(xy 232.598006 -322.011253) (xy 232.554249 -321.964656) (xy 232.516676 -321.912941) (xy 232.485882 -321.856926)
			(xy 232.46235 -321.797493) (xy 232.446453 -321.735579) (xy 232.438442 -321.672161) (xy 219.761562 -321.672161)
			(xy 219.761562 -322.17868) (xy 229.228902 -322.17868) (xy 229.232973 -322.123058) (xy 229.245099 -322.068621)
			(xy 229.265022 -322.01653) (xy 229.292318 -321.967895) (xy 229.326404 -321.923752) (xy 229.366553 -321.885043)
			(xy 229.411911 -321.852592) (xy 229.461511 -321.827091) (xy 229.514295 -321.809084) (xy 229.569138 -321.798954)
			(xy 229.624872 -321.796917) (xy 229.680309 -321.803017) (xy 229.734266 -321.817123) (xy 229.785595 -321.838935)
			(xy 229.833201 -321.867989) (xy 229.876069 -321.903664) (xy 229.913286 -321.945201) (xy 229.944059 -321.991714)
			(xy 229.967731 -322.042211) (xy 229.983799 -322.095618) (xy 229.991919 -322.150794) (xy 229.992428 -322.17868)
			(xy 229.991919 -322.206566) (xy 229.983799 -322.261742) (xy 229.967731 -322.315149) (xy 229.944059 -322.365646)
			(xy 229.913286 -322.412159) (xy 229.876069 -322.453696) (xy 229.833201 -322.489371) (xy 229.785595 -322.518425)
			(xy 229.734266 -322.540237) (xy 229.680309 -322.554343) (xy 229.624872 -322.560443) (xy 229.569138 -322.558406)
			(xy 229.514295 -322.548276) (xy 229.461511 -322.530269) (xy 229.411911 -322.504768) (xy 229.366553 -322.472317)
			(xy 229.326404 -322.433608) (xy 229.292318 -322.389465) (xy 229.265022 -322.34083) (xy 229.245099 -322.288739)
			(xy 229.232973 -322.234302) (xy 229.228902 -322.17868) (xy 219.761562 -322.17868) (xy 219.761562 -323.263768)
			(xy 229.240078 -323.263768) (xy 229.244149 -323.208146) (xy 229.256275 -323.153709) (xy 229.276198 -323.101618)
			(xy 229.303494 -323.052983) (xy 229.33758 -323.00884) (xy 229.377729 -322.970131) (xy 229.423087 -322.93768)
			(xy 229.472687 -322.912179) (xy 229.525471 -322.894172) (xy 229.580314 -322.884042) (xy 229.636048 -322.882005)
			(xy 229.691485 -322.888105) (xy 229.745442 -322.902211) (xy 229.796771 -322.924023) (xy 229.844377 -322.953077)
			(xy 229.887245 -322.988752) (xy 229.924462 -323.030289) (xy 229.955235 -323.076802) (xy 229.978907 -323.127299)
			(xy 229.994975 -323.180706) (xy 230.003095 -323.235882) (xy 230.003604 -323.263768) (xy 230.003095 -323.291654)
			(xy 229.994975 -323.34683) (xy 229.978907 -323.400237) (xy 229.955235 -323.450734) (xy 229.924462 -323.497247)
			(xy 229.887245 -323.538784) (xy 229.844377 -323.574459) (xy 229.796771 -323.603513) (xy 229.745442 -323.625325)
			(xy 229.691485 -323.639431) (xy 229.636048 -323.645531) (xy 229.580314 -323.643494) (xy 229.525471 -323.633364)
			(xy 229.472687 -323.615357) (xy 229.423087 -323.589856) (xy 229.377729 -323.557405) (xy 229.33758 -323.518696)
			(xy 229.303494 -323.474553) (xy 229.276198 -323.425918) (xy 229.256275 -323.373827) (xy 229.244149 -323.31939)
			(xy 229.240078 -323.263768) (xy 219.761562 -323.263768) (xy 219.761562 -323.913754) (xy 232.44175 -323.913754)
			(xy 232.442263 -323.881462) (xy 232.450427 -323.817396) (xy 232.466644 -323.754882) (xy 232.490651 -323.694926)
			(xy 232.522062 -323.638495) (xy 232.56037 -323.5865) (xy 232.604958 -323.539778) (xy 232.655107 -323.499082)
			(xy 232.710008 -323.465069) (xy 232.739184 -323.45122) (xy 232.751884 -323.445378) (xy 232.767886 -323.422264)
			(xy 232.775252 -323.304662) (xy 232.762552 -323.27977) (xy 232.75036 -323.272404) (xy 232.723216 -323.254933)
			(xy 232.673127 -323.214212) (xy 232.628592 -323.167481) (xy 232.590329 -323.11549) (xy 232.558952 -323.059076)
			(xy 232.534965 -322.999145) (xy 232.518754 -322.93666) (xy 232.51058 -322.872627) (xy 232.510076 -322.84035)
			(xy 232.510578 -322.808389) (xy 232.518589 -322.744971) (xy 232.534486 -322.683057) (xy 232.558018 -322.623624)
			(xy 232.588812 -322.567609) (xy 232.626385 -322.515894) (xy 232.670142 -322.469297) (xy 232.719395 -322.428552)
			(xy 232.773366 -322.394301) (xy 232.831205 -322.367084) (xy 232.891998 -322.347331) (xy 232.954788 -322.335353)
			(xy 233.018584 -322.33134) (xy 233.08238 -322.335353) (xy 233.14517 -322.347331) (xy 233.205963 -322.367084)
			(xy 233.263802 -322.394301) (xy 233.317773 -322.428552) (xy 233.367026 -322.469297) (xy 233.410783 -322.515894)
			(xy 233.448356 -322.567609) (xy 233.47915 -322.623624) (xy 233.502682 -322.683057) (xy 233.50283 -322.683632)
			(xy 235.558836 -322.683632) (xy 235.562907 -322.62801) (xy 235.575033 -322.573573) (xy 235.594956 -322.521482)
			(xy 235.622252 -322.472847) (xy 235.656338 -322.428704) (xy 235.696487 -322.389995) (xy 235.741845 -322.357544)
			(xy 235.791445 -322.332043) (xy 235.844229 -322.314036) (xy 235.899072 -322.303906) (xy 235.954806 -322.301869)
			(xy 236.010243 -322.307969) (xy 236.0642 -322.322075) (xy 236.115529 -322.343887) (xy 236.163135 -322.372941)
			(xy 236.206003 -322.408616) (xy 236.24322 -322.450153) (xy 236.273993 -322.496666) (xy 236.297665 -322.547163)
			(xy 236.313733 -322.60057) (xy 236.321853 -322.655746) (xy 236.322362 -322.683632) (xy 236.321853 -322.711518)
			(xy 236.313733 -322.766694) (xy 236.297665 -322.820101) (xy 236.273993 -322.870598) (xy 236.24322 -322.917111)
			(xy 236.206003 -322.958648) (xy 236.163135 -322.994323) (xy 236.115529 -323.023377) (xy 236.0642 -323.045189)
			(xy 236.010243 -323.059295) (xy 235.954806 -323.065395) (xy 235.899072 -323.063358) (xy 235.844229 -323.053228)
			(xy 235.791445 -323.035221) (xy 235.741845 -323.00972) (xy 235.696487 -322.977269) (xy 235.656338 -322.93856)
			(xy 235.622252 -322.894417) (xy 235.594956 -322.845782) (xy 235.575033 -322.793691) (xy 235.562907 -322.739254)
			(xy 235.558836 -322.683632) (xy 233.50283 -322.683632) (xy 233.518579 -322.744971) (xy 233.52659 -322.808389)
			(xy 233.527092 -322.84035) (xy 233.526616 -322.872643) (xy 233.51845 -322.936712) (xy 233.502231 -322.999229)
			(xy 233.478221 -323.059187) (xy 233.446805 -323.115618) (xy 233.408492 -323.167614) (xy 233.363899 -323.214335)
			(xy 233.313744 -323.255028) (xy 233.258837 -323.289038) (xy 233.229658 -323.302884) (xy 233.216958 -323.308726)
			(xy 233.200956 -323.33184) (xy 233.19359 -323.449442) (xy 233.20629 -323.474334) (xy 233.218482 -323.4817)
			(xy 233.245638 -323.499154) (xy 233.295725 -323.539879) (xy 233.340257 -323.586613) (xy 233.378519 -323.638607)
			(xy 233.409894 -323.695023) (xy 233.43034 -323.746114) (xy 235.54639 -323.746114) (xy 235.550461 -323.690492)
			(xy 235.562587 -323.636055) (xy 235.58251 -323.583964) (xy 235.609806 -323.535329) (xy 235.643892 -323.491186)
			(xy 235.684041 -323.452477) (xy 235.729399 -323.420026) (xy 235.778999 -323.394525) (xy 235.831783 -323.376518)
			(xy 235.886626 -323.366388) (xy 235.94236 -323.364351) (xy 235.997797 -323.370451) (xy 236.051754 -323.384557)
			(xy 236.103083 -323.406369) (xy 236.150689 -323.435423) (xy 236.193557 -323.471098) (xy 236.230774 -323.512635)
			(xy 236.261547 -323.559148) (xy 236.285219 -323.609645) (xy 236.301287 -323.663052) (xy 236.309407 -323.718228)
			(xy 236.309916 -323.746114) (xy 236.309407 -323.774) (xy 236.301287 -323.829176) (xy 236.285219 -323.882583)
			(xy 236.261547 -323.93308) (xy 236.230774 -323.979593) (xy 236.193557 -324.02113) (xy 236.150689 -324.056805)
			(xy 236.103083 -324.085859) (xy 236.051754 -324.107671) (xy 235.997797 -324.121777) (xy 235.94236 -324.127877)
			(xy 235.886626 -324.12584) (xy 235.831783 -324.11571) (xy 235.778999 -324.097703) (xy 235.729399 -324.072202)
			(xy 235.684041 -324.039751) (xy 235.643892 -324.001042) (xy 235.609806 -323.956899) (xy 235.58251 -323.908264)
			(xy 235.562587 -323.856173) (xy 235.550461 -323.801736) (xy 235.54639 -323.746114) (xy 233.43034 -323.746114)
			(xy 233.433879 -323.754956) (xy 233.450089 -323.817442) (xy 233.458263 -323.881477) (xy 233.458766 -323.913754)
			(xy 233.458227 -323.947343) (xy 233.449387 -324.013937) (xy 233.431854 -324.078786) (xy 233.405935 -324.140762)
			(xy 233.37208 -324.198786) (xy 233.330879 -324.251845) (xy 233.28305 -324.299018) (xy 233.229425 -324.339481)
			(xy 233.200448 -324.356476) (xy 233.188256 -324.363334) (xy 233.17454 -324.38721) (xy 233.175302 -324.503796)
			(xy 233.189526 -324.527418) (xy 233.201718 -324.534276) (xy 233.228082 -324.549152) (xy 233.277406 -324.584252)
			(xy 233.322212 -324.624961) (xy 233.361867 -324.670702) (xy 233.39581 -324.720828) (xy 233.423561 -324.774631)
			(xy 233.430454 -324.793102) (xy 235.578648 -324.793102) (xy 235.582719 -324.73748) (xy 235.594845 -324.683043)
			(xy 235.614768 -324.630952) (xy 235.642064 -324.582317) (xy 235.67615 -324.538174) (xy 235.716299 -324.499465)
			(xy 235.761657 -324.467014) (xy 235.811257 -324.441513) (xy 235.864041 -324.423506) (xy 235.918884 -324.413376)
			(xy 235.974618 -324.411339) (xy 236.030055 -324.417439) (xy 236.084012 -324.431545) (xy 236.135341 -324.453357)
			(xy 236.182947 -324.482411) (xy 236.225815 -324.518086) (xy 236.263032 -324.559623) (xy 236.293805 -324.606136)
			(xy 236.317477 -324.656633) (xy 236.333545 -324.71004) (xy 236.341665 -324.765216) (xy 236.342174 -324.793102)
			(xy 236.341665 -324.820988) (xy 236.333545 -324.876164) (xy 236.317477 -324.929571) (xy 236.293805 -324.980068)
			(xy 236.263032 -325.026581) (xy 236.225815 -325.068118) (xy 236.182947 -325.103793) (xy 236.135341 -325.132847)
			(xy 236.084012 -325.154659) (xy 236.030055 -325.168765) (xy 235.974618 -325.174865) (xy 235.918884 -325.172828)
			(xy 235.864041 -325.162698) (xy 235.811257 -325.144691) (xy 235.761657 -325.11919) (xy 235.716299 -325.086739)
			(xy 235.67615 -325.04803) (xy 235.642064 -325.003887) (xy 235.614768 -324.955252) (xy 235.594845 -324.903161)
			(xy 235.582719 -324.848724) (xy 235.578648 -324.793102) (xy 233.430454 -324.793102) (xy 233.444726 -324.831348)
			(xy 233.459007 -324.890177) (xy 233.466201 -324.950285) (xy 233.46664 -324.980554) (xy 233.466241 -325.011065)
			(xy 233.458939 -325.071648) (xy 233.444435 -325.130921) (xy 233.422937 -325.18803) (xy 233.394755 -325.242154)
			(xy 233.360294 -325.292514) (xy 233.320051 -325.338385) (xy 233.274604 -325.379106) (xy 233.224608 -325.414092)
			(xy 233.197908 -325.428864) (xy 233.185208 -325.435722) (xy 233.17073 -325.461122) (xy 233.17581 -325.582026)
			(xy 233.19232 -325.605902) (xy 233.205782 -325.611744) (xy 233.235794 -325.625236) (xy 233.292357 -325.658859)
			(xy 233.344113 -325.699494) (xy 233.390197 -325.746463) (xy 233.429841 -325.798982) (xy 233.462382 -325.856174)
			(xy 233.47792 -325.894192) (xy 235.54004 -325.894192) (xy 235.544111 -325.83857) (xy 235.556237 -325.784133)
			(xy 235.57616 -325.732042) (xy 235.603456 -325.683407) (xy 235.637542 -325.639264) (xy 235.677691 -325.600555)
			(xy 235.723049 -325.568104) (xy 235.772649 -325.542603) (xy 235.825433 -325.524596) (xy 235.880276 -325.514466)
			(xy 235.93601 -325.512429) (xy 235.991447 -325.518529) (xy 236.045404 -325.532635) (xy 236.096733 -325.554447)
			(xy 236.144339 -325.583501) (xy 236.187207 -325.619176) (xy 236.224424 -325.660713) (xy 236.255197 -325.707226)
			(xy 236.278869 -325.757723) (xy 236.294937 -325.81113) (xy 236.303057 -325.866306) (xy 236.303566 -325.894192)
			(xy 236.303057 -325.922078) (xy 236.294937 -325.977254) (xy 236.278869 -326.030661) (xy 236.255197 -326.081158)
			(xy 236.224424 -326.127671) (xy 236.187207 -326.169208) (xy 236.144339 -326.204883) (xy 236.096733 -326.233937)
			(xy 236.045404 -326.255749) (xy 235.991447 -326.269855) (xy 235.93601 -326.275955) (xy 235.880276 -326.273918)
			(xy 235.825433 -326.263788) (xy 235.772649 -326.245781) (xy 235.723049 -326.22028) (xy 235.677691 -326.187829)
			(xy 235.637542 -326.14912) (xy 235.603456 -326.104977) (xy 235.57616 -326.056342) (xy 235.556237 -326.004251)
			(xy 235.544111 -325.949814) (xy 235.54004 -325.894192) (xy 233.47792 -325.894192) (xy 233.487277 -325.917085)
			(xy 233.50411 -325.980697) (xy 233.512601 -326.045949) (xy 233.513122 -326.07885) (xy 233.51262 -326.110811)
			(xy 233.504609 -326.174229) (xy 233.488712 -326.236143) (xy 233.46518 -326.295576) (xy 233.434386 -326.351591)
			(xy 233.396813 -326.403306) (xy 233.353056 -326.449903) (xy 233.303803 -326.490648) (xy 233.249832 -326.524899)
			(xy 233.191993 -326.552116) (xy 233.1312 -326.571869) (xy 233.06841 -326.583847) (xy 233.004614 -326.587861)
			(xy 232.940818 -326.583847) (xy 232.878028 -326.571869) (xy 232.817235 -326.552116) (xy 232.759396 -326.524899)
			(xy 232.705425 -326.490648) (xy 232.656172 -326.449903) (xy 232.612415 -326.403306) (xy 232.574842 -326.351591)
			(xy 232.544048 -326.295576) (xy 232.520516 -326.236143) (xy 232.504619 -326.174229) (xy 232.496608 -326.110811)
			(xy 232.496106 -326.07885) (xy 232.496537 -326.04834) (xy 232.503837 -325.987759) (xy 232.518339 -325.928489)
			(xy 232.539834 -325.871381) (xy 232.568012 -325.817257) (xy 232.602469 -325.766898) (xy 232.642707 -325.721026)
			(xy 232.688149 -325.680303) (xy 232.73814 -325.645314) (xy 232.764838 -325.63054) (xy 232.777538 -325.623682)
			(xy 232.792016 -325.598282) (xy 232.786936 -325.477378) (xy 232.770426 -325.453502) (xy 232.756964 -325.44766)
			(xy 232.726942 -325.434191) (xy 232.67038 -325.400564) (xy 232.618626 -325.359924) (xy 232.572544 -325.312951)
			(xy 232.532902 -325.260429) (xy 232.500363 -325.203235) (xy 232.475469 -325.142322) (xy 232.458636 -325.078708)
			(xy 232.450145 -325.013455) (xy 232.449624 -324.980554) (xy 232.450174 -324.946965) (xy 232.459013 -324.880373)
			(xy 232.476545 -324.815523) (xy 232.502463 -324.753548) (xy 232.536316 -324.695524) (xy 232.577515 -324.642464)
			(xy 232.625343 -324.595292) (xy 232.678966 -324.554828) (xy 232.707942 -324.537832) (xy 232.720134 -324.530974)
			(xy 232.73385 -324.507098) (xy 232.733088 -324.390512) (xy 232.718864 -324.36689) (xy 232.706672 -324.360032)
			(xy 232.680309 -324.345154) (xy 232.630986 -324.310054) (xy 232.58618 -324.269345) (xy 232.546525 -324.223604)
			(xy 232.512582 -324.173478) (xy 232.484831 -324.119676) (xy 232.463666 -324.062959) (xy 232.449384 -324.004131)
			(xy 232.44219 -323.944023) (xy 232.44175 -323.913754) (xy 219.761562 -323.913754) (xy 219.761562 -324.349872)
			(xy 229.22052 -324.349872) (xy 229.224591 -324.29425) (xy 229.236717 -324.239813) (xy 229.25664 -324.187722)
			(xy 229.283936 -324.139087) (xy 229.318022 -324.094944) (xy 229.358171 -324.056235) (xy 229.403529 -324.023784)
			(xy 229.453129 -323.998283) (xy 229.505913 -323.980276) (xy 229.560756 -323.970146) (xy 229.61649 -323.968109)
			(xy 229.671927 -323.974209) (xy 229.725884 -323.988315) (xy 229.777213 -324.010127) (xy 229.824819 -324.039181)
			(xy 229.867687 -324.074856) (xy 229.904904 -324.116393) (xy 229.935677 -324.162906) (xy 229.959349 -324.213403)
			(xy 229.975417 -324.26681) (xy 229.983537 -324.321986) (xy 229.984046 -324.349872) (xy 229.983537 -324.377758)
			(xy 229.975417 -324.432934) (xy 229.959349 -324.486341) (xy 229.935677 -324.536838) (xy 229.904904 -324.583351)
			(xy 229.867687 -324.624888) (xy 229.824819 -324.660563) (xy 229.777213 -324.689617) (xy 229.725884 -324.711429)
			(xy 229.671927 -324.725535) (xy 229.61649 -324.731635) (xy 229.560756 -324.729598) (xy 229.505913 -324.719468)
			(xy 229.453129 -324.701461) (xy 229.403529 -324.67596) (xy 229.358171 -324.643509) (xy 229.318022 -324.6048)
			(xy 229.283936 -324.560657) (xy 229.25664 -324.512022) (xy 229.236717 -324.459931) (xy 229.224591 -324.405494)
			(xy 229.22052 -324.349872) (xy 219.761562 -324.349872) (xy 219.761562 -325.425562) (xy 229.208328 -325.425562)
			(xy 229.212399 -325.36994) (xy 229.224525 -325.315503) (xy 229.244448 -325.263412) (xy 229.271744 -325.214777)
			(xy 229.30583 -325.170634) (xy 229.345979 -325.131925) (xy 229.391337 -325.099474) (xy 229.440937 -325.073973)
			(xy 229.493721 -325.055966) (xy 229.548564 -325.045836) (xy 229.604298 -325.043799) (xy 229.659735 -325.049899)
			(xy 229.713692 -325.064005) (xy 229.765021 -325.085817) (xy 229.812627 -325.114871) (xy 229.855495 -325.150546)
			(xy 229.892712 -325.192083) (xy 229.923485 -325.238596) (xy 229.947157 -325.289093) (xy 229.963225 -325.3425)
			(xy 229.971345 -325.397676) (xy 229.971854 -325.425562) (xy 229.971345 -325.453448) (xy 229.963225 -325.508624)
			(xy 229.947157 -325.562031) (xy 229.923485 -325.612528) (xy 229.892712 -325.659041) (xy 229.855495 -325.700578)
			(xy 229.812627 -325.736253) (xy 229.765021 -325.765307) (xy 229.713692 -325.787119) (xy 229.659735 -325.801225)
			(xy 229.604298 -325.807325) (xy 229.548564 -325.805288) (xy 229.493721 -325.795158) (xy 229.440937 -325.777151)
			(xy 229.391337 -325.75165) (xy 229.345979 -325.719199) (xy 229.30583 -325.68049) (xy 229.271744 -325.636347)
			(xy 229.244448 -325.587712) (xy 229.224525 -325.535621) (xy 229.212399 -325.481184) (xy 229.208328 -325.425562)
			(xy 219.761562 -325.425562) (xy 219.761562 -326.49668) (xy 229.220012 -326.49668) (xy 229.224083 -326.441058)
			(xy 229.236209 -326.386621) (xy 229.256132 -326.33453) (xy 229.283428 -326.285895) (xy 229.317514 -326.241752)
			(xy 229.357663 -326.203043) (xy 229.403021 -326.170592) (xy 229.452621 -326.145091) (xy 229.505405 -326.127084)
			(xy 229.560248 -326.116954) (xy 229.615982 -326.114917) (xy 229.671419 -326.121017) (xy 229.725376 -326.135123)
			(xy 229.776705 -326.156935) (xy 229.824311 -326.185989) (xy 229.867179 -326.221664) (xy 229.904396 -326.263201)
			(xy 229.935169 -326.309714) (xy 229.958841 -326.360211) (xy 229.974909 -326.413618) (xy 229.983029 -326.468794)
			(xy 229.983538 -326.49668) (xy 229.983029 -326.524566) (xy 229.974909 -326.579742) (xy 229.958841 -326.633149)
			(xy 229.935169 -326.683646) (xy 229.904396 -326.730159) (xy 229.867179 -326.771696) (xy 229.824311 -326.807371)
			(xy 229.776705 -326.836425) (xy 229.725376 -326.858237) (xy 229.671419 -326.872343) (xy 229.615982 -326.878443)
			(xy 229.560248 -326.876406) (xy 229.505405 -326.866276) (xy 229.452621 -326.848269) (xy 229.403021 -326.822768)
			(xy 229.357663 -326.790317) (xy 229.317514 -326.751608) (xy 229.283428 -326.707465) (xy 229.256132 -326.65883)
			(xy 229.236209 -326.606739) (xy 229.224083 -326.552302) (xy 229.220012 -326.49668) (xy 219.761562 -326.49668)
			(xy 219.761562 -326.497442) (xy 219.76113 -326.507508) (xy 219.753401 -326.526098) (xy 219.746576 -326.53351)
			(xy 218.714066 -327.56602) (xy 229.214424 -327.56602) (xy 229.218495 -327.510398) (xy 229.230621 -327.455961)
			(xy 229.250544 -327.40387) (xy 229.27784 -327.355235) (xy 229.311926 -327.311092) (xy 229.352075 -327.272383)
			(xy 229.397433 -327.239932) (xy 229.447033 -327.214431) (xy 229.499817 -327.196424) (xy 229.55466 -327.186294)
			(xy 229.610394 -327.184257) (xy 229.665831 -327.190357) (xy 229.719788 -327.204463) (xy 229.771117 -327.226275)
			(xy 229.818723 -327.255329) (xy 229.861591 -327.291004) (xy 229.898808 -327.332541) (xy 229.929581 -327.379054)
			(xy 229.953253 -327.429551) (xy 229.969321 -327.482958) (xy 229.977441 -327.538134) (xy 229.97795 -327.56602)
			(xy 229.977441 -327.593906) (xy 229.969321 -327.649082) (xy 229.953253 -327.702489) (xy 229.929581 -327.752986)
			(xy 229.898808 -327.799499) (xy 229.861591 -327.841036) (xy 229.818723 -327.876711) (xy 229.771117 -327.905765)
			(xy 229.719788 -327.927577) (xy 229.665831 -327.941683) (xy 229.610394 -327.947783) (xy 229.55466 -327.945746)
			(xy 229.499817 -327.935616) (xy 229.447033 -327.917609) (xy 229.397433 -327.892108) (xy 229.352075 -327.859657)
			(xy 229.311926 -327.820948) (xy 229.27784 -327.776805) (xy 229.250544 -327.72817) (xy 229.230621 -327.676079)
			(xy 229.218495 -327.621642) (xy 229.214424 -327.56602) (xy 218.714066 -327.56602) (xy 218.028266 -328.25182)
			(xy 232.382822 -328.25182) (xy 232.383345 -328.218264) (xy 232.392159 -328.151735) (xy 232.40965 -328.086943)
			(xy 232.435514 -328.025017) (xy 232.469301 -327.967031) (xy 232.510424 -327.913995) (xy 232.558167 -327.866831)
			(xy 232.611701 -327.826359) (xy 232.640632 -327.809352) (xy 232.65257 -327.802748) (xy 232.666032 -327.780396)
			(xy 232.669842 -327.666858) (xy 232.657904 -327.64349) (xy 232.646728 -327.636124) (xy 232.620747 -327.618478)
			(xy 232.572966 -327.577715) (xy 232.53057 -327.531376) (xy 232.494205 -327.480167) (xy 232.464426 -327.424869)
			(xy 232.441686 -327.366323) (xy 232.426331 -327.305422) (xy 232.418595 -327.243093) (xy 232.418128 -327.21169)
			(xy 232.41863 -327.179729) (xy 232.426641 -327.116311) (xy 232.442538 -327.054397) (xy 232.46607 -326.994964)
			(xy 232.496864 -326.938949) (xy 232.534437 -326.887234) (xy 232.578194 -326.840637) (xy 232.627447 -326.799892)
			(xy 232.681418 -326.765641) (xy 232.739257 -326.738424) (xy 232.80005 -326.718671) (xy 232.86284 -326.706693)
			(xy 232.926636 -326.70268) (xy 232.990432 -326.706693) (xy 233.053222 -326.718671) (xy 233.114015 -326.738424)
			(xy 233.171854 -326.765641) (xy 233.225825 -326.799892) (xy 233.275078 -326.840637) (xy 233.318835 -326.887234)
			(xy 233.356408 -326.938949) (xy 233.360846 -326.947022) (xy 235.565694 -326.947022) (xy 235.569765 -326.8914)
			(xy 235.581891 -326.836963) (xy 235.601814 -326.784872) (xy 235.62911 -326.736237) (xy 235.663196 -326.692094)
			(xy 235.703345 -326.653385) (xy 235.748703 -326.620934) (xy 235.798303 -326.595433) (xy 235.851087 -326.577426)
			(xy 235.90593 -326.567296) (xy 235.961664 -326.565259) (xy 236.017101 -326.571359) (xy 236.071058 -326.585465)
			(xy 236.122387 -326.607277) (xy 236.169993 -326.636331) (xy 236.212861 -326.672006) (xy 236.250078 -326.713543)
			(xy 236.280851 -326.760056) (xy 236.304523 -326.810553) (xy 236.320591 -326.86396) (xy 236.328711 -326.919136)
			(xy 236.32922 -326.947022) (xy 236.328711 -326.974908) (xy 236.320591 -327.030084) (xy 236.304523 -327.083491)
			(xy 236.280851 -327.133988) (xy 236.250078 -327.180501) (xy 236.212861 -327.222038) (xy 236.169993 -327.257713)
			(xy 236.122387 -327.286767) (xy 236.071058 -327.308579) (xy 236.017101 -327.322685) (xy 235.961664 -327.328785)
			(xy 235.90593 -327.326748) (xy 235.851087 -327.316618) (xy 235.798303 -327.298611) (xy 235.748703 -327.27311)
			(xy 235.703345 -327.240659) (xy 235.663196 -327.20195) (xy 235.62911 -327.157807) (xy 235.601814 -327.109172)
			(xy 235.581891 -327.057081) (xy 235.569765 -327.002644) (xy 235.565694 -326.947022) (xy 233.360846 -326.947022)
			(xy 233.387202 -326.994964) (xy 233.410734 -327.054397) (xy 233.426631 -327.116311) (xy 233.434642 -327.179729)
			(xy 233.435144 -327.21169) (xy 233.434647 -327.245247) (xy 233.42583 -327.311778) (xy 233.408336 -327.376571)
			(xy 233.382469 -327.438498) (xy 233.348679 -327.496484) (xy 233.307552 -327.549519) (xy 233.259805 -327.596682)
			(xy 233.206267 -327.637153) (xy 233.177334 -327.654158) (xy 233.165396 -327.660762) (xy 233.151934 -327.683114)
			(xy 233.148124 -327.796652) (xy 233.160062 -327.82002) (xy 233.171238 -327.827386) (xy 233.197216 -327.845036)
			(xy 233.244998 -327.885798) (xy 233.287396 -327.932136) (xy 233.323761 -327.983343) (xy 233.353541 -328.038641)
			(xy 233.371822 -328.085704) (xy 235.560106 -328.085704) (xy 235.564177 -328.030082) (xy 235.576303 -327.975645)
			(xy 235.596226 -327.923554) (xy 235.623522 -327.874919) (xy 235.657608 -327.830776) (xy 235.697757 -327.792067)
			(xy 235.743115 -327.759616) (xy 235.792715 -327.734115) (xy 235.845499 -327.716108) (xy 235.900342 -327.705978)
			(xy 235.956076 -327.703941) (xy 236.011513 -327.710041) (xy 236.06547 -327.724147) (xy 236.116799 -327.745959)
			(xy 236.164405 -327.775013) (xy 236.207273 -327.810688) (xy 236.24449 -327.852225) (xy 236.275263 -327.898738)
			(xy 236.298935 -327.949235) (xy 236.315003 -328.002642) (xy 236.323123 -328.057818) (xy 236.323632 -328.085704)
			(xy 236.323123 -328.11359) (xy 236.315003 -328.168766) (xy 236.298935 -328.222173) (xy 236.275263 -328.27267)
			(xy 236.24449 -328.319183) (xy 236.207273 -328.36072) (xy 236.164405 -328.396395) (xy 236.116799 -328.425449)
			(xy 236.06547 -328.447261) (xy 236.011513 -328.461367) (xy 235.956076 -328.467467) (xy 235.900342 -328.46543)
			(xy 235.845499 -328.4553) (xy 235.792715 -328.437293) (xy 235.743115 -328.411792) (xy 235.697757 -328.379341)
			(xy 235.657608 -328.340632) (xy 235.623522 -328.296489) (xy 235.596226 -328.247854) (xy 235.576303 -328.195763)
			(xy 235.564177 -328.141326) (xy 235.560106 -328.085704) (xy 233.371822 -328.085704) (xy 233.376282 -328.097187)
			(xy 233.391637 -328.158088) (xy 233.399372 -328.220417) (xy 233.399838 -328.25182) (xy 233.399313 -328.28397)
			(xy 233.391194 -328.347756) (xy 233.375099 -328.410009) (xy 233.351287 -328.469738) (xy 233.320136 -328.525989)
			(xy 233.282144 -328.577865) (xy 233.237916 -328.624538) (xy 233.188158 -328.665265) (xy 233.133664 -328.699396)
			(xy 233.10469 -328.713338) (xy 233.090974 -328.719688) (xy 233.074972 -328.745088) (xy 233.076496 -328.86777)
			(xy 233.093006 -328.892662) (xy 233.106722 -328.898758) (xy 233.136596 -328.91232) (xy 233.192907 -328.945988)
			(xy 233.24442 -328.986621) (xy 233.290278 -329.033541) (xy 233.329719 -329.085971) (xy 233.362088 -329.143039)
			(xy 233.37433 -329.173078) (xy 235.579664 -329.173078) (xy 235.583735 -329.117456) (xy 235.595861 -329.063019)
			(xy 235.615784 -329.010928) (xy 235.64308 -328.962293) (xy 235.677166 -328.91815) (xy 235.717315 -328.879441)
			(xy 235.762673 -328.84699) (xy 235.812273 -328.821489) (xy 235.865057 -328.803482) (xy 235.9199 -328.793352)
			(xy 235.975634 -328.791315) (xy 236.031071 -328.797415) (xy 236.085028 -328.811521) (xy 236.136357 -328.833333)
			(xy 236.183963 -328.862387) (xy 236.226831 -328.898062) (xy 236.264048 -328.939599) (xy 236.294821 -328.986112)
			(xy 236.318493 -329.036609) (xy 236.334561 -329.090016) (xy 236.342681 -329.145192) (xy 236.34319 -329.173078)
			(xy 236.342681 -329.200964) (xy 236.334561 -329.25614) (xy 236.318493 -329.309547) (xy 236.294821 -329.360044)
			(xy 236.264048 -329.406557) (xy 236.226831 -329.448094) (xy 236.183963 -329.483769) (xy 236.136357 -329.512823)
			(xy 236.085028 -329.534635) (xy 236.031071 -329.548741) (xy 235.975634 -329.554841) (xy 235.9199 -329.552804)
			(xy 235.865057 -329.542674) (xy 235.812273 -329.524667) (xy 235.762673 -329.499166) (xy 235.717315 -329.466715)
			(xy 235.677166 -329.428006) (xy 235.64308 -329.383863) (xy 235.615784 -329.335228) (xy 235.595861 -329.283137)
			(xy 235.583735 -329.2287) (xy 235.579664 -329.173078) (xy 233.37433 -329.173078) (xy 233.386848 -329.203796)
			(xy 233.403586 -329.267234) (xy 233.412025 -329.332298) (xy 233.412538 -329.365102) (xy 233.412036 -329.397063)
			(xy 233.404025 -329.460481) (xy 233.388128 -329.522395) (xy 233.364596 -329.581828) (xy 233.333802 -329.637843)
			(xy 233.296229 -329.689558) (xy 233.252472 -329.736155) (xy 233.203219 -329.7769) (xy 233.149248 -329.811151)
			(xy 233.091409 -329.838368) (xy 233.030616 -329.858121) (xy 232.967826 -329.870099) (xy 232.90403 -329.874113)
			(xy 232.840234 -329.870099) (xy 232.777444 -329.858121) (xy 232.716651 -329.838368) (xy 232.658812 -329.811151)
			(xy 232.604841 -329.7769) (xy 232.555588 -329.736155) (xy 232.511831 -329.689558) (xy 232.474258 -329.637843)
			(xy 232.443464 -329.581828) (xy 232.419932 -329.522395) (xy 232.404035 -329.460481) (xy 232.396024 -329.397063)
			(xy 232.395522 -329.365102) (xy 232.396088 -329.332953) (xy 232.404204 -329.26917) (xy 232.420295 -329.206919)
			(xy 232.444103 -329.147192) (xy 232.475248 -329.090942) (xy 232.513235 -329.039065) (xy 232.557457 -328.992391)
			(xy 232.60721 -328.951662) (xy 232.661699 -328.917528) (xy 232.69067 -328.903584) (xy 232.704386 -328.897234)
			(xy 232.720388 -328.871834) (xy 232.718864 -328.749152) (xy 232.702354 -328.72426) (xy 232.688638 -328.718164)
			(xy 232.658763 -328.704604) (xy 232.602454 -328.670933) (xy 232.550943 -328.6303) (xy 232.505086 -328.583378)
			(xy 232.465646 -328.530948) (xy 232.433277 -328.473881) (xy 232.408517 -328.413124) (xy 232.391777 -328.349687)
			(xy 232.383336 -328.284624) (xy 232.382822 -328.25182) (xy 218.028266 -328.25182) (xy 217.641424 -328.638662)
			(xy 229.145336 -328.638662) (xy 229.149407 -328.58304) (xy 229.161533 -328.528603) (xy 229.181456 -328.476512)
			(xy 229.208752 -328.427877) (xy 229.242838 -328.383734) (xy 229.282987 -328.345025) (xy 229.328345 -328.312574)
			(xy 229.377945 -328.287073) (xy 229.430729 -328.269066) (xy 229.485572 -328.258936) (xy 229.541306 -328.256899)
			(xy 229.596743 -328.262999) (xy 229.6507 -328.277105) (xy 229.702029 -328.298917) (xy 229.749635 -328.327971)
			(xy 229.792503 -328.363646) (xy 229.82972 -328.405183) (xy 229.860493 -328.451696) (xy 229.884165 -328.502193)
			(xy 229.900233 -328.5556) (xy 229.908353 -328.610776) (xy 229.908862 -328.638662) (xy 229.908353 -328.666548)
			(xy 229.900233 -328.721724) (xy 229.884165 -328.775131) (xy 229.860493 -328.825628) (xy 229.82972 -328.872141)
			(xy 229.792503 -328.913678) (xy 229.749635 -328.949353) (xy 229.702029 -328.978407) (xy 229.6507 -329.000219)
			(xy 229.596743 -329.014325) (xy 229.541306 -329.020425) (xy 229.485572 -329.018388) (xy 229.430729 -329.008258)
			(xy 229.377945 -328.990251) (xy 229.328345 -328.96475) (xy 229.282987 -328.932299) (xy 229.242838 -328.89359)
			(xy 229.208752 -328.849447) (xy 229.181456 -328.800812) (xy 229.161533 -328.748721) (xy 229.149407 -328.694284)
			(xy 229.145336 -328.638662) (xy 217.641424 -328.638662) (xy 216.581228 -329.698858) (xy 229.155242 -329.698858)
			(xy 229.159313 -329.643236) (xy 229.171439 -329.588799) (xy 229.191362 -329.536708) (xy 229.218658 -329.488073)
			(xy 229.252744 -329.44393) (xy 229.292893 -329.405221) (xy 229.338251 -329.37277) (xy 229.387851 -329.347269)
			(xy 229.440635 -329.329262) (xy 229.495478 -329.319132) (xy 229.551212 -329.317095) (xy 229.606649 -329.323195)
			(xy 229.660606 -329.337301) (xy 229.711935 -329.359113) (xy 229.759541 -329.388167) (xy 229.802409 -329.423842)
			(xy 229.839626 -329.465379) (xy 229.870399 -329.511892) (xy 229.894071 -329.562389) (xy 229.910139 -329.615796)
			(xy 229.918259 -329.670972) (xy 229.918768 -329.698858) (xy 229.918259 -329.726744) (xy 229.910139 -329.78192)
			(xy 229.894071 -329.835327) (xy 229.870399 -329.885824) (xy 229.839626 -329.932337) (xy 229.802409 -329.973874)
			(xy 229.759541 -330.009549) (xy 229.711935 -330.038603) (xy 229.660606 -330.060415) (xy 229.606649 -330.074521)
			(xy 229.551212 -330.080621) (xy 229.495478 -330.078584) (xy 229.440635 -330.068454) (xy 229.387851 -330.050447)
			(xy 229.338251 -330.024946) (xy 229.292893 -329.992495) (xy 229.252744 -329.953786) (xy 229.218658 -329.909643)
			(xy 229.191362 -329.861008) (xy 229.171439 -329.808917) (xy 229.159313 -329.75448) (xy 229.155242 -329.698858)
			(xy 216.581228 -329.698858) (xy 216.252552 -330.027534) (xy 216.245934 -330.034705) (xy 216.238233 -330.052616)
			(xy 216.237829 -330.072108) (xy 216.240868 -330.081382) (xy 216.27846 -330.181966) (xy 216.302082 -330.199746)
			(xy 216.317068 -330.200762) (xy 216.348742 -330.203507) (xy 216.411103 -330.215886) (xy 216.471435 -330.235944)
			(xy 216.528795 -330.263365) (xy 216.58229 -330.297724) (xy 216.631085 -330.338482) (xy 216.674418 -330.385006)
			(xy 216.711613 -330.436568) (xy 216.74209 -330.492365) (xy 216.765375 -330.551527) (xy 216.781102 -330.613129)
			(xy 216.789028 -330.676211) (xy 216.789508 -330.708) (xy 216.789046 -330.738693) (xy 216.781656 -330.799634)
			(xy 216.766983 -330.859241) (xy 216.74524 -330.916648) (xy 216.716745 -330.97102) (xy 216.68191 -331.021566)
			(xy 216.641244 -331.067551) (xy 216.618566 -331.088238) (xy 216.610692 -331.09535) (xy 216.601802 -331.1144)
			(xy 216.599008 -331.209396) (xy 216.606882 -331.228954) (xy 216.614248 -331.23632) (xy 216.637558 -331.260245)
			(xy 216.678344 -331.313145) (xy 216.711847 -331.370934) (xy 216.737487 -331.432614) (xy 216.754824 -331.497123)
			(xy 216.763558 -331.563347) (xy 216.764108 -331.596746) (xy 216.763606 -331.628707) (xy 216.755595 -331.692125)
			(xy 216.739698 -331.754039) (xy 216.716166 -331.813472) (xy 216.685372 -331.869487) (xy 216.647799 -331.921202)
			(xy 216.604042 -331.967799) (xy 216.554789 -332.008544) (xy 216.500818 -332.042795) (xy 216.442979 -332.070012)
			(xy 216.382186 -332.089765) (xy 216.319396 -332.101743) (xy 216.267631 -332.105) (xy 224.407982 -332.105)
			(xy 224.412053 -332.049378) (xy 224.424179 -331.994941) (xy 224.444102 -331.94285) (xy 224.471398 -331.894215)
			(xy 224.505484 -331.850072) (xy 224.545633 -331.811363) (xy 224.590991 -331.778912) (xy 224.640591 -331.753411)
			(xy 224.693375 -331.735404) (xy 224.748218 -331.725274) (xy 224.803952 -331.723237) (xy 224.859389 -331.729337)
			(xy 224.913346 -331.743443) (xy 224.964675 -331.765255) (xy 225.012281 -331.794309) (xy 225.055149 -331.829984)
			(xy 225.092366 -331.871521) (xy 225.123139 -331.918034) (xy 225.146811 -331.968531) (xy 225.162879 -332.021938)
			(xy 225.170999 -332.077114) (xy 225.171508 -332.105) (xy 225.170999 -332.132886) (xy 225.170399 -332.136961)
			(xy 226.059994 -332.136961) (xy 226.059994 -332.073039) (xy 226.068005 -332.009621) (xy 226.083902 -331.947707)
			(xy 226.107434 -331.888274) (xy 226.138228 -331.832259) (xy 226.175801 -331.780544) (xy 226.219558 -331.733947)
			(xy 226.268811 -331.693202) (xy 226.322782 -331.658951) (xy 226.380621 -331.631734) (xy 226.441414 -331.611981)
			(xy 226.504204 -331.600003) (xy 226.568 -331.59599) (xy 226.631796 -331.600003) (xy 226.694586 -331.611981)
			(xy 226.755379 -331.631734) (xy 226.813218 -331.658951) (xy 226.867189 -331.693202) (xy 226.904418 -331.724)
			(xy 234.314492 -331.724) (xy 234.314911 -331.69272) (xy 234.322575 -331.630631) (xy 234.337801 -331.569953)
			(xy 234.360358 -331.511601) (xy 234.389904 -331.456458) (xy 234.425995 -331.405358) (xy 234.468083 -331.359072)
			(xy 234.515532 -331.318301) (xy 234.541314 -331.300582) (xy 234.551474 -331.29313) (xy 234.56346 -331.270999)
			(xy 234.564174 -331.258418) (xy 234.564174 -331.173582) (xy 234.563494 -331.160999) (xy 234.551472 -331.13888)
			(xy 234.541314 -331.131418) (xy 234.515567 -331.113656) (xy 234.468139 -331.072876) (xy 234.426068 -331.026589)
			(xy 234.38999 -330.975492) (xy 234.36045 -330.920358) (xy 234.337892 -330.862017) (xy 234.322657 -330.801351)
			(xy 234.314976 -330.739275) (xy 234.314492 -330.708) (xy 234.314994 -330.676039) (xy 234.323005 -330.612621)
			(xy 234.338902 -330.550707) (xy 234.362434 -330.491274) (xy 234.393228 -330.435259) (xy 234.430801 -330.383544)
			(xy 234.474558 -330.336947) (xy 234.523811 -330.296202) (xy 234.577782 -330.261951) (xy 234.635621 -330.234734)
			(xy 234.696414 -330.214981) (xy 234.759204 -330.203003) (xy 234.823 -330.19899) (xy 234.886796 -330.203003)
			(xy 234.949586 -330.214981) (xy 235.010379 -330.234734) (xy 235.068218 -330.261951) (xy 235.122189 -330.296202)
			(xy 235.171442 -330.336947) (xy 235.215199 -330.383544) (xy 235.252772 -330.435259) (xy 235.283566 -330.491274)
			(xy 235.307098 -330.550707) (xy 235.322995 -330.612621) (xy 235.331006 -330.676039) (xy 235.331508 -330.708)
			(xy 235.331089 -330.73928) (xy 235.323425 -330.801369) (xy 235.308199 -330.862047) (xy 235.285642 -330.920399)
			(xy 235.256096 -330.975542) (xy 235.220005 -331.026642) (xy 235.177917 -331.072928) (xy 235.130468 -331.113699)
			(xy 235.104686 -331.131418) (xy 235.094526 -331.13887) (xy 235.08254 -331.161001) (xy 235.081826 -331.173582)
			(xy 235.081826 -331.258418) (xy 235.082506 -331.271001) (xy 235.094528 -331.29312) (xy 235.104686 -331.300582)
			(xy 235.130433 -331.318344) (xy 235.177861 -331.359124) (xy 235.219932 -331.405411) (xy 235.25601 -331.456508)
			(xy 235.28555 -331.511642) (xy 235.308108 -331.569983) (xy 235.323343 -331.630649) (xy 235.331024 -331.692725)
			(xy 235.331508 -331.724) (xy 235.331006 -331.755961) (xy 235.322995 -331.819379) (xy 235.307098 -331.881293)
			(xy 235.283566 -331.940726) (xy 235.252772 -331.996741) (xy 235.215199 -332.048456) (xy 235.171442 -332.095053)
			(xy 235.122189 -332.135798) (xy 235.068218 -332.170049) (xy 235.010379 -332.197266) (xy 234.949586 -332.217019)
			(xy 234.886796 -332.228997) (xy 234.823 -332.233011) (xy 234.759204 -332.228997) (xy 234.696414 -332.217019)
			(xy 234.635621 -332.197266) (xy 234.577782 -332.170049) (xy 234.523811 -332.135798) (xy 234.474558 -332.095053)
			(xy 234.430801 -332.048456) (xy 234.393228 -331.996741) (xy 234.362434 -331.940726) (xy 234.338902 -331.881293)
			(xy 234.323005 -331.819379) (xy 234.314994 -331.755961) (xy 234.314492 -331.724) (xy 226.904418 -331.724)
			(xy 226.916442 -331.733947) (xy 226.960199 -331.780544) (xy 226.997772 -331.832259) (xy 227.028566 -331.888274)
			(xy 227.052098 -331.947707) (xy 227.067995 -332.009621) (xy 227.076006 -332.073039) (xy 227.076508 -332.105)
			(xy 227.076006 -332.136961) (xy 227.067995 -332.200379) (xy 227.052098 -332.262293) (xy 227.028566 -332.321726)
			(xy 226.997772 -332.377741) (xy 226.960199 -332.429456) (xy 226.916442 -332.476053) (xy 226.867189 -332.516798)
			(xy 226.813218 -332.551049) (xy 226.755379 -332.578266) (xy 226.694586 -332.598019) (xy 226.631796 -332.609997)
			(xy 226.568 -332.614011) (xy 226.504204 -332.609997) (xy 226.441414 -332.598019) (xy 226.380621 -332.578266)
			(xy 226.322782 -332.551049) (xy 226.268811 -332.516798) (xy 226.219558 -332.476053) (xy 226.175801 -332.429456)
			(xy 226.138228 -332.377741) (xy 226.107434 -332.321726) (xy 226.083902 -332.262293) (xy 226.068005 -332.200379)
			(xy 226.059994 -332.136961) (xy 225.170399 -332.136961) (xy 225.162879 -332.188062) (xy 225.146811 -332.241469)
			(xy 225.123139 -332.291966) (xy 225.092366 -332.338479) (xy 225.055149 -332.380016) (xy 225.012281 -332.415691)
			(xy 224.964675 -332.444745) (xy 224.913346 -332.466557) (xy 224.859389 -332.480663) (xy 224.803952 -332.486763)
			(xy 224.748218 -332.484726) (xy 224.693375 -332.474596) (xy 224.640591 -332.456589) (xy 224.590991 -332.431088)
			(xy 224.545633 -332.398637) (xy 224.505484 -332.359928) (xy 224.471398 -332.315785) (xy 224.444102 -332.26715)
			(xy 224.424179 -332.215059) (xy 224.412053 -332.160622) (xy 224.407982 -332.105) (xy 216.267631 -332.105)
			(xy 216.2556 -332.105757) (xy 216.191804 -332.101743) (xy 216.129014 -332.089765) (xy 216.068221 -332.070012)
			(xy 216.010382 -332.042795) (xy 215.956411 -332.008544) (xy 215.907158 -331.967799) (xy 215.863401 -331.921202)
			(xy 215.825828 -331.869487) (xy 215.795034 -331.813472) (xy 215.771502 -331.754039) (xy 215.755605 -331.692125)
			(xy 215.747594 -331.628707) (xy 215.747092 -331.596746) (xy 215.747557 -331.566054) (xy 215.754953 -331.505117)
			(xy 215.769631 -331.445514) (xy 215.791378 -331.388111) (xy 215.819877 -331.333743) (xy 215.854714 -331.283202)
			(xy 215.895382 -331.237223) (xy 215.918034 -331.216508) (xy 215.925908 -331.209396) (xy 215.934798 -331.190346)
			(xy 215.937592 -331.09535) (xy 215.929718 -331.075792) (xy 215.922352 -331.068426) (xy 215.901127 -331.046676)
			(xy 215.863466 -330.998979) (xy 215.831753 -330.947137) (xy 215.80644 -330.891887) (xy 215.787885 -330.834016)
			(xy 215.776355 -330.774347) (xy 215.773762 -330.744068) (xy 215.772746 -330.729082) (xy 215.754966 -330.70546)
			(xy 215.654382 -330.667868) (xy 215.645109 -330.664877) (xy 215.625648 -330.665347) (xy 215.60775 -330.673003)
			(xy 215.600534 -330.679552) (xy 215.009476 -331.27061) (xy 215.002081 -331.277463) (xy 214.983481 -331.285202)
			(xy 214.973408 -331.285596) (xy 214.341456 -331.285596) (xy 214.331477 -331.28603) (xy 214.313001 -331.293564)
			(xy 214.298807 -331.307587) (xy 214.294466 -331.316584) (xy 214.252048 -331.416914) (xy 214.25789 -331.446886)
			(xy 214.268558 -331.458062) (xy 214.288694 -331.479551) (xy 214.322773 -331.527574) (xy 214.349067 -331.580264)
			(xy 214.366952 -331.636369) (xy 214.376001 -331.694557) (xy 214.376508 -331.724) (xy 214.376022 -331.751251)
			(xy 214.368266 -331.805199) (xy 214.352911 -331.857494) (xy 214.330269 -331.907071) (xy 214.300803 -331.952921)
			(xy 214.265112 -331.994112) (xy 214.223921 -332.029803) (xy 214.178071 -332.059269) (xy 214.128494 -332.081911)
			(xy 214.076199 -332.097266) (xy 214.022251 -332.105022) (xy 213.967749 -332.105022) (xy 213.913801 -332.097266)
			(xy 213.861506 -332.081911) (xy 213.811929 -332.059269) (xy 213.766079 -332.029803) (xy 213.724888 -331.994112)
			(xy 213.689197 -331.952921) (xy 213.659731 -331.907071) (xy 213.637089 -331.857494) (xy 213.621734 -331.805199)
			(xy 213.613978 -331.751251) (xy 213.613492 -331.724) (xy 213.614038 -331.694558) (xy 213.623083 -331.636373)
			(xy 213.640958 -331.580269) (xy 213.667239 -331.527575) (xy 213.701303 -331.479545) (xy 213.721442 -331.458062)
			(xy 213.73211 -331.446886) (xy 213.737952 -331.416914) (xy 213.695534 -331.316584) (xy 213.691191 -331.307594)
			(xy 213.676985 -331.293593) (xy 213.658518 -331.286055) (xy 213.648544 -331.285596) (xy 208.618328 -331.285596)
			(xy 208.608264 -331.286032) (xy 208.589678 -331.293765) (xy 208.58226 -331.300582) (xy 207.606646 -332.276196)
			(xy 207.599794 -332.283592) (xy 207.592051 -332.302191) (xy 207.59166 -332.312264) (xy 207.59166 -332.74)
			(xy 213.612982 -332.74) (xy 213.617053 -332.684378) (xy 213.629179 -332.629941) (xy 213.649102 -332.57785)
			(xy 213.676398 -332.529215) (xy 213.710484 -332.485072) (xy 213.750633 -332.446363) (xy 213.795991 -332.413912)
			(xy 213.845591 -332.388411) (xy 213.898375 -332.370404) (xy 213.953218 -332.360274) (xy 214.008952 -332.358237)
			(xy 214.064389 -332.364337) (xy 214.118346 -332.378443) (xy 214.169675 -332.400255) (xy 214.217281 -332.429309)
			(xy 214.260149 -332.464984) (xy 214.297366 -332.506521) (xy 214.328139 -332.553034) (xy 214.351811 -332.603531)
			(xy 214.367879 -332.656938) (xy 214.375999 -332.712114) (xy 214.376508 -332.74) (xy 214.375999 -332.767886)
			(xy 214.375399 -332.771961) (xy 215.56573 -332.771961) (xy 215.56573 -332.708039) (xy 215.573741 -332.644621)
			(xy 215.589638 -332.582707) (xy 215.61317 -332.523274) (xy 215.643964 -332.467259) (xy 215.681537 -332.415544)
			(xy 215.725294 -332.368947) (xy 215.774547 -332.328202) (xy 215.828518 -332.293951) (xy 215.886357 -332.266734)
			(xy 215.94715 -332.246981) (xy 216.00994 -332.235003) (xy 216.073736 -332.23099) (xy 216.137532 -332.235003)
			(xy 216.200322 -332.246981) (xy 216.261115 -332.266734) (xy 216.318954 -332.293951) (xy 216.372925 -332.328202)
			(xy 216.422178 -332.368947) (xy 216.465935 -332.415544) (xy 216.503508 -332.467259) (xy 216.534302 -332.523274)
			(xy 216.557834 -332.582707) (xy 216.573731 -332.644621) (xy 216.581742 -332.708039) (xy 216.582244 -332.74)
			(xy 216.581742 -332.771961) (xy 231.266994 -332.771961) (xy 231.266994 -332.708039) (xy 231.275005 -332.644621)
			(xy 231.290902 -332.582707) (xy 231.314434 -332.523274) (xy 231.345228 -332.467259) (xy 231.382801 -332.415544)
			(xy 231.426558 -332.368947) (xy 231.475811 -332.328202) (xy 231.529782 -332.293951) (xy 231.587621 -332.266734)
			(xy 231.648414 -332.246981) (xy 231.711204 -332.235003) (xy 231.775 -332.23099) (xy 231.838796 -332.235003)
			(xy 231.901586 -332.246981) (xy 231.962379 -332.266734) (xy 232.020218 -332.293951) (xy 232.074189 -332.328202)
			(xy 232.123442 -332.368947) (xy 232.167199 -332.415544) (xy 232.204772 -332.467259) (xy 232.235566 -332.523274)
			(xy 232.259098 -332.582707) (xy 232.274995 -332.644621) (xy 232.283006 -332.708039) (xy 232.283508 -332.74)
			(xy 234.313982 -332.74) (xy 234.318053 -332.684378) (xy 234.330179 -332.629941) (xy 234.350102 -332.57785)
			(xy 234.377398 -332.529215) (xy 234.411484 -332.485072) (xy 234.451633 -332.446363) (xy 234.496991 -332.413912)
			(xy 234.546591 -332.388411) (xy 234.599375 -332.370404) (xy 234.654218 -332.360274) (xy 234.709952 -332.358237)
			(xy 234.765389 -332.364337) (xy 234.819346 -332.378443) (xy 234.870675 -332.400255) (xy 234.918281 -332.429309)
			(xy 234.961149 -332.464984) (xy 234.998366 -332.506521) (xy 235.029139 -332.553034) (xy 235.052811 -332.603531)
			(xy 235.068879 -332.656938) (xy 235.076999 -332.712114) (xy 235.077508 -332.74) (xy 235.076999 -332.767886)
			(xy 235.068879 -332.823062) (xy 235.052811 -332.876469) (xy 235.029139 -332.926966) (xy 234.998366 -332.973479)
			(xy 234.961149 -333.015016) (xy 234.918281 -333.050691) (xy 234.870675 -333.079745) (xy 234.819346 -333.101557)
			(xy 234.765389 -333.115663) (xy 234.709952 -333.121763) (xy 234.654218 -333.119726) (xy 234.599375 -333.109596)
			(xy 234.546591 -333.091589) (xy 234.496991 -333.066088) (xy 234.451633 -333.033637) (xy 234.411484 -332.994928)
			(xy 234.377398 -332.950785) (xy 234.350102 -332.90215) (xy 234.330179 -332.850059) (xy 234.318053 -332.795622)
			(xy 234.313982 -332.74) (xy 232.283508 -332.74) (xy 232.283006 -332.771961) (xy 232.274995 -332.835379)
			(xy 232.259098 -332.897293) (xy 232.235566 -332.956726) (xy 232.204772 -333.012741) (xy 232.167199 -333.064456)
			(xy 232.123442 -333.111053) (xy 232.074189 -333.151798) (xy 232.020218 -333.186049) (xy 231.962379 -333.213266)
			(xy 231.901586 -333.233019) (xy 231.838796 -333.244997) (xy 231.775 -333.249011) (xy 231.711204 -333.244997)
			(xy 231.648414 -333.233019) (xy 231.587621 -333.213266) (xy 231.529782 -333.186049) (xy 231.475811 -333.151798)
			(xy 231.426558 -333.111053) (xy 231.382801 -333.064456) (xy 231.345228 -333.012741) (xy 231.314434 -332.956726)
			(xy 231.290902 -332.897293) (xy 231.275005 -332.835379) (xy 231.266994 -332.771961) (xy 216.581742 -332.771961)
			(xy 216.573731 -332.835379) (xy 216.557834 -332.897293) (xy 216.534302 -332.956726) (xy 216.503508 -333.012741)
			(xy 216.465935 -333.064456) (xy 216.422178 -333.111053) (xy 216.372925 -333.151798) (xy 216.318954 -333.186049)
			(xy 216.261115 -333.213266) (xy 216.200322 -333.233019) (xy 216.137532 -333.244997) (xy 216.073736 -333.249011)
			(xy 216.00994 -333.244997) (xy 215.94715 -333.233019) (xy 215.886357 -333.213266) (xy 215.828518 -333.186049)
			(xy 215.774547 -333.151798) (xy 215.725294 -333.111053) (xy 215.681537 -333.064456) (xy 215.643964 -333.012741)
			(xy 215.61317 -332.956726) (xy 215.589638 -332.897293) (xy 215.573741 -332.835379) (xy 215.56573 -332.771961)
			(xy 214.375399 -332.771961) (xy 214.367879 -332.823062) (xy 214.351811 -332.876469) (xy 214.328139 -332.926966)
			(xy 214.297366 -332.973479) (xy 214.260149 -333.015016) (xy 214.217281 -333.050691) (xy 214.169675 -333.079745)
			(xy 214.118346 -333.101557) (xy 214.064389 -333.115663) (xy 214.008952 -333.121763) (xy 213.953218 -333.119726)
			(xy 213.898375 -333.109596) (xy 213.845591 -333.091589) (xy 213.795991 -333.066088) (xy 213.750633 -333.033637)
			(xy 213.710484 -332.994928) (xy 213.676398 -332.950785) (xy 213.649102 -332.90215) (xy 213.629179 -332.850059)
			(xy 213.617053 -332.795622) (xy 213.612982 -332.74) (xy 207.59166 -332.74) (xy 207.59166 -333.365305)
			(xy 222.487738 -333.365305) (xy 222.487738 -333.301383) (xy 222.495749 -333.237965) (xy 222.511646 -333.176051)
			(xy 222.535178 -333.116618) (xy 222.565972 -333.060603) (xy 222.603545 -333.008888) (xy 222.647302 -332.962291)
			(xy 222.696555 -332.921546) (xy 222.750526 -332.887295) (xy 222.808365 -332.860078) (xy 222.869158 -332.840325)
			(xy 222.931948 -332.828347) (xy 222.995744 -332.824334) (xy 223.05954 -332.828347) (xy 223.12233 -332.840325)
			(xy 223.183123 -332.860078) (xy 223.240962 -332.887295) (xy 223.294933 -332.921546) (xy 223.344186 -332.962291)
			(xy 223.387943 -333.008888) (xy 223.425516 -333.060603) (xy 223.45631 -333.116618) (xy 223.479842 -333.176051)
			(xy 223.495739 -333.237965) (xy 223.50375 -333.301383) (xy 223.504252 -333.333344) (xy 223.50375 -333.365305)
			(xy 223.498488 -333.406961) (xy 232.663994 -333.406961) (xy 232.663994 -333.343039) (xy 232.672005 -333.279621)
			(xy 232.687902 -333.217707) (xy 232.711434 -333.158274) (xy 232.742228 -333.102259) (xy 232.779801 -333.050544)
			(xy 232.823558 -333.003947) (xy 232.872811 -332.963202) (xy 232.926782 -332.928951) (xy 232.984621 -332.901734)
			(xy 233.045414 -332.881981) (xy 233.108204 -332.870003) (xy 233.172 -332.86599) (xy 233.235796 -332.870003)
			(xy 233.298586 -332.881981) (xy 233.359379 -332.901734) (xy 233.417218 -332.928951) (xy 233.471189 -332.963202)
			(xy 233.520442 -333.003947) (xy 233.564199 -333.050544) (xy 233.601772 -333.102259) (xy 233.632566 -333.158274)
			(xy 233.656098 -333.217707) (xy 233.671995 -333.279621) (xy 233.680006 -333.343039) (xy 233.680508 -333.375)
			(xy 233.680006 -333.406961) (xy 233.671995 -333.470379) (xy 233.656098 -333.532293) (xy 233.632566 -333.591726)
			(xy 233.601772 -333.647741) (xy 233.564199 -333.699456) (xy 233.520442 -333.746053) (xy 233.471189 -333.786798)
			(xy 233.417218 -333.821049) (xy 233.359379 -333.848266) (xy 233.298586 -333.868019) (xy 233.235796 -333.879997)
			(xy 233.172 -333.884011) (xy 233.108204 -333.879997) (xy 233.045414 -333.868019) (xy 232.984621 -333.848266)
			(xy 232.926782 -333.821049) (xy 232.872811 -333.786798) (xy 232.823558 -333.746053) (xy 232.779801 -333.699456)
			(xy 232.742228 -333.647741) (xy 232.711434 -333.591726) (xy 232.687902 -333.532293) (xy 232.672005 -333.470379)
			(xy 232.663994 -333.406961) (xy 223.498488 -333.406961) (xy 223.495739 -333.428723) (xy 223.479842 -333.490637)
			(xy 223.45631 -333.55007) (xy 223.425516 -333.606085) (xy 223.387943 -333.6578) (xy 223.344186 -333.704397)
			(xy 223.294933 -333.745142) (xy 223.240962 -333.779393) (xy 223.183123 -333.80661) (xy 223.12233 -333.826363)
			(xy 223.05954 -333.838341) (xy 222.995744 -333.842355) (xy 222.931948 -333.838341) (xy 222.869158 -333.826363)
			(xy 222.808365 -333.80661) (xy 222.750526 -333.779393) (xy 222.696555 -333.745142) (xy 222.647302 -333.704397)
			(xy 222.603545 -333.6578) (xy 222.565972 -333.606085) (xy 222.535178 -333.55007) (xy 222.511646 -333.490637)
			(xy 222.495749 -333.428723) (xy 222.487738 -333.365305) (xy 207.59166 -333.365305) (xy 207.59166 -334.099408)
			(xy 234.558078 -334.099408) (xy 234.55858 -334.067447) (xy 234.566591 -334.004029) (xy 234.582488 -333.942115)
			(xy 234.60602 -333.882682) (xy 234.636814 -333.826667) (xy 234.674387 -333.774952) (xy 234.718144 -333.728355)
			(xy 234.767397 -333.68761) (xy 234.821368 -333.653359) (xy 234.879207 -333.626142) (xy 234.94 -333.606389)
			(xy 235.00279 -333.594411) (xy 235.066586 -333.590398) (xy 235.130382 -333.594411) (xy 235.193172 -333.606389)
			(xy 235.253965 -333.626142) (xy 235.311804 -333.653359) (xy 235.365775 -333.68761) (xy 235.415028 -333.728355)
			(xy 235.458785 -333.774952) (xy 235.496358 -333.826667) (xy 235.527152 -333.882682) (xy 235.550684 -333.942115)
			(xy 235.566581 -334.004029) (xy 235.574592 -334.067447) (xy 235.575094 -334.099408) (xy 235.573824 -334.133952)
			(xy 235.573316 -334.14462) (xy 235.580174 -334.164432) (xy 235.64596 -334.234282) (xy 235.665264 -334.24241)
			(xy 235.678726 -334.24241) (xy 235.705979 -334.242854) (xy 235.759929 -334.250614) (xy 235.812226 -334.265974)
			(xy 235.861804 -334.288619) (xy 235.907655 -334.31809) (xy 235.948846 -334.353786) (xy 235.984537 -334.39498)
			(xy 236.014002 -334.440835) (xy 236.036642 -334.490416) (xy 236.051995 -334.542714) (xy 236.059749 -334.596665)
			(xy 236.060234 -334.623918) (xy 236.059753 -334.651065) (xy 236.052054 -334.704811) (xy 236.036813 -334.756922)
			(xy 236.014338 -334.806347) (xy 235.985083 -334.852086) (xy 235.94964 -334.893216) (xy 235.908724 -334.928906)
			(xy 235.863162 -334.958435) (xy 235.813873 -334.981206) (xy 235.761854 -334.996761) (xy 235.708156 -335.004783)
			(xy 235.681012 -335.005426) (xy 235.671614 -335.005426) (xy 235.65485 -335.01203) (xy 235.590842 -335.068418)
			(xy 235.582206 -335.084166) (xy 235.580936 -335.093564) (xy 235.575966 -335.126432) (xy 235.558634 -335.190606)
			(xy 235.533086 -335.251974) (xy 235.499758 -335.309489) (xy 235.459218 -335.36217) (xy 235.412158 -335.409118)
			(xy 235.359381 -335.449532) (xy 235.301787 -335.482723) (xy 235.240359 -335.508125) (xy 235.176143 -335.525304)
			(xy 235.110237 -335.533967) (xy 235.077 -335.534508) (xy 235.046269 -335.534044) (xy 234.985255 -335.526635)
			(xy 234.925579 -335.511927) (xy 234.868111 -335.490132) (xy 234.813689 -335.461569) (xy 234.763107 -335.426655)
			(xy 234.717102 -335.385898) (xy 234.676345 -335.339893) (xy 234.641431 -335.289311) (xy 234.612868 -335.234889)
			(xy 234.591073 -335.177421) (xy 234.576365 -335.117745) (xy 234.568956 -335.056731) (xy 234.568492 -335.026)
			(xy 234.568997 -334.995064) (xy 234.576504 -334.933648) (xy 234.591406 -334.873597) (xy 234.613483 -334.815798)
			(xy 234.64241 -334.761104) (xy 234.677758 -334.710323) (xy 234.719006 -334.664206) (xy 234.741974 -334.643476)
			(xy 234.750356 -334.63611) (xy 234.759246 -334.616044) (xy 234.75823 -334.516476) (xy 234.748578 -334.49641)
			(xy 234.740196 -334.489298) (xy 234.716136 -334.468576) (xy 234.672892 -334.422074) (xy 234.635778 -334.370548)
			(xy 234.605371 -334.314801) (xy 234.582144 -334.2557) (xy 234.566459 -334.194167) (xy 234.558561 -334.131159)
			(xy 234.558078 -334.099408) (xy 207.59166 -334.099408) (xy 207.59166 -335.9658) (xy 231.731589 -335.9658)
			(xy 231.735603 -335.902005) (xy 231.74758 -335.839217) (xy 231.767332 -335.778425) (xy 231.794548 -335.720587)
			(xy 231.828798 -335.666617) (xy 231.869541 -335.617365) (xy 231.916137 -335.573607) (xy 231.967849 -335.536034)
			(xy 232.023862 -335.505239) (xy 232.083293 -335.481707) (xy 232.145205 -335.465808) (xy 232.208622 -335.457795)
			(xy 232.240582 -335.457292) (xy 232.271924 -335.457748) (xy 232.334132 -335.465459) (xy 232.394922 -335.480752)
			(xy 232.453373 -335.503397) (xy 232.508599 -335.533051) (xy 232.53446 -335.550764) (xy 232.544366 -335.557876)
			(xy 232.568242 -335.561432) (xy 232.668826 -335.528666) (xy 232.685844 -335.511648) (xy 232.689654 -335.500218)
			(xy 232.700129 -335.470222) (xy 232.727559 -335.412911) (xy 232.761918 -335.359465) (xy 232.80267 -335.310719)
			(xy 232.849179 -335.267431) (xy 232.900721 -335.230277) (xy 232.956492 -335.199836) (xy 233.015621 -335.176584)
			(xy 233.077188 -335.160882) (xy 233.140231 -335.152976) (xy 233.172 -335.152492) (xy 233.206492 -335.153055)
			(xy 233.274843 -335.162393) (xy 233.341304 -335.180883) (xy 233.404656 -335.208186) (xy 233.463736 -335.243802)
			(xy 233.51746 -335.287076) (xy 233.54157 -335.31175) (xy 233.54825 -335.318272) (xy 233.56507 -335.326341)
			(xy 233.574336 -335.327498) (xy 233.605324 -335.330038) (xy 233.614472 -335.330347) (xy 233.632044 -335.325276)
			(xy 233.639614 -335.320132) (xy 233.664485 -335.302408) (xy 233.71866 -335.274226) (xy 233.776631 -335.255026)
			(xy 233.836918 -335.245298) (xy 233.867452 -335.244694) (xy 233.894704 -335.2452) (xy 233.948653 -335.25295)
			(xy 234.00095 -335.2683) (xy 234.050531 -335.290938) (xy 234.096384 -335.320401) (xy 234.137577 -335.35609)
			(xy 234.173272 -335.397279) (xy 234.20274 -335.443129) (xy 234.225383 -335.492706) (xy 234.24074 -335.545002)
			(xy 234.248497 -335.59895) (xy 234.24896 -335.626202) (xy 234.248781 -335.64209) (xy 234.24611 -335.673754)
			(xy 234.243626 -335.689448) (xy 234.242102 -335.698846) (xy 234.245912 -335.717388) (xy 234.29341 -335.790794)
			(xy 234.30865 -335.80197) (xy 234.318048 -335.804256) (xy 234.350165 -335.81337) (xy 234.411912 -335.838748)
			(xy 234.469809 -335.871986) (xy 234.52286 -335.912512) (xy 234.570153 -335.959631) (xy 234.610875 -336.012533)
			(xy 234.644325 -336.070307) (xy 234.669929 -336.131961) (xy 234.687248 -336.196435) (xy 234.695982 -336.26262)
			(xy 234.696508 -336.296) (xy 234.696089 -336.32728) (xy 234.688425 -336.389369) (xy 234.673199 -336.450047)
			(xy 234.650642 -336.508399) (xy 234.621096 -336.563542) (xy 234.585005 -336.614642) (xy 234.542917 -336.660928)
			(xy 234.495468 -336.701699) (xy 234.469686 -336.719418) (xy 234.459526 -336.72687) (xy 234.44754 -336.749001)
			(xy 234.446826 -336.761582) (xy 234.446826 -336.846418) (xy 234.447506 -336.859001) (xy 234.459528 -336.88112)
			(xy 234.469686 -336.888582) (xy 234.495433 -336.906344) (xy 234.542861 -336.947124) (xy 234.584932 -336.993411)
			(xy 234.62101 -337.044508) (xy 234.65055 -337.099642) (xy 234.673108 -337.157983) (xy 234.688343 -337.218649)
			(xy 234.696024 -337.280725) (xy 234.696508 -337.312) (xy 234.696006 -337.343961) (xy 234.687995 -337.407379)
			(xy 234.672098 -337.469293) (xy 234.648566 -337.528726) (xy 234.617772 -337.584741) (xy 234.580199 -337.636456)
			(xy 234.536442 -337.683053) (xy 234.487189 -337.723798) (xy 234.433218 -337.758049) (xy 234.375379 -337.785266)
			(xy 234.314586 -337.805019) (xy 234.251796 -337.816997) (xy 234.188 -337.821011) (xy 234.124204 -337.816997)
			(xy 234.061414 -337.805019) (xy 234.000621 -337.785266) (xy 233.942782 -337.758049) (xy 233.888811 -337.723798)
			(xy 233.839558 -337.683053) (xy 233.795801 -337.636456) (xy 233.758228 -337.584741) (xy 233.727434 -337.528726)
			(xy 233.703902 -337.469293) (xy 233.688005 -337.407379) (xy 233.679994 -337.343961) (xy 233.679492 -337.312)
			(xy 233.679911 -337.28072) (xy 233.687575 -337.218631) (xy 233.702801 -337.157953) (xy 233.725358 -337.099601)
			(xy 233.754904 -337.044458) (xy 233.790995 -336.993358) (xy 233.833083 -336.947072) (xy 233.880532 -336.906301)
			(xy 233.906314 -336.888582) (xy 233.916474 -336.88113) (xy 233.92846 -336.858999) (xy 233.929174 -336.846418)
			(xy 233.929174 -336.761582) (xy 233.928494 -336.748999) (xy 233.916472 -336.72688) (xy 233.906314 -336.719418)
			(xy 233.880567 -336.701656) (xy 233.833139 -336.660876) (xy 233.791068 -336.614589) (xy 233.75499 -336.563492)
			(xy 233.72545 -336.508358) (xy 233.702892 -336.450017) (xy 233.687657 -336.389351) (xy 233.679976 -336.327275)
			(xy 233.679492 -336.296) (xy 233.680089 -336.260403) (xy 233.690046 -336.189907) (xy 233.709723 -336.121485)
			(xy 233.723688 -336.088736) (xy 233.727498 -336.0801) (xy 233.728514 -336.06105) (xy 233.701082 -335.977992)
			(xy 233.68889 -335.963514) (xy 233.680508 -335.958942) (xy 233.671364 -335.953354) (xy 233.663264 -335.948993)
			(xy 233.64517 -335.945739) (xy 233.636058 -335.947004) (xy 233.605832 -335.952592) (xy 233.596645 -335.954611)
			(xy 233.580599 -335.964405) (xy 233.57459 -335.971642) (xy 233.553887 -335.997597) (xy 233.506833 -336.044435)
			(xy 233.454083 -336.084751) (xy 233.396534 -336.117859) (xy 233.335167 -336.143195) (xy 233.271024 -336.160329)
			(xy 233.205196 -336.16897) (xy 233.172 -336.169508) (xy 233.140659 -336.169009) (xy 233.078453 -336.161309)
			(xy 233.017664 -336.146025) (xy 232.959212 -336.12339) (xy 232.903984 -336.093745) (xy 232.878122 -336.076036)
			(xy 232.868216 -336.068924) (xy 232.84434 -336.065368) (xy 232.743756 -336.098134) (xy 232.726738 -336.115152)
			(xy 232.722928 -336.126582) (xy 232.712382 -336.156551) (xy 232.684958 -336.213859) (xy 232.650606 -336.267302)
			(xy 232.609862 -336.316048) (xy 232.56336 -336.359337) (xy 232.511827 -336.396493) (xy 232.456065 -336.426937)
			(xy 232.396943 -336.450195) (xy 232.335385 -336.465904) (xy 232.272348 -336.473819) (xy 232.240582 -336.474308)
			(xy 232.208622 -336.473805) (xy 232.145205 -336.465792) (xy 232.083293 -336.449893) (xy 232.023862 -336.426361)
			(xy 231.967849 -336.395566) (xy 231.916137 -336.357993) (xy 231.869541 -336.314235) (xy 231.828798 -336.264983)
			(xy 231.794548 -336.211013) (xy 231.767332 -336.153175) (xy 231.74758 -336.092383) (xy 231.735603 -336.029595)
			(xy 231.731589 -335.9658) (xy 207.59166 -335.9658) (xy 207.59166 -337.859624) (xy 211.265516 -337.859624)
			(xy 211.266018 -337.827663) (xy 211.274029 -337.764245) (xy 211.289926 -337.702331) (xy 211.313458 -337.642898)
			(xy 211.344252 -337.586883) (xy 211.381825 -337.535168) (xy 211.425582 -337.488571) (xy 211.474835 -337.447826)
			(xy 211.528806 -337.413575) (xy 211.586645 -337.386358) (xy 211.647438 -337.366605) (xy 211.710228 -337.354627)
			(xy 211.774024 -337.350614) (xy 211.83782 -337.354627) (xy 211.90061 -337.366605) (xy 211.961403 -337.386358)
			(xy 212.019242 -337.413575) (xy 212.073213 -337.447826) (xy 212.122466 -337.488571) (xy 212.166223 -337.535168)
			(xy 212.203796 -337.586883) (xy 212.23459 -337.642898) (xy 212.239461 -337.6552) (xy 231.764222 -337.6552)
			(xy 231.768237 -337.591392) (xy 231.780218 -337.52859) (xy 231.799976 -337.467785) (xy 231.827199 -337.409937)
			(xy 231.861459 -337.355956) (xy 231.902214 -337.306696) (xy 231.948823 -337.262932) (xy 232.000549 -337.225355)
			(xy 232.056577 -337.194558) (xy 232.116023 -337.171027) (xy 232.17795 -337.155132) (xy 232.241381 -337.147124)
			(xy 232.273348 -337.146646) (xy 232.303866 -337.147067) (xy 232.364464 -337.154357) (xy 232.423754 -337.16885)
			(xy 232.480882 -337.190338) (xy 232.535026 -337.218511) (xy 232.585408 -337.252965) (xy 232.631301 -337.293203)
			(xy 232.672047 -337.338647) (xy 232.707058 -337.388643) (xy 232.735831 -337.442471) (xy 232.747312 -337.47075)
			(xy 232.751376 -337.481672) (xy 232.767886 -337.497166) (xy 232.86466 -337.528408) (xy 232.887012 -337.525614)
			(xy 232.896918 -337.519264) (xy 232.921598 -337.503896) (xy 232.973775 -337.478242) (xy 233.028535 -337.458704)
			(xy 233.085166 -337.445535) (xy 233.142929 -337.438907) (xy 233.172 -337.438492) (xy 233.203961 -337.438994)
			(xy 233.267379 -337.447005) (xy 233.329293 -337.462902) (xy 233.388726 -337.486434) (xy 233.444741 -337.517228)
			(xy 233.496456 -337.554801) (xy 233.543053 -337.598558) (xy 233.583798 -337.647811) (xy 233.618049 -337.701782)
			(xy 233.645266 -337.759621) (xy 233.665019 -337.820414) (xy 233.676997 -337.883204) (xy 233.681011 -337.947)
			(xy 233.676997 -338.010796) (xy 233.665019 -338.073586) (xy 233.645266 -338.134379) (xy 233.618049 -338.192218)
			(xy 233.583798 -338.246189) (xy 233.543053 -338.295442) (xy 233.496456 -338.339199) (xy 233.444741 -338.376772)
			(xy 233.388726 -338.407566) (xy 233.329293 -338.431098) (xy 233.267379 -338.446995) (xy 233.203961 -338.455006)
			(xy 233.172 -338.455508) (xy 233.141485 -338.455011) (xy 233.08089 -338.447728) (xy 233.021604 -338.433242)
			(xy 232.964478 -338.411762) (xy 232.910335 -338.383596) (xy 232.859954 -338.349151) (xy 232.81406 -338.308921)
			(xy 232.773312 -338.263486) (xy 232.738298 -338.213499) (xy 232.70952 -338.159679) (xy 232.698036 -338.131404)
			(xy 232.693972 -338.120482) (xy 232.677462 -338.104988) (xy 232.580688 -338.073746) (xy 232.558336 -338.07654)
			(xy 232.54843 -338.08289) (xy 232.523741 -338.098244) (xy 232.471567 -338.123899) (xy 232.416808 -338.14344)
			(xy 232.36018 -338.156612) (xy 232.302418 -338.163244) (xy 232.273348 -338.163662) (xy 232.241381 -338.163276)
			(xy 232.17795 -338.155268) (xy 232.116023 -338.139373) (xy 232.056577 -338.115842) (xy 232.000549 -338.085045)
			(xy 231.948823 -338.047468) (xy 231.902214 -338.003704) (xy 231.861459 -337.954444) (xy 231.827199 -337.900463)
			(xy 231.799976 -337.842615) (xy 231.780218 -337.78181) (xy 231.768237 -337.719008) (xy 231.764222 -337.6552)
			(xy 212.239461 -337.6552) (xy 212.258122 -337.702331) (xy 212.274019 -337.764245) (xy 212.28203 -337.827663)
			(xy 212.282532 -337.859624) (xy 212.281951 -337.893506) (xy 212.272942 -337.960669) (xy 212.255099 -338.026042)
			(xy 212.228738 -338.088469) (xy 212.194326 -338.146845) (xy 212.152471 -338.200138) (xy 212.103913 -338.247405)
			(xy 212.077046 -338.268056) (xy 212.067394 -338.275168) (xy 212.056726 -338.29625) (xy 212.055456 -338.400898)
			(xy 212.065616 -338.422234) (xy 212.075014 -338.4296) (xy 212.097457 -338.447792) (xy 212.137132 -338.489785)
			(xy 212.170018 -338.537282) (xy 212.195363 -338.589197) (xy 212.212587 -338.64434) (xy 212.221296 -338.701451)
			(xy 212.221826 -338.730336) (xy 212.22138 -338.756952) (xy 212.213976 -338.809666) (xy 212.199303 -338.860835)
			(xy 212.177646 -338.909462) (xy 212.163914 -338.932266) (xy 212.159476 -338.939997) (xy 212.15584 -338.957439)
			(xy 212.156802 -338.966302) (xy 212.160866 -338.996274) (xy 212.162473 -339.005223) (xy 212.171059 -339.021233)
			(xy 212.17763 -339.027516) (xy 212.200295 -339.048256) (xy 212.241031 -339.094244) (xy 212.275927 -339.144807)
			(xy 212.304475 -339.199207) (xy 212.326258 -339.256651) (xy 212.340959 -339.316302) (xy 212.348363 -339.37729)
			(xy 212.348826 -339.408008) (xy 212.348335 -339.439776) (xy 212.340425 -339.502818) (xy 212.32473 -339.564384)
			(xy 212.301493 -339.623518) (xy 212.271075 -339.6793) (xy 212.233951 -339.730862) (xy 212.212682 -339.754464)
			(xy 212.206078 -339.761322) (xy 212.19922 -339.778594) (xy 212.197696 -339.865716) (xy 212.198427 -339.867705)
			(xy 225.26091 -339.867705) (xy 225.26091 -339.803783) (xy 225.268921 -339.740365) (xy 225.284818 -339.678451)
			(xy 225.30835 -339.619018) (xy 225.339144 -339.563003) (xy 225.376717 -339.511288) (xy 225.420474 -339.464691)
			(xy 225.469727 -339.423946) (xy 225.523698 -339.389695) (xy 225.581537 -339.362478) (xy 225.64233 -339.342725)
			(xy 225.70512 -339.330747) (xy 225.768916 -339.326734) (xy 225.832712 -339.330747) (xy 225.895502 -339.342725)
			(xy 225.956295 -339.362478) (xy 226.014134 -339.389695) (xy 226.068105 -339.423946) (xy 226.117358 -339.464691)
			(xy 226.161115 -339.511288) (xy 226.198688 -339.563003) (xy 226.229482 -339.619018) (xy 226.253014 -339.678451)
			(xy 226.268911 -339.740365) (xy 226.276922 -339.803783) (xy 226.277424 -339.835744) (xy 226.276922 -339.867705)
			(xy 226.268911 -339.931123) (xy 226.253014 -339.993037) (xy 226.229482 -340.05247) (xy 226.198688 -340.108485)
			(xy 226.161115 -340.1602) (xy 226.117358 -340.206797) (xy 226.068105 -340.247542) (xy 226.014134 -340.281793)
			(xy 225.956295 -340.30901) (xy 225.895502 -340.328763) (xy 225.832712 -340.340741) (xy 225.768916 -340.344755)
			(xy 225.70512 -340.340741) (xy 225.64233 -340.328763) (xy 225.581537 -340.30901) (xy 225.523698 -340.281793)
			(xy 225.469727 -340.247542) (xy 225.420474 -340.206797) (xy 225.376717 -340.1602) (xy 225.339144 -340.108485)
			(xy 225.30835 -340.05247) (xy 225.284818 -339.993037) (xy 225.268921 -339.931123) (xy 225.26091 -339.867705)
			(xy 212.198427 -339.867705) (xy 212.204046 -339.882988) (xy 212.210396 -339.8901) (xy 212.229981 -339.913284)
			(xy 212.264072 -339.963497) (xy 212.291938 -340.017413) (xy 212.313182 -340.074266) (xy 212.3275 -340.133245)
			(xy 212.334689 -340.19351) (xy 212.33511 -340.223856) (xy 212.334667 -340.254655) (xy 212.327241 -340.315803)
			(xy 212.312479 -340.375606) (xy 212.295149 -340.421214) (xy 222.375982 -340.421214) (xy 222.380053 -340.365592)
			(xy 222.392179 -340.311155) (xy 222.412102 -340.259064) (xy 222.439398 -340.210429) (xy 222.473484 -340.166286)
			(xy 222.513633 -340.127577) (xy 222.558991 -340.095126) (xy 222.608591 -340.069625) (xy 222.661375 -340.051618)
			(xy 222.716218 -340.041488) (xy 222.771952 -340.039451) (xy 222.827389 -340.045551) (xy 222.881346 -340.059657)
			(xy 222.932675 -340.081469) (xy 222.980281 -340.110523) (xy 223.023149 -340.146198) (xy 223.060366 -340.187735)
			(xy 223.091139 -340.234248) (xy 223.114811 -340.284745) (xy 223.130879 -340.338152) (xy 223.138999 -340.393328)
			(xy 223.139508 -340.421214) (xy 223.138999 -340.4491) (xy 223.130879 -340.504276) (xy 223.118807 -340.5444)
			(xy 231.737193 -340.5444) (xy 231.741207 -340.480607) (xy 231.753184 -340.41782) (xy 231.772935 -340.357029)
			(xy 231.80015 -340.299193) (xy 231.834398 -340.245223) (xy 231.87514 -340.195972) (xy 231.921734 -340.152214)
			(xy 231.973444 -340.114642) (xy 232.029456 -340.083846) (xy 232.088885 -340.060313) (xy 232.150796 -340.044414)
			(xy 232.21421 -340.0364) (xy 232.24617 -340.035896) (xy 232.27689 -340.036384) (xy 232.337883 -340.043779)
			(xy 232.397541 -340.058466) (xy 232.454997 -340.080231) (xy 232.509413 -340.108757) (xy 232.534968 -340.125812)
			(xy 232.544874 -340.13267) (xy 232.568242 -340.135972) (xy 232.668572 -340.10219) (xy 232.685082 -340.085426)
			(xy 232.688892 -340.073996) (xy 232.699327 -340.043881) (xy 232.726665 -339.986306) (xy 232.760985 -339.932599)
			(xy 232.801747 -339.883602) (xy 232.848313 -339.840084) (xy 232.899952 -339.802725) (xy 232.955856 -339.772113)
			(xy 233.015146 -339.748727) (xy 233.076894 -339.732934) (xy 233.140132 -339.724982) (xy 233.172 -339.724492)
			(xy 233.203961 -339.724994) (xy 233.267379 -339.733005) (xy 233.329293 -339.748902) (xy 233.388726 -339.772434)
			(xy 233.444741 -339.803228) (xy 233.496456 -339.840801) (xy 233.543053 -339.884558) (xy 233.583798 -339.933811)
			(xy 233.618049 -339.987782) (xy 233.645266 -340.045621) (xy 233.665019 -340.106414) (xy 233.676997 -340.169204)
			(xy 233.681011 -340.233) (xy 233.676997 -340.296796) (xy 233.665019 -340.359586) (xy 233.645266 -340.420379)
			(xy 233.618049 -340.478218) (xy 233.583798 -340.532189) (xy 233.543053 -340.581442) (xy 233.496456 -340.625199)
			(xy 233.444741 -340.662772) (xy 233.388726 -340.693566) (xy 233.329293 -340.717098) (xy 233.267379 -340.732995)
			(xy 233.203961 -340.741006) (xy 233.172 -340.741508) (xy 233.14128 -340.741035) (xy 233.080286 -340.733636)
			(xy 233.020627 -340.718945) (xy 232.963172 -340.697177) (xy 232.908756 -340.668648) (xy 232.883202 -340.651592)
			(xy 232.873296 -340.644734) (xy 232.849928 -340.641432) (xy 232.749598 -340.675214) (xy 232.733088 -340.691978)
			(xy 232.729278 -340.703408) (xy 232.718785 -340.733502) (xy 232.691451 -340.791073) (xy 232.657137 -340.844778)
			(xy 232.61638 -340.893774) (xy 232.569821 -340.937293) (xy 232.518189 -340.974653) (xy 232.462293 -341.005268)
			(xy 232.403009 -341.028659) (xy 232.341268 -341.044458) (xy 232.278036 -341.052418) (xy 232.24617 -341.052912)
			(xy 232.21421 -341.0524) (xy 232.150796 -341.044386) (xy 232.088885 -341.028487) (xy 232.029456 -341.004954)
			(xy 231.973444 -340.974158) (xy 231.921734 -340.936586) (xy 231.87514 -340.892828) (xy 231.834398 -340.843577)
			(xy 231.80015 -340.789607) (xy 231.772935 -340.731771) (xy 231.753184 -340.67098) (xy 231.741207 -340.608193)
			(xy 231.737193 -340.5444) (xy 223.118807 -340.5444) (xy 223.114811 -340.557683) (xy 223.091139 -340.60818)
			(xy 223.060366 -340.654693) (xy 223.023149 -340.69623) (xy 222.980281 -340.731905) (xy 222.932675 -340.760959)
			(xy 222.881346 -340.782771) (xy 222.827389 -340.796877) (xy 222.771952 -340.802977) (xy 222.716218 -340.80094)
			(xy 222.661375 -340.79081) (xy 222.608591 -340.772803) (xy 222.558991 -340.747302) (xy 222.513633 -340.714851)
			(xy 222.473484 -340.676142) (xy 222.439398 -340.631999) (xy 222.412102 -340.583364) (xy 222.392179 -340.531273)
			(xy 222.380053 -340.476836) (xy 222.375982 -340.421214) (xy 212.295149 -340.421214) (xy 212.290599 -340.433187)
			(xy 212.261921 -340.487701) (xy 212.226865 -340.538351) (xy 212.185946 -340.584393) (xy 212.163152 -340.60511)
			(xy 212.155786 -340.611714) (xy 212.146896 -340.628986) (xy 212.139276 -340.718648) (xy 212.145118 -340.73719)
			(xy 212.151214 -340.74481) (xy 212.167109 -340.765228) (xy 212.193802 -340.809555) (xy 212.214264 -340.857082)
			(xy 212.228117 -340.906937) (xy 212.23511 -340.958206) (xy 212.235542 -340.984078) (xy 212.23503 -341.011787)
			(xy 212.227021 -341.066623) (xy 212.211155 -341.11972) (xy 212.196397 -341.151421) (xy 225.709474 -341.151421)
			(xy 225.709474 -341.087499) (xy 225.717485 -341.024081) (xy 225.733382 -340.962167) (xy 225.756914 -340.902734)
			(xy 225.787708 -340.846719) (xy 225.825281 -340.795004) (xy 225.869038 -340.748407) (xy 225.918291 -340.707662)
			(xy 225.972262 -340.673411) (xy 226.030101 -340.646194) (xy 226.090894 -340.626441) (xy 226.153684 -340.614463)
			(xy 226.21748 -340.61045) (xy 226.281276 -340.614463) (xy 226.344066 -340.626441) (xy 226.404859 -340.646194)
			(xy 226.462698 -340.673411) (xy 226.516669 -340.707662) (xy 226.565922 -340.748407) (xy 226.609679 -340.795004)
			(xy 226.647252 -340.846719) (xy 226.678046 -340.902734) (xy 226.701578 -340.962167) (xy 226.717475 -341.024081)
			(xy 226.725486 -341.087499) (xy 226.725988 -341.11946) (xy 226.725486 -341.151421) (xy 226.717475 -341.214839)
			(xy 226.701578 -341.276753) (xy 226.678046 -341.336186) (xy 226.647252 -341.392201) (xy 226.609679 -341.443916)
			(xy 226.565922 -341.490513) (xy 226.516669 -341.531258) (xy 226.462698 -341.565509) (xy 226.404859 -341.592726)
			(xy 226.344066 -341.612479) (xy 226.281276 -341.624457) (xy 226.21748 -341.628471) (xy 226.153684 -341.624457)
			(xy 226.090894 -341.612479) (xy 226.030101 -341.592726) (xy 225.972262 -341.565509) (xy 225.918291 -341.531258)
			(xy 225.869038 -341.490513) (xy 225.825281 -341.443916) (xy 225.787708 -341.392201) (xy 225.756914 -341.336186)
			(xy 225.733382 -341.276753) (xy 225.717485 -341.214839) (xy 225.709474 -341.151421) (xy 212.196397 -341.151421)
			(xy 212.187766 -341.16996) (xy 212.157348 -341.216283) (xy 212.120541 -341.257712) (xy 212.099652 -341.275924)
			(xy 212.090508 -341.283544) (xy 212.081364 -341.304372) (xy 212.084158 -341.407496) (xy 212.094572 -341.427816)
			(xy 212.10397 -341.434928) (xy 212.130556 -341.455605) (xy 212.17861 -341.502795) (xy 212.220014 -341.555916)
			(xy 212.254042 -341.614038) (xy 212.280099 -341.676144) (xy 212.297729 -341.741146) (xy 212.306623 -341.807907)
			(xy 212.30717 -341.841582) (xy 212.306668 -341.873543) (xy 212.306181 -341.877396) (xy 212.588094 -341.877396)
			(xy 212.588596 -341.845435) (xy 212.596607 -341.782017) (xy 212.612504 -341.720103) (xy 212.636036 -341.66067)
			(xy 212.66683 -341.604655) (xy 212.704403 -341.55294) (xy 212.74816 -341.506343) (xy 212.797413 -341.465598)
			(xy 212.851384 -341.431347) (xy 212.909223 -341.40413) (xy 212.970016 -341.384377) (xy 213.032806 -341.372399)
			(xy 213.096602 -341.368386) (xy 213.160398 -341.372399) (xy 213.223188 -341.384377) (xy 213.283981 -341.40413)
			(xy 213.34182 -341.431347) (xy 213.395791 -341.465598) (xy 213.445044 -341.506343) (xy 213.488801 -341.55294)
			(xy 213.526374 -341.604655) (xy 213.557168 -341.66067) (xy 213.5807 -341.720103) (xy 213.596597 -341.782017)
			(xy 213.604608 -341.845435) (xy 213.60511 -341.877396) (xy 213.604553 -341.911396) (xy 213.595503 -341.978792)
			(xy 213.577549 -342.044379) (xy 213.551012 -342.106988) (xy 213.516366 -342.1655) (xy 213.47423 -342.218872)
			(xy 213.45017 -342.242902) (xy 213.443058 -342.24976) (xy 213.435184 -342.267286) (xy 213.433247 -342.309661)
			(xy 231.718098 -342.309661) (xy 231.718098 -342.245739) (xy 231.726109 -342.182321) (xy 231.742006 -342.120407)
			(xy 231.765538 -342.060974) (xy 231.796332 -342.004959) (xy 231.833905 -341.953244) (xy 231.877662 -341.906647)
			(xy 231.926915 -341.865902) (xy 231.980886 -341.831651) (xy 232.038725 -341.804434) (xy 232.099518 -341.784681)
			(xy 232.162308 -341.772703) (xy 232.226104 -341.76869) (xy 232.2899 -341.772703) (xy 232.35269 -341.784681)
			(xy 232.413483 -341.804434) (xy 232.471322 -341.831651) (xy 232.525293 -341.865902) (xy 232.574546 -341.906647)
			(xy 232.618303 -341.953244) (xy 232.655876 -342.004959) (xy 232.68667 -342.060974) (xy 232.710202 -342.120407)
			(xy 232.726099 -342.182321) (xy 232.73411 -342.245739) (xy 232.734612 -342.2777) (xy 232.73411 -342.309661)
			(xy 232.726099 -342.373079) (xy 232.710202 -342.434993) (xy 232.68667 -342.494426) (xy 232.655876 -342.550441)
			(xy 232.618303 -342.602156) (xy 232.574546 -342.648753) (xy 232.547957 -342.670749) (xy 233.237414 -342.670749)
			(xy 233.237416 -342.616235) (xy 233.245175 -342.562277) (xy 233.260535 -342.509972) (xy 233.283183 -342.460385)
			(xy 233.312657 -342.414527) (xy 233.348358 -342.37333) (xy 233.389559 -342.337633) (xy 233.43542 -342.308164)
			(xy 233.485009 -342.285521) (xy 233.537316 -342.270167) (xy 233.591275 -342.262413) (xy 233.618532 -342.261952)
			(xy 233.639106 -342.26246) (xy 233.652822 -342.263222) (xy 233.676698 -342.25103) (xy 233.739944 -342.154002)
			(xy 233.741214 -342.127332) (xy 233.734864 -342.114886) (xy 233.721654 -342.087988) (xy 233.700943 -342.031753)
			(xy 233.686971 -341.973477) (xy 233.67993 -341.913964) (xy 233.679492 -341.884) (xy 233.679911 -341.85272)
			(xy 233.687575 -341.790631) (xy 233.702801 -341.729953) (xy 233.725358 -341.671601) (xy 233.754904 -341.616458)
			(xy 233.790995 -341.565358) (xy 233.833083 -341.519072) (xy 233.880532 -341.478301) (xy 233.906314 -341.460582)
			(xy 233.916474 -341.45313) (xy 233.92846 -341.430999) (xy 233.929174 -341.418418) (xy 233.929174 -341.333582)
			(xy 233.928494 -341.320999) (xy 233.916472 -341.29888) (xy 233.906314 -341.291418) (xy 233.880567 -341.273656)
			(xy 233.833139 -341.232876) (xy 233.791068 -341.186589) (xy 233.75499 -341.135492) (xy 233.72545 -341.080358)
			(xy 233.702892 -341.022017) (xy 233.687657 -340.961351) (xy 233.679976 -340.899275) (xy 233.679492 -340.868)
			(xy 233.679956 -340.837269) (xy 233.687365 -340.776255) (xy 233.702073 -340.716579) (xy 233.723868 -340.659111)
			(xy 233.752431 -340.604689) (xy 233.787345 -340.554107) (xy 233.828102 -340.508102) (xy 233.874107 -340.467345)
			(xy 233.924689 -340.432431) (xy 233.979111 -340.403868) (xy 234.036579 -340.382073) (xy 234.096255 -340.367365)
			(xy 234.157269 -340.359956) (xy 234.188 -340.359492) (xy 234.188254 -340.359492) (xy 234.198273 -340.359043)
			(xy 234.216791 -340.351386) (xy 234.230965 -340.337223) (xy 234.238635 -340.318711) (xy 234.239054 -340.308692)
			(xy 234.239054 -340.304628) (xy 234.238292 -340.30031) (xy 234.235901 -340.284864) (xy 234.233358 -340.253709)
			(xy 234.233212 -340.23808) (xy 234.233708 -340.210224) (xy 234.241835 -340.155107) (xy 234.257884 -340.101755)
			(xy 234.281514 -340.051302) (xy 234.312224 -340.004817) (xy 234.349363 -339.963288) (xy 234.392141 -339.927595)
			(xy 234.439651 -339.898497) (xy 234.490886 -339.876611) (xy 234.517692 -339.869018) (xy 234.527598 -339.866478)
			(xy 234.544108 -339.854032) (xy 234.589828 -339.772498) (xy 234.592368 -339.751924) (xy 234.58932 -339.742018)
			(xy 234.579577 -339.706814) (xy 234.569124 -339.634522) (xy 234.568492 -339.598) (xy 234.568911 -339.56672)
			(xy 234.576575 -339.504631) (xy 234.591801 -339.443953) (xy 234.614358 -339.385601) (xy 234.643904 -339.330458)
			(xy 234.679995 -339.279358) (xy 234.722083 -339.233072) (xy 234.769532 -339.192301) (xy 234.795314 -339.174582)
			(xy 234.805474 -339.16713) (xy 234.81746 -339.144999) (xy 234.818174 -339.132418) (xy 234.818174 -339.047582)
			(xy 234.817494 -339.034999) (xy 234.805472 -339.01288) (xy 234.795314 -339.005418) (xy 234.769567 -338.987656)
			(xy 234.722139 -338.946876) (xy 234.680068 -338.900589) (xy 234.64399 -338.849492) (xy 234.61445 -338.794358)
			(xy 234.591892 -338.736017) (xy 234.576657 -338.675351) (xy 234.568976 -338.613275) (xy 234.568492 -338.582)
			(xy 234.568994 -338.550039) (xy 234.577005 -338.486621) (xy 234.592902 -338.424707) (xy 234.616434 -338.365274)
			(xy 234.647228 -338.309259) (xy 234.684801 -338.257544) (xy 234.728558 -338.210947) (xy 234.777811 -338.170202)
			(xy 234.831782 -338.135951) (xy 234.889621 -338.108734) (xy 234.950414 -338.088981) (xy 235.013204 -338.077003)
			(xy 235.077 -338.07299) (xy 235.140796 -338.077003) (xy 235.203586 -338.088981) (xy 235.264379 -338.108734)
			(xy 235.322218 -338.135951) (xy 235.376189 -338.170202) (xy 235.425442 -338.210947) (xy 235.469199 -338.257544)
			(xy 235.506772 -338.309259) (xy 235.537566 -338.365274) (xy 235.561098 -338.424707) (xy 235.576995 -338.486621)
			(xy 235.585006 -338.550039) (xy 235.585508 -338.582) (xy 235.585089 -338.61328) (xy 235.577425 -338.675369)
			(xy 235.562199 -338.736047) (xy 235.539642 -338.794399) (xy 235.510096 -338.849542) (xy 235.474005 -338.900642)
			(xy 235.431917 -338.946928) (xy 235.384468 -338.987699) (xy 235.358686 -339.005418) (xy 235.348526 -339.01287)
			(xy 235.33654 -339.035001) (xy 235.335826 -339.047582) (xy 235.335826 -339.132418) (xy 235.336506 -339.145001)
			(xy 235.348528 -339.16712) (xy 235.358686 -339.174582) (xy 235.384433 -339.192344) (xy 235.431861 -339.233124)
			(xy 235.473932 -339.279411) (xy 235.51001 -339.330508) (xy 235.53955 -339.385642) (xy 235.562108 -339.443983)
			(xy 235.577343 -339.504649) (xy 235.585024 -339.566725) (xy 235.585508 -339.598) (xy 235.585 -339.630606)
			(xy 235.576663 -339.695283) (xy 235.560127 -339.758363) (xy 235.535661 -339.818811) (xy 235.503668 -339.875636)
			(xy 235.464674 -339.927904) (xy 235.419317 -339.974758) (xy 235.368342 -340.015429) (xy 235.312586 -340.04925)
			(xy 235.252964 -340.075665) (xy 235.190454 -340.094242) (xy 235.126082 -340.104674) (xy 235.09351 -340.106254)
			(xy 235.08335 -340.106508) (xy 235.064554 -340.115144) (xy 235.001562 -340.184486) (xy 234.994704 -340.20379)
			(xy 234.995466 -340.214204) (xy 234.996228 -340.23808) (xy 234.995817 -340.26431) (xy 234.988619 -340.316273)
			(xy 234.974371 -340.366761) (xy 234.95334 -340.41482) (xy 234.925924 -340.459545) (xy 234.892638 -340.500093)
			(xy 234.854112 -340.535698) (xy 234.811072 -340.56569) (xy 234.764328 -340.589502) (xy 234.739688 -340.598506)
			(xy 234.73029 -340.601808) (xy 234.715558 -340.614508) (xy 234.67441 -340.694518) (xy 234.672632 -340.713822)
			(xy 234.675426 -340.723474) (xy 234.685274 -340.758791) (xy 234.695853 -340.831341) (xy 234.696508 -340.868)
			(xy 234.696089 -340.89928) (xy 234.688425 -340.961369) (xy 234.673199 -341.022047) (xy 234.650642 -341.080399)
			(xy 234.621096 -341.135542) (xy 234.585005 -341.186642) (xy 234.542917 -341.232928) (xy 234.495468 -341.273699)
			(xy 234.469686 -341.291418) (xy 234.459526 -341.29887) (xy 234.44754 -341.321001) (xy 234.446826 -341.333582)
			(xy 234.446826 -341.418418) (xy 234.447506 -341.431001) (xy 234.459528 -341.45312) (xy 234.469686 -341.460582)
			(xy 234.495433 -341.478344) (xy 234.542861 -341.519124) (xy 234.584932 -341.565411) (xy 234.62101 -341.616508)
			(xy 234.65055 -341.671642) (xy 234.673108 -341.729983) (xy 234.688343 -341.790649) (xy 234.696024 -341.852725)
			(xy 234.696508 -341.884) (xy 234.696044 -341.914731) (xy 234.688635 -341.975745) (xy 234.673927 -342.035421)
			(xy 234.652132 -342.092889) (xy 234.623569 -342.147311) (xy 234.588655 -342.197893) (xy 234.547898 -342.243898)
			(xy 234.501893 -342.284655) (xy 234.451311 -342.319569) (xy 234.396889 -342.348132) (xy 234.339421 -342.369927)
			(xy 234.279745 -342.384635) (xy 234.218731 -342.392044) (xy 234.188 -342.392508) (xy 234.16417 -342.392249)
			(xy 234.11672 -342.387795) (xy 234.093258 -342.383618) (xy 234.079542 -342.381078) (xy 234.054396 -342.389968)
			(xy 233.978958 -342.477598) (xy 233.973878 -342.504014) (xy 233.97845 -342.516968) (xy 233.988506 -342.547621)
			(xy 233.999363 -342.611207) (xy 234.00004 -342.64346) (xy 233.999588 -342.670717) (xy 233.991835 -342.724676)
			(xy 233.976482 -342.776983) (xy 233.95384 -342.826573) (xy 233.924372 -342.872435) (xy 233.888676 -342.913636)
			(xy 233.84748 -342.949338) (xy 233.801622 -342.978813) (xy 233.752036 -343.001462) (xy 233.699731 -343.016823)
			(xy 233.645773 -343.024584) (xy 233.591259 -343.024586) (xy 233.5373 -343.01683) (xy 233.484994 -343.001473)
			(xy 233.435406 -342.978829) (xy 233.389546 -342.949357) (xy 233.348347 -342.913659) (xy 233.312648 -342.872461)
			(xy 233.283175 -342.826601) (xy 233.26053 -342.777013) (xy 233.245172 -342.724708) (xy 233.237414 -342.670749)
			(xy 232.547957 -342.670749) (xy 232.525293 -342.689498) (xy 232.471322 -342.723749) (xy 232.413483 -342.750966)
			(xy 232.35269 -342.770719) (xy 232.2899 -342.782697) (xy 232.226104 -342.786711) (xy 232.162308 -342.782697)
			(xy 232.099518 -342.770719) (xy 232.038725 -342.750966) (xy 231.980886 -342.723749) (xy 231.926915 -342.689498)
			(xy 231.877662 -342.648753) (xy 231.833905 -342.602156) (xy 231.796332 -342.550441) (xy 231.765538 -342.494426)
			(xy 231.742006 -342.434993) (xy 231.726109 -342.373079) (xy 231.718098 -342.309661) (xy 213.433247 -342.309661)
			(xy 213.43112 -342.356186) (xy 213.437216 -342.374474) (xy 213.443566 -342.38184) (xy 213.460769 -342.402692)
			(xy 213.489776 -342.448305) (xy 213.512055 -342.497555) (xy 213.527161 -342.549456) (xy 213.53479 -342.60297)
			(xy 213.53526 -342.629998) (xy 213.534799 -342.65637) (xy 213.527515 -342.708608) (xy 213.5131 -342.759344)
			(xy 213.491828 -342.807609) (xy 213.464107 -342.85248) (xy 213.44763 -342.873076) (xy 213.441026 -342.881204)
			(xy 213.435184 -342.901524) (xy 213.447122 -342.996012) (xy 213.45779 -343.014046) (xy 213.466426 -343.020142)
			(xy 213.490453 -343.038107) (xy 213.534545 -343.078793) (xy 213.573544 -343.124384) (xy 213.606908 -343.174246)
			(xy 213.634173 -343.227688) (xy 213.654961 -343.283967) (xy 213.668984 -343.3423) (xy 213.676045 -343.401878)
			(xy 213.676484 -343.431876) (xy 213.675982 -343.463837) (xy 213.667971 -343.527255) (xy 213.652074 -343.589169)
			(xy 213.628542 -343.648602) (xy 213.597748 -343.704617) (xy 213.560175 -343.756332) (xy 213.516418 -343.802929)
			(xy 213.467165 -343.843674) (xy 213.413194 -343.877925) (xy 213.355355 -343.905142) (xy 213.294562 -343.924895)
			(xy 213.231772 -343.936873) (xy 213.167976 -343.940887) (xy 213.10418 -343.936873) (xy 213.04139 -343.924895)
			(xy 212.980597 -343.905142) (xy 212.922758 -343.877925) (xy 212.868787 -343.843674) (xy 212.819534 -343.802929)
			(xy 212.775777 -343.756332) (xy 212.738204 -343.704617) (xy 212.70741 -343.648602) (xy 212.683878 -343.589169)
			(xy 212.667981 -343.527255) (xy 212.65997 -343.463837) (xy 212.659468 -343.431876) (xy 212.65999 -343.398887)
			(xy 212.668527 -343.333463) (xy 212.685452 -343.269692) (xy 212.710483 -343.208646) (xy 212.743199 -343.15135)
			(xy 212.783051 -343.098767) (xy 212.829368 -343.051779) (xy 212.855048 -343.031064) (xy 212.86343 -343.02446)
			(xy 212.87359 -343.006172) (xy 212.882226 -342.911176) (xy 212.875622 -342.891364) (xy 212.86851 -342.88349)
			(xy 212.85046 -342.86243) (xy 212.820046 -342.816047) (xy 212.796654 -342.765756) (xy 212.780776 -342.712612)
			(xy 212.772746 -342.657731) (xy 212.772244 -342.629998) (xy 212.772694 -342.603467) (xy 212.780037 -342.550916)
			(xy 212.794581 -342.499886) (xy 212.816047 -342.45136) (xy 212.829648 -342.428576) (xy 212.834982 -342.420194)
			(xy 212.838284 -342.401144) (xy 212.820758 -342.314022) (xy 212.81009 -342.297766) (xy 212.802216 -342.292178)
			(xy 212.777752 -342.274264) (xy 212.732845 -342.233519) (xy 212.693099 -342.187725) (xy 212.659078 -342.137532)
			(xy 212.631263 -342.08365) (xy 212.61005 -342.026845) (xy 212.595739 -341.967922) (xy 212.588532 -341.907714)
			(xy 212.588094 -341.877396) (xy 212.306181 -341.877396) (xy 212.298657 -341.936961) (xy 212.28276 -341.998875)
			(xy 212.259228 -342.058308) (xy 212.228434 -342.114323) (xy 212.190861 -342.166038) (xy 212.147104 -342.212635)
			(xy 212.097851 -342.25338) (xy 212.04388 -342.287631) (xy 211.986041 -342.314848) (xy 211.925248 -342.334601)
			(xy 211.862458 -342.346579) (xy 211.798662 -342.350593) (xy 211.734866 -342.346579) (xy 211.672076 -342.334601)
			(xy 211.611283 -342.314848) (xy 211.553444 -342.287631) (xy 211.499473 -342.25338) (xy 211.45022 -342.212635)
			(xy 211.406463 -342.166038) (xy 211.36889 -342.114323) (xy 211.338096 -342.058308) (xy 211.314564 -341.998875)
			(xy 211.298667 -341.936961) (xy 211.290656 -341.873543) (xy 211.290154 -341.841582) (xy 211.290736 -341.808017)
			(xy 211.299552 -341.74147) (xy 211.317054 -341.676663) (xy 211.342938 -341.614725) (xy 211.376753 -341.556735)
			(xy 211.41791 -341.503703) (xy 211.465692 -341.456552) (xy 211.519267 -341.416104) (xy 211.548218 -341.399114)
			(xy 211.558378 -341.393272) (xy 211.571332 -341.374476) (xy 211.587588 -341.272622) (xy 211.580984 -341.250778)
			(xy 211.572856 -341.241888) (xy 211.554102 -341.220656) (xy 211.522401 -341.173711) (xy 211.497994 -341.122592)
			(xy 211.48142 -341.068425) (xy 211.473042 -341.012401) (xy 211.472526 -340.984078) (xy 211.473036 -340.955183)
			(xy 211.481745 -340.898055) (xy 211.498975 -340.842894) (xy 211.524332 -340.790966) (xy 211.540344 -340.766908)
			(xy 211.545932 -340.75878) (xy 211.55025 -340.739984) (xy 211.53628 -340.65083) (xy 211.526374 -340.63432)
			(xy 211.5185 -340.628224) (xy 211.492221 -340.607576) (xy 211.444803 -340.56048) (xy 211.403968 -340.507572)
			(xy 211.370423 -340.449769) (xy 211.344745 -340.388066) (xy 211.327378 -340.323529) (xy 211.318621 -340.257272)
			(xy 211.318094 -340.223856) (xy 211.318557 -340.192087) (xy 211.326472 -340.129044) (xy 211.342172 -340.067477)
			(xy 211.365415 -340.008343) (xy 211.395837 -339.952562) (xy 211.432966 -339.901001) (xy 211.454238 -339.8774)
			(xy 211.460842 -339.870542) (xy 211.4677 -339.85327) (xy 211.469224 -339.766148) (xy 211.462874 -339.748876)
			(xy 211.456524 -339.741764) (xy 211.436957 -339.718566) (xy 211.402866 -339.668355) (xy 211.374998 -339.614441)
			(xy 211.353752 -339.557591) (xy 211.339429 -339.498616) (xy 211.332234 -339.438353) (xy 211.33181 -339.408008)
			(xy 211.332263 -339.37729) (xy 211.339675 -339.316302) (xy 211.35438 -339.256651) (xy 211.376163 -339.199206)
			(xy 211.404708 -339.144804) (xy 211.439599 -339.094236) (xy 211.480327 -339.04824) (xy 211.503006 -339.027516)
			(xy 211.509575 -339.02123) (xy 211.51817 -339.005224) (xy 211.51977 -338.996274) (xy 211.523834 -338.966302)
			(xy 211.524704 -338.957445) (xy 211.521061 -338.940037) (xy 211.516722 -338.932266) (xy 211.503016 -338.90945)
			(xy 211.481391 -338.860816) (xy 211.466722 -338.809652) (xy 211.459293 -338.756948) (xy 211.45881 -338.730336)
			(xy 211.459349 -338.70149) (xy 211.468025 -338.644454) (xy 211.4852 -338.589377) (xy 211.51048 -338.537519)
			(xy 211.543289 -338.490064) (xy 211.562696 -338.468716) (xy 211.570824 -338.459826) (xy 211.577936 -338.43722)
			(xy 211.560664 -338.333842) (xy 211.546948 -338.314792) (xy 211.53628 -338.309204) (xy 211.509404 -338.294474)
			(xy 211.459069 -338.259507) (xy 211.413301 -338.218744) (xy 211.372762 -338.172777) (xy 211.33804 -338.122273)
			(xy 211.309638 -338.067962) (xy 211.287967 -338.010632) (xy 211.273343 -337.951113) (xy 211.265975 -337.890268)
			(xy 211.265516 -337.859624) (xy 207.59166 -337.859624) (xy 207.59166 -344.952828) (xy 213.115398 -344.952828)
			(xy 213.1159 -344.920867) (xy 213.123911 -344.857449) (xy 213.139808 -344.795535) (xy 213.16334 -344.736102)
			(xy 213.194134 -344.680087) (xy 213.231707 -344.628372) (xy 213.275464 -344.581775) (xy 213.324717 -344.54103)
			(xy 213.378688 -344.506779) (xy 213.436527 -344.479562) (xy 213.49732 -344.459809) (xy 213.56011 -344.447831)
			(xy 213.623906 -344.443818) (xy 213.687702 -344.447831) (xy 213.750492 -344.459809) (xy 213.811285 -344.479562)
			(xy 213.869124 -344.506779) (xy 213.923095 -344.54103) (xy 213.972348 -344.581775) (xy 214.016105 -344.628372)
			(xy 214.053678 -344.680087) (xy 214.084472 -344.736102) (xy 214.108004 -344.795535) (xy 214.123901 -344.857449)
			(xy 214.131912 -344.920867) (xy 214.132414 -344.952828) (xy 214.131913 -344.986106) (xy 214.123242 -345.052094)
			(xy 214.106038 -345.116387) (xy 214.080595 -345.177888) (xy 214.047349 -345.235545) (xy 214.006866 -345.288372)
			(xy 213.959839 -345.335469) (xy 213.933786 -345.35618) (xy 213.924642 -345.363038) (xy 213.914482 -345.382596)
			(xy 213.909656 -345.482672) (xy 213.917784 -345.503246) (xy 213.926166 -345.510866) (xy 213.944893 -345.52897)
			(xy 213.977735 -345.569397) (xy 214.004773 -345.613916) (xy 214.025504 -345.661699) (xy 214.039543 -345.711858)
			(xy 214.046628 -345.763461) (xy 214.04707 -345.789504) (xy 214.046597 -345.817473) (xy 214.03844 -345.872812)
			(xy 214.022287 -345.926367) (xy 213.998484 -345.976987) (xy 213.967542 -346.023588) (xy 213.930126 -346.065169)
			(xy 213.908894 -346.083382) (xy 213.89848 -346.092018) (xy 213.889082 -346.116402) (xy 213.905338 -346.228924)
			(xy 213.92134 -346.249752) (xy 213.933786 -346.255086) (xy 213.963905 -346.268523) (xy 214.020685 -346.302079)
			(xy 214.07265 -346.342692) (xy 214.118929 -346.389683) (xy 214.158746 -346.442261) (xy 214.191432 -346.499545)
			(xy 214.216439 -346.560574) (xy 214.233347 -346.624323) (xy 214.241872 -346.689723) (xy 214.242396 -346.7227)
			(xy 214.241894 -346.754661) (xy 214.233883 -346.818079) (xy 214.217986 -346.879993) (xy 214.194454 -346.939426)
			(xy 214.16366 -346.995441) (xy 214.126087 -347.047156) (xy 214.08233 -347.093753) (xy 214.033077 -347.134498)
			(xy 213.979106 -347.168749) (xy 213.921267 -347.195966) (xy 213.860474 -347.215719) (xy 213.797684 -347.227697)
			(xy 213.733888 -347.231711) (xy 213.670092 -347.227697) (xy 213.607302 -347.215719) (xy 213.546509 -347.195966)
			(xy 213.48867 -347.168749) (xy 213.434699 -347.134498) (xy 213.385446 -347.093753) (xy 213.341689 -347.047156)
			(xy 213.304116 -346.995441) (xy 213.273322 -346.939426) (xy 213.24979 -346.879993) (xy 213.233893 -346.818079)
			(xy 213.225882 -346.754661) (xy 213.22538 -346.7227) (xy 213.225901 -346.690239) (xy 213.234164 -346.625844)
			(xy 213.250557 -346.563025) (xy 213.274812 -346.502803) (xy 213.306534 -346.446158) (xy 213.345209 -346.394012)
			(xy 213.390206 -346.347212) (xy 213.440794 -346.30652) (xy 213.468204 -346.289122) (xy 213.479634 -346.28201)
			(xy 213.492334 -346.259404) (xy 213.49208 -346.145358) (xy 213.47938 -346.122752) (xy 213.467696 -346.11564)
			(xy 213.444063 -346.100696) (xy 213.400994 -346.06504) (xy 213.363593 -346.023477) (xy 213.332662 -345.976899)
			(xy 213.308864 -345.926303) (xy 213.29271 -345.872774) (xy 213.284544 -345.817461) (xy 213.284054 -345.789504)
			(xy 213.284543 -345.762041) (xy 213.292402 -345.70768) (xy 213.307974 -345.655008) (xy 213.330935 -345.605112)
			(xy 213.360813 -345.559023) (xy 213.378542 -345.538044) (xy 213.386162 -345.529662) (xy 213.392258 -345.508326)
			(xy 213.377526 -345.409266) (xy 213.365334 -345.390724) (xy 213.355682 -345.384882) (xy 213.328533 -345.367418)
			(xy 213.278443 -345.326697) (xy 213.233908 -345.279965) (xy 213.195645 -345.227973) (xy 213.164268 -345.171558)
			(xy 213.140282 -345.111625) (xy 213.124073 -345.04914) (xy 213.1159 -344.985105) (xy 213.115398 -344.952828)
			(xy 207.59166 -344.952828) (xy 207.59166 -354.085906) (xy 207.591235 -354.095975) (xy 207.583514 -354.114574)
			(xy 207.576674 -354.121974) (xy 200.934574 -360.764074) (xy 209.406497 -360.764074) (xy 209.410504 -360.57917)
			(xy 209.422517 -360.394612) (xy 209.442513 -360.210748) (xy 209.470455 -360.027924) (xy 209.506291 -359.846481)
			(xy 209.549953 -359.66676) (xy 209.60136 -359.4891) (xy 209.660414 -359.313834) (xy 209.727005 -359.14129)
			(xy 209.801008 -358.971793) (xy 209.882284 -358.805661) (xy 209.97068 -358.643205) (xy 210.066031 -358.484731)
			(xy 210.168157 -358.330536) (xy 210.276866 -358.18091) (xy 210.391955 -358.036134) (xy 210.513208 -357.896479)
			(xy 210.640397 -357.762208) (xy 210.773282 -357.633572) (xy 210.911616 -357.510813) (xy 211.055137 -357.394163)
			(xy 211.203576 -357.283839) (xy 211.356656 -357.180048) (xy 211.514087 -357.082986) (xy 211.675576 -356.992836)
			(xy 211.840818 -356.909765) (xy 212.009504 -356.83393) (xy 212.181316 -356.765474) (xy 212.355932 -356.704524)
			(xy 212.533025 -356.651197) (xy 212.712262 -356.60559) (xy 212.893306 -356.567791) (xy 213.075817 -356.53787)
			(xy 213.259454 -356.515883) (xy 213.44387 -356.501871) (xy 213.62872 -356.495861) (xy 213.813657 -356.497865)
			(xy 213.998334 -356.507878) (xy 214.182404 -356.525881) (xy 214.36552 -356.551842) (xy 214.547341 -356.58571)
			(xy 214.727524 -356.627422) (xy 214.90573 -356.676901) (xy 215.081626 -356.734053) (xy 215.254881 -356.798771)
			(xy 215.42517 -356.870934) (xy 215.592173 -356.950405) (xy 215.755577 -357.037036) (xy 215.915074 -357.130665)
			(xy 216.070366 -357.231114) (xy 216.221161 -357.338197) (xy 216.367176 -357.451711) (xy 216.508136 -357.571443)
			(xy 216.643777 -357.69717) (xy 216.773845 -357.828654) (xy 216.898095 -357.96565) (xy 217.016293 -358.107899)
			(xy 217.125847 -358.252014) (xy 221.738698 -358.252014) (xy 221.739177 -358.220503) (xy 221.74697 -358.157963)
			(xy 221.762426 -358.096865) (xy 221.785308 -358.038142) (xy 221.815266 -357.982695) (xy 221.851841 -357.931371)
			(xy 221.87281 -357.907844) (xy 221.87916 -357.900986) (xy 221.886018 -357.883714) (xy 221.887542 -357.797354)
			(xy 221.881192 -357.779828) (xy 221.874842 -357.772716) (xy 221.855455 -357.749586) (xy 221.82173 -357.699531)
			(xy 221.794164 -357.645838) (xy 221.773144 -357.589261) (xy 221.758966 -357.530594) (xy 221.751827 -357.470662)
			(xy 221.751398 -357.440484) (xy 221.7519 -357.408523) (xy 221.759911 -357.345105) (xy 221.775808 -357.283191)
			(xy 221.79934 -357.223758) (xy 221.830134 -357.167743) (xy 221.867707 -357.116028) (xy 221.911464 -357.069431)
			(xy 221.960717 -357.028686) (xy 222.014688 -356.994435) (xy 222.072527 -356.967218) (xy 222.13332 -356.947465)
			(xy 222.19611 -356.935487) (xy 222.259906 -356.931474) (xy 222.323702 -356.935487) (xy 222.386492 -356.947465)
			(xy 222.447285 -356.967218) (xy 222.505124 -356.994435) (xy 222.559095 -357.028686) (xy 222.608348 -357.069431)
			(xy 222.652105 -357.116028) (xy 222.689678 -357.167743) (xy 222.720472 -357.223758) (xy 222.744004 -357.283191)
			(xy 222.759901 -357.345105) (xy 222.767912 -357.408523) (xy 222.768414 -357.440484) (xy 222.76793 -357.471995)
			(xy 222.760138 -357.534534) (xy 222.744683 -357.595633) (xy 222.721802 -357.654355) (xy 222.691845 -357.709803)
			(xy 222.65527 -357.761127) (xy 222.634302 -357.784654) (xy 222.627952 -357.791512) (xy 222.621094 -357.808784)
			(xy 222.61957 -357.895144) (xy 222.62592 -357.91267) (xy 222.63227 -357.919782) (xy 222.651658 -357.942911)
			(xy 222.685382 -357.992967) (xy 222.712948 -358.04666) (xy 222.733967 -358.103237) (xy 222.748146 -358.161904)
			(xy 222.755285 -358.221836) (xy 222.755714 -358.252014) (xy 222.755212 -358.283975) (xy 222.747201 -358.347393)
			(xy 222.731304 -358.409307) (xy 222.707772 -358.46874) (xy 222.676978 -358.524755) (xy 222.639405 -358.57647)
			(xy 222.595648 -358.623067) (xy 222.546395 -358.663812) (xy 222.492424 -358.698063) (xy 222.434585 -358.72528)
			(xy 222.373792 -358.745033) (xy 222.311002 -358.757011) (xy 222.247206 -358.761025) (xy 222.18341 -358.757011)
			(xy 222.12062 -358.745033) (xy 222.059827 -358.72528) (xy 222.001988 -358.698063) (xy 221.948017 -358.663812)
			(xy 221.898764 -358.623067) (xy 221.855007 -358.57647) (xy 221.817434 -358.524755) (xy 221.78664 -358.46874)
			(xy 221.763108 -358.409307) (xy 221.747211 -358.347393) (xy 221.7392 -358.283975) (xy 221.738698 -358.252014)
			(xy 217.125847 -358.252014) (xy 217.128219 -358.255134) (xy 217.233662 -358.40708) (xy 217.332423 -358.563451)
			(xy 217.424318 -358.723954) (xy 217.509174 -358.888286) (xy 217.586832 -359.056141) (xy 217.657145 -359.227201)
			(xy 217.719982 -359.401147) (xy 217.775226 -359.577652) (xy 217.822771 -359.756384) (xy 217.862529 -359.937008)
			(xy 217.894426 -360.119185) (xy 217.918401 -360.302572) (xy 217.934409 -360.486826) (xy 217.942421 -360.6716)
			(xy 217.942922 -360.764074) (xy 217.942421 -360.856548) (xy 217.934409 -361.041322) (xy 217.927712 -361.118404)
			(xy 223.844358 -361.118404) (xy 223.84477 -361.08805) (xy 223.851988 -361.027774) (xy 223.866332 -360.968786)
			(xy 223.8876 -360.911927) (xy 223.915488 -360.858005) (xy 223.9496 -360.807788) (xy 223.989449 -360.761991)
			(xy 224.034468 -360.721265) (xy 224.058988 -360.703368) (xy 224.068894 -360.69651) (xy 224.08007 -360.675682)
			(xy 224.082864 -360.569764) (xy 224.072704 -360.548428) (xy 224.063052 -360.540808) (xy 224.037629 -360.520103)
			(xy 223.991832 -360.47318) (xy 223.952446 -360.42076) (xy 223.920124 -360.363713) (xy 223.895403 -360.302984)
			(xy 223.878691 -360.239582) (xy 223.870268 -360.174558) (xy 223.869758 -360.141774) (xy 223.87026 -360.109813)
			(xy 223.878271 -360.046395) (xy 223.894168 -359.984481) (xy 223.9177 -359.925048) (xy 223.948494 -359.869033)
			(xy 223.986067 -359.817318) (xy 224.029824 -359.770721) (xy 224.079077 -359.729976) (xy 224.133048 -359.695725)
			(xy 224.190887 -359.668508) (xy 224.25168 -359.648755) (xy 224.31447 -359.636777) (xy 224.378266 -359.632764)
			(xy 224.442062 -359.636777) (xy 224.504852 -359.648755) (xy 224.565645 -359.668508) (xy 224.623484 -359.695725)
			(xy 224.677455 -359.729976) (xy 224.726708 -359.770721) (xy 224.770465 -359.817318) (xy 224.808038 -359.869033)
			(xy 224.838832 -359.925048) (xy 224.862364 -359.984481) (xy 224.878261 -360.046395) (xy 224.886272 -360.109813)
			(xy 224.886774 -360.141774) (xy 224.886332 -360.172127) (xy 224.879117 -360.232401) (xy 224.864776 -360.291388)
			(xy 224.843512 -360.348247) (xy 224.815628 -360.402168) (xy 224.781521 -360.452386) (xy 224.741677 -360.498184)
			(xy 224.696661 -360.538911) (xy 224.672144 -360.55681) (xy 224.662238 -360.563668) (xy 224.651062 -360.584496)
			(xy 224.648268 -360.690414) (xy 224.658428 -360.71175) (xy 224.66808 -360.71937) (xy 224.693499 -360.740079)
			(xy 224.739295 -360.787002) (xy 224.77868 -360.839422) (xy 224.811002 -360.896469) (xy 224.835724 -360.957196)
			(xy 224.852437 -361.020597) (xy 224.860863 -361.085621) (xy 224.861374 -361.118404) (xy 224.860872 -361.150365)
			(xy 224.852861 -361.213783) (xy 224.836964 -361.275697) (xy 224.813432 -361.33513) (xy 224.782638 -361.391145)
			(xy 224.745065 -361.44286) (xy 224.701308 -361.489457) (xy 224.652055 -361.530202) (xy 224.598084 -361.564453)
			(xy 224.540245 -361.59167) (xy 224.479452 -361.611423) (xy 224.416662 -361.623401) (xy 224.352866 -361.627415)
			(xy 224.28907 -361.623401) (xy 224.22628 -361.611423) (xy 224.165487 -361.59167) (xy 224.107648 -361.564453)
			(xy 224.053677 -361.530202) (xy 224.004424 -361.489457) (xy 223.960667 -361.44286) (xy 223.923094 -361.391145)
			(xy 223.8923 -361.33513) (xy 223.868768 -361.275697) (xy 223.852871 -361.213783) (xy 223.84486 -361.150365)
			(xy 223.844358 -361.118404) (xy 217.927712 -361.118404) (xy 217.918401 -361.225576) (xy 217.894426 -361.408963)
			(xy 217.862529 -361.59114) (xy 217.822771 -361.771764) (xy 217.775226 -361.950496) (xy 217.765298 -361.982215)
			(xy 222.86569 -361.982215) (xy 222.86569 -361.918293) (xy 222.873701 -361.854875) (xy 222.889598 -361.792961)
			(xy 222.91313 -361.733528) (xy 222.943924 -361.677513) (xy 222.981497 -361.625798) (xy 223.025254 -361.579201)
			(xy 223.074507 -361.538456) (xy 223.128478 -361.504205) (xy 223.186317 -361.476988) (xy 223.24711 -361.457235)
			(xy 223.3099 -361.445257) (xy 223.373696 -361.441244) (xy 223.437492 -361.445257) (xy 223.500282 -361.457235)
			(xy 223.561075 -361.476988) (xy 223.618914 -361.504205) (xy 223.672885 -361.538456) (xy 223.722138 -361.579201)
			(xy 223.765895 -361.625798) (xy 223.803468 -361.677513) (xy 223.834262 -361.733528) (xy 223.857794 -361.792961)
			(xy 223.873691 -361.854875) (xy 223.881702 -361.918293) (xy 223.882204 -361.950254) (xy 223.881702 -361.982215)
			(xy 223.873691 -362.045633) (xy 223.857794 -362.107547) (xy 223.834262 -362.16698) (xy 223.803468 -362.222995)
			(xy 223.765895 -362.27471) (xy 223.722138 -362.321307) (xy 223.672885 -362.362052) (xy 223.618914 -362.396303)
			(xy 223.561075 -362.42352) (xy 223.500282 -362.443273) (xy 223.437492 -362.455251) (xy 223.373696 -362.459265)
			(xy 223.3099 -362.455251) (xy 223.24711 -362.443273) (xy 223.186317 -362.42352) (xy 223.128478 -362.396303)
			(xy 223.074507 -362.362052) (xy 223.025254 -362.321307) (xy 222.981497 -362.27471) (xy 222.943924 -362.222995)
			(xy 222.91313 -362.16698) (xy 222.889598 -362.107547) (xy 222.873701 -362.045633) (xy 222.86569 -361.982215)
			(xy 217.765298 -361.982215) (xy 217.719982 -362.127001) (xy 217.657145 -362.300947) (xy 217.586832 -362.472007)
			(xy 217.509174 -362.639862) (xy 217.424318 -362.804194) (xy 217.332423 -362.964697) (xy 217.233662 -363.121068)
			(xy 217.128219 -363.273014) (xy 217.016293 -363.420249) (xy 216.898095 -363.562498) (xy 216.861563 -363.602778)
			(xy 224.128838 -363.602778) (xy 224.129307 -363.570652) (xy 224.137415 -363.506913) (xy 224.153486 -363.444703)
			(xy 224.177266 -363.385013) (xy 224.208373 -363.328793) (xy 224.246314 -363.276939) (xy 224.290485 -363.230277)
			(xy 224.34018 -363.189549) (xy 224.39461 -363.155405) (xy 224.452906 -363.128389) (xy 224.514141 -363.108931)
			(xy 224.545652 -363.102652) (xy 224.55505 -363.100874) (xy 224.570798 -363.091222) (xy 224.624138 -363.022642)
			(xy 224.629472 -363.004862) (xy 224.62871 -362.995464) (xy 224.62744 -362.959142) (xy 224.627942 -362.927181)
			(xy 224.635953 -362.863763) (xy 224.65185 -362.801849) (xy 224.675382 -362.742416) (xy 224.706176 -362.686401)
			(xy 224.743749 -362.634686) (xy 224.787506 -362.588089) (xy 224.836759 -362.547344) (xy 224.89073 -362.513093)
			(xy 224.948569 -362.485876) (xy 225.009362 -362.466123) (xy 225.072152 -362.454145) (xy 225.135948 -362.450132)
			(xy 225.199744 -362.454145) (xy 225.262534 -362.466123) (xy 225.323327 -362.485876) (xy 225.381166 -362.513093)
			(xy 225.435137 -362.547344) (xy 225.48439 -362.588089) (xy 225.528147 -362.634686) (xy 225.56572 -362.686401)
			(xy 225.596514 -362.742416) (xy 225.620046 -362.801849) (xy 225.635943 -362.863763) (xy 225.643954 -362.927181)
			(xy 225.644456 -362.959142) (xy 225.643918 -362.991266) (xy 225.63582 -363.055003) (xy 225.619758 -363.117211)
			(xy 225.595987 -363.176901) (xy 225.564887 -363.233121) (xy 225.526953 -363.284976) (xy 225.482789 -363.331639)
			(xy 225.433099 -363.372368) (xy 225.378674 -363.406513) (xy 225.320382 -363.43353) (xy 225.259151 -363.452989)
			(xy 225.227642 -363.459268) (xy 225.218244 -363.461046) (xy 225.202496 -363.470698) (xy 225.149156 -363.539278)
			(xy 225.143822 -363.557058) (xy 225.144584 -363.566456) (xy 225.145854 -363.602778) (xy 225.145352 -363.634739)
			(xy 225.137341 -363.698157) (xy 225.121444 -363.760071) (xy 225.097912 -363.819504) (xy 225.067118 -363.875519)
			(xy 225.029545 -363.927234) (xy 224.985788 -363.973831) (xy 224.936535 -364.014576) (xy 224.882564 -364.048827)
			(xy 224.824725 -364.076044) (xy 224.763932 -364.095797) (xy 224.701142 -364.107775) (xy 224.637346 -364.111789)
			(xy 224.57355 -364.107775) (xy 224.51076 -364.095797) (xy 224.449967 -364.076044) (xy 224.392128 -364.048827)
			(xy 224.338157 -364.014576) (xy 224.288904 -363.973831) (xy 224.245147 -363.927234) (xy 224.207574 -363.875519)
			(xy 224.17678 -363.819504) (xy 224.153248 -363.760071) (xy 224.137351 -363.698157) (xy 224.12934 -363.634739)
			(xy 224.128838 -363.602778) (xy 216.861563 -363.602778) (xy 216.773845 -363.699494) (xy 216.643777 -363.830978)
			(xy 216.508136 -363.956705) (xy 216.367176 -364.076437) (xy 216.221161 -364.189951) (xy 216.070366 -364.297034)
			(xy 215.915074 -364.397483) (xy 215.755577 -364.491112) (xy 215.592173 -364.577743) (xy 215.42517 -364.657214)
			(xy 215.254881 -364.729377) (xy 215.081626 -364.794095) (xy 214.90573 -364.851247) (xy 214.727524 -364.900726)
			(xy 214.547341 -364.942438) (xy 214.36552 -364.976306) (xy 214.182404 -365.002267) (xy 213.998334 -365.02027)
			(xy 213.813657 -365.030283) (xy 213.62872 -365.032287) (xy 213.44387 -365.026277) (xy 213.259454 -365.012265)
			(xy 213.075817 -364.990278) (xy 212.893306 -364.960357) (xy 212.712262 -364.922558) (xy 212.533025 -364.876951)
			(xy 212.355932 -364.823624) (xy 212.181316 -364.762674) (xy 212.009504 -364.694218) (xy 211.840818 -364.618383)
			(xy 211.675576 -364.535312) (xy 211.514087 -364.445162) (xy 211.356656 -364.3481) (xy 211.203576 -364.244309)
			(xy 211.055137 -364.133985) (xy 210.911616 -364.017335) (xy 210.773282 -363.894576) (xy 210.640397 -363.76594)
			(xy 210.513208 -363.631669) (xy 210.391955 -363.492014) (xy 210.276866 -363.347238) (xy 210.168157 -363.197612)
			(xy 210.066031 -363.043417) (xy 209.97068 -362.884943) (xy 209.882284 -362.722487) (xy 209.801008 -362.556355)
			(xy 209.727005 -362.386858) (xy 209.660414 -362.214314) (xy 209.60136 -362.039048) (xy 209.549953 -361.861388)
			(xy 209.506291 -361.681667) (xy 209.470455 -361.500224) (xy 209.442513 -361.3174) (xy 209.422517 -361.133536)
			(xy 209.410504 -360.948978) (xy 209.406497 -360.764074) (xy 200.934574 -360.764074) (xy 195.472189 -366.226459)
			(xy 220.783373 -366.226459) (xy 220.783373 -366.098741) (xy 220.791393 -365.971275) (xy 220.8074 -365.844564)
			(xy 220.831332 -365.719108) (xy 220.863094 -365.595402) (xy 220.902561 -365.473935) (xy 220.949578 -365.355185)
			(xy 221.003958 -365.239623) (xy 221.065486 -365.127702) (xy 221.133921 -365.019866) (xy 221.208992 -364.91654)
			(xy 221.290403 -364.818132) (xy 221.377832 -364.725029) (xy 221.470935 -364.6376) (xy 221.569343 -364.55619)
			(xy 221.67267 -364.481119) (xy 221.780506 -364.412684) (xy 221.892426 -364.351156) (xy 222.007989 -364.296776)
			(xy 222.126739 -364.24976) (xy 222.248206 -364.210293) (xy 222.371912 -364.178531) (xy 222.497368 -364.154599)
			(xy 222.624079 -364.138592) (xy 222.751545 -364.130573) (xy 222.815404 -364.130082) (xy 222.879318 -364.130518)
			(xy 223.006893 -364.138558) (xy 223.133711 -364.154599) (xy 223.259271 -364.178577) (xy 223.383075 -364.210399)
			(xy 223.504634 -364.249939) (xy 223.623469 -364.297039) (xy 223.739109 -364.351514) (xy 223.851096 -364.413148)
			(xy 223.95899 -364.481699) (xy 224.062362 -364.556894) (xy 224.160804 -364.638436) (xy 224.253927 -364.726004)
			(xy 224.341363 -364.819251) (xy 224.422767 -364.917809) (xy 224.455289 -364.962651) (xy 224.819712 -364.962651)
			(xy 224.819712 -364.898729) (xy 224.827723 -364.835311) (xy 224.84362 -364.773397) (xy 224.867152 -364.713964)
			(xy 224.897946 -364.657949) (xy 224.935519 -364.606234) (xy 224.979276 -364.559637) (xy 225.028529 -364.518892)
			(xy 225.0825 -364.484641) (xy 225.140339 -364.457424) (xy 225.201132 -364.437671) (xy 225.263922 -364.425693)
			(xy 225.327718 -364.42168) (xy 225.391514 -364.425693) (xy 225.454304 -364.437671) (xy 225.515097 -364.457424)
			(xy 225.572936 -364.484641) (xy 225.626907 -364.518892) (xy 225.67616 -364.559637) (xy 225.719917 -364.606234)
			(xy 225.75749 -364.657949) (xy 225.788284 -364.713964) (xy 225.811816 -364.773397) (xy 225.827713 -364.835311)
			(xy 225.835724 -364.898729) (xy 225.836226 -364.93069) (xy 225.835724 -364.962651) (xy 225.827713 -365.026069)
			(xy 225.811816 -365.087983) (xy 225.788284 -365.147416) (xy 225.758996 -365.200692) (xy 228.296724 -365.200692)
			(xy 228.297176 -365.170819) (xy 228.304178 -365.111483) (xy 228.318085 -365.053377) (xy 228.338704 -364.997301)
			(xy 228.365753 -364.944027) (xy 228.398857 -364.89429) (xy 228.417882 -364.871254) (xy 228.424933 -364.862133)
			(xy 228.430715 -364.839839) (xy 228.426188 -364.817256) (xy 228.41966 -364.807754) (xy 228.400124 -364.781135)
			(xy 228.367366 -364.723805) (xy 228.342303 -364.662718) (xy 228.325355 -364.598902) (xy 228.316809 -364.533428)
			(xy 228.316282 -364.500414) (xy 228.316784 -364.468453) (xy 228.324795 -364.405035) (xy 228.340692 -364.343121)
			(xy 228.364224 -364.283688) (xy 228.395018 -364.227673) (xy 228.432591 -364.175958) (xy 228.476348 -364.129361)
			(xy 228.525601 -364.088616) (xy 228.579572 -364.054365) (xy 228.637411 -364.027148) (xy 228.698204 -364.007395)
			(xy 228.760994 -363.995417) (xy 228.82479 -363.991404) (xy 228.888586 -363.995417) (xy 228.951376 -364.007395)
			(xy 229.012169 -364.027148) (xy 229.070008 -364.054365) (xy 229.123979 -364.088616) (xy 229.173232 -364.129361)
			(xy 229.216989 -364.175958) (xy 229.254562 -364.227673) (xy 229.285356 -364.283688) (xy 229.308888 -364.343121)
			(xy 229.324785 -364.405035) (xy 229.332796 -364.468453) (xy 229.333298 -364.500414) (xy 229.332844 -364.530287)
			(xy 229.325842 -364.589622) (xy 229.311935 -364.647728) (xy 229.291316 -364.703804) (xy 229.264268 -364.757078)
			(xy 229.231164 -364.806816) (xy 229.21214 -364.829852) (xy 229.205083 -364.83897) (xy 229.199299 -364.861266)
			(xy 229.203831 -364.88385) (xy 229.210362 -364.893352) (xy 229.229891 -364.919976) (xy 229.262652 -364.977304)
			(xy 229.287718 -365.038389) (xy 229.304667 -365.102205) (xy 229.313213 -365.167678) (xy 229.31374 -365.200692)
			(xy 229.313238 -365.232653) (xy 229.305227 -365.296071) (xy 229.28933 -365.357985) (xy 229.265798 -365.417418)
			(xy 229.235004 -365.473433) (xy 229.197431 -365.525148) (xy 229.153674 -365.571745) (xy 229.104421 -365.61249)
			(xy 229.05045 -365.646741) (xy 228.992611 -365.673958) (xy 228.931818 -365.693711) (xy 228.869028 -365.705689)
			(xy 228.805232 -365.709703) (xy 228.741436 -365.705689) (xy 228.678646 -365.693711) (xy 228.617853 -365.673958)
			(xy 228.560014 -365.646741) (xy 228.506043 -365.61249) (xy 228.45679 -365.571745) (xy 228.413033 -365.525148)
			(xy 228.37546 -365.473433) (xy 228.344666 -365.417418) (xy 228.321134 -365.357985) (xy 228.305237 -365.296071)
			(xy 228.297226 -365.232653) (xy 228.296724 -365.200692) (xy 225.758996 -365.200692) (xy 225.75749 -365.203431)
			(xy 225.719917 -365.255146) (xy 225.67616 -365.301743) (xy 225.626907 -365.342488) (xy 225.572936 -365.376739)
			(xy 225.515097 -365.403956) (xy 225.454304 -365.423709) (xy 225.391514 -365.435687) (xy 225.327718 -365.439701)
			(xy 225.263922 -365.435687) (xy 225.201132 -365.423709) (xy 225.140339 -365.403956) (xy 225.0825 -365.376739)
			(xy 225.028529 -365.342488) (xy 224.979276 -365.301743) (xy 224.935519 -365.255146) (xy 224.897946 -365.203431)
			(xy 224.867152 -365.147416) (xy 224.84362 -365.087983) (xy 224.827723 -365.026069) (xy 224.819712 -364.962651)
			(xy 224.455289 -364.962651) (xy 224.497816 -365.021287) (xy 224.566214 -365.129277) (xy 224.62769 -365.241352)
			(xy 224.682001 -365.357068) (xy 224.705926 -365.416338) (xy 224.708776 -365.423026) (xy 224.717693 -365.434505)
			(xy 224.723452 -365.438944) (xy 224.747454 -365.456904) (xy 224.791499 -365.497574) (xy 224.830453 -365.543143)
			(xy 224.863778 -365.592977) (xy 224.891009 -365.646384) (xy 224.91177 -365.702624) (xy 224.925772 -365.760916)
			(xy 224.932821 -365.820449) (xy 224.933256 -365.850424) (xy 224.932666 -365.886025) (xy 224.931243 -365.8961)
			(xy 230.641412 -365.8961) (xy 230.645426 -365.832306) (xy 230.657404 -365.769518) (xy 230.677157 -365.708726)
			(xy 230.704373 -365.650889) (xy 230.738624 -365.59692) (xy 230.779369 -365.547669) (xy 230.825965 -365.503913)
			(xy 230.877678 -365.466343) (xy 230.933693 -365.43555) (xy 230.993125 -365.412021) (xy 231.055037 -365.396126)
			(xy 231.118454 -365.388116) (xy 231.150414 -365.387636) (xy 231.180288 -365.388082) (xy 231.239623 -365.395085)
			(xy 231.29773 -365.408992) (xy 231.353806 -365.429613) (xy 231.407079 -365.456663) (xy 231.456816 -365.489768)
			(xy 231.479852 -365.508794) (xy 231.487218 -365.51489) (xy 231.50449 -365.520986) (xy 231.592374 -365.518192)
			(xy 231.609392 -365.510826) (xy 231.61625 -365.504222) (xy 231.640051 -365.481821) (xy 231.692382 -365.442661)
			(xy 231.749299 -365.410529) (xy 231.809864 -365.385954) (xy 231.873078 -365.369341) (xy 231.9379 -365.360964)
			(xy 231.97058 -365.360458) (xy 232.002541 -365.361006) (xy 232.065959 -365.369015) (xy 232.127874 -365.38491)
			(xy 232.187308 -365.408439) (xy 232.243324 -365.439232) (xy 232.295039 -365.476804) (xy 232.341637 -365.52056)
			(xy 232.382383 -365.569812) (xy 232.416635 -365.623783) (xy 232.443852 -365.681621) (xy 232.463606 -365.742414)
			(xy 232.475584 -365.805204) (xy 232.479598 -365.869) (xy 232.475584 -365.932796) (xy 232.463606 -365.995586)
			(xy 232.443852 -366.056379) (xy 232.416635 -366.114217) (xy 232.382383 -366.168188) (xy 232.341637 -366.21744)
			(xy 232.295039 -366.261196) (xy 232.243324 -366.298768) (xy 232.187308 -366.329561) (xy 232.127874 -366.35309)
			(xy 232.065959 -366.368985) (xy 232.002541 -366.376994) (xy 231.97058 -366.377474) (xy 231.940706 -366.377029)
			(xy 231.881371 -366.370026) (xy 231.823265 -366.356118) (xy 231.767188 -366.335497) (xy 231.713915 -366.308447)
			(xy 231.664178 -366.275341) (xy 231.641142 -366.256316) (xy 231.633776 -366.25022) (xy 231.616504 -366.244124)
			(xy 231.52862 -366.246918) (xy 231.511602 -366.254284) (xy 231.504744 -366.260888) (xy 231.480947 -366.283293)
			(xy 231.428615 -366.322453) (xy 231.371697 -366.354584) (xy 231.311132 -366.379159) (xy 231.247917 -366.395771)
			(xy 231.183095 -366.404147) (xy 231.150414 -366.404652) (xy 231.118454 -366.404084) (xy 231.055037 -366.396074)
			(xy 230.993125 -366.380179) (xy 230.933693 -366.35665) (xy 230.877678 -366.325857) (xy 230.825965 -366.288287)
			(xy 230.779369 -366.244531) (xy 230.738624 -366.19528) (xy 230.704373 -366.141311) (xy 230.677157 -366.083474)
			(xy 230.657404 -366.022682) (xy 230.645426 -365.959894) (xy 230.641412 -365.8961) (xy 224.931243 -365.8961)
			(xy 224.92271 -365.956528) (xy 224.903009 -366.024951) (xy 224.87395 -366.089953) (xy 224.855532 -366.120426)
			(xy 224.851899 -366.126685) (xy 224.848027 -366.140622) (xy 224.847912 -366.147858) (xy 224.847912 -366.16259)
			(xy 224.847411 -366.225485) (xy 224.839639 -366.351034) (xy 224.824117 -366.475862) (xy 224.800906 -366.599491)
			(xy 224.770094 -366.721448) (xy 224.731798 -366.841266) (xy 224.686166 -366.958487) (xy 224.660206 -367.015776)
			(xy 224.655126 -367.026698) (xy 224.655634 -367.049558) (xy 224.701862 -367.141506) (xy 224.719896 -367.155476)
			(xy 224.73158 -367.158016) (xy 224.749001 -367.161886) (xy 224.783092 -367.172446) (xy 224.799652 -367.179098)
			(xy 224.813114 -367.184686) (xy 224.841308 -367.180114) (xy 224.931986 -367.101628) (xy 224.940622 -367.07445)
			(xy 224.937066 -367.060226) (xy 224.929706 -367.02938) (xy 224.921805 -366.966458) (xy 224.921318 -366.93475)
			(xy 224.921821 -366.903213) (xy 224.929628 -366.840624) (xy 224.945118 -366.779482) (xy 224.96805 -366.720725)
			(xy 224.998075 -366.665255) (xy 225.03473 -366.613926) (xy 225.077452 -366.567524) (xy 225.125586 -366.526763)
			(xy 225.178391 -366.492268) (xy 225.235058 -366.46457) (xy 225.294715 -366.444093) (xy 225.356448 -366.431153)
			(xy 225.419306 -366.425948) (xy 225.482326 -366.428557) (xy 225.544539 -366.438941) (xy 225.60499 -366.456941)
			(xy 225.662751 -366.48228) (xy 225.716934 -366.514568) (xy 225.766707 -366.55331) (xy 225.811306 -366.597911)
			(xy 225.850046 -366.647686) (xy 225.882331 -366.70187) (xy 225.907667 -366.759632) (xy 225.925664 -366.820084)
			(xy 225.936045 -366.882298) (xy 225.938652 -366.945318) (xy 225.933443 -367.008176) (xy 225.9205 -367.069908)
			(xy 225.900021 -367.129564) (xy 225.87232 -367.18623) (xy 225.837823 -367.239034) (xy 225.797059 -367.287165)
			(xy 225.750656 -367.329885) (xy 225.699324 -367.366538) (xy 225.643853 -367.39656) (xy 225.585095 -367.41949)
			(xy 225.523952 -367.434976) (xy 225.461363 -367.442781) (xy 225.429826 -367.443258) (xy 225.397414 -367.442745)
			(xy 225.333112 -367.434547) (xy 225.270374 -367.418242) (xy 225.210216 -367.394096) (xy 225.181668 -367.378742)
			(xy 225.168968 -367.37163) (xy 225.14052 -367.372646) (xy 225.041206 -367.44021) (xy 225.029522 -367.466372)
			(xy 225.031554 -367.48085) (xy 225.033121 -367.493427) (xy 225.034771 -367.518722) (xy 225.034856 -367.531396)
			(xy 225.034319 -367.558645) (xy 225.026564 -367.612588) (xy 225.011212 -367.664879) (xy 224.988575 -367.714453)
			(xy 224.959113 -367.760301) (xy 224.923427 -367.80149) (xy 224.882243 -367.837182) (xy 224.836399 -367.86665)
			(xy 224.786828 -367.889294) (xy 224.734539 -367.904653) (xy 224.680597 -367.912415) (xy 224.653348 -367.912904)
			(xy 224.615248 -367.910872) (xy 224.602294 -367.909602) (xy 224.578672 -367.919508) (xy 224.509076 -368.006122)
			(xy 224.506031 -368.021827) (xy 230.498136 -368.021827) (xy 230.498136 -367.957905) (xy 230.506147 -367.894487)
			(xy 230.522044 -367.832573) (xy 230.545576 -367.77314) (xy 230.57637 -367.717125) (xy 230.613943 -367.66541)
			(xy 230.6577 -367.618813) (xy 230.706953 -367.578068) (xy 230.760924 -367.543817) (xy 230.818763 -367.5166)
			(xy 230.879556 -367.496847) (xy 230.942346 -367.484869) (xy 231.006142 -367.480856) (xy 231.069938 -367.484869)
			(xy 231.132728 -367.496847) (xy 231.193521 -367.5166) (xy 231.25136 -367.543817) (xy 231.305331 -367.578068)
			(xy 231.354584 -367.618813) (xy 231.398341 -367.66541) (xy 231.435914 -367.717125) (xy 231.466708 -367.77314)
			(xy 231.49024 -367.832573) (xy 231.506137 -367.894487) (xy 231.514148 -367.957905) (xy 231.51465 -367.989866)
			(xy 231.514148 -368.021827) (xy 231.506137 -368.085245) (xy 231.49024 -368.147159) (xy 231.466708 -368.206592)
			(xy 231.435914 -368.262607) (xy 231.398341 -368.314322) (xy 231.354584 -368.360919) (xy 231.305331 -368.401664)
			(xy 231.25136 -368.435915) (xy 231.193521 -368.463132) (xy 231.132728 -368.482885) (xy 231.069938 -368.494863)
			(xy 231.006142 -368.498877) (xy 230.942346 -368.494863) (xy 230.879556 -368.482885) (xy 230.818763 -368.463132)
			(xy 230.760924 -368.435915) (xy 230.706953 -368.401664) (xy 230.6577 -368.360919) (xy 230.613943 -368.314322)
			(xy 230.57637 -368.262607) (xy 230.545576 -368.206592) (xy 230.522044 -368.147159) (xy 230.506147 -368.085245)
			(xy 230.498136 -368.021827) (xy 224.506031 -368.021827) (xy 224.50425 -368.031014) (xy 224.508314 -368.04346)
			(xy 224.519893 -368.081669) (xy 224.532401 -368.160516) (xy 224.533206 -368.200432) (xy 224.532774 -368.231164)
			(xy 224.525362 -368.292179) (xy 224.510649 -368.351855) (xy 224.488851 -368.409324) (xy 224.460285 -368.463746)
			(xy 224.425368 -368.514328) (xy 224.384609 -368.560333) (xy 224.338601 -368.601089) (xy 224.288017 -368.636003)
			(xy 224.233593 -368.664565) (xy 224.176123 -368.68636) (xy 224.116445 -368.701068) (xy 224.05543 -368.708476)
			(xy 224.024698 -368.70894) (xy 223.991758 -368.708467) (xy 223.92643 -368.699971) (xy 223.862745 -368.68311)
			(xy 223.801772 -368.658164) (xy 223.744531 -368.625553) (xy 223.691981 -368.585823) (xy 223.645002 -368.539638)
			(xy 223.604382 -368.487773) (xy 223.5708 -368.431096) (xy 223.544819 -368.370556) (xy 223.526874 -368.307168)
			(xy 223.517266 -368.241994) (xy 223.51619 -368.209068) (xy 223.515936 -368.19713) (xy 223.505268 -368.176048)
			(xy 223.42094 -368.114072) (xy 223.397572 -368.110008) (xy 223.386142 -368.11331) (xy 223.3305 -368.129165)
			(xy 223.217775 -368.155289) (xy 223.103747 -368.174957) (xy 222.988784 -368.188104) (xy 222.87326 -368.194689)
			(xy 222.815404 -368.195098) (xy 222.751545 -368.194627) (xy 222.624079 -368.186608) (xy 222.497368 -368.170601)
			(xy 222.371912 -368.146669) (xy 222.248206 -368.114907) (xy 222.126739 -368.07544) (xy 222.007989 -368.028424)
			(xy 221.892426 -367.974044) (xy 221.780506 -367.912516) (xy 221.67267 -367.844081) (xy 221.569343 -367.76901)
			(xy 221.470935 -367.6876) (xy 221.377832 -367.600171) (xy 221.290403 -367.507068) (xy 221.208992 -367.40866)
			(xy 221.133921 -367.305334) (xy 221.065486 -367.197498) (xy 221.003958 -367.085577) (xy 220.949578 -366.970015)
			(xy 220.902561 -366.851265) (xy 220.863094 -366.729798) (xy 220.831332 -366.606092) (xy 220.8074 -366.480636)
			(xy 220.791393 -366.353925) (xy 220.783373 -366.226459) (xy 195.472189 -366.226459) (xy 194.961002 -366.737646)
			(xy 194.953606 -366.744499) (xy 194.935008 -366.752242) (xy 194.924934 -366.752632) (xy 145.594324 -366.752632)
			(xy 145.584261 -366.75307) (xy 145.565679 -366.760807) (xy 145.558256 -366.767618) (xy 145.375673 -366.950201)
			(xy 218.883224 -366.950201) (xy 218.883224 -366.886279) (xy 218.891235 -366.822861) (xy 218.907132 -366.760947)
			(xy 218.930664 -366.701514) (xy 218.961458 -366.645499) (xy 218.999031 -366.593784) (xy 219.042788 -366.547187)
			(xy 219.092041 -366.506442) (xy 219.146012 -366.472191) (xy 219.203851 -366.444974) (xy 219.264644 -366.425221)
			(xy 219.327434 -366.413243) (xy 219.39123 -366.40923) (xy 219.455026 -366.413243) (xy 219.517816 -366.425221)
			(xy 219.578609 -366.444974) (xy 219.636448 -366.472191) (xy 219.690419 -366.506442) (xy 219.739672 -366.547187)
			(xy 219.783429 -366.593784) (xy 219.821002 -366.645499) (xy 219.851796 -366.701514) (xy 219.875328 -366.760947)
			(xy 219.891225 -366.822861) (xy 219.899236 -366.886279) (xy 219.899738 -366.91824) (xy 219.899236 -366.950201)
			(xy 219.891225 -367.013619) (xy 219.875328 -367.075533) (xy 219.851796 -367.134966) (xy 219.821002 -367.190981)
			(xy 219.783429 -367.242696) (xy 219.739672 -367.289293) (xy 219.690419 -367.330038) (xy 219.636448 -367.364289)
			(xy 219.578609 -367.391506) (xy 219.517816 -367.411259) (xy 219.455026 -367.423237) (xy 219.39123 -367.427251)
			(xy 219.327434 -367.423237) (xy 219.264644 -367.411259) (xy 219.203851 -367.391506) (xy 219.146012 -367.364289)
			(xy 219.092041 -367.330038) (xy 219.042788 -367.289293) (xy 218.999031 -367.242696) (xy 218.961458 -367.190981)
			(xy 218.930664 -367.134966) (xy 218.907132 -367.075533) (xy 218.891235 -367.013619) (xy 218.883224 -366.950201)
			(xy 145.375673 -366.950201) (xy 144.399762 -367.926112) (xy 144.3926 -367.934134) (xy 144.38499 -367.95422)
			(xy 144.38503 -367.964974) (xy 144.389602 -368.051334) (xy 144.399508 -368.070384) (xy 144.40789 -368.077242)
			(xy 144.429795 -368.095447) (xy 144.468475 -368.137253) (xy 144.500503 -368.184351) (xy 144.525164 -368.23569)
			(xy 144.54191 -368.290128) (xy 144.550368 -368.346452) (xy 144.550892 -368.37493) (xy 144.550346 -368.404368)
			(xy 144.541286 -368.462543) (xy 144.532858 -368.490754) (xy 144.53057 -368.499369) (xy 144.531363 -368.517163)
			(xy 144.534382 -368.525552) (xy 144.54632 -368.553746) (xy 144.57045 -368.579654) (xy 144.596135 -368.592836)
			(xy 144.644638 -368.624155) (xy 144.667224 -368.642138) (xy 144.699228 -368.653568) (xy 144.853406 -368.653568)
			(xy 144.85366 -368.653568) (xy 144.885664 -368.642138) (xy 144.908238 -368.624138) (xy 144.956742 -368.592818)
			(xy 144.982438 -368.579654) (xy 145.006568 -368.553746) (xy 145.018506 -368.525552) (xy 145.021619 -368.517186)
			(xy 145.022393 -368.499363) (xy 145.02003 -368.490754) (xy 145.011616 -368.46254) (xy 145.002562 -368.404367)
			(xy 145.001996 -368.37493) (xy 145.002482 -368.347679) (xy 145.010238 -368.293731) (xy 145.025593 -368.241436)
			(xy 145.048235 -368.191859) (xy 145.077701 -368.146009) (xy 145.113392 -368.104818) (xy 145.154583 -368.069127)
			(xy 145.200433 -368.039661) (xy 145.25001 -368.017019) (xy 145.302305 -368.001664) (xy 145.356253 -367.993908)
			(xy 145.410755 -367.993908) (xy 145.464703 -368.001664) (xy 145.516998 -368.017019) (xy 145.566575 -368.039661)
			(xy 145.612425 -368.069127) (xy 145.653616 -368.104818) (xy 145.689307 -368.146009) (xy 145.718773 -368.191859)
			(xy 145.741415 -368.241436) (xy 145.75677 -368.293731) (xy 145.764526 -368.347679) (xy 145.765012 -368.37493)
			(xy 145.765012 -368.375184) (xy 145.764647 -368.399214) (xy 145.758604 -368.446891) (xy 145.746611 -368.49343)
			(xy 145.738088 -368.5159) (xy 145.733008 -368.528346) (xy 145.73631 -368.554254) (xy 145.803112 -368.644932)
			(xy 145.826734 -368.655854) (xy 145.839942 -368.654838) (xy 145.868644 -368.653822) (xy 145.895891 -368.654311)
			(xy 145.94983 -368.662072) (xy 146.002115 -368.67743) (xy 146.051683 -368.700072) (xy 146.097524 -368.729537)
			(xy 146.138706 -368.765226) (xy 146.17439 -368.806411) (xy 146.203849 -368.852256) (xy 146.226486 -368.901826)
			(xy 146.241837 -368.954113) (xy 146.249592 -369.008053) (xy 146.249592 -369.062547) (xy 146.249591 -369.062553)
			(xy 150.110385 -369.062553) (xy 150.110385 -369.008047) (xy 150.118143 -368.954097) (xy 150.1335 -368.901799)
			(xy 150.156144 -368.85222) (xy 150.185614 -368.806369) (xy 150.221309 -368.765178) (xy 150.262504 -368.729487)
			(xy 150.308359 -368.700023) (xy 150.357941 -368.677385) (xy 150.41024 -368.662034) (xy 150.464191 -368.654282)
			(xy 150.491444 -368.653822) (xy 150.520146 -368.654838) (xy 150.533354 -368.655854) (xy 150.556976 -368.644932)
			(xy 150.623778 -368.554254) (xy 150.62708 -368.528346) (xy 150.622 -368.5159) (xy 150.613467 -368.493388)
			(xy 150.601462 -368.446766) (xy 150.595428 -368.399002) (xy 150.595076 -368.37493) (xy 150.595562 -368.347679)
			(xy 150.603318 -368.293731) (xy 150.618673 -368.241436) (xy 150.641315 -368.191859) (xy 150.670781 -368.146009)
			(xy 150.706472 -368.104818) (xy 150.747663 -368.069127) (xy 150.793513 -368.039661) (xy 150.84309 -368.017019)
			(xy 150.895385 -368.001664) (xy 150.949333 -367.993908) (xy 151.003835 -367.993908) (xy 151.057783 -368.001664)
			(xy 151.110078 -368.017019) (xy 151.159655 -368.039661) (xy 151.205505 -368.069127) (xy 151.246696 -368.104818)
			(xy 151.282387 -368.146009) (xy 151.311853 -368.191859) (xy 151.334495 -368.241436) (xy 151.34985 -368.293731)
			(xy 151.357606 -368.347679) (xy 151.358092 -368.37493) (xy 151.357526 -368.404367) (xy 151.348472 -368.46254)
			(xy 151.340058 -368.490754) (xy 151.337696 -368.499363) (xy 151.33847 -368.517186) (xy 151.341582 -368.525552)
			(xy 151.35352 -368.553746) (xy 151.35732 -368.561992) (xy 151.369703 -368.575259) (xy 151.37765 -368.579654)
			(xy 151.403345 -368.592819) (xy 151.45185 -368.624138) (xy 151.474424 -368.642138) (xy 151.481414 -368.647423)
			(xy 151.497924 -368.65326) (xy 151.506682 -368.653568) (xy 151.660606 -368.653568) (xy 151.669354 -368.653213)
			(xy 151.685845 -368.647371) (xy 151.692864 -368.642138) (xy 151.715451 -368.624157) (xy 151.763953 -368.592837)
			(xy 151.789638 -368.579654) (xy 151.79758 -368.575257) (xy 151.809943 -368.561979) (xy 151.813768 -368.553746)
			(xy 151.825706 -368.525552) (xy 151.828725 -368.517163) (xy 151.829518 -368.499369) (xy 151.82723 -368.490754)
			(xy 151.818802 -368.462543) (xy 151.809742 -368.404368) (xy 151.809196 -368.37493) (xy 151.809682 -368.347679)
			(xy 151.817438 -368.293731) (xy 151.832793 -368.241436) (xy 151.855435 -368.191859) (xy 151.884901 -368.146009)
			(xy 151.920592 -368.104818) (xy 151.961783 -368.069127) (xy 152.007633 -368.039661) (xy 152.05721 -368.017019)
			(xy 152.109505 -368.001664) (xy 152.163453 -367.993908) (xy 152.217955 -367.993908) (xy 152.271903 -368.001664)
			(xy 152.324198 -368.017019) (xy 152.373775 -368.039661) (xy 152.419625 -368.069127) (xy 152.460816 -368.104818)
			(xy 152.496507 -368.146009) (xy 152.525973 -368.191859) (xy 152.548615 -368.241436) (xy 152.56397 -368.293731)
			(xy 152.571726 -368.347679) (xy 152.572212 -368.37493) (xy 152.571854 -368.399002) (xy 152.565815 -368.446764)
			(xy 152.553825 -368.49339) (xy 152.545288 -368.5159) (xy 152.540208 -368.528346) (xy 152.54351 -368.554254)
			(xy 152.610312 -368.644932) (xy 152.633934 -368.655854) (xy 152.647142 -368.654838) (xy 152.675844 -368.653822)
			(xy 152.703095 -368.654251) (xy 152.757043 -368.662013) (xy 152.809336 -368.677373) (xy 152.858912 -368.700019)
			(xy 152.90476 -368.729488) (xy 152.945948 -368.765183) (xy 152.981638 -368.806375) (xy 153.011102 -368.852227)
			(xy 153.033742 -368.901805) (xy 153.049096 -368.954101) (xy 153.056852 -369.008049) (xy 153.056852 -369.062551)
			(xy 153.056852 -369.062553) (xy 156.917585 -369.062553) (xy 156.917585 -369.008047) (xy 156.925343 -368.954097)
			(xy 156.9407 -368.901799) (xy 156.963344 -368.85222) (xy 156.992814 -368.806369) (xy 157.028509 -368.765178)
			(xy 157.069704 -368.729487) (xy 157.115559 -368.700023) (xy 157.165141 -368.677385) (xy 157.21744 -368.662034)
			(xy 157.271391 -368.654282) (xy 157.298644 -368.653822) (xy 157.327346 -368.654838) (xy 157.340554 -368.655854)
			(xy 157.364176 -368.644932) (xy 157.430978 -368.554254) (xy 157.43428 -368.528346) (xy 157.4292 -368.5159)
			(xy 157.420667 -368.493388) (xy 157.408662 -368.446766) (xy 157.402628 -368.399002) (xy 157.402276 -368.37493)
			(xy 157.402762 -368.347679) (xy 157.410518 -368.293731) (xy 157.425873 -368.241436) (xy 157.448515 -368.191859)
			(xy 157.477981 -368.146009) (xy 157.513672 -368.104818) (xy 157.554863 -368.069127) (xy 157.600713 -368.039661)
			(xy 157.65029 -368.017019) (xy 157.702585 -368.001664) (xy 157.756533 -367.993908) (xy 157.811035 -367.993908)
			(xy 157.864983 -368.001664) (xy 157.917278 -368.017019) (xy 157.966855 -368.039661) (xy 158.012705 -368.069127)
			(xy 158.053896 -368.104818) (xy 158.089587 -368.146009) (xy 158.119053 -368.191859) (xy 158.141695 -368.241436)
			(xy 158.15705 -368.293731) (xy 158.164806 -368.347679) (xy 158.165292 -368.37493) (xy 158.164726 -368.404367)
			(xy 158.155672 -368.46254) (xy 158.147258 -368.490754) (xy 158.144896 -368.499363) (xy 158.14567 -368.517186)
			(xy 158.148782 -368.525552) (xy 158.16072 -368.553746) (xy 158.16452 -368.561992) (xy 158.176903 -368.575259)
			(xy 158.18485 -368.579654) (xy 158.210545 -368.592819) (xy 158.25905 -368.624138) (xy 158.281624 -368.642138)
			(xy 158.288614 -368.647423) (xy 158.305124 -368.65326) (xy 158.313882 -368.653568) (xy 158.467806 -368.653568)
			(xy 158.476554 -368.653213) (xy 158.493045 -368.647371) (xy 158.500064 -368.642138) (xy 158.522651 -368.624157)
			(xy 158.571153 -368.592837) (xy 158.596838 -368.579654) (xy 158.60478 -368.575257) (xy 158.617143 -368.561979)
			(xy 158.620968 -368.553746) (xy 158.632906 -368.525552) (xy 158.635925 -368.517163) (xy 158.636718 -368.499369)
			(xy 158.63443 -368.490754) (xy 158.626002 -368.462543) (xy 158.616942 -368.404368) (xy 158.616396 -368.37493)
			(xy 158.616882 -368.347679) (xy 158.624638 -368.293731) (xy 158.639993 -368.241436) (xy 158.662635 -368.191859)
			(xy 158.692101 -368.146009) (xy 158.727792 -368.104818) (xy 158.768983 -368.069127) (xy 158.814833 -368.039661)
			(xy 158.86441 -368.017019) (xy 158.916705 -368.001664) (xy 158.970653 -367.993908) (xy 159.025155 -367.993908)
			(xy 159.079103 -368.001664) (xy 159.131398 -368.017019) (xy 159.180975 -368.039661) (xy 159.226825 -368.069127)
			(xy 159.268016 -368.104818) (xy 159.303707 -368.146009) (xy 159.333173 -368.191859) (xy 159.355815 -368.241436)
			(xy 159.37117 -368.293731) (xy 159.378926 -368.347679) (xy 159.379412 -368.37493) (xy 159.379054 -368.399002)
			(xy 159.373015 -368.446764) (xy 159.361025 -368.49339) (xy 159.352488 -368.5159) (xy 159.347408 -368.528346)
			(xy 159.35071 -368.554254) (xy 159.417512 -368.644932) (xy 159.441134 -368.655854) (xy 159.454342 -368.654838)
			(xy 159.483044 -368.653822) (xy 159.510295 -368.654251) (xy 159.564243 -368.662013) (xy 159.616536 -368.677373)
			(xy 159.666112 -368.700019) (xy 159.71196 -368.729488) (xy 159.753148 -368.765183) (xy 159.788838 -368.806375)
			(xy 159.818302 -368.852227) (xy 159.840942 -368.901805) (xy 159.856296 -368.954101) (xy 159.864052 -369.008049)
			(xy 159.864052 -369.062551) (xy 159.864052 -369.062553) (xy 163.724785 -369.062553) (xy 163.724785 -369.008047)
			(xy 163.732543 -368.954097) (xy 163.7479 -368.901799) (xy 163.770544 -368.85222) (xy 163.800014 -368.806369)
			(xy 163.835709 -368.765178) (xy 163.876904 -368.729487) (xy 163.922759 -368.700023) (xy 163.972341 -368.677385)
			(xy 164.02464 -368.662034) (xy 164.078591 -368.654282) (xy 164.105844 -368.653822) (xy 164.134546 -368.654838)
			(xy 164.147754 -368.655854) (xy 164.171376 -368.644932) (xy 164.238178 -368.554254) (xy 164.24148 -368.528346)
			(xy 164.2364 -368.5159) (xy 164.227867 -368.493388) (xy 164.215862 -368.446766) (xy 164.209828 -368.399002)
			(xy 164.209476 -368.37493) (xy 164.209962 -368.347679) (xy 164.217718 -368.293731) (xy 164.233073 -368.241436)
			(xy 164.255715 -368.191859) (xy 164.285181 -368.146009) (xy 164.320872 -368.104818) (xy 164.362063 -368.069127)
			(xy 164.407913 -368.039661) (xy 164.45749 -368.017019) (xy 164.509785 -368.001664) (xy 164.563733 -367.993908)
			(xy 164.618235 -367.993908) (xy 164.672183 -368.001664) (xy 164.724478 -368.017019) (xy 164.774055 -368.039661)
			(xy 164.819905 -368.069127) (xy 164.861096 -368.104818) (xy 164.896787 -368.146009) (xy 164.926253 -368.191859)
			(xy 164.948895 -368.241436) (xy 164.96425 -368.293731) (xy 164.972006 -368.347679) (xy 164.972492 -368.37493)
			(xy 164.971926 -368.404367) (xy 164.962872 -368.46254) (xy 164.954458 -368.490754) (xy 164.952096 -368.499363)
			(xy 164.95287 -368.517186) (xy 164.955982 -368.525552) (xy 164.96792 -368.553746) (xy 164.97172 -368.561992)
			(xy 164.984103 -368.575259) (xy 164.99205 -368.579654) (xy 165.017745 -368.592819) (xy 165.06625 -368.624138)
			(xy 165.088824 -368.642138) (xy 165.095814 -368.647423) (xy 165.112324 -368.65326) (xy 165.121082 -368.653568)
			(xy 165.275006 -368.653568) (xy 165.283754 -368.653213) (xy 165.300245 -368.647371) (xy 165.307264 -368.642138)
			(xy 165.329851 -368.624157) (xy 165.378353 -368.592837) (xy 165.404038 -368.579654) (xy 165.41198 -368.575257)
			(xy 165.424343 -368.561979) (xy 165.428168 -368.553746) (xy 165.440106 -368.525552) (xy 165.443125 -368.517163)
			(xy 165.443918 -368.499369) (xy 165.44163 -368.490754) (xy 165.433202 -368.462543) (xy 165.424142 -368.404368)
			(xy 165.423596 -368.37493) (xy 165.424082 -368.347679) (xy 165.431838 -368.293731) (xy 165.447193 -368.241436)
			(xy 165.469835 -368.191859) (xy 165.499301 -368.146009) (xy 165.534992 -368.104818) (xy 165.576183 -368.069127)
			(xy 165.622033 -368.039661) (xy 165.67161 -368.017019) (xy 165.723905 -368.001664) (xy 165.777853 -367.993908)
			(xy 165.832355 -367.993908) (xy 165.886303 -368.001664) (xy 165.938598 -368.017019) (xy 165.988175 -368.039661)
			(xy 166.034025 -368.069127) (xy 166.075216 -368.104818) (xy 166.110907 -368.146009) (xy 166.140373 -368.191859)
			(xy 166.163015 -368.241436) (xy 166.17837 -368.293731) (xy 166.186126 -368.347679) (xy 166.186612 -368.37493)
			(xy 166.186254 -368.399002) (xy 166.180215 -368.446764) (xy 166.168225 -368.49339) (xy 166.159688 -368.5159)
			(xy 166.154608 -368.528346) (xy 166.15791 -368.554254) (xy 166.224712 -368.644932) (xy 166.248334 -368.655854)
			(xy 166.261542 -368.654838) (xy 166.290244 -368.653822) (xy 166.317495 -368.654251) (xy 166.371443 -368.662013)
			(xy 166.423736 -368.677373) (xy 166.473312 -368.700019) (xy 166.51916 -368.729488) (xy 166.560348 -368.765183)
			(xy 166.596038 -368.806375) (xy 166.625502 -368.852227) (xy 166.648142 -368.901805) (xy 166.663496 -368.954101)
			(xy 166.671252 -369.008049) (xy 166.671252 -369.062551) (xy 166.671252 -369.062553) (xy 167.128385 -369.062553)
			(xy 167.128385 -369.008047) (xy 167.136143 -368.954097) (xy 167.1515 -368.901799) (xy 167.174144 -368.85222)
			(xy 167.203614 -368.806369) (xy 167.239309 -368.765178) (xy 167.280504 -368.729487) (xy 167.326359 -368.700023)
			(xy 167.375941 -368.677385) (xy 167.42824 -368.662034) (xy 167.482191 -368.654282) (xy 167.509444 -368.653822)
			(xy 167.538146 -368.654838) (xy 167.551354 -368.655854) (xy 167.574976 -368.644932) (xy 167.641778 -368.554254)
			(xy 167.64508 -368.528346) (xy 167.64 -368.5159) (xy 167.631467 -368.493388) (xy 167.619462 -368.446766)
			(xy 167.613428 -368.399002) (xy 167.613076 -368.37493) (xy 167.613562 -368.347679) (xy 167.621318 -368.293731)
			(xy 167.636673 -368.241436) (xy 167.659315 -368.191859) (xy 167.688781 -368.146009) (xy 167.724472 -368.104818)
			(xy 167.765663 -368.069127) (xy 167.811513 -368.039661) (xy 167.86109 -368.017019) (xy 167.913385 -368.001664)
			(xy 167.967333 -367.993908) (xy 168.021835 -367.993908) (xy 168.075783 -368.001664) (xy 168.128078 -368.017019)
			(xy 168.177655 -368.039661) (xy 168.223505 -368.069127) (xy 168.264696 -368.104818) (xy 168.300387 -368.146009)
			(xy 168.329853 -368.191859) (xy 168.352495 -368.241436) (xy 168.36785 -368.293731) (xy 168.375606 -368.347679)
			(xy 168.376092 -368.37493) (xy 168.375526 -368.404367) (xy 168.366472 -368.46254) (xy 168.358058 -368.490754)
			(xy 168.355696 -368.499363) (xy 168.35647 -368.517186) (xy 168.359582 -368.525552) (xy 168.37152 -368.553746)
			(xy 168.37532 -368.561992) (xy 168.387703 -368.575259) (xy 168.39565 -368.579654) (xy 168.421345 -368.592819)
			(xy 168.46985 -368.624138) (xy 168.492424 -368.642138) (xy 168.499414 -368.647423) (xy 168.515924 -368.65326)
			(xy 168.524682 -368.653568) (xy 168.678606 -368.653568) (xy 168.687354 -368.653213) (xy 168.703845 -368.647371)
			(xy 168.710864 -368.642138) (xy 168.733451 -368.624157) (xy 168.781953 -368.592837) (xy 168.807638 -368.579654)
			(xy 168.81558 -368.575257) (xy 168.827943 -368.561979) (xy 168.831768 -368.553746) (xy 168.843706 -368.525552)
			(xy 168.846725 -368.517163) (xy 168.847518 -368.499369) (xy 168.84523 -368.490754) (xy 168.836802 -368.462543)
			(xy 168.827742 -368.404368) (xy 168.827196 -368.37493) (xy 168.827682 -368.347679) (xy 168.835438 -368.293731)
			(xy 168.850793 -368.241436) (xy 168.873435 -368.191859) (xy 168.902901 -368.146009) (xy 168.938592 -368.104818)
			(xy 168.979783 -368.069127) (xy 169.025633 -368.039661) (xy 169.07521 -368.017019) (xy 169.127505 -368.001664)
			(xy 169.181453 -367.993908) (xy 169.235955 -367.993908) (xy 169.289903 -368.001664) (xy 169.342198 -368.017019)
			(xy 169.391775 -368.039661) (xy 169.437625 -368.069127) (xy 169.478816 -368.104818) (xy 169.514507 -368.146009)
			(xy 169.543973 -368.191859) (xy 169.566615 -368.241436) (xy 169.58197 -368.293731) (xy 169.589726 -368.347679)
			(xy 169.590212 -368.37493) (xy 169.589854 -368.399002) (xy 169.583815 -368.446764) (xy 169.571825 -368.49339)
			(xy 169.563288 -368.5159) (xy 169.558208 -368.528346) (xy 169.56151 -368.554254) (xy 169.628312 -368.644932)
			(xy 169.651934 -368.655854) (xy 169.665142 -368.654838) (xy 169.693844 -368.653822) (xy 169.721095 -368.654251)
			(xy 169.775043 -368.662013) (xy 169.827336 -368.677373) (xy 169.876912 -368.700019) (xy 169.92276 -368.729488)
			(xy 169.963948 -368.765183) (xy 169.999638 -368.806375) (xy 170.029102 -368.852227) (xy 170.039063 -368.87404)
			(xy 173.298612 -368.87404) (xy 173.29915 -368.840441) (xy 173.307979 -368.773827) (xy 173.325502 -368.708955)
			(xy 173.351414 -368.646955) (xy 173.385264 -368.588907) (xy 173.426461 -368.535821) (xy 173.449996 -368.511836)
			(xy 173.457108 -368.504978) (xy 173.464982 -368.48669) (xy 173.467014 -368.396012) (xy 173.459902 -368.37747)
			(xy 173.453044 -368.370358) (xy 173.431697 -368.346746) (xy 173.394436 -368.295136) (xy 173.363905 -368.239281)
			(xy 173.340579 -368.180054) (xy 173.324824 -368.118379) (xy 173.316884 -368.055221) (xy 173.316392 -368.023394)
			(xy 173.316894 -367.991433) (xy 173.324905 -367.928015) (xy 173.340802 -367.866101) (xy 173.364334 -367.806668)
			(xy 173.395128 -367.750653) (xy 173.432701 -367.698938) (xy 173.476458 -367.652341) (xy 173.525711 -367.611596)
			(xy 173.579682 -367.577345) (xy 173.637521 -367.550128) (xy 173.698314 -367.530375) (xy 173.761104 -367.518397)
			(xy 173.8249 -367.514384) (xy 173.888696 -367.518397) (xy 173.951486 -367.530375) (xy 174.012279 -367.550128)
			(xy 174.070118 -367.577345) (xy 174.124089 -367.611596) (xy 174.173342 -367.652341) (xy 174.211188 -367.692643)
			(xy 180.91378 -367.692643) (xy 180.91378 -367.628721) (xy 180.921791 -367.565303) (xy 180.937688 -367.503389)
			(xy 180.96122 -367.443956) (xy 180.992014 -367.387941) (xy 181.029587 -367.336226) (xy 181.073344 -367.289629)
			(xy 181.122597 -367.248884) (xy 181.176568 -367.214633) (xy 181.234407 -367.187416) (xy 181.2952 -367.167663)
			(xy 181.35799 -367.155685) (xy 181.421786 -367.151672) (xy 181.485582 -367.155685) (xy 181.548372 -367.167663)
			(xy 181.609165 -367.187416) (xy 181.667004 -367.214633) (xy 181.720975 -367.248884) (xy 181.770228 -367.289629)
			(xy 181.813985 -367.336226) (xy 181.851558 -367.387941) (xy 181.882352 -367.443956) (xy 181.905884 -367.503389)
			(xy 181.921781 -367.565303) (xy 181.929792 -367.628721) (xy 181.930294 -367.660682) (xy 181.929792 -367.692643)
			(xy 181.921781 -367.756061) (xy 181.905884 -367.817975) (xy 181.882352 -367.877408) (xy 181.851558 -367.933423)
			(xy 181.813985 -367.985138) (xy 181.770228 -368.031735) (xy 181.720975 -368.07248) (xy 181.667004 -368.106731)
			(xy 181.609165 -368.133948) (xy 181.548372 -368.153701) (xy 181.485582 -368.165679) (xy 181.421786 -368.169693)
			(xy 181.35799 -368.165679) (xy 181.2952 -368.153701) (xy 181.234407 -368.133948) (xy 181.176568 -368.106731)
			(xy 181.122597 -368.07248) (xy 181.073344 -368.031735) (xy 181.029587 -367.985138) (xy 180.992014 -367.933423)
			(xy 180.96122 -367.877408) (xy 180.937688 -367.817975) (xy 180.921791 -367.756061) (xy 180.91378 -367.692643)
			(xy 174.211188 -367.692643) (xy 174.217099 -367.698938) (xy 174.254672 -367.750653) (xy 174.285466 -367.806668)
			(xy 174.308998 -367.866101) (xy 174.324895 -367.928015) (xy 174.332906 -367.991433) (xy 174.333408 -368.023394)
			(xy 174.333007 -368.052049) (xy 174.326561 -368.108995) (xy 174.313752 -368.164855) (xy 174.29474 -368.218919)
			(xy 174.282608 -368.244882) (xy 174.276258 -368.25809) (xy 174.279306 -368.286792) (xy 174.354744 -368.381788)
			(xy 174.381922 -368.39144) (xy 174.3964 -368.388138) (xy 174.423971 -368.382308) (xy 174.479982 -368.376071)
			(xy 174.50816 -368.375692) (xy 174.538891 -368.376175) (xy 174.599906 -368.383579) (xy 174.659584 -368.398284)
			(xy 174.717053 -368.420076) (xy 174.771477 -368.448636) (xy 174.822062 -368.483548) (xy 174.868069 -368.524303)
			(xy 174.908827 -368.570307) (xy 174.943744 -368.620889) (xy 174.972308 -368.67531) (xy 174.994104 -368.732778)
			(xy 175.008814 -368.792454) (xy 175.016222 -368.853469) (xy 175.016668 -368.8842) (xy 175.016229 -368.913136)
			(xy 175.009636 -368.970633) (xy 174.996571 -369.027012) (xy 174.9772 -369.081547) (xy 174.964852 -369.10772)
			(xy 174.96028 -369.117372) (xy 174.959264 -369.138708) (xy 174.995586 -369.228878) (xy 175.010826 -369.243864)
			(xy 175.020986 -369.247674) (xy 175.040991 -369.255297) (xy 175.079306 -369.274395) (xy 175.09744 -369.285774)
			(xy 175.105298 -369.290461) (xy 175.123129 -369.2945) (xy 175.132238 -369.293648) (xy 175.162718 -369.28933)
			(xy 175.171896 -369.287582) (xy 175.188182 -369.278462) (xy 175.194468 -369.27155) (xy 175.215234 -369.247578)
			(xy 175.261739 -369.204451) (xy 175.313245 -369.167439) (xy 175.368951 -369.137116) (xy 175.427994 -369.113953)
			(xy 175.489459 -369.098308) (xy 175.552392 -369.090425) (xy 175.584104 -369.08994) (xy 175.619059 -369.090533)
			(xy 175.688311 -369.100094) (xy 175.755601 -369.119049) (xy 175.819662 -369.147041) (xy 175.879285 -369.183543)
			(xy 175.906684 -369.205256) (xy 175.913684 -369.210551) (xy 175.930175 -369.216526) (xy 175.938942 -369.21694)
			(xy 176.092866 -369.21694) (xy 176.101641 -369.216555) (xy 176.118143 -369.210585) (xy 176.125124 -369.205256)
			(xy 176.15251 -369.183526) (xy 176.21214 -369.147032) (xy 176.276204 -369.119043) (xy 176.343495 -369.100087)
			(xy 176.412749 -369.090519) (xy 176.447704 -369.08994) (xy 176.480996 -369.090485) (xy 176.547011 -369.099162)
			(xy 176.611329 -369.11638) (xy 176.67285 -369.141845) (xy 176.701958 -369.158012) (xy 176.710436 -369.162483)
			(xy 176.729367 -369.165361) (xy 176.738788 -369.1636) (xy 176.769268 -369.156488) (xy 176.778366 -369.153975)
			(xy 176.793889 -369.143256) (xy 176.799494 -369.13566) (xy 176.814825 -369.114121) (xy 176.85049 -369.075095)
			(xy 176.891198 -369.041362) (xy 176.93617 -369.013567) (xy 176.984547 -368.992242) (xy 177.035403 -368.977794)
			(xy 177.087766 -368.970501) (xy 177.1142 -368.970052) (xy 177.141448 -368.970618) (xy 177.19539 -368.978374)
			(xy 177.24768 -368.993727) (xy 177.297252 -369.016366) (xy 177.343097 -369.045829) (xy 177.384283 -369.081517)
			(xy 177.419971 -369.122703) (xy 177.449434 -369.168548) (xy 177.472073 -369.21812) (xy 177.487426 -369.27041)
			(xy 177.495182 -369.324352) (xy 177.495182 -369.378848) (xy 177.487426 -369.43279) (xy 177.472073 -369.48508)
			(xy 177.449434 -369.534652) (xy 177.419971 -369.580497) (xy 177.384283 -369.621683) (xy 177.343097 -369.657371)
			(xy 177.297252 -369.686834) (xy 177.24768 -369.709473) (xy 177.19539 -369.724826) (xy 177.141448 -369.732582)
			(xy 177.1142 -369.733068) (xy 177.089406 -369.732685) (xy 177.040228 -369.72632) (xy 177.016156 -369.720368)
			(xy 177.006938 -369.718331) (xy 176.988177 -369.720279) (xy 176.97958 -369.724178) (xy 176.951894 -369.738656)
			(xy 176.94359 -369.743452) (xy 176.93105 -369.757938) (xy 176.92751 -369.76685) (xy 176.916657 -369.796283)
			(xy 176.888763 -369.852472) (xy 176.854169 -369.904803) (xy 176.813399 -369.952481) (xy 176.767074 -369.994781)
			(xy 176.715897 -370.031061) (xy 176.660645 -370.060769) (xy 176.602159 -370.083455) (xy 176.541326 -370.098773)
			(xy 176.47907 -370.106491) (xy 176.447704 -370.106956) (xy 176.412749 -370.10636) (xy 176.343497 -370.0968)
			(xy 176.276207 -370.077845) (xy 176.212146 -370.049854) (xy 176.152523 -370.013353) (xy 176.125124 -369.99164)
			(xy 176.118122 -369.986348) (xy 176.101633 -369.980371) (xy 176.092866 -369.979956) (xy 175.938942 -369.979956)
			(xy 175.930168 -369.980346) (xy 175.913666 -369.986313) (xy 175.906684 -369.99164) (xy 175.879295 -370.013366)
			(xy 175.819666 -370.049861) (xy 175.755603 -370.07785) (xy 175.688312 -370.096808) (xy 175.619059 -370.106377)
			(xy 175.584104 -370.106956) (xy 175.553139 -370.106522) (xy 175.491667 -370.099001) (xy 175.431563 -370.084069)
			(xy 175.373718 -370.061948) (xy 175.318988 -370.032966) (xy 175.268183 -369.997551) (xy 175.222056 -369.956227)
			(xy 175.201326 -369.93322) (xy 175.1949 -369.926497) (xy 175.178488 -369.917776) (xy 175.169322 -369.916202)
			(xy 175.138588 -369.912392) (xy 175.129414 -369.911665) (xy 175.11157 -369.91611) (xy 175.10379 -369.921028)
			(xy 175.079908 -369.936598) (xy 175.028522 -369.961282) (xy 174.974036 -369.978052) (xy 174.917664 -369.986535)
			(xy 174.88916 -369.987068) (xy 174.861906 -369.986659) (xy 174.807953 -369.978896) (xy 174.755655 -369.963534)
			(xy 174.706075 -369.940885) (xy 174.660223 -369.911411) (xy 174.619032 -369.875712) (xy 174.583341 -369.834513)
			(xy 174.553876 -369.788655) (xy 174.531238 -369.73907) (xy 174.515887 -369.686768) (xy 174.508135 -369.632814)
			(xy 174.507652 -369.60556) (xy 174.507983 -369.582076) (xy 174.513712 -369.53546) (xy 174.519082 -369.512596)
			(xy 174.521876 -369.502182) (xy 174.518066 -369.4811) (xy 174.463964 -369.400328) (xy 174.44593 -369.388898)
			(xy 174.435262 -369.387374) (xy 174.400871 -369.381815) (xy 174.333927 -369.362535) (xy 174.270241 -369.334297)
			(xy 174.211005 -369.297631) (xy 174.183802 -369.275868) (xy 174.174565 -369.268898) (xy 174.152118 -369.263367)
			(xy 174.129507 -369.268185) (xy 174.120048 -369.274852) (xy 174.093121 -369.295158) (xy 174.034946 -369.329275)
			(xy 173.972772 -369.355402) (xy 173.907689 -369.373079) (xy 173.84084 -369.381998) (xy 173.80712 -369.382548)
			(xy 173.776391 -369.382025) (xy 173.715381 -369.37462) (xy 173.655708 -369.359915) (xy 173.598243 -369.338124)
			(xy 173.543823 -369.309566) (xy 173.493242 -369.274657) (xy 173.447237 -369.233905) (xy 173.40648 -369.187905)
			(xy 173.371565 -369.137329) (xy 173.343001 -369.082912) (xy 173.321203 -369.025449) (xy 173.306491 -368.965778)
			(xy 173.299078 -368.904769) (xy 173.298612 -368.87404) (xy 170.039063 -368.87404) (xy 170.051742 -368.901805)
			(xy 170.067096 -368.954101) (xy 170.074852 -369.008049) (xy 170.074852 -369.062551) (xy 170.067096 -369.116499)
			(xy 170.051742 -369.168795) (xy 170.029102 -369.218373) (xy 169.999638 -369.264225) (xy 169.963948 -369.305417)
			(xy 169.92276 -369.341112) (xy 169.876912 -369.370581) (xy 169.827336 -369.393227) (xy 169.775043 -369.408587)
			(xy 169.721095 -369.416349) (xy 169.693844 -369.416838) (xy 169.665142 -369.415822) (xy 169.651934 -369.414806)
			(xy 169.628312 -369.425728) (xy 169.56151 -369.516406) (xy 169.558208 -369.542314) (xy 169.563288 -369.55476)
			(xy 169.571838 -369.577266) (xy 169.583837 -369.623891) (xy 169.589864 -369.671657) (xy 169.590212 -369.69573)
			(xy 169.589726 -369.722981) (xy 169.58197 -369.776929) (xy 169.566615 -369.829224) (xy 169.543973 -369.878801)
			(xy 169.514507 -369.924651) (xy 169.478816 -369.965842) (xy 169.437625 -370.001533) (xy 169.391775 -370.030999)
			(xy 169.342198 -370.053641) (xy 169.289903 -370.068996) (xy 169.235955 -370.076752) (xy 169.181453 -370.076752)
			(xy 169.127505 -370.068996) (xy 169.07521 -370.053641) (xy 169.025633 -370.030999) (xy 168.979783 -370.001533)
			(xy 168.938592 -369.965842) (xy 168.902901 -369.924651) (xy 168.873435 -369.878801) (xy 168.850793 -369.829224)
			(xy 168.835438 -369.776929) (xy 168.827682 -369.722981) (xy 168.827196 -369.69573) (xy 168.827753 -369.666293)
			(xy 168.836813 -369.60812) (xy 168.84523 -369.579906) (xy 168.847613 -369.571301) (xy 168.846826 -369.553474)
			(xy 168.843706 -369.545108) (xy 168.831768 -369.516914) (xy 168.827919 -369.508695) (xy 168.81557 -369.495414)
			(xy 168.807638 -369.491006) (xy 168.78194 -369.477846) (xy 168.733437 -369.446523) (xy 168.710864 -369.428522)
			(xy 168.703853 -369.423269) (xy 168.687359 -369.417414) (xy 168.678606 -369.417092) (xy 168.524682 -369.417092)
			(xy 168.515935 -369.41745) (xy 168.499444 -369.423291) (xy 168.492424 -369.428522) (xy 168.469841 -369.446509)
			(xy 168.421336 -369.477825) (xy 168.39565 -369.491006) (xy 168.387692 -369.495379) (xy 168.375337 -369.508673)
			(xy 168.37152 -369.516914) (xy 168.359582 -369.545108) (xy 168.356534 -369.553488) (xy 168.35576 -369.57129)
			(xy 168.358058 -369.579906) (xy 168.366499 -369.608114) (xy 168.375551 -369.666291) (xy 168.376092 -369.69573)
			(xy 168.375606 -369.722981) (xy 168.36785 -369.776929) (xy 168.352495 -369.829224) (xy 168.329853 -369.878801)
			(xy 168.300387 -369.924651) (xy 168.264696 -369.965842) (xy 168.223505 -370.001533) (xy 168.177655 -370.030999)
			(xy 168.128078 -370.053641) (xy 168.075783 -370.068996) (xy 168.021835 -370.076752) (xy 167.967333 -370.076752)
			(xy 167.913385 -370.068996) (xy 167.86109 -370.053641) (xy 167.811513 -370.030999) (xy 167.765663 -370.001533)
			(xy 167.724472 -369.965842) (xy 167.688781 -369.924651) (xy 167.659315 -369.878801) (xy 167.636673 -369.829224)
			(xy 167.621318 -369.776929) (xy 167.613562 -369.722981) (xy 167.613076 -369.69573) (xy 167.613423 -369.671658)
			(xy 167.619466 -369.623895) (xy 167.631461 -369.577269) (xy 167.64 -369.55476) (xy 167.64508 -369.542314)
			(xy 167.641778 -369.516406) (xy 167.574976 -369.425728) (xy 167.551354 -369.414806) (xy 167.538146 -369.415822)
			(xy 167.509444 -369.416838) (xy 167.482191 -369.416318) (xy 167.42824 -369.408566) (xy 167.375941 -369.393215)
			(xy 167.326359 -369.370577) (xy 167.280504 -369.341113) (xy 167.239309 -369.305422) (xy 167.203614 -369.264231)
			(xy 167.174144 -369.21838) (xy 167.1515 -369.168801) (xy 167.136143 -369.116503) (xy 167.128385 -369.062553)
			(xy 166.671252 -369.062553) (xy 166.663496 -369.116499) (xy 166.648142 -369.168795) (xy 166.625502 -369.218373)
			(xy 166.596038 -369.264225) (xy 166.560348 -369.305417) (xy 166.51916 -369.341112) (xy 166.473312 -369.370581)
			(xy 166.423736 -369.393227) (xy 166.371443 -369.408587) (xy 166.317495 -369.416349) (xy 166.290244 -369.416838)
			(xy 166.261542 -369.415822) (xy 166.248334 -369.414806) (xy 166.224712 -369.425728) (xy 166.15791 -369.516406)
			(xy 166.154608 -369.542314) (xy 166.159688 -369.55476) (xy 166.168238 -369.577266) (xy 166.180237 -369.623891)
			(xy 166.186264 -369.671657) (xy 166.186612 -369.69573) (xy 166.186126 -369.722981) (xy 166.17837 -369.776929)
			(xy 166.163015 -369.829224) (xy 166.140373 -369.878801) (xy 166.110907 -369.924651) (xy 166.075216 -369.965842)
			(xy 166.034025 -370.001533) (xy 165.988175 -370.030999) (xy 165.938598 -370.053641) (xy 165.886303 -370.068996)
			(xy 165.832355 -370.076752) (xy 165.777853 -370.076752) (xy 165.723905 -370.068996) (xy 165.67161 -370.053641)
			(xy 165.622033 -370.030999) (xy 165.576183 -370.001533) (xy 165.534992 -369.965842) (xy 165.499301 -369.924651)
			(xy 165.469835 -369.878801) (xy 165.447193 -369.829224) (xy 165.431838 -369.776929) (xy 165.424082 -369.722981)
			(xy 165.423596 -369.69573) (xy 165.424153 -369.666293) (xy 165.433213 -369.60812) (xy 165.44163 -369.579906)
			(xy 165.444013 -369.571301) (xy 165.443226 -369.553474) (xy 165.440106 -369.545108) (xy 165.428168 -369.516914)
			(xy 165.424319 -369.508695) (xy 165.41197 -369.495414) (xy 165.404038 -369.491006) (xy 165.37834 -369.477846)
			(xy 165.329837 -369.446523) (xy 165.307264 -369.428522) (xy 165.300253 -369.423269) (xy 165.283759 -369.417414)
			(xy 165.275006 -369.417092) (xy 165.121082 -369.417092) (xy 165.112335 -369.41745) (xy 165.095844 -369.423291)
			(xy 165.088824 -369.428522) (xy 165.066241 -369.446509) (xy 165.017736 -369.477825) (xy 164.99205 -369.491006)
			(xy 164.984092 -369.495379) (xy 164.971737 -369.508673) (xy 164.96792 -369.516914) (xy 164.955982 -369.545108)
			(xy 164.952934 -369.553488) (xy 164.95216 -369.57129) (xy 164.954458 -369.579906) (xy 164.962899 -369.608114)
			(xy 164.971951 -369.666291) (xy 164.972492 -369.69573) (xy 164.972006 -369.722981) (xy 164.96425 -369.776929)
			(xy 164.948895 -369.829224) (xy 164.926253 -369.878801) (xy 164.896787 -369.924651) (xy 164.861096 -369.965842)
			(xy 164.819905 -370.001533) (xy 164.774055 -370.030999) (xy 164.724478 -370.053641) (xy 164.672183 -370.068996)
			(xy 164.618235 -370.076752) (xy 164.563733 -370.076752) (xy 164.509785 -370.068996) (xy 164.45749 -370.053641)
			(xy 164.407913 -370.030999) (xy 164.362063 -370.001533) (xy 164.320872 -369.965842) (xy 164.285181 -369.924651)
			(xy 164.255715 -369.878801) (xy 164.233073 -369.829224) (xy 164.217718 -369.776929) (xy 164.209962 -369.722981)
			(xy 164.209476 -369.69573) (xy 164.209823 -369.671658) (xy 164.215866 -369.623895) (xy 164.227861 -369.577269)
			(xy 164.2364 -369.55476) (xy 164.24148 -369.542314) (xy 164.238178 -369.516406) (xy 164.171376 -369.425728)
			(xy 164.147754 -369.414806) (xy 164.134546 -369.415822) (xy 164.105844 -369.416838) (xy 164.078591 -369.416318)
			(xy 164.02464 -369.408566) (xy 163.972341 -369.393215) (xy 163.922759 -369.370577) (xy 163.876904 -369.341113)
			(xy 163.835709 -369.305422) (xy 163.800014 -369.264231) (xy 163.770544 -369.21838) (xy 163.7479 -369.168801)
			(xy 163.732543 -369.116503) (xy 163.724785 -369.062553) (xy 159.864052 -369.062553) (xy 159.856296 -369.116499)
			(xy 159.840942 -369.168795) (xy 159.818302 -369.218373) (xy 159.788838 -369.264225) (xy 159.753148 -369.305417)
			(xy 159.71196 -369.341112) (xy 159.666112 -369.370581) (xy 159.616536 -369.393227) (xy 159.564243 -369.408587)
			(xy 159.510295 -369.416349) (xy 159.483044 -369.416838) (xy 159.454342 -369.415822) (xy 159.441134 -369.414806)
			(xy 159.417512 -369.425728) (xy 159.35071 -369.516406) (xy 159.347408 -369.542314) (xy 159.352488 -369.55476)
			(xy 159.361038 -369.577266) (xy 159.373037 -369.623891) (xy 159.379064 -369.671657) (xy 159.379412 -369.69573)
			(xy 159.378926 -369.722981) (xy 159.37117 -369.776929) (xy 159.355815 -369.829224) (xy 159.333173 -369.878801)
			(xy 159.303707 -369.924651) (xy 159.268016 -369.965842) (xy 159.226825 -370.001533) (xy 159.180975 -370.030999)
			(xy 159.131398 -370.053641) (xy 159.079103 -370.068996) (xy 159.025155 -370.076752) (xy 158.970653 -370.076752)
			(xy 158.916705 -370.068996) (xy 158.86441 -370.053641) (xy 158.814833 -370.030999) (xy 158.768983 -370.001533)
			(xy 158.727792 -369.965842) (xy 158.692101 -369.924651) (xy 158.662635 -369.878801) (xy 158.639993 -369.829224)
			(xy 158.624638 -369.776929) (xy 158.616882 -369.722981) (xy 158.616396 -369.69573) (xy 158.616953 -369.666293)
			(xy 158.626013 -369.60812) (xy 158.63443 -369.579906) (xy 158.636813 -369.571301) (xy 158.636026 -369.553474)
			(xy 158.632906 -369.545108) (xy 158.620968 -369.516914) (xy 158.617119 -369.508695) (xy 158.60477 -369.495414)
			(xy 158.596838 -369.491006) (xy 158.57114 -369.477846) (xy 158.522637 -369.446523) (xy 158.500064 -369.428522)
			(xy 158.493053 -369.423269) (xy 158.476559 -369.417414) (xy 158.467806 -369.417092) (xy 158.313882 -369.417092)
			(xy 158.305135 -369.41745) (xy 158.288644 -369.423291) (xy 158.281624 -369.428522) (xy 158.259041 -369.446509)
			(xy 158.210536 -369.477825) (xy 158.18485 -369.491006) (xy 158.176892 -369.495379) (xy 158.164537 -369.508673)
			(xy 158.16072 -369.516914) (xy 158.148782 -369.545108) (xy 158.145734 -369.553488) (xy 158.14496 -369.57129)
			(xy 158.147258 -369.579906) (xy 158.155699 -369.608114) (xy 158.164751 -369.666291) (xy 158.165292 -369.69573)
			(xy 158.164806 -369.722981) (xy 158.15705 -369.776929) (xy 158.141695 -369.829224) (xy 158.119053 -369.878801)
			(xy 158.089587 -369.924651) (xy 158.053896 -369.965842) (xy 158.012705 -370.001533) (xy 157.966855 -370.030999)
			(xy 157.917278 -370.053641) (xy 157.864983 -370.068996) (xy 157.811035 -370.076752) (xy 157.756533 -370.076752)
			(xy 157.702585 -370.068996) (xy 157.65029 -370.053641) (xy 157.600713 -370.030999) (xy 157.554863 -370.001533)
			(xy 157.513672 -369.965842) (xy 157.477981 -369.924651) (xy 157.448515 -369.878801) (xy 157.425873 -369.829224)
			(xy 157.410518 -369.776929) (xy 157.402762 -369.722981) (xy 157.402276 -369.69573) (xy 157.402623 -369.671658)
			(xy 157.408666 -369.623895) (xy 157.420661 -369.577269) (xy 157.4292 -369.55476) (xy 157.43428 -369.542314)
			(xy 157.430978 -369.516406) (xy 157.364176 -369.425728) (xy 157.340554 -369.414806) (xy 157.327346 -369.415822)
			(xy 157.298644 -369.416838) (xy 157.271391 -369.416318) (xy 157.21744 -369.408566) (xy 157.165141 -369.393215)
			(xy 157.115559 -369.370577) (xy 157.069704 -369.341113) (xy 157.028509 -369.305422) (xy 156.992814 -369.264231)
			(xy 156.963344 -369.21838) (xy 156.9407 -369.168801) (xy 156.925343 -369.116503) (xy 156.917585 -369.062553)
			(xy 153.056852 -369.062553) (xy 153.049096 -369.116499) (xy 153.033742 -369.168795) (xy 153.011102 -369.218373)
			(xy 152.981638 -369.264225) (xy 152.945948 -369.305417) (xy 152.90476 -369.341112) (xy 152.858912 -369.370581)
			(xy 152.809336 -369.393227) (xy 152.757043 -369.408587) (xy 152.703095 -369.416349) (xy 152.675844 -369.416838)
			(xy 152.647142 -369.415822) (xy 152.633934 -369.414806) (xy 152.610312 -369.425728) (xy 152.54351 -369.516406)
			(xy 152.540208 -369.542314) (xy 152.545288 -369.55476) (xy 152.553838 -369.577266) (xy 152.565837 -369.623891)
			(xy 152.571864 -369.671657) (xy 152.572212 -369.69573) (xy 152.571726 -369.722981) (xy 152.56397 -369.776929)
			(xy 152.548615 -369.829224) (xy 152.525973 -369.878801) (xy 152.496507 -369.924651) (xy 152.460816 -369.965842)
			(xy 152.419625 -370.001533) (xy 152.373775 -370.030999) (xy 152.324198 -370.053641) (xy 152.271903 -370.068996)
			(xy 152.217955 -370.076752) (xy 152.163453 -370.076752) (xy 152.109505 -370.068996) (xy 152.05721 -370.053641)
			(xy 152.007633 -370.030999) (xy 151.961783 -370.001533) (xy 151.920592 -369.965842) (xy 151.884901 -369.924651)
			(xy 151.855435 -369.878801) (xy 151.832793 -369.829224) (xy 151.817438 -369.776929) (xy 151.809682 -369.722981)
			(xy 151.809196 -369.69573) (xy 151.809753 -369.666293) (xy 151.818813 -369.60812) (xy 151.82723 -369.579906)
			(xy 151.829613 -369.571301) (xy 151.828826 -369.553474) (xy 151.825706 -369.545108) (xy 151.813768 -369.516914)
			(xy 151.809919 -369.508695) (xy 151.79757 -369.495414) (xy 151.789638 -369.491006) (xy 151.76394 -369.477846)
			(xy 151.715437 -369.446523) (xy 151.692864 -369.428522) (xy 151.685853 -369.423269) (xy 151.669359 -369.417414)
			(xy 151.660606 -369.417092) (xy 151.506682 -369.417092) (xy 151.497935 -369.41745) (xy 151.481444 -369.423291)
			(xy 151.474424 -369.428522) (xy 151.451841 -369.446509) (xy 151.403336 -369.477825) (xy 151.37765 -369.491006)
			(xy 151.369692 -369.495379) (xy 151.357337 -369.508673) (xy 151.35352 -369.516914) (xy 151.341582 -369.545108)
			(xy 151.338534 -369.553488) (xy 151.33776 -369.57129) (xy 151.340058 -369.579906) (xy 151.348499 -369.608114)
			(xy 151.357551 -369.666291) (xy 151.358092 -369.69573) (xy 151.357606 -369.722981) (xy 151.34985 -369.776929)
			(xy 151.334495 -369.829224) (xy 151.311853 -369.878801) (xy 151.282387 -369.924651) (xy 151.246696 -369.965842)
			(xy 151.205505 -370.001533) (xy 151.159655 -370.030999) (xy 151.110078 -370.053641) (xy 151.057783 -370.068996)
			(xy 151.003835 -370.076752) (xy 150.949333 -370.076752) (xy 150.895385 -370.068996) (xy 150.84309 -370.053641)
			(xy 150.793513 -370.030999) (xy 150.747663 -370.001533) (xy 150.706472 -369.965842) (xy 150.670781 -369.924651)
			(xy 150.641315 -369.878801) (xy 150.618673 -369.829224) (xy 150.603318 -369.776929) (xy 150.595562 -369.722981)
			(xy 150.595076 -369.69573) (xy 150.595423 -369.671658) (xy 150.601466 -369.623895) (xy 150.613461 -369.577269)
			(xy 150.622 -369.55476) (xy 150.62708 -369.542314) (xy 150.623778 -369.516406) (xy 150.556976 -369.425728)
			(xy 150.533354 -369.414806) (xy 150.520146 -369.415822) (xy 150.491444 -369.416838) (xy 150.464191 -369.416318)
			(xy 150.41024 -369.408566) (xy 150.357941 -369.393215) (xy 150.308359 -369.370577) (xy 150.262504 -369.341113)
			(xy 150.221309 -369.305422) (xy 150.185614 -369.264231) (xy 150.156144 -369.21838) (xy 150.1335 -369.168801)
			(xy 150.118143 -369.116503) (xy 150.110385 -369.062553) (xy 146.249591 -369.062553) (xy 146.241837 -369.116487)
			(xy 146.226486 -369.168774) (xy 146.203849 -369.218344) (xy 146.17439 -369.264189) (xy 146.138706 -369.305374)
			(xy 146.097524 -369.341063) (xy 146.051683 -369.370528) (xy 146.002115 -369.39317) (xy 145.94983 -369.408528)
			(xy 145.895891 -369.416289) (xy 145.868644 -369.416838) (xy 145.839942 -369.415822) (xy 145.826734 -369.414806)
			(xy 145.803112 -369.425728) (xy 145.73631 -369.516406) (xy 145.733008 -369.542314) (xy 145.738088 -369.55476)
			(xy 145.746614 -369.577229) (xy 145.758599 -369.62377) (xy 145.764653 -369.671447) (xy 145.765012 -369.695476)
			(xy 145.765012 -369.69573) (xy 145.764526 -369.722981) (xy 145.75677 -369.776929) (xy 145.741415 -369.829224)
			(xy 145.718773 -369.878801) (xy 145.689307 -369.924651) (xy 145.653616 -369.965842) (xy 145.612425 -370.001533)
			(xy 145.566575 -370.030999) (xy 145.516998 -370.053641) (xy 145.464703 -370.068996) (xy 145.410755 -370.076752)
			(xy 145.356253 -370.076752) (xy 145.302305 -370.068996) (xy 145.25001 -370.053641) (xy 145.200433 -370.030999)
			(xy 145.154583 -370.001533) (xy 145.113392 -369.965842) (xy 145.077701 -369.924651) (xy 145.048235 -369.878801)
			(xy 145.025593 -369.829224) (xy 145.010238 -369.776929) (xy 145.002482 -369.722981) (xy 145.001996 -369.69573)
			(xy 145.002537 -369.666291) (xy 145.011589 -369.608114) (xy 145.02003 -369.579906) (xy 145.022329 -369.57129)
			(xy 145.021554 -369.553488) (xy 145.018506 -369.545108) (xy 145.006568 -369.516914) (xy 144.982438 -369.491006)
			(xy 144.956752 -369.477825) (xy 144.908248 -369.446508) (xy 144.885664 -369.428522) (xy 144.85366 -369.417092)
			(xy 144.699482 -369.417092) (xy 144.699228 -369.417092) (xy 144.667224 -369.428522) (xy 144.644651 -369.446523)
			(xy 144.596147 -369.477844) (xy 144.57045 -369.491006) (xy 144.54632 -369.516914) (xy 144.534382 -369.545108)
			(xy 144.531263 -369.553474) (xy 144.530476 -369.571301) (xy 144.532858 -369.579906) (xy 144.541275 -369.60812)
			(xy 144.550335 -369.666293) (xy 144.550892 -369.69573) (xy 144.550406 -369.722981) (xy 144.54265 -369.776929)
			(xy 144.527295 -369.829224) (xy 144.504653 -369.878801) (xy 144.475187 -369.924651) (xy 144.439496 -369.965842)
			(xy 144.398305 -370.001533) (xy 144.352455 -370.030999) (xy 144.302878 -370.053641) (xy 144.250583 -370.068996)
			(xy 144.196635 -370.076752) (xy 144.142133 -370.076752) (xy 144.088185 -370.068996) (xy 144.03589 -370.053641)
			(xy 143.986313 -370.030999) (xy 143.940463 -370.001533) (xy 143.899272 -369.965842) (xy 143.863581 -369.924651)
			(xy 143.834115 -369.878801) (xy 143.811473 -369.829224) (xy 143.796118 -369.776929) (xy 143.788362 -369.722981)
			(xy 143.787876 -369.69573) (xy 143.787876 -369.695476) (xy 143.788237 -369.671446) (xy 143.794275 -369.623766)
			(xy 143.806263 -369.577226) (xy 143.8148 -369.55476) (xy 143.81988 -369.542314) (xy 143.816578 -369.516406)
			(xy 143.749776 -369.425728) (xy 143.726154 -369.414806) (xy 143.712946 -369.415822) (xy 143.684244 -369.416838)
			(xy 143.656577 -369.416341) (xy 143.601823 -369.40834) (xy 143.5488 -369.392513) (xy 143.49862 -369.369192)
			(xy 143.452334 -369.338867) (xy 143.410915 -369.302174) (xy 143.375231 -369.259882) (xy 143.34603 -369.21288)
			(xy 143.334486 -369.18773) (xy 143.329406 -369.176046) (xy 143.309848 -369.160298) (xy 143.214852 -369.142518)
			(xy 143.202486 -369.140768) (xy 143.178644 -369.148104) (xy 143.169386 -369.156488) (xy 142.934944 -369.39093)
			(xy 142.928098 -369.398328) (xy 142.920367 -369.416927) (xy 142.919958 -369.426998) (xy 142.919958 -370.417555)
			(xy 187.353188 -370.417555) (xy 187.353188 -370.353633) (xy 187.361199 -370.290215) (xy 187.377096 -370.228301)
			(xy 187.400628 -370.168868) (xy 187.431422 -370.112853) (xy 187.468995 -370.061138) (xy 187.512752 -370.014541)
			(xy 187.562005 -369.973796) (xy 187.615976 -369.939545) (xy 187.673815 -369.912328) (xy 187.734608 -369.892575)
			(xy 187.797398 -369.880597) (xy 187.861194 -369.876584) (xy 187.92499 -369.880597) (xy 187.98778 -369.892575)
			(xy 188.048573 -369.912328) (xy 188.106412 -369.939545) (xy 188.160383 -369.973796) (xy 188.160715 -369.974071)
			(xy 228.695752 -369.974071) (xy 228.695752 -369.910149) (xy 228.703763 -369.846731) (xy 228.71966 -369.784817)
			(xy 228.743192 -369.725384) (xy 228.773986 -369.669369) (xy 228.811559 -369.617654) (xy 228.855316 -369.571057)
			(xy 228.904569 -369.530312) (xy 228.95854 -369.496061) (xy 229.016379 -369.468844) (xy 229.077172 -369.449091)
			(xy 229.139962 -369.437113) (xy 229.203758 -369.4331) (xy 229.267554 -369.437113) (xy 229.330344 -369.449091)
			(xy 229.391137 -369.468844) (xy 229.448976 -369.496061) (xy 229.502947 -369.530312) (xy 229.5522 -369.571057)
			(xy 229.595957 -369.617654) (xy 229.63353 -369.669369) (xy 229.664324 -369.725384) (xy 229.687856 -369.784817)
			(xy 229.703753 -369.846731) (xy 229.711764 -369.910149) (xy 229.712266 -369.94211) (xy 229.711764 -369.974071)
			(xy 229.703753 -370.037489) (xy 229.687856 -370.099403) (xy 229.664324 -370.158836) (xy 229.658937 -370.168635)
			(xy 229.877868 -370.168635) (xy 229.877868 -370.104713) (xy 229.885879 -370.041295) (xy 229.901776 -369.979381)
			(xy 229.925308 -369.919948) (xy 229.956102 -369.863933) (xy 229.993675 -369.812218) (xy 230.037432 -369.765621)
			(xy 230.086685 -369.724876) (xy 230.140656 -369.690625) (xy 230.198495 -369.663408) (xy 230.259288 -369.643655)
			(xy 230.322078 -369.631677) (xy 230.385874 -369.627664) (xy 230.44967 -369.631677) (xy 230.51246 -369.643655)
			(xy 230.573253 -369.663408) (xy 230.631092 -369.690625) (xy 230.685063 -369.724876) (xy 230.734316 -369.765621)
			(xy 230.778073 -369.812218) (xy 230.815646 -369.863933) (xy 230.84644 -369.919948) (xy 230.869972 -369.979381)
			(xy 230.885869 -370.041295) (xy 230.89388 -370.104713) (xy 230.894382 -370.136674) (xy 230.89388 -370.168635)
			(xy 230.885869 -370.232053) (xy 230.869972 -370.293967) (xy 230.84644 -370.3534) (xy 230.815646 -370.409415)
			(xy 230.778073 -370.46113) (xy 230.734316 -370.507727) (xy 230.685063 -370.548472) (xy 230.631092 -370.582723)
			(xy 230.573253 -370.60994) (xy 230.51246 -370.629693) (xy 230.44967 -370.641671) (xy 230.385874 -370.645685)
			(xy 230.322078 -370.641671) (xy 230.259288 -370.629693) (xy 230.198495 -370.60994) (xy 230.140656 -370.582723)
			(xy 230.086685 -370.548472) (xy 230.037432 -370.507727) (xy 229.993675 -370.46113) (xy 229.956102 -370.409415)
			(xy 229.925308 -370.3534) (xy 229.901776 -370.293967) (xy 229.885879 -370.232053) (xy 229.877868 -370.168635)
			(xy 229.658937 -370.168635) (xy 229.63353 -370.214851) (xy 229.595957 -370.266566) (xy 229.5522 -370.313163)
			(xy 229.502947 -370.353908) (xy 229.448976 -370.388159) (xy 229.391137 -370.415376) (xy 229.330344 -370.435129)
			(xy 229.267554 -370.447107) (xy 229.203758 -370.451121) (xy 229.139962 -370.447107) (xy 229.077172 -370.435129)
			(xy 229.016379 -370.415376) (xy 228.95854 -370.388159) (xy 228.904569 -370.353908) (xy 228.855316 -370.313163)
			(xy 228.811559 -370.266566) (xy 228.773986 -370.214851) (xy 228.743192 -370.158836) (xy 228.71966 -370.099403)
			(xy 228.703763 -370.037489) (xy 228.695752 -369.974071) (xy 188.160715 -369.974071) (xy 188.209636 -370.014541)
			(xy 188.253393 -370.061138) (xy 188.290966 -370.112853) (xy 188.32176 -370.168868) (xy 188.345292 -370.228301)
			(xy 188.361189 -370.290215) (xy 188.3692 -370.353633) (xy 188.369702 -370.385594) (xy 188.3692 -370.417555)
			(xy 188.361189 -370.480973) (xy 188.345292 -370.542887) (xy 188.32176 -370.60232) (xy 188.290966 -370.658335)
			(xy 188.253393 -370.71005) (xy 188.209636 -370.756647) (xy 188.160383 -370.797392) (xy 188.106412 -370.831643)
			(xy 188.048573 -370.85886) (xy 187.98778 -370.878613) (xy 187.92499 -370.890591) (xy 187.861194 -370.894605)
			(xy 187.797398 -370.890591) (xy 187.734608 -370.878613) (xy 187.673815 -370.85886) (xy 187.615976 -370.831643)
			(xy 187.562005 -370.797392) (xy 187.512752 -370.756647) (xy 187.468995 -370.71005) (xy 187.431422 -370.658335)
			(xy 187.400628 -370.60232) (xy 187.377096 -370.542887) (xy 187.361199 -370.480973) (xy 187.353188 -370.417555)
			(xy 142.919958 -370.417555) (xy 142.919958 -371.045994) (xy 142.94104 -371.087142) (xy 142.965424 -371.105938)
			(xy 142.997428 -371.117368) (xy 143.151606 -371.117368) (xy 143.15186 -371.117368) (xy 143.183864 -371.105938)
			(xy 143.206438 -371.087938) (xy 143.254942 -371.056618) (xy 143.280638 -371.043454) (xy 143.304768 -371.017546)
			(xy 143.316706 -370.989352) (xy 143.319819 -370.980986) (xy 143.320593 -370.963163) (xy 143.31823 -370.954554)
			(xy 143.309816 -370.92634) (xy 143.300762 -370.868167) (xy 143.300196 -370.83873) (xy 143.300682 -370.811479)
			(xy 143.308438 -370.757531) (xy 143.323793 -370.705236) (xy 143.346435 -370.655659) (xy 143.375901 -370.609809)
			(xy 143.411592 -370.568618) (xy 143.452783 -370.532927) (xy 143.498633 -370.503461) (xy 143.54821 -370.480819)
			(xy 143.600505 -370.465464) (xy 143.654453 -370.457708) (xy 143.708955 -370.457708) (xy 143.762903 -370.465464)
			(xy 143.815198 -370.480819) (xy 143.864775 -370.503461) (xy 143.910625 -370.532927) (xy 143.951816 -370.568618)
			(xy 143.987507 -370.609809) (xy 144.016973 -370.655659) (xy 144.039615 -370.705236) (xy 144.05497 -370.757531)
			(xy 144.062726 -370.811479) (xy 144.063212 -370.83873) (xy 144.063212 -370.838984) (xy 144.062847 -370.863014)
			(xy 144.056804 -370.910691) (xy 144.044811 -370.95723) (xy 144.036288 -370.9797) (xy 144.031208 -370.992146)
			(xy 144.03451 -371.018054) (xy 144.101312 -371.108732) (xy 144.124934 -371.119654) (xy 144.138142 -371.118638)
			(xy 144.166844 -371.117622) (xy 144.194091 -371.118111) (xy 144.24803 -371.125872) (xy 144.300315 -371.14123)
			(xy 144.349883 -371.163872) (xy 144.395724 -371.193337) (xy 144.436906 -371.229026) (xy 144.47259 -371.270211)
			(xy 144.502049 -371.316056) (xy 144.524686 -371.365626) (xy 144.540037 -371.417913) (xy 144.547792 -371.471853)
			(xy 144.547792 -371.526347) (xy 144.547791 -371.526353) (xy 148.408585 -371.526353) (xy 148.408585 -371.471847)
			(xy 148.416343 -371.417897) (xy 148.4317 -371.365599) (xy 148.454344 -371.31602) (xy 148.483814 -371.270169)
			(xy 148.519509 -371.228978) (xy 148.560704 -371.193287) (xy 148.606559 -371.163823) (xy 148.656141 -371.141185)
			(xy 148.70844 -371.125834) (xy 148.762391 -371.118082) (xy 148.789644 -371.117622) (xy 148.818346 -371.118638)
			(xy 148.831554 -371.119654) (xy 148.855176 -371.108732) (xy 148.921978 -371.018054) (xy 148.92528 -370.992146)
			(xy 148.9202 -370.9797) (xy 148.911667 -370.957188) (xy 148.899662 -370.910566) (xy 148.893628 -370.862802)
			(xy 148.893276 -370.83873) (xy 148.893762 -370.811479) (xy 148.901518 -370.757531) (xy 148.916873 -370.705236)
			(xy 148.939515 -370.655659) (xy 148.968981 -370.609809) (xy 149.004672 -370.568618) (xy 149.045863 -370.532927)
			(xy 149.091713 -370.503461) (xy 149.14129 -370.480819) (xy 149.193585 -370.465464) (xy 149.247533 -370.457708)
			(xy 149.302035 -370.457708) (xy 149.355983 -370.465464) (xy 149.408278 -370.480819) (xy 149.457855 -370.503461)
			(xy 149.503705 -370.532927) (xy 149.544896 -370.568618) (xy 149.580587 -370.609809) (xy 149.610053 -370.655659)
			(xy 149.632695 -370.705236) (xy 149.64805 -370.757531) (xy 149.655806 -370.811479) (xy 149.656292 -370.83873)
			(xy 149.655726 -370.868167) (xy 149.646672 -370.92634) (xy 149.638258 -370.954554) (xy 149.635896 -370.963163)
			(xy 149.63667 -370.980986) (xy 149.639782 -370.989352) (xy 149.65172 -371.017546) (xy 149.65552 -371.025792)
			(xy 149.667903 -371.039059) (xy 149.67585 -371.043454) (xy 149.701545 -371.056619) (xy 149.75005 -371.087938)
			(xy 149.772624 -371.105938) (xy 149.779614 -371.111223) (xy 149.796124 -371.11706) (xy 149.804882 -371.117368)
			(xy 149.958806 -371.117368) (xy 149.967554 -371.117013) (xy 149.984045 -371.111171) (xy 149.991064 -371.105938)
			(xy 150.013651 -371.087957) (xy 150.062153 -371.056637) (xy 150.087838 -371.043454) (xy 150.09578 -371.039057)
			(xy 150.108143 -371.025779) (xy 150.111968 -371.017546) (xy 150.123906 -370.989352) (xy 150.126925 -370.980963)
			(xy 150.127718 -370.963169) (xy 150.12543 -370.954554) (xy 150.117002 -370.926343) (xy 150.107942 -370.868168)
			(xy 150.107396 -370.83873) (xy 150.107882 -370.811479) (xy 150.115638 -370.757531) (xy 150.130993 -370.705236)
			(xy 150.153635 -370.655659) (xy 150.183101 -370.609809) (xy 150.218792 -370.568618) (xy 150.259983 -370.532927)
			(xy 150.305833 -370.503461) (xy 150.35541 -370.480819) (xy 150.407705 -370.465464) (xy 150.461653 -370.457708)
			(xy 150.516155 -370.457708) (xy 150.570103 -370.465464) (xy 150.622398 -370.480819) (xy 150.671975 -370.503461)
			(xy 150.717825 -370.532927) (xy 150.759016 -370.568618) (xy 150.794707 -370.609809) (xy 150.824173 -370.655659)
			(xy 150.846815 -370.705236) (xy 150.86217 -370.757531) (xy 150.869926 -370.811479) (xy 150.870412 -370.83873)
			(xy 150.870054 -370.862802) (xy 150.864015 -370.910564) (xy 150.852025 -370.95719) (xy 150.843488 -370.9797)
			(xy 150.838408 -370.992146) (xy 150.84171 -371.018054) (xy 150.908512 -371.108732) (xy 150.932134 -371.119654)
			(xy 150.945342 -371.118638) (xy 150.974044 -371.117622) (xy 151.001295 -371.118051) (xy 151.055243 -371.125813)
			(xy 151.107536 -371.141173) (xy 151.157112 -371.163819) (xy 151.20296 -371.193288) (xy 151.244148 -371.228983)
			(xy 151.279838 -371.270175) (xy 151.309302 -371.316027) (xy 151.331942 -371.365605) (xy 151.347296 -371.417901)
			(xy 151.355052 -371.471849) (xy 151.355052 -371.526351) (xy 151.355052 -371.526353) (xy 155.215785 -371.526353)
			(xy 155.215785 -371.471847) (xy 155.223543 -371.417897) (xy 155.2389 -371.365599) (xy 155.261544 -371.31602)
			(xy 155.291014 -371.270169) (xy 155.326709 -371.228978) (xy 155.367904 -371.193287) (xy 155.413759 -371.163823)
			(xy 155.463341 -371.141185) (xy 155.51564 -371.125834) (xy 155.569591 -371.118082) (xy 155.596844 -371.117622)
			(xy 155.625546 -371.118638) (xy 155.638754 -371.119654) (xy 155.662376 -371.108732) (xy 155.729178 -371.018054)
			(xy 155.73248 -370.992146) (xy 155.7274 -370.9797) (xy 155.718867 -370.957188) (xy 155.706862 -370.910566)
			(xy 155.700828 -370.862802) (xy 155.700476 -370.83873) (xy 155.700962 -370.811479) (xy 155.708718 -370.757531)
			(xy 155.724073 -370.705236) (xy 155.746715 -370.655659) (xy 155.776181 -370.609809) (xy 155.811872 -370.568618)
			(xy 155.853063 -370.532927) (xy 155.898913 -370.503461) (xy 155.94849 -370.480819) (xy 156.000785 -370.465464)
			(xy 156.054733 -370.457708) (xy 156.109235 -370.457708) (xy 156.163183 -370.465464) (xy 156.215478 -370.480819)
			(xy 156.265055 -370.503461) (xy 156.310905 -370.532927) (xy 156.352096 -370.568618) (xy 156.387787 -370.609809)
			(xy 156.417253 -370.655659) (xy 156.439895 -370.705236) (xy 156.45525 -370.757531) (xy 156.463006 -370.811479)
			(xy 156.463492 -370.83873) (xy 156.462926 -370.868167) (xy 156.453872 -370.92634) (xy 156.445458 -370.954554)
			(xy 156.443096 -370.963163) (xy 156.44387 -370.980986) (xy 156.446982 -370.989352) (xy 156.45892 -371.017546)
			(xy 156.46272 -371.025792) (xy 156.475103 -371.039059) (xy 156.48305 -371.043454) (xy 156.508745 -371.056619)
			(xy 156.55725 -371.087938) (xy 156.579824 -371.105938) (xy 156.586814 -371.111223) (xy 156.603324 -371.11706)
			(xy 156.612082 -371.117368) (xy 156.766006 -371.117368) (xy 156.774754 -371.117013) (xy 156.791245 -371.111171)
			(xy 156.798264 -371.105938) (xy 156.820851 -371.087957) (xy 156.869353 -371.056637) (xy 156.895038 -371.043454)
			(xy 156.90298 -371.039057) (xy 156.915343 -371.025779) (xy 156.919168 -371.017546) (xy 156.931106 -370.989352)
			(xy 156.934125 -370.980963) (xy 156.934918 -370.963169) (xy 156.93263 -370.954554) (xy 156.924202 -370.926343)
			(xy 156.915142 -370.868168) (xy 156.914596 -370.83873) (xy 156.915082 -370.811479) (xy 156.922838 -370.757531)
			(xy 156.938193 -370.705236) (xy 156.960835 -370.655659) (xy 156.990301 -370.609809) (xy 157.025992 -370.568618)
			(xy 157.067183 -370.532927) (xy 157.113033 -370.503461) (xy 157.16261 -370.480819) (xy 157.214905 -370.465464)
			(xy 157.268853 -370.457708) (xy 157.323355 -370.457708) (xy 157.377303 -370.465464) (xy 157.429598 -370.480819)
			(xy 157.479175 -370.503461) (xy 157.525025 -370.532927) (xy 157.566216 -370.568618) (xy 157.601907 -370.609809)
			(xy 157.631373 -370.655659) (xy 157.654015 -370.705236) (xy 157.66937 -370.757531) (xy 157.677126 -370.811479)
			(xy 157.677612 -370.83873) (xy 157.677254 -370.862802) (xy 157.671215 -370.910564) (xy 157.659225 -370.95719)
			(xy 157.650688 -370.9797) (xy 157.645608 -370.992146) (xy 157.64891 -371.018054) (xy 157.715712 -371.108732)
			(xy 157.739334 -371.119654) (xy 157.752542 -371.118638) (xy 157.781244 -371.117622) (xy 157.808495 -371.118051)
			(xy 157.862443 -371.125813) (xy 157.914736 -371.141173) (xy 157.964312 -371.163819) (xy 158.01016 -371.193288)
			(xy 158.051348 -371.228983) (xy 158.087038 -371.270175) (xy 158.116502 -371.316027) (xy 158.139142 -371.365605)
			(xy 158.154496 -371.417901) (xy 158.162252 -371.471849) (xy 158.162252 -371.526351) (xy 158.162252 -371.526353)
			(xy 162.022985 -371.526353) (xy 162.022985 -371.471847) (xy 162.030743 -371.417897) (xy 162.0461 -371.365599)
			(xy 162.068744 -371.31602) (xy 162.098214 -371.270169) (xy 162.133909 -371.228978) (xy 162.175104 -371.193287)
			(xy 162.220959 -371.163823) (xy 162.270541 -371.141185) (xy 162.32284 -371.125834) (xy 162.376791 -371.118082)
			(xy 162.404044 -371.117622) (xy 162.432746 -371.118638) (xy 162.445954 -371.119654) (xy 162.469576 -371.108732)
			(xy 162.536378 -371.018054) (xy 162.53968 -370.992146) (xy 162.5346 -370.9797) (xy 162.526067 -370.957188)
			(xy 162.514062 -370.910566) (xy 162.508028 -370.862802) (xy 162.507676 -370.83873) (xy 162.508162 -370.811479)
			(xy 162.515918 -370.757531) (xy 162.531273 -370.705236) (xy 162.553915 -370.655659) (xy 162.583381 -370.609809)
			(xy 162.619072 -370.568618) (xy 162.660263 -370.532927) (xy 162.706113 -370.503461) (xy 162.75569 -370.480819)
			(xy 162.807985 -370.465464) (xy 162.861933 -370.457708) (xy 162.916435 -370.457708) (xy 162.970383 -370.465464)
			(xy 163.022678 -370.480819) (xy 163.072255 -370.503461) (xy 163.118105 -370.532927) (xy 163.159296 -370.568618)
			(xy 163.194987 -370.609809) (xy 163.224453 -370.655659) (xy 163.247095 -370.705236) (xy 163.26245 -370.757531)
			(xy 163.270206 -370.811479) (xy 163.270692 -370.83873) (xy 163.270126 -370.868167) (xy 163.261072 -370.92634)
			(xy 163.252658 -370.954554) (xy 163.250296 -370.963163) (xy 163.25107 -370.980986) (xy 163.254182 -370.989352)
			(xy 163.26612 -371.017546) (xy 163.26992 -371.025792) (xy 163.282303 -371.039059) (xy 163.29025 -371.043454)
			(xy 163.315945 -371.056619) (xy 163.36445 -371.087938) (xy 163.387024 -371.105938) (xy 163.394014 -371.111223)
			(xy 163.410524 -371.11706) (xy 163.419282 -371.117368) (xy 163.573206 -371.117368) (xy 163.581954 -371.117013)
			(xy 163.598445 -371.111171) (xy 163.605464 -371.105938) (xy 163.628051 -371.087957) (xy 163.676553 -371.056637)
			(xy 163.702238 -371.043454) (xy 163.71018 -371.039057) (xy 163.722543 -371.025779) (xy 163.726368 -371.017546)
			(xy 163.738306 -370.989352) (xy 163.741325 -370.980963) (xy 163.742118 -370.963169) (xy 163.73983 -370.954554)
			(xy 163.731402 -370.926343) (xy 163.722342 -370.868168) (xy 163.721796 -370.83873) (xy 163.722282 -370.811479)
			(xy 163.730038 -370.757531) (xy 163.745393 -370.705236) (xy 163.768035 -370.655659) (xy 163.797501 -370.609809)
			(xy 163.833192 -370.568618) (xy 163.874383 -370.532927) (xy 163.920233 -370.503461) (xy 163.96981 -370.480819)
			(xy 164.022105 -370.465464) (xy 164.076053 -370.457708) (xy 164.130555 -370.457708) (xy 164.184503 -370.465464)
			(xy 164.236798 -370.480819) (xy 164.286375 -370.503461) (xy 164.332225 -370.532927) (xy 164.373416 -370.568618)
			(xy 164.409107 -370.609809) (xy 164.438573 -370.655659) (xy 164.461215 -370.705236) (xy 164.47657 -370.757531)
			(xy 164.484326 -370.811479) (xy 164.484812 -370.83873) (xy 164.484454 -370.862802) (xy 164.478415 -370.910564)
			(xy 164.466425 -370.95719) (xy 164.457888 -370.9797) (xy 164.452808 -370.992146) (xy 164.45611 -371.018054)
			(xy 164.522912 -371.108732) (xy 164.546534 -371.119654) (xy 164.559742 -371.118638) (xy 164.588444 -371.117622)
			(xy 164.615695 -371.118051) (xy 164.669643 -371.125813) (xy 164.721936 -371.141173) (xy 164.771512 -371.163819)
			(xy 164.81736 -371.193288) (xy 164.858548 -371.228983) (xy 164.894238 -371.270175) (xy 164.923702 -371.316027)
			(xy 164.946342 -371.365605) (xy 164.961696 -371.417901) (xy 164.962741 -371.425173) (xy 198.79792 -371.425173)
			(xy 198.79792 -371.361251) (xy 198.805931 -371.297833) (xy 198.821828 -371.235919) (xy 198.84536 -371.176486)
			(xy 198.876154 -371.120471) (xy 198.913727 -371.068756) (xy 198.957484 -371.022159) (xy 199.006737 -370.981414)
			(xy 199.060708 -370.947163) (xy 199.118547 -370.919946) (xy 199.17934 -370.900193) (xy 199.24213 -370.888215)
			(xy 199.305926 -370.884202) (xy 199.369722 -370.888215) (xy 199.432512 -370.900193) (xy 199.493305 -370.919946)
			(xy 199.551144 -370.947163) (xy 199.605115 -370.981414) (xy 199.654368 -371.022159) (xy 199.698125 -371.068756)
			(xy 199.735698 -371.120471) (xy 199.766492 -371.176486) (xy 199.790024 -371.235919) (xy 199.805921 -371.297833)
			(xy 199.813932 -371.361251) (xy 199.814434 -371.393212) (xy 199.813932 -371.425173) (xy 199.805921 -371.488591)
			(xy 199.790024 -371.550505) (xy 199.766492 -371.609938) (xy 199.735698 -371.665953) (xy 199.698125 -371.717668)
			(xy 199.654368 -371.764265) (xy 199.605115 -371.80501) (xy 199.551144 -371.839261) (xy 199.493305 -371.866478)
			(xy 199.432512 -371.886231) (xy 199.369722 -371.898209) (xy 199.305926 -371.902223) (xy 199.24213 -371.898209)
			(xy 199.17934 -371.886231) (xy 199.118547 -371.866478) (xy 199.060708 -371.839261) (xy 199.006737 -371.80501)
			(xy 198.957484 -371.764265) (xy 198.913727 -371.717668) (xy 198.876154 -371.665953) (xy 198.84536 -371.609938)
			(xy 198.821828 -371.550505) (xy 198.805931 -371.488591) (xy 198.79792 -371.425173) (xy 164.962741 -371.425173)
			(xy 164.969452 -371.471849) (xy 164.969452 -371.526351) (xy 164.961696 -371.580299) (xy 164.946342 -371.632595)
			(xy 164.923702 -371.682173) (xy 164.894238 -371.728025) (xy 164.858548 -371.769217) (xy 164.81736 -371.804912)
			(xy 164.771512 -371.834381) (xy 164.721936 -371.857027) (xy 164.669643 -371.872387) (xy 164.615695 -371.880149)
			(xy 164.588444 -371.880638) (xy 164.559742 -371.879622) (xy 164.546534 -371.878606) (xy 164.522912 -371.889528)
			(xy 164.45611 -371.980206) (xy 164.452808 -372.006114) (xy 164.457888 -372.01856) (xy 164.466438 -372.041066)
			(xy 164.478437 -372.087691) (xy 164.484464 -372.135457) (xy 164.484812 -372.15953) (xy 164.484326 -372.186781)
			(xy 164.47657 -372.240729) (xy 164.461215 -372.293024) (xy 164.438573 -372.342601) (xy 164.409107 -372.388451)
			(xy 164.373416 -372.429642) (xy 164.332225 -372.465333) (xy 164.286375 -372.494799) (xy 164.236798 -372.517441)
			(xy 164.184503 -372.532796) (xy 164.130555 -372.540552) (xy 164.076053 -372.540552) (xy 164.022105 -372.532796)
			(xy 163.96981 -372.517441) (xy 163.920233 -372.494799) (xy 163.874383 -372.465333) (xy 163.833192 -372.429642)
			(xy 163.797501 -372.388451) (xy 163.768035 -372.342601) (xy 163.745393 -372.293024) (xy 163.730038 -372.240729)
			(xy 163.722282 -372.186781) (xy 163.721796 -372.15953) (xy 163.722353 -372.130093) (xy 163.731413 -372.07192)
			(xy 163.73983 -372.043706) (xy 163.742213 -372.035101) (xy 163.741426 -372.017274) (xy 163.738306 -372.008908)
			(xy 163.726368 -371.980714) (xy 163.722519 -371.972495) (xy 163.71017 -371.959214) (xy 163.702238 -371.954806)
			(xy 163.67654 -371.941646) (xy 163.628037 -371.910323) (xy 163.605464 -371.892322) (xy 163.598453 -371.887069)
			(xy 163.581959 -371.881214) (xy 163.573206 -371.880892) (xy 163.419282 -371.880892) (xy 163.410535 -371.88125)
			(xy 163.394044 -371.887091) (xy 163.387024 -371.892322) (xy 163.364441 -371.910309) (xy 163.315936 -371.941625)
			(xy 163.29025 -371.954806) (xy 163.282292 -371.959179) (xy 163.269937 -371.972473) (xy 163.26612 -371.980714)
			(xy 163.254182 -372.008908) (xy 163.251134 -372.017288) (xy 163.25036 -372.03509) (xy 163.252658 -372.043706)
			(xy 163.261099 -372.071914) (xy 163.270151 -372.130091) (xy 163.270692 -372.15953) (xy 163.270206 -372.186781)
			(xy 163.26245 -372.240729) (xy 163.247095 -372.293024) (xy 163.224453 -372.342601) (xy 163.194987 -372.388451)
			(xy 163.159296 -372.429642) (xy 163.118105 -372.465333) (xy 163.072255 -372.494799) (xy 163.022678 -372.517441)
			(xy 162.970383 -372.532796) (xy 162.916435 -372.540552) (xy 162.861933 -372.540552) (xy 162.807985 -372.532796)
			(xy 162.75569 -372.517441) (xy 162.706113 -372.494799) (xy 162.660263 -372.465333) (xy 162.619072 -372.429642)
			(xy 162.583381 -372.388451) (xy 162.553915 -372.342601) (xy 162.531273 -372.293024) (xy 162.515918 -372.240729)
			(xy 162.508162 -372.186781) (xy 162.507676 -372.15953) (xy 162.508023 -372.135458) (xy 162.514066 -372.087695)
			(xy 162.526061 -372.041069) (xy 162.5346 -372.01856) (xy 162.53968 -372.006114) (xy 162.536378 -371.980206)
			(xy 162.469576 -371.889528) (xy 162.445954 -371.878606) (xy 162.432746 -371.879622) (xy 162.404044 -371.880638)
			(xy 162.376791 -371.880118) (xy 162.32284 -371.872366) (xy 162.270541 -371.857015) (xy 162.220959 -371.834377)
			(xy 162.175104 -371.804913) (xy 162.133909 -371.769222) (xy 162.098214 -371.728031) (xy 162.068744 -371.68218)
			(xy 162.0461 -371.632601) (xy 162.030743 -371.580303) (xy 162.022985 -371.526353) (xy 158.162252 -371.526353)
			(xy 158.154496 -371.580299) (xy 158.139142 -371.632595) (xy 158.116502 -371.682173) (xy 158.087038 -371.728025)
			(xy 158.051348 -371.769217) (xy 158.01016 -371.804912) (xy 157.964312 -371.834381) (xy 157.914736 -371.857027)
			(xy 157.862443 -371.872387) (xy 157.808495 -371.880149) (xy 157.781244 -371.880638) (xy 157.752542 -371.879622)
			(xy 157.739334 -371.878606) (xy 157.715712 -371.889528) (xy 157.64891 -371.980206) (xy 157.645608 -372.006114)
			(xy 157.650688 -372.01856) (xy 157.659238 -372.041066) (xy 157.671237 -372.087691) (xy 157.677264 -372.135457)
			(xy 157.677612 -372.15953) (xy 157.677126 -372.186781) (xy 157.66937 -372.240729) (xy 157.654015 -372.293024)
			(xy 157.631373 -372.342601) (xy 157.601907 -372.388451) (xy 157.566216 -372.429642) (xy 157.525025 -372.465333)
			(xy 157.479175 -372.494799) (xy 157.429598 -372.517441) (xy 157.377303 -372.532796) (xy 157.323355 -372.540552)
			(xy 157.268853 -372.540552) (xy 157.214905 -372.532796) (xy 157.16261 -372.517441) (xy 157.113033 -372.494799)
			(xy 157.067183 -372.465333) (xy 157.025992 -372.429642) (xy 156.990301 -372.388451) (xy 156.960835 -372.342601)
			(xy 156.938193 -372.293024) (xy 156.922838 -372.240729) (xy 156.915082 -372.186781) (xy 156.914596 -372.15953)
			(xy 156.915153 -372.130093) (xy 156.924213 -372.07192) (xy 156.93263 -372.043706) (xy 156.935013 -372.035101)
			(xy 156.934226 -372.017274) (xy 156.931106 -372.008908) (xy 156.919168 -371.980714) (xy 156.915319 -371.972495)
			(xy 156.90297 -371.959214) (xy 156.895038 -371.954806) (xy 156.86934 -371.941646) (xy 156.820837 -371.910323)
			(xy 156.798264 -371.892322) (xy 156.791253 -371.887069) (xy 156.774759 -371.881214) (xy 156.766006 -371.880892)
			(xy 156.612082 -371.880892) (xy 156.603335 -371.88125) (xy 156.586844 -371.887091) (xy 156.579824 -371.892322)
			(xy 156.557241 -371.910309) (xy 156.508736 -371.941625) (xy 156.48305 -371.954806) (xy 156.475092 -371.959179)
			(xy 156.462737 -371.972473) (xy 156.45892 -371.980714) (xy 156.446982 -372.008908) (xy 156.443934 -372.017288)
			(xy 156.44316 -372.03509) (xy 156.445458 -372.043706) (xy 156.453899 -372.071914) (xy 156.462951 -372.130091)
			(xy 156.463492 -372.15953) (xy 156.463006 -372.186781) (xy 156.45525 -372.240729) (xy 156.439895 -372.293024)
			(xy 156.417253 -372.342601) (xy 156.387787 -372.388451) (xy 156.352096 -372.429642) (xy 156.310905 -372.465333)
			(xy 156.265055 -372.494799) (xy 156.215478 -372.517441) (xy 156.163183 -372.532796) (xy 156.109235 -372.540552)
			(xy 156.054733 -372.540552) (xy 156.000785 -372.532796) (xy 155.94849 -372.517441) (xy 155.898913 -372.494799)
			(xy 155.853063 -372.465333) (xy 155.811872 -372.429642) (xy 155.776181 -372.388451) (xy 155.746715 -372.342601)
			(xy 155.724073 -372.293024) (xy 155.708718 -372.240729) (xy 155.700962 -372.186781) (xy 155.700476 -372.15953)
			(xy 155.700823 -372.135458) (xy 155.706866 -372.087695) (xy 155.718861 -372.041069) (xy 155.7274 -372.01856)
			(xy 155.73248 -372.006114) (xy 155.729178 -371.980206) (xy 155.662376 -371.889528) (xy 155.638754 -371.878606)
			(xy 155.625546 -371.879622) (xy 155.596844 -371.880638) (xy 155.569591 -371.880118) (xy 155.51564 -371.872366)
			(xy 155.463341 -371.857015) (xy 155.413759 -371.834377) (xy 155.367904 -371.804913) (xy 155.326709 -371.769222)
			(xy 155.291014 -371.728031) (xy 155.261544 -371.68218) (xy 155.2389 -371.632601) (xy 155.223543 -371.580303)
			(xy 155.215785 -371.526353) (xy 151.355052 -371.526353) (xy 151.347296 -371.580299) (xy 151.331942 -371.632595)
			(xy 151.309302 -371.682173) (xy 151.279838 -371.728025) (xy 151.244148 -371.769217) (xy 151.20296 -371.804912)
			(xy 151.157112 -371.834381) (xy 151.107536 -371.857027) (xy 151.055243 -371.872387) (xy 151.001295 -371.880149)
			(xy 150.974044 -371.880638) (xy 150.945342 -371.879622) (xy 150.932134 -371.878606) (xy 150.908512 -371.889528)
			(xy 150.84171 -371.980206) (xy 150.838408 -372.006114) (xy 150.843488 -372.01856) (xy 150.852038 -372.041066)
			(xy 150.864037 -372.087691) (xy 150.870064 -372.135457) (xy 150.870412 -372.15953) (xy 150.869926 -372.186781)
			(xy 150.86217 -372.240729) (xy 150.846815 -372.293024) (xy 150.824173 -372.342601) (xy 150.794707 -372.388451)
			(xy 150.759016 -372.429642) (xy 150.717825 -372.465333) (xy 150.671975 -372.494799) (xy 150.622398 -372.517441)
			(xy 150.570103 -372.532796) (xy 150.516155 -372.540552) (xy 150.461653 -372.540552) (xy 150.407705 -372.532796)
			(xy 150.35541 -372.517441) (xy 150.305833 -372.494799) (xy 150.259983 -372.465333) (xy 150.218792 -372.429642)
			(xy 150.183101 -372.388451) (xy 150.153635 -372.342601) (xy 150.130993 -372.293024) (xy 150.115638 -372.240729)
			(xy 150.107882 -372.186781) (xy 150.107396 -372.15953) (xy 150.107953 -372.130093) (xy 150.117013 -372.07192)
			(xy 150.12543 -372.043706) (xy 150.127813 -372.035101) (xy 150.127026 -372.017274) (xy 150.123906 -372.008908)
			(xy 150.111968 -371.980714) (xy 150.108119 -371.972495) (xy 150.09577 -371.959214) (xy 150.087838 -371.954806)
			(xy 150.06214 -371.941646) (xy 150.013637 -371.910323) (xy 149.991064 -371.892322) (xy 149.984053 -371.887069)
			(xy 149.967559 -371.881214) (xy 149.958806 -371.880892) (xy 149.804882 -371.880892) (xy 149.796135 -371.88125)
			(xy 149.779644 -371.887091) (xy 149.772624 -371.892322) (xy 149.750041 -371.910309) (xy 149.701536 -371.941625)
			(xy 149.67585 -371.954806) (xy 149.667892 -371.959179) (xy 149.655537 -371.972473) (xy 149.65172 -371.980714)
			(xy 149.639782 -372.008908) (xy 149.636734 -372.017288) (xy 149.63596 -372.03509) (xy 149.638258 -372.043706)
			(xy 149.646699 -372.071914) (xy 149.655751 -372.130091) (xy 149.656292 -372.15953) (xy 149.655806 -372.186781)
			(xy 149.64805 -372.240729) (xy 149.632695 -372.293024) (xy 149.610053 -372.342601) (xy 149.580587 -372.388451)
			(xy 149.544896 -372.429642) (xy 149.503705 -372.465333) (xy 149.457855 -372.494799) (xy 149.408278 -372.517441)
			(xy 149.355983 -372.532796) (xy 149.302035 -372.540552) (xy 149.247533 -372.540552) (xy 149.193585 -372.532796)
			(xy 149.14129 -372.517441) (xy 149.091713 -372.494799) (xy 149.045863 -372.465333) (xy 149.004672 -372.429642)
			(xy 148.968981 -372.388451) (xy 148.939515 -372.342601) (xy 148.916873 -372.293024) (xy 148.901518 -372.240729)
			(xy 148.893762 -372.186781) (xy 148.893276 -372.15953) (xy 148.893623 -372.135458) (xy 148.899666 -372.087695)
			(xy 148.911661 -372.041069) (xy 148.9202 -372.01856) (xy 148.92528 -372.006114) (xy 148.921978 -371.980206)
			(xy 148.855176 -371.889528) (xy 148.831554 -371.878606) (xy 148.818346 -371.879622) (xy 148.789644 -371.880638)
			(xy 148.762391 -371.880118) (xy 148.70844 -371.872366) (xy 148.656141 -371.857015) (xy 148.606559 -371.834377)
			(xy 148.560704 -371.804913) (xy 148.519509 -371.769222) (xy 148.483814 -371.728031) (xy 148.454344 -371.68218)
			(xy 148.4317 -371.632601) (xy 148.416343 -371.580303) (xy 148.408585 -371.526353) (xy 144.547791 -371.526353)
			(xy 144.540037 -371.580287) (xy 144.524686 -371.632574) (xy 144.502049 -371.682144) (xy 144.47259 -371.727989)
			(xy 144.436906 -371.769174) (xy 144.395724 -371.804863) (xy 144.349883 -371.834328) (xy 144.300315 -371.85697)
			(xy 144.24803 -371.872328) (xy 144.194091 -371.880089) (xy 144.166844 -371.880638) (xy 144.138142 -371.879622)
			(xy 144.124934 -371.878606) (xy 144.101312 -371.889528) (xy 144.03451 -371.980206) (xy 144.031208 -372.006114)
			(xy 144.036288 -372.01856) (xy 144.044814 -372.041029) (xy 144.056799 -372.08757) (xy 144.062853 -372.135247)
			(xy 144.063212 -372.159276) (xy 144.063212 -372.15953) (xy 144.062726 -372.186781) (xy 144.05497 -372.240729)
			(xy 144.039615 -372.293024) (xy 144.016973 -372.342601) (xy 143.987507 -372.388451) (xy 143.951816 -372.429642)
			(xy 143.910625 -372.465333) (xy 143.864775 -372.494799) (xy 143.815198 -372.517441) (xy 143.762903 -372.532796)
			(xy 143.708955 -372.540552) (xy 143.654453 -372.540552) (xy 143.600505 -372.532796) (xy 143.54821 -372.517441)
			(xy 143.498633 -372.494799) (xy 143.452783 -372.465333) (xy 143.411592 -372.429642) (xy 143.375901 -372.388451)
			(xy 143.346435 -372.342601) (xy 143.323793 -372.293024) (xy 143.308438 -372.240729) (xy 143.300682 -372.186781)
			(xy 143.300196 -372.15953) (xy 143.300737 -372.130091) (xy 143.309789 -372.071914) (xy 143.31823 -372.043706)
			(xy 143.320529 -372.03509) (xy 143.319754 -372.017288) (xy 143.316706 -372.008908) (xy 143.304768 -371.980714)
			(xy 143.280638 -371.954806) (xy 143.254952 -371.941625) (xy 143.206448 -371.910308) (xy 143.183864 -371.892322)
			(xy 143.15186 -371.880892) (xy 142.997682 -371.880892) (xy 142.997428 -371.880892) (xy 142.965424 -371.892322)
			(xy 142.94104 -371.911118) (xy 142.919958 -371.952266) (xy 142.919958 -373.990153) (xy 146.706785 -373.990153)
			(xy 146.706785 -373.935647) (xy 146.714543 -373.881697) (xy 146.7299 -373.829399) (xy 146.752544 -373.77982)
			(xy 146.782014 -373.733969) (xy 146.817709 -373.692778) (xy 146.858904 -373.657087) (xy 146.904759 -373.627623)
			(xy 146.954341 -373.604985) (xy 147.00664 -373.589634) (xy 147.060591 -373.581882) (xy 147.087844 -373.581422)
			(xy 147.116546 -373.582438) (xy 147.129754 -373.583454) (xy 147.153376 -373.572532) (xy 147.220178 -373.481854)
			(xy 147.22348 -373.455946) (xy 147.2184 -373.4435) (xy 147.209867 -373.420988) (xy 147.197862 -373.374366)
			(xy 147.191828 -373.326602) (xy 147.191476 -373.30253) (xy 147.191962 -373.275279) (xy 147.199718 -373.221331)
			(xy 147.215073 -373.169036) (xy 147.237715 -373.119459) (xy 147.267181 -373.073609) (xy 147.302872 -373.032418)
			(xy 147.344063 -372.996727) (xy 147.389913 -372.967261) (xy 147.43949 -372.944619) (xy 147.491785 -372.929264)
			(xy 147.545733 -372.921508) (xy 147.600235 -372.921508) (xy 147.654183 -372.929264) (xy 147.706478 -372.944619)
			(xy 147.756055 -372.967261) (xy 147.801905 -372.996727) (xy 147.843096 -373.032418) (xy 147.878787 -373.073609)
			(xy 147.908253 -373.119459) (xy 147.930895 -373.169036) (xy 147.94625 -373.221331) (xy 147.954006 -373.275279)
			(xy 147.954492 -373.30253) (xy 147.953926 -373.331967) (xy 147.944872 -373.39014) (xy 147.936458 -373.418354)
			(xy 147.934096 -373.426963) (xy 147.93487 -373.444786) (xy 147.937982 -373.453152) (xy 147.94992 -373.481346)
			(xy 147.95372 -373.489592) (xy 147.966103 -373.502859) (xy 147.97405 -373.507254) (xy 147.999745 -373.520419)
			(xy 148.04825 -373.551738) (xy 148.070824 -373.569738) (xy 148.077814 -373.575023) (xy 148.094324 -373.58086)
			(xy 148.103082 -373.581168) (xy 148.257006 -373.581168) (xy 148.265754 -373.580813) (xy 148.282245 -373.574971)
			(xy 148.289264 -373.569738) (xy 148.311851 -373.551757) (xy 148.360353 -373.520437) (xy 148.386038 -373.507254)
			(xy 148.39398 -373.502857) (xy 148.406343 -373.489579) (xy 148.410168 -373.481346) (xy 148.422106 -373.453152)
			(xy 148.425125 -373.444763) (xy 148.425918 -373.426969) (xy 148.42363 -373.418354) (xy 148.415202 -373.390143)
			(xy 148.406142 -373.331968) (xy 148.405596 -373.30253) (xy 148.406082 -373.275279) (xy 148.413838 -373.221331)
			(xy 148.429193 -373.169036) (xy 148.451835 -373.119459) (xy 148.481301 -373.073609) (xy 148.516992 -373.032418)
			(xy 148.558183 -372.996727) (xy 148.604033 -372.967261) (xy 148.65361 -372.944619) (xy 148.705905 -372.929264)
			(xy 148.759853 -372.921508) (xy 148.814355 -372.921508) (xy 148.868303 -372.929264) (xy 148.920598 -372.944619)
			(xy 148.970175 -372.967261) (xy 149.016025 -372.996727) (xy 149.057216 -373.032418) (xy 149.092907 -373.073609)
			(xy 149.122373 -373.119459) (xy 149.145015 -373.169036) (xy 149.16037 -373.221331) (xy 149.168126 -373.275279)
			(xy 149.168612 -373.30253) (xy 149.168254 -373.326602) (xy 149.162215 -373.374364) (xy 149.150225 -373.42099)
			(xy 149.141688 -373.4435) (xy 149.136608 -373.455946) (xy 149.13991 -373.481854) (xy 149.206712 -373.572532)
			(xy 149.230334 -373.583454) (xy 149.243542 -373.582438) (xy 149.272244 -373.581422) (xy 149.299495 -373.581851)
			(xy 149.353443 -373.589613) (xy 149.405736 -373.604973) (xy 149.455312 -373.627619) (xy 149.50116 -373.657088)
			(xy 149.542348 -373.692783) (xy 149.578038 -373.733975) (xy 149.607502 -373.779827) (xy 149.630142 -373.829405)
			(xy 149.645496 -373.881701) (xy 149.653252 -373.935649) (xy 149.653252 -373.990151) (xy 149.653252 -373.990153)
			(xy 153.513985 -373.990153) (xy 153.513985 -373.935647) (xy 153.521743 -373.881697) (xy 153.5371 -373.829399)
			(xy 153.559744 -373.77982) (xy 153.589214 -373.733969) (xy 153.624909 -373.692778) (xy 153.666104 -373.657087)
			(xy 153.711959 -373.627623) (xy 153.761541 -373.604985) (xy 153.81384 -373.589634) (xy 153.867791 -373.581882)
			(xy 153.895044 -373.581422) (xy 153.923746 -373.582438) (xy 153.936954 -373.583454) (xy 153.960576 -373.572532)
			(xy 154.027378 -373.481854) (xy 154.03068 -373.455946) (xy 154.0256 -373.4435) (xy 154.017067 -373.420988)
			(xy 154.005062 -373.374366) (xy 153.999028 -373.326602) (xy 153.998676 -373.30253) (xy 153.999162 -373.275279)
			(xy 154.006918 -373.221331) (xy 154.022273 -373.169036) (xy 154.044915 -373.119459) (xy 154.074381 -373.073609)
			(xy 154.110072 -373.032418) (xy 154.151263 -372.996727) (xy 154.197113 -372.967261) (xy 154.24669 -372.944619)
			(xy 154.298985 -372.929264) (xy 154.352933 -372.921508) (xy 154.407435 -372.921508) (xy 154.461383 -372.929264)
			(xy 154.513678 -372.944619) (xy 154.563255 -372.967261) (xy 154.609105 -372.996727) (xy 154.650296 -373.032418)
			(xy 154.685987 -373.073609) (xy 154.715453 -373.119459) (xy 154.738095 -373.169036) (xy 154.75345 -373.221331)
			(xy 154.761206 -373.275279) (xy 154.761692 -373.30253) (xy 154.761126 -373.331967) (xy 154.752072 -373.39014)
			(xy 154.743658 -373.418354) (xy 154.741296 -373.426963) (xy 154.74207 -373.444786) (xy 154.745182 -373.453152)
			(xy 154.75712 -373.481346) (xy 154.76092 -373.489592) (xy 154.773303 -373.502859) (xy 154.78125 -373.507254)
			(xy 154.806945 -373.520419) (xy 154.85545 -373.551738) (xy 154.878024 -373.569738) (xy 154.885014 -373.575023)
			(xy 154.901524 -373.58086) (xy 154.910282 -373.581168) (xy 155.064206 -373.581168) (xy 155.072954 -373.580813)
			(xy 155.089445 -373.574971) (xy 155.096464 -373.569738) (xy 155.119051 -373.551757) (xy 155.167553 -373.520437)
			(xy 155.193238 -373.507254) (xy 155.20118 -373.502857) (xy 155.213543 -373.489579) (xy 155.217368 -373.481346)
			(xy 155.229306 -373.453152) (xy 155.232325 -373.444763) (xy 155.233118 -373.426969) (xy 155.23083 -373.418354)
			(xy 155.222402 -373.390143) (xy 155.213342 -373.331968) (xy 155.212796 -373.30253) (xy 155.213282 -373.275279)
			(xy 155.221038 -373.221331) (xy 155.236393 -373.169036) (xy 155.259035 -373.119459) (xy 155.288501 -373.073609)
			(xy 155.324192 -373.032418) (xy 155.365383 -372.996727) (xy 155.411233 -372.967261) (xy 155.46081 -372.944619)
			(xy 155.513105 -372.929264) (xy 155.567053 -372.921508) (xy 155.621555 -372.921508) (xy 155.675503 -372.929264)
			(xy 155.727798 -372.944619) (xy 155.777375 -372.967261) (xy 155.823225 -372.996727) (xy 155.864416 -373.032418)
			(xy 155.900107 -373.073609) (xy 155.929573 -373.119459) (xy 155.952215 -373.169036) (xy 155.96757 -373.221331)
			(xy 155.975326 -373.275279) (xy 155.975812 -373.30253) (xy 155.975454 -373.326602) (xy 155.969415 -373.374364)
			(xy 155.957425 -373.42099) (xy 155.948888 -373.4435) (xy 155.943808 -373.455946) (xy 155.94711 -373.481854)
			(xy 156.013912 -373.572532) (xy 156.037534 -373.583454) (xy 156.050742 -373.582438) (xy 156.079444 -373.581422)
			(xy 156.106695 -373.581851) (xy 156.160643 -373.589613) (xy 156.212936 -373.604973) (xy 156.262512 -373.627619)
			(xy 156.30836 -373.657088) (xy 156.349548 -373.692783) (xy 156.385238 -373.733975) (xy 156.414702 -373.779827)
			(xy 156.437342 -373.829405) (xy 156.452696 -373.881701) (xy 156.460452 -373.935649) (xy 156.460452 -373.990151)
			(xy 156.460452 -373.990153) (xy 160.321185 -373.990153) (xy 160.321185 -373.935647) (xy 160.328943 -373.881697)
			(xy 160.3443 -373.829399) (xy 160.366944 -373.77982) (xy 160.396414 -373.733969) (xy 160.432109 -373.692778)
			(xy 160.473304 -373.657087) (xy 160.519159 -373.627623) (xy 160.568741 -373.604985) (xy 160.62104 -373.589634)
			(xy 160.674991 -373.581882) (xy 160.702244 -373.581422) (xy 160.730946 -373.582438) (xy 160.744154 -373.583454)
			(xy 160.767776 -373.572532) (xy 160.834578 -373.481854) (xy 160.83788 -373.455946) (xy 160.8328 -373.4435)
			(xy 160.824267 -373.420988) (xy 160.812262 -373.374366) (xy 160.806228 -373.326602) (xy 160.805876 -373.30253)
			(xy 160.806362 -373.275279) (xy 160.814118 -373.221331) (xy 160.829473 -373.169036) (xy 160.852115 -373.119459)
			(xy 160.881581 -373.073609) (xy 160.917272 -373.032418) (xy 160.958463 -372.996727) (xy 161.004313 -372.967261)
			(xy 161.05389 -372.944619) (xy 161.106185 -372.929264) (xy 161.160133 -372.921508) (xy 161.214635 -372.921508)
			(xy 161.268583 -372.929264) (xy 161.320878 -372.944619) (xy 161.370455 -372.967261) (xy 161.416305 -372.996727)
			(xy 161.457496 -373.032418) (xy 161.493187 -373.073609) (xy 161.522653 -373.119459) (xy 161.545295 -373.169036)
			(xy 161.56065 -373.221331) (xy 161.568406 -373.275279) (xy 161.568892 -373.30253) (xy 161.568326 -373.331967)
			(xy 161.559272 -373.39014) (xy 161.550858 -373.418354) (xy 161.548496 -373.426963) (xy 161.54927 -373.444786)
			(xy 161.552382 -373.453152) (xy 161.56432 -373.481346) (xy 161.56812 -373.489592) (xy 161.580503 -373.502859)
			(xy 161.58845 -373.507254) (xy 161.614145 -373.520419) (xy 161.66265 -373.551738) (xy 161.685224 -373.569738)
			(xy 161.692214 -373.575023) (xy 161.708724 -373.58086) (xy 161.717482 -373.581168) (xy 161.871406 -373.581168)
			(xy 161.880154 -373.580813) (xy 161.896645 -373.574971) (xy 161.903664 -373.569738) (xy 161.926251 -373.551757)
			(xy 161.974753 -373.520437) (xy 162.000438 -373.507254) (xy 162.00838 -373.502857) (xy 162.020743 -373.489579)
			(xy 162.024568 -373.481346) (xy 162.036506 -373.453152) (xy 162.039525 -373.444763) (xy 162.040318 -373.426969)
			(xy 162.03803 -373.418354) (xy 162.029602 -373.390143) (xy 162.020542 -373.331968) (xy 162.019996 -373.30253)
			(xy 162.020482 -373.275279) (xy 162.028238 -373.221331) (xy 162.043593 -373.169036) (xy 162.066235 -373.119459)
			(xy 162.095701 -373.073609) (xy 162.131392 -373.032418) (xy 162.172583 -372.996727) (xy 162.218433 -372.967261)
			(xy 162.26801 -372.944619) (xy 162.320305 -372.929264) (xy 162.374253 -372.921508) (xy 162.428755 -372.921508)
			(xy 162.482703 -372.929264) (xy 162.534998 -372.944619) (xy 162.584575 -372.967261) (xy 162.630425 -372.996727)
			(xy 162.671616 -373.032418) (xy 162.707307 -373.073609) (xy 162.736773 -373.119459) (xy 162.759415 -373.169036)
			(xy 162.77477 -373.221331) (xy 162.782526 -373.275279) (xy 162.783012 -373.30253) (xy 162.782654 -373.326602)
			(xy 162.776615 -373.374364) (xy 162.764625 -373.42099) (xy 162.756088 -373.4435) (xy 162.751008 -373.455946)
			(xy 162.75431 -373.481854) (xy 162.821112 -373.572532) (xy 162.844734 -373.583454) (xy 162.857942 -373.582438)
			(xy 162.886644 -373.581422) (xy 162.913895 -373.581851) (xy 162.967843 -373.589613) (xy 163.020136 -373.604973)
			(xy 163.069712 -373.627619) (xy 163.11556 -373.657088) (xy 163.156748 -373.692783) (xy 163.192438 -373.733975)
			(xy 163.221902 -373.779827) (xy 163.244542 -373.829405) (xy 163.259896 -373.881701) (xy 163.267652 -373.935649)
			(xy 163.267652 -373.990151) (xy 163.259896 -374.044099) (xy 163.244542 -374.096395) (xy 163.221902 -374.145973)
			(xy 163.192438 -374.191825) (xy 163.156748 -374.233017) (xy 163.11556 -374.268712) (xy 163.069712 -374.298181)
			(xy 163.020136 -374.320827) (xy 162.967843 -374.336187) (xy 162.913895 -374.343949) (xy 162.886644 -374.344438)
			(xy 162.857942 -374.343422) (xy 162.844734 -374.342406) (xy 162.821112 -374.353328) (xy 162.75431 -374.444006)
			(xy 162.751008 -374.469914) (xy 162.756088 -374.48236) (xy 162.764638 -374.504866) (xy 162.776637 -374.551491)
			(xy 162.782664 -374.599257) (xy 162.783012 -374.62333) (xy 162.782526 -374.650581) (xy 162.77477 -374.704529)
			(xy 162.759415 -374.756824) (xy 162.736773 -374.806401) (xy 162.707307 -374.852251) (xy 162.671616 -374.893442)
			(xy 162.630425 -374.929133) (xy 162.584575 -374.958599) (xy 162.534998 -374.981241) (xy 162.482703 -374.996596)
			(xy 162.428755 -375.004352) (xy 162.374253 -375.004352) (xy 162.320305 -374.996596) (xy 162.26801 -374.981241)
			(xy 162.218433 -374.958599) (xy 162.172583 -374.929133) (xy 162.131392 -374.893442) (xy 162.095701 -374.852251)
			(xy 162.066235 -374.806401) (xy 162.043593 -374.756824) (xy 162.028238 -374.704529) (xy 162.020482 -374.650581)
			(xy 162.019996 -374.62333) (xy 162.020553 -374.593893) (xy 162.029613 -374.53572) (xy 162.03803 -374.507506)
			(xy 162.040413 -374.498901) (xy 162.039626 -374.481074) (xy 162.036506 -374.472708) (xy 162.024568 -374.444514)
			(xy 162.020719 -374.436295) (xy 162.00837 -374.423014) (xy 162.000438 -374.418606) (xy 161.97474 -374.405446)
			(xy 161.926237 -374.374123) (xy 161.903664 -374.356122) (xy 161.896653 -374.350869) (xy 161.880159 -374.345014)
			(xy 161.871406 -374.344692) (xy 161.717482 -374.344692) (xy 161.708735 -374.34505) (xy 161.692244 -374.350891)
			(xy 161.685224 -374.356122) (xy 161.662641 -374.374109) (xy 161.614136 -374.405425) (xy 161.58845 -374.418606)
			(xy 161.580492 -374.422979) (xy 161.568137 -374.436273) (xy 161.56432 -374.444514) (xy 161.552382 -374.472708)
			(xy 161.549334 -374.481088) (xy 161.54856 -374.49889) (xy 161.550858 -374.507506) (xy 161.559299 -374.535714)
			(xy 161.568351 -374.593891) (xy 161.568892 -374.62333) (xy 161.568406 -374.650581) (xy 161.56065 -374.704529)
			(xy 161.545295 -374.756824) (xy 161.522653 -374.806401) (xy 161.493187 -374.852251) (xy 161.457496 -374.893442)
			(xy 161.416305 -374.929133) (xy 161.370455 -374.958599) (xy 161.320878 -374.981241) (xy 161.268583 -374.996596)
			(xy 161.214635 -375.004352) (xy 161.160133 -375.004352) (xy 161.106185 -374.996596) (xy 161.05389 -374.981241)
			(xy 161.004313 -374.958599) (xy 160.958463 -374.929133) (xy 160.917272 -374.893442) (xy 160.881581 -374.852251)
			(xy 160.852115 -374.806401) (xy 160.829473 -374.756824) (xy 160.814118 -374.704529) (xy 160.806362 -374.650581)
			(xy 160.805876 -374.62333) (xy 160.806223 -374.599258) (xy 160.812266 -374.551495) (xy 160.824261 -374.504869)
			(xy 160.8328 -374.48236) (xy 160.83788 -374.469914) (xy 160.834578 -374.444006) (xy 160.767776 -374.353328)
			(xy 160.744154 -374.342406) (xy 160.730946 -374.343422) (xy 160.702244 -374.344438) (xy 160.674991 -374.343918)
			(xy 160.62104 -374.336166) (xy 160.568741 -374.320815) (xy 160.519159 -374.298177) (xy 160.473304 -374.268713)
			(xy 160.432109 -374.233022) (xy 160.396414 -374.191831) (xy 160.366944 -374.14598) (xy 160.3443 -374.096401)
			(xy 160.328943 -374.044103) (xy 160.321185 -373.990153) (xy 156.460452 -373.990153) (xy 156.452696 -374.044099)
			(xy 156.437342 -374.096395) (xy 156.414702 -374.145973) (xy 156.385238 -374.191825) (xy 156.349548 -374.233017)
			(xy 156.30836 -374.268712) (xy 156.262512 -374.298181) (xy 156.212936 -374.320827) (xy 156.160643 -374.336187)
			(xy 156.106695 -374.343949) (xy 156.079444 -374.344438) (xy 156.050742 -374.343422) (xy 156.037534 -374.342406)
			(xy 156.013912 -374.353328) (xy 155.94711 -374.444006) (xy 155.943808 -374.469914) (xy 155.948888 -374.48236)
			(xy 155.957438 -374.504866) (xy 155.969437 -374.551491) (xy 155.975464 -374.599257) (xy 155.975812 -374.62333)
			(xy 155.975326 -374.650581) (xy 155.96757 -374.704529) (xy 155.952215 -374.756824) (xy 155.929573 -374.806401)
			(xy 155.900107 -374.852251) (xy 155.864416 -374.893442) (xy 155.823225 -374.929133) (xy 155.777375 -374.958599)
			(xy 155.727798 -374.981241) (xy 155.675503 -374.996596) (xy 155.621555 -375.004352) (xy 155.567053 -375.004352)
			(xy 155.513105 -374.996596) (xy 155.46081 -374.981241) (xy 155.411233 -374.958599) (xy 155.365383 -374.929133)
			(xy 155.324192 -374.893442) (xy 155.288501 -374.852251) (xy 155.259035 -374.806401) (xy 155.236393 -374.756824)
			(xy 155.221038 -374.704529) (xy 155.213282 -374.650581) (xy 155.212796 -374.62333) (xy 155.213353 -374.593893)
			(xy 155.222413 -374.53572) (xy 155.23083 -374.507506) (xy 155.233213 -374.498901) (xy 155.232426 -374.481074)
			(xy 155.229306 -374.472708) (xy 155.217368 -374.444514) (xy 155.213519 -374.436295) (xy 155.20117 -374.423014)
			(xy 155.193238 -374.418606) (xy 155.16754 -374.405446) (xy 155.119037 -374.374123) (xy 155.096464 -374.356122)
			(xy 155.089453 -374.350869) (xy 155.072959 -374.345014) (xy 155.064206 -374.344692) (xy 154.910282 -374.344692)
			(xy 154.901535 -374.34505) (xy 154.885044 -374.350891) (xy 154.878024 -374.356122) (xy 154.855441 -374.374109)
			(xy 154.806936 -374.405425) (xy 154.78125 -374.418606) (xy 154.773292 -374.422979) (xy 154.760937 -374.436273)
			(xy 154.75712 -374.444514) (xy 154.745182 -374.472708) (xy 154.742134 -374.481088) (xy 154.74136 -374.49889)
			(xy 154.743658 -374.507506) (xy 154.752099 -374.535714) (xy 154.761151 -374.593891) (xy 154.761692 -374.62333)
			(xy 154.761206 -374.650581) (xy 154.75345 -374.704529) (xy 154.738095 -374.756824) (xy 154.715453 -374.806401)
			(xy 154.685987 -374.852251) (xy 154.650296 -374.893442) (xy 154.609105 -374.929133) (xy 154.563255 -374.958599)
			(xy 154.513678 -374.981241) (xy 154.461383 -374.996596) (xy 154.407435 -375.004352) (xy 154.352933 -375.004352)
			(xy 154.298985 -374.996596) (xy 154.24669 -374.981241) (xy 154.197113 -374.958599) (xy 154.151263 -374.929133)
			(xy 154.110072 -374.893442) (xy 154.074381 -374.852251) (xy 154.044915 -374.806401) (xy 154.022273 -374.756824)
			(xy 154.006918 -374.704529) (xy 153.999162 -374.650581) (xy 153.998676 -374.62333) (xy 153.999023 -374.599258)
			(xy 154.005066 -374.551495) (xy 154.017061 -374.504869) (xy 154.0256 -374.48236) (xy 154.03068 -374.469914)
			(xy 154.027378 -374.444006) (xy 153.960576 -374.353328) (xy 153.936954 -374.342406) (xy 153.923746 -374.343422)
			(xy 153.895044 -374.344438) (xy 153.867791 -374.343918) (xy 153.81384 -374.336166) (xy 153.761541 -374.320815)
			(xy 153.711959 -374.298177) (xy 153.666104 -374.268713) (xy 153.624909 -374.233022) (xy 153.589214 -374.191831)
			(xy 153.559744 -374.14598) (xy 153.5371 -374.096401) (xy 153.521743 -374.044103) (xy 153.513985 -373.990153)
			(xy 149.653252 -373.990153) (xy 149.645496 -374.044099) (xy 149.630142 -374.096395) (xy 149.607502 -374.145973)
			(xy 149.578038 -374.191825) (xy 149.542348 -374.233017) (xy 149.50116 -374.268712) (xy 149.455312 -374.298181)
			(xy 149.405736 -374.320827) (xy 149.353443 -374.336187) (xy 149.299495 -374.343949) (xy 149.272244 -374.344438)
			(xy 149.243542 -374.343422) (xy 149.230334 -374.342406) (xy 149.206712 -374.353328) (xy 149.13991 -374.444006)
			(xy 149.136608 -374.469914) (xy 149.141688 -374.48236) (xy 149.150238 -374.504866) (xy 149.162237 -374.551491)
			(xy 149.168264 -374.599257) (xy 149.168612 -374.62333) (xy 149.168126 -374.650581) (xy 149.16037 -374.704529)
			(xy 149.145015 -374.756824) (xy 149.122373 -374.806401) (xy 149.092907 -374.852251) (xy 149.057216 -374.893442)
			(xy 149.016025 -374.929133) (xy 148.970175 -374.958599) (xy 148.920598 -374.981241) (xy 148.868303 -374.996596)
			(xy 148.814355 -375.004352) (xy 148.759853 -375.004352) (xy 148.705905 -374.996596) (xy 148.65361 -374.981241)
			(xy 148.604033 -374.958599) (xy 148.558183 -374.929133) (xy 148.516992 -374.893442) (xy 148.481301 -374.852251)
			(xy 148.451835 -374.806401) (xy 148.429193 -374.756824) (xy 148.413838 -374.704529) (xy 148.406082 -374.650581)
			(xy 148.405596 -374.62333) (xy 148.406153 -374.593893) (xy 148.415213 -374.53572) (xy 148.42363 -374.507506)
			(xy 148.426013 -374.498901) (xy 148.425226 -374.481074) (xy 148.422106 -374.472708) (xy 148.410168 -374.444514)
			(xy 148.406319 -374.436295) (xy 148.39397 -374.423014) (xy 148.386038 -374.418606) (xy 148.36034 -374.405446)
			(xy 148.311837 -374.374123) (xy 148.289264 -374.356122) (xy 148.282253 -374.350869) (xy 148.265759 -374.345014)
			(xy 148.257006 -374.344692) (xy 148.103082 -374.344692) (xy 148.094335 -374.34505) (xy 148.077844 -374.350891)
			(xy 148.070824 -374.356122) (xy 148.048241 -374.374109) (xy 147.999736 -374.405425) (xy 147.97405 -374.418606)
			(xy 147.966092 -374.422979) (xy 147.953737 -374.436273) (xy 147.94992 -374.444514) (xy 147.937982 -374.472708)
			(xy 147.934934 -374.481088) (xy 147.93416 -374.49889) (xy 147.936458 -374.507506) (xy 147.944899 -374.535714)
			(xy 147.953951 -374.593891) (xy 147.954492 -374.62333) (xy 147.954006 -374.650581) (xy 147.94625 -374.704529)
			(xy 147.930895 -374.756824) (xy 147.908253 -374.806401) (xy 147.878787 -374.852251) (xy 147.843096 -374.893442)
			(xy 147.801905 -374.929133) (xy 147.756055 -374.958599) (xy 147.706478 -374.981241) (xy 147.654183 -374.996596)
			(xy 147.600235 -375.004352) (xy 147.545733 -375.004352) (xy 147.491785 -374.996596) (xy 147.43949 -374.981241)
			(xy 147.389913 -374.958599) (xy 147.344063 -374.929133) (xy 147.302872 -374.893442) (xy 147.267181 -374.852251)
			(xy 147.237715 -374.806401) (xy 147.215073 -374.756824) (xy 147.199718 -374.704529) (xy 147.191962 -374.650581)
			(xy 147.191476 -374.62333) (xy 147.191823 -374.599258) (xy 147.197866 -374.551495) (xy 147.209861 -374.504869)
			(xy 147.2184 -374.48236) (xy 147.22348 -374.469914) (xy 147.220178 -374.444006) (xy 147.153376 -374.353328)
			(xy 147.129754 -374.342406) (xy 147.116546 -374.343422) (xy 147.087844 -374.344438) (xy 147.060591 -374.343918)
			(xy 147.00664 -374.336166) (xy 146.954341 -374.320815) (xy 146.904759 -374.298177) (xy 146.858904 -374.268713)
			(xy 146.817709 -374.233022) (xy 146.782014 -374.191831) (xy 146.752544 -374.14598) (xy 146.7299 -374.096401)
			(xy 146.714543 -374.044103) (xy 146.706785 -373.990153) (xy 142.919958 -373.990153) (xy 142.919958 -375.945256)
			(xy 169.863923 -375.945256) (xy 169.863923 -375.890744) (xy 169.871681 -375.836786) (xy 169.88704 -375.784482)
			(xy 169.909686 -375.734896) (xy 169.939159 -375.689038) (xy 169.974858 -375.647841) (xy 170.016057 -375.612144)
			(xy 170.061917 -375.582674) (xy 170.111504 -375.560031) (xy 170.16381 -375.544676) (xy 170.217768 -375.536921)
			(xy 170.245024 -375.53646) (xy 170.269095 -375.536822) (xy 170.316858 -375.542859) (xy 170.363484 -375.554848)
			(xy 170.385994 -375.563384) (xy 170.39844 -375.568464) (xy 170.424348 -375.565162) (xy 170.515026 -375.49836)
			(xy 170.525948 -375.474738) (xy 170.524932 -375.46153) (xy 170.523916 -375.432828) (xy 170.524381 -375.405575)
			(xy 170.532135 -375.351623) (xy 170.547489 -375.299323) (xy 170.57013 -375.249742) (xy 170.599597 -375.203887)
			(xy 170.635291 -375.162694) (xy 170.676484 -375.127) (xy 170.722338 -375.097532) (xy 170.77192 -375.07489)
			(xy 170.824219 -375.059536) (xy 170.878171 -375.051782) (xy 170.905424 -375.05132) (xy 170.931932 -375.051808)
			(xy 170.984434 -375.059165) (xy 171.035413 -375.073719) (xy 171.083886 -375.095191) (xy 171.12892 -375.123167)
			(xy 171.169646 -375.157108) (xy 171.205282 -375.19636) (xy 171.235141 -375.240168) (xy 171.258647 -375.287688)
			(xy 171.275348 -375.338004) (xy 171.280582 -375.363994) (xy 171.282614 -375.374408) (xy 171.293536 -375.391172)
			(xy 171.37126 -375.443496) (xy 171.391072 -375.447306) (xy 171.401232 -375.445274) (xy 171.420325 -375.441603)
			(xy 171.459007 -375.437654) (xy 171.478448 -375.4374) (xy 171.505698 -375.437873) (xy 171.559641 -375.445635)
			(xy 171.611931 -375.460995) (xy 171.661504 -375.483639) (xy 171.707349 -375.513107) (xy 171.748534 -375.5488)
			(xy 171.784221 -375.58999) (xy 171.813684 -375.635839) (xy 171.836322 -375.685414) (xy 171.851675 -375.737706)
			(xy 171.85943 -375.79165) (xy 171.85943 -375.84615) (xy 171.851675 -375.900094) (xy 171.836322 -375.952386)
			(xy 171.813684 -376.001961) (xy 171.784221 -376.04781) (xy 171.748534 -376.089) (xy 171.707349 -376.124693)
			(xy 171.661504 -376.154161) (xy 171.611931 -376.176805) (xy 171.559641 -376.192165) (xy 171.505698 -376.199927)
			(xy 171.478448 -376.200416) (xy 171.446698 -376.199146) (xy 171.435006 -376.198748) (xy 171.413226 -376.207195)
			(xy 171.39744 -376.224416) (xy 171.393612 -376.235468) (xy 171.383522 -376.268169) (xy 171.355772 -376.330726)
			(xy 171.319879 -376.388993) (xy 171.298616 -376.415808) (xy 171.293308 -376.4228) (xy 171.287342 -376.439297)
			(xy 171.286932 -376.448066) (xy 171.286932 -376.49658) (xy 173.226991 -376.49658) (xy 173.230998 -376.311676)
			(xy 173.243011 -376.127118) (xy 173.263007 -375.943254) (xy 173.290949 -375.76043) (xy 173.326785 -375.578987)
			(xy 173.370447 -375.399266) (xy 173.421854 -375.221606) (xy 173.480908 -375.04634) (xy 173.547499 -374.873796)
			(xy 173.621502 -374.704299) (xy 173.702778 -374.538167) (xy 173.791174 -374.375711) (xy 173.886525 -374.217237)
			(xy 173.988651 -374.063042) (xy 174.09736 -373.913416) (xy 174.212449 -373.76864) (xy 174.333702 -373.628985)
			(xy 174.460891 -373.494714) (xy 174.593776 -373.366078) (xy 174.73211 -373.243319) (xy 174.875631 -373.126669)
			(xy 175.02407 -373.016345) (xy 175.17715 -372.912554) (xy 175.334581 -372.815492) (xy 175.49607 -372.725342)
			(xy 175.661312 -372.642271) (xy 175.829998 -372.566436) (xy 176.00181 -372.49798) (xy 176.176426 -372.43703)
			(xy 176.353519 -372.383703) (xy 176.532756 -372.338096) (xy 176.7138 -372.300297) (xy 176.896311 -372.270376)
			(xy 177.079948 -372.248389) (xy 177.264364 -372.234377) (xy 177.449214 -372.228367) (xy 177.634151 -372.230371)
			(xy 177.818828 -372.240384) (xy 178.002898 -372.258387) (xy 178.186014 -372.284348) (xy 178.367835 -372.318216)
			(xy 178.548018 -372.359928) (xy 178.726224 -372.409407) (xy 178.90212 -372.466559) (xy 179.075375 -372.531277)
			(xy 179.080925 -372.533629) (xy 220.78035 -372.533629) (xy 220.78035 -372.469707) (xy 220.788361 -372.406289)
			(xy 220.804258 -372.344375) (xy 220.82779 -372.284942) (xy 220.858584 -372.228927) (xy 220.896157 -372.177212)
			(xy 220.939914 -372.130615) (xy 220.989167 -372.08987) (xy 221.043138 -372.055619) (xy 221.100977 -372.028402)
			(xy 221.16177 -372.008649) (xy 221.22456 -371.996671) (xy 221.288356 -371.992658) (xy 221.352152 -371.996671)
			(xy 221.414942 -372.008649) (xy 221.475735 -372.028402) (xy 221.533574 -372.055619) (xy 221.587545 -372.08987)
			(xy 221.636798 -372.130615) (xy 221.680555 -372.177212) (xy 221.718128 -372.228927) (xy 221.748922 -372.284942)
			(xy 221.772454 -372.344375) (xy 221.788351 -372.406289) (xy 221.796362 -372.469707) (xy 221.796864 -372.501668)
			(xy 221.796362 -372.533629) (xy 221.788351 -372.597047) (xy 221.772454 -372.658961) (xy 221.748922 -372.718394)
			(xy 221.718128 -372.774409) (xy 221.680555 -372.826124) (xy 221.636798 -372.872721) (xy 221.587545 -372.913466)
			(xy 221.533574 -372.947717) (xy 221.475735 -372.974934) (xy 221.414942 -372.994687) (xy 221.352152 -373.006665)
			(xy 221.288356 -373.010679) (xy 221.22456 -373.006665) (xy 221.16177 -372.994687) (xy 221.100977 -372.974934)
			(xy 221.043138 -372.947717) (xy 220.989167 -372.913466) (xy 220.939914 -372.872721) (xy 220.896157 -372.826124)
			(xy 220.858584 -372.774409) (xy 220.82779 -372.718394) (xy 220.804258 -372.658961) (xy 220.788361 -372.597047)
			(xy 220.78035 -372.533629) (xy 179.080925 -372.533629) (xy 179.245664 -372.60344) (xy 179.412667 -372.682911)
			(xy 179.576071 -372.769542) (xy 179.735568 -372.863171) (xy 179.89086 -372.96362) (xy 180.041655 -373.070703)
			(xy 180.118937 -373.130783) (xy 190.098166 -373.130783) (xy 190.098166 -373.066861) (xy 190.106177 -373.003443)
			(xy 190.122074 -372.941529) (xy 190.145606 -372.882096) (xy 190.1764 -372.826081) (xy 190.213973 -372.774366)
			(xy 190.25773 -372.727769) (xy 190.306983 -372.687024) (xy 190.360954 -372.652773) (xy 190.418793 -372.625556)
			(xy 190.479586 -372.605803) (xy 190.542376 -372.593825) (xy 190.606172 -372.589812) (xy 190.669968 -372.593825)
			(xy 190.732758 -372.605803) (xy 190.793551 -372.625556) (xy 190.85139 -372.652773) (xy 190.905361 -372.687024)
			(xy 190.954614 -372.727769) (xy 190.998371 -372.774366) (xy 191.035944 -372.826081) (xy 191.066738 -372.882096)
			(xy 191.09027 -372.941529) (xy 191.106167 -373.003443) (xy 191.114178 -373.066861) (xy 191.11468 -373.098822)
			(xy 191.114178 -373.130783) (xy 191.106167 -373.194201) (xy 191.09027 -373.256115) (xy 191.066738 -373.315548)
			(xy 191.035944 -373.371563) (xy 190.998371 -373.423278) (xy 190.954614 -373.469875) (xy 190.905361 -373.51062)
			(xy 190.85139 -373.544871) (xy 190.793551 -373.572088) (xy 190.732758 -373.591841) (xy 190.669968 -373.603819)
			(xy 190.606172 -373.607833) (xy 190.542376 -373.603819) (xy 190.479586 -373.591841) (xy 190.418793 -373.572088)
			(xy 190.360954 -373.544871) (xy 190.306983 -373.51062) (xy 190.25773 -373.469875) (xy 190.213973 -373.423278)
			(xy 190.1764 -373.371563) (xy 190.145606 -373.315548) (xy 190.122074 -373.256115) (xy 190.106177 -373.194201)
			(xy 190.098166 -373.130783) (xy 180.118937 -373.130783) (xy 180.18767 -373.184217) (xy 180.32863 -373.303949)
			(xy 180.464271 -373.429676) (xy 180.594339 -373.56116) (xy 180.718589 -373.698156) (xy 180.836787 -373.840405)
			(xy 180.948713 -373.98764) (xy 181.054156 -374.139586) (xy 181.152917 -374.295957) (xy 181.244812 -374.45646)
			(xy 181.329668 -374.620792) (xy 181.407326 -374.788647) (xy 181.477639 -374.959707) (xy 181.540476 -375.133653)
			(xy 181.59572 -375.310158) (xy 181.643265 -375.48889) (xy 181.683023 -375.669514) (xy 181.71492 -375.851691)
			(xy 181.738895 -376.035078) (xy 181.754903 -376.219332) (xy 181.762915 -376.404106) (xy 181.763416 -376.49658)
			(xy 181.763134 -376.548607) (xy 190.237866 -376.548607) (xy 190.237866 -376.484685) (xy 190.245877 -376.421267)
			(xy 190.261774 -376.359353) (xy 190.285306 -376.29992) (xy 190.3161 -376.243905) (xy 190.353673 -376.19219)
			(xy 190.39743 -376.145593) (xy 190.446683 -376.104848) (xy 190.500654 -376.070597) (xy 190.558493 -376.04338)
			(xy 190.619286 -376.023627) (xy 190.682076 -376.011649) (xy 190.745872 -376.007636) (xy 190.809668 -376.011649)
			(xy 190.872458 -376.023627) (xy 190.933251 -376.04338) (xy 190.99109 -376.070597) (xy 191.045061 -376.104848)
			(xy 191.094314 -376.145593) (xy 191.138071 -376.19219) (xy 191.175644 -376.243905) (xy 191.206438 -376.29992)
			(xy 191.22997 -376.359353) (xy 191.245867 -376.421267) (xy 191.24829 -376.440446) (xy 192.195448 -376.440446)
			(xy 192.199519 -376.384824) (xy 192.211645 -376.330387) (xy 192.231568 -376.278296) (xy 192.258864 -376.229661)
			(xy 192.29295 -376.185518) (xy 192.333099 -376.146809) (xy 192.378457 -376.114358) (xy 192.428057 -376.088857)
			(xy 192.480841 -376.07085) (xy 192.535684 -376.06072) (xy 192.591418 -376.058683) (xy 192.646855 -376.064783)
			(xy 192.700812 -376.078889) (xy 192.752141 -376.100701) (xy 192.799747 -376.129755) (xy 192.842615 -376.16543)
			(xy 192.879832 -376.206967) (xy 192.910605 -376.25348) (xy 192.934277 -376.303977) (xy 192.950345 -376.357384)
			(xy 192.958465 -376.41256) (xy 192.958974 -376.440446) (xy 198.820276 -376.440446) (xy 198.824347 -376.384824)
			(xy 198.836473 -376.330387) (xy 198.856396 -376.278296) (xy 198.883692 -376.229661) (xy 198.917778 -376.185518)
			(xy 198.957927 -376.146809) (xy 199.003285 -376.114358) (xy 199.052885 -376.088857) (xy 199.105669 -376.07085)
			(xy 199.160512 -376.06072) (xy 199.216246 -376.058683) (xy 199.271683 -376.064783) (xy 199.32564 -376.078889)
			(xy 199.376969 -376.100701) (xy 199.424575 -376.129755) (xy 199.467443 -376.16543) (xy 199.50466 -376.206967)
			(xy 199.535433 -376.25348) (xy 199.559105 -376.303977) (xy 199.575173 -376.357384) (xy 199.583293 -376.41256)
			(xy 199.583802 -376.440446) (xy 199.583293 -376.468332) (xy 199.575173 -376.523508) (xy 199.559105 -376.576915)
			(xy 199.535433 -376.627412) (xy 199.50466 -376.673925) (xy 199.467443 -376.715462) (xy 199.424575 -376.751137)
			(xy 199.376969 -376.780191) (xy 199.32564 -376.802003) (xy 199.271683 -376.816109) (xy 199.216246 -376.822209)
			(xy 199.160512 -376.820172) (xy 199.105669 -376.810042) (xy 199.052885 -376.792035) (xy 199.003285 -376.766534)
			(xy 198.957927 -376.734083) (xy 198.917778 -376.695374) (xy 198.883692 -376.651231) (xy 198.856396 -376.602596)
			(xy 198.836473 -376.550505) (xy 198.824347 -376.496068) (xy 198.820276 -376.440446) (xy 192.958974 -376.440446)
			(xy 192.958465 -376.468332) (xy 192.950345 -376.523508) (xy 192.934277 -376.576915) (xy 192.910605 -376.627412)
			(xy 192.879832 -376.673925) (xy 192.842615 -376.715462) (xy 192.799747 -376.751137) (xy 192.752141 -376.780191)
			(xy 192.700812 -376.802003) (xy 192.646855 -376.816109) (xy 192.591418 -376.822209) (xy 192.535684 -376.820172)
			(xy 192.480841 -376.810042) (xy 192.428057 -376.792035) (xy 192.378457 -376.766534) (xy 192.333099 -376.734083)
			(xy 192.29295 -376.695374) (xy 192.258864 -376.651231) (xy 192.231568 -376.602596) (xy 192.211645 -376.550505)
			(xy 192.199519 -376.496068) (xy 192.195448 -376.440446) (xy 191.24829 -376.440446) (xy 191.253878 -376.484685)
			(xy 191.25438 -376.516646) (xy 191.253878 -376.548607) (xy 191.245867 -376.612025) (xy 191.22997 -376.673939)
			(xy 191.206438 -376.733372) (xy 191.175644 -376.789387) (xy 191.138071 -376.841102) (xy 191.094314 -376.887699)
			(xy 191.045061 -376.928444) (xy 190.99109 -376.962695) (xy 190.933251 -376.989912) (xy 190.872458 -377.009665)
			(xy 190.809668 -377.021643) (xy 190.745872 -377.025657) (xy 190.682076 -377.021643) (xy 190.619286 -377.009665)
			(xy 190.558493 -376.989912) (xy 190.500654 -376.962695) (xy 190.446683 -376.928444) (xy 190.39743 -376.887699)
			(xy 190.353673 -376.841102) (xy 190.3161 -376.789387) (xy 190.285306 -376.733372) (xy 190.261774 -376.673939)
			(xy 190.245877 -376.612025) (xy 190.237866 -376.548607) (xy 181.763134 -376.548607) (xy 181.762915 -376.589054)
			(xy 181.754903 -376.773828) (xy 181.738895 -376.958082) (xy 181.71492 -377.141469) (xy 181.683023 -377.323646)
			(xy 181.643265 -377.50427) (xy 181.596948 -377.678385) (xy 193.900548 -377.678385) (xy 193.900548 -377.593663)
			(xy 193.908601 -377.509326) (xy 193.924635 -377.426136) (xy 193.948503 -377.344846) (xy 193.979991 -377.266194)
			(xy 194.018813 -377.190891) (xy 194.064616 -377.119619) (xy 194.116987 -377.053023) (xy 194.175452 -376.991708)
			(xy 194.23948 -376.936227) (xy 194.308492 -376.887084) (xy 194.381862 -376.844724) (xy 194.458927 -376.809529)
			(xy 194.538989 -376.78182) (xy 194.621322 -376.761846) (xy 194.705181 -376.749789) (xy 194.789806 -376.745758)
			(xy 194.874431 -376.749789) (xy 194.95829 -376.761846) (xy 195.040623 -376.78182) (xy 195.120685 -376.809529)
			(xy 195.19775 -376.844724) (xy 195.27112 -376.887084) (xy 195.340132 -376.936227) (xy 195.40416 -376.991708)
			(xy 195.462625 -377.053023) (xy 195.514996 -377.119619) (xy 195.560799 -377.190891) (xy 195.599621 -377.266194)
			(xy 195.631109 -377.344846) (xy 195.654977 -377.426136) (xy 195.671011 -377.509326) (xy 195.679064 -377.593663)
			(xy 195.679568 -377.636024) (xy 195.679064 -377.678385) (xy 195.671011 -377.762722) (xy 195.654977 -377.845912)
			(xy 195.631109 -377.927202) (xy 195.599621 -378.005854) (xy 195.560799 -378.081157) (xy 195.514996 -378.152429)
			(xy 195.508622 -378.160534) (xy 199.950322 -378.160534) (xy 199.954393 -378.104912) (xy 199.966519 -378.050475)
			(xy 199.986442 -377.998384) (xy 200.013738 -377.949749) (xy 200.047824 -377.905606) (xy 200.087973 -377.866897)
			(xy 200.133331 -377.834446) (xy 200.182931 -377.808945) (xy 200.235715 -377.790938) (xy 200.290558 -377.780808)
			(xy 200.346292 -377.778771) (xy 200.401729 -377.784871) (xy 200.455686 -377.798977) (xy 200.507015 -377.820789)
			(xy 200.552966 -377.848833) (xy 201.918564 -377.848833) (xy 201.918564 -377.784911) (xy 201.926575 -377.721493)
			(xy 201.942472 -377.659579) (xy 201.966004 -377.600146) (xy 201.996798 -377.544131) (xy 202.034371 -377.492416)
			(xy 202.078128 -377.445819) (xy 202.127381 -377.405074) (xy 202.181352 -377.370823) (xy 202.239191 -377.343606)
			(xy 202.299984 -377.323853) (xy 202.362774 -377.311875) (xy 202.42657 -377.307862) (xy 202.490366 -377.311875)
			(xy 202.553156 -377.323853) (xy 202.613949 -377.343606) (xy 202.671788 -377.370823) (xy 202.725759 -377.405074)
			(xy 202.775012 -377.445819) (xy 202.818769 -377.492416) (xy 202.856342 -377.544131) (xy 202.887136 -377.600146)
			(xy 202.910668 -377.659579) (xy 202.926565 -377.721493) (xy 202.934576 -377.784911) (xy 202.935078 -377.816872)
			(xy 202.934576 -377.848833) (xy 202.926565 -377.912251) (xy 202.910668 -377.974165) (xy 202.887136 -378.033598)
			(xy 202.856342 -378.089613) (xy 202.818769 -378.141328) (xy 202.775012 -378.187925) (xy 202.725759 -378.22867)
			(xy 202.671788 -378.262921) (xy 202.613949 -378.290138) (xy 202.553156 -378.309891) (xy 202.490366 -378.321869)
			(xy 202.42657 -378.325883) (xy 202.362774 -378.321869) (xy 202.299984 -378.309891) (xy 202.239191 -378.290138)
			(xy 202.181352 -378.262921) (xy 202.127381 -378.22867) (xy 202.078128 -378.187925) (xy 202.034371 -378.141328)
			(xy 201.996798 -378.089613) (xy 201.966004 -378.033598) (xy 201.942472 -377.974165) (xy 201.926575 -377.912251)
			(xy 201.918564 -377.848833) (xy 200.552966 -377.848833) (xy 200.554621 -377.849843) (xy 200.597489 -377.885518)
			(xy 200.634706 -377.927055) (xy 200.665479 -377.973568) (xy 200.689151 -378.024065) (xy 200.705219 -378.077472)
			(xy 200.713339 -378.132648) (xy 200.713848 -378.160534) (xy 200.713339 -378.18842) (xy 200.705219 -378.243596)
			(xy 200.689151 -378.297003) (xy 200.665479 -378.3475) (xy 200.634706 -378.394013) (xy 200.597489 -378.43555)
			(xy 200.554621 -378.471225) (xy 200.507015 -378.500279) (xy 200.455686 -378.522091) (xy 200.401729 -378.536197)
			(xy 200.346292 -378.542297) (xy 200.290558 -378.54026) (xy 200.235715 -378.53013) (xy 200.182931 -378.512123)
			(xy 200.133331 -378.486622) (xy 200.087973 -378.454171) (xy 200.047824 -378.415462) (xy 200.013738 -378.371319)
			(xy 199.986442 -378.322684) (xy 199.966519 -378.270593) (xy 199.954393 -378.216156) (xy 199.950322 -378.160534)
			(xy 195.508622 -378.160534) (xy 195.462625 -378.219025) (xy 195.40416 -378.28034) (xy 195.340132 -378.335821)
			(xy 195.27112 -378.384964) (xy 195.19775 -378.427324) (xy 195.120685 -378.462519) (xy 195.040623 -378.490228)
			(xy 194.95829 -378.510202) (xy 194.874431 -378.522259) (xy 194.789806 -378.526291) (xy 194.705181 -378.522259)
			(xy 194.621322 -378.510202) (xy 194.538989 -378.490228) (xy 194.458927 -378.462519) (xy 194.381862 -378.427324)
			(xy 194.308492 -378.384964) (xy 194.23948 -378.335821) (xy 194.175452 -378.28034) (xy 194.116987 -378.219025)
			(xy 194.064616 -378.152429) (xy 194.018813 -378.081157) (xy 193.979991 -378.005854) (xy 193.948503 -377.927202)
			(xy 193.924635 -377.845912) (xy 193.908601 -377.762722) (xy 193.900548 -377.678385) (xy 181.596948 -377.678385)
			(xy 181.59572 -377.683002) (xy 181.540476 -377.859507) (xy 181.477639 -378.033453) (xy 181.407326 -378.204513)
			(xy 181.329668 -378.372368) (xy 181.244812 -378.5367) (xy 181.152917 -378.697203) (xy 181.054156 -378.853574)
			(xy 180.948713 -379.00552) (xy 180.836787 -379.152755) (xy 180.718589 -379.295004) (xy 180.594339 -379.432)
			(xy 180.464271 -379.563484) (xy 180.32863 -379.689211) (xy 180.18767 -379.808943) (xy 180.041655 -379.922457)
			(xy 179.89086 -380.02954) (xy 179.735568 -380.129989) (xy 179.576071 -380.223618) (xy 179.412667 -380.310249)
			(xy 179.245664 -380.38972) (xy 179.075375 -380.461883) (xy 178.90212 -380.526601) (xy 178.726224 -380.583753)
			(xy 178.548018 -380.633232) (xy 178.367835 -380.674944) (xy 178.186014 -380.708812) (xy 178.002898 -380.734773)
			(xy 177.818828 -380.752776) (xy 177.634151 -380.762789) (xy 177.449214 -380.764793) (xy 177.264364 -380.758783)
			(xy 177.079948 -380.744771) (xy 176.896311 -380.722784) (xy 176.7138 -380.692863) (xy 176.532756 -380.655064)
			(xy 176.353519 -380.609457) (xy 176.176426 -380.55613) (xy 176.00181 -380.49518) (xy 175.829998 -380.426724)
			(xy 175.661312 -380.350889) (xy 175.49607 -380.267818) (xy 175.334581 -380.177668) (xy 175.17715 -380.080606)
			(xy 175.02407 -379.976815) (xy 174.875631 -379.866491) (xy 174.73211 -379.749841) (xy 174.593776 -379.627082)
			(xy 174.460891 -379.498446) (xy 174.333702 -379.364175) (xy 174.212449 -379.22452) (xy 174.09736 -379.079744)
			(xy 173.988651 -378.930118) (xy 173.886525 -378.775923) (xy 173.791174 -378.617449) (xy 173.702778 -378.454993)
			(xy 173.621502 -378.288861) (xy 173.547499 -378.119364) (xy 173.480908 -377.94682) (xy 173.421854 -377.771554)
			(xy 173.370447 -377.593894) (xy 173.326785 -377.414173) (xy 173.290949 -377.23273) (xy 173.263007 -377.049906)
			(xy 173.243011 -376.866042) (xy 173.230998 -376.681484) (xy 173.226991 -376.49658) (xy 171.286932 -376.49658)
			(xy 171.286932 -376.60199) (xy 171.287312 -376.610765) (xy 171.293286 -376.627267) (xy 171.298616 -376.634248)
			(xy 171.316599 -376.656833) (xy 171.347918 -376.705337) (xy 171.3611 -376.731022) (xy 171.365483 -376.738974)
			(xy 171.37877 -376.751333) (xy 171.387008 -376.755152) (xy 171.415202 -376.76709) (xy 171.423583 -376.770136)
			(xy 171.441384 -376.770912) (xy 171.45 -376.768614) (xy 171.478208 -376.760174) (xy 171.536385 -376.751121)
			(xy 171.565824 -376.75058) (xy 171.593073 -376.751092) (xy 171.647017 -376.758851) (xy 171.699307 -376.774208)
			(xy 171.748879 -376.796849) (xy 171.794725 -376.826315) (xy 171.835911 -376.862006) (xy 171.871599 -376.903194)
			(xy 171.901062 -376.949042) (xy 171.923701 -376.998616) (xy 171.939054 -377.050907) (xy 171.94681 -377.104851)
			(xy 171.94681 -377.159349) (xy 171.939054 -377.213293) (xy 171.923701 -377.265584) (xy 171.901062 -377.315158)
			(xy 171.871599 -377.361006) (xy 171.835911 -377.402194) (xy 171.794725 -377.437885) (xy 171.748879 -377.467351)
			(xy 171.699307 -377.489992) (xy 171.647017 -377.505349) (xy 171.593073 -377.513108) (xy 171.565824 -377.513596)
			(xy 171.541752 -377.513246) (xy 171.493989 -377.507203) (xy 171.447364 -377.49521) (xy 171.424854 -377.486672)
			(xy 171.412408 -377.481592) (xy 171.3865 -377.484894) (xy 171.295822 -377.551696) (xy 171.2849 -377.575318)
			(xy 171.285916 -377.588526) (xy 171.286932 -377.617228) (xy 171.286446 -377.644479) (xy 171.27869 -377.698427)
			(xy 171.263335 -377.750722) (xy 171.240693 -377.800299) (xy 171.211227 -377.846149) (xy 171.175536 -377.88734)
			(xy 171.134345 -377.923031) (xy 171.088495 -377.952497) (xy 171.038918 -377.975139) (xy 170.986623 -377.990494)
			(xy 170.932675 -377.99825) (xy 170.878173 -377.99825) (xy 170.824225 -377.990494) (xy 170.77193 -377.975139)
			(xy 170.722353 -377.952497) (xy 170.676503 -377.923031) (xy 170.635312 -377.88734) (xy 170.599621 -377.846149)
			(xy 170.570155 -377.800299) (xy 170.547513 -377.750722) (xy 170.532158 -377.698427) (xy 170.524402 -377.644479)
			(xy 170.523916 -377.617228) (xy 170.524932 -377.588526) (xy 170.525948 -377.575318) (xy 170.515026 -377.551696)
			(xy 170.424348 -377.484894) (xy 170.39844 -377.481592) (xy 170.385994 -377.486672) (xy 170.363484 -377.49521)
			(xy 170.31686 -377.507213) (xy 170.269096 -377.513245) (xy 170.245024 -377.513596) (xy 170.217769 -377.513159)
			(xy 170.163814 -377.505404) (xy 170.111511 -377.49005) (xy 170.061927 -377.467408) (xy 170.016069 -377.43794)
			(xy 169.974872 -377.402245) (xy 169.939175 -377.36105) (xy 169.909704 -377.315194) (xy 169.887059 -377.265611)
			(xy 169.871701 -377.21331) (xy 169.863943 -377.159355) (xy 169.863943 -377.104845) (xy 169.871701 -377.05089)
			(xy 169.887059 -376.998589) (xy 169.909704 -376.949006) (xy 169.939175 -376.90315) (xy 169.974872 -376.861955)
			(xy 170.016069 -376.82626) (xy 170.061927 -376.796792) (xy 170.111511 -376.77415) (xy 170.163814 -376.758796)
			(xy 170.217769 -376.751041) (xy 170.245024 -376.75058) (xy 170.27446 -376.751149) (xy 170.332634 -376.760201)
			(xy 170.360848 -376.768614) (xy 170.369458 -376.770974) (xy 170.38728 -376.770202) (xy 170.395646 -376.76709)
			(xy 170.42384 -376.755152) (xy 170.432071 -376.751325) (xy 170.445345 -376.73896) (xy 170.449748 -376.731022)
			(xy 170.462922 -376.705332) (xy 170.494235 -376.656824) (xy 170.512232 -376.634248) (xy 170.517511 -376.627237)
			(xy 170.523497 -376.610755) (xy 170.523916 -376.60199) (xy 170.523916 -376.448066) (xy 170.523568 -376.439287)
			(xy 170.517573 -376.422785) (xy 170.512232 -376.415808) (xy 170.494247 -376.393224) (xy 170.46293 -376.34472)
			(xy 170.449748 -376.319034) (xy 170.445332 -376.311103) (xy 170.432069 -376.298732) (xy 170.42384 -376.294904)
			(xy 170.395646 -376.282966) (xy 170.387258 -376.279943) (xy 170.369463 -376.279151) (xy 170.360848 -376.281442)
			(xy 170.332637 -376.289871) (xy 170.274462 -376.298931) (xy 170.245024 -376.299476) (xy 170.217768 -376.299079)
			(xy 170.16381 -376.291324) (xy 170.111504 -376.275969) (xy 170.061917 -376.253326) (xy 170.016057 -376.223856)
			(xy 169.974858 -376.188159) (xy 169.939159 -376.146962) (xy 169.909686 -376.101104) (xy 169.88704 -376.051518)
			(xy 169.871681 -375.999214) (xy 169.863923 -375.945256) (xy 142.919958 -375.945256) (xy 142.919958 -379.348856)
			(xy 169.863923 -379.348856) (xy 169.863923 -379.294344) (xy 169.871681 -379.240386) (xy 169.88704 -379.188082)
			(xy 169.909686 -379.138496) (xy 169.939159 -379.092638) (xy 169.974858 -379.051441) (xy 170.016057 -379.015744)
			(xy 170.061917 -378.986274) (xy 170.111504 -378.963631) (xy 170.16381 -378.948276) (xy 170.217768 -378.940521)
			(xy 170.245024 -378.94006) (xy 170.269095 -378.940422) (xy 170.316858 -378.946459) (xy 170.363484 -378.958448)
			(xy 170.385994 -378.966984) (xy 170.39844 -378.972064) (xy 170.424348 -378.968762) (xy 170.515026 -378.90196)
			(xy 170.525948 -378.878338) (xy 170.524932 -378.86513) (xy 170.523916 -378.836428) (xy 170.524402 -378.809177)
			(xy 170.532158 -378.755229) (xy 170.547513 -378.702934) (xy 170.570155 -378.653357) (xy 170.599621 -378.607507)
			(xy 170.635312 -378.566316) (xy 170.676503 -378.530625) (xy 170.722353 -378.501159) (xy 170.77193 -378.478517)
			(xy 170.824225 -378.463162) (xy 170.878173 -378.455406) (xy 170.932675 -378.455406) (xy 170.986623 -378.463162)
			(xy 171.038918 -378.478517) (xy 171.088495 -378.501159) (xy 171.134345 -378.530625) (xy 171.175536 -378.566316)
			(xy 171.211227 -378.607507) (xy 171.240693 -378.653357) (xy 171.263335 -378.702934) (xy 171.27869 -378.755229)
			(xy 171.286446 -378.809177) (xy 171.286932 -378.836428) (xy 171.285916 -378.86513) (xy 171.2849 -378.878338)
			(xy 171.295822 -378.90196) (xy 171.3865 -378.968762) (xy 171.412408 -378.972064) (xy 171.424854 -378.966984)
			(xy 171.44736 -378.958435) (xy 171.493985 -378.946436) (xy 171.541751 -378.940408) (xy 171.565824 -378.94006)
			(xy 171.593072 -378.940612) (xy 171.647012 -378.94837) (xy 171.6993 -378.963726) (xy 171.74887 -378.986367)
			(xy 171.794713 -379.015831) (xy 171.835897 -379.05152) (xy 171.871583 -379.092706) (xy 171.901045 -379.138551)
			(xy 171.923682 -379.188123) (xy 171.939035 -379.240411) (xy 171.94679 -379.294352) (xy 171.94679 -379.348848)
			(xy 171.939035 -379.402789) (xy 171.923682 -379.455077) (xy 171.901045 -379.504649) (xy 171.871583 -379.550494)
			(xy 171.835897 -379.59168) (xy 171.794713 -379.627369) (xy 171.74887 -379.656833) (xy 171.6993 -379.679474)
			(xy 171.647012 -379.69483) (xy 171.593072 -379.702588) (xy 171.565824 -379.703076) (xy 171.536387 -379.702521)
			(xy 171.478213 -379.69346) (xy 171.45 -379.685042) (xy 171.441396 -379.682658) (xy 171.423568 -379.683446)
			(xy 171.415202 -379.686566) (xy 171.387008 -379.698504) (xy 171.378774 -379.702327) (xy 171.3655 -379.714694)
			(xy 171.3611 -379.722634) (xy 171.347937 -379.74833) (xy 171.316617 -379.796835) (xy 171.298616 -379.819408)
			(xy 171.293308 -379.8264) (xy 171.287342 -379.842897) (xy 171.286932 -379.851666) (xy 171.286932 -380.00559)
			(xy 171.287312 -380.014365) (xy 171.293286 -380.030867) (xy 171.298616 -380.037848) (xy 171.316599 -380.060433)
			(xy 171.347918 -380.108937) (xy 171.3611 -380.134622) (xy 171.365483 -380.142574) (xy 171.37877 -380.154933)
			(xy 171.387008 -380.158752) (xy 171.415202 -380.17069) (xy 171.423583 -380.173736) (xy 171.441384 -380.174512)
			(xy 171.45 -380.172214) (xy 171.478208 -380.163774) (xy 171.536385 -380.154721) (xy 171.565824 -380.15418)
			(xy 171.593073 -380.154692) (xy 171.647017 -380.162451) (xy 171.699307 -380.177808) (xy 171.748879 -380.200449)
			(xy 171.794725 -380.229915) (xy 171.835911 -380.265606) (xy 171.871599 -380.306794) (xy 171.901062 -380.352642)
			(xy 171.923701 -380.402216) (xy 171.939054 -380.454507) (xy 171.94681 -380.508451) (xy 171.94681 -380.562949)
			(xy 171.939054 -380.616893) (xy 171.923701 -380.669184) (xy 171.901062 -380.718758) (xy 171.871599 -380.764606)
			(xy 171.835911 -380.805794) (xy 171.794725 -380.841485) (xy 171.748879 -380.870951) (xy 171.699307 -380.893592)
			(xy 171.647017 -380.908949) (xy 171.593073 -380.916708) (xy 171.565824 -380.917196) (xy 171.541752 -380.916846)
			(xy 171.493989 -380.910803) (xy 171.447364 -380.89881) (xy 171.424854 -380.890272) (xy 171.412408 -380.885192)
			(xy 171.3865 -380.888494) (xy 171.295822 -380.955296) (xy 171.2849 -380.978918) (xy 171.285916 -380.992126)
			(xy 171.286932 -381.020828) (xy 171.286446 -381.048079) (xy 171.27869 -381.102027) (xy 171.263335 -381.154322)
			(xy 171.240693 -381.203899) (xy 171.211227 -381.249749) (xy 171.196099 -381.267208) (xy 188.971428 -381.267208)
			(xy 188.97193 -381.235247) (xy 188.979941 -381.171829) (xy 188.995838 -381.109915) (xy 189.01937 -381.050482)
			(xy 189.050164 -380.994467) (xy 189.087737 -380.942752) (xy 189.131494 -380.896155) (xy 189.180747 -380.85541)
			(xy 189.234718 -380.821159) (xy 189.292557 -380.793942) (xy 189.35335 -380.774189) (xy 189.41614 -380.762211)
			(xy 189.479936 -380.758198) (xy 189.543732 -380.762211) (xy 189.606522 -380.774189) (xy 189.667315 -380.793942)
			(xy 189.725154 -380.821159) (xy 189.779125 -380.85541) (xy 189.828378 -380.896155) (xy 189.872135 -380.942752)
			(xy 189.909708 -380.994467) (xy 189.940502 -381.050482) (xy 189.964034 -381.109915) (xy 189.979931 -381.171829)
			(xy 189.987942 -381.235247) (xy 189.988444 -381.267208) (xy 189.988 -381.296633) (xy 189.981212 -381.35509)
			(xy 189.967728 -381.412375) (xy 189.947728 -381.467722) (xy 189.921478 -381.520393) (xy 189.889329 -381.569686)
			(xy 189.870842 -381.592582) (xy 189.865192 -381.600046) (xy 189.859202 -381.617765) (xy 189.859158 -381.627126)
			(xy 189.860428 -381.65786) (xy 189.861238 -381.6672) (xy 189.868659 -381.684398) (xy 189.874906 -381.691388)
			(xy 189.897613 -381.715229) (xy 189.937316 -381.76775) (xy 189.969906 -381.824958) (xy 189.994836 -381.885895)
			(xy 190.01169 -381.949541) (xy 190.020185 -382.01483) (xy 190.020702 -382.04775) (xy 190.020207 -382.08012)
			(xy 190.011988 -382.144337) (xy 189.99569 -382.206992) (xy 189.971576 -382.267074) (xy 189.940036 -382.323611)
			(xy 189.901578 -382.375691) (xy 189.856825 -382.422472) (xy 189.83198 -382.443228) (xy 189.824779 -382.449573)
			(xy 189.815383 -382.466292) (xy 189.813692 -382.47574) (xy 189.809374 -382.506728) (xy 189.80848 -382.516156)
			(xy 189.812922 -382.534554) (xy 189.81801 -382.542542) (xy 189.834106 -382.56668) (xy 189.859647 -382.618768)
			(xy 189.877009 -382.674123) (xy 189.885793 -382.731467) (xy 189.886336 -382.760474) (xy 189.88585 -382.787725)
			(xy 189.878094 -382.841673) (xy 189.862739 -382.893968) (xy 189.840097 -382.943545) (xy 189.810631 -382.989395)
			(xy 189.77494 -383.030586) (xy 189.733749 -383.066277) (xy 189.687899 -383.095743) (xy 189.638322 -383.118385)
			(xy 189.586027 -383.13374) (xy 189.532079 -383.141496) (xy 189.477577 -383.141496) (xy 189.423629 -383.13374)
			(xy 189.371334 -383.118385) (xy 189.321757 -383.095743) (xy 189.275907 -383.066277) (xy 189.234716 -383.030586)
			(xy 189.199025 -382.989395) (xy 189.169559 -382.943545) (xy 189.146917 -382.893968) (xy 189.131562 -382.841673)
			(xy 189.123806 -382.787725) (xy 189.12332 -382.760474) (xy 189.123886 -382.730487) (xy 189.133272 -382.671252)
			(xy 189.151809 -382.614214) (xy 189.179041 -382.560779) (xy 189.196218 -382.536192) (xy 189.201488 -382.528266)
			(xy 189.206318 -382.50987) (xy 189.205616 -382.500378) (xy 189.20206 -382.46939) (xy 189.200523 -382.459868)
			(xy 189.191379 -382.4429) (xy 189.18428 -382.43637) (xy 189.16041 -382.415645) (xy 189.117518 -382.369205)
			(xy 189.080715 -382.317805) (xy 189.050568 -382.262239) (xy 189.027543 -382.203364) (xy 189.011994 -382.142089)
			(xy 189.004163 -382.079359) (xy 189.003686 -382.04775) (xy 189.004099 -382.018324) (xy 189.010892 -381.959865)
			(xy 189.024382 -381.90258) (xy 189.044388 -381.847233) (xy 189.070643 -381.794562) (xy 189.102798 -381.745271)
			(xy 189.121288 -381.722376) (xy 189.126916 -381.714898) (xy 189.132919 -381.69719) (xy 189.132972 -381.687832)
			(xy 189.131702 -381.657098) (xy 189.130904 -381.647756) (xy 189.123474 -381.630559) (xy 189.117224 -381.62357)
			(xy 189.094533 -381.599715) (xy 189.05483 -381.547196) (xy 189.02224 -381.48999) (xy 188.997307 -381.429056)
			(xy 188.980449 -381.365413) (xy 188.971949 -381.300127) (xy 188.971428 -381.267208) (xy 171.196099 -381.267208)
			(xy 171.175536 -381.29094) (xy 171.134345 -381.326631) (xy 171.088495 -381.356097) (xy 171.038918 -381.378739)
			(xy 170.986623 -381.394094) (xy 170.932675 -381.40185) (xy 170.878173 -381.40185) (xy 170.824225 -381.394094)
			(xy 170.77193 -381.378739) (xy 170.722353 -381.356097) (xy 170.676503 -381.326631) (xy 170.635312 -381.29094)
			(xy 170.599621 -381.249749) (xy 170.570155 -381.203899) (xy 170.547513 -381.154322) (xy 170.532158 -381.102027)
			(xy 170.524402 -381.048079) (xy 170.523916 -381.020828) (xy 170.524932 -380.992126) (xy 170.525948 -380.978918)
			(xy 170.515026 -380.955296) (xy 170.424348 -380.888494) (xy 170.39844 -380.885192) (xy 170.385994 -380.890272)
			(xy 170.363484 -380.89881) (xy 170.31686 -380.910813) (xy 170.269096 -380.916845) (xy 170.245024 -380.917196)
			(xy 170.217769 -380.916759) (xy 170.163814 -380.909004) (xy 170.111511 -380.89365) (xy 170.061927 -380.871008)
			(xy 170.016069 -380.84154) (xy 169.974872 -380.805845) (xy 169.939175 -380.76465) (xy 169.909704 -380.718794)
			(xy 169.887059 -380.669211) (xy 169.871701 -380.61691) (xy 169.863943 -380.562955) (xy 169.863943 -380.508445)
			(xy 169.871701 -380.45449) (xy 169.887059 -380.402189) (xy 169.909704 -380.352606) (xy 169.939175 -380.30675)
			(xy 169.974872 -380.265555) (xy 170.016069 -380.22986) (xy 170.061927 -380.200392) (xy 170.111511 -380.17775)
			(xy 170.163814 -380.162396) (xy 170.217769 -380.154641) (xy 170.245024 -380.15418) (xy 170.27446 -380.154749)
			(xy 170.332634 -380.163801) (xy 170.360848 -380.172214) (xy 170.369458 -380.174574) (xy 170.38728 -380.173802)
			(xy 170.395646 -380.17069) (xy 170.42384 -380.158752) (xy 170.432071 -380.154925) (xy 170.445345 -380.14256)
			(xy 170.449748 -380.134622) (xy 170.462922 -380.108932) (xy 170.494235 -380.060424) (xy 170.512232 -380.037848)
			(xy 170.517511 -380.030837) (xy 170.523497 -380.014355) (xy 170.523916 -380.00559) (xy 170.523916 -379.851666)
			(xy 170.523568 -379.842887) (xy 170.517573 -379.826385) (xy 170.512232 -379.819408) (xy 170.494247 -379.796824)
			(xy 170.46293 -379.74832) (xy 170.449748 -379.722634) (xy 170.445332 -379.714703) (xy 170.432069 -379.702332)
			(xy 170.42384 -379.698504) (xy 170.395646 -379.686566) (xy 170.387258 -379.683543) (xy 170.369463 -379.682751)
			(xy 170.360848 -379.685042) (xy 170.332637 -379.693471) (xy 170.274462 -379.702531) (xy 170.245024 -379.703076)
			(xy 170.217768 -379.702679) (xy 170.16381 -379.694924) (xy 170.111504 -379.679569) (xy 170.061917 -379.656926)
			(xy 170.016057 -379.627456) (xy 169.974858 -379.591759) (xy 169.939159 -379.550562) (xy 169.909686 -379.504704)
			(xy 169.88704 -379.455118) (xy 169.871681 -379.402814) (xy 169.863923 -379.348856) (xy 142.919958 -379.348856)
			(xy 142.919958 -379.500892) (xy 142.919535 -379.510962) (xy 142.911818 -379.529564) (xy 142.904972 -379.53696)
			(xy 141.666214 -380.775718) (xy 141.659619 -380.783009) (xy 141.651997 -380.801113) (xy 141.651663 -380.820753)
			(xy 141.654784 -380.830074) (xy 141.657678 -380.83744) (xy 142.584422 -380.83744) (xy 142.588493 -380.781818)
			(xy 142.600619 -380.727381) (xy 142.620542 -380.67529) (xy 142.647838 -380.626655) (xy 142.681924 -380.582512)
			(xy 142.722073 -380.543803) (xy 142.767431 -380.511352) (xy 142.817031 -380.485851) (xy 142.869815 -380.467844)
			(xy 142.924658 -380.457714) (xy 142.980392 -380.455677) (xy 143.035829 -380.461777) (xy 143.089786 -380.475883)
			(xy 143.141115 -380.497695) (xy 143.188721 -380.526749) (xy 143.231589 -380.562424) (xy 143.268806 -380.603961)
			(xy 143.299579 -380.650474) (xy 143.323251 -380.700971) (xy 143.339319 -380.754378) (xy 143.347439 -380.809554)
			(xy 143.347948 -380.83744) (xy 143.347439 -380.865326) (xy 143.339319 -380.920502) (xy 143.323251 -380.973909)
			(xy 143.299579 -381.024406) (xy 143.268806 -381.070919) (xy 143.231589 -381.112456) (xy 143.188721 -381.148131)
			(xy 143.141115 -381.177185) (xy 143.089786 -381.198997) (xy 143.035829 -381.213103) (xy 142.980392 -381.219203)
			(xy 142.924658 -381.217166) (xy 142.869815 -381.207036) (xy 142.817031 -381.189029) (xy 142.767431 -381.163528)
			(xy 142.722073 -381.131077) (xy 142.681924 -381.092368) (xy 142.647838 -381.048225) (xy 142.620542 -380.99959)
			(xy 142.600619 -380.947499) (xy 142.588493 -380.893062) (xy 142.584422 -380.83744) (xy 141.657678 -380.83744)
			(xy 141.694408 -380.930912) (xy 141.718792 -380.948438) (xy 141.734032 -380.948946) (xy 141.760551 -380.950465)
			(xy 141.812819 -380.95993) (xy 141.863269 -380.976554) (xy 141.910924 -381.000018) (xy 141.954862 -381.029866)
			(xy 141.994235 -381.065522) (xy 142.028279 -381.106296) (xy 142.056337 -381.151398) (xy 142.077867 -381.199958)
			(xy 142.09245 -381.251035) (xy 142.099806 -381.303641) (xy 142.1003 -381.3302) (xy 142.099837 -381.357453)
			(xy 142.09208 -381.411403) (xy 142.076724 -381.463701) (xy 142.054081 -381.51328) (xy 142.024613 -381.559133)
			(xy 141.988919 -381.600325) (xy 141.947726 -381.636018) (xy 141.901873 -381.665485) (xy 141.852293 -381.688126)
			(xy 141.799995 -381.703481) (xy 141.746045 -381.711237) (xy 141.718792 -381.711708) (xy 141.689354 -381.711164)
			(xy 141.631178 -381.702107) (xy 141.602968 -381.693674) (xy 141.594352 -381.691382) (xy 141.576555 -381.692168)
			(xy 141.56817 -381.695198) (xy 141.539976 -381.707136) (xy 141.514068 -381.731266) (xy 141.500886 -381.756951)
			(xy 141.469567 -381.805454) (xy 141.451584 -381.82804) (xy 141.446246 -381.835018) (xy 141.44026 -381.851521)
			(xy 141.4399 -381.860298) (xy 141.4399 -382.014222) (xy 141.440309 -382.022991) (xy 141.446279 -382.039486)
			(xy 141.451584 -382.04648) (xy 141.469586 -382.069052) (xy 141.500909 -382.117555) (xy 141.514068 -382.143254)
			(xy 141.539976 -382.167384) (xy 141.56817 -382.179322) (xy 141.576536 -382.18243) (xy 141.594357 -382.183196)
			(xy 141.602968 -382.180846) (xy 141.631182 -382.172434) (xy 141.689356 -382.163383) (xy 141.718792 -382.162812)
			(xy 141.746044 -382.163275) (xy 141.799993 -382.17103) (xy 141.852289 -382.186385) (xy 141.901867 -382.209026)
			(xy 141.946157 -382.237488) (xy 168.720516 -382.237488) (xy 168.720977 -382.211274) (xy 168.728133 -382.159337)
			(xy 168.742337 -382.10887) (xy 168.76332 -382.060824) (xy 168.790688 -382.016106) (xy 168.823923 -381.975559)
			(xy 168.862399 -381.939946) (xy 168.905391 -381.909941) (xy 168.928542 -381.897636) (xy 168.941375 -381.890569)
			(xy 168.962611 -381.870402) (xy 168.977251 -381.845038) (xy 168.984089 -381.816562) (xy 168.982565 -381.787316)
			(xy 168.972803 -381.759705) (xy 168.955605 -381.736) (xy 168.94429 -381.726694) (xy 168.921524 -381.708518)
			(xy 168.881256 -381.666423) (xy 168.847857 -381.618695) (xy 168.822104 -381.566443) (xy 168.804597 -381.510883)
			(xy 168.795742 -381.453307) (xy 168.795192 -381.42418) (xy 168.795678 -381.396929) (xy 168.803434 -381.342981)
			(xy 168.818789 -381.290686) (xy 168.841431 -381.241109) (xy 168.870897 -381.195259) (xy 168.906588 -381.154068)
			(xy 168.947779 -381.118377) (xy 168.993629 -381.088911) (xy 169.043206 -381.066269) (xy 169.095501 -381.050914)
			(xy 169.149449 -381.043158) (xy 169.203951 -381.043158) (xy 169.257899 -381.050914) (xy 169.310194 -381.066269)
			(xy 169.359771 -381.088911) (xy 169.405621 -381.118377) (xy 169.446812 -381.154068) (xy 169.482503 -381.195259)
			(xy 169.511969 -381.241109) (xy 169.534611 -381.290686) (xy 169.549966 -381.342981) (xy 169.557722 -381.396929)
			(xy 169.558208 -381.42418) (xy 169.55779 -381.450395) (xy 169.550625 -381.502334) (xy 169.536414 -381.552801)
			(xy 169.515423 -381.600846) (xy 169.48805 -381.645564) (xy 169.45481 -381.686111) (xy 169.41633 -381.721722)
			(xy 169.373334 -381.751728) (xy 169.350182 -381.764032) (xy 169.337377 -381.771139) (xy 169.316157 -381.791304)
			(xy 169.301528 -381.816659) (xy 169.294691 -381.845123) (xy 169.296208 -381.874356) (xy 169.305955 -381.901959)
			(xy 169.32313 -381.925663) (xy 169.334434 -381.934974) (xy 169.35719 -381.953162) (xy 169.397457 -381.995255)
			(xy 169.430857 -382.042981) (xy 169.456611 -382.09523) (xy 169.474121 -382.150788) (xy 169.48298 -382.208362)
			(xy 169.483532 -382.237488) (xy 169.483046 -382.264739) (xy 169.47529 -382.318687) (xy 169.459935 -382.370982)
			(xy 169.437293 -382.420559) (xy 169.407827 -382.466409) (xy 169.372136 -382.5076) (xy 169.330945 -382.543291)
			(xy 169.285095 -382.572757) (xy 169.235518 -382.595399) (xy 169.183223 -382.610754) (xy 169.129275 -382.61851)
			(xy 169.074773 -382.61851) (xy 169.020825 -382.610754) (xy 168.96853 -382.595399) (xy 168.918953 -382.572757)
			(xy 168.873103 -382.543291) (xy 168.831912 -382.5076) (xy 168.796221 -382.466409) (xy 168.766755 -382.420559)
			(xy 168.744113 -382.370982) (xy 168.728758 -382.318687) (xy 168.721002 -382.264739) (xy 168.720516 -382.237488)
			(xy 141.946157 -382.237488) (xy 141.947719 -382.238492) (xy 141.988911 -382.274184) (xy 142.024603 -382.315375)
			(xy 142.05407 -382.361226) (xy 142.076712 -382.410804) (xy 142.092068 -382.463099) (xy 142.099825 -382.517048)
			(xy 142.099825 -382.571552) (xy 142.092068 -382.625501) (xy 142.076712 -382.677796) (xy 142.05407 -382.727374)
			(xy 142.024603 -382.773225) (xy 141.988911 -382.814416) (xy 141.947719 -382.850108) (xy 141.901867 -382.879574)
			(xy 141.852289 -382.902215) (xy 141.799993 -382.91757) (xy 141.746044 -382.925325) (xy 141.718792 -382.925828)
			(xy 141.718538 -382.925828) (xy 141.694508 -382.925464) (xy 141.64683 -382.919422) (xy 141.600291 -382.90743)
			(xy 141.577822 -382.898904) (xy 141.565376 -382.893824) (xy 141.539468 -382.897126) (xy 141.490377 -382.933291)
			(xy 144.656761 -382.933291) (xy 144.656761 -382.881309) (xy 144.664893 -382.829967) (xy 144.680957 -382.78053)
			(xy 144.704556 -382.734214) (xy 144.735111 -382.69216) (xy 144.771868 -382.655404) (xy 144.813923 -382.624851)
			(xy 144.860239 -382.601253) (xy 144.909677 -382.585191) (xy 144.961019 -382.57706) (xy 144.98701 -382.576578)
			(xy 145.010208 -382.576961) (xy 145.056148 -382.583453) (xy 145.100733 -382.596294) (xy 145.143088 -382.615233)
			(xy 145.182384 -382.639899) (xy 145.20037 -382.654556) (xy 145.207482 -382.660652) (xy 145.225008 -382.666748)
			(xy 145.310606 -382.66497) (xy 145.327878 -382.657858) (xy 145.334736 -382.651508) (xy 145.353153 -382.63516)
			(xy 145.393934 -382.607556) (xy 145.438357 -382.586303) (xy 145.48544 -382.571872) (xy 145.534142 -382.56458)
			(xy 145.558764 -382.564132) (xy 145.583601 -382.564579) (xy 145.632718 -382.571998) (xy 145.68017 -382.586689)
			(xy 145.724886 -382.608322) (xy 145.765858 -382.636407) (xy 145.784316 -382.653032) (xy 145.791392 -382.659057)
			(xy 145.808574 -382.6661) (xy 145.817844 -382.666748) (xy 145.849086 -382.66751) (xy 145.858341 -382.667354)
			(xy 145.875794 -382.661229) (xy 145.883122 -382.655572) (xy 145.905655 -382.637365) (xy 145.955796 -382.608358)
			(xy 146.010219 -382.588516) (xy 146.067264 -382.578443) (xy 146.096228 -382.577848) (xy 146.12221 -382.578448)
			(xy 146.173534 -382.586581) (xy 146.222955 -382.602642) (xy 146.269254 -382.626236) (xy 146.311293 -382.656783)
			(xy 146.348036 -382.693529) (xy 146.378578 -382.73557) (xy 146.402168 -382.781871) (xy 146.418226 -382.831293)
			(xy 146.425768 -382.878917) (xy 147.114008 -382.878917) (xy 147.114008 -382.826943) (xy 147.122138 -382.775608)
			(xy 147.138199 -382.726178) (xy 147.161795 -382.679868) (xy 147.192345 -382.63782) (xy 147.229096 -382.601069)
			(xy 147.271144 -382.570519) (xy 147.317454 -382.546923) (xy 147.366884 -382.530862) (xy 147.418219 -382.522732)
			(xy 147.470193 -382.522732) (xy 147.521528 -382.530862) (xy 147.570958 -382.546923) (xy 147.617268 -382.570519)
			(xy 147.659316 -382.601069) (xy 147.696067 -382.63782) (xy 147.726617 -382.679868) (xy 147.750213 -382.726178)
			(xy 147.766274 -382.775608) (xy 147.774404 -382.826943) (xy 147.774914 -382.85293) (xy 147.774404 -382.878917)
			(xy 148.314158 -382.878917) (xy 148.314158 -382.826943) (xy 148.322288 -382.775608) (xy 148.338349 -382.726178)
			(xy 148.361945 -382.679868) (xy 148.392495 -382.63782) (xy 148.429246 -382.601069) (xy 148.471294 -382.570519)
			(xy 148.517604 -382.546923) (xy 148.567034 -382.530862) (xy 148.618369 -382.522732) (xy 148.670343 -382.522732)
			(xy 148.721678 -382.530862) (xy 148.771108 -382.546923) (xy 148.817418 -382.570519) (xy 148.859466 -382.601069)
			(xy 148.896217 -382.63782) (xy 148.926767 -382.679868) (xy 148.950363 -382.726178) (xy 148.966424 -382.775608)
			(xy 148.974554 -382.826943) (xy 148.975064 -382.85293) (xy 148.974554 -382.878917) (xy 149.514054 -382.878917)
			(xy 149.514054 -382.826943) (xy 149.522184 -382.775608) (xy 149.538245 -382.726178) (xy 149.561841 -382.679868)
			(xy 149.592391 -382.63782) (xy 149.629142 -382.601069) (xy 149.67119 -382.570519) (xy 149.7175 -382.546923)
			(xy 149.76693 -382.530862) (xy 149.818265 -382.522732) (xy 149.870239 -382.522732) (xy 149.921574 -382.530862)
			(xy 149.971004 -382.546923) (xy 150.017314 -382.570519) (xy 150.059362 -382.601069) (xy 150.096113 -382.63782)
			(xy 150.126663 -382.679868) (xy 150.150259 -382.726178) (xy 150.16632 -382.775608) (xy 150.17445 -382.826943)
			(xy 150.17496 -382.85293) (xy 150.17445 -382.878917) (xy 150.71395 -382.878917) (xy 150.71395 -382.826943)
			(xy 150.72208 -382.775608) (xy 150.738141 -382.726178) (xy 150.761737 -382.679868) (xy 150.792287 -382.63782)
			(xy 150.829038 -382.601069) (xy 150.871086 -382.570519) (xy 150.917396 -382.546923) (xy 150.966826 -382.530862)
			(xy 151.018161 -382.522732) (xy 151.070135 -382.522732) (xy 151.12147 -382.530862) (xy 151.1709 -382.546923)
			(xy 151.21721 -382.570519) (xy 151.259258 -382.601069) (xy 151.296009 -382.63782) (xy 151.326559 -382.679868)
			(xy 151.350155 -382.726178) (xy 151.366216 -382.775608) (xy 151.374346 -382.826943) (xy 151.374856 -382.85293)
			(xy 151.374346 -382.878917) (xy 151.9141 -382.878917) (xy 151.9141 -382.826943) (xy 151.92223 -382.775608)
			(xy 151.938291 -382.726178) (xy 151.961887 -382.679868) (xy 151.992437 -382.63782) (xy 152.029188 -382.601069)
			(xy 152.071236 -382.570519) (xy 152.117546 -382.546923) (xy 152.166976 -382.530862) (xy 152.218311 -382.522732)
			(xy 152.270285 -382.522732) (xy 152.32162 -382.530862) (xy 152.37105 -382.546923) (xy 152.41736 -382.570519)
			(xy 152.459408 -382.601069) (xy 152.496159 -382.63782) (xy 152.526709 -382.679868) (xy 152.550305 -382.726178)
			(xy 152.566366 -382.775608) (xy 152.574496 -382.826943) (xy 152.575006 -382.85293) (xy 152.574496 -382.878917)
			(xy 153.113996 -382.878917) (xy 153.113996 -382.826943) (xy 153.122126 -382.775608) (xy 153.138187 -382.726178)
			(xy 153.161783 -382.679868) (xy 153.192333 -382.63782) (xy 153.229084 -382.601069) (xy 153.271132 -382.570519)
			(xy 153.317442 -382.546923) (xy 153.366872 -382.530862) (xy 153.418207 -382.522732) (xy 153.470181 -382.522732)
			(xy 153.521516 -382.530862) (xy 153.570946 -382.546923) (xy 153.617256 -382.570519) (xy 153.659304 -382.601069)
			(xy 153.696055 -382.63782) (xy 153.726605 -382.679868) (xy 153.750201 -382.726178) (xy 153.766262 -382.775608)
			(xy 153.774392 -382.826943) (xy 153.774902 -382.85293) (xy 153.774392 -382.878917) (xy 154.314146 -382.878917)
			(xy 154.314146 -382.826943) (xy 154.322276 -382.775608) (xy 154.338337 -382.726178) (xy 154.361933 -382.679868)
			(xy 154.392483 -382.63782) (xy 154.429234 -382.601069) (xy 154.471282 -382.570519) (xy 154.517592 -382.546923)
			(xy 154.567022 -382.530862) (xy 154.618357 -382.522732) (xy 154.670331 -382.522732) (xy 154.721666 -382.530862)
			(xy 154.771096 -382.546923) (xy 154.817406 -382.570519) (xy 154.859454 -382.601069) (xy 154.896205 -382.63782)
			(xy 154.926755 -382.679868) (xy 154.950351 -382.726178) (xy 154.966412 -382.775608) (xy 154.974542 -382.826943)
			(xy 154.975052 -382.85293) (xy 154.974542 -382.878917) (xy 155.514042 -382.878917) (xy 155.514042 -382.826943)
			(xy 155.522172 -382.775608) (xy 155.538233 -382.726178) (xy 155.561829 -382.679868) (xy 155.592379 -382.63782)
			(xy 155.62913 -382.601069) (xy 155.671178 -382.570519) (xy 155.717488 -382.546923) (xy 155.766918 -382.530862)
			(xy 155.818253 -382.522732) (xy 155.870227 -382.522732) (xy 155.921562 -382.530862) (xy 155.970992 -382.546923)
			(xy 156.017302 -382.570519) (xy 156.05935 -382.601069) (xy 156.096101 -382.63782) (xy 156.126651 -382.679868)
			(xy 156.150247 -382.726178) (xy 156.166308 -382.775608) (xy 156.174438 -382.826943) (xy 156.174948 -382.85293)
			(xy 156.174438 -382.878917) (xy 156.713938 -382.878917) (xy 156.713938 -382.826943) (xy 156.722068 -382.775608)
			(xy 156.738129 -382.726178) (xy 156.761725 -382.679868) (xy 156.792275 -382.63782) (xy 156.829026 -382.601069)
			(xy 156.871074 -382.570519) (xy 156.917384 -382.546923) (xy 156.966814 -382.530862) (xy 157.018149 -382.522732)
			(xy 157.070123 -382.522732) (xy 157.121458 -382.530862) (xy 157.170888 -382.546923) (xy 157.217198 -382.570519)
			(xy 157.259246 -382.601069) (xy 157.295997 -382.63782) (xy 157.326547 -382.679868) (xy 157.350143 -382.726178)
			(xy 157.366204 -382.775608) (xy 157.374334 -382.826943) (xy 157.374844 -382.85293) (xy 157.374334 -382.878917)
			(xy 157.914088 -382.878917) (xy 157.914088 -382.826943) (xy 157.922218 -382.775608) (xy 157.938279 -382.726178)
			(xy 157.961875 -382.679868) (xy 157.992425 -382.63782) (xy 158.029176 -382.601069) (xy 158.071224 -382.570519)
			(xy 158.117534 -382.546923) (xy 158.166964 -382.530862) (xy 158.218299 -382.522732) (xy 158.270273 -382.522732)
			(xy 158.321608 -382.530862) (xy 158.371038 -382.546923) (xy 158.417348 -382.570519) (xy 158.459396 -382.601069)
			(xy 158.496147 -382.63782) (xy 158.526697 -382.679868) (xy 158.550293 -382.726178) (xy 158.566354 -382.775608)
			(xy 158.574484 -382.826943) (xy 158.574994 -382.85293) (xy 158.574484 -382.878917) (xy 159.113984 -382.878917)
			(xy 159.113984 -382.826943) (xy 159.122114 -382.775608) (xy 159.138175 -382.726178) (xy 159.161771 -382.679868)
			(xy 159.192321 -382.63782) (xy 159.229072 -382.601069) (xy 159.27112 -382.570519) (xy 159.31743 -382.546923)
			(xy 159.36686 -382.530862) (xy 159.418195 -382.522732) (xy 159.470169 -382.522732) (xy 159.521504 -382.530862)
			(xy 159.570934 -382.546923) (xy 159.617244 -382.570519) (xy 159.659292 -382.601069) (xy 159.696043 -382.63782)
			(xy 159.726593 -382.679868) (xy 159.750189 -382.726178) (xy 159.76625 -382.775608) (xy 159.77438 -382.826943)
			(xy 159.77489 -382.85293) (xy 159.77438 -382.878917) (xy 160.314134 -382.878917) (xy 160.314134 -382.826943)
			(xy 160.322264 -382.775608) (xy 160.338325 -382.726178) (xy 160.361921 -382.679868) (xy 160.392471 -382.63782)
			(xy 160.429222 -382.601069) (xy 160.47127 -382.570519) (xy 160.51758 -382.546923) (xy 160.56701 -382.530862)
			(xy 160.618345 -382.522732) (xy 160.670319 -382.522732) (xy 160.721654 -382.530862) (xy 160.771084 -382.546923)
			(xy 160.817394 -382.570519) (xy 160.859442 -382.601069) (xy 160.896193 -382.63782) (xy 160.926743 -382.679868)
			(xy 160.950339 -382.726178) (xy 160.9664 -382.775608) (xy 160.97453 -382.826943) (xy 160.97504 -382.85293)
			(xy 160.97453 -382.878917) (xy 161.51403 -382.878917) (xy 161.51403 -382.826943) (xy 161.52216 -382.775608)
			(xy 161.538221 -382.726178) (xy 161.561817 -382.679868) (xy 161.592367 -382.63782) (xy 161.629118 -382.601069)
			(xy 161.671166 -382.570519) (xy 161.717476 -382.546923) (xy 161.766906 -382.530862) (xy 161.818241 -382.522732)
			(xy 161.870215 -382.522732) (xy 161.92155 -382.530862) (xy 161.97098 -382.546923) (xy 162.01729 -382.570519)
			(xy 162.059338 -382.601069) (xy 162.096089 -382.63782) (xy 162.126639 -382.679868) (xy 162.150235 -382.726178)
			(xy 162.166296 -382.775608) (xy 162.174426 -382.826943) (xy 162.174936 -382.85293) (xy 162.174426 -382.878917)
			(xy 162.713926 -382.878917) (xy 162.713926 -382.826943) (xy 162.722056 -382.775608) (xy 162.738117 -382.726178)
			(xy 162.761713 -382.679868) (xy 162.792263 -382.63782) (xy 162.829014 -382.601069) (xy 162.871062 -382.570519)
			(xy 162.917372 -382.546923) (xy 162.966802 -382.530862) (xy 163.018137 -382.522732) (xy 163.070111 -382.522732)
			(xy 163.121446 -382.530862) (xy 163.170876 -382.546923) (xy 163.217186 -382.570519) (xy 163.259234 -382.601069)
			(xy 163.295985 -382.63782) (xy 163.326535 -382.679868) (xy 163.350131 -382.726178) (xy 163.366192 -382.775608)
			(xy 163.374322 -382.826943) (xy 163.374832 -382.85293) (xy 163.374322 -382.878917) (xy 163.914076 -382.878917)
			(xy 163.914076 -382.826943) (xy 163.922206 -382.775608) (xy 163.938267 -382.726178) (xy 163.961863 -382.679868)
			(xy 163.992413 -382.63782) (xy 164.029164 -382.601069) (xy 164.071212 -382.570519) (xy 164.117522 -382.546923)
			(xy 164.166952 -382.530862) (xy 164.218287 -382.522732) (xy 164.270261 -382.522732) (xy 164.321596 -382.530862)
			(xy 164.371026 -382.546923) (xy 164.417336 -382.570519) (xy 164.459384 -382.601069) (xy 164.496135 -382.63782)
			(xy 164.526685 -382.679868) (xy 164.550281 -382.726178) (xy 164.566342 -382.775608) (xy 164.574472 -382.826943)
			(xy 164.574982 -382.85293) (xy 164.574472 -382.878917) (xy 165.113972 -382.878917) (xy 165.113972 -382.826943)
			(xy 165.122102 -382.775608) (xy 165.138163 -382.726178) (xy 165.161759 -382.679868) (xy 165.192309 -382.63782)
			(xy 165.22906 -382.601069) (xy 165.271108 -382.570519) (xy 165.317418 -382.546923) (xy 165.366848 -382.530862)
			(xy 165.418183 -382.522732) (xy 165.470157 -382.522732) (xy 165.521492 -382.530862) (xy 165.570922 -382.546923)
			(xy 165.617232 -382.570519) (xy 165.65928 -382.601069) (xy 165.696031 -382.63782) (xy 165.726581 -382.679868)
			(xy 165.750177 -382.726178) (xy 165.766238 -382.775608) (xy 165.774368 -382.826943) (xy 165.774878 -382.85293)
			(xy 165.774368 -382.878917) (xy 165.771949 -382.894193) (xy 166.180945 -382.894193) (xy 166.180945 -382.842207)
			(xy 166.189078 -382.790862) (xy 166.205143 -382.741421) (xy 166.228745 -382.695102) (xy 166.259303 -382.653045)
			(xy 166.296064 -382.616287) (xy 166.338122 -382.585733) (xy 166.384443 -382.562134) (xy 166.433885 -382.546072)
			(xy 166.485231 -382.537943) (xy 166.511224 -382.537462) (xy 166.534999 -382.537839) (xy 166.58206 -382.544648)
			(xy 166.627658 -382.558135) (xy 166.67085 -382.578021) (xy 166.710744 -382.603897) (xy 166.728902 -382.61925)
			(xy 166.736006 -382.624959) (xy 166.753069 -382.631329) (xy 166.762176 -382.631696) (xy 166.793672 -382.631696)
			(xy 166.802771 -382.631288) (xy 166.819822 -382.624923) (xy 166.826946 -382.61925) (xy 166.845129 -382.603931)
			(xy 166.885024 -382.57807) (xy 166.928211 -382.55819) (xy 166.973801 -382.5447) (xy 167.020852 -382.53788)
			(xy 167.044624 -382.537462) (xy 167.070608 -382.538033) (xy 167.121935 -382.546166) (xy 167.171357 -382.562228)
			(xy 167.217659 -382.585823) (xy 167.2597 -382.61637) (xy 167.296445 -382.653118) (xy 167.32699 -382.695161)
			(xy 167.350581 -382.741465) (xy 167.36664 -382.790889) (xy 167.374769 -382.842216) (xy 167.374769 -382.894184)
			(xy 167.36664 -382.945511) (xy 167.350582 -382.994935) (xy 167.32699 -383.041239) (xy 167.296445 -383.083282)
			(xy 167.2597 -383.12003) (xy 167.217659 -383.150577) (xy 167.171357 -383.174172) (xy 167.121935 -383.190234)
			(xy 167.070608 -383.198367) (xy 167.044624 -383.198878) (xy 167.02085 -383.198463) (xy 166.973792 -383.191662)
			(xy 166.928195 -383.178183) (xy 166.885002 -383.158305) (xy 166.845106 -383.132439) (xy 166.826946 -383.11709)
			(xy 166.819833 -383.111394) (xy 166.802777 -383.105018) (xy 166.793672 -383.104644) (xy 166.762176 -383.104644)
			(xy 166.753073 -383.105018) (xy 166.736023 -383.111406) (xy 166.728902 -383.11709) (xy 166.710744 -383.13244)
			(xy 166.670842 -383.158295) (xy 166.627648 -383.178169) (xy 166.582053 -383.191651) (xy 166.534997 -383.198464)
			(xy 166.511224 -383.198878) (xy 166.485231 -383.198457) (xy 166.433885 -383.190328) (xy 166.384443 -383.174266)
			(xy 166.338122 -383.150667) (xy 166.296064 -383.120113) (xy 166.259303 -383.083355) (xy 166.228745 -383.041298)
			(xy 166.205143 -382.994979) (xy 166.189078 -382.945538) (xy 166.180945 -382.894193) (xy 165.771949 -382.894193)
			(xy 165.766238 -382.930252) (xy 165.750177 -382.979682) (xy 165.726581 -383.025992) (xy 165.696031 -383.06804)
			(xy 165.65928 -383.104791) (xy 165.617232 -383.135341) (xy 165.570922 -383.158937) (xy 165.521492 -383.174998)
			(xy 165.470157 -383.183128) (xy 165.418183 -383.183128) (xy 165.366848 -383.174998) (xy 165.317418 -383.158937)
			(xy 165.271108 -383.135341) (xy 165.22906 -383.104791) (xy 165.192309 -383.06804) (xy 165.161759 -383.025992)
			(xy 165.138163 -382.979682) (xy 165.122102 -382.930252) (xy 165.113972 -382.878917) (xy 164.574472 -382.878917)
			(xy 164.566342 -382.930252) (xy 164.550281 -382.979682) (xy 164.526685 -383.025992) (xy 164.496135 -383.06804)
			(xy 164.459384 -383.104791) (xy 164.417336 -383.135341) (xy 164.371026 -383.158937) (xy 164.321596 -383.174998)
			(xy 164.270261 -383.183128) (xy 164.218287 -383.183128) (xy 164.166952 -383.174998) (xy 164.117522 -383.158937)
			(xy 164.071212 -383.135341) (xy 164.029164 -383.104791) (xy 163.992413 -383.06804) (xy 163.961863 -383.025992)
			(xy 163.938267 -382.979682) (xy 163.922206 -382.930252) (xy 163.914076 -382.878917) (xy 163.374322 -382.878917)
			(xy 163.366192 -382.930252) (xy 163.350131 -382.979682) (xy 163.326535 -383.025992) (xy 163.295985 -383.06804)
			(xy 163.259234 -383.104791) (xy 163.217186 -383.135341) (xy 163.170876 -383.158937) (xy 163.121446 -383.174998)
			(xy 163.070111 -383.183128) (xy 163.018137 -383.183128) (xy 162.966802 -383.174998) (xy 162.917372 -383.158937)
			(xy 162.871062 -383.135341) (xy 162.829014 -383.104791) (xy 162.792263 -383.06804) (xy 162.761713 -383.025992)
			(xy 162.738117 -382.979682) (xy 162.722056 -382.930252) (xy 162.713926 -382.878917) (xy 162.174426 -382.878917)
			(xy 162.166296 -382.930252) (xy 162.150235 -382.979682) (xy 162.126639 -383.025992) (xy 162.096089 -383.06804)
			(xy 162.059338 -383.104791) (xy 162.01729 -383.135341) (xy 161.97098 -383.158937) (xy 161.92155 -383.174998)
			(xy 161.870215 -383.183128) (xy 161.818241 -383.183128) (xy 161.766906 -383.174998) (xy 161.717476 -383.158937)
			(xy 161.671166 -383.135341) (xy 161.629118 -383.104791) (xy 161.592367 -383.06804) (xy 161.561817 -383.025992)
			(xy 161.538221 -382.979682) (xy 161.52216 -382.930252) (xy 161.51403 -382.878917) (xy 160.97453 -382.878917)
			(xy 160.9664 -382.930252) (xy 160.950339 -382.979682) (xy 160.926743 -383.025992) (xy 160.896193 -383.06804)
			(xy 160.859442 -383.104791) (xy 160.817394 -383.135341) (xy 160.771084 -383.158937) (xy 160.721654 -383.174998)
			(xy 160.670319 -383.183128) (xy 160.618345 -383.183128) (xy 160.56701 -383.174998) (xy 160.51758 -383.158937)
			(xy 160.47127 -383.135341) (xy 160.429222 -383.104791) (xy 160.392471 -383.06804) (xy 160.361921 -383.025992)
			(xy 160.338325 -382.979682) (xy 160.322264 -382.930252) (xy 160.314134 -382.878917) (xy 159.77438 -382.878917)
			(xy 159.76625 -382.930252) (xy 159.750189 -382.979682) (xy 159.726593 -383.025992) (xy 159.696043 -383.06804)
			(xy 159.659292 -383.104791) (xy 159.617244 -383.135341) (xy 159.570934 -383.158937) (xy 159.521504 -383.174998)
			(xy 159.470169 -383.183128) (xy 159.418195 -383.183128) (xy 159.36686 -383.174998) (xy 159.31743 -383.158937)
			(xy 159.27112 -383.135341) (xy 159.229072 -383.104791) (xy 159.192321 -383.06804) (xy 159.161771 -383.025992)
			(xy 159.138175 -382.979682) (xy 159.122114 -382.930252) (xy 159.113984 -382.878917) (xy 158.574484 -382.878917)
			(xy 158.566354 -382.930252) (xy 158.550293 -382.979682) (xy 158.526697 -383.025992) (xy 158.496147 -383.06804)
			(xy 158.459396 -383.104791) (xy 158.417348 -383.135341) (xy 158.371038 -383.158937) (xy 158.321608 -383.174998)
			(xy 158.270273 -383.183128) (xy 158.218299 -383.183128) (xy 158.166964 -383.174998) (xy 158.117534 -383.158937)
			(xy 158.071224 -383.135341) (xy 158.029176 -383.104791) (xy 157.992425 -383.06804) (xy 157.961875 -383.025992)
			(xy 157.938279 -382.979682) (xy 157.922218 -382.930252) (xy 157.914088 -382.878917) (xy 157.374334 -382.878917)
			(xy 157.366204 -382.930252) (xy 157.350143 -382.979682) (xy 157.326547 -383.025992) (xy 157.295997 -383.06804)
			(xy 157.259246 -383.104791) (xy 157.217198 -383.135341) (xy 157.170888 -383.158937) (xy 157.121458 -383.174998)
			(xy 157.070123 -383.183128) (xy 157.018149 -383.183128) (xy 156.966814 -383.174998) (xy 156.917384 -383.158937)
			(xy 156.871074 -383.135341) (xy 156.829026 -383.104791) (xy 156.792275 -383.06804) (xy 156.761725 -383.025992)
			(xy 156.738129 -382.979682) (xy 156.722068 -382.930252) (xy 156.713938 -382.878917) (xy 156.174438 -382.878917)
			(xy 156.166308 -382.930252) (xy 156.150247 -382.979682) (xy 156.126651 -383.025992) (xy 156.096101 -383.06804)
			(xy 156.05935 -383.104791) (xy 156.017302 -383.135341) (xy 155.970992 -383.158937) (xy 155.921562 -383.174998)
			(xy 155.870227 -383.183128) (xy 155.818253 -383.183128) (xy 155.766918 -383.174998) (xy 155.717488 -383.158937)
			(xy 155.671178 -383.135341) (xy 155.62913 -383.104791) (xy 155.592379 -383.06804) (xy 155.561829 -383.025992)
			(xy 155.538233 -382.979682) (xy 155.522172 -382.930252) (xy 155.514042 -382.878917) (xy 154.974542 -382.878917)
			(xy 154.966412 -382.930252) (xy 154.950351 -382.979682) (xy 154.926755 -383.025992) (xy 154.896205 -383.06804)
			(xy 154.859454 -383.104791) (xy 154.817406 -383.135341) (xy 154.771096 -383.158937) (xy 154.721666 -383.174998)
			(xy 154.670331 -383.183128) (xy 154.618357 -383.183128) (xy 154.567022 -383.174998) (xy 154.517592 -383.158937)
			(xy 154.471282 -383.135341) (xy 154.429234 -383.104791) (xy 154.392483 -383.06804) (xy 154.361933 -383.025992)
			(xy 154.338337 -382.979682) (xy 154.322276 -382.930252) (xy 154.314146 -382.878917) (xy 153.774392 -382.878917)
			(xy 153.766262 -382.930252) (xy 153.750201 -382.979682) (xy 153.726605 -383.025992) (xy 153.696055 -383.06804)
			(xy 153.659304 -383.104791) (xy 153.617256 -383.135341) (xy 153.570946 -383.158937) (xy 153.521516 -383.174998)
			(xy 153.470181 -383.183128) (xy 153.418207 -383.183128) (xy 153.366872 -383.174998) (xy 153.317442 -383.158937)
			(xy 153.271132 -383.135341) (xy 153.229084 -383.104791) (xy 153.192333 -383.06804) (xy 153.161783 -383.025992)
			(xy 153.138187 -382.979682) (xy 153.122126 -382.930252) (xy 153.113996 -382.878917) (xy 152.574496 -382.878917)
			(xy 152.566366 -382.930252) (xy 152.550305 -382.979682) (xy 152.526709 -383.025992) (xy 152.496159 -383.06804)
			(xy 152.459408 -383.104791) (xy 152.41736 -383.135341) (xy 152.37105 -383.158937) (xy 152.32162 -383.174998)
			(xy 152.270285 -383.183128) (xy 152.218311 -383.183128) (xy 152.166976 -383.174998) (xy 152.117546 -383.158937)
			(xy 152.071236 -383.135341) (xy 152.029188 -383.104791) (xy 151.992437 -383.06804) (xy 151.961887 -383.025992)
			(xy 151.938291 -382.979682) (xy 151.92223 -382.930252) (xy 151.9141 -382.878917) (xy 151.374346 -382.878917)
			(xy 151.366216 -382.930252) (xy 151.350155 -382.979682) (xy 151.326559 -383.025992) (xy 151.296009 -383.06804)
			(xy 151.259258 -383.104791) (xy 151.21721 -383.135341) (xy 151.1709 -383.158937) (xy 151.12147 -383.174998)
			(xy 151.070135 -383.183128) (xy 151.018161 -383.183128) (xy 150.966826 -383.174998) (xy 150.917396 -383.158937)
			(xy 150.871086 -383.135341) (xy 150.829038 -383.104791) (xy 150.792287 -383.06804) (xy 150.761737 -383.025992)
			(xy 150.738141 -382.979682) (xy 150.72208 -382.930252) (xy 150.71395 -382.878917) (xy 150.17445 -382.878917)
			(xy 150.16632 -382.930252) (xy 150.150259 -382.979682) (xy 150.126663 -383.025992) (xy 150.096113 -383.06804)
			(xy 150.059362 -383.104791) (xy 150.017314 -383.135341) (xy 149.971004 -383.158937) (xy 149.921574 -383.174998)
			(xy 149.870239 -383.183128) (xy 149.818265 -383.183128) (xy 149.76693 -383.174998) (xy 149.7175 -383.158937)
			(xy 149.67119 -383.135341) (xy 149.629142 -383.104791) (xy 149.592391 -383.06804) (xy 149.561841 -383.025992)
			(xy 149.538245 -382.979682) (xy 149.522184 -382.930252) (xy 149.514054 -382.878917) (xy 148.974554 -382.878917)
			(xy 148.966424 -382.930252) (xy 148.950363 -382.979682) (xy 148.926767 -383.025992) (xy 148.896217 -383.06804)
			(xy 148.859466 -383.104791) (xy 148.817418 -383.135341) (xy 148.771108 -383.158937) (xy 148.721678 -383.174998)
			(xy 148.670343 -383.183128) (xy 148.618369 -383.183128) (xy 148.567034 -383.174998) (xy 148.517604 -383.158937)
			(xy 148.471294 -383.135341) (xy 148.429246 -383.104791) (xy 148.392495 -383.06804) (xy 148.361945 -383.025992)
			(xy 148.338349 -382.979682) (xy 148.322288 -382.930252) (xy 148.314158 -382.878917) (xy 147.774404 -382.878917)
			(xy 147.766274 -382.930252) (xy 147.750213 -382.979682) (xy 147.726617 -383.025992) (xy 147.696067 -383.06804)
			(xy 147.659316 -383.104791) (xy 147.617268 -383.135341) (xy 147.570958 -383.158937) (xy 147.521528 -383.174998)
			(xy 147.470193 -383.183128) (xy 147.418219 -383.183128) (xy 147.366884 -383.174998) (xy 147.317454 -383.158937)
			(xy 147.271144 -383.135341) (xy 147.229096 -383.104791) (xy 147.192345 -383.06804) (xy 147.161795 -383.025992)
			(xy 147.138199 -382.979682) (xy 147.122138 -382.930252) (xy 147.114008 -382.878917) (xy 146.425768 -382.878917)
			(xy 146.426354 -382.882618) (xy 146.426354 -382.934582) (xy 146.418226 -382.985907) (xy 146.402168 -383.035329)
			(xy 146.378578 -383.08163) (xy 146.348036 -383.123671) (xy 146.311293 -383.160417) (xy 146.269254 -383.190964)
			(xy 146.222955 -383.214558) (xy 146.173534 -383.230619) (xy 146.12221 -383.238752) (xy 146.096228 -383.239264)
			(xy 146.071391 -383.238823) (xy 146.022273 -383.231403) (xy 145.974822 -383.21671) (xy 145.930105 -383.195076)
			(xy 145.889133 -383.16699) (xy 145.870676 -383.150364) (xy 145.863602 -383.144335) (xy 145.846419 -383.137294)
			(xy 145.837148 -383.136648) (xy 145.805906 -383.135886) (xy 145.79665 -383.136039) (xy 145.779197 -383.142166)
			(xy 145.77187 -383.147824) (xy 145.749305 -383.165988) (xy 145.699175 -383.195005) (xy 145.644762 -383.214858)
			(xy 145.587725 -383.224945) (xy 145.558764 -383.225548) (xy 145.535568 -383.225117) (xy 145.48963 -383.218636)
			(xy 145.445046 -383.205805) (xy 145.40269 -383.186877) (xy 145.363391 -383.162222) (xy 145.345404 -383.14757)
			(xy 145.338292 -383.141474) (xy 145.320766 -383.135378) (xy 145.235168 -383.137156) (xy 145.217896 -383.144268)
			(xy 145.211038 -383.150618) (xy 145.192595 -383.166936) (xy 145.151821 -383.194543) (xy 145.107404 -383.215801)
			(xy 145.060328 -383.23024) (xy 145.011631 -383.237541) (xy 144.98701 -383.237994) (xy 144.961019 -383.23754)
			(xy 144.909677 -383.229409) (xy 144.860239 -383.213347) (xy 144.813923 -383.189749) (xy 144.771868 -383.159196)
			(xy 144.735111 -383.12244) (xy 144.704556 -383.080386) (xy 144.680957 -383.03407) (xy 144.664893 -382.984633)
			(xy 144.656761 -382.933291) (xy 141.490377 -382.933291) (xy 141.44879 -382.963928) (xy 141.437868 -382.98755)
			(xy 141.438884 -383.000758) (xy 141.4399 -383.02946) (xy 141.439414 -383.056711) (xy 141.431658 -383.110659)
			(xy 141.416303 -383.162954) (xy 141.393661 -383.212531) (xy 141.364195 -383.258381) (xy 141.328504 -383.299572)
			(xy 141.287313 -383.335263) (xy 141.241463 -383.364729) (xy 141.191886 -383.387371) (xy 141.139591 -383.402726)
			(xy 141.085643 -383.410482) (xy 141.031141 -383.410482) (xy 140.977193 -383.402726) (xy 140.924898 -383.387371)
			(xy 140.875321 -383.364729) (xy 140.829471 -383.335263) (xy 140.78828 -383.299572) (xy 140.752589 -383.258381)
			(xy 140.723123 -383.212531) (xy 140.700481 -383.162954) (xy 140.685126 -383.110659) (xy 140.67737 -383.056711)
			(xy 140.676884 -383.02946) (xy 140.6779 -383.000758) (xy 140.678916 -382.98755) (xy 140.667994 -382.963928)
			(xy 140.577316 -382.897126) (xy 140.551408 -382.893824) (xy 140.538962 -382.898904) (xy 140.516492 -382.907425)
			(xy 140.46995 -382.9194) (xy 140.422275 -382.925444) (xy 140.398246 -382.925828) (xy 140.397992 -382.925828)
			(xy 140.37074 -382.925342) (xy 140.31679 -382.917584) (xy 140.264493 -382.902227) (xy 140.214915 -382.879584)
			(xy 140.169063 -382.850116) (xy 140.127871 -382.814423) (xy 140.092179 -382.773231) (xy 140.062712 -382.727378)
			(xy 140.04007 -382.677799) (xy 140.024715 -382.625502) (xy 140.016958 -382.571552) (xy 140.016958 -382.517048)
			(xy 140.024715 -382.463098) (xy 140.04007 -382.410801) (xy 140.062712 -382.361222) (xy 140.092179 -382.315369)
			(xy 140.127871 -382.274177) (xy 140.169063 -382.238484) (xy 140.214915 -382.209016) (xy 140.264493 -382.186373)
			(xy 140.31679 -382.171016) (xy 140.37074 -382.163258) (xy 140.397992 -382.162812) (xy 140.427431 -382.163355)
			(xy 140.485607 -382.17241) (xy 140.513816 -382.180846) (xy 140.522432 -382.18314) (xy 140.540231 -382.182359)
			(xy 140.548614 -382.179322) (xy 140.576808 -382.167384) (xy 140.602716 -382.143254) (xy 140.615897 -382.117568)
			(xy 140.647214 -382.069064) (xy 140.6652 -382.04648) (xy 140.670533 -382.0395) (xy 140.676516 -382.022998)
			(xy 140.676884 -382.014222) (xy 140.676884 -381.860298) (xy 140.67648 -381.851527) (xy 140.670523 -381.835022)
			(xy 140.6652 -381.82804) (xy 140.647202 -381.805465) (xy 140.615886 -381.756959) (xy 140.602716 -381.731266)
			(xy 140.576808 -381.707136) (xy 140.548614 -381.695198) (xy 140.540248 -381.692074) (xy 140.522418 -381.69128)
			(xy 140.513816 -381.693674) (xy 140.485603 -381.702092) (xy 140.427429 -381.711155) (xy 140.397992 -381.711708)
			(xy 140.368852 -381.711163) (xy 140.31125 -381.702308) (xy 140.255666 -381.684792) (xy 140.203394 -381.659021)
			(xy 140.155653 -381.625596) (xy 140.113555 -381.585295) (xy 140.078079 -381.539058) (xy 140.050052 -381.487961)
			(xy 140.039598 -381.460756) (xy 140.03401 -381.445262) (xy 140.008102 -381.427228) (xy 138.34237 -381.427228)
			(xy 138.332302 -381.4268) (xy 138.313702 -381.419081) (xy 138.306302 -381.412242) (xy 138.290046 -381.395986)
			(xy 138.27887 -381.389382) (xy 138.27252 -381.387604) (xy 138.24612 -381.379526) (xy 138.195799 -381.35682)
			(xy 138.149274 -381.3271) (xy 138.107519 -381.290985) (xy 138.071403 -381.24923) (xy 138.041682 -381.202706)
			(xy 138.018975 -381.152384) (xy 138.0109 -381.125984) (xy 138.009122 -381.119634) (xy 138.002518 -381.108458)
			(xy 137.812018 -380.917958) (xy 137.789158 -380.910592) (xy 137.776966 -380.912624) (xy 137.76214 -380.914798)
			(xy 137.73226 -380.91709) (xy 137.717276 -380.917196) (xy 137.690026 -380.916708) (xy 137.636082 -380.908949)
			(xy 137.583791 -380.893591) (xy 137.534217 -380.870949) (xy 137.488371 -380.841482) (xy 137.447184 -380.80579)
			(xy 137.411497 -380.7646) (xy 137.382034 -380.718751) (xy 137.359396 -380.669176) (xy 137.344044 -380.616883)
			(xy 137.336289 -380.562938) (xy 137.335768 -380.535688) (xy 137.335887 -380.520704) (xy 137.338179 -380.490826)
			(xy 137.34034 -380.475998) (xy 137.342372 -380.463806) (xy 137.335006 -380.440946) (xy 132.884164 -375.990104)
			(xy 132.876764 -375.983263) (xy 132.858166 -375.975541) (xy 132.848096 -375.975118) (xy 116.599208 -375.975118)
			(xy 116.589138 -375.97554) (xy 116.570533 -375.983254) (xy 116.56314 -375.990104) (xy 110.315756 -382.237488)
			(xy 136.192258 -382.237488) (xy 136.196329 -382.181866) (xy 136.208455 -382.127429) (xy 136.228378 -382.075338)
			(xy 136.255674 -382.026703) (xy 136.28976 -381.98256) (xy 136.329909 -381.943851) (xy 136.375267 -381.9114)
			(xy 136.424867 -381.885899) (xy 136.477651 -381.867892) (xy 136.532494 -381.857762) (xy 136.588228 -381.855725)
			(xy 136.643665 -381.861825) (xy 136.697622 -381.875931) (xy 136.748951 -381.897743) (xy 136.796557 -381.926797)
			(xy 136.839425 -381.962472) (xy 136.876642 -382.004009) (xy 136.907415 -382.050522) (xy 136.931087 -382.101019)
			(xy 136.947155 -382.154426) (xy 136.955275 -382.209602) (xy 136.955784 -382.237488) (xy 136.955275 -382.265374)
			(xy 136.947155 -382.32055) (xy 136.931087 -382.373957) (xy 136.907415 -382.424454) (xy 136.876642 -382.470967)
			(xy 136.839425 -382.512504) (xy 136.796557 -382.548179) (xy 136.748951 -382.577233) (xy 136.697622 -382.599045)
			(xy 136.643665 -382.613151) (xy 136.588228 -382.619251) (xy 136.532494 -382.617214) (xy 136.477651 -382.607084)
			(xy 136.424867 -382.589077) (xy 136.375267 -382.563576) (xy 136.329909 -382.531125) (xy 136.28976 -382.492416)
			(xy 136.255674 -382.448273) (xy 136.228378 -382.399638) (xy 136.208455 -382.347547) (xy 136.196329 -382.29311)
			(xy 136.192258 -382.237488) (xy 110.315756 -382.237488) (xy 109.619958 -382.933286) (xy 112.129087 -382.933286)
			(xy 112.129087 -382.881314) (xy 112.137217 -382.829981) (xy 112.153277 -382.780551) (xy 112.17687 -382.734242)
			(xy 112.207417 -382.692194) (xy 112.244165 -382.655442) (xy 112.28621 -382.62489) (xy 112.332516 -382.601291)
			(xy 112.381944 -382.585226) (xy 112.433276 -382.57709) (xy 112.459262 -382.576578) (xy 112.482496 -382.576962)
			(xy 112.528508 -382.583464) (xy 112.573155 -382.596343) (xy 112.61556 -382.615348) (xy 112.654885 -382.640102)
			(xy 112.672876 -382.65481) (xy 112.679988 -382.660906) (xy 112.696498 -382.667002) (xy 112.780826 -382.667002)
			(xy 112.797336 -382.660906) (xy 112.804448 -382.65481) (xy 112.822446 -382.640113) (xy 112.861773 -382.615364)
			(xy 112.904176 -382.596363) (xy 112.948821 -382.583481) (xy 112.994829 -382.576974) (xy 113.018062 -382.576578)
			(xy 113.046657 -382.57717) (xy 113.102992 -382.587025) (xy 113.156795 -382.606414) (xy 113.206466 -382.634759)
			(xy 113.228882 -382.652524) (xy 113.23574 -382.658112) (xy 113.252504 -382.664208) (xy 113.3348 -382.664208)
			(xy 113.351564 -382.658366) (xy 113.358422 -382.652778) (xy 113.380786 -382.635141) (xy 113.430303 -382.607006)
			(xy 113.483902 -382.587756) (xy 113.540005 -382.57796) (xy 113.56848 -382.57734) (xy 113.594474 -382.577726)
			(xy 113.645822 -382.585856) (xy 113.695267 -382.601919) (xy 113.74159 -382.625519) (xy 113.78365 -382.656075)
			(xy 113.820412 -382.692835) (xy 113.850971 -382.734893) (xy 113.874574 -382.781215) (xy 113.89064 -382.830658)
			(xy 113.898284 -382.878917) (xy 114.58626 -382.878917) (xy 114.58626 -382.826943) (xy 114.59439 -382.775608)
			(xy 114.610451 -382.726178) (xy 114.634047 -382.679868) (xy 114.664597 -382.63782) (xy 114.701348 -382.601069)
			(xy 114.743396 -382.570519) (xy 114.789706 -382.546923) (xy 114.839136 -382.530862) (xy 114.890471 -382.522732)
			(xy 114.942445 -382.522732) (xy 114.99378 -382.530862) (xy 115.04321 -382.546923) (xy 115.08952 -382.570519)
			(xy 115.131568 -382.601069) (xy 115.168319 -382.63782) (xy 115.198869 -382.679868) (xy 115.222465 -382.726178)
			(xy 115.238526 -382.775608) (xy 115.246656 -382.826943) (xy 115.247166 -382.85293) (xy 115.246656 -382.878917)
			(xy 115.78641 -382.878917) (xy 115.78641 -382.826943) (xy 115.79454 -382.775608) (xy 115.810601 -382.726178)
			(xy 115.834197 -382.679868) (xy 115.864747 -382.63782) (xy 115.901498 -382.601069) (xy 115.943546 -382.570519)
			(xy 115.989856 -382.546923) (xy 116.039286 -382.530862) (xy 116.090621 -382.522732) (xy 116.142595 -382.522732)
			(xy 116.19393 -382.530862) (xy 116.24336 -382.546923) (xy 116.28967 -382.570519) (xy 116.331718 -382.601069)
			(xy 116.368469 -382.63782) (xy 116.399019 -382.679868) (xy 116.422615 -382.726178) (xy 116.438676 -382.775608)
			(xy 116.446806 -382.826943) (xy 116.447316 -382.85293) (xy 116.446806 -382.878917) (xy 116.986306 -382.878917)
			(xy 116.986306 -382.826943) (xy 116.994436 -382.775608) (xy 117.010497 -382.726178) (xy 117.034093 -382.679868)
			(xy 117.064643 -382.63782) (xy 117.101394 -382.601069) (xy 117.143442 -382.570519) (xy 117.189752 -382.546923)
			(xy 117.239182 -382.530862) (xy 117.290517 -382.522732) (xy 117.342491 -382.522732) (xy 117.393826 -382.530862)
			(xy 117.443256 -382.546923) (xy 117.489566 -382.570519) (xy 117.531614 -382.601069) (xy 117.568365 -382.63782)
			(xy 117.598915 -382.679868) (xy 117.622511 -382.726178) (xy 117.638572 -382.775608) (xy 117.646702 -382.826943)
			(xy 117.647212 -382.85293) (xy 117.646702 -382.878917) (xy 118.186202 -382.878917) (xy 118.186202 -382.826943)
			(xy 118.194332 -382.775608) (xy 118.210393 -382.726178) (xy 118.233989 -382.679868) (xy 118.264539 -382.63782)
			(xy 118.30129 -382.601069) (xy 118.343338 -382.570519) (xy 118.389648 -382.546923) (xy 118.439078 -382.530862)
			(xy 118.490413 -382.522732) (xy 118.542387 -382.522732) (xy 118.593722 -382.530862) (xy 118.643152 -382.546923)
			(xy 118.689462 -382.570519) (xy 118.73151 -382.601069) (xy 118.768261 -382.63782) (xy 118.798811 -382.679868)
			(xy 118.822407 -382.726178) (xy 118.838468 -382.775608) (xy 118.846598 -382.826943) (xy 118.847108 -382.85293)
			(xy 118.846598 -382.878917) (xy 119.386352 -382.878917) (xy 119.386352 -382.826943) (xy 119.394482 -382.775608)
			(xy 119.410543 -382.726178) (xy 119.434139 -382.679868) (xy 119.464689 -382.63782) (xy 119.50144 -382.601069)
			(xy 119.543488 -382.570519) (xy 119.589798 -382.546923) (xy 119.639228 -382.530862) (xy 119.690563 -382.522732)
			(xy 119.742537 -382.522732) (xy 119.793872 -382.530862) (xy 119.843302 -382.546923) (xy 119.889612 -382.570519)
			(xy 119.93166 -382.601069) (xy 119.968411 -382.63782) (xy 119.998961 -382.679868) (xy 120.022557 -382.726178)
			(xy 120.038618 -382.775608) (xy 120.046748 -382.826943) (xy 120.047258 -382.85293) (xy 120.046748 -382.878917)
			(xy 120.586248 -382.878917) (xy 120.586248 -382.826943) (xy 120.594378 -382.775608) (xy 120.610439 -382.726178)
			(xy 120.634035 -382.679868) (xy 120.664585 -382.63782) (xy 120.701336 -382.601069) (xy 120.743384 -382.570519)
			(xy 120.789694 -382.546923) (xy 120.839124 -382.530862) (xy 120.890459 -382.522732) (xy 120.942433 -382.522732)
			(xy 120.993768 -382.530862) (xy 121.043198 -382.546923) (xy 121.089508 -382.570519) (xy 121.131556 -382.601069)
			(xy 121.168307 -382.63782) (xy 121.198857 -382.679868) (xy 121.222453 -382.726178) (xy 121.238514 -382.775608)
			(xy 121.246644 -382.826943) (xy 121.247154 -382.85293) (xy 121.246644 -382.878917) (xy 121.786398 -382.878917)
			(xy 121.786398 -382.826943) (xy 121.794528 -382.775608) (xy 121.810589 -382.726178) (xy 121.834185 -382.679868)
			(xy 121.864735 -382.63782) (xy 121.901486 -382.601069) (xy 121.943534 -382.570519) (xy 121.989844 -382.546923)
			(xy 122.039274 -382.530862) (xy 122.090609 -382.522732) (xy 122.142583 -382.522732) (xy 122.193918 -382.530862)
			(xy 122.243348 -382.546923) (xy 122.289658 -382.570519) (xy 122.331706 -382.601069) (xy 122.368457 -382.63782)
			(xy 122.399007 -382.679868) (xy 122.422603 -382.726178) (xy 122.438664 -382.775608) (xy 122.446794 -382.826943)
			(xy 122.447304 -382.85293) (xy 122.446794 -382.878917) (xy 122.986294 -382.878917) (xy 122.986294 -382.826943)
			(xy 122.994424 -382.775608) (xy 123.010485 -382.726178) (xy 123.034081 -382.679868) (xy 123.064631 -382.63782)
			(xy 123.101382 -382.601069) (xy 123.14343 -382.570519) (xy 123.18974 -382.546923) (xy 123.23917 -382.530862)
			(xy 123.290505 -382.522732) (xy 123.342479 -382.522732) (xy 123.393814 -382.530862) (xy 123.443244 -382.546923)
			(xy 123.489554 -382.570519) (xy 123.531602 -382.601069) (xy 123.568353 -382.63782) (xy 123.598903 -382.679868)
			(xy 123.622499 -382.726178) (xy 123.63856 -382.775608) (xy 123.64669 -382.826943) (xy 123.6472 -382.85293)
			(xy 123.64669 -382.878917) (xy 124.18619 -382.878917) (xy 124.18619 -382.826943) (xy 124.19432 -382.775608)
			(xy 124.210381 -382.726178) (xy 124.233977 -382.679868) (xy 124.264527 -382.63782) (xy 124.301278 -382.601069)
			(xy 124.343326 -382.570519) (xy 124.389636 -382.546923) (xy 124.439066 -382.530862) (xy 124.490401 -382.522732)
			(xy 124.542375 -382.522732) (xy 124.59371 -382.530862) (xy 124.64314 -382.546923) (xy 124.68945 -382.570519)
			(xy 124.731498 -382.601069) (xy 124.768249 -382.63782) (xy 124.798799 -382.679868) (xy 124.822395 -382.726178)
			(xy 124.838456 -382.775608) (xy 124.846586 -382.826943) (xy 124.847096 -382.85293) (xy 124.846586 -382.878917)
			(xy 125.38634 -382.878917) (xy 125.38634 -382.826943) (xy 125.39447 -382.775608) (xy 125.410531 -382.726178)
			(xy 125.434127 -382.679868) (xy 125.464677 -382.63782) (xy 125.501428 -382.601069) (xy 125.543476 -382.570519)
			(xy 125.589786 -382.546923) (xy 125.639216 -382.530862) (xy 125.690551 -382.522732) (xy 125.742525 -382.522732)
			(xy 125.79386 -382.530862) (xy 125.84329 -382.546923) (xy 125.8896 -382.570519) (xy 125.931648 -382.601069)
			(xy 125.968399 -382.63782) (xy 125.998949 -382.679868) (xy 126.022545 -382.726178) (xy 126.038606 -382.775608)
			(xy 126.046736 -382.826943) (xy 126.047246 -382.85293) (xy 126.046736 -382.878917) (xy 126.586236 -382.878917)
			(xy 126.586236 -382.826943) (xy 126.594366 -382.775608) (xy 126.610427 -382.726178) (xy 126.634023 -382.679868)
			(xy 126.664573 -382.63782) (xy 126.701324 -382.601069) (xy 126.743372 -382.570519) (xy 126.789682 -382.546923)
			(xy 126.839112 -382.530862) (xy 126.890447 -382.522732) (xy 126.942421 -382.522732) (xy 126.993756 -382.530862)
			(xy 127.043186 -382.546923) (xy 127.089496 -382.570519) (xy 127.131544 -382.601069) (xy 127.168295 -382.63782)
			(xy 127.198845 -382.679868) (xy 127.222441 -382.726178) (xy 127.238502 -382.775608) (xy 127.246632 -382.826943)
			(xy 127.247142 -382.85293) (xy 127.246632 -382.878917) (xy 127.786386 -382.878917) (xy 127.786386 -382.826943)
			(xy 127.794516 -382.775608) (xy 127.810577 -382.726178) (xy 127.834173 -382.679868) (xy 127.864723 -382.63782)
			(xy 127.901474 -382.601069) (xy 127.943522 -382.570519) (xy 127.989832 -382.546923) (xy 128.039262 -382.530862)
			(xy 128.090597 -382.522732) (xy 128.142571 -382.522732) (xy 128.193906 -382.530862) (xy 128.243336 -382.546923)
			(xy 128.289646 -382.570519) (xy 128.331694 -382.601069) (xy 128.368445 -382.63782) (xy 128.398995 -382.679868)
			(xy 128.422591 -382.726178) (xy 128.438652 -382.775608) (xy 128.446782 -382.826943) (xy 128.447292 -382.85293)
			(xy 128.446782 -382.878917) (xy 128.986282 -382.878917) (xy 128.986282 -382.826943) (xy 128.994412 -382.775608)
			(xy 129.010473 -382.726178) (xy 129.034069 -382.679868) (xy 129.064619 -382.63782) (xy 129.10137 -382.601069)
			(xy 129.143418 -382.570519) (xy 129.189728 -382.546923) (xy 129.239158 -382.530862) (xy 129.290493 -382.522732)
			(xy 129.342467 -382.522732) (xy 129.393802 -382.530862) (xy 129.443232 -382.546923) (xy 129.489542 -382.570519)
			(xy 129.53159 -382.601069) (xy 129.568341 -382.63782) (xy 129.598891 -382.679868) (xy 129.622487 -382.726178)
			(xy 129.638548 -382.775608) (xy 129.646678 -382.826943) (xy 129.647188 -382.85293) (xy 129.646678 -382.878917)
			(xy 130.186178 -382.878917) (xy 130.186178 -382.826943) (xy 130.194308 -382.775608) (xy 130.210369 -382.726178)
			(xy 130.233965 -382.679868) (xy 130.264515 -382.63782) (xy 130.301266 -382.601069) (xy 130.343314 -382.570519)
			(xy 130.389624 -382.546923) (xy 130.439054 -382.530862) (xy 130.490389 -382.522732) (xy 130.542363 -382.522732)
			(xy 130.593698 -382.530862) (xy 130.643128 -382.546923) (xy 130.689438 -382.570519) (xy 130.731486 -382.601069)
			(xy 130.768237 -382.63782) (xy 130.798787 -382.679868) (xy 130.822383 -382.726178) (xy 130.838444 -382.775608)
			(xy 130.846574 -382.826943) (xy 130.847084 -382.85293) (xy 130.846574 -382.878917) (xy 131.386328 -382.878917)
			(xy 131.386328 -382.826943) (xy 131.394458 -382.775608) (xy 131.410519 -382.726178) (xy 131.434115 -382.679868)
			(xy 131.464665 -382.63782) (xy 131.501416 -382.601069) (xy 131.543464 -382.570519) (xy 131.589774 -382.546923)
			(xy 131.639204 -382.530862) (xy 131.690539 -382.522732) (xy 131.742513 -382.522732) (xy 131.793848 -382.530862)
			(xy 131.843278 -382.546923) (xy 131.889588 -382.570519) (xy 131.931636 -382.601069) (xy 131.968387 -382.63782)
			(xy 131.998937 -382.679868) (xy 132.022533 -382.726178) (xy 132.038594 -382.775608) (xy 132.046724 -382.826943)
			(xy 132.047234 -382.85293) (xy 132.046724 -382.878917) (xy 132.586224 -382.878917) (xy 132.586224 -382.826943)
			(xy 132.594354 -382.775608) (xy 132.610415 -382.726178) (xy 132.634011 -382.679868) (xy 132.664561 -382.63782)
			(xy 132.701312 -382.601069) (xy 132.74336 -382.570519) (xy 132.78967 -382.546923) (xy 132.8391 -382.530862)
			(xy 132.890435 -382.522732) (xy 132.942409 -382.522732) (xy 132.993744 -382.530862) (xy 133.043174 -382.546923)
			(xy 133.089484 -382.570519) (xy 133.131532 -382.601069) (xy 133.168283 -382.63782) (xy 133.198833 -382.679868)
			(xy 133.222429 -382.726178) (xy 133.23849 -382.775608) (xy 133.24662 -382.826943) (xy 133.24713 -382.85293)
			(xy 133.24662 -382.878917) (xy 133.244202 -382.894188) (xy 133.653272 -382.894188) (xy 133.653272 -382.842212)
			(xy 133.661402 -382.790875) (xy 133.677463 -382.741442) (xy 133.701059 -382.69513) (xy 133.731609 -382.653079)
			(xy 133.768361 -382.616324) (xy 133.810409 -382.585772) (xy 133.85672 -382.562172) (xy 133.906151 -382.546108)
			(xy 133.957488 -382.537973) (xy 133.983476 -382.537462) (xy 134.00725 -382.537867) (xy 134.05431 -382.544669)
			(xy 134.099907 -382.558149) (xy 134.1431 -382.57803) (xy 134.182995 -382.6039) (xy 134.201154 -382.61925)
			(xy 134.208272 -382.624938) (xy 134.225324 -382.631321) (xy 134.234428 -382.631696) (xy 134.265924 -382.631696)
			(xy 134.275026 -382.631313) (xy 134.292076 -382.624931) (xy 134.299198 -382.61925) (xy 134.317361 -382.603906)
			(xy 134.357261 -382.578049) (xy 134.400454 -382.558174) (xy 134.446048 -382.54469) (xy 134.493103 -382.537876)
			(xy 134.516876 -382.537462) (xy 134.542864 -382.538003) (xy 134.594201 -382.546131) (xy 134.643634 -382.562189)
			(xy 134.689947 -382.585784) (xy 134.731998 -382.616333) (xy 134.768752 -382.653084) (xy 134.799304 -382.695133)
			(xy 134.822901 -382.741444) (xy 134.838964 -382.790876) (xy 134.847095 -382.842212) (xy 134.847095 -382.894188)
			(xy 134.838964 -382.945524) (xy 134.822901 -382.994956) (xy 134.799304 -383.041267) (xy 134.768752 -383.083316)
			(xy 134.731998 -383.120067) (xy 134.689947 -383.150616) (xy 134.643634 -383.174211) (xy 134.594201 -383.190269)
			(xy 134.542864 -383.198397) (xy 134.516876 -383.198878) (xy 134.493101 -383.198492) (xy 134.446041 -383.191684)
			(xy 134.400444 -383.178199) (xy 134.357251 -383.158314) (xy 134.317357 -383.132442) (xy 134.299198 -383.11709)
			(xy 134.292099 -383.111374) (xy 134.275032 -383.10501) (xy 134.265924 -383.104644) (xy 134.234428 -383.104644)
			(xy 134.225328 -383.105043) (xy 134.208277 -383.111413) (xy 134.201154 -383.11709) (xy 134.182977 -383.132416)
			(xy 134.14308 -383.158274) (xy 134.099891 -383.178153) (xy 134.0543 -383.191641) (xy 134.007248 -383.198461)
			(xy 133.983476 -383.198878) (xy 133.957488 -383.198427) (xy 133.906151 -383.190292) (xy 133.85672 -383.174228)
			(xy 133.810409 -383.150628) (xy 133.768361 -383.120076) (xy 133.731609 -383.083321) (xy 133.701059 -383.04127)
			(xy 133.677463 -382.994958) (xy 133.661402 -382.945525) (xy 133.653272 -382.894188) (xy 133.244202 -382.894188)
			(xy 133.23849 -382.930252) (xy 133.222429 -382.979682) (xy 133.198833 -383.025992) (xy 133.168283 -383.06804)
			(xy 133.131532 -383.104791) (xy 133.089484 -383.135341) (xy 133.043174 -383.158937) (xy 132.993744 -383.174998)
			(xy 132.942409 -383.183128) (xy 132.890435 -383.183128) (xy 132.8391 -383.174998) (xy 132.78967 -383.158937)
			(xy 132.74336 -383.135341) (xy 132.701312 -383.104791) (xy 132.664561 -383.06804) (xy 132.634011 -383.025992)
			(xy 132.610415 -382.979682) (xy 132.594354 -382.930252) (xy 132.586224 -382.878917) (xy 132.046724 -382.878917)
			(xy 132.038594 -382.930252) (xy 132.022533 -382.979682) (xy 131.998937 -383.025992) (xy 131.968387 -383.06804)
			(xy 131.931636 -383.104791) (xy 131.889588 -383.135341) (xy 131.843278 -383.158937) (xy 131.793848 -383.174998)
			(xy 131.742513 -383.183128) (xy 131.690539 -383.183128) (xy 131.639204 -383.174998) (xy 131.589774 -383.158937)
			(xy 131.543464 -383.135341) (xy 131.501416 -383.104791) (xy 131.464665 -383.06804) (xy 131.434115 -383.025992)
			(xy 131.410519 -382.979682) (xy 131.394458 -382.930252) (xy 131.386328 -382.878917) (xy 130.846574 -382.878917)
			(xy 130.838444 -382.930252) (xy 130.822383 -382.979682) (xy 130.798787 -383.025992) (xy 130.768237 -383.06804)
			(xy 130.731486 -383.104791) (xy 130.689438 -383.135341) (xy 130.643128 -383.158937) (xy 130.593698 -383.174998)
			(xy 130.542363 -383.183128) (xy 130.490389 -383.183128) (xy 130.439054 -383.174998) (xy 130.389624 -383.158937)
			(xy 130.343314 -383.135341) (xy 130.301266 -383.104791) (xy 130.264515 -383.06804) (xy 130.233965 -383.025992)
			(xy 130.210369 -382.979682) (xy 130.194308 -382.930252) (xy 130.186178 -382.878917) (xy 129.646678 -382.878917)
			(xy 129.638548 -382.930252) (xy 129.622487 -382.979682) (xy 129.598891 -383.025992) (xy 129.568341 -383.06804)
			(xy 129.53159 -383.104791) (xy 129.489542 -383.135341) (xy 129.443232 -383.158937) (xy 129.393802 -383.174998)
			(xy 129.342467 -383.183128) (xy 129.290493 -383.183128) (xy 129.239158 -383.174998) (xy 129.189728 -383.158937)
			(xy 129.143418 -383.135341) (xy 129.10137 -383.104791) (xy 129.064619 -383.06804) (xy 129.034069 -383.025992)
			(xy 129.010473 -382.979682) (xy 128.994412 -382.930252) (xy 128.986282 -382.878917) (xy 128.446782 -382.878917)
			(xy 128.438652 -382.930252) (xy 128.422591 -382.979682) (xy 128.398995 -383.025992) (xy 128.368445 -383.06804)
			(xy 128.331694 -383.104791) (xy 128.289646 -383.135341) (xy 128.243336 -383.158937) (xy 128.193906 -383.174998)
			(xy 128.142571 -383.183128) (xy 128.090597 -383.183128) (xy 128.039262 -383.174998) (xy 127.989832 -383.158937)
			(xy 127.943522 -383.135341) (xy 127.901474 -383.104791) (xy 127.864723 -383.06804) (xy 127.834173 -383.025992)
			(xy 127.810577 -382.979682) (xy 127.794516 -382.930252) (xy 127.786386 -382.878917) (xy 127.246632 -382.878917)
			(xy 127.238502 -382.930252) (xy 127.222441 -382.979682) (xy 127.198845 -383.025992) (xy 127.168295 -383.06804)
			(xy 127.131544 -383.104791) (xy 127.089496 -383.135341) (xy 127.043186 -383.158937) (xy 126.993756 -383.174998)
			(xy 126.942421 -383.183128) (xy 126.890447 -383.183128) (xy 126.839112 -383.174998) (xy 126.789682 -383.158937)
			(xy 126.743372 -383.135341) (xy 126.701324 -383.104791) (xy 126.664573 -383.06804) (xy 126.634023 -383.025992)
			(xy 126.610427 -382.979682) (xy 126.594366 -382.930252) (xy 126.586236 -382.878917) (xy 126.046736 -382.878917)
			(xy 126.038606 -382.930252) (xy 126.022545 -382.979682) (xy 125.998949 -383.025992) (xy 125.968399 -383.06804)
			(xy 125.931648 -383.104791) (xy 125.8896 -383.135341) (xy 125.84329 -383.158937) (xy 125.79386 -383.174998)
			(xy 125.742525 -383.183128) (xy 125.690551 -383.183128) (xy 125.639216 -383.174998) (xy 125.589786 -383.158937)
			(xy 125.543476 -383.135341) (xy 125.501428 -383.104791) (xy 125.464677 -383.06804) (xy 125.434127 -383.025992)
			(xy 125.410531 -382.979682) (xy 125.39447 -382.930252) (xy 125.38634 -382.878917) (xy 124.846586 -382.878917)
			(xy 124.838456 -382.930252) (xy 124.822395 -382.979682) (xy 124.798799 -383.025992) (xy 124.768249 -383.06804)
			(xy 124.731498 -383.104791) (xy 124.68945 -383.135341) (xy 124.64314 -383.158937) (xy 124.59371 -383.174998)
			(xy 124.542375 -383.183128) (xy 124.490401 -383.183128) (xy 124.439066 -383.174998) (xy 124.389636 -383.158937)
			(xy 124.343326 -383.135341) (xy 124.301278 -383.104791) (xy 124.264527 -383.06804) (xy 124.233977 -383.025992)
			(xy 124.210381 -382.979682) (xy 124.19432 -382.930252) (xy 124.18619 -382.878917) (xy 123.64669 -382.878917)
			(xy 123.63856 -382.930252) (xy 123.622499 -382.979682) (xy 123.598903 -383.025992) (xy 123.568353 -383.06804)
			(xy 123.531602 -383.104791) (xy 123.489554 -383.135341) (xy 123.443244 -383.158937) (xy 123.393814 -383.174998)
			(xy 123.342479 -383.183128) (xy 123.290505 -383.183128) (xy 123.23917 -383.174998) (xy 123.18974 -383.158937)
			(xy 123.14343 -383.135341) (xy 123.101382 -383.104791) (xy 123.064631 -383.06804) (xy 123.034081 -383.025992)
			(xy 123.010485 -382.979682) (xy 122.994424 -382.930252) (xy 122.986294 -382.878917) (xy 122.446794 -382.878917)
			(xy 122.438664 -382.930252) (xy 122.422603 -382.979682) (xy 122.399007 -383.025992) (xy 122.368457 -383.06804)
			(xy 122.331706 -383.104791) (xy 122.289658 -383.135341) (xy 122.243348 -383.158937) (xy 122.193918 -383.174998)
			(xy 122.142583 -383.183128) (xy 122.090609 -383.183128) (xy 122.039274 -383.174998) (xy 121.989844 -383.158937)
			(xy 121.943534 -383.135341) (xy 121.901486 -383.104791) (xy 121.864735 -383.06804) (xy 121.834185 -383.025992)
			(xy 121.810589 -382.979682) (xy 121.794528 -382.930252) (xy 121.786398 -382.878917) (xy 121.246644 -382.878917)
			(xy 121.238514 -382.930252) (xy 121.222453 -382.979682) (xy 121.198857 -383.025992) (xy 121.168307 -383.06804)
			(xy 121.131556 -383.104791) (xy 121.089508 -383.135341) (xy 121.043198 -383.158937) (xy 120.993768 -383.174998)
			(xy 120.942433 -383.183128) (xy 120.890459 -383.183128) (xy 120.839124 -383.174998) (xy 120.789694 -383.158937)
			(xy 120.743384 -383.135341) (xy 120.701336 -383.104791) (xy 120.664585 -383.06804) (xy 120.634035 -383.025992)
			(xy 120.610439 -382.979682) (xy 120.594378 -382.930252) (xy 120.586248 -382.878917) (xy 120.046748 -382.878917)
			(xy 120.038618 -382.930252) (xy 120.022557 -382.979682) (xy 119.998961 -383.025992) (xy 119.968411 -383.06804)
			(xy 119.93166 -383.104791) (xy 119.889612 -383.135341) (xy 119.843302 -383.158937) (xy 119.793872 -383.174998)
			(xy 119.742537 -383.183128) (xy 119.690563 -383.183128) (xy 119.639228 -383.174998) (xy 119.589798 -383.158937)
			(xy 119.543488 -383.135341) (xy 119.50144 -383.104791) (xy 119.464689 -383.06804) (xy 119.434139 -383.025992)
			(xy 119.410543 -382.979682) (xy 119.394482 -382.930252) (xy 119.386352 -382.878917) (xy 118.846598 -382.878917)
			(xy 118.838468 -382.930252) (xy 118.822407 -382.979682) (xy 118.798811 -383.025992) (xy 118.768261 -383.06804)
			(xy 118.73151 -383.104791) (xy 118.689462 -383.135341) (xy 118.643152 -383.158937) (xy 118.593722 -383.174998)
			(xy 118.542387 -383.183128) (xy 118.490413 -383.183128) (xy 118.439078 -383.174998) (xy 118.389648 -383.158937)
			(xy 118.343338 -383.135341) (xy 118.30129 -383.104791) (xy 118.264539 -383.06804) (xy 118.233989 -383.025992)
			(xy 118.210393 -382.979682) (xy 118.194332 -382.930252) (xy 118.186202 -382.878917) (xy 117.646702 -382.878917)
			(xy 117.638572 -382.930252) (xy 117.622511 -382.979682) (xy 117.598915 -383.025992) (xy 117.568365 -383.06804)
			(xy 117.531614 -383.104791) (xy 117.489566 -383.135341) (xy 117.443256 -383.158937) (xy 117.393826 -383.174998)
			(xy 117.342491 -383.183128) (xy 117.290517 -383.183128) (xy 117.239182 -383.174998) (xy 117.189752 -383.158937)
			(xy 117.143442 -383.135341) (xy 117.101394 -383.104791) (xy 117.064643 -383.06804) (xy 117.034093 -383.025992)
			(xy 117.010497 -382.979682) (xy 116.994436 -382.930252) (xy 116.986306 -382.878917) (xy 116.446806 -382.878917)
			(xy 116.438676 -382.930252) (xy 116.422615 -382.979682) (xy 116.399019 -383.025992) (xy 116.368469 -383.06804)
			(xy 116.331718 -383.104791) (xy 116.28967 -383.135341) (xy 116.24336 -383.158937) (xy 116.19393 -383.174998)
			(xy 116.142595 -383.183128) (xy 116.090621 -383.183128) (xy 116.039286 -383.174998) (xy 115.989856 -383.158937)
			(xy 115.943546 -383.135341) (xy 115.901498 -383.104791) (xy 115.864747 -383.06804) (xy 115.834197 -383.025992)
			(xy 115.810601 -382.979682) (xy 115.79454 -382.930252) (xy 115.78641 -382.878917) (xy 115.246656 -382.878917)
			(xy 115.238526 -382.930252) (xy 115.222465 -382.979682) (xy 115.198869 -383.025992) (xy 115.168319 -383.06804)
			(xy 115.131568 -383.104791) (xy 115.08952 -383.135341) (xy 115.04321 -383.158937) (xy 114.99378 -383.174998)
			(xy 114.942445 -383.183128) (xy 114.890471 -383.183128) (xy 114.839136 -383.174998) (xy 114.789706 -383.158937)
			(xy 114.743396 -383.135341) (xy 114.701348 -383.104791) (xy 114.664597 -383.06804) (xy 114.634047 -383.025992)
			(xy 114.610451 -382.979682) (xy 114.59439 -382.930252) (xy 114.58626 -382.878917) (xy 113.898284 -382.878917)
			(xy 113.898773 -382.882006) (xy 113.898773 -382.933994) (xy 113.89064 -382.985342) (xy 113.874574 -383.034785)
			(xy 113.850971 -383.081107) (xy 113.820412 -383.123165) (xy 113.78365 -383.159925) (xy 113.74159 -383.190481)
			(xy 113.695267 -383.214081) (xy 113.645822 -383.230144) (xy 113.594474 -383.238274) (xy 113.56848 -383.238756)
			(xy 113.539887 -383.238133) (xy 113.483554 -383.228287) (xy 113.42975 -383.208907) (xy 113.380077 -383.18057)
			(xy 113.35766 -383.16281) (xy 113.350802 -383.157222) (xy 113.334038 -383.151126) (xy 113.251742 -383.151126)
			(xy 113.234978 -383.156968) (xy 113.22812 -383.162556) (xy 113.205768 -383.18021) (xy 113.156248 -383.208344)
			(xy 113.102645 -383.227589) (xy 113.046538 -383.237379) (xy 113.018062 -383.237994) (xy 112.994828 -383.237602)
			(xy 112.948817 -383.231103) (xy 112.904169 -383.218226) (xy 112.861764 -383.199223) (xy 112.822439 -383.174469)
			(xy 112.804448 -383.159762) (xy 112.797336 -383.153666) (xy 112.780826 -383.14757) (xy 112.696498 -383.14757)
			(xy 112.679988 -383.153666) (xy 112.672876 -383.159762) (xy 112.654866 -383.174444) (xy 112.615543 -383.199195)
			(xy 112.573143 -383.218201) (xy 112.5285 -383.231086) (xy 112.482494 -383.237596) (xy 112.459262 -383.237994)
			(xy 112.433276 -383.23751) (xy 112.381944 -383.229374) (xy 112.332516 -383.213309) (xy 112.28621 -383.18971)
			(xy 112.244165 -383.159158) (xy 112.207417 -383.122406) (xy 112.17687 -383.080358) (xy 112.153277 -383.034049)
			(xy 112.137217 -382.984619) (xy 112.129087 -382.933286) (xy 109.619958 -382.933286) (xy 109.498638 -383.054606)
			(xy 109.491236 -383.061442) (xy 109.472638 -383.069153) (xy 109.46257 -383.069592) (xy 108.935012 -383.069592)
			(xy 108.907326 -383.091944) (xy 108.903516 -383.109724) (xy 108.897317 -383.136304) (xy 108.878343 -383.18748)
			(xy 108.852269 -383.235428) (xy 108.819626 -383.279169) (xy 108.781081 -383.317811) (xy 108.737421 -383.350565)
			(xy 108.689539 -383.37676) (xy 108.638412 -383.395863) (xy 108.585084 -383.407483) (xy 108.530644 -383.411383)
			(xy 108.476204 -383.407483) (xy 108.422876 -383.395863) (xy 108.371749 -383.37676) (xy 108.323867 -383.350565)
			(xy 108.280207 -383.317811) (xy 108.241662 -383.279169) (xy 108.209019 -383.235428) (xy 108.182945 -383.18748)
			(xy 108.163971 -383.136304) (xy 108.157772 -383.109724) (xy 108.153962 -383.091944) (xy 108.126276 -383.069592)
			(xy 103.046276 -383.069592) (xy 103.036955 -383.070014) (xy 103.019555 -383.076703) (xy 103.005708 -383.089183)
			(xy 103.001064 -383.097278) (xy 102.953312 -383.190242) (xy 102.955344 -383.218436) (xy 102.963726 -383.230374)
			(xy 102.980484 -383.254776) (xy 103.007055 -383.30767) (xy 103.025131 -383.364037) (xy 103.034277 -383.422519)
			(xy 103.034846 -383.452116) (xy 103.034222 -383.483767) (xy 103.023748 -383.546197) (xy 103.014018 -383.576322)
			(xy 103.011478 -383.592578) (xy 103.011547 -383.597053) (xy 103.013079 -383.605869) (xy 103.014526 -383.610104)
			(xy 103.024686 -383.638298) (xy 103.028059 -383.646493) (xy 103.039357 -383.660132) (xy 103.046784 -383.664968)
			(xy 103.075118 -383.68213) (xy 103.127501 -383.722681) (xy 103.147871 -383.7432) (xy 110.783876 -383.7432)
			(xy 110.787947 -383.687578) (xy 110.800073 -383.633141) (xy 110.819996 -383.58105) (xy 110.847292 -383.532415)
			(xy 110.881378 -383.488272) (xy 110.921527 -383.449563) (xy 110.966885 -383.417112) (xy 111.016485 -383.391611)
			(xy 111.069269 -383.373604) (xy 111.124112 -383.363474) (xy 111.179846 -383.361437) (xy 111.235283 -383.367537)
			(xy 111.28924 -383.381643) (xy 111.340569 -383.403455) (xy 111.388175 -383.432509) (xy 111.431043 -383.468184)
			(xy 111.46826 -383.509721) (xy 111.499033 -383.556234) (xy 111.522705 -383.606731) (xy 111.538773 -383.660138)
			(xy 111.546893 -383.715314) (xy 111.547402 -383.7432) (xy 111.546893 -383.771086) (xy 111.538773 -383.826262)
			(xy 111.522705 -383.879669) (xy 111.499033 -383.930166) (xy 111.46826 -383.976679) (xy 111.431043 -384.018216)
			(xy 111.388175 -384.053891) (xy 111.340569 -384.082945) (xy 111.28924 -384.104757) (xy 111.235283 -384.118863)
			(xy 111.179846 -384.124963) (xy 111.124112 -384.122926) (xy 111.069269 -384.112796) (xy 111.016485 -384.094789)
			(xy 110.966885 -384.069288) (xy 110.921527 -384.036837) (xy 110.881378 -383.998128) (xy 110.847292 -383.953985)
			(xy 110.819996 -383.90535) (xy 110.800073 -383.853259) (xy 110.787947 -383.798822) (xy 110.783876 -383.7432)
			(xy 103.147871 -383.7432) (xy 103.174171 -383.769693) (xy 103.214338 -383.822371) (xy 103.247322 -383.87982)
			(xy 103.272561 -383.941068) (xy 103.289631 -384.005075) (xy 103.298239 -384.070758) (xy 103.298752 -384.10388)
			(xy 103.298308 -384.13399) (xy 103.291194 -384.193789) (xy 103.277063 -384.252328) (xy 103.256114 -384.308787)
			(xy 103.228639 -384.362375) (xy 103.195024 -384.41234) (xy 103.15574 -384.457983) (xy 103.111337 -384.498663)
			(xy 103.08717 -384.51663) (xy 103.066088 -384.557778) (xy 103.066088 -384.640328) (xy 103.066088 -384.640582)
			(xy 103.07741 -384.66268) (xy 110.783876 -384.66268) (xy 110.787947 -384.607058) (xy 110.800073 -384.552621)
			(xy 110.819996 -384.50053) (xy 110.847292 -384.451895) (xy 110.881378 -384.407752) (xy 110.921527 -384.369043)
			(xy 110.966885 -384.336592) (xy 111.016485 -384.311091) (xy 111.069269 -384.293084) (xy 111.124112 -384.282954)
			(xy 111.179846 -384.280917) (xy 111.235283 -384.287017) (xy 111.28924 -384.301123) (xy 111.340569 -384.322935)
			(xy 111.388175 -384.351989) (xy 111.430654 -384.38734) (xy 112.043954 -384.38734) (xy 112.043954 -384.327404)
			(xy 112.051777 -384.267982) (xy 112.06729 -384.210089) (xy 112.090226 -384.154716) (xy 112.120193 -384.10281)
			(xy 112.15668 -384.05526) (xy 112.19906 -384.01288) (xy 112.24661 -383.976393) (xy 112.298516 -383.946426)
			(xy 112.353889 -383.92349) (xy 112.411782 -383.907977) (xy 112.471204 -383.900154) (xy 112.53114 -383.900154)
			(xy 112.590562 -383.907977) (xy 112.648455 -383.92349) (xy 112.703828 -383.946426) (xy 112.755734 -383.976393)
			(xy 112.803284 -384.01288) (xy 112.845664 -384.05526) (xy 112.882151 -384.10281) (xy 112.912118 -384.154716)
			(xy 112.935054 -384.210089) (xy 112.950567 -384.267982) (xy 112.95839 -384.327404) (xy 112.95888 -384.357372)
			(xy 112.95839 -384.38734) (xy 112.950567 -384.446762) (xy 112.935054 -384.504655) (xy 112.912118 -384.560028)
			(xy 112.882151 -384.611934) (xy 112.845664 -384.659484) (xy 112.803284 -384.701864) (xy 112.755734 -384.738351)
			(xy 112.703828 -384.768318) (xy 112.648455 -384.791254) (xy 112.590562 -384.806767) (xy 112.53114 -384.81459)
			(xy 112.471204 -384.81459) (xy 112.411782 -384.806767) (xy 112.353889 -384.791254) (xy 112.298516 -384.768318)
			(xy 112.24661 -384.738351) (xy 112.19906 -384.701864) (xy 112.15668 -384.659484) (xy 112.120193 -384.611934)
			(xy 112.090226 -384.560028) (xy 112.06729 -384.504655) (xy 112.051777 -384.446762) (xy 112.043954 -384.38734)
			(xy 111.430654 -384.38734) (xy 111.431043 -384.387664) (xy 111.46826 -384.429201) (xy 111.499033 -384.475714)
			(xy 111.522705 -384.526211) (xy 111.538773 -384.579618) (xy 111.546893 -384.634794) (xy 111.547402 -384.66268)
			(xy 111.546893 -384.690566) (xy 111.538773 -384.745742) (xy 111.522705 -384.799149) (xy 111.499033 -384.849646)
			(xy 111.46826 -384.896159) (xy 111.431043 -384.937696) (xy 111.388175 -384.973371) (xy 111.340569 -385.002425)
			(xy 111.28924 -385.024237) (xy 111.235283 -385.038343) (xy 111.179846 -385.044443) (xy 111.124112 -385.042406)
			(xy 111.069269 -385.032276) (xy 111.016485 -385.014269) (xy 110.966885 -384.988768) (xy 110.921527 -384.956317)
			(xy 110.881378 -384.917608) (xy 110.847292 -384.873465) (xy 110.819996 -384.82483) (xy 110.800073 -384.772739)
			(xy 110.787947 -384.718302) (xy 110.783876 -384.66268) (xy 103.07741 -384.66268) (xy 103.08717 -384.68173)
			(xy 103.111351 -384.699675) (xy 103.155736 -384.740372) (xy 103.195006 -384.786024) (xy 103.22861 -384.835994)
			(xy 103.256078 -384.889583) (xy 103.277027 -384.94604) (xy 103.291162 -385.004576) (xy 103.298287 -385.064371)
			(xy 103.298752 -385.09448) (xy 103.29829 -385.125213) (xy 103.290883 -385.18623) (xy 103.276176 -385.245911)
			(xy 103.254383 -385.303383) (xy 103.225822 -385.357809) (xy 103.190908 -385.408397) (xy 103.150152 -385.454407)
			(xy 103.104147 -385.495169) (xy 103.053564 -385.530089) (xy 102.999141 -385.558657) (xy 102.941672 -385.580457)
			(xy 102.881993 -385.595172) (xy 102.820977 -385.602586) (xy 102.790244 -385.602988) (xy 102.78999 -385.602988)
			(xy 102.759694 -385.602555) (xy 102.69953 -385.595362) (xy 102.640648 -385.581067) (xy 102.583883 -385.559873)
			(xy 102.530041 -385.532081) (xy 102.479884 -385.498085) (xy 102.456742 -385.478528) (xy 102.449884 -385.472178)
			(xy 102.432866 -385.466082) (xy 102.347522 -385.466082) (xy 102.330504 -385.472178) (xy 102.323646 -385.478528)
			(xy 102.296214 -385.500626) (xy 102.286872 -385.508533) (xy 102.276278 -385.530555) (xy 102.275894 -385.54279)
			(xy 102.27691 -385.574286) (xy 102.278051 -385.586528) (xy 102.290113 -385.607909) (xy 102.292219 -385.609454)
			(xy 110.784838 -385.609454) (xy 110.784838 -385.554946) (xy 110.792595 -385.500993) (xy 110.807951 -385.448694)
			(xy 110.830595 -385.399112) (xy 110.860063 -385.353257) (xy 110.895758 -385.312062) (xy 110.936952 -385.276367)
			(xy 110.982806 -385.246897) (xy 111.032388 -385.224254) (xy 111.084687 -385.208896) (xy 111.13864 -385.201138)
			(xy 111.165894 -385.200652) (xy 111.194527 -385.201205) (xy 111.251149 -385.209764) (xy 111.305856 -385.226688)
			(xy 111.357419 -385.2516) (xy 111.40468 -385.283938) (xy 111.446577 -385.322976) (xy 111.482168 -385.367838)
			(xy 111.496856 -385.392422) (xy 111.503968 -385.404614) (xy 111.527844 -385.41833) (xy 111.644938 -385.416044)
			(xy 111.668306 -385.40182) (xy 111.67491 -385.389374) (xy 111.689843 -385.362119) (xy 111.725974 -385.311554)
			(xy 111.768618 -385.266346) (xy 111.816989 -385.227327) (xy 111.870198 -385.195216) (xy 111.927263 -385.170603)
			(xy 111.987136 -385.153943) (xy 112.048712 -385.145541) (xy 112.079786 -385.145026) (xy 112.109756 -385.145474)
			(xy 112.169184 -385.153297) (xy 112.227082 -385.16881) (xy 112.282459 -385.191748) (xy 112.334369 -385.221718)
			(xy 112.381922 -385.258208) (xy 112.424305 -385.300593) (xy 112.460793 -385.348148) (xy 112.490761 -385.400059)
			(xy 112.513697 -385.455437) (xy 112.529207 -385.513336) (xy 112.537027 -385.572764) (xy 112.537494 -385.602734)
			(xy 112.536983 -385.633614) (xy 112.528668 -385.694811) (xy 112.512194 -385.754333) (xy 112.487861 -385.811096)
			(xy 112.456111 -385.864069) (xy 112.446939 -385.87553) (xy 113.933986 -385.87553) (xy 113.934503 -385.849542)
			(xy 113.942629 -385.798205) (xy 113.958687 -385.748771) (xy 113.982281 -385.702459) (xy 114.012829 -385.660407)
			(xy 114.04958 -385.623652) (xy 114.091628 -385.593099) (xy 114.137938 -385.569501) (xy 114.18737 -385.553438)
			(xy 114.238706 -385.545306) (xy 114.264694 -385.544822) (xy 114.281127 -385.545054) (xy 114.313827 -385.548358)
			(xy 114.329972 -385.551426) (xy 114.342926 -385.553966) (xy 114.368072 -385.546092) (xy 114.445288 -385.464304)
			(xy 114.451892 -385.438904) (xy 114.44859 -385.426204) (xy 114.441584 -385.397762) (xy 114.434066 -385.339669)
			(xy 114.433604 -385.31038) (xy 114.434129 -385.279492) (xy 114.442434 -385.218277) (xy 114.458891 -385.158733)
			(xy 114.483201 -385.101941) (xy 114.498628 -385.075176) (xy 114.50447 -385.06527) (xy 114.506756 -385.042918)
			(xy 114.473482 -384.947668) (xy 114.457734 -384.931666) (xy 114.447066 -384.927602) (xy 114.423678 -384.918434)
			(xy 114.379782 -384.894012) (xy 114.340086 -384.863228) (xy 114.305506 -384.826792) (xy 114.276838 -384.785543)
			(xy 114.254741 -384.740431) (xy 114.239725 -384.692495) (xy 114.232136 -384.642839) (xy 114.231674 -384.617722)
			(xy 114.232184 -384.591735) (xy 114.240314 -384.5404) (xy 114.256375 -384.49097) (xy 114.279971 -384.44466)
			(xy 114.310521 -384.402612) (xy 114.347272 -384.365861) (xy 114.38932 -384.335311) (xy 114.43563 -384.311715)
			(xy 114.48506 -384.295654) (xy 114.536395 -384.287524) (xy 114.588369 -384.287524) (xy 114.639704 -384.295654)
			(xy 114.689134 -384.311715) (xy 114.735444 -384.335311) (xy 114.777492 -384.365861) (xy 114.814243 -384.402612)
			(xy 114.844793 -384.44466) (xy 114.868389 -384.49097) (xy 114.88445 -384.5404) (xy 114.89258 -384.591735)
			(xy 114.89309 -384.617722) (xy 115.43157 -384.617722) (xy 115.43208 -384.591735) (xy 115.44021 -384.5404)
			(xy 115.456271 -384.49097) (xy 115.479867 -384.44466) (xy 115.510417 -384.402612) (xy 115.547168 -384.365861)
			(xy 115.589216 -384.335311) (xy 115.635526 -384.311715) (xy 115.684956 -384.295654) (xy 115.736291 -384.287524)
			(xy 115.788265 -384.287524) (xy 115.8396 -384.295654) (xy 115.88903 -384.311715) (xy 115.93534 -384.335311)
			(xy 115.977388 -384.365861) (xy 116.014139 -384.402612) (xy 116.044689 -384.44466) (xy 116.068285 -384.49097)
			(xy 116.084346 -384.5404) (xy 116.092476 -384.591735) (xy 116.092986 -384.617722) (xy 116.63172 -384.617722)
			(xy 116.63223 -384.591735) (xy 116.64036 -384.5404) (xy 116.656421 -384.49097) (xy 116.680017 -384.44466)
			(xy 116.710567 -384.402612) (xy 116.747318 -384.365861) (xy 116.789366 -384.335311) (xy 116.835676 -384.311715)
			(xy 116.885106 -384.295654) (xy 116.936441 -384.287524) (xy 116.988415 -384.287524) (xy 117.03975 -384.295654)
			(xy 117.08918 -384.311715) (xy 117.13549 -384.335311) (xy 117.177538 -384.365861) (xy 117.214289 -384.402612)
			(xy 117.244839 -384.44466) (xy 117.268435 -384.49097) (xy 117.284496 -384.5404) (xy 117.292626 -384.591735)
			(xy 117.293136 -384.617722) (xy 117.831616 -384.617722) (xy 117.832126 -384.591735) (xy 117.840256 -384.5404)
			(xy 117.856317 -384.49097) (xy 117.879913 -384.44466) (xy 117.910463 -384.402612) (xy 117.947214 -384.365861)
			(xy 117.989262 -384.335311) (xy 118.035572 -384.311715) (xy 118.085002 -384.295654) (xy 118.136337 -384.287524)
			(xy 118.188311 -384.287524) (xy 118.239646 -384.295654) (xy 118.289076 -384.311715) (xy 118.335386 -384.335311)
			(xy 118.377434 -384.365861) (xy 118.414185 -384.402612) (xy 118.444735 -384.44466) (xy 118.468331 -384.49097)
			(xy 118.484392 -384.5404) (xy 118.492522 -384.591735) (xy 118.493032 -384.617722) (xy 119.031766 -384.617722)
			(xy 119.032276 -384.591735) (xy 119.040406 -384.5404) (xy 119.056467 -384.49097) (xy 119.080063 -384.44466)
			(xy 119.110613 -384.402612) (xy 119.147364 -384.365861) (xy 119.189412 -384.335311) (xy 119.235722 -384.311715)
			(xy 119.285152 -384.295654) (xy 119.336487 -384.287524) (xy 119.388461 -384.287524) (xy 119.439796 -384.295654)
			(xy 119.489226 -384.311715) (xy 119.535536 -384.335311) (xy 119.577584 -384.365861) (xy 119.614335 -384.402612)
			(xy 119.644885 -384.44466) (xy 119.668481 -384.49097) (xy 119.684542 -384.5404) (xy 119.692672 -384.591735)
			(xy 119.693182 -384.617722) (xy 120.231662 -384.617722) (xy 120.232172 -384.591735) (xy 120.240302 -384.5404)
			(xy 120.256363 -384.49097) (xy 120.279959 -384.44466) (xy 120.310509 -384.402612) (xy 120.34726 -384.365861)
			(xy 120.389308 -384.335311) (xy 120.435618 -384.311715) (xy 120.485048 -384.295654) (xy 120.536383 -384.287524)
			(xy 120.588357 -384.287524) (xy 120.639692 -384.295654) (xy 120.689122 -384.311715) (xy 120.735432 -384.335311)
			(xy 120.77748 -384.365861) (xy 120.814231 -384.402612) (xy 120.844781 -384.44466) (xy 120.868377 -384.49097)
			(xy 120.884438 -384.5404) (xy 120.892568 -384.591735) (xy 120.893078 -384.617722) (xy 121.431558 -384.617722)
			(xy 121.432068 -384.591735) (xy 121.440198 -384.5404) (xy 121.456259 -384.49097) (xy 121.479855 -384.44466)
			(xy 121.510405 -384.402612) (xy 121.547156 -384.365861) (xy 121.589204 -384.335311) (xy 121.635514 -384.311715)
			(xy 121.684944 -384.295654) (xy 121.736279 -384.287524) (xy 121.788253 -384.287524) (xy 121.839588 -384.295654)
			(xy 121.889018 -384.311715) (xy 121.935328 -384.335311) (xy 121.977376 -384.365861) (xy 122.014127 -384.402612)
			(xy 122.044677 -384.44466) (xy 122.068273 -384.49097) (xy 122.084334 -384.5404) (xy 122.092464 -384.591735)
			(xy 122.092974 -384.617722) (xy 122.631708 -384.617722) (xy 122.632218 -384.591735) (xy 122.640348 -384.5404)
			(xy 122.656409 -384.49097) (xy 122.680005 -384.44466) (xy 122.710555 -384.402612) (xy 122.747306 -384.365861)
			(xy 122.789354 -384.335311) (xy 122.835664 -384.311715) (xy 122.885094 -384.295654) (xy 122.936429 -384.287524)
			(xy 122.988403 -384.287524) (xy 123.039738 -384.295654) (xy 123.089168 -384.311715) (xy 123.135478 -384.335311)
			(xy 123.177526 -384.365861) (xy 123.214277 -384.402612) (xy 123.244827 -384.44466) (xy 123.268423 -384.49097)
			(xy 123.284484 -384.5404) (xy 123.292614 -384.591735) (xy 123.293124 -384.617722) (xy 123.831604 -384.617722)
			(xy 123.832114 -384.591735) (xy 123.840244 -384.5404) (xy 123.856305 -384.49097) (xy 123.879901 -384.44466)
			(xy 123.910451 -384.402612) (xy 123.947202 -384.365861) (xy 123.98925 -384.335311) (xy 124.03556 -384.311715)
			(xy 124.08499 -384.295654) (xy 124.136325 -384.287524) (xy 124.188299 -384.287524) (xy 124.239634 -384.295654)
			(xy 124.289064 -384.311715) (xy 124.335374 -384.335311) (xy 124.377422 -384.365861) (xy 124.414173 -384.402612)
			(xy 124.444723 -384.44466) (xy 124.468319 -384.49097) (xy 124.48438 -384.5404) (xy 124.49251 -384.591735)
			(xy 124.49302 -384.617722) (xy 125.031754 -384.617722) (xy 125.032264 -384.591735) (xy 125.040394 -384.5404)
			(xy 125.056455 -384.49097) (xy 125.080051 -384.44466) (xy 125.110601 -384.402612) (xy 125.147352 -384.365861)
			(xy 125.1894 -384.335311) (xy 125.23571 -384.311715) (xy 125.28514 -384.295654) (xy 125.336475 -384.287524)
			(xy 125.388449 -384.287524) (xy 125.439784 -384.295654) (xy 125.489214 -384.311715) (xy 125.535524 -384.335311)
			(xy 125.577572 -384.365861) (xy 125.614323 -384.402612) (xy 125.644873 -384.44466) (xy 125.668469 -384.49097)
			(xy 125.68453 -384.5404) (xy 125.69266 -384.591735) (xy 125.69317 -384.617722) (xy 126.23165 -384.617722)
			(xy 126.23216 -384.591735) (xy 126.24029 -384.5404) (xy 126.256351 -384.49097) (xy 126.279947 -384.44466)
			(xy 126.310497 -384.402612) (xy 126.347248 -384.365861) (xy 126.389296 -384.335311) (xy 126.435606 -384.311715)
			(xy 126.485036 -384.295654) (xy 126.536371 -384.287524) (xy 126.588345 -384.287524) (xy 126.63968 -384.295654)
			(xy 126.68911 -384.311715) (xy 126.73542 -384.335311) (xy 126.777468 -384.365861) (xy 126.814219 -384.402612)
			(xy 126.844769 -384.44466) (xy 126.868365 -384.49097) (xy 126.884426 -384.5404) (xy 126.892556 -384.591735)
			(xy 126.893066 -384.617722) (xy 127.431546 -384.617722) (xy 127.432056 -384.591735) (xy 127.440186 -384.5404)
			(xy 127.456247 -384.49097) (xy 127.479843 -384.44466) (xy 127.510393 -384.402612) (xy 127.547144 -384.365861)
			(xy 127.589192 -384.335311) (xy 127.635502 -384.311715) (xy 127.684932 -384.295654) (xy 127.736267 -384.287524)
			(xy 127.788241 -384.287524) (xy 127.839576 -384.295654) (xy 127.889006 -384.311715) (xy 127.935316 -384.335311)
			(xy 127.977364 -384.365861) (xy 128.014115 -384.402612) (xy 128.044665 -384.44466) (xy 128.068261 -384.49097)
			(xy 128.084322 -384.5404) (xy 128.092452 -384.591735) (xy 128.092962 -384.617722) (xy 128.631696 -384.617722)
			(xy 128.632206 -384.591735) (xy 128.640336 -384.5404) (xy 128.656397 -384.49097) (xy 128.679993 -384.44466)
			(xy 128.710543 -384.402612) (xy 128.747294 -384.365861) (xy 128.789342 -384.335311) (xy 128.835652 -384.311715)
			(xy 128.885082 -384.295654) (xy 128.936417 -384.287524) (xy 128.988391 -384.287524) (xy 129.039726 -384.295654)
			(xy 129.089156 -384.311715) (xy 129.135466 -384.335311) (xy 129.177514 -384.365861) (xy 129.214265 -384.402612)
			(xy 129.244815 -384.44466) (xy 129.268411 -384.49097) (xy 129.284472 -384.5404) (xy 129.292602 -384.591735)
			(xy 129.293112 -384.617722) (xy 129.831592 -384.617722) (xy 129.832102 -384.591735) (xy 129.840232 -384.5404)
			(xy 129.856293 -384.49097) (xy 129.879889 -384.44466) (xy 129.910439 -384.402612) (xy 129.94719 -384.365861)
			(xy 129.989238 -384.335311) (xy 130.035548 -384.311715) (xy 130.084978 -384.295654) (xy 130.136313 -384.287524)
			(xy 130.188287 -384.287524) (xy 130.239622 -384.295654) (xy 130.289052 -384.311715) (xy 130.335362 -384.335311)
			(xy 130.37741 -384.365861) (xy 130.414161 -384.402612) (xy 130.444711 -384.44466) (xy 130.468307 -384.49097)
			(xy 130.484368 -384.5404) (xy 130.492498 -384.591735) (xy 130.493008 -384.617722) (xy 131.031742 -384.617722)
			(xy 131.032252 -384.591735) (xy 131.040382 -384.5404) (xy 131.056443 -384.49097) (xy 131.080039 -384.44466)
			(xy 131.110589 -384.402612) (xy 131.14734 -384.365861) (xy 131.189388 -384.335311) (xy 131.235698 -384.311715)
			(xy 131.285128 -384.295654) (xy 131.336463 -384.287524) (xy 131.388437 -384.287524) (xy 131.439772 -384.295654)
			(xy 131.489202 -384.311715) (xy 131.535512 -384.335311) (xy 131.57756 -384.365861) (xy 131.614311 -384.402612)
			(xy 131.644861 -384.44466) (xy 131.668457 -384.49097) (xy 131.684518 -384.5404) (xy 131.692648 -384.591735)
			(xy 131.693158 -384.617722) (xy 132.231638 -384.617722) (xy 132.232148 -384.591735) (xy 132.240278 -384.5404)
			(xy 132.256339 -384.49097) (xy 132.279935 -384.44466) (xy 132.310485 -384.402612) (xy 132.347236 -384.365861)
			(xy 132.389284 -384.335311) (xy 132.435594 -384.311715) (xy 132.485024 -384.295654) (xy 132.536359 -384.287524)
			(xy 132.588333 -384.287524) (xy 132.639668 -384.295654) (xy 132.689098 -384.311715) (xy 132.735408 -384.335311)
			(xy 132.777456 -384.365861) (xy 132.814207 -384.402612) (xy 132.844757 -384.44466) (xy 132.868353 -384.49097)
			(xy 132.884414 -384.5404) (xy 132.892544 -384.591735) (xy 132.893054 -384.617722) (xy 132.892524 -384.644824)
			(xy 132.883714 -384.698307) (xy 132.875528 -384.724148) (xy 132.871718 -384.73507) (xy 132.874258 -384.757422)
			(xy 132.926836 -384.843274) (xy 132.945886 -384.85572) (xy 132.957062 -384.857498) (xy 132.986384 -384.862181)
			(xy 133.043555 -384.878233) (xy 133.098169 -384.901547) (xy 133.149308 -384.931729) (xy 133.196113 -384.968273)
			(xy 133.237797 -385.010564) (xy 133.273661 -385.057893) (xy 133.3031 -385.109463) (xy 133.319447 -385.149344)
			(xy 134.402322 -385.149344) (xy 134.402747 -385.120708) (xy 134.409904 -385.063886) (xy 134.424086 -385.008398)
			(xy 134.445073 -384.95511) (xy 134.472538 -384.904854) (xy 134.488936 -384.881374) (xy 134.494612 -384.872857)
			(xy 134.499222 -384.85293) (xy 134.495655 -384.832791) (xy 134.49046 -384.82397) (xy 134.472973 -384.795993)
			(xy 134.445344 -384.73608) (xy 134.426598 -384.672823) (xy 134.417125 -384.60753) (xy 134.416546 -384.574542)
			(xy 134.417008 -384.545301) (xy 134.424441 -384.487294) (xy 134.439202 -384.430706) (xy 134.461053 -384.37646)
			(xy 134.489636 -384.325439) (xy 134.524486 -384.278476) (xy 134.565035 -384.236335) (xy 134.610623 -384.199703)
			(xy 134.660505 -384.169177) (xy 134.71387 -384.145255) (xy 134.769848 -384.128327) (xy 134.827526 -384.118667)
			(xy 134.856728 -384.117088) (xy 134.86638 -384.116834) (xy 134.883906 -384.109214) (xy 134.94639 -384.046222)
			(xy 134.95401 -384.02895) (xy 134.954264 -384.019044) (xy 134.955853 -383.986494) (xy 134.966343 -383.922172)
			(xy 134.984963 -383.859718) (xy 135.01141 -383.800155) (xy 135.045251 -383.744459) (xy 135.085929 -383.693542)
			(xy 135.132779 -383.64824) (xy 135.185033 -383.609294) (xy 135.241834 -383.577343) (xy 135.302251 -383.55291)
			(xy 135.365295 -383.536397) (xy 135.429933 -383.528073) (xy 135.462518 -383.527554) (xy 135.496101 -383.528123)
			(xy 135.562684 -383.536949) (xy 135.627524 -383.554469) (xy 135.68949 -383.58038) (xy 135.747503 -383.61423)
			(xy 135.80055 -383.655427) (xy 135.847706 -383.703255) (xy 135.88815 -383.756878) (xy 135.921177 -383.815363)
			(xy 135.934196 -383.846324) (xy 135.939784 -383.86004) (xy 135.963406 -383.877058) (xy 136.084564 -383.884678)
			(xy 136.110218 -383.870454) (xy 136.11733 -383.8575) (xy 136.134273 -383.828169) (xy 136.17468 -383.773808)
			(xy 136.221942 -383.725288) (xy 136.275224 -383.683467) (xy 136.333584 -383.649086) (xy 136.395989 -383.622751)
			(xy 136.461337 -383.604929) (xy 136.528471 -383.595934) (xy 136.562338 -383.595372) (xy 136.592652 -383.595827)
			(xy 136.652853 -383.603014) (xy 136.711773 -383.617306) (xy 136.768577 -383.6385) (xy 136.822458 -383.666296)
			(xy 136.872654 -383.700299) (xy 136.89584 -383.719832) (xy 136.902698 -383.726182) (xy 136.919716 -383.732278)
			(xy 137.00506 -383.732278) (xy 137.022078 -383.726182) (xy 137.028936 -383.719832) (xy 137.052105 -383.700275)
			(xy 137.102296 -383.666256) (xy 137.156179 -383.63845) (xy 137.212986 -383.617253) (xy 137.271913 -383.602966)
			(xy 137.332121 -383.595792) (xy 137.362438 -383.595372) (xy 137.393169 -383.59582) (xy 137.454183 -383.603232)
			(xy 137.513858 -383.617945) (xy 137.571325 -383.639742) (xy 137.625746 -383.668307) (xy 137.676327 -383.703223)
			(xy 137.72145 -383.7432) (xy 143.311624 -383.7432) (xy 143.315695 -383.687578) (xy 143.327821 -383.633141)
			(xy 143.347744 -383.58105) (xy 143.37504 -383.532415) (xy 143.409126 -383.488272) (xy 143.449275 -383.449563)
			(xy 143.494633 -383.417112) (xy 143.544233 -383.391611) (xy 143.597017 -383.373604) (xy 143.65186 -383.363474)
			(xy 143.707594 -383.361437) (xy 143.763031 -383.367537) (xy 143.816988 -383.381643) (xy 143.868317 -383.403455)
			(xy 143.915923 -383.432509) (xy 143.958791 -383.468184) (xy 143.996008 -383.509721) (xy 144.026781 -383.556234)
			(xy 144.050453 -383.606731) (xy 144.066521 -383.660138) (xy 144.074641 -383.715314) (xy 144.07515 -383.7432)
			(xy 144.074641 -383.771086) (xy 144.066521 -383.826262) (xy 144.050453 -383.879669) (xy 144.026781 -383.930166)
			(xy 143.996008 -383.976679) (xy 143.958791 -384.018216) (xy 143.915923 -384.053891) (xy 143.868317 -384.082945)
			(xy 143.816988 -384.104757) (xy 143.763031 -384.118863) (xy 143.707594 -384.124963) (xy 143.65186 -384.122926)
			(xy 143.597017 -384.112796) (xy 143.544233 -384.094789) (xy 143.494633 -384.069288) (xy 143.449275 -384.036837)
			(xy 143.409126 -383.998128) (xy 143.37504 -383.953985) (xy 143.347744 -383.90535) (xy 143.327821 -383.853259)
			(xy 143.315695 -383.798822) (xy 143.311624 -383.7432) (xy 137.72145 -383.7432) (xy 137.722332 -383.743981)
			(xy 137.763088 -383.789987) (xy 137.798002 -383.840569) (xy 137.826565 -383.894991) (xy 137.848361 -383.952459)
			(xy 137.863071 -384.012135) (xy 137.870481 -384.073149) (xy 137.870946 -384.10388) (xy 137.870528 -384.13399)
			(xy 137.863397 -384.193788) (xy 137.849254 -384.252325) (xy 137.828299 -384.308782) (xy 137.800824 -384.362371)
			(xy 137.767214 -384.41234) (xy 137.727938 -384.457991) (xy 137.683548 -384.498686) (xy 137.659364 -384.51663)
			(xy 137.6499 -384.524256) (xy 137.638899 -384.545892) (xy 137.638282 -384.558032) (xy 137.638282 -384.640328)
			(xy 137.638889 -384.652463) (xy 137.644106 -384.66268) (xy 143.311624 -384.66268) (xy 143.315695 -384.607058)
			(xy 143.327821 -384.552621) (xy 143.347744 -384.50053) (xy 143.37504 -384.451895) (xy 143.409126 -384.407752)
			(xy 143.449275 -384.369043) (xy 143.494633 -384.336592) (xy 143.544233 -384.311091) (xy 143.597017 -384.293084)
			(xy 143.65186 -384.282954) (xy 143.707594 -384.280917) (xy 143.763031 -384.287017) (xy 143.816988 -384.301123)
			(xy 143.868317 -384.322935) (xy 143.915923 -384.351989) (xy 143.958402 -384.38734) (xy 144.571702 -384.38734)
			(xy 144.571702 -384.327404) (xy 144.579525 -384.267982) (xy 144.595038 -384.210089) (xy 144.617974 -384.154716)
			(xy 144.647941 -384.10281) (xy 144.684428 -384.05526) (xy 144.726808 -384.01288) (xy 144.774358 -383.976393)
			(xy 144.826264 -383.946426) (xy 144.881637 -383.92349) (xy 144.93953 -383.907977) (xy 144.998952 -383.900154)
			(xy 145.058888 -383.900154) (xy 145.11831 -383.907977) (xy 145.176203 -383.92349) (xy 145.231576 -383.946426)
			(xy 145.283482 -383.976393) (xy 145.331032 -384.01288) (xy 145.373412 -384.05526) (xy 145.409899 -384.10281)
			(xy 145.439866 -384.154716) (xy 145.462802 -384.210089) (xy 145.478315 -384.267982) (xy 145.486138 -384.327404)
			(xy 145.486628 -384.357372) (xy 145.486138 -384.38734) (xy 145.478315 -384.446762) (xy 145.462802 -384.504655)
			(xy 145.439866 -384.560028) (xy 145.409899 -384.611934) (xy 145.373412 -384.659484) (xy 145.331032 -384.701864)
			(xy 145.283482 -384.738351) (xy 145.231576 -384.768318) (xy 145.176203 -384.791254) (xy 145.11831 -384.806767)
			(xy 145.058888 -384.81459) (xy 144.998952 -384.81459) (xy 144.93953 -384.806767) (xy 144.881637 -384.791254)
			(xy 144.826264 -384.768318) (xy 144.774358 -384.738351) (xy 144.726808 -384.701864) (xy 144.684428 -384.659484)
			(xy 144.647941 -384.611934) (xy 144.617974 -384.560028) (xy 144.595038 -384.504655) (xy 144.579525 -384.446762)
			(xy 144.571702 -384.38734) (xy 143.958402 -384.38734) (xy 143.958791 -384.387664) (xy 143.996008 -384.429201)
			(xy 144.026781 -384.475714) (xy 144.050453 -384.526211) (xy 144.066521 -384.579618) (xy 144.074641 -384.634794)
			(xy 144.07515 -384.66268) (xy 144.074641 -384.690566) (xy 144.066521 -384.745742) (xy 144.050453 -384.799149)
			(xy 144.026781 -384.849646) (xy 143.996008 -384.896159) (xy 143.958791 -384.937696) (xy 143.915923 -384.973371)
			(xy 143.868317 -385.002425) (xy 143.816988 -385.024237) (xy 143.763031 -385.038343) (xy 143.707594 -385.044443)
			(xy 143.65186 -385.042406) (xy 143.597017 -385.032276) (xy 143.544233 -385.014269) (xy 143.494633 -384.988768)
			(xy 143.449275 -384.956317) (xy 143.409126 -384.917608) (xy 143.37504 -384.873465) (xy 143.347744 -384.82483)
			(xy 143.327821 -384.772739) (xy 143.315695 -384.718302) (xy 143.311624 -384.66268) (xy 137.644106 -384.66268)
			(xy 137.649924 -384.674076) (xy 137.659364 -384.68173) (xy 137.683558 -384.699662) (xy 137.72796 -384.740347)
			(xy 137.767243 -384.785995) (xy 137.800856 -384.835966) (xy 137.828327 -384.889558) (xy 137.849272 -384.946022)
			(xy 137.863398 -385.004566) (xy 137.870506 -385.064368) (xy 137.870946 -385.09448) (xy 137.870425 -385.125209)
			(xy 137.86302 -385.18622) (xy 137.848315 -385.245893) (xy 137.826524 -385.303358) (xy 137.797966 -385.357778)
			(xy 137.763056 -385.408359) (xy 137.722304 -385.454363) (xy 137.676305 -385.49512) (xy 137.625728 -385.530036)
			(xy 137.571311 -385.5586) (xy 137.513848 -385.580397) (xy 137.454177 -385.595109) (xy 137.393167 -385.602522)
			(xy 137.362438 -385.602988) (xy 137.330313 -385.602517) (xy 137.266577 -385.594406) (xy 137.204369 -385.578335)
			(xy 137.144681 -385.554558) (xy 137.088461 -385.523455) (xy 137.036605 -385.485521) (xy 137.012934 -385.463796)
			(xy 137.005588 -385.457452) (xy 136.987578 -385.450261) (xy 136.977882 -385.449826) (xy 136.946894 -385.449826)
			(xy 136.937192 -385.450252) (xy 136.919166 -385.457422) (xy 136.911842 -385.463796) (xy 136.896094 -385.478274)
			(xy 136.887204 -385.485894) (xy 136.878314 -385.506468) (xy 136.881616 -385.608576) (xy 136.882063 -385.609458)
			(xy 143.312515 -385.609458) (xy 143.312515 -385.554942) (xy 143.320274 -385.500982) (xy 143.335634 -385.448675)
			(xy 143.358282 -385.399087) (xy 143.387757 -385.353227) (xy 143.423459 -385.312029) (xy 143.464661 -385.276332)
			(xy 143.510524 -385.246862) (xy 143.560115 -385.224219) (xy 143.612423 -385.208865) (xy 143.666384 -385.201112)
			(xy 143.693642 -385.200652) (xy 143.722276 -385.201167) (xy 143.7789 -385.209733) (xy 143.833608 -385.226664)
			(xy 143.885171 -385.251582) (xy 143.932432 -385.283926) (xy 143.974327 -385.322969) (xy 144.009917 -385.367836)
			(xy 144.024604 -385.392422) (xy 144.031716 -385.404614) (xy 144.055592 -385.41833) (xy 144.172686 -385.416044)
			(xy 144.196054 -385.40182) (xy 144.202658 -385.389374) (xy 144.217629 -385.362141) (xy 144.253755 -385.311577)
			(xy 144.296394 -385.266368) (xy 144.344759 -385.227348) (xy 144.397962 -385.195234) (xy 144.455022 -385.170618)
			(xy 144.51489 -385.153952) (xy 144.576462 -385.145544) (xy 144.607534 -385.145026) (xy 144.637504 -385.14545)
			(xy 144.69693 -385.153278) (xy 144.754826 -385.168796) (xy 144.810202 -385.191738) (xy 144.862109 -385.221712)
			(xy 144.90966 -385.258205) (xy 144.95204 -385.300592) (xy 144.988526 -385.348148) (xy 145.018492 -385.400059)
			(xy 145.041426 -385.455438) (xy 145.056935 -385.513337) (xy 145.064754 -385.572764) (xy 145.065242 -385.602734)
			(xy 145.064747 -385.633614) (xy 145.056431 -385.694813) (xy 145.039955 -385.754335) (xy 145.015619 -385.811099)
			(xy 144.983865 -385.864072) (xy 144.974694 -385.87553) (xy 146.461734 -385.87553) (xy 146.462203 -385.849539)
			(xy 146.470331 -385.798198) (xy 146.486392 -385.74876) (xy 146.509989 -385.702444) (xy 146.540543 -385.660391)
			(xy 146.5773 -385.623635) (xy 146.619354 -385.593083) (xy 146.665671 -385.569487) (xy 146.71511 -385.553428)
			(xy 146.766451 -385.545302) (xy 146.792442 -385.544822) (xy 146.808875 -385.545047) (xy 146.841575 -385.548355)
			(xy 146.85772 -385.551426) (xy 146.870674 -385.553966) (xy 146.89582 -385.546092) (xy 146.973036 -385.464304)
			(xy 146.97964 -385.438904) (xy 146.976338 -385.426204) (xy 146.969331 -385.397762) (xy 146.961814 -385.339669)
			(xy 146.961352 -385.31038) (xy 146.96187 -385.279492) (xy 146.970177 -385.218276) (xy 146.986635 -385.158732)
			(xy 147.010948 -385.10194) (xy 147.026376 -385.075176) (xy 147.032218 -385.06527) (xy 147.034504 -385.042918)
			(xy 147.00123 -384.947668) (xy 146.985482 -384.931666) (xy 146.974814 -384.927602) (xy 146.951437 -384.918408)
			(xy 146.907539 -384.893992) (xy 146.867842 -384.863213) (xy 146.83326 -384.826781) (xy 146.804589 -384.785536)
			(xy 146.782491 -384.740426) (xy 146.767474 -384.692492) (xy 146.759884 -384.642838) (xy 146.759422 -384.617722)
			(xy 146.759932 -384.591735) (xy 146.768062 -384.5404) (xy 146.784123 -384.49097) (xy 146.807719 -384.44466)
			(xy 146.838269 -384.402612) (xy 146.87502 -384.365861) (xy 146.917068 -384.335311) (xy 146.963378 -384.311715)
			(xy 147.012808 -384.295654) (xy 147.064143 -384.287524) (xy 147.116117 -384.287524) (xy 147.167452 -384.295654)
			(xy 147.216882 -384.311715) (xy 147.263192 -384.335311) (xy 147.30524 -384.365861) (xy 147.341991 -384.402612)
			(xy 147.372541 -384.44466) (xy 147.396137 -384.49097) (xy 147.412198 -384.5404) (xy 147.420328 -384.591735)
			(xy 147.420838 -384.617722) (xy 147.959318 -384.617722) (xy 147.959828 -384.591735) (xy 147.967958 -384.5404)
			(xy 147.984019 -384.49097) (xy 148.007615 -384.44466) (xy 148.038165 -384.402612) (xy 148.074916 -384.365861)
			(xy 148.116964 -384.335311) (xy 148.163274 -384.311715) (xy 148.212704 -384.295654) (xy 148.264039 -384.287524)
			(xy 148.316013 -384.287524) (xy 148.367348 -384.295654) (xy 148.416778 -384.311715) (xy 148.463088 -384.335311)
			(xy 148.505136 -384.365861) (xy 148.541887 -384.402612) (xy 148.572437 -384.44466) (xy 148.596033 -384.49097)
			(xy 148.612094 -384.5404) (xy 148.620224 -384.591735) (xy 148.620734 -384.617722) (xy 149.159468 -384.617722)
			(xy 149.159978 -384.591735) (xy 149.168108 -384.5404) (xy 149.184169 -384.49097) (xy 149.207765 -384.44466)
			(xy 149.238315 -384.402612) (xy 149.275066 -384.365861) (xy 149.317114 -384.335311) (xy 149.363424 -384.311715)
			(xy 149.412854 -384.295654) (xy 149.464189 -384.287524) (xy 149.516163 -384.287524) (xy 149.567498 -384.295654)
			(xy 149.616928 -384.311715) (xy 149.663238 -384.335311) (xy 149.705286 -384.365861) (xy 149.742037 -384.402612)
			(xy 149.772587 -384.44466) (xy 149.796183 -384.49097) (xy 149.812244 -384.5404) (xy 149.820374 -384.591735)
			(xy 149.820884 -384.617722) (xy 150.359364 -384.617722) (xy 150.359874 -384.591735) (xy 150.368004 -384.5404)
			(xy 150.384065 -384.49097) (xy 150.407661 -384.44466) (xy 150.438211 -384.402612) (xy 150.474962 -384.365861)
			(xy 150.51701 -384.335311) (xy 150.56332 -384.311715) (xy 150.61275 -384.295654) (xy 150.664085 -384.287524)
			(xy 150.716059 -384.287524) (xy 150.767394 -384.295654) (xy 150.816824 -384.311715) (xy 150.863134 -384.335311)
			(xy 150.905182 -384.365861) (xy 150.941933 -384.402612) (xy 150.972483 -384.44466) (xy 150.996079 -384.49097)
			(xy 151.01214 -384.5404) (xy 151.02027 -384.591735) (xy 151.02078 -384.617722) (xy 151.559514 -384.617722)
			(xy 151.560024 -384.591735) (xy 151.568154 -384.5404) (xy 151.584215 -384.49097) (xy 151.607811 -384.44466)
			(xy 151.638361 -384.402612) (xy 151.675112 -384.365861) (xy 151.71716 -384.335311) (xy 151.76347 -384.311715)
			(xy 151.8129 -384.295654) (xy 151.864235 -384.287524) (xy 151.916209 -384.287524) (xy 151.967544 -384.295654)
			(xy 152.016974 -384.311715) (xy 152.063284 -384.335311) (xy 152.105332 -384.365861) (xy 152.142083 -384.402612)
			(xy 152.172633 -384.44466) (xy 152.196229 -384.49097) (xy 152.21229 -384.5404) (xy 152.22042 -384.591735)
			(xy 152.22093 -384.617722) (xy 152.75941 -384.617722) (xy 152.75992 -384.591735) (xy 152.76805 -384.5404)
			(xy 152.784111 -384.49097) (xy 152.807707 -384.44466) (xy 152.838257 -384.402612) (xy 152.875008 -384.365861)
			(xy 152.917056 -384.335311) (xy 152.963366 -384.311715) (xy 153.012796 -384.295654) (xy 153.064131 -384.287524)
			(xy 153.116105 -384.287524) (xy 153.16744 -384.295654) (xy 153.21687 -384.311715) (xy 153.26318 -384.335311)
			(xy 153.305228 -384.365861) (xy 153.341979 -384.402612) (xy 153.372529 -384.44466) (xy 153.396125 -384.49097)
			(xy 153.412186 -384.5404) (xy 153.420316 -384.591735) (xy 153.420826 -384.617722) (xy 153.959306 -384.617722)
			(xy 153.959816 -384.591735) (xy 153.967946 -384.5404) (xy 153.984007 -384.49097) (xy 154.007603 -384.44466)
			(xy 154.038153 -384.402612) (xy 154.074904 -384.365861) (xy 154.116952 -384.335311) (xy 154.163262 -384.311715)
			(xy 154.212692 -384.295654) (xy 154.264027 -384.287524) (xy 154.316001 -384.287524) (xy 154.367336 -384.295654)
			(xy 154.416766 -384.311715) (xy 154.463076 -384.335311) (xy 154.505124 -384.365861) (xy 154.541875 -384.402612)
			(xy 154.572425 -384.44466) (xy 154.596021 -384.49097) (xy 154.612082 -384.5404) (xy 154.620212 -384.591735)
			(xy 154.620722 -384.617722) (xy 155.159456 -384.617722) (xy 155.159966 -384.591735) (xy 155.168096 -384.5404)
			(xy 155.184157 -384.49097) (xy 155.207753 -384.44466) (xy 155.238303 -384.402612) (xy 155.275054 -384.365861)
			(xy 155.317102 -384.335311) (xy 155.363412 -384.311715) (xy 155.412842 -384.295654) (xy 155.464177 -384.287524)
			(xy 155.516151 -384.287524) (xy 155.567486 -384.295654) (xy 155.616916 -384.311715) (xy 155.663226 -384.335311)
			(xy 155.705274 -384.365861) (xy 155.742025 -384.402612) (xy 155.772575 -384.44466) (xy 155.796171 -384.49097)
			(xy 155.812232 -384.5404) (xy 155.820362 -384.591735) (xy 155.820872 -384.617722) (xy 156.359352 -384.617722)
			(xy 156.359862 -384.591735) (xy 156.367992 -384.5404) (xy 156.384053 -384.49097) (xy 156.407649 -384.44466)
			(xy 156.438199 -384.402612) (xy 156.47495 -384.365861) (xy 156.516998 -384.335311) (xy 156.563308 -384.311715)
			(xy 156.612738 -384.295654) (xy 156.664073 -384.287524) (xy 156.716047 -384.287524) (xy 156.767382 -384.295654)
			(xy 156.816812 -384.311715) (xy 156.863122 -384.335311) (xy 156.90517 -384.365861) (xy 156.941921 -384.402612)
			(xy 156.972471 -384.44466) (xy 156.996067 -384.49097) (xy 157.012128 -384.5404) (xy 157.020258 -384.591735)
			(xy 157.020768 -384.617722) (xy 157.559502 -384.617722) (xy 157.560012 -384.591735) (xy 157.568142 -384.5404)
			(xy 157.584203 -384.49097) (xy 157.607799 -384.44466) (xy 157.638349 -384.402612) (xy 157.6751 -384.365861)
			(xy 157.717148 -384.335311) (xy 157.763458 -384.311715) (xy 157.812888 -384.295654) (xy 157.864223 -384.287524)
			(xy 157.916197 -384.287524) (xy 157.967532 -384.295654) (xy 158.016962 -384.311715) (xy 158.063272 -384.335311)
			(xy 158.10532 -384.365861) (xy 158.142071 -384.402612) (xy 158.172621 -384.44466) (xy 158.196217 -384.49097)
			(xy 158.212278 -384.5404) (xy 158.220408 -384.591735) (xy 158.220918 -384.617722) (xy 158.759398 -384.617722)
			(xy 158.759908 -384.591735) (xy 158.768038 -384.5404) (xy 158.784099 -384.49097) (xy 158.807695 -384.44466)
			(xy 158.838245 -384.402612) (xy 158.874996 -384.365861) (xy 158.917044 -384.335311) (xy 158.963354 -384.311715)
			(xy 159.012784 -384.295654) (xy 159.064119 -384.287524) (xy 159.116093 -384.287524) (xy 159.167428 -384.295654)
			(xy 159.216858 -384.311715) (xy 159.263168 -384.335311) (xy 159.305216 -384.365861) (xy 159.341967 -384.402612)
			(xy 159.372517 -384.44466) (xy 159.396113 -384.49097) (xy 159.412174 -384.5404) (xy 159.420304 -384.591735)
			(xy 159.420814 -384.617722) (xy 159.959294 -384.617722) (xy 159.959804 -384.591735) (xy 159.967934 -384.5404)
			(xy 159.983995 -384.49097) (xy 160.007591 -384.44466) (xy 160.038141 -384.402612) (xy 160.074892 -384.365861)
			(xy 160.11694 -384.335311) (xy 160.16325 -384.311715) (xy 160.21268 -384.295654) (xy 160.264015 -384.287524)
			(xy 160.315989 -384.287524) (xy 160.367324 -384.295654) (xy 160.416754 -384.311715) (xy 160.463064 -384.335311)
			(xy 160.505112 -384.365861) (xy 160.541863 -384.402612) (xy 160.572413 -384.44466) (xy 160.596009 -384.49097)
			(xy 160.61207 -384.5404) (xy 160.6202 -384.591735) (xy 160.62071 -384.617722) (xy 161.159444 -384.617722)
			(xy 161.159954 -384.591735) (xy 161.168084 -384.5404) (xy 161.184145 -384.49097) (xy 161.207741 -384.44466)
			(xy 161.238291 -384.402612) (xy 161.275042 -384.365861) (xy 161.31709 -384.335311) (xy 161.3634 -384.311715)
			(xy 161.41283 -384.295654) (xy 161.464165 -384.287524) (xy 161.516139 -384.287524) (xy 161.567474 -384.295654)
			(xy 161.616904 -384.311715) (xy 161.663214 -384.335311) (xy 161.705262 -384.365861) (xy 161.742013 -384.402612)
			(xy 161.772563 -384.44466) (xy 161.796159 -384.49097) (xy 161.81222 -384.5404) (xy 161.82035 -384.591735)
			(xy 161.82086 -384.617722) (xy 162.35934 -384.617722) (xy 162.35985 -384.591735) (xy 162.36798 -384.5404)
			(xy 162.384041 -384.49097) (xy 162.407637 -384.44466) (xy 162.438187 -384.402612) (xy 162.474938 -384.365861)
			(xy 162.516986 -384.335311) (xy 162.563296 -384.311715) (xy 162.612726 -384.295654) (xy 162.664061 -384.287524)
			(xy 162.716035 -384.287524) (xy 162.76737 -384.295654) (xy 162.8168 -384.311715) (xy 162.86311 -384.335311)
			(xy 162.905158 -384.365861) (xy 162.941909 -384.402612) (xy 162.972459 -384.44466) (xy 162.996055 -384.49097)
			(xy 163.012116 -384.5404) (xy 163.020246 -384.591735) (xy 163.020756 -384.617722) (xy 163.55949 -384.617722)
			(xy 163.56 -384.591735) (xy 163.56813 -384.5404) (xy 163.584191 -384.49097) (xy 163.607787 -384.44466)
			(xy 163.638337 -384.402612) (xy 163.675088 -384.365861) (xy 163.717136 -384.335311) (xy 163.763446 -384.311715)
			(xy 163.812876 -384.295654) (xy 163.864211 -384.287524) (xy 163.916185 -384.287524) (xy 163.96752 -384.295654)
			(xy 164.01695 -384.311715) (xy 164.06326 -384.335311) (xy 164.105308 -384.365861) (xy 164.142059 -384.402612)
			(xy 164.172609 -384.44466) (xy 164.196205 -384.49097) (xy 164.212266 -384.5404) (xy 164.220396 -384.591735)
			(xy 164.220906 -384.617722) (xy 164.759386 -384.617722) (xy 164.759896 -384.591735) (xy 164.768026 -384.5404)
			(xy 164.784087 -384.49097) (xy 164.807683 -384.44466) (xy 164.838233 -384.402612) (xy 164.874984 -384.365861)
			(xy 164.917032 -384.335311) (xy 164.963342 -384.311715) (xy 165.012772 -384.295654) (xy 165.064107 -384.287524)
			(xy 165.116081 -384.287524) (xy 165.167416 -384.295654) (xy 165.216846 -384.311715) (xy 165.263156 -384.335311)
			(xy 165.305204 -384.365861) (xy 165.341955 -384.402612) (xy 165.372505 -384.44466) (xy 165.396101 -384.49097)
			(xy 165.412162 -384.5404) (xy 165.420292 -384.591735) (xy 165.420802 -384.617722) (xy 165.420269 -384.644824)
			(xy 165.411461 -384.698306) (xy 165.403276 -384.724148) (xy 165.399466 -384.73507) (xy 165.402006 -384.757422)
			(xy 165.454584 -384.843274) (xy 165.473634 -384.85572) (xy 165.48481 -384.857498) (xy 165.514125 -384.862222)
			(xy 165.571296 -384.878268) (xy 165.62591 -384.901575) (xy 165.67705 -384.931752) (xy 165.723856 -384.968291)
			(xy 165.765541 -385.010579) (xy 165.801406 -385.057904) (xy 165.830846 -385.109471) (xy 165.847191 -385.149344)
			(xy 166.93007 -385.149344) (xy 166.930505 -385.120709) (xy 166.937661 -385.063887) (xy 166.951841 -385.0084)
			(xy 166.972826 -384.955112) (xy 167.000287 -384.904854) (xy 167.016684 -384.881374) (xy 167.022364 -384.872858)
			(xy 167.026978 -384.85293) (xy 167.023407 -384.83279) (xy 167.018208 -384.82397) (xy 167.000726 -384.795989)
			(xy 166.973094 -384.736078) (xy 166.954347 -384.672822) (xy 166.944873 -384.60753) (xy 166.944294 -384.574542)
			(xy 166.9448 -384.544574) (xy 166.952619 -384.48515) (xy 166.968127 -384.427255) (xy 166.99106 -384.371879)
			(xy 167.021025 -384.319971) (xy 167.057509 -384.272419) (xy 167.099889 -384.230036) (xy 167.147438 -384.193547)
			(xy 167.199343 -384.163577) (xy 167.254717 -384.14064) (xy 167.31261 -384.125126) (xy 167.372034 -384.117303)
			(xy 167.402002 -384.116834) (xy 167.431747 -384.117291) (xy 167.490735 -384.125) (xy 167.548227 -384.140286)
			(xy 167.603255 -384.162892) (xy 167.654889 -384.192437) (xy 167.678862 -384.210052) (xy 167.688442 -384.216547)
			(xy 167.711126 -384.22101) (xy 167.733484 -384.215128) (xy 167.742616 -384.20802) (xy 167.767032 -384.187714)
			(xy 167.81998 -384.152651) (xy 167.876878 -384.124446) (xy 167.9067 -384.113532) (xy 167.917648 -384.109081)
			(xy 167.934111 -384.092164) (xy 167.941228 -384.069658) (xy 167.939974 -384.057906) (xy 167.937228 -384.038656)
			(xy 167.9343 -383.99988) (xy 167.934132 -383.980436) (xy 167.934634 -383.948475) (xy 167.942645 -383.885057)
			(xy 167.958542 -383.823143) (xy 167.982074 -383.76371) (xy 168.012868 -383.707695) (xy 168.050441 -383.65598)
			(xy 168.094198 -383.609383) (xy 168.143451 -383.568638) (xy 168.197422 -383.534387) (xy 168.255261 -383.50717)
			(xy 168.316054 -383.487417) (xy 168.378844 -383.475439) (xy 168.44264 -383.471426) (xy 168.506436 -383.475439)
			(xy 168.569226 -383.487417) (xy 168.630019 -383.50717) (xy 168.687858 -383.534387) (xy 168.741829 -383.568638)
			(xy 168.791082 -383.609383) (xy 168.834839 -383.65598) (xy 168.872412 -383.707695) (xy 168.903206 -383.76371)
			(xy 168.926738 -383.823143) (xy 168.942635 -383.885057) (xy 168.950646 -383.948475) (xy 168.951148 -383.980436)
			(xy 168.950666 -384.011842) (xy 168.942926 -384.074174) (xy 168.927568 -384.135079) (xy 168.904827 -384.193629)
			(xy 168.875047 -384.248932) (xy 168.838683 -384.300147) (xy 168.796289 -384.346493) (xy 168.748509 -384.387266)
			(xy 168.696072 -384.421843) (xy 168.639775 -384.449699) (xy 168.61028 -384.460496) (xy 168.599361 -384.465003)
			(xy 168.582902 -384.481897) (xy 168.575768 -384.504378) (xy 168.577006 -384.516122) (xy 168.579755 -384.535371)
			(xy 168.582681 -384.574148) (xy 168.582848 -384.593592) (xy 168.582531 -384.617941) (xy 168.577826 -384.666412)
			(xy 168.57345 -384.690366) (xy 168.572112 -384.699232) (xy 168.574966 -384.716922) (xy 168.579038 -384.72491)
			(xy 168.59377 -384.751326) (xy 168.598492 -384.758942) (xy 168.612153 -384.770522) (xy 168.62044 -384.773932)
			(xy 168.649193 -384.785177) (xy 168.703996 -384.813611) (xy 168.754953 -384.84847) (xy 168.801316 -384.889241)
			(xy 168.842401 -384.935326) (xy 168.877605 -384.986046) (xy 168.90641 -385.040654) (xy 168.928391 -385.098349)
			(xy 168.943226 -385.15828) (xy 168.950212 -385.215595) (xy 188.722248 -385.215595) (xy 188.722248 -385.151673)
			(xy 188.730259 -385.088255) (xy 188.746156 -385.026341) (xy 188.769688 -384.966908) (xy 188.800482 -384.910893)
			(xy 188.838055 -384.859178) (xy 188.881812 -384.812581) (xy 188.931065 -384.771836) (xy 188.985036 -384.737585)
			(xy 189.042875 -384.710368) (xy 189.103668 -384.690615) (xy 189.166458 -384.678637) (xy 189.230254 -384.674624)
			(xy 189.29405 -384.678637) (xy 189.35684 -384.690615) (xy 189.417633 -384.710368) (xy 189.475472 -384.737585)
			(xy 189.529443 -384.771836) (xy 189.578696 -384.812581) (xy 189.622453 -384.859178) (xy 189.660026 -384.910893)
			(xy 189.69082 -384.966908) (xy 189.714352 -385.026341) (xy 189.730249 -385.088255) (xy 189.73826 -385.151673)
			(xy 189.738682 -385.178554) (xy 190.030862 -385.178554) (xy 190.031391 -385.145093) (xy 190.040163 -385.078748)
			(xy 190.057564 -385.014128) (xy 190.083292 -384.952349) (xy 190.116902 -384.894479) (xy 190.157814 -384.841519)
			(xy 190.20532 -384.794383) (xy 190.2586 -384.753888) (xy 190.287402 -384.736848) (xy 190.300212 -384.728806)
			(xy 190.320921 -384.706792) (xy 190.33429 -384.679686) (xy 190.339153 -384.649856) (xy 190.335083 -384.619908)
			(xy 190.322437 -384.592457) (xy 190.302319 -384.569901) (xy 190.289688 -384.561588) (xy 190.261927 -384.544289)
			(xy 190.210687 -384.503628) (xy 190.165084 -384.456733) (xy 190.12587 -384.404378) (xy 190.093694 -384.347426)
			(xy 190.069085 -384.286819) (xy 190.052452 -384.223557) (xy 190.044067 -384.158684) (xy 190.043562 -384.125978)
			(xy 190.044064 -384.094017) (xy 190.052075 -384.030599) (xy 190.067972 -383.968685) (xy 190.091504 -383.909252)
			(xy 190.122298 -383.853237) (xy 190.159871 -383.801522) (xy 190.203628 -383.754925) (xy 190.252881 -383.71418)
			(xy 190.306852 -383.679929) (xy 190.364691 -383.652712) (xy 190.425484 -383.632959) (xy 190.488274 -383.620981)
			(xy 190.55207 -383.616968) (xy 190.615866 -383.620981) (xy 190.678656 -383.632959) (xy 190.739449 -383.652712)
			(xy 190.797288 -383.679929) (xy 190.851259 -383.71418) (xy 190.900512 -383.754925) (xy 190.944269 -383.801522)
			(xy 190.981842 -383.853237) (xy 191.012636 -383.909252) (xy 191.036168 -383.968685) (xy 191.052065 -384.030599)
			(xy 191.060076 -384.094017) (xy 191.060578 -384.125978) (xy 191.060055 -384.159439) (xy 191.051279 -384.225783)
			(xy 191.033876 -384.290403) (xy 191.008147 -384.352181) (xy 190.974536 -384.410051) (xy 190.933624 -384.463011)
			(xy 190.886118 -384.510146) (xy 190.83284 -384.550643) (xy 190.804038 -384.567684) (xy 190.791195 -384.57568)
			(xy 190.770476 -384.597701) (xy 190.757102 -384.624817) (xy 190.752241 -384.65466) (xy 190.753056 -384.660648)
			(xy 191.979296 -384.660648) (xy 191.979826 -384.62721) (xy 191.98858 -384.560909) (xy 192.005957 -384.49633)
			(xy 192.031655 -384.434589) (xy 192.065231 -384.376752) (xy 192.106104 -384.32382) (xy 192.153569 -384.276708)
			(xy 192.206803 -384.23623) (xy 192.235582 -384.219196) (xy 192.246504 -384.212846) (xy 192.259712 -384.192018)
			(xy 192.26911 -384.08356) (xy 192.259458 -384.0607) (xy 192.249806 -384.052572) (xy 192.225404 -384.031853)
			(xy 192.181525 -383.985241) (xy 192.143845 -383.93349) (xy 192.11296 -383.877417) (xy 192.089358 -383.817911)
			(xy 192.073414 -383.755913) (xy 192.065378 -383.692404) (xy 192.064894 -383.660396) (xy 192.065339 -383.629875)
			(xy 192.072658 -383.569273) (xy 192.087177 -383.509983) (xy 192.108689 -383.452857) (xy 192.136883 -383.398716)
			(xy 192.171355 -383.348339) (xy 192.211609 -383.30245) (xy 192.257065 -383.261709) (xy 192.28181 -383.243836)
			(xy 192.291627 -383.236353) (xy 192.303071 -383.214511) (xy 192.303654 -383.20218) (xy 192.303654 -383.118868)
			(xy 192.302897 -383.106585) (xy 192.29148 -383.084825) (xy 192.28181 -383.077212) (xy 192.257046 -383.059364)
			(xy 192.211583 -383.018625) (xy 192.171326 -382.972735) (xy 192.136853 -382.922355) (xy 192.108661 -382.868209)
			(xy 192.087156 -382.811077) (xy 192.072647 -382.751781) (xy 192.065343 -382.691175) (xy 192.064894 -382.660652)
			(xy 192.065312 -382.630105) (xy 192.072627 -382.569451) (xy 192.087157 -382.510111) (xy 192.108694 -382.452939)
			(xy 192.136927 -382.398761) (xy 192.171448 -382.348355) (xy 192.211761 -382.30245) (xy 192.257285 -382.261707)
			(xy 192.282064 -382.243838) (xy 192.29189 -382.236365) (xy 192.303327 -382.214515) (xy 192.303908 -382.202182)
			(xy 192.303908 -382.11887) (xy 192.303168 -382.106584) (xy 192.291741 -382.084823) (xy 192.282064 -382.077214)
			(xy 192.255655 -382.058121) (xy 192.207449 -382.014269) (xy 192.16524 -381.964618) (xy 192.12972 -381.909982)
			(xy 192.101471 -381.851256) (xy 192.080955 -381.789402) (xy 192.06851 -381.725434) (xy 192.064339 -381.6604)
			(xy 192.06851 -381.595366) (xy 192.080955 -381.531398) (xy 192.101471 -381.469544) (xy 192.12972 -381.410818)
			(xy 192.16524 -381.356182) (xy 192.207449 -381.306531) (xy 192.255655 -381.262679) (xy 192.282064 -381.243586)
			(xy 192.291639 -381.235915) (xy 192.302923 -381.214175) (xy 192.303654 -381.20193) (xy 192.303654 -381.118872)
			(xy 192.302948 -381.106612) (xy 192.291686 -381.084842) (xy 192.282064 -381.077216) (xy 192.255657 -381.05812)
			(xy 192.207451 -381.014269) (xy 192.165242 -380.964618) (xy 192.129722 -380.909982) (xy 192.101473 -380.851256)
			(xy 192.080957 -380.789403) (xy 192.068512 -380.725435) (xy 192.06434 -380.660401) (xy 192.068512 -380.595368)
			(xy 192.080957 -380.5314) (xy 192.101472 -380.469546) (xy 192.129721 -380.41082) (xy 192.165241 -380.356184)
			(xy 192.20745 -380.306533) (xy 192.255656 -380.262681) (xy 192.282064 -380.243588) (xy 192.291638 -380.235916)
			(xy 192.302923 -380.214177) (xy 192.303654 -380.201932) (xy 192.303654 -380.118874) (xy 192.302947 -380.106615)
			(xy 192.291686 -380.084844) (xy 192.282064 -380.077218) (xy 192.255659 -380.058119) (xy 192.207453 -380.014268)
			(xy 192.165244 -379.964618) (xy 192.129724 -379.909983) (xy 192.101475 -379.851257) (xy 192.080959 -379.789403)
			(xy 192.068514 -379.725436) (xy 192.064342 -379.660402) (xy 192.068513 -379.595369) (xy 192.080958 -379.531401)
			(xy 192.101473 -379.469547) (xy 192.129722 -379.410821) (xy 192.165241 -379.356185) (xy 192.20745 -379.306535)
			(xy 192.255656 -379.262683) (xy 192.282064 -379.24359) (xy 192.291682 -379.235964) (xy 192.302944 -379.21419)
			(xy 192.303654 -379.201934) (xy 192.303654 -379.118876) (xy 192.302945 -379.106617) (xy 192.291685 -379.084846)
			(xy 192.282064 -379.07722) (xy 192.257287 -379.059352) (xy 192.211774 -379.018601) (xy 192.171471 -378.972691)
			(xy 192.136957 -378.922285) (xy 192.10873 -378.868107) (xy 192.087196 -378.810938) (xy 192.072665 -378.751601)
			(xy 192.065347 -378.690951) (xy 192.064894 -378.660406) (xy 192.065396 -378.628445) (xy 192.073407 -378.565027)
			(xy 192.089304 -378.503113) (xy 192.112836 -378.44368) (xy 192.14363 -378.387665) (xy 192.181203 -378.33595)
			(xy 192.22496 -378.289353) (xy 192.274213 -378.248608) (xy 192.328184 -378.214357) (xy 192.386023 -378.18714)
			(xy 192.446816 -378.167387) (xy 192.509606 -378.155409) (xy 192.573402 -378.151396) (xy 192.637198 -378.155409)
			(xy 192.699988 -378.167387) (xy 192.760781 -378.18714) (xy 192.81862 -378.214357) (xy 192.872591 -378.248608)
			(xy 192.921844 -378.289353) (xy 192.965601 -378.33595) (xy 193.003174 -378.387665) (xy 193.033968 -378.44368)
			(xy 193.0575 -378.503113) (xy 193.070952 -378.555504) (xy 204.904848 -378.555504) (xy 204.905275 -378.525288)
			(xy 204.912462 -378.465285) (xy 204.926713 -378.406557) (xy 204.947826 -378.349933) (xy 204.975503 -378.296211)
			(xy 205.009354 -378.246149) (xy 205.0288 -378.223018) (xy 205.034418 -378.215876) (xy 205.040667 -378.198825)
			(xy 205.040992 -378.189744) (xy 205.040992 -378.159264) (xy 205.040665 -378.150183) (xy 205.034419 -378.133132)
			(xy 205.0288 -378.12599) (xy 205.009372 -378.102846) (xy 204.97553 -378.052782) (xy 204.947859 -377.999061)
			(xy 204.926748 -377.94244) (xy 204.912494 -377.883717) (xy 204.905298 -377.823718) (xy 204.904848 -377.793504)
			(xy 204.90535 -377.761543) (xy 204.913361 -377.698125) (xy 204.929258 -377.636211) (xy 204.95279 -377.576778)
			(xy 204.983584 -377.520763) (xy 205.021157 -377.469048) (xy 205.064914 -377.422451) (xy 205.114167 -377.381706)
			(xy 205.168138 -377.347455) (xy 205.225977 -377.320238) (xy 205.28677 -377.300485) (xy 205.34956 -377.288507)
			(xy 205.413356 -377.284494) (xy 205.477152 -377.288507) (xy 205.539942 -377.300485) (xy 205.600735 -377.320238)
			(xy 205.658574 -377.347455) (xy 205.712545 -377.381706) (xy 205.761798 -377.422451) (xy 205.805555 -377.469048)
			(xy 205.843128 -377.520763) (xy 205.873922 -377.576778) (xy 205.897454 -377.636211) (xy 205.913351 -377.698125)
			(xy 205.921362 -377.761543) (xy 205.921864 -377.793504) (xy 205.921439 -377.82372) (xy 205.914251 -377.883723)
			(xy 205.899999 -377.942451) (xy 205.878886 -377.999075) (xy 205.851209 -378.052797) (xy 205.817358 -378.102859)
			(xy 205.797912 -378.12599) (xy 205.792292 -378.133131) (xy 205.786044 -378.150182) (xy 205.78572 -378.159264)
			(xy 205.78572 -378.189744) (xy 205.78604 -378.198826) (xy 205.792291 -378.215877) (xy 205.797912 -378.223018)
			(xy 205.817346 -378.246157) (xy 205.851186 -378.296223) (xy 205.878856 -378.349944) (xy 205.899967 -378.406566)
			(xy 205.914219 -378.46529) (xy 205.921414 -378.52529) (xy 205.921864 -378.555504) (xy 206.930752 -378.555504)
			(xy 206.931178 -378.525288) (xy 206.938365 -378.465285) (xy 206.952616 -378.406557) (xy 206.973729 -378.349933)
			(xy 207.001407 -378.296211) (xy 207.035258 -378.246149) (xy 207.054704 -378.223018) (xy 207.060323 -378.215876)
			(xy 207.066571 -378.198825) (xy 207.066896 -378.189744) (xy 207.066896 -378.159264) (xy 207.066569 -378.150183)
			(xy 207.060323 -378.133132) (xy 207.054704 -378.12599) (xy 207.035276 -378.102845) (xy 207.001435 -378.052782)
			(xy 206.973763 -377.999061) (xy 206.952652 -377.94244) (xy 206.938398 -377.883717) (xy 206.931202 -377.823718)
			(xy 206.930752 -377.793504) (xy 206.931254 -377.761543) (xy 206.939265 -377.698125) (xy 206.955162 -377.636211)
			(xy 206.978694 -377.576778) (xy 207.009488 -377.520763) (xy 207.047061 -377.469048) (xy 207.090818 -377.422451)
			(xy 207.140071 -377.381706) (xy 207.194042 -377.347455) (xy 207.251881 -377.320238) (xy 207.312674 -377.300485)
			(xy 207.375464 -377.288507) (xy 207.43926 -377.284494) (xy 207.503056 -377.288507) (xy 207.565846 -377.300485)
			(xy 207.626639 -377.320238) (xy 207.684478 -377.347455) (xy 207.738449 -377.381706) (xy 207.787702 -377.422451)
			(xy 207.831459 -377.469048) (xy 207.869032 -377.520763) (xy 207.899826 -377.576778) (xy 207.923358 -377.636211)
			(xy 207.939255 -377.698125) (xy 207.947266 -377.761543) (xy 207.947768 -377.793504) (xy 207.947342 -377.82372)
			(xy 207.940154 -377.883723) (xy 207.925903 -377.942451) (xy 207.90479 -377.999075) (xy 207.877112 -378.052797)
			(xy 207.843262 -378.102859) (xy 207.823816 -378.12599) (xy 207.818196 -378.133131) (xy 207.811948 -378.150182)
			(xy 207.811624 -378.159264) (xy 207.811624 -378.189744) (xy 207.811943 -378.198826) (xy 207.818194 -378.215877)
			(xy 207.823816 -378.223018) (xy 207.843251 -378.246157) (xy 207.877091 -378.296222) (xy 207.904761 -378.349944)
			(xy 207.925871 -378.406566) (xy 207.940123 -378.46529) (xy 207.947318 -378.52529) (xy 207.947768 -378.555504)
			(xy 208.968848 -378.555504) (xy 208.969275 -378.525288) (xy 208.976462 -378.465285) (xy 208.990713 -378.406557)
			(xy 209.011826 -378.349933) (xy 209.039503 -378.296211) (xy 209.073354 -378.246149) (xy 209.0928 -378.223018)
			(xy 209.098418 -378.215876) (xy 209.104667 -378.198825) (xy 209.104992 -378.189744) (xy 209.104992 -378.159264)
			(xy 209.104665 -378.150183) (xy 209.098419 -378.133132) (xy 209.0928 -378.12599) (xy 209.073372 -378.102846)
			(xy 209.03953 -378.052782) (xy 209.011859 -377.999061) (xy 208.990748 -377.94244) (xy 208.976494 -377.883717)
			(xy 208.969298 -377.823718) (xy 208.968848 -377.793504) (xy 208.96935 -377.761543) (xy 208.977361 -377.698125)
			(xy 208.993258 -377.636211) (xy 209.01679 -377.576778) (xy 209.047584 -377.520763) (xy 209.085157 -377.469048)
			(xy 209.128914 -377.422451) (xy 209.178167 -377.381706) (xy 209.232138 -377.347455) (xy 209.289977 -377.320238)
			(xy 209.35077 -377.300485) (xy 209.41356 -377.288507) (xy 209.477356 -377.284494) (xy 209.541152 -377.288507)
			(xy 209.603942 -377.300485) (xy 209.664735 -377.320238) (xy 209.722574 -377.347455) (xy 209.776545 -377.381706)
			(xy 209.825798 -377.422451) (xy 209.869555 -377.469048) (xy 209.907128 -377.520763) (xy 209.937922 -377.576778)
			(xy 209.961454 -377.636211) (xy 209.977351 -377.698125) (xy 209.985362 -377.761543) (xy 209.985864 -377.793504)
			(xy 209.985439 -377.82372) (xy 209.978251 -377.883723) (xy 209.963999 -377.942451) (xy 209.942886 -377.999075)
			(xy 209.915209 -378.052797) (xy 209.881358 -378.102859) (xy 209.861912 -378.12599) (xy 209.856292 -378.133131)
			(xy 209.850044 -378.150182) (xy 209.84972 -378.159264) (xy 209.84972 -378.189744) (xy 209.85004 -378.198826)
			(xy 209.856291 -378.215877) (xy 209.861912 -378.223018) (xy 209.881346 -378.246157) (xy 209.915186 -378.296223)
			(xy 209.942856 -378.349944) (xy 209.963967 -378.406566) (xy 209.978219 -378.46529) (xy 209.985414 -378.52529)
			(xy 209.985864 -378.555504) (xy 209.985362 -378.587465) (xy 209.977351 -378.650883) (xy 209.961454 -378.712797)
			(xy 209.937922 -378.77223) (xy 209.907128 -378.828245) (xy 209.869555 -378.87996) (xy 209.825798 -378.926557)
			(xy 209.776545 -378.967302) (xy 209.722574 -379.001553) (xy 209.664735 -379.02877) (xy 209.603942 -379.048523)
			(xy 209.541152 -379.060501) (xy 209.477356 -379.064515) (xy 209.41356 -379.060501) (xy 209.35077 -379.048523)
			(xy 209.289977 -379.02877) (xy 209.232138 -379.001553) (xy 209.178167 -378.967302) (xy 209.128914 -378.926557)
			(xy 209.085157 -378.87996) (xy 209.047584 -378.828245) (xy 209.01679 -378.77223) (xy 208.993258 -378.712797)
			(xy 208.977361 -378.650883) (xy 208.96935 -378.587465) (xy 208.968848 -378.555504) (xy 207.947768 -378.555504)
			(xy 207.947266 -378.587465) (xy 207.939255 -378.650883) (xy 207.923358 -378.712797) (xy 207.899826 -378.77223)
			(xy 207.869032 -378.828245) (xy 207.831459 -378.87996) (xy 207.787702 -378.926557) (xy 207.738449 -378.967302)
			(xy 207.684478 -379.001553) (xy 207.626639 -379.02877) (xy 207.565846 -379.048523) (xy 207.503056 -379.060501)
			(xy 207.43926 -379.064515) (xy 207.375464 -379.060501) (xy 207.312674 -379.048523) (xy 207.251881 -379.02877)
			(xy 207.194042 -379.001553) (xy 207.140071 -378.967302) (xy 207.090818 -378.926557) (xy 207.047061 -378.87996)
			(xy 207.009488 -378.828245) (xy 206.978694 -378.77223) (xy 206.955162 -378.712797) (xy 206.939265 -378.650883)
			(xy 206.931254 -378.587465) (xy 206.930752 -378.555504) (xy 205.921864 -378.555504) (xy 205.921362 -378.587465)
			(xy 205.913351 -378.650883) (xy 205.897454 -378.712797) (xy 205.873922 -378.77223) (xy 205.843128 -378.828245)
			(xy 205.805555 -378.87996) (xy 205.761798 -378.926557) (xy 205.712545 -378.967302) (xy 205.658574 -379.001553)
			(xy 205.600735 -379.02877) (xy 205.539942 -379.048523) (xy 205.477152 -379.060501) (xy 205.413356 -379.064515)
			(xy 205.34956 -379.060501) (xy 205.28677 -379.048523) (xy 205.225977 -379.02877) (xy 205.168138 -379.001553)
			(xy 205.114167 -378.967302) (xy 205.064914 -378.926557) (xy 205.021157 -378.87996) (xy 204.983584 -378.828245)
			(xy 204.95279 -378.77223) (xy 204.929258 -378.712797) (xy 204.913361 -378.650883) (xy 204.90535 -378.587465)
			(xy 204.904848 -378.555504) (xy 193.070952 -378.555504) (xy 193.073397 -378.565027) (xy 193.081408 -378.628445)
			(xy 193.08191 -378.660406) (xy 193.081458 -378.690952) (xy 193.074148 -378.751604) (xy 193.059623 -378.810944)
			(xy 193.038091 -378.868115) (xy 193.009863 -378.922294) (xy 192.975346 -378.9727) (xy 192.935037 -379.018606)
			(xy 192.889518 -379.05935) (xy 192.86474 -379.07722) (xy 192.855163 -379.084889) (xy 192.84388 -379.10663)
			(xy 192.84315 -379.118876) (xy 192.84315 -379.201934) (xy 192.843851 -379.214194) (xy 192.855116 -379.235965)
			(xy 192.86474 -379.24359) (xy 192.891152 -379.262678) (xy 192.939358 -379.306531) (xy 192.981567 -379.356182)
			(xy 193.017087 -379.410819) (xy 193.045336 -379.469545) (xy 193.065851 -379.5314) (xy 193.078296 -379.595368)
			(xy 193.082467 -379.660402) (xy 193.078295 -379.725436) (xy 193.06585 -379.789405) (xy 193.045334 -379.851259)
			(xy 193.017085 -379.909985) (xy 192.981564 -379.964622) (xy 192.939355 -380.014273) (xy 192.891149 -380.058124)
			(xy 192.86474 -380.077218) (xy 192.855164 -380.084888) (xy 192.84388 -380.106629) (xy 192.84315 -380.118874)
			(xy 192.84315 -380.201932) (xy 192.843852 -380.214192) (xy 192.855117 -380.235963) (xy 192.86474 -380.243588)
			(xy 192.89115 -380.262679) (xy 192.939356 -380.306531) (xy 192.981565 -380.356182) (xy 193.017085 -380.410818)
			(xy 193.045334 -380.469545) (xy 193.065849 -380.531399) (xy 193.078294 -380.595367) (xy 193.082465 -380.660401)
			(xy 193.078294 -380.725435) (xy 193.065848 -380.789403) (xy 193.045333 -380.851257) (xy 193.017084 -380.909984)
			(xy 192.981564 -380.96462) (xy 192.939355 -381.014271) (xy 192.891149 -381.058122) (xy 192.86474 -381.077216)
			(xy 192.855165 -381.084887) (xy 192.84388 -381.106627) (xy 192.84315 -381.118872) (xy 192.84315 -381.20193)
			(xy 192.843854 -381.21419) (xy 192.855117 -381.235961) (xy 192.86474 -381.243586) (xy 192.891148 -381.26268)
			(xy 192.939354 -381.306531) (xy 192.981563 -381.356182) (xy 193.017083 -381.410818) (xy 193.045332 -381.469544)
			(xy 193.065847 -381.531398) (xy 193.078292 -381.595366) (xy 193.082463 -381.6604) (xy 193.078292 -381.725434)
			(xy 193.065847 -381.789402) (xy 193.045332 -381.851256) (xy 193.017083 -381.909982) (xy 192.981563 -381.964618)
			(xy 192.939354 -382.014269) (xy 192.891148 -382.05812) (xy 192.86474 -382.077214) (xy 192.854937 -382.084711)
			(xy 192.843488 -382.106543) (xy 192.842896 -382.11887) (xy 192.842896 -382.202182) (xy 192.843663 -382.214464)
			(xy 192.855071 -382.236226) (xy 192.86474 -382.243838) (xy 192.889499 -382.261732) (xy 192.935011 -382.302479)
			(xy 192.975315 -382.348384) (xy 193.009831 -382.398787) (xy 193.03806 -382.452961) (xy 193.059597 -382.510127)
			(xy 193.074132 -382.569461) (xy 193.081455 -382.630108) (xy 193.08191 -382.660652) (xy 193.081424 -382.691172)
			(xy 193.074111 -382.751772) (xy 193.059598 -382.811061) (xy 193.038092 -382.868187) (xy 193.009904 -382.922328)
			(xy 192.975437 -382.972706) (xy 192.935189 -383.018596) (xy 192.889736 -383.059338) (xy 192.864994 -383.077212)
			(xy 192.855202 -383.084721) (xy 192.843744 -383.106544) (xy 192.84315 -383.118868) (xy 192.84315 -383.20218)
			(xy 192.843936 -383.214459) (xy 192.855332 -383.23622) (xy 192.864994 -383.243836) (xy 192.889734 -383.261716)
			(xy 192.935198 -383.30245) (xy 192.975456 -383.348335) (xy 193.009931 -383.398711) (xy 193.038126 -383.452852)
			(xy 193.059635 -383.509979) (xy 193.074148 -383.569271) (xy 193.081458 -383.629875) (xy 193.08191 -383.660396)
			(xy 193.081412 -383.693835) (xy 193.072653 -383.760137) (xy 193.055271 -383.824717) (xy 193.029568 -383.886458)
			(xy 192.995987 -383.944295) (xy 192.95511 -383.997226) (xy 192.907642 -384.044337) (xy 192.854404 -384.084814)
			(xy 192.825624 -384.101848) (xy 192.814702 -384.108198) (xy 192.801494 -384.129026) (xy 192.792096 -384.237484)
			(xy 192.801748 -384.260344) (xy 192.8114 -384.268472) (xy 192.835776 -384.28922) (xy 192.879656 -384.335827)
			(xy 192.917338 -384.387573) (xy 192.948227 -384.443641) (xy 192.971833 -384.503142) (xy 192.987783 -384.565136)
			(xy 192.995825 -384.628642) (xy 192.996312 -384.660648) (xy 192.995767 -384.693519) (xy 192.98729 -384.758713)
			(xy 192.970482 -384.822271) (xy 192.945625 -384.883133) (xy 192.913132 -384.940285) (xy 192.873546 -384.992774)
			(xy 192.827526 -385.039724) (xy 192.802002 -385.060444) (xy 192.792096 -385.068318) (xy 192.781936 -385.090924)
			(xy 192.788286 -385.199128) (xy 192.800986 -385.220464) (xy 192.811654 -385.227068) (xy 192.839111 -385.244414)
			(xy 192.889748 -385.285084) (xy 192.934792 -385.331873) (xy 192.973507 -385.38402) (xy 193.005264 -385.440674)
			(xy 193.029544 -385.500913) (xy 193.045952 -385.563753) (xy 193.05422 -385.628172) (xy 193.054732 -385.660646)
			(xy 193.054168 -385.694584) (xy 193.045161 -385.761861) (xy 193.027285 -385.827341) (xy 193.000859 -385.889862)
			(xy 192.966351 -385.948313) (xy 192.924376 -386.001655) (xy 192.87568 -386.048939) (xy 192.848738 -386.069586)
			(xy 192.838578 -386.076952) (xy 192.827656 -386.099304) (xy 192.830704 -386.207508) (xy 192.842642 -386.229098)
			(xy 192.853056 -386.235956) (xy 192.879051 -386.253623) (xy 192.926889 -386.294392) (xy 192.969336 -386.340747)
			(xy 193.005745 -386.391981) (xy 193.035561 -386.447313) (xy 193.058329 -386.505898) (xy 193.073701 -386.566842)
			(xy 193.081444 -386.629217) (xy 193.08191 -386.660644) (xy 193.081408 -386.692605) (xy 193.073397 -386.756023)
			(xy 193.057778 -386.816854) (xy 195.809616 -386.816854) (xy 195.810086 -386.786246) (xy 195.817452 -386.725474)
			(xy 195.832059 -386.666026) (xy 195.853698 -386.608761) (xy 195.882054 -386.554507) (xy 195.916717 -386.50405)
			(xy 195.957187 -386.458119) (xy 196.002878 -386.417378) (xy 196.053129 -386.382416) (xy 196.107213 -386.353739)
			(xy 196.164349 -386.331762) (xy 196.193918 -386.32384) (xy 196.202867 -386.321114) (xy 196.218115 -386.310309)
			(xy 196.223636 -386.302758) (xy 196.240654 -386.277358) (xy 196.24552 -386.269429) (xy 196.249684 -386.251312)
			(xy 196.248782 -386.242052) (xy 196.246509 -386.224552) (xy 196.244091 -386.189341) (xy 196.243956 -386.171694)
			(xy 196.244363 -386.141115) (xy 196.251721 -386.080402) (xy 196.266304 -386.021009) (xy 196.287903 -385.963793)
			(xy 196.316206 -385.909579) (xy 196.350805 -385.859149) (xy 196.391201 -385.813232) (xy 196.436811 -385.772489)
			(xy 196.461634 -385.754626) (xy 196.472048 -385.74726) (xy 196.483478 -385.72567) (xy 196.48424 -385.61772)
			(xy 196.473064 -385.59613) (xy 196.462904 -385.588764) (xy 196.438752 -385.570794) (xy 196.394403 -385.530083)
			(xy 196.355169 -385.484423) (xy 196.321599 -385.434451) (xy 196.294161 -385.380866) (xy 196.27324 -385.324418)
			(xy 196.259127 -385.265894) (xy 196.25202 -385.206114) (xy 196.251576 -385.176014) (xy 196.252078 -385.144053)
			(xy 196.260089 -385.080635) (xy 196.275986 -385.018721) (xy 196.299518 -384.959288) (xy 196.330312 -384.903273)
			(xy 196.367885 -384.851558) (xy 196.411642 -384.804961) (xy 196.460895 -384.764216) (xy 196.514866 -384.729965)
			(xy 196.572705 -384.702748) (xy 196.633498 -384.682995) (xy 196.696288 -384.671017) (xy 196.760084 -384.667004)
			(xy 196.82388 -384.671017) (xy 196.88667 -384.682995) (xy 196.947463 -384.702748) (xy 197.005302 -384.729965)
			(xy 197.059273 -384.764216) (xy 197.108526 -384.804961) (xy 197.152283 -384.851558) (xy 197.189856 -384.903273)
			(xy 197.22065 -384.959288) (xy 197.244182 -385.018721) (xy 197.260079 -385.080635) (xy 197.26809 -385.144053)
			(xy 197.268592 -385.176014) (xy 197.268094 -385.20659) (xy 197.260749 -385.267299) (xy 197.246178 -385.326689)
			(xy 197.224591 -385.383904) (xy 197.1963 -385.438118) (xy 197.161713 -385.488549) (xy 197.12133 -385.534469)
			(xy 197.075732 -385.575216) (xy 197.050914 -385.593082) (xy 197.0405 -385.600448) (xy 197.02907 -385.622038)
			(xy 197.028308 -385.729988) (xy 197.039484 -385.751578) (xy 197.049644 -385.758944) (xy 197.073811 -385.776895)
			(xy 197.118157 -385.81761) (xy 197.157389 -385.863274) (xy 197.190957 -385.913249) (xy 197.218392 -385.966836)
			(xy 197.239312 -386.023287) (xy 197.253423 -386.081812) (xy 197.260529 -386.141593) (xy 197.260972 -386.171694)
			(xy 197.26048 -386.202301) (xy 197.25311 -386.263069) (xy 197.2385 -386.322514) (xy 197.216861 -386.379776)
			(xy 197.188505 -386.434026) (xy 197.153844 -386.484482) (xy 197.113378 -386.530412) (xy 197.067692 -386.571154)
			(xy 197.017446 -386.606118) (xy 196.963367 -386.634799) (xy 196.906236 -386.656782) (xy 196.87667 -386.664708)
			(xy 196.867713 -386.667413) (xy 196.852468 -386.678232) (xy 196.846952 -386.68579) (xy 196.829934 -386.71119)
			(xy 196.825092 -386.719132) (xy 196.820914 -386.737238) (xy 196.821806 -386.746496) (xy 196.824084 -386.763996)
			(xy 196.826499 -386.799207) (xy 196.826632 -386.816854) (xy 196.82613 -386.848815) (xy 196.818119 -386.912233)
			(xy 196.802222 -386.974147) (xy 196.77869 -387.03358) (xy 196.747896 -387.089595) (xy 196.710323 -387.14131)
			(xy 196.666566 -387.187907) (xy 196.617313 -387.228652) (xy 196.563342 -387.262903) (xy 196.505503 -387.29012)
			(xy 196.44471 -387.309873) (xy 196.38192 -387.321851) (xy 196.318124 -387.325865) (xy 196.254328 -387.321851)
			(xy 196.191538 -387.309873) (xy 196.130745 -387.29012) (xy 196.072906 -387.262903) (xy 196.018935 -387.228652)
			(xy 195.969682 -387.187907) (xy 195.925925 -387.14131) (xy 195.888352 -387.089595) (xy 195.857558 -387.03358)
			(xy 195.834026 -386.974147) (xy 195.818129 -386.912233) (xy 195.810118 -386.848815) (xy 195.809616 -386.816854)
			(xy 193.057778 -386.816854) (xy 193.0575 -386.817937) (xy 193.033968 -386.87737) (xy 193.003174 -386.933385)
			(xy 192.965601 -386.9851) (xy 192.921844 -387.031697) (xy 192.872591 -387.072442) (xy 192.81862 -387.106693)
			(xy 192.760781 -387.13391) (xy 192.699988 -387.153663) (xy 192.637198 -387.165641) (xy 192.573402 -387.169655)
			(xy 192.509606 -387.165641) (xy 192.446816 -387.153663) (xy 192.386023 -387.13391) (xy 192.328184 -387.106693)
			(xy 192.274213 -387.072442) (xy 192.22496 -387.031697) (xy 192.181203 -386.9851) (xy 192.14363 -386.933385)
			(xy 192.112836 -386.87737) (xy 192.089304 -386.817937) (xy 192.073407 -386.756023) (xy 192.065396 -386.692605)
			(xy 192.064894 -386.660644) (xy 192.06548 -386.626707) (xy 192.074488 -386.559432) (xy 192.092362 -386.493954)
			(xy 192.118785 -386.431434) (xy 192.153288 -386.372983) (xy 192.195258 -386.31964) (xy 192.243949 -386.272353)
			(xy 192.270888 -386.251704) (xy 192.281048 -386.244338) (xy 192.29197 -386.221986) (xy 192.288922 -386.113782)
			(xy 192.276984 -386.092192) (xy 192.26657 -386.085334) (xy 192.240554 -386.067698) (xy 192.192719 -386.026922)
			(xy 192.150275 -385.980561) (xy 192.11387 -385.929322) (xy 192.084057 -385.873986) (xy 192.061292 -385.815398)
			(xy 192.045922 -385.754451) (xy 192.038181 -385.692074) (xy 192.037716 -385.660646) (xy 192.038246 -385.627774)
			(xy 192.046725 -385.562579) (xy 192.063534 -385.49902) (xy 192.088394 -385.438158) (xy 192.120889 -385.381006)
			(xy 192.160478 -385.328518) (xy 192.206501 -385.28157) (xy 192.232026 -385.26085) (xy 192.241932 -385.252976)
			(xy 192.252092 -385.23037) (xy 192.245742 -385.122166) (xy 192.233042 -385.10083) (xy 192.222374 -385.094226)
			(xy 192.194921 -385.076874) (xy 192.144282 -385.036206) (xy 192.099238 -384.989418) (xy 192.060521 -384.937272)
			(xy 192.028764 -384.880619) (xy 192.004483 -384.820381) (xy 191.988075 -384.75754) (xy 191.979807 -384.693122)
			(xy 191.979296 -384.660648) (xy 190.753056 -384.660648) (xy 190.756318 -384.684619) (xy 190.768977 -384.712077)
			(xy 190.789112 -384.734633) (xy 190.801752 -384.742944) (xy 190.829492 -384.760275) (xy 190.88073 -384.800933)
			(xy 190.926332 -384.847824) (xy 190.965547 -384.900175) (xy 190.997725 -384.957121) (xy 191.022338 -385.017723)
			(xy 191.038977 -385.080981) (xy 191.047369 -385.145849) (xy 191.047878 -385.178554) (xy 191.047376 -385.210515)
			(xy 191.039365 -385.273933) (xy 191.023468 -385.335847) (xy 190.999936 -385.39528) (xy 190.969142 -385.451295)
			(xy 190.931569 -385.50301) (xy 190.887812 -385.549607) (xy 190.838559 -385.590352) (xy 190.784588 -385.624603)
			(xy 190.726749 -385.65182) (xy 190.665956 -385.671573) (xy 190.603166 -385.683551) (xy 190.53937 -385.687565)
			(xy 190.475574 -385.683551) (xy 190.412784 -385.671573) (xy 190.351991 -385.65182) (xy 190.294152 -385.624603)
			(xy 190.240181 -385.590352) (xy 190.190928 -385.549607) (xy 190.147171 -385.50301) (xy 190.109598 -385.451295)
			(xy 190.078804 -385.39528) (xy 190.055272 -385.335847) (xy 190.039375 -385.273933) (xy 190.031364 -385.210515)
			(xy 190.030862 -385.178554) (xy 189.738682 -385.178554) (xy 189.738762 -385.183634) (xy 189.73826 -385.215595)
			(xy 189.730249 -385.279013) (xy 189.714352 -385.340927) (xy 189.69082 -385.40036) (xy 189.660026 -385.456375)
			(xy 189.622453 -385.50809) (xy 189.578696 -385.554687) (xy 189.529443 -385.595432) (xy 189.475472 -385.629683)
			(xy 189.417633 -385.6569) (xy 189.35684 -385.676653) (xy 189.29405 -385.688631) (xy 189.230254 -385.692645)
			(xy 189.166458 -385.688631) (xy 189.103668 -385.676653) (xy 189.042875 -385.6569) (xy 188.985036 -385.629683)
			(xy 188.931065 -385.595432) (xy 188.881812 -385.554687) (xy 188.838055 -385.50809) (xy 188.800482 -385.456375)
			(xy 188.769688 -385.40036) (xy 188.746156 -385.340927) (xy 188.730259 -385.279013) (xy 188.722248 -385.215595)
			(xy 168.950212 -385.215595) (xy 168.950696 -385.219566) (xy 168.951148 -385.250436) (xy 168.950683 -385.281133)
			(xy 168.94328 -385.342078) (xy 168.928587 -385.401687) (xy 168.906816 -385.459091) (xy 168.878287 -385.513453)
			(xy 168.861232 -385.53898) (xy 168.855726 -385.547714) (xy 168.851605 -385.56793) (xy 168.85575 -385.588141)
			(xy 168.861232 -385.596892) (xy 168.878253 -385.622439) (xy 168.906767 -385.676804) (xy 168.928533 -385.734203)
			(xy 168.943238 -385.793805) (xy 168.950665 -385.854742) (xy 168.951148 -385.885436) (xy 168.950683 -385.916133)
			(xy 168.94328 -385.977078) (xy 168.935065 -386.010404) (xy 170.98848 -386.010404) (xy 170.992551 -385.954782)
			(xy 171.004677 -385.900345) (xy 171.0246 -385.848254) (xy 171.051896 -385.799619) (xy 171.085982 -385.755476)
			(xy 171.126131 -385.716767) (xy 171.171489 -385.684316) (xy 171.221089 -385.658815) (xy 171.273873 -385.640808)
			(xy 171.328716 -385.630678) (xy 171.38445 -385.628641) (xy 171.439887 -385.634741) (xy 171.493844 -385.648847)
			(xy 171.545173 -385.670659) (xy 171.592779 -385.699713) (xy 171.635647 -385.735388) (xy 171.672864 -385.776925)
			(xy 171.703637 -385.823438) (xy 171.727309 -385.873935) (xy 171.743377 -385.927342) (xy 171.751497 -385.982518)
			(xy 171.752006 -386.010404) (xy 171.751497 -386.03829) (xy 171.743377 -386.093466) (xy 171.727309 -386.146873)
			(xy 171.724842 -386.152136) (xy 172.518322 -386.152136) (xy 172.522393 -386.096514) (xy 172.534519 -386.042077)
			(xy 172.554442 -385.989986) (xy 172.581738 -385.941351) (xy 172.615824 -385.897208) (xy 172.655973 -385.858499)
			(xy 172.701331 -385.826048) (xy 172.750931 -385.800547) (xy 172.803715 -385.78254) (xy 172.858558 -385.77241)
			(xy 172.914292 -385.770373) (xy 172.969729 -385.776473) (xy 173.023686 -385.790579) (xy 173.075015 -385.812391)
			(xy 173.122621 -385.841445) (xy 173.165489 -385.87712) (xy 173.202706 -385.918657) (xy 173.233479 -385.96517)
			(xy 173.2398 -385.978654) (xy 174.400462 -385.978654) (xy 174.404533 -385.923032) (xy 174.416659 -385.868595)
			(xy 174.436582 -385.816504) (xy 174.463878 -385.767869) (xy 174.497964 -385.723726) (xy 174.538113 -385.685017)
			(xy 174.583471 -385.652566) (xy 174.633071 -385.627065) (xy 174.685855 -385.609058) (xy 174.740698 -385.598928)
			(xy 174.796432 -385.596891) (xy 174.851869 -385.602991) (xy 174.905826 -385.617097) (xy 174.957155 -385.638909)
			(xy 175.004761 -385.667963) (xy 175.047629 -385.703638) (xy 175.084846 -385.745175) (xy 175.115619 -385.791688)
			(xy 175.139291 -385.842185) (xy 175.155359 -385.895592) (xy 175.163479 -385.950768) (xy 175.163988 -385.978654)
			(xy 175.163479 -386.00654) (xy 175.155359 -386.061716) (xy 175.139291 -386.115123) (xy 175.115619 -386.16562)
			(xy 175.084846 -386.212133) (xy 175.047629 -386.25367) (xy 175.004761 -386.289345) (xy 174.957155 -386.318399)
			(xy 174.905826 -386.340211) (xy 174.851869 -386.354317) (xy 174.796432 -386.360417) (xy 174.740698 -386.35838)
			(xy 174.685855 -386.34825) (xy 174.633071 -386.330243) (xy 174.583471 -386.304742) (xy 174.538113 -386.272291)
			(xy 174.497964 -386.233582) (xy 174.463878 -386.189439) (xy 174.436582 -386.140804) (xy 174.416659 -386.088713)
			(xy 174.404533 -386.034276) (xy 174.400462 -385.978654) (xy 173.2398 -385.978654) (xy 173.257151 -386.015667)
			(xy 173.273219 -386.069074) (xy 173.281339 -386.12425) (xy 173.281848 -386.152136) (xy 173.281339 -386.180022)
			(xy 173.273219 -386.235198) (xy 173.257151 -386.288605) (xy 173.233479 -386.339102) (xy 173.202706 -386.385615)
			(xy 173.165489 -386.427152) (xy 173.122621 -386.462827) (xy 173.075015 -386.491881) (xy 173.023686 -386.513693)
			(xy 172.969729 -386.527799) (xy 172.914292 -386.533899) (xy 172.858558 -386.531862) (xy 172.803715 -386.521732)
			(xy 172.750931 -386.503725) (xy 172.701331 -386.478224) (xy 172.655973 -386.445773) (xy 172.615824 -386.407064)
			(xy 172.581738 -386.362921) (xy 172.554442 -386.314286) (xy 172.534519 -386.262195) (xy 172.522393 -386.207758)
			(xy 172.518322 -386.152136) (xy 171.724842 -386.152136) (xy 171.703637 -386.19737) (xy 171.672864 -386.243883)
			(xy 171.635647 -386.28542) (xy 171.592779 -386.321095) (xy 171.545173 -386.350149) (xy 171.493844 -386.371961)
			(xy 171.439887 -386.386067) (xy 171.38445 -386.392167) (xy 171.328716 -386.39013) (xy 171.273873 -386.38)
			(xy 171.221089 -386.361993) (xy 171.171489 -386.336492) (xy 171.126131 -386.304041) (xy 171.085982 -386.265332)
			(xy 171.051896 -386.221189) (xy 171.0246 -386.172554) (xy 171.004677 -386.120463) (xy 170.992551 -386.066026)
			(xy 170.98848 -386.010404) (xy 168.935065 -386.010404) (xy 168.928587 -386.036687) (xy 168.906816 -386.094091)
			(xy 168.878287 -386.148453) (xy 168.861232 -386.17398) (xy 168.855726 -386.182714) (xy 168.851605 -386.20293)
			(xy 168.85575 -386.223141) (xy 168.861232 -386.231892) (xy 168.878253 -386.257439) (xy 168.906767 -386.311804)
			(xy 168.928533 -386.369203) (xy 168.943238 -386.428805) (xy 168.950665 -386.489742) (xy 168.951148 -386.520436)
			(xy 168.950683 -386.551133) (xy 168.94328 -386.612078) (xy 168.928587 -386.671687) (xy 168.906816 -386.729091)
			(xy 168.888884 -386.76326) (xy 170.479718 -386.76326) (xy 170.483789 -386.707638) (xy 170.495915 -386.653201)
			(xy 170.515838 -386.60111) (xy 170.543134 -386.552475) (xy 170.57722 -386.508332) (xy 170.617369 -386.469623)
			(xy 170.662727 -386.437172) (xy 170.712327 -386.411671) (xy 170.765111 -386.393664) (xy 170.819954 -386.383534)
			(xy 170.875688 -386.381497) (xy 170.931125 -386.387597) (xy 170.985082 -386.401703) (xy 171.036411 -386.423515)
			(xy 171.084017 -386.452569) (xy 171.126885 -386.488244) (xy 171.164102 -386.529781) (xy 171.194875 -386.576294)
			(xy 171.218547 -386.626791) (xy 171.228808 -386.660898) (xy 173.271178 -386.660898) (xy 173.275249 -386.605276)
			(xy 173.287375 -386.550839) (xy 173.307298 -386.498748) (xy 173.334594 -386.450113) (xy 173.36868 -386.40597)
			(xy 173.408829 -386.367261) (xy 173.454187 -386.33481) (xy 173.503787 -386.309309) (xy 173.556571 -386.291302)
			(xy 173.611414 -386.281172) (xy 173.667148 -386.279135) (xy 173.722585 -386.285235) (xy 173.776542 -386.299341)
			(xy 173.827871 -386.321153) (xy 173.875477 -386.350207) (xy 173.918345 -386.385882) (xy 173.955562 -386.427419)
			(xy 173.986335 -386.473932) (xy 174.010007 -386.524429) (xy 174.026075 -386.577836) (xy 174.034195 -386.633012)
			(xy 174.034704 -386.660898) (xy 174.034195 -386.688784) (xy 174.026075 -386.74396) (xy 174.010007 -386.797367)
			(xy 173.986335 -386.847864) (xy 173.955562 -386.894377) (xy 173.918345 -386.935914) (xy 173.875477 -386.971589)
			(xy 173.827871 -387.000643) (xy 173.776542 -387.022455) (xy 173.722585 -387.036561) (xy 173.667148 -387.042661)
			(xy 173.611414 -387.040624) (xy 173.556571 -387.030494) (xy 173.503787 -387.012487) (xy 173.454187 -386.986986)
			(xy 173.408829 -386.954535) (xy 173.36868 -386.915826) (xy 173.334594 -386.871683) (xy 173.307298 -386.823048)
			(xy 173.287375 -386.770957) (xy 173.275249 -386.71652) (xy 173.271178 -386.660898) (xy 171.228808 -386.660898)
			(xy 171.234615 -386.680198) (xy 171.242735 -386.735374) (xy 171.243244 -386.76326) (xy 171.242735 -386.791146)
			(xy 171.234615 -386.846322) (xy 171.218547 -386.899729) (xy 171.194875 -386.950226) (xy 171.164102 -386.996739)
			(xy 171.126885 -387.038276) (xy 171.084017 -387.073951) (xy 171.036411 -387.103005) (xy 170.985082 -387.124817)
			(xy 170.931125 -387.138923) (xy 170.875688 -387.145023) (xy 170.819954 -387.142986) (xy 170.765111 -387.132856)
			(xy 170.712327 -387.114849) (xy 170.662727 -387.089348) (xy 170.617369 -387.056897) (xy 170.57722 -387.018188)
			(xy 170.543134 -386.974045) (xy 170.515838 -386.92541) (xy 170.495915 -386.873319) (xy 170.483789 -386.818882)
			(xy 170.479718 -386.76326) (xy 168.888884 -386.76326) (xy 168.878287 -386.783453) (xy 168.861232 -386.80898)
			(xy 168.855726 -386.817714) (xy 168.851605 -386.83793) (xy 168.85575 -386.858141) (xy 168.861232 -386.866892)
			(xy 168.878253 -386.892439) (xy 168.906767 -386.946804) (xy 168.928533 -387.004203) (xy 168.943238 -387.063805)
			(xy 168.950665 -387.124742) (xy 168.951148 -387.155436) (xy 168.950729 -387.185177) (xy 168.943782 -387.244253)
			(xy 168.929989 -387.302114) (xy 168.92016 -387.330188) (xy 168.915334 -387.343142) (xy 168.92016 -387.369558)
			(xy 168.994328 -387.458458) (xy 169.019474 -387.467602) (xy 169.03319 -387.465062) (xy 169.055046 -387.461463)
			(xy 169.099179 -387.457651) (xy 169.121328 -387.457442) (xy 169.152058 -387.45793) (xy 169.213069 -387.46534)
			(xy 169.272742 -387.48005) (xy 169.330207 -387.501845) (xy 169.384626 -387.530407) (xy 169.435206 -387.56532)
			(xy 169.48121 -387.606075) (xy 169.521966 -387.652076) (xy 169.556881 -387.702655) (xy 169.585446 -387.757073)
			(xy 169.607243 -387.814537) (xy 169.621956 -387.87421) (xy 169.629369 -387.93522) (xy 169.629836 -387.96595)
			(xy 169.629276 -387.999899) (xy 169.620246 -388.067193) (xy 169.60234 -388.132687) (xy 169.575875 -388.195215)
			(xy 169.541325 -388.253665) (xy 169.499302 -388.306995) (xy 169.450555 -388.354259) (xy 169.423588 -388.37489)
			(xy 169.414952 -388.38124) (xy 169.404792 -388.39902) (xy 169.393362 -388.493762) (xy 169.399204 -388.51332)
			(xy 169.406062 -388.521702) (xy 169.4227 -388.542376) (xy 169.450724 -388.587439) (xy 169.47224 -388.635948)
			(xy 169.486836 -388.686968) (xy 169.494229 -388.739517) (xy 169.494483 -388.753604) (xy 170.361102 -388.753604)
			(xy 170.361529 -388.723494) (xy 170.368662 -388.663698) (xy 170.382805 -388.605162) (xy 170.403759 -388.548705)
			(xy 170.431233 -388.495117) (xy 170.464841 -388.445148) (xy 170.504114 -388.399496) (xy 170.548502 -388.3588)
			(xy 170.572684 -388.340854) (xy 170.582147 -388.333226) (xy 170.593151 -388.311592) (xy 170.593766 -388.299452)
			(xy 170.593766 -388.217156) (xy 170.593091 -388.205031) (xy 170.582103 -388.183417) (xy 170.572684 -388.175754)
			(xy 170.548471 -388.157848) (xy 170.504071 -388.117157) (xy 170.464791 -388.071504) (xy 170.431181 -388.02153)
			(xy 170.403713 -387.967934) (xy 170.38277 -387.911467) (xy 170.368647 -387.852921) (xy 170.361541 -387.793117)
			(xy 170.361102 -387.763004) (xy 170.361604 -387.731043) (xy 170.369615 -387.667625) (xy 170.385512 -387.605711)
			(xy 170.409044 -387.546278) (xy 170.439838 -387.490263) (xy 170.477411 -387.438548) (xy 170.521168 -387.391951)
			(xy 170.570421 -387.351206) (xy 170.624392 -387.316955) (xy 170.682231 -387.289738) (xy 170.743024 -387.269985)
			(xy 170.805814 -387.258007) (xy 170.86961 -387.253994) (xy 170.933406 -387.258007) (xy 170.996196 -387.269985)
			(xy 171.056989 -387.289738) (xy 171.114828 -387.316955) (xy 171.168799 -387.351206) (xy 171.218052 -387.391951)
			(xy 171.261809 -387.438548) (xy 171.299382 -387.490263) (xy 171.330176 -387.546278) (xy 171.353708 -387.605711)
			(xy 171.369605 -387.667625) (xy 171.377616 -387.731043) (xy 171.377719 -387.737604) (xy 173.18939 -387.737604)
			(xy 173.193461 -387.681982) (xy 173.205587 -387.627545) (xy 173.22551 -387.575454) (xy 173.252806 -387.526819)
			(xy 173.286892 -387.482676) (xy 173.327041 -387.443967) (xy 173.372399 -387.411516) (xy 173.421999 -387.386015)
			(xy 173.474783 -387.368008) (xy 173.529626 -387.357878) (xy 173.58536 -387.355841) (xy 173.640797 -387.361941)
			(xy 173.694754 -387.376047) (xy 173.746083 -387.397859) (xy 173.793689 -387.426913) (xy 173.81362 -387.4435)
			(xy 186.296061 -387.4435) (xy 186.300075 -387.379704) (xy 186.312052 -387.316913) (xy 186.331805 -387.256119)
			(xy 186.35902 -387.198279) (xy 186.39327 -387.144307) (xy 186.434014 -387.095052) (xy 186.48061 -387.051293)
			(xy 186.532323 -387.013718) (xy 186.588337 -386.98292) (xy 186.64777 -386.959385) (xy 186.709683 -386.943484)
			(xy 186.773101 -386.935468) (xy 186.805062 -386.934964) (xy 186.81954 -386.935218) (xy 186.82985 -386.935068)
			(xy 186.849024 -386.92753) (xy 186.863702 -386.913071) (xy 186.868054 -386.903722) (xy 186.881222 -386.873118)
			(xy 186.914505 -386.815399) (xy 186.95504 -386.762522) (xy 187.002135 -386.715392) (xy 187.054982 -386.674817)
			(xy 187.112676 -386.641491) (xy 187.174227 -386.615985) (xy 187.238583 -386.598738) (xy 187.30464 -386.590043)
			(xy 187.337954 -386.589524) (xy 187.370314 -386.589997) (xy 187.434517 -386.598154) (xy 187.46597 -386.60578)
			(xy 187.475996 -386.607964) (xy 187.496284 -386.605026) (xy 187.513764 -386.594315) (xy 187.520072 -386.586222)
			(xy 187.537943 -386.561743) (xy 187.578656 -386.516842) (xy 187.62442 -386.4771) (xy 187.674584 -386.443081)
			(xy 187.728438 -386.415269) (xy 187.785216 -386.394056) (xy 187.844113 -386.379745) (xy 187.904294 -386.372539)
			(xy 187.9346 -386.3721) (xy 187.966562 -386.372586) (xy 188.029981 -386.380598) (xy 188.091895 -386.396495)
			(xy 188.15133 -386.420026) (xy 188.207346 -386.450821) (xy 188.259061 -386.488395) (xy 188.305659 -386.532153)
			(xy 188.346405 -386.581406) (xy 188.380656 -386.635378) (xy 188.407873 -386.693218) (xy 188.427627 -386.754012)
			(xy 188.439605 -386.816803) (xy 188.443619 -386.8806) (xy 188.439605 -386.944397) (xy 188.427627 -387.007188)
			(xy 188.407873 -387.067982) (xy 188.380656 -387.125822) (xy 188.346405 -387.179794) (xy 188.305659 -387.229047)
			(xy 188.259061 -387.272805) (xy 188.207346 -387.310379) (xy 188.15133 -387.341174) (xy 188.091895 -387.364705)
			(xy 188.029981 -387.380602) (xy 187.966562 -387.388614) (xy 187.9346 -387.389116) (xy 187.90224 -387.388635)
			(xy 187.838037 -387.380483) (xy 187.806584 -387.37286) (xy 187.796561 -387.37066) (xy 187.776273 -387.373613)
			(xy 187.758793 -387.384326) (xy 187.752482 -387.392418) (xy 187.73456 -387.416858) (xy 187.693855 -387.461763)
			(xy 187.6481 -387.501508) (xy 187.597944 -387.535532) (xy 187.544098 -387.56335) (xy 187.487326 -387.584568)
			(xy 187.428434 -387.598885) (xy 187.368258 -387.606098) (xy 187.337954 -387.60654) (xy 187.323476 -387.606286)
			(xy 187.313167 -387.606446) (xy 187.293992 -387.613979) (xy 187.279314 -387.628434) (xy 187.274962 -387.637782)
			(xy 187.265116 -387.660642) (xy 192.191384 -387.660642) (xy 192.195455 -387.60502) (xy 192.207581 -387.550583)
			(xy 192.227504 -387.498492) (xy 192.2548 -387.449857) (xy 192.288886 -387.405714) (xy 192.329035 -387.367005)
			(xy 192.374393 -387.334554) (xy 192.423993 -387.309053) (xy 192.476777 -387.291046) (xy 192.53162 -387.280916)
			(xy 192.587354 -387.278879) (xy 192.642791 -387.284979) (xy 192.696748 -387.299085) (xy 192.748077 -387.320897)
			(xy 192.795683 -387.349951) (xy 192.838551 -387.385626) (xy 192.875768 -387.427163) (xy 192.906541 -387.473676)
			(xy 192.930213 -387.524173) (xy 192.946281 -387.57758) (xy 192.954401 -387.632756) (xy 192.95491 -387.660642)
			(xy 192.954401 -387.688528) (xy 192.946281 -387.743704) (xy 192.930213 -387.797111) (xy 192.906541 -387.847608)
			(xy 192.875768 -387.894121) (xy 192.838551 -387.935658) (xy 192.795683 -387.971333) (xy 192.748077 -388.000387)
			(xy 192.696748 -388.022199) (xy 192.642791 -388.036305) (xy 192.587354 -388.042405) (xy 192.53162 -388.040368)
			(xy 192.476777 -388.030238) (xy 192.423993 -388.012231) (xy 192.374393 -387.98673) (xy 192.329035 -387.954279)
			(xy 192.288886 -387.91557) (xy 192.2548 -387.871427) (xy 192.227504 -387.822792) (xy 192.207581 -387.770701)
			(xy 192.195455 -387.716264) (xy 192.191384 -387.660642) (xy 187.265116 -387.660642) (xy 187.261783 -387.668381)
			(xy 187.228501 -387.726099) (xy 187.187967 -387.778976) (xy 187.140873 -387.826106) (xy 187.088028 -387.866682)
			(xy 187.030336 -387.900008) (xy 186.968785 -387.925514) (xy 186.904431 -387.942764) (xy 186.838375 -387.95146)
			(xy 186.805062 -387.95198) (xy 186.773101 -387.951532) (xy 186.709683 -387.943516) (xy 186.64777 -387.927615)
			(xy 186.588337 -387.90408) (xy 186.532323 -387.873282) (xy 186.48061 -387.835707) (xy 186.434014 -387.791948)
			(xy 186.39327 -387.742693) (xy 186.35902 -387.68872) (xy 186.331805 -387.630881) (xy 186.312052 -387.570087)
			(xy 186.300075 -387.507296) (xy 186.296061 -387.4435) (xy 173.81362 -387.4435) (xy 173.836557 -387.462588)
			(xy 173.873774 -387.504125) (xy 173.904547 -387.550638) (xy 173.928219 -387.601135) (xy 173.944287 -387.654542)
			(xy 173.952407 -387.709718) (xy 173.952916 -387.737604) (xy 173.952407 -387.76549) (xy 173.944287 -387.820666)
			(xy 173.928219 -387.874073) (xy 173.904547 -387.92457) (xy 173.873774 -387.971083) (xy 173.836557 -388.01262)
			(xy 173.793689 -388.048295) (xy 173.746083 -388.077349) (xy 173.694754 -388.099161) (xy 173.640797 -388.113267)
			(xy 173.58536 -388.119367) (xy 173.529626 -388.11733) (xy 173.474783 -388.1072) (xy 173.421999 -388.089193)
			(xy 173.372399 -388.063692) (xy 173.327041 -388.031241) (xy 173.286892 -387.992532) (xy 173.252806 -387.948389)
			(xy 173.22551 -387.899754) (xy 173.205587 -387.847663) (xy 173.193461 -387.793226) (xy 173.18939 -387.737604)
			(xy 171.377719 -387.737604) (xy 171.378118 -387.763004) (xy 171.377689 -387.793114) (xy 171.370555 -387.85291)
			(xy 171.356412 -387.911445) (xy 171.335458 -387.967902) (xy 171.307984 -388.021489) (xy 171.274377 -388.071459)
			(xy 171.235105 -388.117111) (xy 171.190718 -388.157808) (xy 171.166536 -388.175754) (xy 171.157102 -388.18341)
			(xy 171.146086 -388.205023) (xy 171.145454 -388.217156) (xy 171.145454 -388.299452) (xy 171.146116 -388.311579)
			(xy 171.157113 -388.333193) (xy 171.166536 -388.340854) (xy 171.190758 -388.358749) (xy 171.235156 -388.399443)
			(xy 171.274435 -388.445097) (xy 171.308044 -388.495073) (xy 171.335511 -388.548671) (xy 171.356453 -388.605139)
			(xy 171.370575 -388.663686) (xy 171.377679 -388.723491) (xy 171.378118 -388.753604) (xy 173.18939 -388.753604)
			(xy 173.193461 -388.697982) (xy 173.205587 -388.643545) (xy 173.22551 -388.591454) (xy 173.252806 -388.542819)
			(xy 173.286892 -388.498676) (xy 173.327041 -388.459967) (xy 173.372399 -388.427516) (xy 173.421999 -388.402015)
			(xy 173.474783 -388.384008) (xy 173.529626 -388.373878) (xy 173.58536 -388.371841) (xy 173.640797 -388.377941)
			(xy 173.694754 -388.392047) (xy 173.746083 -388.413859) (xy 173.793689 -388.442913) (xy 173.836557 -388.478588)
			(xy 173.873774 -388.520125) (xy 173.904547 -388.566638) (xy 173.928219 -388.617135) (xy 173.944287 -388.670542)
			(xy 173.952407 -388.725718) (xy 173.952916 -388.753604) (xy 173.952407 -388.78149) (xy 173.944287 -388.836666)
			(xy 173.928219 -388.890073) (xy 173.904547 -388.94057) (xy 173.873774 -388.987083) (xy 173.836557 -389.02862)
			(xy 173.793689 -389.064295) (xy 173.761793 -389.083761) (xy 179.082694 -389.083761) (xy 179.082694 -389.019839)
			(xy 179.090705 -388.956421) (xy 179.106602 -388.894507) (xy 179.130134 -388.835074) (xy 179.160928 -388.779059)
			(xy 179.198501 -388.727344) (xy 179.242258 -388.680747) (xy 179.291511 -388.640002) (xy 179.345482 -388.605751)
			(xy 179.403321 -388.578534) (xy 179.464114 -388.558781) (xy 179.526904 -388.546803) (xy 179.5907 -388.54279)
			(xy 179.654496 -388.546803) (xy 179.717286 -388.558781) (xy 179.778079 -388.578534) (xy 179.835918 -388.605751)
			(xy 179.889889 -388.640002) (xy 179.939142 -388.680747) (xy 179.982899 -388.727344) (xy 180.020472 -388.779059)
			(xy 180.051266 -388.835074) (xy 180.074798 -388.894507) (xy 180.090695 -388.956421) (xy 180.098706 -389.019839)
			(xy 180.099208 -389.0518) (xy 180.098706 -389.083761) (xy 180.090695 -389.147179) (xy 180.074798 -389.209093)
			(xy 180.051266 -389.268526) (xy 180.020472 -389.324541) (xy 179.982899 -389.376256) (xy 179.939142 -389.422853)
			(xy 179.889889 -389.463598) (xy 179.835918 -389.497849) (xy 179.778079 -389.525066) (xy 179.717286 -389.544819)
			(xy 179.654496 -389.556797) (xy 179.5907 -389.560811) (xy 179.526904 -389.556797) (xy 179.464114 -389.544819)
			(xy 179.403321 -389.525066) (xy 179.345482 -389.497849) (xy 179.291511 -389.463598) (xy 179.242258 -389.422853)
			(xy 179.198501 -389.376256) (xy 179.160928 -389.324541) (xy 179.130134 -389.268526) (xy 179.106602 -389.209093)
			(xy 179.090705 -389.147179) (xy 179.082694 -389.083761) (xy 173.761793 -389.083761) (xy 173.746083 -389.093349)
			(xy 173.694754 -389.115161) (xy 173.640797 -389.129267) (xy 173.58536 -389.135367) (xy 173.529626 -389.13333)
			(xy 173.474783 -389.1232) (xy 173.421999 -389.105193) (xy 173.372399 -389.079692) (xy 173.327041 -389.047241)
			(xy 173.286892 -389.008532) (xy 173.252806 -388.964389) (xy 173.22551 -388.915754) (xy 173.205587 -388.863663)
			(xy 173.193461 -388.809226) (xy 173.18939 -388.753604) (xy 171.378118 -388.753604) (xy 171.377616 -388.785565)
			(xy 171.369605 -388.848983) (xy 171.353708 -388.910897) (xy 171.330176 -388.97033) (xy 171.299382 -389.026345)
			(xy 171.261809 -389.07806) (xy 171.218052 -389.124657) (xy 171.168799 -389.165402) (xy 171.114828 -389.199653)
			(xy 171.056989 -389.22687) (xy 170.996196 -389.246623) (xy 170.933406 -389.258601) (xy 170.86961 -389.262615)
			(xy 170.805814 -389.258601) (xy 170.743024 -389.246623) (xy 170.682231 -389.22687) (xy 170.624392 -389.199653)
			(xy 170.570421 -389.165402) (xy 170.521168 -389.124657) (xy 170.477411 -389.07806) (xy 170.439838 -389.026345)
			(xy 170.409044 -388.97033) (xy 170.385512 -388.910897) (xy 170.369615 -388.848983) (xy 170.361604 -388.785565)
			(xy 170.361102 -388.753604) (xy 169.494483 -388.753604) (xy 169.494708 -388.76605) (xy 169.494222 -388.793301)
			(xy 169.486466 -388.847249) (xy 169.471111 -388.899544) (xy 169.448469 -388.949121) (xy 169.419003 -388.994971)
			(xy 169.383312 -389.036162) (xy 169.342121 -389.071853) (xy 169.296271 -389.101319) (xy 169.246694 -389.123961)
			(xy 169.194399 -389.139316) (xy 169.140451 -389.147072) (xy 169.085949 -389.147072) (xy 169.032001 -389.139316)
			(xy 168.979706 -389.123961) (xy 168.930129 -389.101319) (xy 168.884279 -389.071853) (xy 168.843088 -389.036162)
			(xy 168.807397 -388.994971) (xy 168.777931 -388.949121) (xy 168.755289 -388.899544) (xy 168.739934 -388.847249)
			(xy 168.732178 -388.793301) (xy 168.731692 -388.76605) (xy 168.732166 -388.738716) (xy 168.739974 -388.68461)
			(xy 168.755423 -388.632171) (xy 168.778197 -388.582473) (xy 168.807829 -388.536534) (xy 168.825418 -388.515606)
			(xy 168.832276 -388.507478) (xy 168.838626 -388.48792) (xy 168.829228 -388.393178) (xy 168.819322 -388.375144)
			(xy 168.810686 -388.36854) (xy 168.784713 -388.347859) (xy 168.737875 -388.300801) (xy 168.69756 -388.248048)
			(xy 168.664454 -388.190496) (xy 168.63912 -388.129125) (xy 168.62199 -388.064978) (xy 168.613355 -387.999147)
			(xy 168.61282 -387.96595) (xy 168.613231 -387.936208) (xy 168.62018 -387.877132) (xy 168.633977 -387.819271)
			(xy 168.643808 -387.791198) (xy 168.648634 -387.778244) (xy 168.643808 -387.751828) (xy 168.56964 -387.662928)
			(xy 168.544494 -387.653784) (xy 168.530778 -387.656324) (xy 168.508921 -387.659915) (xy 168.464789 -387.663732)
			(xy 168.44264 -387.663944) (xy 168.41191 -387.663425) (xy 168.350898 -387.656021) (xy 168.291223 -387.641318)
			(xy 168.233756 -387.619528) (xy 168.179333 -387.590971) (xy 168.12875 -387.556061) (xy 168.082744 -387.51531)
			(xy 168.041985 -387.469309) (xy 168.007069 -387.418732) (xy 167.978503 -387.364314) (xy 167.956705 -387.30685)
			(xy 167.941992 -387.247177) (xy 167.93458 -387.186166) (xy 167.934132 -387.155436) (xy 167.934586 -387.124739)
			(xy 167.941992 -387.063793) (xy 167.956688 -387.004184) (xy 167.978461 -386.94678) (xy 168.006992 -386.892419)
			(xy 168.024048 -386.866892) (xy 168.029485 -386.858122) (xy 168.03362 -386.83793) (xy 168.029509 -386.817733)
			(xy 168.024048 -386.80898) (xy 168.007012 -386.783443) (xy 167.978502 -386.729075) (xy 167.956738 -386.671673)
			(xy 167.942037 -386.612069) (xy 167.934613 -386.55113) (xy 167.934132 -386.520436) (xy 167.93464 -386.499354)
			(xy 167.935148 -386.488432) (xy 167.927528 -386.468874) (xy 167.859202 -386.400548) (xy 167.839644 -386.392928)
			(xy 167.828722 -386.393436) (xy 167.80764 -386.393944) (xy 167.77691 -386.393425) (xy 167.715898 -386.386021)
			(xy 167.656223 -386.371318) (xy 167.598756 -386.349528) (xy 167.544333 -386.320971) (xy 167.49375 -386.286061)
			(xy 167.447744 -386.24531) (xy 167.406985 -386.199309) (xy 167.372069 -386.148732) (xy 167.343503 -386.094314)
			(xy 167.321705 -386.03685) (xy 167.306992 -385.977177) (xy 167.29958 -385.916166) (xy 167.299132 -385.885436)
			(xy 167.299527 -385.857224) (xy 167.305796 -385.801149) (xy 167.318219 -385.74611) (xy 167.327072 -385.71932)
			(xy 167.330374 -385.709414) (xy 167.329104 -385.68884) (xy 167.285416 -385.604766) (xy 167.269668 -385.591558)
			(xy 167.259508 -385.588764) (xy 167.23136 -385.580059) (xy 167.177391 -385.556417) (xy 167.126901 -385.526046)
			(xy 167.080724 -385.489449) (xy 167.039625 -385.44723) (xy 167.004281 -385.400088) (xy 166.975277 -385.348801)
			(xy 166.953093 -385.294216) (xy 166.938094 -385.237237) (xy 166.93053 -385.178804) (xy 166.93007 -385.149344)
			(xy 165.847191 -385.149344) (xy 165.853368 -385.164414) (xy 165.868593 -385.221808) (xy 165.876265 -385.28069)
			(xy 165.876732 -385.31038) (xy 165.876206 -385.341443) (xy 165.867793 -385.402996) (xy 165.859968 -385.433062)
			(xy 165.857174 -385.443222) (xy 165.859714 -385.463034) (xy 165.907212 -385.54533) (xy 165.923214 -385.557522)
			(xy 165.933374 -385.560062) (xy 165.962488 -385.568047) (xy 166.018454 -385.590684) (xy 166.070959 -385.620481)
			(xy 166.119092 -385.65692) (xy 166.162017 -385.699371) (xy 166.19899 -385.747095) (xy 166.22937 -385.799265)
			(xy 166.252628 -385.854975) (xy 166.268362 -385.91326) (xy 166.276299 -385.973107) (xy 166.276782 -386.003292)
			(xy 166.27668 -386.017042) (xy 166.275028 -386.044493) (xy 166.27348 -386.058156) (xy 166.272768 -386.066844)
			(xy 166.276538 -386.083852) (xy 166.280846 -386.09143) (xy 166.296848 -386.11683) (xy 166.301634 -386.123854)
			(xy 166.314865 -386.134502) (xy 166.322756 -386.137658) (xy 166.346519 -386.146611) (xy 166.39117 -386.170797)
			(xy 166.431597 -386.201526) (xy 166.466851 -386.238075) (xy 166.496101 -386.279584) (xy 166.51866 -386.325079)
			(xy 166.533998 -386.373487) (xy 166.541753 -386.423672) (xy 166.542212 -386.449062) (xy 166.54169 -386.47505)
			(xy 166.533564 -386.526387) (xy 166.517508 -386.575821) (xy 166.493915 -386.622133) (xy 166.463367 -386.664185)
			(xy 166.426617 -386.70094) (xy 166.384569 -386.731493) (xy 166.338259 -386.755092) (xy 166.288828 -386.771155)
			(xy 166.237492 -386.779287) (xy 166.211504 -386.77977) (xy 166.186595 -386.779315) (xy 166.137339 -386.771857)
			(xy 166.089759 -386.757095) (xy 166.044933 -386.735362) (xy 166.003873 -386.70715) (xy 165.967511 -386.673098)
			(xy 165.936668 -386.633977) (xy 165.912043 -386.590671) (xy 165.894193 -386.544162) (xy 165.888416 -386.519928)
			(xy 165.886265 -386.511704) (xy 165.877447 -386.497185) (xy 165.871144 -386.49148) (xy 165.847776 -386.47243)
			(xy 165.8409 -386.467206) (xy 165.824655 -386.461374) (xy 165.816026 -386.461) (xy 165.786188 -386.460342)
			(xy 165.727064 -386.452187) (xy 165.669502 -386.436417) (xy 165.614477 -386.4133) (xy 165.562924 -386.383227)
			(xy 165.515717 -386.346708) (xy 165.473657 -386.304364) (xy 165.437457 -386.256912) (xy 165.407732 -386.205157)
			(xy 165.384985 -386.149978) (xy 165.369603 -386.092311) (xy 165.361847 -386.033134) (xy 165.361366 -386.003292)
			(xy 165.361887 -385.972229) (xy 165.370303 -385.910675) (xy 165.37813 -385.88061) (xy 165.380924 -385.87045)
			(xy 165.378384 -385.850638) (xy 165.330886 -385.768342) (xy 165.314884 -385.75615) (xy 165.304724 -385.75361)
			(xy 165.275602 -385.745652) (xy 165.219635 -385.723013) (xy 165.167129 -385.693213) (xy 165.118995 -385.656771)
			(xy 165.07607 -385.614318) (xy 165.039097 -385.56659) (xy 165.008719 -385.514417) (xy 164.985462 -385.458703)
			(xy 164.969731 -385.400416) (xy 164.961797 -385.340566) (xy 164.961316 -385.31038) (xy 164.96184 -385.279492)
			(xy 164.970145 -385.218276) (xy 164.986602 -385.158732) (xy 165.010913 -385.101941) (xy 165.02634 -385.075176)
			(xy 165.032182 -385.06527) (xy 165.034468 -385.042918) (xy 165.001194 -384.947668) (xy 164.985446 -384.931666)
			(xy 164.974778 -384.927602) (xy 164.951393 -384.918428) (xy 164.907496 -384.894007) (xy 164.8678 -384.863224)
			(xy 164.83322 -384.826789) (xy 164.804551 -384.785541) (xy 164.782454 -384.74043) (xy 164.767437 -384.692494)
			(xy 164.759848 -384.642838) (xy 164.759386 -384.617722) (xy 164.220906 -384.617722) (xy 164.220373 -384.644824)
			(xy 164.211565 -384.698306) (xy 164.20338 -384.724148) (xy 164.19957 -384.73507) (xy 164.20211 -384.757422)
			(xy 164.254688 -384.843274) (xy 164.273738 -384.85572) (xy 164.284914 -384.857498) (xy 164.31423 -384.862218)
			(xy 164.3714 -384.878265) (xy 164.426014 -384.901573) (xy 164.477154 -384.93175) (xy 164.52396 -384.96829)
			(xy 164.565646 -385.010578) (xy 164.60151 -385.057903) (xy 164.630951 -385.109471) (xy 164.653473 -385.164413)
			(xy 164.668697 -385.221808) (xy 164.676369 -385.28069) (xy 164.676836 -385.31038) (xy 164.676313 -385.341506)
			(xy 164.667907 -385.403188) (xy 164.660072 -385.433316) (xy 164.657278 -385.443476) (xy 164.659818 -385.463542)
			(xy 164.707062 -385.54533) (xy 164.723064 -385.557522) (xy 164.733224 -385.560062) (xy 164.762328 -385.568081)
			(xy 164.818295 -385.590711) (xy 164.870801 -385.620503) (xy 164.918935 -385.656938) (xy 164.961862 -385.699384)
			(xy 164.998836 -385.747105) (xy 165.029217 -385.799272) (xy 165.052477 -385.85498) (xy 165.068212 -385.913263)
			(xy 165.076148 -385.973108) (xy 165.076632 -386.003292) (xy 165.076507 -386.017427) (xy 165.074725 -386.045641)
			(xy 165.073076 -386.05968) (xy 165.072312 -386.068287) (xy 165.075954 -386.085167) (xy 165.080188 -386.0927)
			(xy 165.095936 -386.1181) (xy 165.100631 -386.125171) (xy 165.113747 -386.135934) (xy 165.12159 -386.139182)
			(xy 165.144963 -386.148387) (xy 165.18886 -386.172802) (xy 165.228556 -386.20358) (xy 165.263138 -386.24001)
			(xy 165.291809 -386.281254) (xy 165.313908 -386.326361) (xy 165.328927 -386.374294) (xy 165.336519 -386.423947)
			(xy 165.336982 -386.449062) (xy 165.33656 -386.473264) (xy 165.329486 -386.521149) (xy 165.315499 -386.567489)
			(xy 165.294898 -386.611291) (xy 165.281864 -386.631688) (xy 165.277075 -386.639644) (xy 165.273042 -386.657756)
			(xy 165.27399 -386.666994) (xy 165.278308 -386.697982) (xy 165.279987 -386.707279) (xy 165.28927 -386.72372)
			(xy 165.296342 -386.729986) (xy 165.318426 -386.748673) (xy 165.358198 -386.790684) (xy 165.392361 -386.837371)
			(xy 165.42037 -386.887989) (xy 165.441777 -386.941734) (xy 165.456243 -386.997747) (xy 165.463537 -387.055136)
			(xy 165.463982 -387.084062) (xy 165.463388 -387.117383) (xy 165.453727 -387.183321) (xy 165.434602 -387.247161)
			(xy 165.421056 -387.27761) (xy 165.416782 -387.288068) (xy 165.416896 -387.310636) (xy 165.426645 -387.33099)
			(xy 165.435026 -387.33857) (xy 165.457262 -387.357256) (xy 165.497325 -387.39931) (xy 165.531745 -387.446095)
			(xy 165.559971 -387.496858) (xy 165.581549 -387.550783) (xy 165.596131 -387.607006) (xy 165.603483 -387.664621)
			(xy 165.603936 -387.693662) (xy 165.603465 -387.722667) (xy 165.596154 -387.780215) (xy 165.581631 -387.836378)
			(xy 165.56013 -387.890256) (xy 165.531995 -387.940987) (xy 165.497676 -387.987756) (xy 165.457724 -388.029816)
			(xy 165.435534 -388.0485) (xy 165.428422 -388.054088) (xy 165.419278 -388.069328) (xy 165.404038 -388.152132)
			(xy 165.406832 -388.169404) (xy 165.411404 -388.177532) (xy 165.423976 -388.20072) (xy 165.441852 -388.250341)
			(xy 165.448676 -388.289292) (xy 166.996872 -388.289292) (xy 166.997375 -388.259325) (xy 167.005198 -388.199904)
			(xy 167.020711 -388.142012) (xy 167.043647 -388.08664) (xy 167.073613 -388.034736) (xy 167.110099 -387.987187)
			(xy 167.152478 -387.944806) (xy 167.200026 -387.90832) (xy 167.25193 -387.878352) (xy 167.307301 -387.855415)
			(xy 167.365192 -387.839901) (xy 167.424613 -387.832075) (xy 167.45458 -387.831584) (xy 167.484574 -387.832121)
			(xy 167.544048 -387.839967) (xy 167.601988 -387.855515) (xy 167.6574 -387.878498) (xy 167.709335 -387.908522)
			(xy 167.756903 -387.945073) (xy 167.799289 -387.987524) (xy 167.835767 -388.035148) (xy 167.865712 -388.087129)
			(xy 167.88861 -388.142576) (xy 167.896794 -388.171436) (xy 167.899726 -388.18076) (xy 167.91142 -388.1964)
			(xy 167.928121 -388.206519) (xy 167.937688 -388.20852) (xy 167.966484 -388.21379) (xy 168.022537 -388.230673)
			(xy 168.075981 -388.254562) (xy 168.125944 -388.285069) (xy 168.171611 -388.321695) (xy 168.212237 -388.363844)
			(xy 168.24716 -388.410827) (xy 168.275809 -388.461878) (xy 168.297717 -388.516164) (xy 168.312527 -388.5728)
			(xy 168.319998 -388.630862) (xy 168.320466 -388.660132) (xy 168.319978 -388.69125) (xy 168.311566 -388.752914)
			(xy 168.294873 -388.812868) (xy 168.270209 -388.870008) (xy 168.238029 -388.923277) (xy 168.198925 -388.971693)
			(xy 168.15362 -389.014362) (xy 168.10295 -389.050497) (xy 168.04785 -389.079432) (xy 167.989337 -389.100631)
			(xy 167.959024 -389.10768) (xy 167.949908 -389.11003) (xy 167.9342 -389.120383) (xy 167.923323 -389.135732)
			(xy 167.92067 -389.144764) (xy 167.912759 -389.173638) (xy 167.890444 -389.229192) (xy 167.86108 -389.281364)
			(xy 167.825168 -389.329265) (xy 167.804592 -389.351012) (xy 167.798058 -389.358347) (xy 167.790613 -389.376507)
			(xy 167.790114 -389.386318) (xy 167.78986 -389.43915) (xy 167.791638 -389.440674) (xy 167.79931 -389.447345)
			(xy 167.818302 -389.454553) (xy 167.828468 -389.454644) (xy 167.860218 -389.45312) (xy 167.870396 -389.45229)
			(xy 167.888875 -389.44364) (xy 167.896032 -389.436356) (xy 167.917818 -389.412696) (xy 167.966909 -389.371142)
			(xy 168.021335 -389.336873) (xy 168.080024 -389.310564) (xy 168.14182 -389.292734) (xy 168.205504 -389.283735)
			(xy 168.237662 -389.283194) (xy 168.267633 -389.283657) (xy 168.327062 -389.291476) (xy 168.384962 -389.306986)
			(xy 168.440342 -389.329921) (xy 168.492255 -389.359889) (xy 168.539811 -389.396377) (xy 168.582198 -389.43876)
			(xy 168.61869 -389.486314) (xy 168.648662 -389.538224) (xy 168.671602 -389.593602) (xy 168.687116 -389.651501)
			(xy 168.694941 -389.710929) (xy 168.694941 -389.770871) (xy 168.687116 -389.830299) (xy 168.671602 -389.888198)
			(xy 168.648662 -389.943576) (xy 168.639852 -389.958834) (xy 170.971462 -389.958834) (xy 170.975533 -389.903212)
			(xy 170.987659 -389.848775) (xy 171.007582 -389.796684) (xy 171.034878 -389.748049) (xy 171.068964 -389.703906)
			(xy 171.109113 -389.665197) (xy 171.154471 -389.632746) (xy 171.204071 -389.607245) (xy 171.256855 -389.589238)
			(xy 171.311698 -389.579108) (xy 171.367432 -389.577071) (xy 171.422869 -389.583171) (xy 171.476826 -389.597277)
			(xy 171.528155 -389.619089) (xy 171.575761 -389.648143) (xy 171.618629 -389.683818) (xy 171.655846 -389.725355)
			(xy 171.686619 -389.771868) (xy 171.710291 -389.822365) (xy 171.726359 -389.875772) (xy 171.734479 -389.930948)
			(xy 171.734988 -389.958834) (xy 171.734479 -389.98672) (xy 171.726359 -390.041896) (xy 171.710291 -390.095303)
			(xy 171.686619 -390.1458) (xy 171.655846 -390.192313) (xy 171.618629 -390.23385) (xy 171.611887 -390.239461)
			(xy 179.616094 -390.239461) (xy 179.616094 -390.175539) (xy 179.624105 -390.112121) (xy 179.640002 -390.050207)
			(xy 179.663534 -389.990774) (xy 179.694328 -389.934759) (xy 179.731901 -389.883044) (xy 179.775658 -389.836447)
			(xy 179.824911 -389.795702) (xy 179.878882 -389.761451) (xy 179.936721 -389.734234) (xy 179.997514 -389.714481)
			(xy 180.060304 -389.702503) (xy 180.1241 -389.69849) (xy 180.187896 -389.702503) (xy 180.250686 -389.714481)
			(xy 180.311479 -389.734234) (xy 180.369318 -389.761451) (xy 180.423289 -389.795702) (xy 180.472542 -389.836447)
			(xy 180.516299 -389.883044) (xy 180.553872 -389.934759) (xy 180.558869 -389.943848) (xy 180.81117 -389.943848)
			(xy 180.811701 -389.915232) (xy 180.820257 -389.858644) (xy 180.83717 -389.803969) (xy 180.86206 -389.752434)
			(xy 180.894368 -389.705194) (xy 180.93337 -389.66331) (xy 180.978191 -389.627722) (xy 181.027825 -389.599228)
			(xy 181.081158 -389.578468) (xy 181.136994 -389.565906) (xy 181.1655 -389.563356) (xy 181.174898 -389.562594)
			(xy 181.191662 -389.55472) (xy 181.252114 -389.491982) (xy 181.25948 -389.474964) (xy 181.259734 -389.465312)
			(xy 181.261058 -389.438542) (xy 181.270285 -389.385743) (xy 181.286816 -389.334758) (xy 181.310325 -389.28659)
			(xy 181.340348 -389.242189) (xy 181.376293 -389.20243) (xy 181.417453 -389.168098) (xy 181.463015 -389.139869)
			(xy 181.512082 -389.118299) (xy 181.563686 -389.103814) (xy 181.590188 -389.099806) (xy 181.599332 -389.098536)
			(xy 181.615842 -389.0899) (xy 181.671976 -389.024368) (xy 181.678326 -389.006842) (xy 181.678072 -388.997444)
			(xy 181.678072 -388.990586) (xy 181.678558 -388.963335) (xy 181.686314 -388.909387) (xy 181.701669 -388.857092)
			(xy 181.724311 -388.807515) (xy 181.753777 -388.761665) (xy 181.789468 -388.720474) (xy 181.830659 -388.684783)
			(xy 181.876509 -388.655317) (xy 181.926086 -388.632675) (xy 181.978381 -388.61732) (xy 182.032329 -388.609564)
			(xy 182.086831 -388.609564) (xy 182.140779 -388.61732) (xy 182.193074 -388.632675) (xy 182.242651 -388.655317)
			(xy 182.288501 -388.684783) (xy 182.329692 -388.720474) (xy 182.365383 -388.761665) (xy 182.394849 -388.807515)
			(xy 182.417491 -388.857092) (xy 182.432846 -388.909387) (xy 182.440602 -388.963335) (xy 182.441088 -388.990586)
			(xy 182.440613 -389.018022) (xy 182.43278 -389.07233) (xy 182.417244 -389.124955) (xy 182.394328 -389.174811)
			(xy 182.364502 -389.220868) (xy 182.328384 -389.262175) (xy 182.286719 -389.29788) (xy 182.240368 -389.327244)
			(xy 182.190286 -389.349663) (xy 182.137509 -389.364674) (xy 182.11038 -389.368792) (xy 182.101236 -389.370062)
			(xy 182.084726 -389.378698) (xy 182.028592 -389.44423) (xy 182.022242 -389.461756) (xy 182.022496 -389.471154)
			(xy 182.022496 -389.478012) (xy 182.02196 -389.506626) (xy 182.013397 -389.563211) (xy 181.996479 -389.617882)
			(xy 181.971587 -389.669414) (xy 181.939279 -389.71665) (xy 181.900278 -389.758532) (xy 181.855461 -389.79412)
			(xy 181.805831 -389.822616) (xy 181.752502 -389.843381) (xy 181.696671 -389.855949) (xy 181.668166 -389.858504)
			(xy 181.658768 -389.859266) (xy 181.642004 -389.86714) (xy 181.581552 -389.929878) (xy 181.574186 -389.946896)
			(xy 181.573932 -389.956548) (xy 181.572616 -389.983193) (xy 181.563436 -390.035746) (xy 181.547022 -390.086506)
			(xy 181.523695 -390.134485) (xy 181.493912 -390.178745) (xy 181.458251 -390.218423) (xy 181.41741 -390.252746)
			(xy 181.372185 -390.281043) (xy 181.323458 -390.302763) (xy 181.272181 -390.317482) (xy 181.219352 -390.324912)
			(xy 181.192678 -390.325356) (xy 181.165428 -390.324843) (xy 181.111484 -390.317085) (xy 181.059193 -390.301729)
			(xy 181.009619 -390.279089) (xy 180.963771 -390.249625) (xy 180.922582 -390.213936) (xy 180.886891 -390.17275)
			(xy 180.857424 -390.126904) (xy 180.83478 -390.077332) (xy 180.819421 -390.025041) (xy 180.811659 -389.971098)
			(xy 180.81117 -389.943848) (xy 180.558869 -389.943848) (xy 180.584666 -389.990774) (xy 180.608198 -390.050207)
			(xy 180.624095 -390.112121) (xy 180.632106 -390.175539) (xy 180.632608 -390.2075) (xy 180.632106 -390.239461)
			(xy 180.624095 -390.302879) (xy 180.608198 -390.364793) (xy 180.584666 -390.424226) (xy 180.553872 -390.480241)
			(xy 180.516299 -390.531956) (xy 180.472542 -390.578553) (xy 180.423289 -390.619298) (xy 180.369318 -390.653549)
			(xy 180.311479 -390.680766) (xy 180.250686 -390.700519) (xy 180.187896 -390.712497) (xy 180.1241 -390.716511)
			(xy 180.060304 -390.712497) (xy 179.997514 -390.700519) (xy 179.936721 -390.680766) (xy 179.878882 -390.653549)
			(xy 179.824911 -390.619298) (xy 179.775658 -390.578553) (xy 179.731901 -390.531956) (xy 179.694328 -390.480241)
			(xy 179.663534 -390.424226) (xy 179.640002 -390.364793) (xy 179.624105 -390.302879) (xy 179.616094 -390.239461)
			(xy 171.611887 -390.239461) (xy 171.575761 -390.269525) (xy 171.528155 -390.298579) (xy 171.476826 -390.320391)
			(xy 171.422869 -390.334497) (xy 171.367432 -390.340597) (xy 171.311698 -390.33856) (xy 171.256855 -390.32843)
			(xy 171.204071 -390.310423) (xy 171.154471 -390.284922) (xy 171.109113 -390.252471) (xy 171.068964 -390.213762)
			(xy 171.034878 -390.169619) (xy 171.007582 -390.120984) (xy 170.987659 -390.068893) (xy 170.975533 -390.014456)
			(xy 170.971462 -389.958834) (xy 168.639852 -389.958834) (xy 168.61869 -389.995486) (xy 168.582198 -390.04304)
			(xy 168.539811 -390.085423) (xy 168.492255 -390.121911) (xy 168.440342 -390.151879) (xy 168.384962 -390.174814)
			(xy 168.327062 -390.190324) (xy 168.267633 -390.198143) (xy 168.237662 -390.19861) (xy 168.209276 -390.198196)
			(xy 168.152939 -390.191184) (xy 168.097898 -390.177272) (xy 168.071292 -390.167368) (xy 168.0591 -390.162542)
			(xy 168.033192 -390.166098) (xy 167.943022 -390.233154) (xy 167.9321 -390.25703) (xy 167.933116 -390.269984)
			(xy 167.93464 -390.30656) (xy 167.934107 -390.338305) (xy 167.92533 -390.401185) (xy 167.907954 -390.46225)
			(xy 167.88231 -390.52033) (xy 167.86606 -390.547606) (xy 167.861726 -390.555166) (xy 167.857993 -390.572176)
			(xy 167.86017 -390.589455) (xy 167.863774 -390.59739) (xy 167.877744 -390.624568) (xy 167.881968 -390.632234)
			(xy 167.894677 -390.644258) (xy 167.910698 -390.651287) (xy 167.9194 -390.652254) (xy 167.92575 -390.652762)
			(xy 167.936095 -390.653161) (xy 167.955734 -390.64668) (xy 167.971207 -390.632959) (xy 167.976042 -390.623806)
			(xy 167.990094 -390.595142) (xy 168.024361 -390.541279) (xy 168.065103 -390.492131) (xy 168.111678 -390.448471)
			(xy 168.163353 -390.410986) (xy 168.219316 -390.380267) (xy 168.278684 -390.356797) (xy 168.340524 -390.340946)
			(xy 168.403862 -390.332963) (xy 168.435782 -390.332468) (xy 168.466512 -390.332973) (xy 168.527523 -390.340379)
			(xy 168.587197 -390.355085) (xy 168.644664 -390.376876) (xy 168.699084 -390.405436) (xy 168.749666 -390.440347)
			(xy 168.79567 -390.4811) (xy 168.836427 -390.527101) (xy 168.871342 -390.57768) (xy 168.899906 -390.632098)
			(xy 168.921703 -390.689563) (xy 168.927158 -390.71169) (xy 170.4627 -390.71169) (xy 170.466771 -390.656068)
			(xy 170.478897 -390.601631) (xy 170.49882 -390.54954) (xy 170.526116 -390.500905) (xy 170.560202 -390.456762)
			(xy 170.600351 -390.418053) (xy 170.645709 -390.385602) (xy 170.695309 -390.360101) (xy 170.748093 -390.342094)
			(xy 170.802936 -390.331964) (xy 170.85867 -390.329927) (xy 170.914107 -390.336027) (xy 170.968064 -390.350133)
			(xy 171.019393 -390.371945) (xy 171.066999 -390.400999) (xy 171.109867 -390.436674) (xy 171.147084 -390.478211)
			(xy 171.177857 -390.524724) (xy 171.201529 -390.575221) (xy 171.217597 -390.628628) (xy 171.225717 -390.683804)
			(xy 171.226226 -390.71169) (xy 171.225717 -390.739576) (xy 171.217597 -390.794752) (xy 171.201529 -390.848159)
			(xy 171.177857 -390.898656) (xy 171.161739 -390.923018) (xy 172.850046 -390.923018) (xy 172.854117 -390.867396)
			(xy 172.866243 -390.812959) (xy 172.886166 -390.760868) (xy 172.913462 -390.712233) (xy 172.947548 -390.66809)
			(xy 172.987697 -390.629381) (xy 173.033055 -390.59693) (xy 173.082655 -390.571429) (xy 173.135439 -390.553422)
			(xy 173.190282 -390.543292) (xy 173.246016 -390.541255) (xy 173.301453 -390.547355) (xy 173.35541 -390.561461)
			(xy 173.406739 -390.583273) (xy 173.454345 -390.612327) (xy 173.497213 -390.648002) (xy 173.53443 -390.689539)
			(xy 173.565203 -390.736052) (xy 173.588875 -390.786549) (xy 173.604943 -390.839956) (xy 173.613063 -390.895132)
			(xy 173.613572 -390.923018) (xy 173.613063 -390.950904) (xy 173.604943 -391.00608) (xy 173.588875 -391.059487)
			(xy 173.565203 -391.109984) (xy 173.53443 -391.156497) (xy 173.497213 -391.198034) (xy 173.454345 -391.233709)
			(xy 173.406739 -391.262763) (xy 173.35541 -391.284575) (xy 173.301453 -391.298681) (xy 173.246016 -391.304781)
			(xy 173.190282 -391.302744) (xy 173.135439 -391.292614) (xy 173.082655 -391.274607) (xy 173.033055 -391.249106)
			(xy 172.987697 -391.216655) (xy 172.947548 -391.177946) (xy 172.913462 -391.133803) (xy 172.886166 -391.085168)
			(xy 172.866243 -391.033077) (xy 172.854117 -390.97864) (xy 172.850046 -390.923018) (xy 171.161739 -390.923018)
			(xy 171.147084 -390.945169) (xy 171.109867 -390.986706) (xy 171.066999 -391.022381) (xy 171.019393 -391.051435)
			(xy 170.968064 -391.073247) (xy 170.914107 -391.087353) (xy 170.85867 -391.093453) (xy 170.802936 -391.091416)
			(xy 170.748093 -391.081286) (xy 170.695309 -391.063279) (xy 170.645709 -391.037778) (xy 170.600351 -391.005327)
			(xy 170.560202 -390.966618) (xy 170.526116 -390.922475) (xy 170.49882 -390.87384) (xy 170.478897 -390.821749)
			(xy 170.466771 -390.767312) (xy 170.4627 -390.71169) (xy 168.927158 -390.71169) (xy 168.936414 -390.749235)
			(xy 168.943825 -390.810246) (xy 168.94429 -390.840976) (xy 168.943838 -390.871673) (xy 168.936431 -390.932619)
			(xy 168.921734 -390.992228) (xy 168.899961 -391.049631) (xy 168.87143 -391.103993) (xy 168.854374 -391.12952)
			(xy 168.848925 -391.138284) (xy 168.844791 -391.15848) (xy 168.848909 -391.17868) (xy 168.854374 -391.187432)
			(xy 168.871418 -391.212964) (xy 168.899926 -391.267334) (xy 168.921688 -391.324737) (xy 168.936387 -391.384342)
			(xy 168.94381 -391.445281) (xy 168.94429 -391.475976) (xy 168.943838 -391.506673) (xy 168.936431 -391.567619)
			(xy 168.921734 -391.627228) (xy 168.899961 -391.684631) (xy 168.892026 -391.69975) (xy 170.971462 -391.69975)
			(xy 170.975533 -391.644128) (xy 170.987659 -391.589691) (xy 171.007582 -391.5376) (xy 171.034878 -391.488965)
			(xy 171.068964 -391.444822) (xy 171.109113 -391.406113) (xy 171.154471 -391.373662) (xy 171.204071 -391.348161)
			(xy 171.256855 -391.330154) (xy 171.311698 -391.320024) (xy 171.367432 -391.317987) (xy 171.422869 -391.324087)
			(xy 171.476826 -391.338193) (xy 171.528155 -391.360005) (xy 171.575761 -391.389059) (xy 171.618629 -391.424734)
			(xy 171.655846 -391.466271) (xy 171.686619 -391.512784) (xy 171.710291 -391.563281) (xy 171.726359 -391.616688)
			(xy 171.731138 -391.649161) (xy 179.082694 -391.649161) (xy 179.082694 -391.585239) (xy 179.090705 -391.521821)
			(xy 179.106602 -391.459907) (xy 179.130134 -391.400474) (xy 179.160928 -391.344459) (xy 179.198501 -391.292744)
			(xy 179.242258 -391.246147) (xy 179.291511 -391.205402) (xy 179.345482 -391.171151) (xy 179.403321 -391.143934)
			(xy 179.464114 -391.124181) (xy 179.526904 -391.112203) (xy 179.5907 -391.10819) (xy 179.654496 -391.112203)
			(xy 179.717286 -391.124181) (xy 179.778079 -391.143934) (xy 179.835918 -391.171151) (xy 179.889889 -391.205402)
			(xy 179.939142 -391.246147) (xy 179.982899 -391.292744) (xy 180.020472 -391.344459) (xy 180.047112 -391.392918)
			(xy 180.837078 -391.392918) (xy 180.837574 -391.364301) (xy 180.846134 -391.307711) (xy 180.863052 -391.253035)
			(xy 180.887946 -391.201499) (xy 180.920258 -391.154259) (xy 180.959264 -391.112376) (xy 181.004089 -391.076788)
			(xy 181.053726 -391.048295) (xy 181.107062 -391.027536) (xy 181.1629 -391.014976) (xy 181.191408 -391.012426)
			(xy 181.200806 -391.011664) (xy 181.21757 -391.00379) (xy 181.278022 -390.941052) (xy 181.285388 -390.924034)
			(xy 181.285642 -390.914382) (xy 181.287056 -390.886434) (xy 181.297072 -390.83138) (xy 181.315023 -390.778379)
			(xy 181.340525 -390.728569) (xy 181.37303 -390.683019) (xy 181.41184 -390.642707) (xy 181.456123 -390.608496)
			(xy 181.504929 -390.581122) (xy 181.55721 -390.561172) (xy 181.611845 -390.549073) (xy 181.639718 -390.54659)
			(xy 181.649116 -390.545828) (xy 181.66588 -390.537954) (xy 181.726332 -390.475216) (xy 181.733698 -390.458198)
			(xy 181.733952 -390.448546) (xy 181.735278 -390.421902) (xy 181.744459 -390.36935) (xy 181.760873 -390.318591)
			(xy 181.784199 -390.270614) (xy 181.813982 -390.226354) (xy 181.849641 -390.186676) (xy 181.890481 -390.152353)
			(xy 181.935704 -390.124056) (xy 181.984429 -390.102335) (xy 182.035705 -390.087615) (xy 182.088532 -390.080183)
			(xy 182.115206 -390.079738) (xy 182.142461 -390.08015) (xy 182.196416 -390.087909) (xy 182.248718 -390.103268)
			(xy 182.298301 -390.125915) (xy 182.344156 -390.155387) (xy 182.38535 -390.191087) (xy 182.421044 -390.232285)
			(xy 182.45051 -390.278145) (xy 182.47315 -390.327731) (xy 182.488502 -390.380035) (xy 182.496254 -390.433991)
			(xy 182.496714 -390.461246) (xy 182.496193 -390.489862) (xy 182.487637 -390.546451) (xy 182.470724 -390.601128)
			(xy 182.445833 -390.652664) (xy 182.413524 -390.699904) (xy 182.37452 -390.741788) (xy 182.329698 -390.777376)
			(xy 182.280063 -390.80587) (xy 182.226728 -390.826629) (xy 182.170891 -390.839189) (xy 182.142384 -390.841738)
			(xy 182.132986 -390.8425) (xy 182.116222 -390.850374) (xy 182.05577 -390.913112) (xy 182.048404 -390.93013)
			(xy 182.04815 -390.939782) (xy 182.046711 -390.967728) (xy 182.0367 -391.022783) (xy 182.018753 -391.075784)
			(xy 181.993255 -391.125594) (xy 181.960753 -391.171144) (xy 181.921945 -391.211457) (xy 181.877664 -391.245668)
			(xy 181.82886 -391.273043) (xy 181.77658 -391.292993) (xy 181.721947 -391.305091) (xy 181.694074 -391.307574)
			(xy 181.684676 -391.308336) (xy 181.667912 -391.31621) (xy 181.60746 -391.378948) (xy 181.600094 -391.395966)
			(xy 181.59984 -391.405618) (xy 181.59849 -391.432261) (xy 181.589313 -391.484812) (xy 181.572903 -391.535572)
			(xy 181.549581 -391.583549) (xy 181.519801 -391.62781) (xy 181.484144 -391.667488) (xy 181.443306 -391.701812)
			(xy 181.398084 -391.73011) (xy 181.34936 -391.75183) (xy 181.298085 -391.76655) (xy 181.245259 -391.773981)
			(xy 181.218586 -391.774426) (xy 181.191335 -391.773935) (xy 181.137389 -391.766177) (xy 181.085095 -391.750821)
			(xy 181.035519 -391.72818) (xy 180.98967 -391.698714) (xy 180.94848 -391.663023) (xy 180.912789 -391.621834)
			(xy 180.883322 -391.575985) (xy 180.86068 -391.526409) (xy 180.845324 -391.474115) (xy 180.837565 -391.420169)
			(xy 180.837078 -391.392918) (xy 180.047112 -391.392918) (xy 180.051266 -391.400474) (xy 180.074798 -391.459907)
			(xy 180.090695 -391.521821) (xy 180.098706 -391.585239) (xy 180.099208 -391.6172) (xy 180.098706 -391.649161)
			(xy 180.090695 -391.712579) (xy 180.074798 -391.774493) (xy 180.051266 -391.833926) (xy 180.020472 -391.889941)
			(xy 179.982899 -391.941656) (xy 179.939142 -391.988253) (xy 179.889889 -392.028998) (xy 179.835918 -392.063249)
			(xy 179.778079 -392.090466) (xy 179.717286 -392.110219) (xy 179.654496 -392.122197) (xy 179.5907 -392.126211)
			(xy 179.526904 -392.122197) (xy 179.464114 -392.110219) (xy 179.403321 -392.090466) (xy 179.345482 -392.063249)
			(xy 179.291511 -392.028998) (xy 179.242258 -391.988253) (xy 179.198501 -391.941656) (xy 179.160928 -391.889941)
			(xy 179.130134 -391.833926) (xy 179.106602 -391.774493) (xy 179.090705 -391.712579) (xy 179.082694 -391.649161)
			(xy 171.731138 -391.649161) (xy 171.734479 -391.671864) (xy 171.734988 -391.69975) (xy 171.734479 -391.727636)
			(xy 171.726359 -391.782812) (xy 171.710291 -391.836219) (xy 171.686619 -391.886716) (xy 171.655846 -391.933229)
			(xy 171.618629 -391.974766) (xy 171.575761 -392.010441) (xy 171.528155 -392.039495) (xy 171.476826 -392.061307)
			(xy 171.422869 -392.075413) (xy 171.367432 -392.081513) (xy 171.311698 -392.079476) (xy 171.256855 -392.069346)
			(xy 171.204071 -392.051339) (xy 171.154471 -392.025838) (xy 171.109113 -391.993387) (xy 171.068964 -391.954678)
			(xy 171.034878 -391.910535) (xy 171.007582 -391.8619) (xy 170.987659 -391.809809) (xy 170.975533 -391.755372)
			(xy 170.971462 -391.69975) (xy 168.892026 -391.69975) (xy 168.87143 -391.738993) (xy 168.854374 -391.76452)
			(xy 168.848925 -391.773284) (xy 168.844791 -391.79348) (xy 168.848909 -391.81368) (xy 168.854374 -391.822432)
			(xy 168.871418 -391.847964) (xy 168.899926 -391.902334) (xy 168.921688 -391.959737) (xy 168.936387 -392.019342)
			(xy 168.94381 -392.080281) (xy 168.94429 -392.110976) (xy 168.94384 -392.141708) (xy 168.936434 -392.202725)
			(xy 168.921726 -392.262404) (xy 168.899932 -392.319875) (xy 168.871369 -392.3743) (xy 168.836454 -392.424885)
			(xy 168.811896 -392.452606) (xy 170.4627 -392.452606) (xy 170.466771 -392.396984) (xy 170.478897 -392.342547)
			(xy 170.49882 -392.290456) (xy 170.526116 -392.241821) (xy 170.560202 -392.197678) (xy 170.600351 -392.158969)
			(xy 170.645709 -392.126518) (xy 170.695309 -392.101017) (xy 170.748093 -392.08301) (xy 170.802936 -392.07288)
			(xy 170.85867 -392.070843) (xy 170.914107 -392.076943) (xy 170.968064 -392.091049) (xy 171.019393 -392.112861)
			(xy 171.066999 -392.141915) (xy 171.109867 -392.17759) (xy 171.147084 -392.219127) (xy 171.177857 -392.26564)
			(xy 171.201529 -392.316137) (xy 171.217597 -392.369544) (xy 171.225717 -392.42472) (xy 171.226226 -392.452606)
			(xy 171.225717 -392.480492) (xy 171.224706 -392.487361) (xy 178.127654 -392.487361) (xy 178.127654 -392.423439)
			(xy 178.135665 -392.360021) (xy 178.151562 -392.298107) (xy 178.175094 -392.238674) (xy 178.205888 -392.182659)
			(xy 178.243461 -392.130944) (xy 178.287218 -392.084347) (xy 178.336471 -392.043602) (xy 178.390442 -392.009351)
			(xy 178.448281 -391.982134) (xy 178.509074 -391.962381) (xy 178.571864 -391.950403) (xy 178.63566 -391.94639)
			(xy 178.699456 -391.950403) (xy 178.762246 -391.962381) (xy 178.823039 -391.982134) (xy 178.880878 -392.009351)
			(xy 178.934849 -392.043602) (xy 178.984102 -392.084347) (xy 179.027859 -392.130944) (xy 179.065432 -392.182659)
			(xy 179.096226 -392.238674) (xy 179.119758 -392.298107) (xy 179.135655 -392.360021) (xy 179.143666 -392.423439)
			(xy 179.144168 -392.4554) (xy 179.143666 -392.487361) (xy 179.135655 -392.550779) (xy 179.119758 -392.612693)
			(xy 179.096226 -392.672126) (xy 179.065432 -392.728141) (xy 179.027859 -392.779856) (xy 178.984102 -392.826453)
			(xy 178.934849 -392.867198) (xy 178.880878 -392.901449) (xy 178.823039 -392.928666) (xy 178.762246 -392.948419)
			(xy 178.699456 -392.960397) (xy 178.63566 -392.964411) (xy 178.571864 -392.960397) (xy 178.509074 -392.948419)
			(xy 178.448281 -392.928666) (xy 178.390442 -392.901449) (xy 178.336471 -392.867198) (xy 178.287218 -392.826453)
			(xy 178.243461 -392.779856) (xy 178.205888 -392.728141) (xy 178.175094 -392.672126) (xy 178.151562 -392.612693)
			(xy 178.135665 -392.550779) (xy 178.127654 -392.487361) (xy 171.224706 -392.487361) (xy 171.217597 -392.535668)
			(xy 171.201529 -392.589075) (xy 171.177857 -392.639572) (xy 171.147084 -392.686085) (xy 171.109867 -392.727622)
			(xy 171.066999 -392.763297) (xy 171.019393 -392.792351) (xy 170.968064 -392.814163) (xy 170.914107 -392.828269)
			(xy 170.85867 -392.834369) (xy 170.802936 -392.832332) (xy 170.748093 -392.822202) (xy 170.695309 -392.804195)
			(xy 170.645709 -392.778694) (xy 170.600351 -392.746243) (xy 170.560202 -392.707534) (xy 170.526116 -392.663391)
			(xy 170.49882 -392.614756) (xy 170.478897 -392.562665) (xy 170.466771 -392.508228) (xy 170.4627 -392.452606)
			(xy 168.811896 -392.452606) (xy 168.795696 -392.470892) (xy 168.749689 -392.511651) (xy 168.699105 -392.546566)
			(xy 168.64468 -392.57513) (xy 168.58721 -392.596924) (xy 168.527531 -392.611632) (xy 168.466514 -392.619039)
			(xy 168.435782 -392.619484) (xy 168.40397 -392.618954) (xy 168.340843 -392.611027) (xy 168.279198 -392.595285)
			(xy 168.219999 -392.571975) (xy 168.164171 -392.54146) (xy 168.112586 -392.504219) (xy 168.06605 -392.460833)
			(xy 168.025291 -392.41198) (xy 167.990946 -392.358424) (xy 167.976804 -392.329924) (xy 167.971961 -392.320779)
			(xy 167.956478 -392.307079) (xy 167.936853 -392.300576) (xy 167.926512 -392.300968) (xy 167.882062 -392.303)
			(xy 167.837612 -392.300968) (xy 167.827963 -392.300557) (xy 167.809453 -392.305993) (xy 167.794261 -392.317883)
			(xy 167.784537 -392.334545) (xy 167.781658 -392.353621) (xy 167.786031 -392.372411) (xy 167.797036 -392.388255)
			(xy 167.804846 -392.393932) (xy 167.830382 -392.411715) (xy 167.877409 -392.452467) (xy 167.919109 -392.498655)
			(xy 167.95486 -392.549588) (xy 167.984126 -392.604503) (xy 168.00647 -392.662581) (xy 168.021557 -392.722951)
			(xy 168.029162 -392.784712) (xy 168.029636 -392.815826) (xy 168.027858 -392.857228) (xy 168.026842 -392.86942)
			(xy 168.03624 -392.892026) (xy 168.11752 -392.961368) (xy 168.141142 -392.96721) (xy 168.15308 -392.964162)
			(xy 168.175222 -392.959164) (xy 168.220299 -392.953819) (xy 168.242996 -392.953494) (xy 168.270249 -392.953953)
			(xy 168.324201 -392.96171) (xy 168.376499 -392.977065) (xy 168.42608 -392.999708) (xy 168.471934 -393.029176)
			(xy 168.513128 -393.06487) (xy 168.548822 -393.106063) (xy 168.57829 -393.151916) (xy 168.600933 -393.201497)
			(xy 168.61629 -393.253795) (xy 168.624047 -393.307747) (xy 168.624047 -393.362253) (xy 168.61629 -393.416205)
			(xy 168.600933 -393.468503) (xy 168.57829 -393.518084) (xy 168.548822 -393.563937) (xy 168.513128 -393.60513)
			(xy 168.471934 -393.640824) (xy 168.42608 -393.670292) (xy 168.376499 -393.692935) (xy 168.324201 -393.70829)
			(xy 168.270249 -393.716047) (xy 168.242996 -393.71651) (xy 168.214667 -393.715974) (xy 168.158636 -393.707567)
			(xy 168.104463 -393.690967) (xy 168.053341 -393.66654) (xy 168.006392 -393.634823) (xy 167.964648 -393.596512)
			(xy 167.929029 -393.55245) (xy 167.900315 -393.503606) (xy 167.879139 -393.451054) (xy 167.865967 -393.395948)
			(xy 167.863012 -393.367768) (xy 167.861742 -393.355576) (xy 167.848788 -393.334748) (xy 167.757348 -393.279884)
			(xy 167.732964 -393.27836) (xy 167.721534 -393.283186) (xy 167.689744 -393.296198) (xy 167.62354 -393.31452)
			(xy 167.555474 -393.323767) (xy 167.521128 -393.324334) (xy 167.490397 -393.323836) (xy 167.429384 -393.316431)
			(xy 167.369708 -393.301726) (xy 167.31224 -393.279935) (xy 167.257818 -393.251375) (xy 167.207234 -393.216464)
			(xy 167.161228 -393.17571) (xy 167.120469 -393.129708) (xy 167.085553 -393.079129) (xy 167.056988 -393.024709)
			(xy 167.03519 -392.967243) (xy 167.020479 -392.907569) (xy 167.013067 -392.846556) (xy 167.01262 -392.815826)
			(xy 167.013181 -392.782712) (xy 167.021764 -392.717044) (xy 167.0388 -392.653045) (xy 167.064001 -392.591801)
			(xy 167.096942 -392.534347) (xy 167.137063 -392.481656) (xy 167.183686 -392.434621) (xy 167.236021 -392.394037)
			(xy 167.293183 -392.360592) (xy 167.354203 -392.334852) (xy 167.418048 -392.317252) (xy 167.45077 -392.312144)
			(xy 167.464994 -392.310112) (xy 167.486838 -392.292332) (xy 167.526462 -392.180318) (xy 167.520874 -392.152632)
			(xy 167.510968 -392.142218) (xy 167.489531 -392.118568) (xy 167.452061 -392.066891) (xy 167.421353 -392.010932)
			(xy 167.39789 -391.951569) (xy 167.38204 -391.889737) (xy 167.374052 -391.826408) (xy 167.373554 -391.794492)
			(xy 167.374033 -391.763796) (xy 167.381432 -391.702851) (xy 167.396123 -391.643242) (xy 167.41789 -391.585838)
			(xy 167.446416 -391.531475) (xy 167.46347 -391.505948) (xy 167.468951 -391.497201) (xy 167.47308 -391.476993)
			(xy 167.468946 -391.456787) (xy 167.46347 -391.448036) (xy 167.446027 -391.421919) (xy 167.417002 -391.366224)
			(xy 167.395054 -391.307378) (xy 167.380517 -391.246279) (xy 167.376602 -391.215118) (xy 167.375263 -391.20619)
			(xy 167.36719 -391.190054) (xy 167.360854 -391.183622) (xy 167.338756 -391.162794) (xy 167.332124 -391.157017)
			(xy 167.316007 -391.150005) (xy 167.30726 -391.149078) (xy 167.282406 -391.14707) (xy 167.233683 -391.136473)
			(xy 167.187103 -391.118679) (xy 167.143725 -391.09409) (xy 167.104531 -391.063266) (xy 167.070412 -391.026905)
			(xy 167.042141 -390.985831) (xy 167.020359 -390.940978) (xy 167.005561 -390.893362) (xy 166.998082 -390.844063)
			(xy 166.997634 -390.819132) (xy 166.998028 -390.795394) (xy 167.004825 -390.748406) (xy 167.01827 -390.702873)
			(xy 167.038087 -390.65973) (xy 167.063868 -390.619863) (xy 167.079168 -390.601708) (xy 167.085878 -390.593311)
			(xy 167.092208 -390.572789) (xy 167.08962 -390.55147) (xy 167.084502 -390.542018) (xy 167.068998 -390.515248)
			(xy 167.044581 -390.458407) (xy 167.028056 -390.398792) (xy 167.019728 -390.337492) (xy 167.019224 -390.30656)
			(xy 167.019749 -390.274958) (xy 167.028451 -390.212357) (xy 167.045696 -390.151553) (xy 167.071156 -390.093705)
			(xy 167.087296 -390.06653) (xy 167.091881 -390.058329) (xy 167.095299 -390.039866) (xy 167.091857 -390.021407)
			(xy 167.087296 -390.01319) (xy 167.071181 -389.986004) (xy 167.04575 -389.928149) (xy 167.028507 -389.86735)
			(xy 167.019778 -389.804758) (xy 167.019224 -389.77316) (xy 167.019799 -389.739926) (xy 167.029407 -389.674156)
			(xy 167.048429 -389.610469) (xy 167.076465 -389.550203) (xy 167.112926 -389.494628) (xy 167.13454 -389.469376)
			(xy 167.14089 -389.462264) (xy 167.147494 -389.444992) (xy 167.147494 -389.358886) (xy 167.14089 -389.341614)
			(xy 167.13454 -389.334502) (xy 167.112972 -389.309258) (xy 167.076599 -389.253712) (xy 167.04863 -389.193495)
			(xy 167.029654 -389.129869) (xy 167.020067 -389.06417) (xy 167.019478 -389.030972) (xy 167.020015 -388.999147)
			(xy 167.028838 -388.936111) (xy 167.046309 -388.874905) (xy 167.072092 -388.81671) (xy 167.105689 -388.762649)
			(xy 167.12565 -388.737856) (xy 167.131492 -388.730744) (xy 167.137588 -388.713218) (xy 167.135048 -388.627112)
			(xy 167.127936 -388.610094) (xy 167.121586 -388.603236) (xy 167.102104 -388.581961) (xy 167.06811 -388.535354)
			(xy 167.040243 -388.484844) (xy 167.018948 -388.431231) (xy 167.00456 -388.375366) (xy 166.99731 -388.318136)
			(xy 166.996872 -388.289292) (xy 165.448676 -388.289292) (xy 165.450954 -388.302292) (xy 165.451536 -388.328662)
			(xy 165.451467 -388.338021) (xy 165.450324 -388.356703) (xy 165.44925 -388.366) (xy 165.448234 -388.37489)
			(xy 165.452044 -388.391654) (xy 165.495986 -388.461504) (xy 165.509702 -388.471918) (xy 165.518084 -388.474712)
			(xy 165.542101 -388.48321) (xy 165.587275 -388.506755) (xy 165.628082 -388.537248) (xy 165.663463 -388.573897)
			(xy 165.692501 -388.615752) (xy 165.714442 -388.661726) (xy 165.722046 -388.68604) (xy 165.72357 -388.691882)
			(xy 166.043864 -389.245602) (xy 166.047928 -389.24992) (xy 166.064124 -389.267634) (xy 166.091549 -389.307024)
			(xy 166.112692 -389.350112) (xy 166.127068 -389.395905) (xy 166.134344 -389.443346) (xy 166.134796 -389.467344)
			(xy 166.134347 -389.492148) (xy 166.126577 -389.541144) (xy 166.111235 -389.58832) (xy 166.088699 -389.632515)
			(xy 166.059525 -389.672638) (xy 166.024432 -389.707701) (xy 165.984284 -389.736841) (xy 165.940071 -389.759338)
			(xy 165.892881 -389.77464) (xy 165.843878 -389.782368) (xy 165.819074 -389.782812) (xy 165.793679 -389.782334)
			(xy 165.743544 -389.7742) (xy 165.695358 -389.758145) (xy 165.650364 -389.734583) (xy 165.609721 -389.704122)
			(xy 165.574479 -389.667548) (xy 165.545546 -389.625805) (xy 165.523668 -389.579967) (xy 165.516052 -389.555736)
			(xy 165.514528 -389.549894) (xy 165.194234 -388.996174) (xy 165.19017 -388.991856) (xy 165.174013 -388.97412)
			(xy 165.146644 -388.934719) (xy 165.125553 -388.891629) (xy 165.111225 -388.845845) (xy 165.10399 -388.798419)
			(xy 165.103556 -388.774432) (xy 165.103637 -388.762384) (xy 165.105419 -388.738355) (xy 165.107112 -388.726426)
			(xy 165.108382 -388.717536) (xy 165.105334 -388.700518) (xy 165.06317 -388.629652) (xy 165.049962 -388.618476)
			(xy 165.04158 -388.615428) (xy 165.019834 -388.607027) (xy 164.978976 -388.584588) (xy 164.942005 -388.556195)
			(xy 164.909781 -388.522511) (xy 164.883056 -388.484318) (xy 164.862449 -388.442504) (xy 164.848442 -388.398044)
			(xy 164.841358 -388.35197) (xy 164.84092 -388.328662) (xy 164.841483 -388.302289) (xy 164.850567 -388.25033)
			(xy 164.868456 -388.20071) (xy 164.881052 -388.177532) (xy 164.885624 -388.169404) (xy 164.888418 -388.152132)
			(xy 164.873178 -388.069328) (xy 164.864034 -388.054088) (xy 164.856922 -388.0485) (xy 164.834756 -388.029789)
			(xy 164.794808 -387.987729) (xy 164.760489 -387.940962) (xy 164.73235 -387.890237) (xy 164.710839 -387.836365)
			(xy 164.696302 -387.780208) (xy 164.688971 -387.722666) (xy 164.68852 -387.693662) (xy 164.689122 -387.660341)
			(xy 164.69878 -387.594403) (xy 164.717901 -387.530564) (xy 164.731446 -387.500114) (xy 164.735696 -387.489648)
			(xy 164.735591 -387.467086) (xy 164.725852 -387.446735) (xy 164.717476 -387.439154) (xy 164.695204 -387.420509)
			(xy 164.655143 -387.378448) (xy 164.620725 -387.331656) (xy 164.592504 -387.280886) (xy 164.570933 -387.226954)
			(xy 164.556358 -387.170726) (xy 164.549014 -387.113105) (xy 164.548566 -387.084062) (xy 164.549012 -387.055135)
			(xy 164.556296 -386.997743) (xy 164.570756 -386.941726) (xy 164.59216 -386.887978) (xy 164.620168 -386.837356)
			(xy 164.654333 -386.790669) (xy 164.69411 -386.748659) (xy 164.716206 -386.729986) (xy 164.723185 -386.723646)
			(xy 164.732437 -386.707236) (xy 164.73424 -386.697982) (xy 164.738558 -386.666994) (xy 164.73946 -386.657757)
			(xy 164.735437 -386.639658) (xy 164.730684 -386.631688) (xy 164.714374 -386.605843) (xy 164.690472 -386.549607)
			(xy 164.683186 -386.519928) (xy 164.681131 -386.511765) (xy 164.672427 -386.497364) (xy 164.666168 -386.491734)
			(xy 164.643054 -386.472684) (xy 164.636154 -386.467467) (xy 164.619939 -386.461484) (xy 164.611304 -386.461)
			(xy 164.581669 -386.459952) (xy 164.523005 -386.451308) (xy 164.465949 -386.435162) (xy 164.411455 -386.411784)
			(xy 164.360436 -386.381565) (xy 164.313745 -386.345012) (xy 164.272166 -386.302736) (xy 164.236393 -386.255445)
			(xy 164.207025 -386.203931) (xy 164.184556 -386.149056) (xy 164.169359 -386.091739) (xy 164.161691 -386.03294)
			(xy 164.161216 -386.003292) (xy 164.161738 -385.972229) (xy 164.170153 -385.910675) (xy 164.17798 -385.88061)
			(xy 164.180774 -385.87045) (xy 164.178234 -385.850638) (xy 164.130736 -385.768342) (xy 164.114734 -385.75615)
			(xy 164.104574 -385.75361) (xy 164.075494 -385.745551) (xy 164.019566 -385.722889) (xy 163.9671 -385.693078)
			(xy 163.919005 -385.656633) (xy 163.876113 -385.614186) (xy 163.839169 -385.566472) (xy 163.808813 -385.514319)
			(xy 163.78557 -385.458631) (xy 163.769844 -385.400372) (xy 163.761907 -385.340552) (xy 163.76142 -385.31038)
			(xy 163.761943 -385.279492) (xy 163.770248 -385.218276) (xy 163.786706 -385.158732) (xy 163.811017 -385.101941)
			(xy 163.826444 -385.075176) (xy 163.832286 -385.06527) (xy 163.834572 -385.042918) (xy 163.801298 -384.947668)
			(xy 163.78555 -384.931666) (xy 163.774882 -384.927602) (xy 163.751498 -384.918426) (xy 163.707601 -384.894005)
			(xy 163.667905 -384.863223) (xy 163.633324 -384.826789) (xy 163.604655 -384.785541) (xy 163.582558 -384.74043)
			(xy 163.567542 -384.692494) (xy 163.559952 -384.642838) (xy 163.55949 -384.617722) (xy 163.020756 -384.617722)
			(xy 163.020226 -384.644824) (xy 163.011416 -384.698307) (xy 163.00323 -384.724148) (xy 162.99942 -384.73507)
			(xy 163.00196 -384.757422) (xy 163.054538 -384.843274) (xy 163.073588 -384.85572) (xy 163.084764 -384.857498)
			(xy 163.114087 -384.862179) (xy 163.171257 -384.878232) (xy 163.225871 -384.901545) (xy 163.27701 -384.931728)
			(xy 163.323815 -384.968272) (xy 163.3655 -385.010564) (xy 163.401363 -385.057892) (xy 163.430802 -385.109463)
			(xy 163.453324 -385.164408) (xy 163.468548 -385.221805) (xy 163.476219 -385.280689) (xy 163.476686 -385.31038)
			(xy 163.476158 -385.341443) (xy 163.467747 -385.402996) (xy 163.459922 -385.433062) (xy 163.457128 -385.443222)
			(xy 163.459668 -385.463034) (xy 163.507166 -385.54533) (xy 163.523168 -385.557522) (xy 163.533328 -385.560062)
			(xy 163.562433 -385.568078) (xy 163.618399 -385.590709) (xy 163.670905 -385.620501) (xy 163.719039 -385.656937)
			(xy 163.761966 -385.699383) (xy 163.798941 -385.747104) (xy 163.829321 -385.799272) (xy 163.852581 -385.85498)
			(xy 163.868316 -385.913262) (xy 163.876252 -385.973107) (xy 163.876736 -386.003292) (xy 163.876611 -386.017427)
			(xy 163.874829 -386.045641) (xy 163.87318 -386.05968) (xy 163.872416 -386.068287) (xy 163.876057 -386.085167)
			(xy 163.880292 -386.0927) (xy 163.89604 -386.1181) (xy 163.900734 -386.125172) (xy 163.913851 -386.135935)
			(xy 163.921694 -386.139182) (xy 163.945067 -386.148385) (xy 163.988964 -386.172801) (xy 164.028661 -386.203578)
			(xy 164.063243 -386.240009) (xy 164.091913 -386.281253) (xy 164.114013 -386.326361) (xy 164.129031 -386.374293)
			(xy 164.136623 -386.423947) (xy 164.137086 -386.449062) (xy 164.136663 -386.473264) (xy 164.129589 -386.521149)
			(xy 164.115602 -386.567489) (xy 164.095002 -386.611291) (xy 164.081968 -386.631688) (xy 164.07718 -386.639645)
			(xy 164.073146 -386.657756) (xy 164.074094 -386.666994) (xy 164.078412 -386.697982) (xy 164.08009 -386.707279)
			(xy 164.089374 -386.72372) (xy 164.096446 -386.729986) (xy 164.118531 -386.748672) (xy 164.158303 -386.790683)
			(xy 164.192466 -386.83737) (xy 164.220474 -386.887989) (xy 164.241882 -386.941733) (xy 164.256348 -386.997747)
			(xy 164.263641 -387.055136) (xy 164.264086 -387.084062) (xy 164.263492 -387.117383) (xy 164.253831 -387.183321)
			(xy 164.234706 -387.247161) (xy 164.22116 -387.27761) (xy 164.216885 -387.288068) (xy 164.216998 -387.310636)
			(xy 164.226749 -387.33099) (xy 164.23513 -387.33857) (xy 164.257367 -387.357255) (xy 164.297429 -387.39931)
			(xy 164.33185 -387.446094) (xy 164.360076 -387.496857) (xy 164.381653 -387.550783) (xy 164.396235 -387.607006)
			(xy 164.403587 -387.664621) (xy 164.40404 -387.693662) (xy 164.403568 -387.722667) (xy 164.396257 -387.780215)
			(xy 164.381734 -387.836378) (xy 164.360233 -387.890256) (xy 164.332098 -387.940986) (xy 164.29778 -387.987756)
			(xy 164.257828 -388.029816) (xy 164.235638 -388.0485) (xy 164.228526 -388.054088) (xy 164.219382 -388.069328)
			(xy 164.204142 -388.152132) (xy 164.206936 -388.169404) (xy 164.211508 -388.177532) (xy 164.22408 -388.20072)
			(xy 164.241956 -388.250341) (xy 164.251058 -388.302292) (xy 164.25164 -388.328662) (xy 164.251571 -388.338021)
			(xy 164.250428 -388.356703) (xy 164.249354 -388.366) (xy 164.248338 -388.37489) (xy 164.252148 -388.391654)
			(xy 164.29609 -388.461504) (xy 164.309806 -388.471918) (xy 164.318188 -388.474712) (xy 164.342283 -388.483198)
			(xy 164.387574 -388.506822) (xy 164.42847 -388.537432) (xy 164.463902 -388.574228) (xy 164.492945 -388.61625)
			(xy 164.514842 -388.662401) (xy 164.522404 -388.686802) (xy 164.523928 -388.692644) (xy 164.843714 -389.245602)
			(xy 164.847778 -389.24992) (xy 164.863979 -389.267618) (xy 164.89134 -389.30703) (xy 164.912422 -389.350129)
			(xy 164.92674 -389.395922) (xy 164.933964 -389.443354) (xy 164.934392 -389.467344) (xy 164.933923 -389.492134)
			(xy 164.926161 -389.541102) (xy 164.910836 -389.588253) (xy 164.888324 -389.632427) (xy 164.85918 -389.672536)
			(xy 164.824121 -389.707593) (xy 164.78401 -389.736734) (xy 164.739834 -389.759243) (xy 164.692682 -389.774566)
			(xy 164.643714 -389.782324) (xy 164.618924 -389.782812) (xy 164.59353 -389.78229) (xy 164.543398 -389.774164)
			(xy 164.495213 -389.758116) (xy 164.450218 -389.73456) (xy 164.409575 -389.704106) (xy 164.374332 -389.667537)
			(xy 164.345398 -389.625798) (xy 164.323519 -389.579966) (xy 164.315902 -389.555736) (xy 164.314378 -389.549894)
			(xy 163.99383 -388.995412) (xy 163.989766 -388.991094) (xy 163.973669 -388.973431) (xy 163.94648 -388.934133)
			(xy 163.925527 -388.891185) (xy 163.911291 -388.845568) (xy 163.904095 -388.798326) (xy 163.90366 -388.774432)
			(xy 163.903741 -388.762384) (xy 163.905523 -388.738355) (xy 163.907216 -388.726426) (xy 163.908486 -388.717536)
			(xy 163.905438 -388.700518) (xy 163.863274 -388.629652) (xy 163.850066 -388.618476) (xy 163.841684 -388.615428)
			(xy 163.819939 -388.607025) (xy 163.77908 -388.584586) (xy 163.742109 -388.556194) (xy 163.709886 -388.52251)
			(xy 163.68316 -388.484317) (xy 163.662554 -388.442504) (xy 163.648546 -388.398043) (xy 163.641462 -388.35197)
			(xy 163.641024 -388.328662) (xy 163.641587 -388.302289) (xy 163.65067 -388.25033) (xy 163.66856 -388.20071)
			(xy 163.681156 -388.177532) (xy 163.685728 -388.169404) (xy 163.688522 -388.152132) (xy 163.673282 -388.069328)
			(xy 163.664138 -388.054088) (xy 163.657026 -388.0485) (xy 163.634861 -388.029788) (xy 163.594912 -387.987728)
			(xy 163.560594 -387.940962) (xy 163.532454 -387.890236) (xy 163.510943 -387.836365) (xy 163.496406 -387.780208)
			(xy 163.489075 -387.722666) (xy 163.488624 -387.693662) (xy 163.489225 -387.660341) (xy 163.498884 -387.594403)
			(xy 163.518005 -387.530563) (xy 163.53155 -387.500114) (xy 163.535799 -387.489648) (xy 163.535694 -387.467086)
			(xy 163.525955 -387.446735) (xy 163.51758 -387.439154) (xy 163.495309 -387.420508) (xy 163.455248 -387.378447)
			(xy 163.42083 -387.331656) (xy 163.392608 -387.280886) (xy 163.371037 -387.226954) (xy 163.356462 -387.170725)
			(xy 163.349118 -387.113105) (xy 163.34867 -387.084062) (xy 163.349115 -387.055135) (xy 163.356399 -386.997743)
			(xy 163.370858 -386.941725) (xy 163.392263 -386.887978) (xy 163.420271 -386.837356) (xy 163.454436 -386.790668)
			(xy 163.494214 -386.748659) (xy 163.51631 -386.729986) (xy 163.52329 -386.723647) (xy 163.532542 -386.707237)
			(xy 163.534344 -386.697982) (xy 163.538662 -386.666994) (xy 163.539564 -386.657757) (xy 163.53554 -386.639658)
			(xy 163.530788 -386.631688) (xy 163.514479 -386.605843) (xy 163.490576 -386.549607) (xy 163.48329 -386.519928)
			(xy 163.481234 -386.511765) (xy 163.472531 -386.497364) (xy 163.466272 -386.491734) (xy 163.443158 -386.472684)
			(xy 163.436258 -386.467469) (xy 163.420043 -386.461484) (xy 163.411408 -386.461) (xy 163.381773 -386.459948)
			(xy 163.32311 -386.451305) (xy 163.266053 -386.435159) (xy 163.211559 -386.411782) (xy 163.16054 -386.381564)
			(xy 163.113849 -386.345011) (xy 163.07227 -386.302735) (xy 163.036497 -386.255444) (xy 163.00713 -386.20393)
			(xy 162.98466 -386.149056) (xy 162.969463 -386.091739) (xy 162.961795 -386.03294) (xy 162.96132 -386.003292)
			(xy 162.961842 -385.972229) (xy 162.970257 -385.910675) (xy 162.978084 -385.88061) (xy 162.980878 -385.87045)
			(xy 162.978338 -385.850638) (xy 162.93084 -385.768342) (xy 162.914838 -385.75615) (xy 162.904678 -385.75361)
			(xy 162.875567 -385.745616) (xy 162.819599 -385.722983) (xy 162.767091 -385.69319) (xy 162.718957 -385.656752)
			(xy 162.67603 -385.614303) (xy 162.639055 -385.566579) (xy 162.608676 -385.514409) (xy 162.585418 -385.458698)
			(xy 162.569686 -385.400413) (xy 162.561752 -385.340565) (xy 162.56127 -385.31038) (xy 162.5618 -385.279492)
			(xy 162.570104 -385.218277) (xy 162.58656 -385.158733) (xy 162.610868 -385.101941) (xy 162.626294 -385.075176)
			(xy 162.632136 -385.06527) (xy 162.634422 -385.042918) (xy 162.601148 -384.947668) (xy 162.5854 -384.931666)
			(xy 162.574732 -384.927602) (xy 162.551337 -384.918453) (xy 162.507441 -384.894026) (xy 162.467747 -384.863238)
			(xy 162.433169 -384.8268) (xy 162.404502 -384.785548) (xy 162.382406 -384.740434) (xy 162.367391 -384.692497)
			(xy 162.359802 -384.642839) (xy 162.35934 -384.617722) (xy 161.82086 -384.617722) (xy 161.820329 -384.644824)
			(xy 161.81152 -384.698307) (xy 161.803334 -384.724148) (xy 161.799524 -384.73507) (xy 161.802064 -384.757422)
			(xy 161.854642 -384.843274) (xy 161.873692 -384.85572) (xy 161.884868 -384.857498) (xy 161.914191 -384.862176)
			(xy 161.971362 -384.878229) (xy 162.025976 -384.901543) (xy 162.077115 -384.931726) (xy 162.12392 -384.968271)
			(xy 162.165604 -385.010563) (xy 162.201467 -385.057892) (xy 162.230907 -385.109462) (xy 162.253428 -385.164408)
			(xy 162.268652 -385.221805) (xy 162.276323 -385.280689) (xy 162.27679 -385.31038) (xy 162.276266 -385.341506)
			(xy 162.267861 -385.403188) (xy 162.260026 -385.433316) (xy 162.257232 -385.443476) (xy 162.259772 -385.463542)
			(xy 162.307016 -385.54533) (xy 162.323018 -385.557522) (xy 162.333178 -385.560062) (xy 162.362292 -385.568044)
			(xy 162.418258 -385.590682) (xy 162.470763 -385.620479) (xy 162.518896 -385.656919) (xy 162.561822 -385.69937)
			(xy 162.598795 -385.747094) (xy 162.629174 -385.799264) (xy 162.652433 -385.854975) (xy 162.668166 -385.91326)
			(xy 162.676103 -385.973107) (xy 162.676586 -386.003292) (xy 162.676461 -386.017427) (xy 162.674679 -386.045641)
			(xy 162.67303 -386.05968) (xy 162.672273 -386.068287) (xy 162.675911 -386.085166) (xy 162.680142 -386.0927)
			(xy 162.69589 -386.1181) (xy 162.7006 -386.12516) (xy 162.713705 -386.135929) (xy 162.721544 -386.139182)
			(xy 162.744928 -386.148358) (xy 162.788824 -386.17278) (xy 162.828518 -386.203563) (xy 162.863098 -386.239998)
			(xy 162.891767 -386.281245) (xy 162.913864 -386.326356) (xy 162.928882 -386.374291) (xy 162.936473 -386.423946)
			(xy 162.936936 -386.449062) (xy 162.936521 -386.473265) (xy 162.929446 -386.52115) (xy 162.915457 -386.56749)
			(xy 162.894853 -386.611291) (xy 162.881818 -386.631688) (xy 162.877027 -386.639643) (xy 162.872996 -386.657755)
			(xy 162.873944 -386.666994) (xy 162.878262 -386.697982) (xy 162.879955 -386.707275) (xy 162.889229 -386.723717)
			(xy 162.896296 -386.729986) (xy 162.91837 -386.748684) (xy 162.958145 -386.790692) (xy 162.99231 -386.837376)
			(xy 163.02032 -386.887993) (xy 163.04173 -386.941736) (xy 163.056197 -386.997748) (xy 163.063491 -387.055137)
			(xy 163.063936 -387.084062) (xy 163.063347 -387.117383) (xy 163.053684 -387.183322) (xy 163.034558 -387.247161)
			(xy 163.02101 -387.27761) (xy 163.016751 -387.288072) (xy 163.016865 -387.310635) (xy 163.026605 -387.330987)
			(xy 163.03498 -387.33857) (xy 163.057206 -387.357268) (xy 163.097271 -387.399319) (xy 163.131694 -387.4461)
			(xy 163.159922 -387.496861) (xy 163.181501 -387.550786) (xy 163.196084 -387.607007) (xy 163.203437 -387.664621)
			(xy 163.20389 -387.693662) (xy 163.203399 -387.722666) (xy 163.196089 -387.780212) (xy 163.181569 -387.836374)
			(xy 163.16007 -387.890252) (xy 163.131938 -387.940982) (xy 163.097623 -387.987753) (xy 163.057676 -388.029814)
			(xy 163.035488 -388.0485) (xy 163.028376 -388.054088) (xy 163.019232 -388.069328) (xy 163.003992 -388.152132)
			(xy 163.006786 -388.169404) (xy 163.011358 -388.177532) (xy 163.023935 -388.200718) (xy 163.041808 -388.25034)
			(xy 163.050908 -388.302291) (xy 163.05149 -388.328662) (xy 163.051422 -388.338021) (xy 163.050278 -388.356703)
			(xy 163.049204 -388.366) (xy 163.048188 -388.37489) (xy 163.051998 -388.391654) (xy 163.09594 -388.461504)
			(xy 163.109656 -388.471918) (xy 163.118038 -388.474712) (xy 163.142066 -388.483181) (xy 163.187238 -388.506733)
			(xy 163.228043 -388.537233) (xy 163.263423 -388.573887) (xy 163.292458 -388.615747) (xy 163.314397 -388.661724)
			(xy 163.322 -388.68604) (xy 163.323524 -388.691882) (xy 163.643818 -389.245602) (xy 163.647882 -389.24992)
			(xy 163.664084 -389.267617) (xy 163.691445 -389.30703) (xy 163.712527 -389.350129) (xy 163.726844 -389.395922)
			(xy 163.734068 -389.443354) (xy 163.734496 -389.467344) (xy 163.734023 -389.492133) (xy 163.726261 -389.541101)
			(xy 163.710936 -389.588252) (xy 163.688424 -389.632426) (xy 163.659281 -389.672534) (xy 163.624222 -389.707591)
			(xy 163.584112 -389.736733) (xy 163.539937 -389.759242) (xy 163.492785 -389.774565) (xy 163.443817 -389.782324)
			(xy 163.419028 -389.782812) (xy 163.393635 -389.782287) (xy 163.343502 -389.774161) (xy 163.295317 -389.758113)
			(xy 163.250323 -389.734559) (xy 163.20968 -389.704105) (xy 163.174436 -389.667537) (xy 163.145502 -389.625798)
			(xy 163.123623 -389.579965) (xy 163.116006 -389.555736) (xy 163.114482 -389.549894) (xy 162.794188 -388.996174)
			(xy 162.790124 -388.991856) (xy 162.773925 -388.974144) (xy 162.746499 -388.934755) (xy 162.725355 -388.891666)
			(xy 162.71098 -388.845873) (xy 162.703706 -388.79843) (xy 162.703256 -388.774432) (xy 162.703397 -388.76238)
			(xy 162.705304 -388.73835) (xy 162.707066 -388.726426) (xy 162.708336 -388.717536) (xy 162.705288 -388.700518)
			(xy 162.663124 -388.629652) (xy 162.649916 -388.618476) (xy 162.641534 -388.615428) (xy 162.619778 -388.607052)
			(xy 162.578921 -388.584607) (xy 162.541952 -388.55621) (xy 162.50973 -388.522521) (xy 162.483007 -388.484325)
			(xy 162.462402 -388.442509) (xy 162.448395 -388.398046) (xy 162.441312 -388.35197) (xy 162.440874 -388.328662)
			(xy 162.441443 -388.302289) (xy 162.450525 -388.250331) (xy 162.468412 -388.20071) (xy 162.481006 -388.177532)
			(xy 162.485578 -388.169404) (xy 162.488372 -388.152132) (xy 162.473132 -388.069328) (xy 162.463988 -388.054088)
			(xy 162.456876 -388.0485) (xy 162.4347 -388.0298) (xy 162.394754 -387.987737) (xy 162.360438 -387.940967)
			(xy 162.3323 -387.89024) (xy 162.310791 -387.836367) (xy 162.296255 -387.780209) (xy 162.288925 -387.722666)
			(xy 162.288474 -387.693662) (xy 162.289071 -387.660341) (xy 162.29873 -387.594403) (xy 162.317854 -387.530563)
			(xy 162.3314 -387.500114) (xy 162.335632 -387.489644) (xy 162.335527 -387.467088) (xy 162.325798 -387.446738)
			(xy 162.31743 -387.439154) (xy 162.295169 -387.420496) (xy 162.255106 -387.378438) (xy 162.220685 -387.33165)
			(xy 162.192462 -387.280882) (xy 162.170889 -387.226951) (xy 162.156313 -387.170724) (xy 162.148968 -387.113105)
			(xy 162.14852 -387.084062) (xy 162.148983 -387.055136) (xy 162.156266 -386.997745) (xy 162.170724 -386.941729)
			(xy 162.192126 -386.887981) (xy 162.220131 -386.83736) (xy 162.254293 -386.790672) (xy 162.294066 -386.748661)
			(xy 162.31616 -386.729986) (xy 162.323132 -386.723639) (xy 162.33239 -386.707235) (xy 162.334194 -386.697982)
			(xy 162.338512 -386.666994) (xy 162.339422 -386.657758) (xy 162.335394 -386.639657) (xy 162.330638 -386.631688)
			(xy 162.314333 -386.605841) (xy 162.290428 -386.549606) (xy 162.28314 -386.519928) (xy 162.28107 -386.511769)
			(xy 162.272376 -386.497367) (xy 162.266122 -386.491734) (xy 162.243008 -386.472684) (xy 162.236121 -386.467449)
			(xy 162.219896 -386.461477) (xy 162.211258 -386.461) (xy 162.181621 -386.459994) (xy 162.122956 -386.451345)
			(xy 162.065899 -386.435193) (xy 162.011405 -386.41181) (xy 161.960386 -386.381587) (xy 161.913696 -386.34503)
			(xy 161.872117 -386.30275) (xy 161.836345 -386.255456) (xy 161.806978 -386.203939) (xy 161.784509 -386.149062)
			(xy 161.769313 -386.091743) (xy 161.761645 -386.032941) (xy 161.76117 -386.003292) (xy 161.761691 -385.972229)
			(xy 161.770107 -385.910675) (xy 161.777934 -385.88061) (xy 161.780728 -385.87045) (xy 161.778188 -385.850638)
			(xy 161.73069 -385.768342) (xy 161.714688 -385.75615) (xy 161.704528 -385.75361) (xy 161.675439 -385.745581)
			(xy 161.619512 -385.722914) (xy 161.567047 -385.693098) (xy 161.518952 -385.656648) (xy 161.476062 -385.614198)
			(xy 161.43912 -385.566481) (xy 161.408765 -385.514326) (xy 161.385523 -385.458635) (xy 161.369798 -385.400374)
			(xy 161.361861 -385.340553) (xy 161.361374 -385.31038) (xy 161.361903 -385.279492) (xy 161.370208 -385.218277)
			(xy 161.386664 -385.158733) (xy 161.410972 -385.101941) (xy 161.426398 -385.075176) (xy 161.43224 -385.06527)
			(xy 161.434526 -385.042918) (xy 161.401252 -384.947668) (xy 161.385504 -384.931666) (xy 161.374836 -384.927602)
			(xy 161.351442 -384.91845) (xy 161.307546 -384.894024) (xy 161.267852 -384.863237) (xy 161.233273 -384.826799)
			(xy 161.204606 -384.785548) (xy 161.18251 -384.740434) (xy 161.167495 -384.692497) (xy 161.159906 -384.642839)
			(xy 161.159444 -384.617722) (xy 160.62071 -384.617722) (xy 160.620177 -384.644824) (xy 160.611369 -384.698306)
			(xy 160.603184 -384.724148) (xy 160.599374 -384.73507) (xy 160.601914 -384.757422) (xy 160.654492 -384.843274)
			(xy 160.673542 -384.85572) (xy 160.684718 -384.857498) (xy 160.714034 -384.862215) (xy 160.771205 -384.878262)
			(xy 160.825819 -384.901571) (xy 160.876959 -384.931748) (xy 160.923765 -384.968288) (xy 160.96545 -385.010577)
			(xy 161.001314 -385.057902) (xy 161.030755 -385.10947) (xy 161.053277 -385.164413) (xy 161.068501 -385.221808)
			(xy 161.076173 -385.28069) (xy 161.07664 -385.31038) (xy 161.076114 -385.341443) (xy 161.067701 -385.402996)
			(xy 161.059876 -385.433062) (xy 161.057082 -385.443222) (xy 161.059622 -385.463034) (xy 161.10712 -385.54533)
			(xy 161.123122 -385.557522) (xy 161.133282 -385.560062) (xy 161.162397 -385.568042) (xy 161.218363 -385.59068)
			(xy 161.270868 -385.620477) (xy 161.319001 -385.656918) (xy 161.361926 -385.699369) (xy 161.398899 -385.747093)
			(xy 161.429278 -385.799264) (xy 161.452537 -385.854975) (xy 161.468271 -385.913259) (xy 161.476207 -385.973106)
			(xy 161.47669 -386.003292) (xy 161.476565 -386.017427) (xy 161.474783 -386.045641) (xy 161.473134 -386.05968)
			(xy 161.472377 -386.068287) (xy 161.476015 -386.085167) (xy 161.480246 -386.0927) (xy 161.495994 -386.1181)
			(xy 161.500703 -386.125161) (xy 161.513809 -386.135929) (xy 161.521648 -386.139182) (xy 161.545033 -386.148356)
			(xy 161.588929 -386.172778) (xy 161.628623 -386.203562) (xy 161.663203 -386.239997) (xy 161.691871 -386.281245)
			(xy 161.713969 -386.326356) (xy 161.728986 -386.374291) (xy 161.736577 -386.423946) (xy 161.73704 -386.449062)
			(xy 161.736625 -386.473265) (xy 161.72955 -386.52115) (xy 161.715561 -386.56749) (xy 161.694957 -386.611291)
			(xy 161.681922 -386.631688) (xy 161.677131 -386.639643) (xy 161.6731 -386.657755) (xy 161.674048 -386.666994)
			(xy 161.678366 -386.697982) (xy 161.680058 -386.707275) (xy 161.689333 -386.723717) (xy 161.6964 -386.729986)
			(xy 161.718475 -386.748684) (xy 161.75825 -386.790691) (xy 161.792414 -386.837376) (xy 161.820425 -386.887993)
			(xy 161.841834 -386.941736) (xy 161.856301 -386.997748) (xy 161.863595 -387.055137) (xy 161.86404 -387.084062)
			(xy 161.86345 -387.117383) (xy 161.853788 -387.183322) (xy 161.834662 -387.247161) (xy 161.821114 -387.27761)
			(xy 161.816854 -387.288072) (xy 161.816968 -387.310635) (xy 161.826709 -387.330988) (xy 161.835084 -387.33857)
			(xy 161.857311 -387.357267) (xy 161.897376 -387.399318) (xy 161.931799 -387.4461) (xy 161.960026 -387.496861)
			(xy 161.981605 -387.550785) (xy 161.996188 -387.607007) (xy 162.003541 -387.664621) (xy 162.003994 -387.693662)
			(xy 162.003502 -387.722666) (xy 161.996192 -387.780212) (xy 161.981671 -387.836374) (xy 161.960173 -387.890252)
			(xy 161.932041 -387.940982) (xy 161.897727 -387.987753) (xy 161.85778 -388.029814) (xy 161.835592 -388.0485)
			(xy 161.82848 -388.054088) (xy 161.819336 -388.069328) (xy 161.804096 -388.152132) (xy 161.80689 -388.169404)
			(xy 161.811462 -388.177532) (xy 161.824039 -388.200718) (xy 161.841912 -388.25034) (xy 161.851012 -388.302291)
			(xy 161.851594 -388.328662) (xy 161.851526 -388.338021) (xy 161.850382 -388.356703) (xy 161.849308 -388.366)
			(xy 161.848292 -388.37489) (xy 161.852102 -388.391654) (xy 161.896044 -388.461504) (xy 161.90976 -388.471918)
			(xy 161.918142 -388.474712) (xy 161.942248 -388.483169) (xy 161.987538 -388.506801) (xy 162.028431 -388.537417)
			(xy 162.063861 -388.574218) (xy 162.092902 -388.616245) (xy 162.114797 -388.6624) (xy 162.122358 -388.686802)
			(xy 162.123882 -388.692644) (xy 162.443668 -389.245602) (xy 162.447732 -389.24992) (xy 162.463929 -389.267634)
			(xy 162.491353 -389.307024) (xy 162.512497 -389.350112) (xy 162.526872 -389.395905) (xy 162.534148 -389.443346)
			(xy 162.5346 -389.467344) (xy 162.534147 -389.492148) (xy 162.526377 -389.541143) (xy 162.511035 -389.588319)
			(xy 162.4885 -389.632513) (xy 162.459327 -389.672636) (xy 162.424234 -389.7077) (xy 162.384086 -389.736839)
			(xy 162.339873 -389.759337) (xy 162.292684 -389.774639) (xy 162.243682 -389.782368) (xy 162.218878 -389.782812)
			(xy 162.193483 -389.782331) (xy 162.143348 -389.774197) (xy 162.095163 -389.758142) (xy 162.050168 -389.734581)
			(xy 162.009526 -389.704121) (xy 161.974283 -389.667547) (xy 161.94535 -389.625804) (xy 161.923472 -389.579967)
			(xy 161.915856 -389.555736) (xy 161.914332 -389.549894) (xy 161.593784 -388.995412) (xy 161.58972 -388.991094)
			(xy 161.573628 -388.973414) (xy 161.546376 -388.934139) (xy 161.525362 -388.891202) (xy 161.511067 -388.845585)
			(xy 161.503819 -388.798334) (xy 161.50336 -388.774432) (xy 161.503501 -388.76238) (xy 161.505408 -388.73835)
			(xy 161.50717 -388.726426) (xy 161.50844 -388.717536) (xy 161.505392 -388.700518) (xy 161.463228 -388.629652)
			(xy 161.45002 -388.618476) (xy 161.441638 -388.615428) (xy 161.419883 -388.60705) (xy 161.379026 -388.584605)
			(xy 161.342056 -388.556208) (xy 161.309835 -388.52252) (xy 161.283111 -388.484324) (xy 161.262506 -388.442508)
			(xy 161.248499 -388.398046) (xy 161.241416 -388.35197) (xy 161.240978 -388.328662) (xy 161.241547 -388.302289)
			(xy 161.250629 -388.250331) (xy 161.268516 -388.20071) (xy 161.28111 -388.177532) (xy 161.285682 -388.169404)
			(xy 161.288476 -388.152132) (xy 161.273236 -388.069328) (xy 161.264092 -388.054088) (xy 161.25698 -388.0485)
			(xy 161.234805 -388.029799) (xy 161.194859 -387.987736) (xy 161.160543 -387.940967) (xy 161.132405 -387.89024)
			(xy 161.110895 -387.836367) (xy 161.096359 -387.780209) (xy 161.089029 -387.722666) (xy 161.088578 -387.693662)
			(xy 161.089175 -387.660341) (xy 161.098834 -387.594402) (xy 161.117957 -387.530563) (xy 161.131504 -387.500114)
			(xy 161.135735 -387.489643) (xy 161.13563 -387.467088) (xy 161.125902 -387.446738) (xy 161.117534 -387.439154)
			(xy 161.095274 -387.420495) (xy 161.05521 -387.378438) (xy 161.02079 -387.331649) (xy 160.992566 -387.280882)
			(xy 160.970993 -387.226951) (xy 160.956417 -387.170724) (xy 160.949072 -387.113105) (xy 160.948624 -387.084062)
			(xy 160.949086 -387.055136) (xy 160.956369 -386.997745) (xy 160.970827 -386.941728) (xy 160.992229 -386.887981)
			(xy 161.020234 -386.83736) (xy 161.054396 -386.790671) (xy 161.094169 -386.74866) (xy 161.116264 -386.729986)
			(xy 161.123236 -386.723639) (xy 161.132494 -386.707235) (xy 161.134298 -386.697982) (xy 161.138616 -386.666994)
			(xy 161.139525 -386.657758) (xy 161.135498 -386.639657) (xy 161.130742 -386.631688) (xy 161.114438 -386.60584)
			(xy 161.090532 -386.549606) (xy 161.083244 -386.519928) (xy 161.081173 -386.51177) (xy 161.07248 -386.497367)
			(xy 161.066226 -386.491734) (xy 161.043112 -386.472684) (xy 161.036224 -386.467451) (xy 161.02 -386.461477)
			(xy 161.011362 -386.461) (xy 160.981725 -386.459991) (xy 160.923061 -386.451342) (xy 160.866003 -386.435191)
			(xy 160.811509 -386.411808) (xy 160.76049 -386.381585) (xy 160.7138 -386.345028) (xy 160.672221 -386.302749)
			(xy 160.636449 -386.255455) (xy 160.607082 -386.203938) (xy 160.584613 -386.149061) (xy 160.569417 -386.091742)
			(xy 160.561749 -386.032941) (xy 160.561274 -386.003292) (xy 160.561794 -385.972229) (xy 160.570211 -385.910675)
			(xy 160.578038 -385.88061) (xy 160.580832 -385.87045) (xy 160.578292 -385.850638) (xy 160.530794 -385.768342)
			(xy 160.514792 -385.75615) (xy 160.504632 -385.75361) (xy 160.475512 -385.745646) (xy 160.419544 -385.723008)
			(xy 160.367038 -385.69321) (xy 160.318904 -385.656768) (xy 160.275979 -385.614315) (xy 160.239006 -385.566589)
			(xy 160.208627 -385.514416) (xy 160.18537 -385.458702) (xy 160.169639 -385.400415) (xy 160.161705 -385.340566)
			(xy 160.161224 -385.31038) (xy 160.161746 -385.279492) (xy 160.170052 -385.218276) (xy 160.18651 -385.158732)
			(xy 160.210821 -385.101941) (xy 160.226248 -385.075176) (xy 160.23209 -385.06527) (xy 160.234376 -385.042918)
			(xy 160.201102 -384.947668) (xy 160.185354 -384.931666) (xy 160.174686 -384.927602) (xy 160.151303 -384.918423)
			(xy 160.107406 -384.894003) (xy 160.067709 -384.863222) (xy 160.033129 -384.826788) (xy 160.004459 -384.78554)
			(xy 159.982362 -384.740429) (xy 159.967346 -384.692494) (xy 159.959756 -384.642838) (xy 159.959294 -384.617722)
			(xy 159.420814 -384.617722) (xy 159.420281 -384.644824) (xy 159.411473 -384.698306) (xy 159.403288 -384.724148)
			(xy 159.399478 -384.73507) (xy 159.402018 -384.757422) (xy 159.454596 -384.843274) (xy 159.473646 -384.85572)
			(xy 159.484822 -384.857498) (xy 159.514139 -384.862212) (xy 159.571309 -384.87826) (xy 159.625923 -384.901568)
			(xy 159.677063 -384.931747) (xy 159.723869 -384.968287) (xy 159.765554 -385.010575) (xy 159.801419 -385.057901)
			(xy 159.830859 -385.109469) (xy 159.853381 -385.164412) (xy 159.868605 -385.221808) (xy 159.876277 -385.28069)
			(xy 159.876744 -385.31038) (xy 159.876217 -385.341443) (xy 159.867805 -385.402996) (xy 159.85998 -385.433062)
			(xy 159.857186 -385.443222) (xy 159.859726 -385.463034) (xy 159.907224 -385.54533) (xy 159.923226 -385.557522)
			(xy 159.933386 -385.560062) (xy 159.962502 -385.568039) (xy 160.018468 -385.590677) (xy 160.070973 -385.620475)
			(xy 160.119105 -385.656916) (xy 160.16203 -385.699367) (xy 160.199003 -385.747092) (xy 160.229383 -385.799263)
			(xy 160.252641 -385.854974) (xy 160.268375 -385.913259) (xy 160.276311 -385.973106) (xy 160.276794 -386.003292)
			(xy 160.276669 -386.017427) (xy 160.274887 -386.045641) (xy 160.273238 -386.05968) (xy 160.27248 -386.068287)
			(xy 160.276118 -386.085167) (xy 160.28035 -386.0927) (xy 160.296098 -386.1181) (xy 160.300793 -386.125174)
			(xy 160.313902 -386.135947) (xy 160.321752 -386.139182) (xy 160.345105 -386.148398) (xy 160.388948 -386.172856)
			(xy 160.428591 -386.203658) (xy 160.463124 -386.240096) (xy 160.491755 -386.281335) (xy 160.513826 -386.326426)
			(xy 160.528829 -386.374335) (xy 160.536421 -386.423961) (xy 160.53689 -386.449062) (xy 160.536466 -386.473264)
			(xy 160.529393 -386.521149) (xy 160.515406 -386.567489) (xy 160.494805 -386.611291) (xy 160.481772 -386.631688)
			(xy 160.476984 -386.639645) (xy 160.47295 -386.657756) (xy 160.473898 -386.666994) (xy 160.478216 -386.697982)
			(xy 160.479893 -386.707279) (xy 160.489177 -386.723721) (xy 160.49625 -386.729986) (xy 160.518336 -386.748671)
			(xy 160.558108 -386.790682) (xy 160.59227 -386.837369) (xy 160.620279 -386.887989) (xy 160.641686 -386.941733)
			(xy 160.656152 -386.997747) (xy 160.663445 -387.055136) (xy 160.66389 -387.084062) (xy 160.663296 -387.117383)
			(xy 160.653634 -387.183321) (xy 160.63451 -387.247161) (xy 160.620964 -387.27761) (xy 160.616721 -387.288076)
			(xy 160.616835 -387.310633) (xy 160.626566 -387.330984) (xy 160.634934 -387.33857) (xy 160.657171 -387.357254)
			(xy 160.697234 -387.399309) (xy 160.731654 -387.446094) (xy 160.75988 -387.496857) (xy 160.781457 -387.550783)
			(xy 160.796039 -387.607005) (xy 160.803391 -387.664621) (xy 160.803844 -387.693662) (xy 160.80337 -387.722667)
			(xy 160.796059 -387.780214) (xy 160.781537 -387.836377) (xy 160.760036 -387.890255) (xy 160.731901 -387.940986)
			(xy 160.697583 -387.987756) (xy 160.657632 -388.029816) (xy 160.635442 -388.0485) (xy 160.62833 -388.054088)
			(xy 160.619186 -388.069328) (xy 160.603946 -388.152132) (xy 160.60674 -388.169404) (xy 160.611312 -388.177532)
			(xy 160.623885 -388.20072) (xy 160.64176 -388.250341) (xy 160.650862 -388.302291) (xy 160.651444 -388.328662)
			(xy 160.651375 -388.338021) (xy 160.650232 -388.356703) (xy 160.649158 -388.366) (xy 160.648142 -388.37489)
			(xy 160.651952 -388.391654) (xy 160.695894 -388.461504) (xy 160.70961 -388.471918) (xy 160.717992 -388.474712)
			(xy 160.742011 -388.483205) (xy 160.787184 -388.506752) (xy 160.827991 -388.537245) (xy 160.863372 -388.573896)
			(xy 160.89241 -388.615751) (xy 160.91435 -388.661726) (xy 160.921954 -388.68604) (xy 160.923478 -388.691882)
			(xy 161.243772 -389.245602) (xy 161.247836 -389.24992) (xy 161.264034 -389.267633) (xy 161.291458 -389.307023)
			(xy 161.312601 -389.350112) (xy 161.326976 -389.395904) (xy 161.334252 -389.443346) (xy 161.334704 -389.467344)
			(xy 161.334247 -389.492148) (xy 161.326477 -389.541143) (xy 161.311136 -389.588319) (xy 161.288601 -389.632512)
			(xy 161.259428 -389.672635) (xy 161.224335 -389.707698) (xy 161.184188 -389.736838) (xy 161.139976 -389.759336)
			(xy 161.092788 -389.774638) (xy 161.043786 -389.782367) (xy 161.018982 -389.782812) (xy 160.993587 -389.782327)
			(xy 160.943453 -389.774194) (xy 160.895267 -389.75814) (xy 160.850272 -389.734579) (xy 160.80963 -389.70412)
			(xy 160.774387 -389.667547) (xy 160.745454 -389.625804) (xy 160.723576 -389.579967) (xy 160.71596 -389.555736)
			(xy 160.714436 -389.549894) (xy 160.394142 -388.996174) (xy 160.390078 -388.991856) (xy 160.373923 -388.974118)
			(xy 160.346553 -388.934718) (xy 160.325461 -388.891629) (xy 160.311133 -388.845845) (xy 160.303898 -388.798419)
			(xy 160.303464 -388.774432) (xy 160.303544 -388.762384) (xy 160.305327 -388.738355) (xy 160.30702 -388.726426)
			(xy 160.30829 -388.717536) (xy 160.305242 -388.700518) (xy 160.263078 -388.629652) (xy 160.24987 -388.618476)
			(xy 160.241488 -388.615428) (xy 160.219744 -388.607023) (xy 160.178885 -388.584584) (xy 160.141914 -388.556193)
			(xy 160.10969 -388.522509) (xy 160.082964 -388.484316) (xy 160.062358 -388.442504) (xy 160.04835 -388.398043)
			(xy 160.041266 -388.35197) (xy 160.040828 -388.328662) (xy 160.04139 -388.302289) (xy 160.050474 -388.25033)
			(xy 160.068364 -388.20071) (xy 160.08096 -388.177532) (xy 160.085532 -388.169404) (xy 160.088326 -388.152132)
			(xy 160.073086 -388.069328) (xy 160.063942 -388.054088) (xy 160.05683 -388.0485) (xy 160.034666 -388.029787)
			(xy 159.994717 -387.987727) (xy 159.960398 -387.940961) (xy 159.932258 -387.890236) (xy 159.910747 -387.836364)
			(xy 159.89621 -387.780208) (xy 159.888879 -387.722666) (xy 159.888428 -387.693662) (xy 159.889029 -387.660341)
			(xy 159.898687 -387.594403) (xy 159.917809 -387.530563) (xy 159.931354 -387.500114) (xy 159.935602 -387.489647)
			(xy 159.935497 -387.467086) (xy 159.925759 -387.446735) (xy 159.917384 -387.439154) (xy 159.895114 -387.420507)
			(xy 159.855052 -387.378446) (xy 159.820634 -387.331655) (xy 159.792413 -387.280886) (xy 159.770841 -387.226953)
			(xy 159.756266 -387.170725) (xy 159.748922 -387.113105) (xy 159.748474 -387.084062) (xy 159.748917 -387.055135)
			(xy 159.756201 -386.997742) (xy 159.770661 -386.941725) (xy 159.792066 -386.887977) (xy 159.820074 -386.837356)
			(xy 159.85424 -386.790668) (xy 159.894017 -386.748659) (xy 159.916114 -386.729986) (xy 159.923078 -386.723631)
			(xy 159.932342 -386.707233) (xy 159.934148 -386.697982) (xy 159.938466 -386.666994) (xy 159.939367 -386.657757)
			(xy 159.935344 -386.639658) (xy 159.930592 -386.631688) (xy 159.914283 -386.605843) (xy 159.89038 -386.549607)
			(xy 159.883094 -386.519928) (xy 159.881037 -386.511765) (xy 159.872335 -386.497364) (xy 159.866076 -386.491734)
			(xy 159.842962 -386.472684) (xy 159.836145 -386.467458) (xy 159.820042 -386.4615) (xy 159.811466 -386.461)
			(xy 159.78183 -386.459987) (xy 159.723165 -386.451338) (xy 159.666108 -386.435188) (xy 159.611614 -386.411806)
			(xy 159.560594 -386.381583) (xy 159.513905 -386.345027) (xy 159.472325 -386.302748) (xy 159.436553 -386.255454)
			(xy 159.407186 -386.203938) (xy 159.384717 -386.149061) (xy 159.369521 -386.091742) (xy 159.361853 -386.032941)
			(xy 159.361378 -386.003292) (xy 159.361898 -385.972229) (xy 159.370315 -385.910675) (xy 159.378142 -385.88061)
			(xy 159.380936 -385.87045) (xy 159.378396 -385.850638) (xy 159.330898 -385.768342) (xy 159.314896 -385.75615)
			(xy 159.304736 -385.75361) (xy 159.275617 -385.745644) (xy 159.219649 -385.723006) (xy 159.167143 -385.693208)
			(xy 159.119009 -385.656767) (xy 159.076083 -385.614314) (xy 159.03911 -385.566588) (xy 159.008731 -385.514415)
			(xy 158.985474 -385.458702) (xy 158.969743 -385.400415) (xy 158.961809 -385.340566) (xy 158.961328 -385.31038)
			(xy 158.96185 -385.279492) (xy 158.970155 -385.218276) (xy 158.986613 -385.158732) (xy 159.010925 -385.10194)
			(xy 159.026352 -385.075176) (xy 159.032194 -385.06527) (xy 159.03448 -385.042918) (xy 159.001206 -384.947668)
			(xy 158.985458 -384.931666) (xy 158.97479 -384.927602) (xy 158.951407 -384.918421) (xy 158.90751 -384.894002)
			(xy 158.867814 -384.863221) (xy 158.833233 -384.826787) (xy 158.804564 -384.785539) (xy 158.782466 -384.740429)
			(xy 158.76745 -384.692494) (xy 158.75986 -384.642838) (xy 158.759398 -384.617722) (xy 158.220918 -384.617722)
			(xy 158.220385 -384.644824) (xy 158.211577 -384.698306) (xy 158.203392 -384.724148) (xy 158.199582 -384.73507)
			(xy 158.202122 -384.757422) (xy 158.2547 -384.843528) (xy 158.273496 -384.85572) (xy 158.284926 -384.857498)
			(xy 158.314213 -384.862319) (xy 158.371347 -384.87839) (xy 158.425923 -384.901714) (xy 158.477027 -384.931897)
			(xy 158.523798 -384.968435) (xy 158.565453 -385.010713) (xy 158.601292 -385.058022) (xy 158.630714 -385.109568)
			(xy 158.653224 -385.164485) (xy 158.668445 -385.221851) (xy 158.676121 -385.280704) (xy 158.676594 -385.31038)
			(xy 158.676069 -385.341443) (xy 158.667656 -385.402997) (xy 158.65983 -385.433062) (xy 158.657036 -385.443222)
			(xy 158.659576 -385.463034) (xy 158.707074 -385.54533) (xy 158.723076 -385.557522) (xy 158.733236 -385.560062)
			(xy 158.762342 -385.568073) (xy 158.818309 -385.590705) (xy 158.870815 -385.620498) (xy 158.918948 -385.656934)
			(xy 158.961875 -385.699381) (xy 158.998849 -385.747103) (xy 159.02923 -385.79927) (xy 159.052489 -385.854979)
			(xy 159.068224 -385.913262) (xy 159.07616 -385.973107) (xy 159.076644 -386.003292) (xy 159.076519 -386.017427)
			(xy 159.074737 -386.045641) (xy 159.073088 -386.05968) (xy 159.072323 -386.068287) (xy 159.075965 -386.085168)
			(xy 159.0802 -386.0927) (xy 159.095948 -386.1181) (xy 159.100639 -386.125174) (xy 159.113758 -386.135936)
			(xy 159.121602 -386.139182) (xy 159.144977 -386.14838) (xy 159.188874 -386.172797) (xy 159.22857 -386.203576)
			(xy 159.263152 -386.240007) (xy 159.291822 -386.281252) (xy 159.313921 -386.32636) (xy 159.328939 -386.374293)
			(xy 159.336531 -386.423947) (xy 159.336994 -386.449062) (xy 159.33657 -386.473264) (xy 159.329496 -386.521149)
			(xy 159.315509 -386.567488) (xy 159.294909 -386.61129) (xy 159.281876 -386.631688) (xy 159.277089 -386.639645)
			(xy 159.273054 -386.657756) (xy 159.274002 -386.666994) (xy 159.27832 -386.697982) (xy 159.279996 -386.70728)
			(xy 159.289281 -386.723721) (xy 159.296354 -386.729986) (xy 159.31844 -386.74867) (xy 159.358212 -386.790681)
			(xy 159.392375 -386.837369) (xy 159.420383 -386.887988) (xy 159.44179 -386.941733) (xy 159.456256 -386.997747)
			(xy 159.463549 -387.055136) (xy 159.463994 -387.084062) (xy 159.463399 -387.117383) (xy 159.453738 -387.183321)
			(xy 159.434614 -387.247161) (xy 159.421068 -387.27761) (xy 159.416823 -387.288076) (xy 159.416937 -387.310634)
			(xy 159.426669 -387.330985) (xy 159.435038 -387.33857) (xy 159.457276 -387.357254) (xy 159.497338 -387.399308)
			(xy 159.531759 -387.446093) (xy 159.559984 -387.496857) (xy 159.581561 -387.550783) (xy 159.596143 -387.607005)
			(xy 159.603495 -387.664621) (xy 159.603948 -387.693662) (xy 159.603473 -387.722667) (xy 159.596162 -387.780214)
			(xy 159.58164 -387.836377) (xy 159.560139 -387.890255) (xy 159.532004 -387.940986) (xy 159.497687 -387.987756)
			(xy 159.457735 -388.029815) (xy 159.435546 -388.0485) (xy 159.428434 -388.054088) (xy 159.41929 -388.069328)
			(xy 159.40405 -388.152132) (xy 159.406844 -388.169404) (xy 159.411416 -388.177532) (xy 159.423989 -388.20072)
			(xy 159.441864 -388.25034) (xy 159.450966 -388.302291) (xy 159.451548 -388.328662) (xy 159.451479 -388.338021)
			(xy 159.450336 -388.356703) (xy 159.449262 -388.366) (xy 159.448246 -388.37489) (xy 159.452056 -388.391654)
			(xy 159.495998 -388.461504) (xy 159.509714 -388.471918) (xy 159.518096 -388.474712) (xy 159.542116 -388.483203)
			(xy 159.587289 -388.50675) (xy 159.628096 -388.537244) (xy 159.663477 -388.573895) (xy 159.692514 -388.615751)
			(xy 159.714454 -388.661726) (xy 159.722058 -388.68604) (xy 159.723582 -388.691882) (xy 160.043876 -389.245602)
			(xy 160.04794 -389.24992) (xy 160.064138 -389.267633) (xy 160.091562 -389.307023) (xy 160.112705 -389.350111)
			(xy 160.12708 -389.395904) (xy 160.134356 -389.443346) (xy 160.134808 -389.467344) (xy 160.134347 -389.492147)
			(xy 160.126577 -389.541142) (xy 160.111236 -389.588318) (xy 160.088701 -389.632511) (xy 160.059529 -389.672634)
			(xy 160.024437 -389.707697) (xy 159.984291 -389.736836) (xy 159.940079 -389.759335) (xy 159.892891 -389.774637)
			(xy 159.84389 -389.782367) (xy 159.819086 -389.782812) (xy 159.793691 -389.782324) (xy 159.743557 -389.774191)
			(xy 159.695371 -389.758138) (xy 159.650377 -389.734577) (xy 159.609734 -389.704118) (xy 159.574492 -389.667546)
			(xy 159.545558 -389.625803) (xy 159.52368 -389.579967) (xy 159.516064 -389.555736) (xy 159.51454 -389.549894)
			(xy 159.194246 -388.996174) (xy 159.190182 -388.991856) (xy 159.174027 -388.974118) (xy 159.146657 -388.934717)
			(xy 159.125565 -388.891629) (xy 159.111237 -388.845845) (xy 159.104002 -388.798419) (xy 159.103568 -388.774432)
			(xy 159.103648 -388.762384) (xy 159.105431 -388.738355) (xy 159.107124 -388.726426) (xy 159.108394 -388.717536)
			(xy 159.105346 -388.700518) (xy 159.063182 -388.629652) (xy 159.049974 -388.618476) (xy 159.041592 -388.615428)
			(xy 159.019849 -388.607021) (xy 158.97899 -388.584583) (xy 158.942018 -388.556192) (xy 158.909795 -388.522508)
			(xy 158.883069 -388.484316) (xy 158.862462 -388.442503) (xy 158.848454 -388.398043) (xy 158.84137 -388.351969)
			(xy 158.840932 -388.328662) (xy 158.841494 -388.302289) (xy 158.850578 -388.25033) (xy 158.868468 -388.20071)
			(xy 158.881064 -388.177532) (xy 158.885636 -388.169404) (xy 158.88843 -388.152132) (xy 158.87319 -388.069328)
			(xy 158.864046 -388.054088) (xy 158.856934 -388.0485) (xy 158.83477 -388.029786) (xy 158.794822 -387.987727)
			(xy 158.760503 -387.940961) (xy 158.732362 -387.890236) (xy 158.710851 -387.836364) (xy 158.696314 -387.780208)
			(xy 158.688983 -387.722666) (xy 158.688532 -387.693662) (xy 158.689133 -387.660341) (xy 158.698791 -387.594403)
			(xy 158.717913 -387.530563) (xy 158.731458 -387.500114) (xy 158.735704 -387.489647) (xy 158.7356 -387.467087)
			(xy 158.725862 -387.446735) (xy 158.717488 -387.439154) (xy 158.695218 -387.420506) (xy 158.655157 -387.378446)
			(xy 158.620739 -387.331655) (xy 158.592517 -387.280885) (xy 158.570945 -387.226953) (xy 158.55637 -387.170725)
			(xy 158.549026 -387.113105) (xy 158.548578 -387.084062) (xy 158.54902 -387.055135) (xy 158.556304 -386.997742)
			(xy 158.570764 -386.941725) (xy 158.592169 -386.887977) (xy 158.620178 -386.837355) (xy 158.654343 -386.790668)
			(xy 158.694121 -386.748659) (xy 158.716218 -386.729986) (xy 158.723183 -386.723632) (xy 158.732446 -386.707233)
			(xy 158.734252 -386.697982) (xy 158.73857 -386.666994) (xy 158.739471 -386.657757) (xy 158.735448 -386.639658)
			(xy 158.730696 -386.631688) (xy 158.714387 -386.605843) (xy 158.690484 -386.549607) (xy 158.683198 -386.519928)
			(xy 158.681139 -386.511766) (xy 158.672438 -386.497365) (xy 158.66618 -386.491734) (xy 158.643066 -386.472684)
			(xy 158.63619 -386.467432) (xy 158.619956 -386.46147) (xy 158.611316 -386.461) (xy 158.581681 -386.459941)
			(xy 158.523018 -386.451299) (xy 158.465962 -386.435154) (xy 158.411468 -386.411777) (xy 158.360449 -386.38156)
			(xy 158.313758 -386.345007) (xy 158.272178 -386.302732) (xy 158.236405 -386.255442) (xy 158.207038 -386.203929)
			(xy 158.184568 -386.149055) (xy 158.169371 -386.091739) (xy 158.161703 -386.03294) (xy 158.161228 -386.003292)
			(xy 158.161749 -385.972229) (xy 158.170165 -385.910675) (xy 158.177992 -385.88061) (xy 158.180786 -385.87045)
			(xy 158.178246 -385.850638) (xy 158.130748 -385.768342) (xy 158.114746 -385.75615) (xy 158.104586 -385.75361)
			(xy 158.075476 -385.74561) (xy 158.019508 -385.722979) (xy 157.967001 -385.693186) (xy 157.918866 -385.656749)
			(xy 157.875938 -385.614301) (xy 157.838964 -385.566578) (xy 157.808584 -385.514408) (xy 157.785326 -385.458697)
			(xy 157.769594 -385.400412) (xy 157.76166 -385.340565) (xy 157.761178 -385.31038) (xy 157.761646 -385.279457)
			(xy 157.769929 -385.21817) (xy 157.786396 -385.158558) (xy 157.810746 -385.101709) (xy 157.826202 -385.074922)
			(xy 157.832298 -385.06527) (xy 157.834584 -385.042918) (xy 157.801056 -384.947668) (xy 157.785308 -384.931666)
			(xy 157.77464 -384.927602) (xy 157.751279 -384.918404) (xy 157.707437 -384.893943) (xy 157.667793 -384.863139)
			(xy 157.63326 -384.826698) (xy 157.60463 -384.785456) (xy 157.582561 -384.740363) (xy 157.567559 -384.692452)
			(xy 157.55997 -384.642824) (xy 157.559502 -384.617722) (xy 157.020768 -384.617722) (xy 157.020237 -384.644824)
			(xy 157.011428 -384.698307) (xy 157.003242 -384.724148) (xy 156.999432 -384.73507) (xy 157.001972 -384.757422)
			(xy 157.05455 -384.843274) (xy 157.0736 -384.85572) (xy 157.084776 -384.857498) (xy 157.1141 -384.86217)
			(xy 157.171271 -384.878224) (xy 157.225885 -384.901539) (xy 157.277024 -384.931722) (xy 157.323828 -384.968268)
			(xy 157.365513 -385.01056) (xy 157.401376 -385.05789) (xy 157.430815 -385.109461) (xy 157.453336 -385.164407)
			(xy 157.46856 -385.221804) (xy 157.476231 -385.280689) (xy 157.476698 -385.31038) (xy 157.476173 -385.341443)
			(xy 157.46776 -385.402997) (xy 157.459934 -385.433062) (xy 157.45714 -385.443222) (xy 157.45968 -385.463034)
			(xy 157.507178 -385.54533) (xy 157.52318 -385.557522) (xy 157.53334 -385.560062) (xy 157.562447 -385.56807)
			(xy 157.618413 -385.590703) (xy 157.670919 -385.620496) (xy 157.719053 -385.656932) (xy 157.761979 -385.69938)
			(xy 157.798954 -385.747102) (xy 157.829334 -385.79927) (xy 157.852593 -385.854979) (xy 157.868328 -385.913262)
			(xy 157.876264 -385.973107) (xy 157.876748 -386.003292) (xy 157.876623 -386.017427) (xy 157.874841 -386.045641)
			(xy 157.873192 -386.05968) (xy 157.872426 -386.068287) (xy 157.876068 -386.085168) (xy 157.880304 -386.0927)
			(xy 157.896052 -386.1181) (xy 157.900762 -386.125163) (xy 157.913861 -386.135942) (xy 157.921706 -386.139182)
			(xy 157.945049 -386.148423) (xy 157.988893 -386.172875) (xy 158.028538 -386.203672) (xy 158.063073 -386.240107)
			(xy 158.091706 -386.281342) (xy 158.113778 -386.326431) (xy 158.128783 -386.374337) (xy 158.136375 -386.423961)
			(xy 158.136844 -386.449062) (xy 158.136428 -386.473265) (xy 158.129353 -386.52115) (xy 158.115364 -386.56749)
			(xy 158.094761 -386.611291) (xy 158.081726 -386.631688) (xy 158.076935 -386.639643) (xy 158.072904 -386.657756)
			(xy 158.073852 -386.666994) (xy 158.07817 -386.697982) (xy 158.079861 -386.707276) (xy 158.089136 -386.723718)
			(xy 158.096204 -386.729986) (xy 158.11828 -386.748683) (xy 158.158054 -386.79069) (xy 158.192219 -386.837375)
			(xy 158.220229 -386.887992) (xy 158.241638 -386.941736) (xy 158.256105 -386.997748) (xy 158.263399 -387.055137)
			(xy 158.263844 -387.084062) (xy 158.263254 -387.117383) (xy 158.253591 -387.183322) (xy 158.234466 -387.247161)
			(xy 158.220918 -387.27761) (xy 158.216657 -387.288071) (xy 158.21677 -387.310635) (xy 158.226512 -387.330988)
			(xy 158.234888 -387.33857) (xy 158.257116 -387.357266) (xy 158.297181 -387.399317) (xy 158.331603 -387.446099)
			(xy 158.359831 -387.496861) (xy 158.381409 -387.550785) (xy 158.395992 -387.607007) (xy 158.403345 -387.664621)
			(xy 158.403798 -387.693662) (xy 158.40334 -387.722668) (xy 158.396029 -387.780216) (xy 158.381505 -387.83638)
			(xy 158.360002 -387.890259) (xy 158.331864 -387.940989) (xy 158.297542 -387.987758) (xy 158.257587 -388.029816)
			(xy 158.235396 -388.0485) (xy 158.228284 -388.054088) (xy 158.21914 -388.069328) (xy 158.2039 -388.152132)
			(xy 158.206694 -388.169404) (xy 158.211266 -388.177532) (xy 158.223843 -388.200718) (xy 158.241716 -388.25034)
			(xy 158.250816 -388.302291) (xy 158.251398 -388.328662) (xy 158.25133 -388.338021) (xy 158.250186 -388.356703)
			(xy 158.249112 -388.366) (xy 158.248096 -388.37489) (xy 158.251906 -388.391654) (xy 158.295848 -388.461504)
			(xy 158.309564 -388.471918) (xy 158.317946 -388.474712) (xy 158.341976 -388.483177) (xy 158.387148 -388.50673)
			(xy 158.427952 -388.53723) (xy 158.463331 -388.573886) (xy 158.492367 -388.615746) (xy 158.514305 -388.661724)
			(xy 158.521908 -388.68604) (xy 158.523432 -388.691882) (xy 158.843726 -389.245602) (xy 158.84779 -389.24992)
			(xy 158.863993 -389.267616) (xy 158.891353 -389.307029) (xy 158.912435 -389.350129) (xy 158.926752 -389.395922)
			(xy 158.933976 -389.443354) (xy 158.934404 -389.467344) (xy 158.933923 -389.492133) (xy 158.926161 -389.5411)
			(xy 158.910837 -389.58825) (xy 158.888326 -389.632423) (xy 158.859183 -389.672532) (xy 158.824126 -389.707588)
			(xy 158.784016 -389.73673) (xy 158.739843 -389.75924) (xy 158.692692 -389.774563) (xy 158.643725 -389.782323)
			(xy 158.618936 -389.782812) (xy 158.593543 -389.78228) (xy 158.543411 -389.774155) (xy 158.495226 -389.758109)
			(xy 158.450231 -389.734555) (xy 158.409588 -389.704102) (xy 158.374345 -389.667535) (xy 158.34541 -389.625797)
			(xy 158.323531 -389.579965) (xy 158.315914 -389.555736) (xy 158.31439 -389.549894) (xy 157.994096 -388.996174)
			(xy 157.990032 -388.991856) (xy 157.973817 -388.974158) (xy 157.946397 -388.934763) (xy 157.925258 -388.891671)
			(xy 157.910886 -388.845875) (xy 157.903614 -388.798431) (xy 157.903164 -388.774432) (xy 157.903305 -388.76238)
			(xy 157.905212 -388.73835) (xy 157.906974 -388.726426) (xy 157.908244 -388.717536) (xy 157.905196 -388.700518)
			(xy 157.863032 -388.629652) (xy 157.849824 -388.618476) (xy 157.841442 -388.615428) (xy 157.819688 -388.607048)
			(xy 157.77883 -388.584604) (xy 157.741861 -388.556207) (xy 157.709639 -388.522519) (xy 157.682915 -388.484324)
			(xy 157.66231 -388.442508) (xy 157.648303 -388.398046) (xy 157.64122 -388.35197) (xy 157.640782 -388.328662)
			(xy 157.64135 -388.302289) (xy 157.650432 -388.250331) (xy 157.66832 -388.20071) (xy 157.680914 -388.177532)
			(xy 157.685486 -388.169404) (xy 157.68828 -388.152132) (xy 157.67304 -388.069328) (xy 157.663896 -388.054088)
			(xy 157.656784 -388.0485) (xy 157.63461 -388.029798) (xy 157.594664 -387.987735) (xy 157.560347 -387.940967)
			(xy 157.532209 -387.89024) (xy 157.5107 -387.836367) (xy 157.496163 -387.780209) (xy 157.488833 -387.722666)
			(xy 157.488382 -387.693662) (xy 157.488978 -387.660341) (xy 157.498638 -387.594402) (xy 157.517761 -387.530563)
			(xy 157.531308 -387.500114) (xy 157.535538 -387.489643) (xy 157.535432 -387.467088) (xy 157.525705 -387.446739)
			(xy 157.517338 -387.439154) (xy 157.495079 -387.420494) (xy 157.455015 -387.378437) (xy 157.420594 -387.331649)
			(xy 157.39237 -387.280881) (xy 157.370797 -387.226951) (xy 157.356221 -387.170724) (xy 157.348876 -387.113105)
			(xy 157.348428 -387.084062) (xy 157.348888 -387.055136) (xy 157.356171 -386.997744) (xy 157.37063 -386.941728)
			(xy 157.392032 -386.887981) (xy 157.420038 -386.837359) (xy 157.4542 -386.790671) (xy 157.493973 -386.74866)
			(xy 157.516068 -386.729986) (xy 157.523041 -386.72364) (xy 157.532298 -386.707235) (xy 157.534102 -386.697982)
			(xy 157.53842 -386.666994) (xy 157.539328 -386.657757) (xy 157.535302 -386.639657) (xy 157.530546 -386.631688)
			(xy 157.514242 -386.60584) (xy 157.490336 -386.549606) (xy 157.483048 -386.519928) (xy 157.480976 -386.51177)
			(xy 157.472283 -386.497368) (xy 157.46603 -386.491734) (xy 157.442916 -386.472684) (xy 157.436085 -386.467479)
			(xy 157.419993 -386.461508) (xy 157.41142 -386.461) (xy 157.381782 -386.460029) (xy 157.323116 -386.451375)
			(xy 157.266058 -386.435219) (xy 157.211564 -386.411832) (xy 157.160545 -386.381605) (xy 157.113855 -386.345044)
			(xy 157.072277 -386.302762) (xy 157.036505 -386.255465) (xy 157.007139 -386.203946) (xy 156.98467 -386.149066)
			(xy 156.969475 -386.091745) (xy 156.961807 -386.032942) (xy 156.961332 -386.003292) (xy 156.961853 -385.972229)
			(xy 156.970269 -385.910675) (xy 156.978096 -385.88061) (xy 156.98089 -385.87045) (xy 156.97835 -385.850638)
			(xy 156.930852 -385.768342) (xy 156.91485 -385.75615) (xy 156.90469 -385.75361) (xy 156.875581 -385.745608)
			(xy 156.819613 -385.722977) (xy 156.767105 -385.693184) (xy 156.71897 -385.656748) (xy 156.676043 -385.6143)
			(xy 156.639068 -385.566577) (xy 156.608688 -385.514407) (xy 156.58543 -385.458697) (xy 156.569698 -385.400412)
			(xy 156.561764 -385.340565) (xy 156.561282 -385.31038) (xy 156.56181 -385.279492) (xy 156.570115 -385.218277)
			(xy 156.586571 -385.158733) (xy 156.61088 -385.101941) (xy 156.626306 -385.075176) (xy 156.632148 -385.06527)
			(xy 156.634434 -385.042918) (xy 156.60116 -384.947668) (xy 156.585412 -384.931666) (xy 156.574744 -384.927602)
			(xy 156.551351 -384.918446) (xy 156.507456 -384.894021) (xy 156.467761 -384.863235) (xy 156.433182 -384.826797)
			(xy 156.404514 -384.785547) (xy 156.382418 -384.740433) (xy 156.367403 -384.692496) (xy 156.359814 -384.642839)
			(xy 156.359352 -384.617722) (xy 155.820872 -384.617722) (xy 155.820341 -384.644824) (xy 155.811532 -384.698307)
			(xy 155.803346 -384.724148) (xy 155.799536 -384.73507) (xy 155.802076 -384.757422) (xy 155.854654 -384.843274)
			(xy 155.873704 -384.85572) (xy 155.88488 -384.857498) (xy 155.914205 -384.862167) (xy 155.971376 -384.878222)
			(xy 156.025989 -384.901537) (xy 156.077128 -384.931721) (xy 156.123933 -384.968266) (xy 156.165617 -385.010559)
			(xy 156.20148 -385.057889) (xy 156.230919 -385.10946) (xy 156.25344 -385.164406) (xy 156.268664 -385.221804)
			(xy 156.276335 -385.280689) (xy 156.276802 -385.31038) (xy 156.276278 -385.341506) (xy 156.267873 -385.403188)
			(xy 156.260038 -385.433316) (xy 156.257244 -385.443476) (xy 156.259784 -385.463542) (xy 156.307028 -385.54533)
			(xy 156.32303 -385.557522) (xy 156.33319 -385.560062) (xy 156.362307 -385.568036) (xy 156.418273 -385.590675)
			(xy 156.470777 -385.620474) (xy 156.51891 -385.656915) (xy 156.561835 -385.699366) (xy 156.598808 -385.747092)
			(xy 156.629187 -385.799263) (xy 156.652445 -385.854974) (xy 156.668179 -385.913259) (xy 156.676115 -385.973106)
			(xy 156.676598 -386.003292) (xy 156.676473 -386.017427) (xy 156.674691 -386.045641) (xy 156.673042 -386.05968)
			(xy 156.672283 -386.068287) (xy 156.675922 -386.085167) (xy 156.680154 -386.0927) (xy 156.695902 -386.1181)
			(xy 156.700608 -386.125163) (xy 156.713716 -386.13593) (xy 156.721556 -386.139182) (xy 156.744943 -386.148351)
			(xy 156.788838 -386.172775) (xy 156.828532 -386.203559) (xy 156.863112 -386.239995) (xy 156.89178 -386.281244)
			(xy 156.913877 -386.326355) (xy 156.928894 -386.37429) (xy 156.936485 -386.423946) (xy 156.936948 -386.449062)
			(xy 156.936531 -386.473264) (xy 156.929457 -386.52115) (xy 156.915468 -386.56749) (xy 156.894865 -386.611291)
			(xy 156.88183 -386.631688) (xy 156.877039 -386.639643) (xy 156.873008 -386.657756) (xy 156.873956 -386.666994)
			(xy 156.878274 -386.697982) (xy 156.879964 -386.707276) (xy 156.88924 -386.723718) (xy 156.896308 -386.729986)
			(xy 156.918384 -386.748682) (xy 156.958159 -386.79069) (xy 156.992323 -386.837375) (xy 157.020333 -386.887992)
			(xy 157.041742 -386.941735) (xy 157.056209 -386.997748) (xy 157.063503 -387.055137) (xy 157.063948 -387.084062)
			(xy 157.063358 -387.117383) (xy 157.053695 -387.183322) (xy 157.034569 -387.247161) (xy 157.021022 -387.27761)
			(xy 157.01676 -387.288071) (xy 157.016873 -387.310635) (xy 157.026616 -387.330988) (xy 157.034992 -387.33857)
			(xy 157.057221 -387.357265) (xy 157.097285 -387.399316) (xy 157.131708 -387.446099) (xy 157.159935 -387.49686)
			(xy 157.181513 -387.550785) (xy 157.196096 -387.607006) (xy 157.203449 -387.664621) (xy 157.203902 -387.693662)
			(xy 157.203443 -387.722668) (xy 157.196131 -387.780216) (xy 157.181608 -387.83638) (xy 157.160105 -387.890259)
			(xy 157.131967 -387.940989) (xy 157.097646 -387.987758) (xy 157.057691 -388.029816) (xy 157.0355 -388.0485)
			(xy 157.028388 -388.054088) (xy 157.019244 -388.069328) (xy 157.004004 -388.152132) (xy 157.006798 -388.169404)
			(xy 157.01137 -388.177532) (xy 157.023939 -388.200722) (xy 157.041817 -388.250341) (xy 157.05092 -388.302292)
			(xy 157.051502 -388.328662) (xy 157.051434 -388.338021) (xy 157.05029 -388.356703) (xy 157.049216 -388.366)
			(xy 157.0482 -388.37489) (xy 157.05201 -388.391654) (xy 157.095952 -388.461504) (xy 157.109668 -388.471918)
			(xy 157.11805 -388.474712) (xy 157.14208 -388.483174) (xy 157.187252 -388.506729) (xy 157.228057 -388.537229)
			(xy 157.263436 -388.573885) (xy 157.292471 -388.615746) (xy 157.314409 -388.661724) (xy 157.322012 -388.68604)
			(xy 157.323536 -388.691882) (xy 157.64383 -389.245602) (xy 157.647894 -389.24992) (xy 157.664098 -389.267615)
			(xy 157.691458 -389.307029) (xy 157.712539 -389.350128) (xy 157.726856 -389.395922) (xy 157.73408 -389.443354)
			(xy 157.734508 -389.467344) (xy 157.734023 -389.492133) (xy 157.726262 -389.541099) (xy 157.710937 -389.588249)
			(xy 157.688427 -389.632422) (xy 157.659284 -389.67253) (xy 157.624227 -389.707587) (xy 157.584119 -389.736729)
			(xy 157.539946 -389.759239) (xy 157.492795 -389.774562) (xy 157.443829 -389.782323) (xy 157.41904 -389.782812)
			(xy 157.393647 -389.782276) (xy 157.343515 -389.774152) (xy 157.29533 -389.758106) (xy 157.250336 -389.734553)
			(xy 157.209693 -389.704101) (xy 157.174449 -389.667534) (xy 157.145514 -389.625796) (xy 157.123635 -389.579965)
			(xy 157.116018 -389.555736) (xy 157.114494 -389.549894) (xy 156.7942 -388.996174) (xy 156.790136 -388.991856)
			(xy 156.773922 -388.974157) (xy 156.746502 -388.934763) (xy 156.725362 -388.891671) (xy 156.71099 -388.845875)
			(xy 156.703718 -388.798431) (xy 156.703268 -388.774432) (xy 156.70341 -388.76238) (xy 156.705316 -388.73835)
			(xy 156.707078 -388.726426) (xy 156.708348 -388.717536) (xy 156.7053 -388.700518) (xy 156.663136 -388.629652)
			(xy 156.649928 -388.618476) (xy 156.641546 -388.615428) (xy 156.619793 -388.607046) (xy 156.578935 -388.584602)
			(xy 156.541966 -388.556206) (xy 156.509744 -388.522518) (xy 156.483019 -388.484323) (xy 156.462414 -388.442508)
			(xy 156.448407 -388.398045) (xy 156.441324 -388.35197) (xy 156.440886 -388.328662) (xy 156.441454 -388.302289)
			(xy 156.450536 -388.250331) (xy 156.468424 -388.20071) (xy 156.481018 -388.177532) (xy 156.48559 -388.169404)
			(xy 156.488384 -388.152132) (xy 156.473144 -388.069328) (xy 156.464 -388.054088) (xy 156.456888 -388.0485)
			(xy 156.434715 -388.029797) (xy 156.394768 -387.987735) (xy 156.360451 -387.940966) (xy 156.332313 -387.890239)
			(xy 156.310804 -387.836366) (xy 156.296267 -387.780209) (xy 156.288937 -387.722666) (xy 156.288486 -387.693662)
			(xy 156.289082 -387.660341) (xy 156.298741 -387.594402) (xy 156.317865 -387.530563) (xy 156.331412 -387.500114)
			(xy 156.335641 -387.489643) (xy 156.335536 -387.467088) (xy 156.325809 -387.446739) (xy 156.317442 -387.439154)
			(xy 156.295184 -387.420493) (xy 156.255119 -387.378436) (xy 156.220699 -387.331648) (xy 156.192475 -387.280881)
			(xy 156.170901 -387.226951) (xy 156.156325 -387.170724) (xy 156.14898 -387.113105) (xy 156.148532 -387.084062)
			(xy 156.148991 -387.055136) (xy 156.156274 -386.997744) (xy 156.170732 -386.941728) (xy 156.192135 -386.887981)
			(xy 156.220141 -386.837359) (xy 156.254303 -386.790671) (xy 156.294077 -386.74866) (xy 156.316172 -386.729986)
			(xy 156.323146 -386.723641) (xy 156.332402 -386.707235) (xy 156.334206 -386.697982) (xy 156.338524 -386.666994)
			(xy 156.339432 -386.657757) (xy 156.335405 -386.639657) (xy 156.33065 -386.631688) (xy 156.314338 -386.605845)
			(xy 156.290437 -386.549608) (xy 156.283152 -386.519928) (xy 156.281079 -386.51177) (xy 156.272387 -386.497368)
			(xy 156.266134 -386.491734) (xy 156.24302 -386.472684) (xy 156.236129 -386.467454) (xy 156.219907 -386.461479)
			(xy 156.21127 -386.461) (xy 156.181634 -386.459983) (xy 156.122969 -386.451335) (xy 156.065912 -386.435185)
			(xy 156.011418 -386.411804) (xy 155.960399 -386.381582) (xy 155.913709 -386.345025) (xy 155.87213 -386.302746)
			(xy 155.836357 -386.255453) (xy 155.806991 -386.203937) (xy 155.784521 -386.14906) (xy 155.769325 -386.091742)
			(xy 155.761657 -386.032941) (xy 155.761182 -386.003292) (xy 155.761702 -385.972229) (xy 155.770119 -385.910675)
			(xy 155.777946 -385.88061) (xy 155.78074 -385.87045) (xy 155.7782 -385.850638) (xy 155.730702 -385.768342)
			(xy 155.7147 -385.75615) (xy 155.70454 -385.75361) (xy 155.675453 -385.745573) (xy 155.619526 -385.722908)
			(xy 155.567061 -385.693093) (xy 155.518966 -385.656644) (xy 155.476076 -385.614195) (xy 155.439133 -385.566479)
			(xy 155.408777 -385.514324) (xy 155.385535 -385.458634) (xy 155.36981 -385.400374) (xy 155.361873 -385.340553)
			(xy 155.361386 -385.31038) (xy 155.361914 -385.279492) (xy 155.370219 -385.218277) (xy 155.386675 -385.158733)
			(xy 155.410984 -385.101941) (xy 155.42641 -385.075176) (xy 155.432252 -385.06527) (xy 155.434538 -385.042918)
			(xy 155.401264 -384.947668) (xy 155.385516 -384.931666) (xy 155.374848 -384.927602) (xy 155.351456 -384.918444)
			(xy 155.30756 -384.894019) (xy 155.267866 -384.863233) (xy 155.233286 -384.826796) (xy 155.204619 -384.785546)
			(xy 155.182523 -384.740433) (xy 155.167507 -384.692496) (xy 155.159918 -384.642839) (xy 155.159456 -384.617722)
			(xy 154.620722 -384.617722) (xy 154.620193 -384.644824) (xy 154.611383 -384.698307) (xy 154.603196 -384.724148)
			(xy 154.599386 -384.73507) (xy 154.601926 -384.757422) (xy 154.654504 -384.843274) (xy 154.673554 -384.85572)
			(xy 154.68473 -384.857498) (xy 154.714048 -384.862206) (xy 154.771219 -384.878254) (xy 154.825833 -384.901564)
			(xy 154.876972 -384.931743) (xy 154.923778 -384.968284) (xy 154.965463 -385.010573) (xy 155.001327 -385.0579)
			(xy 155.030767 -385.109468) (xy 155.053289 -385.164412) (xy 155.068513 -385.221807) (xy 155.076185 -385.28069)
			(xy 155.076652 -385.31038) (xy 155.076125 -385.341443) (xy 155.067713 -385.402996) (xy 155.059888 -385.433062)
			(xy 155.057094 -385.443222) (xy 155.059634 -385.463034) (xy 155.107132 -385.54533) (xy 155.123134 -385.557522)
			(xy 155.133294 -385.560062) (xy 155.162411 -385.568034) (xy 155.218377 -385.590673) (xy 155.270882 -385.620472)
			(xy 155.319014 -385.656913) (xy 155.361939 -385.699365) (xy 155.398912 -385.747091) (xy 155.429291 -385.799262)
			(xy 155.452549 -385.854974) (xy 155.468283 -385.913259) (xy 155.476219 -385.973106) (xy 155.476702 -386.003292)
			(xy 155.476577 -386.017427) (xy 155.474795 -386.045641) (xy 155.473146 -386.05968) (xy 155.472387 -386.068287)
			(xy 155.476026 -386.085167) (xy 155.480258 -386.0927) (xy 155.496006 -386.1181) (xy 155.500711 -386.125164)
			(xy 155.51382 -386.135931) (xy 155.52166 -386.139182) (xy 155.545048 -386.148349) (xy 155.588943 -386.172773)
			(xy 155.628637 -386.203558) (xy 155.663216 -386.239994) (xy 155.691884 -386.281243) (xy 155.713981 -386.326354)
			(xy 155.728998 -386.37429) (xy 155.736589 -386.423946) (xy 155.737052 -386.449062) (xy 155.736635 -386.473264)
			(xy 155.72956 -386.52115) (xy 155.715572 -386.567489) (xy 155.694969 -386.611291) (xy 155.681934 -386.631688)
			(xy 155.677144 -386.639643) (xy 155.673112 -386.657756) (xy 155.67406 -386.666994) (xy 155.678378 -386.697982)
			(xy 155.680067 -386.707276) (xy 155.689343 -386.723718) (xy 155.696412 -386.729986) (xy 155.718489 -386.748681)
			(xy 155.758263 -386.790689) (xy 155.792428 -386.837374) (xy 155.820437 -386.887992) (xy 155.841846 -386.941735)
			(xy 155.856313 -386.997748) (xy 155.863607 -387.055137) (xy 155.864052 -387.084062) (xy 155.863461 -387.117383)
			(xy 155.853799 -387.183322) (xy 155.834673 -387.247161) (xy 155.821126 -387.27761) (xy 155.816862 -387.288071)
			(xy 155.816976 -387.310635) (xy 155.82672 -387.330988) (xy 155.835096 -387.33857) (xy 155.857325 -387.357264)
			(xy 155.89739 -387.399316) (xy 155.931812 -387.446098) (xy 155.960039 -387.49686) (xy 155.981618 -387.550785)
			(xy 155.9962 -387.607006) (xy 156.003553 -387.664621) (xy 156.004006 -387.693662) (xy 156.003546 -387.722668)
			(xy 155.996234 -387.780216) (xy 155.981711 -387.83638) (xy 155.960208 -387.890259) (xy 155.932071 -387.940989)
			(xy 155.89775 -387.987758) (xy 155.857795 -388.029817) (xy 155.835604 -388.0485) (xy 155.828492 -388.054088)
			(xy 155.819348 -388.069328) (xy 155.804108 -388.152132) (xy 155.806902 -388.169404) (xy 155.811474 -388.177532)
			(xy 155.824044 -388.200721) (xy 155.841921 -388.250341) (xy 155.851024 -388.302292) (xy 155.851606 -388.328662)
			(xy 155.851537 -388.338021) (xy 155.850394 -388.356703) (xy 155.84932 -388.366) (xy 155.848304 -388.37489)
			(xy 155.852114 -388.391654) (xy 155.896056 -388.461504) (xy 155.909772 -388.471918) (xy 155.918154 -388.474712)
			(xy 155.942242 -388.483217) (xy 155.987535 -388.506836) (xy 156.028431 -388.537441) (xy 156.063865 -388.574234)
			(xy 156.092909 -388.616253) (xy 156.114807 -388.662402) (xy 156.12237 -388.686802) (xy 156.123894 -388.692644)
			(xy 156.44368 -389.245602) (xy 156.447744 -389.24992) (xy 156.463943 -389.267632) (xy 156.491366 -389.307023)
			(xy 156.512509 -389.350111) (xy 156.526884 -389.395904) (xy 156.53416 -389.443346) (xy 156.534612 -389.467344)
			(xy 156.534147 -389.492147) (xy 156.526377 -389.541142) (xy 156.511036 -389.588317) (xy 156.488502 -389.63251)
			(xy 156.45933 -389.672632) (xy 156.424239 -389.707695) (xy 156.384093 -389.736835) (xy 156.339882 -389.759334)
			(xy 156.292694 -389.774637) (xy 156.243694 -389.782367) (xy 156.21889 -389.782812) (xy 156.193495 -389.78232)
			(xy 156.143361 -389.774188) (xy 156.095176 -389.758135) (xy 156.050181 -389.734576) (xy 156.009539 -389.704117)
			(xy 155.974296 -389.667545) (xy 155.945363 -389.625803) (xy 155.923485 -389.579967) (xy 155.915868 -389.555736)
			(xy 155.914344 -389.549894) (xy 155.593796 -388.995412) (xy 155.589732 -388.991094) (xy 155.573625 -388.973427)
			(xy 155.546378 -388.934147) (xy 155.525368 -388.891206) (xy 155.511077 -388.845587) (xy 155.50383 -388.798334)
			(xy 155.503372 -388.774432) (xy 155.503514 -388.76238) (xy 155.50542 -388.73835) (xy 155.507182 -388.726426)
			(xy 155.508452 -388.717536) (xy 155.505404 -388.700518) (xy 155.46324 -388.629652) (xy 155.450032 -388.618476)
			(xy 155.44165 -388.615428) (xy 155.419898 -388.607044) (xy 155.37904 -388.5846) (xy 155.34207 -388.556205)
			(xy 155.309848 -388.522518) (xy 155.283124 -388.484322) (xy 155.262518 -388.442507) (xy 155.248511 -388.398045)
			(xy 155.241428 -388.35197) (xy 155.24099 -388.328662) (xy 155.241557 -388.302289) (xy 155.25064 -388.250331)
			(xy 155.268528 -388.20071) (xy 155.281122 -388.177532) (xy 155.285694 -388.169404) (xy 155.288488 -388.152132)
			(xy 155.273248 -388.069328) (xy 155.264104 -388.054088) (xy 155.256992 -388.0485) (xy 155.23482 -388.029796)
			(xy 155.194873 -387.987734) (xy 155.160556 -387.940966) (xy 155.132417 -387.890239) (xy 155.110908 -387.836366)
			(xy 155.096371 -387.780209) (xy 155.089041 -387.722666) (xy 155.08859 -387.693662) (xy 155.089185 -387.660341)
			(xy 155.098845 -387.594402) (xy 155.117969 -387.530563) (xy 155.131516 -387.500114) (xy 155.135743 -387.489642)
			(xy 155.135638 -387.467088) (xy 155.125912 -387.446739) (xy 155.117546 -387.439154) (xy 155.095289 -387.420492)
			(xy 155.055224 -387.378436) (xy 155.020803 -387.331648) (xy 154.992579 -387.280881) (xy 154.971005 -387.22695)
			(xy 154.956429 -387.170724) (xy 154.949084 -387.113105) (xy 154.948636 -387.084062) (xy 154.949093 -387.055136)
			(xy 154.956377 -386.997744) (xy 154.970835 -386.941728) (xy 154.992238 -386.88798) (xy 155.020244 -386.837359)
			(xy 155.054407 -386.790671) (xy 155.094181 -386.74866) (xy 155.116276 -386.729986) (xy 155.12325 -386.723641)
			(xy 155.132506 -386.707235) (xy 155.13431 -386.697982) (xy 155.138628 -386.666994) (xy 155.139535 -386.657757)
			(xy 155.135509 -386.639657) (xy 155.130754 -386.631688) (xy 155.114442 -386.605845) (xy 155.090541 -386.549608)
			(xy 155.083256 -386.519928) (xy 155.081182 -386.511771) (xy 155.072491 -386.497368) (xy 155.066238 -386.491734)
			(xy 155.043124 -386.472684) (xy 155.036232 -386.467455) (xy 155.020011 -386.461479) (xy 155.011374 -386.461)
			(xy 154.981738 -386.45998) (xy 154.923073 -386.451332) (xy 154.866016 -386.435183) (xy 154.811522 -386.411801)
			(xy 154.760503 -386.38158) (xy 154.713813 -386.345024) (xy 154.672234 -386.302745) (xy 154.636461 -386.255452)
			(xy 154.607095 -386.203936) (xy 154.584625 -386.14906) (xy 154.569429 -386.091742) (xy 154.561761 -386.032941)
			(xy 154.561286 -386.003292) (xy 154.561806 -385.972229) (xy 154.570222 -385.910675) (xy 154.57805 -385.88061)
			(xy 154.580844 -385.87045) (xy 154.578304 -385.850638) (xy 154.530806 -385.768342) (xy 154.514804 -385.75615)
			(xy 154.504644 -385.75361) (xy 154.475526 -385.745639) (xy 154.419558 -385.723002) (xy 154.367052 -385.693205)
			(xy 154.318918 -385.656764) (xy 154.275992 -385.614312) (xy 154.239018 -385.566586) (xy 154.20864 -385.514414)
			(xy 154.185383 -385.458701) (xy 154.169651 -385.400415) (xy 154.161717 -385.340566) (xy 154.161236 -385.31038)
			(xy 154.161757 -385.279492) (xy 154.170062 -385.218276) (xy 154.186521 -385.158732) (xy 154.210832 -385.10194)
			(xy 154.22626 -385.075176) (xy 154.232102 -385.06527) (xy 154.234388 -385.042918) (xy 154.201114 -384.947668)
			(xy 154.185366 -384.931666) (xy 154.174698 -384.927602) (xy 154.151317 -384.918417) (xy 154.10742 -384.893998)
			(xy 154.067723 -384.863218) (xy 154.033142 -384.826785) (xy 154.004472 -384.785538) (xy 153.982374 -384.740428)
			(xy 153.967358 -384.692493) (xy 153.959768 -384.642838) (xy 153.959306 -384.617722) (xy 153.420826 -384.617722)
			(xy 153.420297 -384.644824) (xy 153.411487 -384.698307) (xy 153.4033 -384.724148) (xy 153.39949 -384.73507)
			(xy 153.40203 -384.757422) (xy 153.454608 -384.843274) (xy 153.473658 -384.85572) (xy 153.484834 -384.857498)
			(xy 153.514153 -384.862203) (xy 153.571323 -384.878252) (xy 153.625937 -384.901562) (xy 153.677077 -384.931741)
			(xy 153.723882 -384.968283) (xy 153.765567 -385.010572) (xy 153.801431 -385.057899) (xy 153.830871 -385.109467)
			(xy 153.853393 -385.164411) (xy 153.868617 -385.221807) (xy 153.876289 -385.28069) (xy 153.876756 -385.31038)
			(xy 153.876229 -385.341443) (xy 153.867818 -385.402997) (xy 153.859992 -385.433062) (xy 153.857198 -385.443222)
			(xy 153.859738 -385.463034) (xy 153.907236 -385.54533) (xy 153.923238 -385.557522) (xy 153.933398 -385.560062)
			(xy 153.962516 -385.568031) (xy 154.018482 -385.590671) (xy 154.070987 -385.62047) (xy 154.119119 -385.656912)
			(xy 154.162044 -385.699364) (xy 154.199016 -385.74709) (xy 154.229395 -385.799261) (xy 154.252653 -385.854973)
			(xy 154.268387 -385.913259) (xy 154.276323 -385.973106) (xy 154.276806 -386.003292) (xy 154.276681 -386.017427)
			(xy 154.274899 -386.045641) (xy 154.27325 -386.05968) (xy 154.27249 -386.068287) (xy 154.27613 -386.085167)
			(xy 154.280362 -386.0927) (xy 154.29611 -386.1181) (xy 154.300833 -386.125152) (xy 154.313923 -386.135937)
			(xy 154.321764 -386.139182) (xy 154.34512 -386.148392) (xy 154.388962 -386.172851) (xy 154.428605 -386.203654)
			(xy 154.463138 -386.240094) (xy 154.491768 -386.281333) (xy 154.513838 -386.326425) (xy 154.528842 -386.374334)
			(xy 154.536433 -386.42396) (xy 154.536902 -386.449062) (xy 154.536476 -386.473264) (xy 154.529403 -386.521149)
			(xy 154.515417 -386.567488) (xy 154.494817 -386.61129) (xy 154.481784 -386.631688) (xy 154.476997 -386.639645)
			(xy 154.472962 -386.657756) (xy 154.47391 -386.666994) (xy 154.478228 -386.697982) (xy 154.479901 -386.70728)
			(xy 154.489188 -386.723722) (xy 154.496262 -386.729986) (xy 154.51835 -386.748668) (xy 154.558122 -386.79068)
			(xy 154.592284 -386.837368) (xy 154.620291 -386.887988) (xy 154.641699 -386.941733) (xy 154.656164 -386.997746)
			(xy 154.663457 -387.055136) (xy 154.663902 -387.084062) (xy 154.663316 -387.117384) (xy 154.653652 -387.183322)
			(xy 154.634525 -387.247161) (xy 154.620976 -387.27761) (xy 154.616729 -387.288075) (xy 154.616843 -387.310634)
			(xy 154.626576 -387.330985) (xy 154.634946 -387.33857) (xy 154.657165 -387.357276) (xy 154.697232 -387.399324)
			(xy 154.731657 -387.446104) (xy 154.759886 -387.496864) (xy 154.781466 -387.550787) (xy 154.79605 -387.607008)
			(xy 154.803403 -387.664621) (xy 154.803856 -387.693662) (xy 154.803378 -387.722667) (xy 154.796067 -387.780214)
			(xy 154.781545 -387.836376) (xy 154.760045 -387.890255) (xy 154.731911 -387.940985) (xy 154.697594 -387.987755)
			(xy 154.657643 -388.029815) (xy 154.635454 -388.0485) (xy 154.628342 -388.054088) (xy 154.619198 -388.069328)
			(xy 154.603958 -388.152132) (xy 154.606752 -388.169404) (xy 154.611324 -388.177532) (xy 154.623898 -388.200719)
			(xy 154.641773 -388.25034) (xy 154.650874 -388.302291) (xy 154.651456 -388.328662) (xy 154.651387 -388.338021)
			(xy 154.650244 -388.356703) (xy 154.64917 -388.366) (xy 154.648154 -388.37489) (xy 154.651964 -388.391654)
			(xy 154.695906 -388.461504) (xy 154.709622 -388.471918) (xy 154.718004 -388.474712) (xy 154.742025 -388.483199)
			(xy 154.787198 -388.506747) (xy 154.828005 -388.537242) (xy 154.863385 -388.573893) (xy 154.892422 -388.61575)
			(xy 154.914362 -388.661725) (xy 154.921966 -388.68604) (xy 154.92349 -388.691882) (xy 155.243784 -389.245602)
			(xy 155.247848 -389.24992) (xy 155.264048 -389.267631) (xy 155.291471 -389.307022) (xy 155.312613 -389.350111)
			(xy 155.326988 -389.395904) (xy 155.334264 -389.443346) (xy 155.334716 -389.467344) (xy 155.334247 -389.492147)
			(xy 155.326477 -389.541141) (xy 155.311137 -389.588316) (xy 155.288603 -389.632509) (xy 155.259431 -389.672631)
			(xy 155.22434 -389.707694) (xy 155.184195 -389.736834) (xy 155.139984 -389.759332) (xy 155.092798 -389.774636)
			(xy 155.043797 -389.782366) (xy 155.018994 -389.782812) (xy 154.993599 -389.782317) (xy 154.943466 -389.774185)
			(xy 154.89528 -389.758133) (xy 154.850286 -389.734574) (xy 154.809643 -389.704116) (xy 154.7744 -389.667544)
			(xy 154.745467 -389.625802) (xy 154.723589 -389.579967) (xy 154.715972 -389.555736) (xy 154.714448 -389.549894)
			(xy 154.394154 -388.996174) (xy 154.39009 -388.991856) (xy 154.373937 -388.974117) (xy 154.346566 -388.934717)
			(xy 154.325474 -388.891628) (xy 154.311145 -388.845844) (xy 154.30391 -388.798419) (xy 154.303476 -388.774432)
			(xy 154.303556 -388.762384) (xy 154.305339 -388.738355) (xy 154.307032 -388.726426) (xy 154.308302 -388.717536)
			(xy 154.305254 -388.700518) (xy 154.26309 -388.629652) (xy 154.249882 -388.618476) (xy 154.2415 -388.615428)
			(xy 154.219759 -388.607016) (xy 154.178899 -388.584579) (xy 154.141928 -388.556189) (xy 154.109704 -388.522506)
			(xy 154.082977 -388.484315) (xy 154.06237 -388.442502) (xy 154.048362 -388.398042) (xy 154.041278 -388.351969)
			(xy 154.04084 -388.328662) (xy 154.041401 -388.302289) (xy 154.050485 -388.25033) (xy 154.068376 -388.20071)
			(xy 154.080972 -388.177532) (xy 154.085544 -388.169404) (xy 154.088338 -388.152132) (xy 154.073098 -388.069328)
			(xy 154.063954 -388.054088) (xy 154.056842 -388.0485) (xy 154.03468 -388.029784) (xy 153.994731 -387.987725)
			(xy 153.960411 -387.94096) (xy 153.932271 -387.890235) (xy 153.91076 -387.836364) (xy 153.896222 -387.780208)
			(xy 153.888891 -387.722666) (xy 153.88844 -387.693662) (xy 153.88904 -387.660341) (xy 153.898699 -387.594403)
			(xy 153.917821 -387.530563) (xy 153.931366 -387.500114) (xy 153.93561 -387.489646) (xy 153.935505 -387.467087)
			(xy 153.925769 -387.446736) (xy 153.917396 -387.439154) (xy 153.895128 -387.420504) (xy 153.855066 -387.378444)
			(xy 153.820648 -387.331654) (xy 153.792426 -387.280885) (xy 153.770853 -387.226953) (xy 153.756278 -387.170725)
			(xy 153.748934 -387.113105) (xy 153.748486 -387.084062) (xy 153.748925 -387.055135) (xy 153.756209 -386.997742)
			(xy 153.770669 -386.941724) (xy 153.792075 -386.887976) (xy 153.820084 -386.837355) (xy 153.85425 -386.790667)
			(xy 153.894029 -386.748659) (xy 153.916126 -386.729986) (xy 153.923092 -386.723633) (xy 153.932354 -386.707234)
			(xy 153.93416 -386.697982) (xy 153.938478 -386.666994) (xy 153.939377 -386.657757) (xy 153.935355 -386.639658)
			(xy 153.930604 -386.631688) (xy 153.914296 -386.605842) (xy 153.890392 -386.549607) (xy 153.883106 -386.519928)
			(xy 153.881045 -386.511766) (xy 153.872345 -386.497365) (xy 153.866088 -386.491734) (xy 153.842974 -386.472684)
			(xy 153.836154 -386.467463) (xy 153.820054 -386.461502) (xy 153.811478 -386.461) (xy 153.781842 -386.459976)
			(xy 153.723178 -386.451329) (xy 153.666121 -386.43518) (xy 153.611627 -386.411799) (xy 153.560607 -386.381578)
			(xy 153.513917 -386.345022) (xy 153.472338 -386.302744) (xy 153.436566 -386.255451) (xy 153.407199 -386.203936)
			(xy 153.384729 -386.149059) (xy 153.369533 -386.091741) (xy 153.361865 -386.032941) (xy 153.36139 -386.003292)
			(xy 153.36191 -385.972229) (xy 153.370326 -385.910675) (xy 153.378154 -385.88061) (xy 153.380948 -385.87045)
			(xy 153.378408 -385.850638) (xy 153.33091 -385.768342) (xy 153.314908 -385.75615) (xy 153.304748 -385.75361)
			(xy 153.275631 -385.745636) (xy 153.219663 -385.723) (xy 153.167156 -385.693203) (xy 153.119022 -385.656763)
			(xy 153.076096 -385.614311) (xy 153.039123 -385.566585) (xy 153.008744 -385.514414) (xy 152.985487 -385.458701)
			(xy 152.969755 -385.400415) (xy 152.961821 -385.340566) (xy 152.96134 -385.31038) (xy 152.96186 -385.279492)
			(xy 152.970166 -385.218276) (xy 152.986624 -385.158732) (xy 153.010936 -385.10194) (xy 153.026364 -385.075176)
			(xy 153.032206 -385.06527) (xy 153.034492 -385.042918) (xy 153.001218 -384.947668) (xy 152.98547 -384.931666)
			(xy 152.974802 -384.927602) (xy 152.951422 -384.918415) (xy 152.907525 -384.893997) (xy 152.867828 -384.863217)
			(xy 152.833246 -384.826784) (xy 152.804576 -384.785538) (xy 152.782479 -384.740428) (xy 152.767462 -384.692493)
			(xy 152.759872 -384.642838) (xy 152.75941 -384.617722) (xy 152.22093 -384.617722) (xy 152.220401 -384.644824)
			(xy 152.211591 -384.698307) (xy 152.203404 -384.724148) (xy 152.199594 -384.73507) (xy 152.202134 -384.757422)
			(xy 152.254712 -384.843528) (xy 152.273508 -384.85572) (xy 152.284938 -384.857498) (xy 152.314226 -384.86231)
			(xy 152.37136 -384.878382) (xy 152.425937 -384.901707) (xy 152.47704 -384.931892) (xy 152.523811 -384.968431)
			(xy 152.565466 -385.01071) (xy 152.601305 -385.05802) (xy 152.630726 -385.109566) (xy 152.653236 -385.164484)
			(xy 152.668457 -385.221851) (xy 152.676133 -385.280704) (xy 152.676606 -385.31038) (xy 152.676081 -385.341443)
			(xy 152.667668 -385.402997) (xy 152.659842 -385.433062) (xy 152.657048 -385.443222) (xy 152.659588 -385.463034)
			(xy 152.707086 -385.54533) (xy 152.723088 -385.557522) (xy 152.733248 -385.560062) (xy 152.762357 -385.568064)
			(xy 152.818323 -385.590698) (xy 152.870829 -385.620492) (xy 152.918962 -385.656929) (xy 152.961889 -385.699377)
			(xy 152.998863 -385.7471) (xy 153.029243 -385.799269) (xy 153.052502 -385.854978) (xy 153.068236 -385.913261)
			(xy 153.076173 -385.973107) (xy 153.076656 -386.003292) (xy 153.076531 -386.017427) (xy 153.074749 -386.045641)
			(xy 153.0731 -386.05968) (xy 153.072333 -386.068287) (xy 153.075976 -386.085168) (xy 153.080212 -386.0927)
			(xy 153.09596 -386.1181) (xy 153.100679 -386.125153) (xy 153.113778 -386.135926) (xy 153.121614 -386.139182)
			(xy 153.144992 -386.148374) (xy 153.188888 -386.172792) (xy 153.228584 -386.203572) (xy 153.263165 -386.240005)
			(xy 153.291835 -386.28125) (xy 153.313933 -386.326359) (xy 153.328951 -386.374292) (xy 153.336543 -386.423946)
			(xy 153.337006 -386.449062) (xy 153.33658 -386.473264) (xy 153.329506 -386.521149) (xy 153.31552 -386.567488)
			(xy 153.294921 -386.61129) (xy 153.281888 -386.631688) (xy 153.277101 -386.639645) (xy 153.273066 -386.657756)
			(xy 153.274014 -386.666994) (xy 153.278332 -386.697982) (xy 153.280004 -386.707281) (xy 153.289291 -386.723722)
			(xy 153.296366 -386.729986) (xy 153.318455 -386.748667) (xy 153.358226 -386.790679) (xy 153.392388 -386.837367)
			(xy 153.420396 -386.887987) (xy 153.441803 -386.941732) (xy 153.456268 -386.997746) (xy 153.463561 -387.055136)
			(xy 153.464006 -387.084062) (xy 153.463419 -387.117384) (xy 153.453756 -387.183322) (xy 153.434629 -387.247161)
			(xy 153.42108 -387.27761) (xy 153.416831 -387.288075) (xy 153.416945 -387.310634) (xy 153.42668 -387.330985)
			(xy 153.43505 -387.33857) (xy 153.45727 -387.357275) (xy 153.497337 -387.399324) (xy 153.531761 -387.446104)
			(xy 153.55999 -387.496864) (xy 153.58157 -387.550787) (xy 153.596154 -387.607008) (xy 153.603507 -387.664621)
			(xy 153.60396 -387.693662) (xy 153.60348 -387.722667) (xy 153.59617 -387.780214) (xy 153.581648 -387.836376)
			(xy 153.560148 -387.890254) (xy 153.532014 -387.940985) (xy 153.497697 -387.987755) (xy 153.457747 -388.029815)
			(xy 153.435558 -388.0485) (xy 153.428446 -388.054088) (xy 153.419302 -388.069328) (xy 153.404062 -388.152132)
			(xy 153.406856 -388.169404) (xy 153.411428 -388.177532) (xy 153.424002 -388.200719) (xy 153.441877 -388.25034)
			(xy 153.450978 -388.302291) (xy 153.45156 -388.328662) (xy 153.451491 -388.338021) (xy 153.450348 -388.356703)
			(xy 153.449274 -388.366) (xy 153.448258 -388.37489) (xy 153.452068 -388.391654) (xy 153.49601 -388.461504)
			(xy 153.509726 -388.471918) (xy 153.518108 -388.474712) (xy 153.54213 -388.483197) (xy 153.587303 -388.506745)
			(xy 153.628109 -388.537241) (xy 153.66349 -388.573893) (xy 153.692527 -388.61575) (xy 153.714466 -388.661725)
			(xy 153.72207 -388.68604) (xy 153.723594 -388.691882) (xy 154.043888 -389.245602) (xy 154.047952 -389.24992)
			(xy 154.064152 -389.267631) (xy 154.091575 -389.307022) (xy 154.112718 -389.350111) (xy 154.127092 -389.395904)
			(xy 154.134368 -389.443346) (xy 154.13482 -389.467344) (xy 154.134446 -389.492152) (xy 154.126674 -389.541155)
			(xy 154.111328 -389.588338) (xy 154.088785 -389.632537) (xy 154.059603 -389.672664) (xy 154.0245 -389.707728)
			(xy 153.984342 -389.736866) (xy 153.940118 -389.75936) (xy 153.892918 -389.774655) (xy 153.843906 -389.782374)
			(xy 153.819098 -389.782812) (xy 153.793704 -389.782313) (xy 153.74357 -389.774182) (xy 153.695384 -389.758131)
			(xy 153.65039 -389.734572) (xy 153.609747 -389.704114) (xy 153.574504 -389.667543) (xy 153.545571 -389.625802)
			(xy 153.523693 -389.579967) (xy 153.516076 -389.555736) (xy 153.514552 -389.549894) (xy 153.194258 -388.996174)
			(xy 153.190194 -388.991856) (xy 153.174041 -388.974116) (xy 153.146671 -388.934716) (xy 153.125578 -388.891628)
			(xy 153.111249 -388.845844) (xy 153.104014 -388.798419) (xy 153.10358 -388.774432) (xy 153.10366 -388.762384)
			(xy 153.105443 -388.738355) (xy 153.107136 -388.726426) (xy 153.108406 -388.717536) (xy 153.105358 -388.700518)
			(xy 153.063194 -388.629652) (xy 153.049986 -388.618476) (xy 153.041604 -388.615428) (xy 153.019864 -388.607014)
			(xy 152.979004 -388.584578) (xy 152.942032 -388.556188) (xy 152.909808 -388.522505) (xy 152.883082 -388.484314)
			(xy 152.862474 -388.442502) (xy 152.848466 -388.398042) (xy 152.841382 -388.351969) (xy 152.840944 -388.328662)
			(xy 152.841504 -388.302289) (xy 152.850588 -388.25033) (xy 152.86848 -388.20071) (xy 152.881076 -388.177532)
			(xy 152.885648 -388.169404) (xy 152.888442 -388.152132) (xy 152.873202 -388.069328) (xy 152.864058 -388.054088)
			(xy 152.856946 -388.0485) (xy 152.834764 -388.029807) (xy 152.79482 -387.987742) (xy 152.760505 -387.940971)
			(xy 152.732368 -387.890243) (xy 152.71086 -387.836369) (xy 152.696325 -387.78021) (xy 152.688994 -387.722666)
			(xy 152.688544 -387.693662) (xy 152.689144 -387.660341) (xy 152.698802 -387.594403) (xy 152.717924 -387.530563)
			(xy 152.73147 -387.500114) (xy 152.735712 -387.489646) (xy 152.735608 -387.467087) (xy 152.725873 -387.446736)
			(xy 152.7175 -387.439154) (xy 152.695233 -387.420503) (xy 152.655171 -387.378444) (xy 152.620752 -387.331653)
			(xy 152.59253 -387.280884) (xy 152.570958 -387.226953) (xy 152.556382 -387.170725) (xy 152.549038 -387.113105)
			(xy 152.54859 -387.084062) (xy 152.549028 -387.055135) (xy 152.556312 -386.997742) (xy 152.570772 -386.941724)
			(xy 152.592178 -386.887976) (xy 152.620187 -386.837355) (xy 152.654354 -386.790667) (xy 152.694133 -386.748659)
			(xy 152.71623 -386.729986) (xy 152.723197 -386.723634) (xy 152.732458 -386.707234) (xy 152.734264 -386.697982)
			(xy 152.738582 -386.666994) (xy 152.739481 -386.657757) (xy 152.735459 -386.639658) (xy 152.730708 -386.631688)
			(xy 152.7144 -386.605842) (xy 152.690497 -386.549607) (xy 152.68321 -386.519928) (xy 152.681148 -386.511767)
			(xy 152.672449 -386.497365) (xy 152.666192 -386.491734) (xy 152.643078 -386.472684) (xy 152.636199 -386.467437)
			(xy 152.619968 -386.461472) (xy 152.611328 -386.461) (xy 152.58169 -386.460022) (xy 152.523024 -386.451369)
			(xy 152.465967 -386.435214) (xy 152.411472 -386.411827) (xy 152.360453 -386.381601) (xy 152.313764 -386.345041)
			(xy 152.272185 -386.302759) (xy 152.236413 -386.255463) (xy 152.207047 -386.203944) (xy 152.184578 -386.149065)
			(xy 152.169383 -386.091745) (xy 152.161715 -386.032942) (xy 152.16124 -386.003292) (xy 152.161761 -385.972229)
			(xy 152.170177 -385.910675) (xy 152.178004 -385.88061) (xy 152.180798 -385.87045) (xy 152.178258 -385.850638)
			(xy 152.13076 -385.768342) (xy 152.114758 -385.75615) (xy 152.104598 -385.75361) (xy 152.075471 -385.745669)
			(xy 152.019504 -385.723027) (xy 151.966999 -385.693225) (xy 151.918866 -385.65678) (xy 151.875941 -385.614324)
			(xy 151.838969 -385.566595) (xy 151.808592 -385.514421) (xy 151.785335 -385.458706) (xy 151.769604 -385.400417)
			(xy 151.761671 -385.340567) (xy 151.76119 -385.31038) (xy 151.761656 -385.279457) (xy 151.76994 -385.21817)
			(xy 151.786407 -385.158558) (xy 151.810757 -385.101709) (xy 151.826214 -385.074922) (xy 151.83231 -385.06527)
			(xy 151.834596 -385.042918) (xy 151.801068 -384.947668) (xy 151.78532 -384.931666) (xy 151.774652 -384.927602)
			(xy 151.751294 -384.918397) (xy 151.707451 -384.893938) (xy 151.667807 -384.863135) (xy 151.633274 -384.826695)
			(xy 151.604643 -384.785455) (xy 151.582573 -384.740362) (xy 151.567571 -384.692451) (xy 151.559982 -384.642824)
			(xy 151.559514 -384.617722) (xy 151.02078 -384.617722) (xy 151.020248 -384.644824) (xy 151.01144 -384.698307)
			(xy 151.003254 -384.724148) (xy 150.999444 -384.73507) (xy 151.001984 -384.757422) (xy 151.054562 -384.843274)
			(xy 151.073612 -384.85572) (xy 151.084788 -384.857498) (xy 151.1141 -384.862239) (xy 151.171271 -384.878282)
			(xy 151.225885 -384.901587) (xy 151.277025 -384.931762) (xy 151.323831 -384.968299) (xy 151.365518 -385.010585)
			(xy 151.401383 -385.057909) (xy 151.430824 -385.109475) (xy 151.453346 -385.164416) (xy 151.468571 -385.22181)
			(xy 151.476243 -385.280691) (xy 151.47671 -385.31038) (xy 151.476185 -385.341443) (xy 151.467772 -385.402997)
			(xy 151.459946 -385.433062) (xy 151.457152 -385.443222) (xy 151.459692 -385.463034) (xy 151.50719 -385.54533)
			(xy 151.523192 -385.557522) (xy 151.533352 -385.560062) (xy 151.562462 -385.568062) (xy 151.618428 -385.590696)
			(xy 151.670933 -385.62049) (xy 151.719067 -385.656928) (xy 151.761993 -385.699376) (xy 151.798967 -385.747099)
			(xy 151.829347 -385.799268) (xy 151.852606 -385.854978) (xy 151.86834 -385.913261) (xy 151.876277 -385.973107)
			(xy 151.87676 -386.003292) (xy 151.876635 -386.017427) (xy 151.874853 -386.045641) (xy 151.873204 -386.05968)
			(xy 151.872437 -386.068287) (xy 151.87608 -386.085168) (xy 151.880316 -386.0927) (xy 151.896064 -386.1181)
			(xy 151.90077 -386.125166) (xy 151.913871 -386.135943) (xy 151.921718 -386.139182) (xy 151.945064 -386.148416)
			(xy 151.988907 -386.17287) (xy 152.028552 -386.203668) (xy 152.063087 -386.240104) (xy 152.091719 -386.28134)
			(xy 152.113791 -386.32643) (xy 152.128795 -386.374337) (xy 152.136387 -386.423961) (xy 152.136856 -386.449062)
			(xy 152.136438 -386.473264) (xy 152.129364 -386.52115) (xy 152.115375 -386.567489) (xy 152.094773 -386.611291)
			(xy 152.081738 -386.631688) (xy 152.076948 -386.639643) (xy 152.072916 -386.657756) (xy 152.073864 -386.666994)
			(xy 152.078182 -386.697982) (xy 152.079869 -386.707277) (xy 152.089147 -386.723718) (xy 152.096216 -386.729986)
			(xy 152.118294 -386.74868) (xy 152.158068 -386.790688) (xy 152.192232 -386.837374) (xy 152.220242 -386.887991)
			(xy 152.24165 -386.941735) (xy 152.256117 -386.997748) (xy 152.263411 -387.055137) (xy 152.263856 -387.084062)
			(xy 152.263265 -387.117383) (xy 152.253603 -387.183322) (xy 152.234477 -387.247161) (xy 152.22093 -387.27761)
			(xy 152.216665 -387.28807) (xy 152.216779 -387.310635) (xy 152.226523 -387.330988) (xy 152.2349 -387.33857)
			(xy 152.25713 -387.357263) (xy 152.297194 -387.399315) (xy 152.331617 -387.446098) (xy 152.359844 -387.49686)
			(xy 152.381422 -387.550785) (xy 152.396004 -387.607006) (xy 152.403357 -387.664621) (xy 152.40381 -387.693662)
			(xy 152.403349 -387.722668) (xy 152.396037 -387.780216) (xy 152.381514 -387.836379) (xy 152.360011 -387.890258)
			(xy 152.331874 -387.940989) (xy 152.297553 -387.987758) (xy 152.257599 -388.029816) (xy 152.235408 -388.0485)
			(xy 152.228296 -388.054088) (xy 152.219152 -388.069328) (xy 152.203912 -388.152132) (xy 152.206706 -388.169404)
			(xy 152.211278 -388.177532) (xy 152.223848 -388.200721) (xy 152.241725 -388.250341) (xy 152.250828 -388.302292)
			(xy 152.25141 -388.328662) (xy 152.251341 -388.338021) (xy 152.250198 -388.356703) (xy 152.249124 -388.366)
			(xy 152.248108 -388.37489) (xy 152.251918 -388.391654) (xy 152.29586 -388.461504) (xy 152.309576 -388.471918)
			(xy 152.317958 -388.474712) (xy 152.34199 -388.48317) (xy 152.387162 -388.506725) (xy 152.427966 -388.537227)
			(xy 152.463345 -388.573884) (xy 152.492379 -388.615745) (xy 152.514317 -388.661724) (xy 152.52192 -388.68604)
			(xy 152.523444 -388.691882) (xy 152.843738 -389.245602) (xy 152.847802 -389.24992) (xy 152.86399 -389.267629)
			(xy 152.891356 -389.307037) (xy 152.912442 -389.350133) (xy 152.926762 -389.395924) (xy 152.933987 -389.443355)
			(xy 152.934416 -389.467344) (xy 152.933923 -389.492132) (xy 152.926162 -389.541098) (xy 152.910838 -389.588247)
			(xy 152.888328 -389.63242) (xy 152.859187 -389.672528) (xy 152.824131 -389.707584) (xy 152.784023 -389.736726)
			(xy 152.739851 -389.759236) (xy 152.692702 -389.774561) (xy 152.643736 -389.782322) (xy 152.618948 -389.782812)
			(xy 152.593555 -389.782269) (xy 152.543423 -389.774146) (xy 152.495239 -389.758102) (xy 152.450245 -389.73455)
			(xy 152.409601 -389.704098) (xy 152.374358 -389.667532) (xy 152.345423 -389.625796) (xy 152.323543 -389.579965)
			(xy 152.315926 -389.555736) (xy 152.314402 -389.549894) (xy 151.994108 -388.996174) (xy 151.990044 -388.991856)
			(xy 151.973831 -388.974156) (xy 151.946411 -388.934762) (xy 151.92527 -388.89167) (xy 151.910899 -388.845875)
			(xy 151.903626 -388.798431) (xy 151.903176 -388.774432) (xy 151.903318 -388.76238) (xy 151.905224 -388.73835)
			(xy 151.906986 -388.726426) (xy 151.908256 -388.717536) (xy 151.905208 -388.700518) (xy 151.863044 -388.629652)
			(xy 151.849836 -388.618476) (xy 151.841454 -388.615428) (xy 151.819703 -388.607042) (xy 151.778845 -388.584599)
			(xy 151.741875 -388.556203) (xy 151.709653 -388.522517) (xy 151.682928 -388.484322) (xy 151.662322 -388.442507)
			(xy 151.648315 -388.398045) (xy 151.641232 -388.35197) (xy 151.640794 -388.328662) (xy 151.64136 -388.302289)
			(xy 151.650443 -388.250331) (xy 151.668331 -388.20071) (xy 151.680926 -388.177532) (xy 151.685498 -388.169404)
			(xy 151.688292 -388.152132) (xy 151.673052 -388.069328) (xy 151.663908 -388.054088) (xy 151.656796 -388.0485)
			(xy 151.634625 -388.029795) (xy 151.594678 -387.987733) (xy 151.56036 -387.940965) (xy 151.532222 -387.890239)
			(xy 151.510712 -387.836366) (xy 151.496175 -387.780209) (xy 151.488845 -387.722666) (xy 151.488394 -387.693662)
			(xy 151.488989 -387.660341) (xy 151.498649 -387.594402) (xy 151.517773 -387.530563) (xy 151.53132 -387.500114)
			(xy 151.535546 -387.489642) (xy 151.535441 -387.467088) (xy 151.525716 -387.446739) (xy 151.51735 -387.439154)
			(xy 151.495093 -387.420491) (xy 151.455029 -387.378435) (xy 151.420608 -387.331647) (xy 151.392383 -387.28088)
			(xy 151.370809 -387.22695) (xy 151.356233 -387.170724) (xy 151.348888 -387.113105) (xy 151.34844 -387.084062)
			(xy 151.348896 -387.055136) (xy 151.356179 -386.997744) (xy 151.370638 -386.941727) (xy 151.392041 -386.88798)
			(xy 151.420047 -386.837358) (xy 151.45421 -386.79067) (xy 151.493985 -386.74866) (xy 151.51608 -386.729986)
			(xy 151.523055 -386.723642) (xy 151.532311 -386.707236) (xy 151.534114 -386.697982) (xy 151.538432 -386.666994)
			(xy 151.539338 -386.657757) (xy 151.535313 -386.639657) (xy 151.530558 -386.631688) (xy 151.514246 -386.605845)
			(xy 151.490345 -386.549607) (xy 151.48306 -386.519928) (xy 151.481012 -386.511762) (xy 151.472304 -386.497362)
			(xy 151.466042 -386.491734) (xy 151.442928 -386.472684) (xy 151.436094 -386.467484) (xy 151.420004 -386.46151)
			(xy 151.411432 -386.461) (xy 151.381794 -386.460018) (xy 151.323129 -386.451365) (xy 151.266071 -386.435211)
			(xy 151.211577 -386.411825) (xy 151.160558 -386.381599) (xy 151.113868 -386.34504) (xy 151.072289 -386.302758)
			(xy 151.036518 -386.255462) (xy 151.007151 -386.203944) (xy 150.984683 -386.149065) (xy 150.969487 -386.091745)
			(xy 150.961819 -386.032942) (xy 150.961344 -386.003292) (xy 150.961865 -385.972229) (xy 150.970281 -385.910675)
			(xy 150.978108 -385.88061) (xy 150.980902 -385.87045) (xy 150.978362 -385.850638) (xy 150.930864 -385.768342)
			(xy 150.914862 -385.75615) (xy 150.904702 -385.75361) (xy 150.875576 -385.745666) (xy 150.819609 -385.723025)
			(xy 150.767103 -385.693223) (xy 150.71897 -385.656778) (xy 150.676045 -385.614323) (xy 150.639073 -385.566594)
			(xy 150.608696 -385.51442) (xy 150.58544 -385.458705) (xy 150.569708 -385.400417) (xy 150.561775 -385.340567)
			(xy 150.561294 -385.31038) (xy 150.561821 -385.279492) (xy 150.570126 -385.218277) (xy 150.586582 -385.158733)
			(xy 150.610892 -385.101941) (xy 150.626318 -385.075176) (xy 150.63216 -385.06527) (xy 150.634446 -385.042918)
			(xy 150.601172 -384.947668) (xy 150.585424 -384.931666) (xy 150.574756 -384.927602) (xy 150.551366 -384.91844)
			(xy 150.50747 -384.894016) (xy 150.467775 -384.863231) (xy 150.433195 -384.826794) (xy 150.404527 -384.785545)
			(xy 150.382431 -384.740432) (xy 150.367415 -384.692496) (xy 150.359826 -384.642839) (xy 150.359364 -384.617722)
			(xy 149.820884 -384.617722) (xy 149.820352 -384.644824) (xy 149.811544 -384.698307) (xy 149.803358 -384.724148)
			(xy 149.799548 -384.73507) (xy 149.802088 -384.757422) (xy 149.854666 -384.843274) (xy 149.873716 -384.85572)
			(xy 149.884892 -384.857498) (xy 149.914205 -384.862236) (xy 149.971375 -384.87828) (xy 150.025989 -384.901585)
			(xy 150.077129 -384.93176) (xy 150.123936 -384.968298) (xy 150.165622 -385.010584) (xy 150.201487 -385.057908)
			(xy 150.230928 -385.109474) (xy 150.25345 -385.164416) (xy 150.268675 -385.221809) (xy 150.276347 -385.280691)
			(xy 150.276814 -385.31038) (xy 150.276292 -385.341506) (xy 150.267886 -385.403188) (xy 150.26005 -385.433316)
			(xy 150.257256 -385.443476) (xy 150.259796 -385.463542) (xy 150.30704 -385.54533) (xy 150.323042 -385.557522)
			(xy 150.333202 -385.560062) (xy 150.362321 -385.568029) (xy 150.418287 -385.590669) (xy 150.470791 -385.620468)
			(xy 150.518923 -385.656911) (xy 150.561848 -385.699363) (xy 150.598821 -385.747089) (xy 150.629199 -385.799261)
			(xy 150.652457 -385.854973) (xy 150.668191 -385.913258) (xy 150.676127 -385.973106) (xy 150.67661 -386.003292)
			(xy 150.676485 -386.017427) (xy 150.674703 -386.045641) (xy 150.673054 -386.05968) (xy 150.672294 -386.068287)
			(xy 150.675933 -386.085167) (xy 150.680166 -386.0927) (xy 150.695914 -386.1181) (xy 150.700616 -386.125166)
			(xy 150.713727 -386.135932) (xy 150.721568 -386.139182) (xy 150.744958 -386.148345) (xy 150.788852 -386.17277)
			(xy 150.828546 -386.203556) (xy 150.863125 -386.239993) (xy 150.891793 -386.281242) (xy 150.913889 -386.326354)
			(xy 150.928906 -386.374289) (xy 150.936497 -386.423945) (xy 150.93696 -386.449062) (xy 150.936541 -386.473264)
			(xy 150.929467 -386.52115) (xy 150.915479 -386.567489) (xy 150.894877 -386.611291) (xy 150.881842 -386.631688)
			(xy 150.877052 -386.639644) (xy 150.87302 -386.657756) (xy 150.873968 -386.666994) (xy 150.878286 -386.697982)
			(xy 150.879972 -386.707277) (xy 150.889251 -386.723719) (xy 150.89632 -386.729986) (xy 150.918399 -386.748679)
			(xy 150.958173 -386.790688) (xy 150.992337 -386.837373) (xy 151.020346 -386.887991) (xy 151.041755 -386.941735)
			(xy 151.056221 -386.997748) (xy 151.063515 -387.055137) (xy 151.06396 -387.084062) (xy 151.063368 -387.117383)
			(xy 151.053706 -387.183322) (xy 151.034581 -387.247161) (xy 151.021034 -387.27761) (xy 151.016768 -387.28807)
			(xy 151.016881 -387.310636) (xy 151.026626 -387.330989) (xy 151.035004 -387.33857) (xy 151.057235 -387.357262)
			(xy 151.097299 -387.399314) (xy 151.131721 -387.446097) (xy 151.159948 -387.496859) (xy 151.181526 -387.550784)
			(xy 151.196109 -387.607006) (xy 151.203461 -387.664621) (xy 151.203914 -387.693662) (xy 151.203451 -387.722668)
			(xy 151.19614 -387.780216) (xy 151.181616 -387.836379) (xy 151.160114 -387.890258) (xy 151.131977 -387.940988)
			(xy 151.097657 -387.987758) (xy 151.057703 -388.029816) (xy 151.035512 -388.0485) (xy 151.0284 -388.054088)
			(xy 151.019256 -388.069328) (xy 151.004016 -388.152132) (xy 151.00681 -388.169404) (xy 151.011382 -388.177532)
			(xy 151.023952 -388.200721) (xy 151.041829 -388.250341) (xy 151.050932 -388.302292) (xy 151.051514 -388.328662)
			(xy 151.051445 -388.338021) (xy 151.050302 -388.356703) (xy 151.049228 -388.366) (xy 151.048212 -388.37489)
			(xy 151.052022 -388.391654) (xy 151.095964 -388.461504) (xy 151.10968 -388.471918) (xy 151.118062 -388.474712)
			(xy 151.142095 -388.483168) (xy 151.187266 -388.506724) (xy 151.228071 -388.537226) (xy 151.263449 -388.573883)
			(xy 151.292484 -388.615744) (xy 151.314421 -388.661724) (xy 151.322024 -388.68604) (xy 151.323548 -388.691882)
			(xy 151.643842 -389.245602) (xy 151.647906 -389.24992) (xy 151.664095 -389.267628) (xy 151.69146 -389.307037)
			(xy 151.712546 -389.350133) (xy 151.726867 -389.395924) (xy 151.734091 -389.443355) (xy 151.73452 -389.467344)
			(xy 151.734147 -389.492139) (xy 151.726383 -389.541118) (xy 151.711052 -389.588279) (xy 151.688532 -389.632461)
			(xy 151.659377 -389.672577) (xy 151.624307 -389.707637) (xy 151.584183 -389.73678) (xy 151.539994 -389.759287)
			(xy 151.492828 -389.774604) (xy 151.443847 -389.782355) (xy 151.419052 -389.782812) (xy 151.393656 -389.782354)
			(xy 151.343521 -389.774216) (xy 151.295334 -389.758157) (xy 151.25034 -389.734593) (xy 151.209697 -389.704129)
			(xy 151.174456 -389.667553) (xy 151.145523 -389.625807) (xy 151.123646 -389.579968) (xy 151.11603 -389.555736)
			(xy 151.114506 -389.549894) (xy 150.794212 -388.996174) (xy 150.790148 -388.991856) (xy 150.773936 -388.974155)
			(xy 150.746515 -388.934761) (xy 150.725375 -388.89167) (xy 150.711003 -388.845874) (xy 150.70373 -388.798431)
			(xy 150.70328 -388.774432) (xy 150.703422 -388.76238) (xy 150.705328 -388.73835) (xy 150.70709 -388.726426)
			(xy 150.70836 -388.717536) (xy 150.705312 -388.700518) (xy 150.663148 -388.629652) (xy 150.64994 -388.618476)
			(xy 150.641558 -388.615428) (xy 150.619808 -388.607039) (xy 150.578949 -388.584597) (xy 150.541979 -388.556202)
			(xy 150.509757 -388.522516) (xy 150.483032 -388.484321) (xy 150.462427 -388.442507) (xy 150.448419 -388.398045)
			(xy 150.441336 -388.35197) (xy 150.440898 -388.328662) (xy 150.441464 -388.302289) (xy 150.450547 -388.250331)
			(xy 150.468435 -388.20071) (xy 150.48103 -388.177532) (xy 150.485602 -388.169404) (xy 150.488396 -388.152132)
			(xy 150.473156 -388.069328) (xy 150.464012 -388.054088) (xy 150.4569 -388.0485) (xy 150.434729 -388.029794)
			(xy 150.394782 -387.987733) (xy 150.360465 -387.940965) (xy 150.332326 -387.890239) (xy 150.310816 -387.836366)
			(xy 150.296279 -387.780209) (xy 150.288949 -387.722666) (xy 150.288498 -387.693662) (xy 150.289093 -387.660341)
			(xy 150.298753 -387.594402) (xy 150.317877 -387.530563) (xy 150.331424 -387.500114) (xy 150.335649 -387.489642)
			(xy 150.335543 -387.467089) (xy 150.325819 -387.446739) (xy 150.317454 -387.439154) (xy 150.295198 -387.42049)
			(xy 150.255133 -387.378434) (xy 150.220712 -387.331647) (xy 150.192488 -387.28088) (xy 150.170914 -387.22695)
			(xy 150.156337 -387.170724) (xy 150.148992 -387.113105) (xy 150.148544 -387.084062) (xy 150.148998 -387.055136)
			(xy 150.156282 -386.997744) (xy 150.170741 -386.941727) (xy 150.192144 -386.88798) (xy 150.22015 -386.837358)
			(xy 150.254314 -386.79067) (xy 150.294089 -386.74866) (xy 150.316184 -386.729986) (xy 150.32316 -386.723642)
			(xy 150.332415 -386.707236) (xy 150.334218 -386.697982) (xy 150.338536 -386.666994) (xy 150.339442 -386.657757)
			(xy 150.335416 -386.639657) (xy 150.330662 -386.631688) (xy 150.314351 -386.605845) (xy 150.29045 -386.549607)
			(xy 150.283164 -386.519928) (xy 150.281115 -386.511763) (xy 150.272408 -386.497363) (xy 150.266146 -386.491734)
			(xy 150.243032 -386.472684) (xy 150.236138 -386.467459) (xy 150.219918 -386.461481) (xy 150.211282 -386.461)
			(xy 150.181646 -386.459972) (xy 150.122982 -386.451326) (xy 150.065925 -386.435177) (xy 150.011431 -386.411797)
			(xy 149.960412 -386.381576) (xy 149.913722 -386.345021) (xy 149.872142 -386.302743) (xy 149.83637 -386.25545)
			(xy 149.807003 -386.203935) (xy 149.784533 -386.149059) (xy 149.769337 -386.091741) (xy 149.761669 -386.032941)
			(xy 149.761194 -386.003292) (xy 149.761714 -385.972229) (xy 149.77013 -385.910675) (xy 149.777958 -385.88061)
			(xy 149.780752 -385.87045) (xy 149.778212 -385.850638) (xy 149.730714 -385.768342) (xy 149.714712 -385.75615)
			(xy 149.704552 -385.75361) (xy 149.675467 -385.745565) (xy 149.61954 -385.722901) (xy 149.567075 -385.693087)
			(xy 149.51898 -385.65664) (xy 149.476089 -385.614191) (xy 149.439146 -385.566477) (xy 149.40879 -385.514323)
			(xy 149.385548 -385.458633) (xy 149.369822 -385.400373) (xy 149.361885 -385.340552) (xy 149.361398 -385.31038)
			(xy 149.361924 -385.279492) (xy 149.370229 -385.218277) (xy 149.386686 -385.158733) (xy 149.410996 -385.101941)
			(xy 149.426422 -385.075176) (xy 149.432264 -385.06527) (xy 149.43455 -385.042918) (xy 149.401276 -384.947668)
			(xy 149.385528 -384.931666) (xy 149.37486 -384.927602) (xy 149.351471 -384.918438) (xy 149.307575 -384.894014)
			(xy 149.26788 -384.86323) (xy 149.2333 -384.826793) (xy 149.204631 -384.785544) (xy 149.182535 -384.740432)
			(xy 149.167519 -384.692495) (xy 149.15993 -384.642839) (xy 149.159468 -384.617722) (xy 148.620734 -384.617722)
			(xy 148.620205 -384.644824) (xy 148.611395 -384.698307) (xy 148.603208 -384.724148) (xy 148.599398 -384.73507)
			(xy 148.601938 -384.757422) (xy 148.654516 -384.843274) (xy 148.673566 -384.85572) (xy 148.684742 -384.857498)
			(xy 148.714062 -384.862197) (xy 148.771232 -384.878247) (xy 148.825846 -384.901558) (xy 148.876986 -384.931738)
			(xy 148.923791 -384.96828) (xy 148.965476 -385.01057) (xy 149.00134 -385.057897) (xy 149.03078 -385.109466)
			(xy 149.053301 -385.16441) (xy 149.068525 -385.221806) (xy 149.076197 -385.28069) (xy 149.076664 -385.31038)
			(xy 149.076137 -385.341443) (xy 149.067725 -385.402996) (xy 149.0599 -385.433062) (xy 149.057106 -385.443222)
			(xy 149.059646 -385.463034) (xy 149.107144 -385.54533) (xy 149.123146 -385.557522) (xy 149.133306 -385.560062)
			(xy 149.162407 -385.568092) (xy 149.218373 -385.590721) (xy 149.27088 -385.620511) (xy 149.319014 -385.656944)
			(xy 149.361942 -385.699389) (xy 149.398917 -385.747109) (xy 149.429298 -385.799275) (xy 149.452558 -385.854982)
			(xy 149.468293 -385.913264) (xy 149.47623 -385.973108) (xy 149.476714 -386.003292) (xy 149.476589 -386.017427)
			(xy 149.474807 -386.045641) (xy 149.473158 -386.05968) (xy 149.472397 -386.068287) (xy 149.476037 -386.085167)
			(xy 149.48027 -386.0927) (xy 149.496018 -386.1181) (xy 149.500719 -386.125167) (xy 149.513831 -386.135932)
			(xy 149.521672 -386.139182) (xy 149.545062 -386.148343) (xy 149.588957 -386.172768) (xy 149.628651 -386.203554)
			(xy 149.663229 -386.239992) (xy 149.691897 -386.281241) (xy 149.713993 -386.326353) (xy 149.72901 -386.374289)
			(xy 149.736601 -386.423945) (xy 149.737064 -386.449062) (xy 149.736645 -386.473264) (xy 149.72957 -386.521149)
			(xy 149.715582 -386.567489) (xy 149.69498 -386.611291) (xy 149.681946 -386.631688) (xy 149.677156 -386.639644)
			(xy 149.673124 -386.657756) (xy 149.674072 -386.666994) (xy 149.67839 -386.697982) (xy 149.680075 -386.707277)
			(xy 149.689354 -386.723719) (xy 149.696424 -386.729986) (xy 149.718504 -386.748678) (xy 149.758277 -386.790687)
			(xy 149.792441 -386.837373) (xy 149.82045 -386.887991) (xy 149.841859 -386.941735) (xy 149.856325 -386.997747)
			(xy 149.863619 -387.055137) (xy 149.864064 -387.084062) (xy 149.863472 -387.117383) (xy 149.85381 -387.183322)
			(xy 149.834685 -387.247161) (xy 149.821138 -387.27761) (xy 149.81687 -387.28807) (xy 149.816984 -387.310636)
			(xy 149.82673 -387.330989) (xy 149.835108 -387.33857) (xy 149.85734 -387.357261) (xy 149.897404 -387.399314)
			(xy 149.931825 -387.446097) (xy 149.960052 -387.496859) (xy 149.98163 -387.550784) (xy 149.996213 -387.607006)
			(xy 150.003565 -387.664621) (xy 150.004018 -387.693662) (xy 150.003554 -387.722667) (xy 149.996242 -387.780216)
			(xy 149.981719 -387.836379) (xy 149.960217 -387.890258) (xy 149.93208 -387.940988) (xy 149.89776 -387.987757)
			(xy 149.857807 -388.029816) (xy 149.835616 -388.0485) (xy 149.828504 -388.054088) (xy 149.81936 -388.069328)
			(xy 149.80412 -388.152132) (xy 149.806914 -388.169404) (xy 149.811486 -388.177532) (xy 149.824057 -388.200721)
			(xy 149.841934 -388.250341) (xy 149.851036 -388.302292) (xy 149.851618 -388.328662) (xy 149.851549 -388.338021)
			(xy 149.850406 -388.356703) (xy 149.849332 -388.366) (xy 149.848316 -388.37489) (xy 149.852126 -388.391654)
			(xy 149.896068 -388.461504) (xy 149.909784 -388.471918) (xy 149.918166 -388.474712) (xy 149.942257 -388.48321)
			(xy 149.987549 -388.506831) (xy 150.028445 -388.537438) (xy 150.063878 -388.574232) (xy 150.092922 -388.616252)
			(xy 150.114819 -388.662402) (xy 150.122382 -388.686802) (xy 150.123906 -388.692644) (xy 150.443692 -389.245602)
			(xy 150.447756 -389.24992) (xy 150.463957 -389.26763) (xy 150.49138 -389.307021) (xy 150.512522 -389.350111)
			(xy 150.526897 -389.395904) (xy 150.534172 -389.443346) (xy 150.534624 -389.467344) (xy 150.534246 -389.492152)
			(xy 150.526474 -389.541155) (xy 150.511128 -389.588337) (xy 150.488586 -389.632536) (xy 150.459404 -389.672662)
			(xy 150.424302 -389.707727) (xy 150.384144 -389.736865) (xy 150.339921 -389.759359) (xy 150.292721 -389.774654)
			(xy 150.24371 -389.782373) (xy 150.218902 -389.782812) (xy 150.193508 -389.78231) (xy 150.143374 -389.774179)
			(xy 150.095189 -389.758128) (xy 150.050194 -389.73457) (xy 150.009551 -389.704113) (xy 149.974309 -389.667542)
			(xy 149.945375 -389.625801) (xy 149.923497 -389.579966) (xy 149.91588 -389.555736) (xy 149.914356 -389.549894)
			(xy 149.593808 -388.995412) (xy 149.589744 -388.991094) (xy 149.573639 -388.973426) (xy 149.546391 -388.934146)
			(xy 149.525381 -388.891206) (xy 149.511089 -388.845587) (xy 149.503842 -388.798334) (xy 149.503384 -388.774432)
			(xy 149.503526 -388.76238) (xy 149.505432 -388.73835) (xy 149.507194 -388.726426) (xy 149.508464 -388.717536)
			(xy 149.505416 -388.700518) (xy 149.463252 -388.629652) (xy 149.450044 -388.618476) (xy 149.441662 -388.615428)
			(xy 149.419913 -388.607037) (xy 149.379054 -388.584595) (xy 149.342084 -388.556201) (xy 149.309862 -388.522515)
			(xy 149.283137 -388.48432) (xy 149.262531 -388.442506) (xy 149.248523 -388.398045) (xy 149.24144 -388.35197)
			(xy 149.241002 -388.328662) (xy 149.241567 -388.302289) (xy 149.250651 -388.25033) (xy 149.268539 -388.20071)
			(xy 149.281134 -388.177532) (xy 149.285706 -388.169404) (xy 149.2885 -388.152132) (xy 149.27326 -388.069328)
			(xy 149.264116 -388.054088) (xy 149.257004 -388.0485) (xy 149.234834 -388.029793) (xy 149.194887 -387.987732)
			(xy 149.160569 -387.940964) (xy 149.13243 -387.890238) (xy 149.11092 -387.836366) (xy 149.096384 -387.780209)
			(xy 149.089053 -387.722666) (xy 149.088602 -387.693662) (xy 149.089196 -387.660341) (xy 149.098856 -387.594402)
			(xy 149.117981 -387.530563) (xy 149.131528 -387.500114) (xy 149.135751 -387.489641) (xy 149.135646 -387.467089)
			(xy 149.125923 -387.44674) (xy 149.117558 -387.439154) (xy 149.095303 -387.420489) (xy 149.055238 -387.378433)
			(xy 149.020817 -387.331646) (xy 148.992592 -387.28088) (xy 148.971018 -387.22695) (xy 148.956441 -387.170723)
			(xy 148.949096 -387.113105) (xy 148.948648 -387.084062) (xy 148.949101 -387.055136) (xy 148.956384 -386.997743)
			(xy 148.970843 -386.941727) (xy 148.992247 -386.887979) (xy 149.020254 -386.837358) (xy 149.054417 -386.79067)
			(xy 149.094192 -386.74866) (xy 149.116288 -386.729986) (xy 149.123264 -386.723643) (xy 149.132519 -386.707236)
			(xy 149.134322 -386.697982) (xy 149.13864 -386.666994) (xy 149.139545 -386.657757) (xy 149.13552 -386.639657)
			(xy 149.130766 -386.631688) (xy 149.114455 -386.605844) (xy 149.090554 -386.549607) (xy 149.083268 -386.519928)
			(xy 149.081218 -386.511763) (xy 149.072511 -386.497363) (xy 149.06625 -386.491734) (xy 149.043136 -386.472684)
			(xy 149.036241 -386.46746) (xy 149.020022 -386.461481) (xy 149.011386 -386.461) (xy 148.98175 -386.459969)
			(xy 148.923086 -386.451323) (xy 148.866029 -386.435174) (xy 148.811535 -386.411794) (xy 148.760516 -386.381574)
			(xy 148.713826 -386.345019) (xy 148.672247 -386.302742) (xy 148.636474 -386.255449) (xy 148.607107 -386.203934)
			(xy 148.584637 -386.149058) (xy 148.569441 -386.091741) (xy 148.561773 -386.032941) (xy 148.561298 -386.003292)
			(xy 148.561818 -385.972229) (xy 148.570234 -385.910675) (xy 148.578062 -385.88061) (xy 148.580856 -385.87045)
			(xy 148.578316 -385.850638) (xy 148.530818 -385.768342) (xy 148.514816 -385.75615) (xy 148.504656 -385.75361)
			(xy 148.47554 -385.745631) (xy 148.419572 -385.722995) (xy 148.367066 -385.6932) (xy 148.318931 -385.65676)
			(xy 148.276005 -385.614309) (xy 148.239031 -385.566584) (xy 148.208652 -385.514412) (xy 148.185395 -385.4587)
			(xy 148.169663 -385.400414) (xy 148.161729 -385.340566) (xy 148.161248 -385.31038) (xy 148.161767 -385.279492)
			(xy 148.170073 -385.218276) (xy 148.186532 -385.158732) (xy 148.210844 -385.10194) (xy 148.226272 -385.075176)
			(xy 148.232114 -385.06527) (xy 148.2344 -385.042918) (xy 148.201126 -384.947668) (xy 148.185378 -384.931666)
			(xy 148.17471 -384.927602) (xy 148.151332 -384.918411) (xy 148.107434 -384.893993) (xy 148.067737 -384.863214)
			(xy 148.033155 -384.826782) (xy 148.004485 -384.785536) (xy 147.982387 -384.740427) (xy 147.96737 -384.692493)
			(xy 147.95978 -384.642838) (xy 147.959318 -384.617722) (xy 147.420838 -384.617722) (xy 147.420309 -384.644824)
			(xy 147.411499 -384.698307) (xy 147.403312 -384.724148) (xy 147.399502 -384.73507) (xy 147.402042 -384.757422)
			(xy 147.45462 -384.843274) (xy 147.47367 -384.85572) (xy 147.484846 -384.857498) (xy 147.514166 -384.862193)
			(xy 147.571337 -384.878244) (xy 147.625951 -384.901555) (xy 147.67709 -384.931736) (xy 147.723895 -384.968278)
			(xy 147.76558 -385.010569) (xy 147.801444 -385.057896) (xy 147.830884 -385.109466) (xy 147.853405 -385.16441)
			(xy 147.86863 -385.221806) (xy 147.876301 -385.280689) (xy 147.876768 -385.31038) (xy 147.876241 -385.341443)
			(xy 147.867829 -385.402996) (xy 147.860004 -385.433062) (xy 147.85721 -385.443222) (xy 147.85975 -385.463034)
			(xy 147.907248 -385.54533) (xy 147.92325 -385.557522) (xy 147.93341 -385.560062) (xy 147.962511 -385.56809)
			(xy 148.018478 -385.590719) (xy 148.070984 -385.620509) (xy 148.119119 -385.656943) (xy 148.162046 -385.699388)
			(xy 148.199021 -385.747108) (xy 148.229403 -385.799274) (xy 148.252662 -385.854982) (xy 148.268397 -385.913263)
			(xy 148.276334 -385.973108) (xy 148.276818 -386.003292) (xy 148.276693 -386.017427) (xy 148.274911 -386.045641)
			(xy 148.273262 -386.05968) (xy 148.272501 -386.068287) (xy 148.276141 -386.085167) (xy 148.280374 -386.0927)
			(xy 148.296122 -386.1181) (xy 148.300841 -386.125155) (xy 148.313934 -386.135938) (xy 148.321776 -386.139182)
			(xy 148.345135 -386.148385) (xy 148.388976 -386.172845) (xy 148.428619 -386.20365) (xy 148.463151 -386.240091)
			(xy 148.491781 -386.281331) (xy 148.513851 -386.326424) (xy 148.528854 -386.374333) (xy 148.536446 -386.42396)
			(xy 148.536914 -386.449062) (xy 148.536486 -386.473264) (xy 148.529413 -386.521148) (xy 148.515428 -386.567488)
			(xy 148.494829 -386.61129) (xy 148.481796 -386.631688) (xy 148.47701 -386.639646) (xy 148.472974 -386.657756)
			(xy 148.473922 -386.666994) (xy 148.47824 -386.697982) (xy 148.47991 -386.707281) (xy 148.489199 -386.723722)
			(xy 148.496274 -386.729986) (xy 148.518364 -386.748665) (xy 148.558136 -386.790678) (xy 148.592297 -386.837366)
			(xy 148.620304 -386.887987) (xy 148.641711 -386.941732) (xy 148.656176 -386.997746) (xy 148.663469 -387.055136)
			(xy 148.663914 -387.084062) (xy 148.663327 -387.117384) (xy 148.653664 -387.183322) (xy 148.634536 -387.247161)
			(xy 148.620988 -387.27761) (xy 148.616737 -387.288074) (xy 148.616851 -387.310634) (xy 148.626587 -387.330986)
			(xy 148.634958 -387.33857) (xy 148.65718 -387.357273) (xy 148.697246 -387.399322) (xy 148.73167 -387.446103)
			(xy 148.759899 -387.496863) (xy 148.781478 -387.550787) (xy 148.796062 -387.607007) (xy 148.803415 -387.664621)
			(xy 148.803868 -387.693662) (xy 148.803385 -387.722667) (xy 148.796075 -387.780213) (xy 148.781553 -387.836376)
			(xy 148.760054 -387.890254) (xy 148.731921 -387.940984) (xy 148.697604 -387.987754) (xy 148.657655 -388.029815)
			(xy 148.635466 -388.0485) (xy 148.628354 -388.054088) (xy 148.61921 -388.069328) (xy 148.60397 -388.152132)
			(xy 148.606764 -388.169404) (xy 148.611336 -388.177532) (xy 148.623911 -388.200719) (xy 148.641785 -388.25034)
			(xy 148.650886 -388.302291) (xy 148.651468 -388.328662) (xy 148.651399 -388.338021) (xy 148.650256 -388.356703)
			(xy 148.649182 -388.366) (xy 148.648166 -388.37489) (xy 148.651976 -388.391654) (xy 148.695918 -388.461504)
			(xy 148.709634 -388.471918) (xy 148.718016 -388.474712) (xy 148.74204 -388.483193) (xy 148.787212 -388.506742)
			(xy 148.828018 -388.537239) (xy 148.863398 -388.573891) (xy 148.892435 -388.615749) (xy 148.914374 -388.661725)
			(xy 148.921978 -388.68604) (xy 148.923502 -388.691882) (xy 149.243796 -389.245602) (xy 149.24786 -389.24992)
			(xy 149.264062 -389.26763) (xy 149.291484 -389.307021) (xy 149.312626 -389.35011) (xy 149.327001 -389.395904)
			(xy 149.334276 -389.443346) (xy 149.334728 -389.467344) (xy 149.334346 -389.492151) (xy 149.326574 -389.541154)
			(xy 149.311228 -389.588336) (xy 149.288687 -389.632535) (xy 149.259506 -389.672661) (xy 149.224404 -389.707725)
			(xy 149.184246 -389.736864) (xy 149.140023 -389.759358) (xy 149.092825 -389.774653) (xy 149.043814 -389.782373)
			(xy 149.019006 -389.782812) (xy 148.993612 -389.782306) (xy 148.943478 -389.774177) (xy 148.895293 -389.758126)
			(xy 148.850299 -389.734568) (xy 148.809656 -389.704112) (xy 148.774413 -389.667541) (xy 148.745479 -389.625801)
			(xy 148.723601 -389.579966) (xy 148.715984 -389.555736) (xy 148.71446 -389.549894) (xy 148.394166 -388.996174)
			(xy 148.390102 -388.991856) (xy 148.373951 -388.974115) (xy 148.34658 -388.934716) (xy 148.325487 -388.891628)
			(xy 148.311157 -388.845844) (xy 148.303922 -388.798419) (xy 148.303488 -388.774432) (xy 148.303569 -388.762384)
			(xy 148.305352 -388.738355) (xy 148.307044 -388.726426) (xy 148.308314 -388.717536) (xy 148.305266 -388.700518)
			(xy 148.263102 -388.629652) (xy 148.249894 -388.618476) (xy 148.241512 -388.615428) (xy 148.219773 -388.60701)
			(xy 148.178914 -388.584574) (xy 148.141941 -388.556185) (xy 148.109717 -388.522504) (xy 148.08299 -388.484313)
			(xy 148.062383 -388.442501) (xy 148.048374 -388.398042) (xy 148.04129 -388.351969) (xy 148.040852 -388.328662)
			(xy 148.041424 -388.302289) (xy 148.050505 -388.250331) (xy 148.068391 -388.200711) (xy 148.080984 -388.177532)
			(xy 148.085556 -388.169404) (xy 148.08835 -388.152132) (xy 148.07311 -388.069328) (xy 148.063966 -388.054088)
			(xy 148.056854 -388.0485) (xy 148.034674 -388.029805) (xy 147.994729 -387.987741) (xy 147.960414 -387.94097)
			(xy 147.932277 -387.890242) (xy 147.910768 -387.836368) (xy 147.896233 -387.78021) (xy 147.888903 -387.722666)
			(xy 147.888452 -387.693662) (xy 147.889051 -387.660341) (xy 147.89871 -387.594403) (xy 147.917832 -387.530563)
			(xy 147.931378 -387.500114) (xy 147.935618 -387.489645) (xy 147.935513 -387.467087) (xy 147.925779 -387.446737)
			(xy 147.917408 -387.439154) (xy 147.895143 -387.420501) (xy 147.85508 -387.378442) (xy 147.820661 -387.331652)
			(xy 147.792438 -387.280884) (xy 147.770866 -387.226952) (xy 147.75629 -387.170725) (xy 147.748946 -387.113105)
			(xy 147.748498 -387.084062) (xy 147.748933 -387.055135) (xy 147.756217 -386.997741) (xy 147.770678 -386.941724)
			(xy 147.792084 -386.887975) (xy 147.820094 -386.837354) (xy 147.854261 -386.790667) (xy 147.89404 -386.748658)
			(xy 147.916138 -386.729986) (xy 147.923106 -386.723635) (xy 147.932367 -386.707234) (xy 147.934172 -386.697982)
			(xy 147.93849 -386.666994) (xy 147.939387 -386.657757) (xy 147.935366 -386.639658) (xy 147.930616 -386.631688)
			(xy 147.914309 -386.605842) (xy 147.890405 -386.549607) (xy 147.883118 -386.519928) (xy 147.881054 -386.511767)
			(xy 147.872357 -386.497366) (xy 147.8661 -386.491734) (xy 147.842986 -386.472684) (xy 147.836163 -386.467467)
			(xy 147.820065 -386.461504) (xy 147.81149 -386.461) (xy 147.781854 -386.459965) (xy 147.72319 -386.451319)
			(xy 147.666134 -386.435172) (xy 147.61164 -386.411792) (xy 147.56062 -386.381572) (xy 147.51393 -386.345017)
			(xy 147.472351 -386.30274) (xy 147.436578 -386.255448) (xy 147.407211 -386.203933) (xy 147.384741 -386.149058)
			(xy 147.369545 -386.09174) (xy 147.361877 -386.032941) (xy 147.361402 -386.003292) (xy 147.361921 -385.972229)
			(xy 147.370338 -385.910675) (xy 147.378166 -385.88061) (xy 147.38096 -385.87045) (xy 147.37842 -385.850638)
			(xy 147.330922 -385.768342) (xy 147.31492 -385.75615) (xy 147.30476 -385.75361) (xy 147.293038 -385.750466)
			(xy 147.269912 -385.743094) (xy 147.258532 -385.738878) (xy 147.246086 -385.734306) (xy 147.220178 -385.738116)
			(xy 147.13077 -385.806696) (xy 147.120356 -385.830826) (xy 147.121626 -385.84378) (xy 147.12315 -385.87553)
			(xy 147.122767 -385.899206) (xy 147.116034 -385.946077) (xy 147.102668 -385.991504) (xy 147.093178 -386.013198)
			(xy 147.08886 -386.022596) (xy 147.088098 -386.042662) (xy 147.120356 -386.129022) (xy 147.134072 -386.143754)
			(xy 147.14347 -386.148072) (xy 147.167843 -386.159753) (xy 147.212712 -386.189883) (xy 147.252089 -386.226903)
			(xy 147.284927 -386.269829) (xy 147.310352 -386.317522) (xy 147.32769 -386.368712) (xy 147.336479 -386.422039)
			(xy 147.337018 -386.449062) (xy 147.33659 -386.473264) (xy 147.329517 -386.521148) (xy 147.315531 -386.567488)
			(xy 147.294932 -386.61129) (xy 147.2819 -386.631688) (xy 147.277114 -386.639646) (xy 147.273078 -386.657756)
			(xy 147.274026 -386.666994) (xy 147.278344 -386.697982) (xy 147.280013 -386.707282) (xy 147.289302 -386.723722)
			(xy 147.296378 -386.729986) (xy 147.318469 -386.748664) (xy 147.35824 -386.790677) (xy 147.392401 -386.837366)
			(xy 147.420409 -386.887986) (xy 147.441815 -386.941732) (xy 147.45628 -386.997746) (xy 147.463573 -387.055136)
			(xy 147.464018 -387.084062) (xy 147.46343 -387.117384) (xy 147.453767 -387.183322) (xy 147.43464 -387.247161)
			(xy 147.421092 -387.27761) (xy 147.416839 -387.288074) (xy 147.416953 -387.310634) (xy 147.42669 -387.330986)
			(xy 147.435062 -387.33857) (xy 147.457284 -387.357272) (xy 147.49735 -387.399322) (xy 147.531774 -387.446102)
			(xy 147.560003 -387.496863) (xy 147.581582 -387.550787) (xy 147.596166 -387.607007) (xy 147.603519 -387.664621)
			(xy 147.603972 -387.693662) (xy 147.603488 -387.722667) (xy 147.596177 -387.780213) (xy 147.581656 -387.836375)
			(xy 147.560157 -387.890253) (xy 147.532024 -387.940984) (xy 147.497708 -387.987754) (xy 147.457758 -388.029815)
			(xy 147.43557 -388.0485) (xy 147.428458 -388.054088) (xy 147.419314 -388.069328) (xy 147.404074 -388.152132)
			(xy 147.406868 -388.169404) (xy 147.41144 -388.177532) (xy 147.424015 -388.200719) (xy 147.441889 -388.25034)
			(xy 147.45099 -388.302291) (xy 147.451572 -388.328662) (xy 147.451503 -388.338021) (xy 147.45036 -388.356703)
			(xy 147.449286 -388.366) (xy 147.44827 -388.37489) (xy 147.45208 -388.391654) (xy 147.496022 -388.461504)
			(xy 147.509738 -388.471918) (xy 147.51812 -388.474712) (xy 147.542144 -388.48319) (xy 147.587317 -388.506741)
			(xy 147.628123 -388.537238) (xy 147.663503 -388.573891) (xy 147.692539 -388.615748) (xy 147.714479 -388.661725)
			(xy 147.722082 -388.68604) (xy 147.723606 -388.691882) (xy 148.0439 -389.245602) (xy 148.047964 -389.24992)
			(xy 148.064166 -389.267629) (xy 148.091588 -389.307021) (xy 148.11273 -389.35011) (xy 148.127105 -389.395904)
			(xy 148.13438 -389.443346) (xy 148.134832 -389.467344) (xy 148.134447 -389.492151) (xy 148.126674 -389.541153)
			(xy 148.111329 -389.588335) (xy 148.088788 -389.632534) (xy 148.059607 -389.67266) (xy 148.024505 -389.707724)
			(xy 147.984349 -389.736862) (xy 147.940126 -389.759357) (xy 147.892928 -389.774652) (xy 147.843918 -389.782373)
			(xy 147.81911 -389.782812) (xy 147.793716 -389.782303) (xy 147.743583 -389.774174) (xy 147.695397 -389.758124)
			(xy 147.650403 -389.734567) (xy 147.60976 -389.70411) (xy 147.574517 -389.66754) (xy 147.545583 -389.6258)
			(xy 147.523705 -389.579966) (xy 147.516088 -389.555736) (xy 147.514564 -389.549894) (xy 147.19427 -388.996174)
			(xy 147.190206 -388.991856) (xy 147.174039 -388.974129) (xy 147.146673 -388.934724) (xy 147.125585 -388.891633)
			(xy 147.111259 -388.845846) (xy 147.104026 -388.79842) (xy 147.103592 -388.774432) (xy 147.103673 -388.762384)
			(xy 147.105456 -388.738355) (xy 147.107148 -388.726426) (xy 147.108418 -388.717536) (xy 147.10537 -388.700518)
			(xy 147.063206 -388.629652) (xy 147.049998 -388.618476) (xy 147.041616 -388.615428) (xy 147.019878 -388.607008)
			(xy 146.979018 -388.584573) (xy 146.942046 -388.556184) (xy 146.909821 -388.522503) (xy 146.883094 -388.484312)
			(xy 146.862487 -388.442501) (xy 146.848478 -388.398042) (xy 146.841394 -388.351969) (xy 146.840956 -388.328662)
			(xy 146.841527 -388.302289) (xy 146.850609 -388.250331) (xy 146.868495 -388.200711) (xy 146.881088 -388.177532)
			(xy 146.88566 -388.169404) (xy 146.888454 -388.152132) (xy 146.873214 -388.069328) (xy 146.86407 -388.054088)
			(xy 146.856958 -388.0485) (xy 146.834779 -388.029804) (xy 146.794834 -387.98774) (xy 146.760518 -387.94097)
			(xy 146.732381 -387.890242) (xy 146.710873 -387.836368) (xy 146.696337 -387.78021) (xy 146.689007 -387.722666)
			(xy 146.688556 -387.693662) (xy 146.689155 -387.660341) (xy 146.698813 -387.594403) (xy 146.717936 -387.530563)
			(xy 146.731482 -387.500114) (xy 146.73572 -387.489645) (xy 146.735615 -387.467087) (xy 146.725883 -387.446737)
			(xy 146.717512 -387.439154) (xy 146.695247 -387.4205) (xy 146.655185 -387.378441) (xy 146.620765 -387.331652)
			(xy 146.592543 -387.280883) (xy 146.57097 -387.226952) (xy 146.556394 -387.170725) (xy 146.54905 -387.113105)
			(xy 146.548602 -387.084062) (xy 146.549035 -387.055135) (xy 146.55632 -386.997741) (xy 146.57078 -386.941723)
			(xy 146.592187 -386.887975) (xy 146.620197 -386.837354) (xy 146.654364 -386.790666) (xy 146.694144 -386.748658)
			(xy 146.716242 -386.729986) (xy 146.723211 -386.723635) (xy 146.732471 -386.707234) (xy 146.734276 -386.697982)
			(xy 146.738594 -386.666994) (xy 146.739491 -386.657757) (xy 146.73547 -386.639658) (xy 146.73072 -386.631688)
			(xy 146.717735 -386.611264) (xy 146.697153 -386.567463) (xy 146.683165 -386.521132) (xy 146.676069 -386.473259)
			(xy 146.675602 -386.449062) (xy 146.675987 -386.425386) (xy 146.68272 -386.378515) (xy 146.696084 -386.333089)
			(xy 146.705574 -386.311394) (xy 146.709892 -386.301996) (xy 146.710654 -386.28193) (xy 146.678396 -386.19557)
			(xy 146.66468 -386.180838) (xy 146.655282 -386.17652) (xy 146.630917 -386.164821) (xy 146.586046 -386.134697)
			(xy 146.546666 -386.097681) (xy 146.513827 -386.054758) (xy 146.4884 -386.007067) (xy 146.471061 -385.955879)
			(xy 146.462273 -385.902553) (xy 146.461734 -385.87553) (xy 144.974694 -385.87553) (xy 144.945271 -385.912289)
			(xy 144.923256 -385.93395) (xy 144.91462 -385.942332) (xy 144.906492 -385.964684) (xy 144.91843 -386.069078)
			(xy 144.931384 -386.08889) (xy 144.941798 -386.09524) (xy 144.967145 -386.110735) (xy 145.013997 -386.147264)
			(xy 145.055727 -386.189549) (xy 145.091634 -386.236879) (xy 145.121114 -386.288458) (xy 145.14367 -386.343418)
			(xy 145.158924 -386.400835) (xy 145.16662 -386.459744) (xy 145.167096 -386.489448) (xy 145.16664 -386.520108)
			(xy 145.158447 -386.580877) (xy 145.142214 -386.640009) (xy 145.118232 -386.696444) (xy 145.086931 -386.749172)
			(xy 145.04887 -386.797249) (xy 145.027142 -386.818886) (xy 145.019406 -386.827201) (xy 145.011402 -386.84842)
			(xy 145.013311 -386.871018) (xy 145.018506 -386.881116) (xy 145.032645 -386.906584) (xy 145.052714 -386.961264)
			(xy 145.062876 -387.018616) (xy 145.063464 -387.04774) (xy 145.062954 -387.073727) (xy 145.054824 -387.125062)
			(xy 145.038763 -387.174492) (xy 145.015167 -387.220802) (xy 144.984617 -387.26285) (xy 144.947866 -387.299601)
			(xy 144.905818 -387.330151) (xy 144.859508 -387.353747) (xy 144.810078 -387.369808) (xy 144.758743 -387.377938)
			(xy 144.706769 -387.377938) (xy 144.655434 -387.369808) (xy 144.606004 -387.353747) (xy 144.559694 -387.330151)
			(xy 144.517646 -387.299601) (xy 144.480895 -387.26285) (xy 144.450345 -387.220802) (xy 144.426749 -387.174492)
			(xy 144.410688 -387.125062) (xy 144.402558 -387.073727) (xy 144.402048 -387.04774) (xy 144.402473 -387.023227)
			(xy 144.409656 -386.974731) (xy 144.42393 -386.92783) (xy 144.434052 -386.9055) (xy 144.438446 -386.895037)
			(xy 144.438492 -386.872369) (xy 144.428755 -386.851899) (xy 144.420336 -386.844286) (xy 144.398112 -386.825625)
			(xy 144.358104 -386.783587) (xy 144.323733 -386.736828) (xy 144.295551 -386.686097) (xy 144.274011 -386.63221)
			(xy 144.259458 -386.576032) (xy 144.252126 -386.518464) (xy 144.25168 -386.489448) (xy 144.252187 -386.458568)
			(xy 144.260504 -386.397371) (xy 144.276979 -386.33785) (xy 144.301313 -386.281086) (xy 144.333064 -386.228113)
			(xy 144.371653 -386.179894) (xy 144.393666 -386.158232) (xy 144.402302 -386.14985) (xy 144.41043 -386.127498)
			(xy 144.398492 -386.023104) (xy 144.385538 -386.003292) (xy 144.375124 -385.996942) (xy 144.351743 -385.982714)
			(xy 144.308232 -385.949511) (xy 144.268997 -385.911348) (xy 144.234601 -385.868773) (xy 144.205536 -385.822394)
			(xy 144.193514 -385.797806) (xy 144.187418 -385.785106) (xy 144.164558 -385.769612) (xy 144.047718 -385.762246)
			(xy 144.023334 -385.774692) (xy 144.015714 -385.78663) (xy 144.000662 -385.809536) (xy 143.964965 -385.851128)
			(xy 143.923684 -385.887183) (xy 143.877667 -385.916959) (xy 143.827862 -385.939842) (xy 143.775294 -385.955362)
			(xy 143.721047 -385.963198) (xy 143.693642 -385.963668) (xy 143.666384 -385.963288) (xy 143.612423 -385.955535)
			(xy 143.560115 -385.940181) (xy 143.510524 -385.917538) (xy 143.464661 -385.888068) (xy 143.423459 -385.852371)
			(xy 143.387757 -385.811173) (xy 143.358282 -385.765313) (xy 143.335634 -385.715725) (xy 143.320274 -385.663418)
			(xy 143.312515 -385.609458) (xy 136.882063 -385.609458) (xy 136.891776 -385.628642) (xy 136.901174 -385.635754)
			(xy 136.927495 -385.656434) (xy 136.975033 -385.703558) (xy 137.015974 -385.756514) (xy 137.04961 -385.814386)
			(xy 137.075359 -385.876172) (xy 137.092775 -385.940803) (xy 137.101557 -386.007162) (xy 137.102088 -386.04063)
			(xy 137.101672 -386.071362) (xy 137.09426 -386.132379) (xy 137.079547 -386.192057) (xy 137.057748 -386.249526)
			(xy 137.029181 -386.303949) (xy 136.994262 -386.354532) (xy 136.953501 -386.400537) (xy 136.907492 -386.441293)
			(xy 136.856906 -386.476207) (xy 136.80248 -386.504769) (xy 136.745009 -386.526562) (xy 136.685329 -386.541269)
			(xy 136.624312 -386.548675) (xy 136.59358 -386.549138) (xy 136.562078 -386.548652) (xy 136.499557 -386.540863)
			(xy 136.438478 -386.525407) (xy 136.379777 -386.502521) (xy 136.324354 -386.472557) (xy 136.298432 -386.45465)
			(xy 136.28751 -386.44703) (xy 136.261602 -386.444236) (xy 136.157208 -386.488178) (xy 136.141206 -386.508752)
			(xy 136.139174 -386.52196) (xy 136.133738 -386.554309) (xy 136.115508 -386.617323) (xy 136.089328 -386.677471)
			(xy 136.055632 -386.733754) (xy 136.014981 -386.785238) (xy 135.968048 -386.831069) (xy 135.915612 -386.870486)
			(xy 135.858544 -386.902834) (xy 135.797791 -386.927577) (xy 135.734361 -386.944305) (xy 135.669307 -386.95274)
			(xy 135.636508 -386.953252) (xy 135.605104 -386.952719) (xy 135.542775 -386.944985) (xy 135.481873 -386.929633)
			(xy 135.423326 -386.906897) (xy 135.368024 -386.877123) (xy 135.316811 -386.840766) (xy 135.270465 -386.798377)
			(xy 135.229692 -386.750603) (xy 135.195114 -386.698171) (xy 135.167257 -386.64188) (xy 135.146544 -386.582586)
			(xy 135.133292 -386.521193) (xy 135.130032 -386.489956) (xy 135.129016 -386.479796) (xy 135.12038 -386.462778)
			(xy 135.052308 -386.403342) (xy 135.03402 -386.396992) (xy 135.02386 -386.3975) (xy 134.99973 -386.398008)
			(xy 134.968999 -386.397534) (xy 134.907983 -386.390129) (xy 134.848306 -386.375423) (xy 134.790836 -386.35363)
			(xy 134.736412 -386.325069) (xy 134.685828 -386.290156) (xy 134.639821 -386.2494) (xy 134.599062 -386.203396)
			(xy 134.564146 -386.152814) (xy 134.535582 -386.098391) (xy 134.513786 -386.040923) (xy 134.499076 -385.981246)
			(xy 134.491668 -385.920231) (xy 134.491222 -385.8895) (xy 134.491646 -385.858719) (xy 134.499062 -385.797605)
			(xy 134.513798 -385.737833) (xy 134.535638 -385.680275) (xy 134.564264 -385.625773) (xy 134.581392 -385.600194)
			(xy 134.58647 -385.5922) (xy 134.590919 -385.573807) (xy 134.590028 -385.56438) (xy 134.58571 -385.533646)
			(xy 134.584048 -385.524382) (xy 134.574924 -385.507939) (xy 134.56793 -385.501642) (xy 134.546105 -385.482953)
			(xy 134.506799 -385.441039) (xy 134.473051 -385.394534) (xy 134.445391 -385.34417) (xy 134.424254 -385.290738)
			(xy 134.409974 -385.235081) (xy 134.402774 -385.178074) (xy 134.402322 -385.149344) (xy 133.319447 -385.149344)
			(xy 133.325622 -385.164408) (xy 133.340846 -385.221805) (xy 133.348517 -385.280689) (xy 133.348984 -385.31038)
			(xy 133.348457 -385.341443) (xy 133.340045 -385.402996) (xy 133.33222 -385.433062) (xy 133.329426 -385.443222)
			(xy 133.331966 -385.463034) (xy 133.379464 -385.54533) (xy 133.395466 -385.557522) (xy 133.405626 -385.560062)
			(xy 133.43473 -385.568079) (xy 133.490697 -385.59071) (xy 133.543203 -385.620502) (xy 133.591337 -385.656937)
			(xy 133.634264 -385.699384) (xy 133.671239 -385.747105) (xy 133.701619 -385.799272) (xy 133.724879 -385.85498)
			(xy 133.740614 -385.913263) (xy 133.74855 -385.973108) (xy 133.749034 -386.003292) (xy 133.748932 -386.017042)
			(xy 133.74728 -386.044493) (xy 133.745732 -386.058156) (xy 133.745013 -386.066844) (xy 133.748787 -386.083853)
			(xy 133.753098 -386.09143) (xy 133.7691 -386.11683) (xy 133.773869 -386.123867) (xy 133.787112 -386.134509)
			(xy 133.795008 -386.137658) (xy 133.818783 -386.146582) (xy 133.863432 -386.170775) (xy 133.903857 -386.201509)
			(xy 133.939108 -386.238063) (xy 133.968357 -386.279576) (xy 133.990914 -386.325073) (xy 134.00625 -386.373484)
			(xy 134.014005 -386.423671) (xy 134.014464 -386.449062) (xy 134.01399 -386.475052) (xy 134.005863 -386.526394)
			(xy 133.989803 -386.575832) (xy 133.966206 -386.622148) (xy 133.935653 -386.664202) (xy 133.898897 -386.700957)
			(xy 133.856843 -386.731509) (xy 133.810526 -386.755105) (xy 133.761088 -386.771164) (xy 133.709746 -386.77929)
			(xy 133.683756 -386.77977) (xy 133.658849 -386.779268) (xy 133.609595 -386.771818) (xy 133.562016 -386.757063)
			(xy 133.517189 -386.735336) (xy 133.47613 -386.70713) (xy 133.439766 -386.673084) (xy 133.408923 -386.633967)
			(xy 133.384296 -386.590666) (xy 133.366445 -386.54416) (xy 133.360668 -386.519928) (xy 133.358504 -386.511708)
			(xy 133.349694 -386.497188) (xy 133.343396 -386.49148) (xy 133.320028 -386.47243) (xy 133.313138 -386.467227)
			(xy 133.296904 -386.461382) (xy 133.288278 -386.461) (xy 133.258442 -386.460293) (xy 133.199319 -386.452145)
			(xy 133.141758 -386.436382) (xy 133.086734 -386.41327) (xy 133.03518 -386.383202) (xy 132.987973 -386.346688)
			(xy 132.945912 -386.304347) (xy 132.909711 -386.256899) (xy 132.879985 -386.205148) (xy 132.857238 -386.149972)
			(xy 132.841856 -386.092307) (xy 132.834099 -386.033133) (xy 132.833618 -386.003292) (xy 132.83414 -385.972229)
			(xy 132.842555 -385.910675) (xy 132.850382 -385.88061) (xy 132.853176 -385.87045) (xy 132.850636 -385.850638)
			(xy 132.803138 -385.768342) (xy 132.787136 -385.75615) (xy 132.776976 -385.75361) (xy 132.747864 -385.745617)
			(xy 132.691896 -385.722984) (xy 132.639389 -385.69319) (xy 132.591254 -385.656753) (xy 132.548327 -385.614304)
			(xy 132.511353 -385.56658) (xy 132.480974 -385.514409) (xy 132.457716 -385.458698) (xy 132.441984 -385.400413)
			(xy 132.43405 -385.340566) (xy 132.433568 -385.31038) (xy 132.434098 -385.279492) (xy 132.442403 -385.218277)
			(xy 132.458858 -385.158733) (xy 132.483167 -385.101941) (xy 132.498592 -385.075176) (xy 132.504434 -385.06527)
			(xy 132.50672 -385.042918) (xy 132.473446 -384.947668) (xy 132.457698 -384.931666) (xy 132.44703 -384.927602)
			(xy 132.423634 -384.918454) (xy 132.379739 -384.894027) (xy 132.340045 -384.863239) (xy 132.305466 -384.8268)
			(xy 132.276799 -384.785549) (xy 132.254704 -384.740435) (xy 132.239689 -384.692497) (xy 132.2321 -384.642839)
			(xy 132.231638 -384.617722) (xy 131.693158 -384.617722) (xy 131.692628 -384.644824) (xy 131.683818 -384.698307)
			(xy 131.675632 -384.724148) (xy 131.671822 -384.73507) (xy 131.674362 -384.757422) (xy 131.72694 -384.843274)
			(xy 131.74599 -384.85572) (xy 131.757166 -384.857498) (xy 131.786489 -384.862178) (xy 131.84366 -384.878231)
			(xy 131.898273 -384.901544) (xy 131.949412 -384.931727) (xy 131.996217 -384.968271) (xy 132.037902 -385.010563)
			(xy 132.073765 -385.057892) (xy 132.103205 -385.109462) (xy 132.125726 -385.164408) (xy 132.14095 -385.221805)
			(xy 132.148621 -385.280689) (xy 132.149088 -385.31038) (xy 132.148564 -385.341506) (xy 132.140159 -385.403188)
			(xy 132.132324 -385.433316) (xy 132.12953 -385.443476) (xy 132.13207 -385.463542) (xy 132.179314 -385.54533)
			(xy 132.195316 -385.557522) (xy 132.205476 -385.560062) (xy 132.23459 -385.568046) (xy 132.290556 -385.590683)
			(xy 132.343061 -385.62048) (xy 132.391194 -385.65692) (xy 132.434119 -385.69937) (xy 132.471093 -385.747094)
			(xy 132.501472 -385.799265) (xy 132.524731 -385.854975) (xy 132.540464 -385.91326) (xy 132.548401 -385.973107)
			(xy 132.548884 -386.003292) (xy 132.548759 -386.017427) (xy 132.546977 -386.045641) (xy 132.545328 -386.05968)
			(xy 132.544572 -386.068287) (xy 132.548209 -386.085166) (xy 132.55244 -386.0927) (xy 132.568188 -386.1181)
			(xy 132.572899 -386.125159) (xy 132.586004 -386.135929) (xy 132.593842 -386.139182) (xy 132.617226 -386.148359)
			(xy 132.661121 -386.172781) (xy 132.700816 -386.203564) (xy 132.735396 -386.239998) (xy 132.764065 -386.281246)
			(xy 132.786162 -386.326356) (xy 132.80118 -386.374291) (xy 132.808771 -386.423946) (xy 132.809234 -386.449062)
			(xy 132.80882 -386.473265) (xy 132.801745 -386.52115) (xy 132.787755 -386.56749) (xy 132.767151 -386.611291)
			(xy 132.754116 -386.631688) (xy 132.749324 -386.639642) (xy 132.745294 -386.657755) (xy 132.746242 -386.666994)
			(xy 132.75056 -386.697982) (xy 132.752254 -386.707275) (xy 132.761528 -386.723717) (xy 132.768594 -386.729986)
			(xy 132.790668 -386.748685) (xy 132.830443 -386.790692) (xy 132.864608 -386.837376) (xy 132.892618 -386.887993)
			(xy 132.914028 -386.941736) (xy 132.928495 -386.997748) (xy 132.935789 -387.055137) (xy 132.936234 -387.084062)
			(xy 136.983722 -387.084062) (xy 136.987793 -387.02844) (xy 136.999919 -386.974003) (xy 137.019842 -386.921912)
			(xy 137.047138 -386.873277) (xy 137.081224 -386.829134) (xy 137.121373 -386.790425) (xy 137.166731 -386.757974)
			(xy 137.216331 -386.732473) (xy 137.269115 -386.714466) (xy 137.323958 -386.704336) (xy 137.379692 -386.702299)
			(xy 137.435129 -386.708399) (xy 137.489086 -386.722505) (xy 137.540415 -386.744317) (xy 137.588021 -386.773371)
			(xy 137.630889 -386.809046) (xy 137.668106 -386.850583) (xy 137.698879 -386.897096) (xy 137.722551 -386.947593)
			(xy 137.738619 -387.001) (xy 137.746739 -387.056176) (xy 137.747248 -387.084062) (xy 137.746739 -387.111948)
			(xy 137.738619 -387.167124) (xy 137.722551 -387.220531) (xy 137.698879 -387.271028) (xy 137.668106 -387.317541)
			(xy 137.630889 -387.359078) (xy 137.588021 -387.394753) (xy 137.540415 -387.423807) (xy 137.489086 -387.445619)
			(xy 137.435129 -387.459725) (xy 137.379692 -387.465825) (xy 137.323958 -387.463788) (xy 137.269115 -387.453658)
			(xy 137.216331 -387.435651) (xy 137.166731 -387.41015) (xy 137.121373 -387.377699) (xy 137.081224 -387.33899)
			(xy 137.047138 -387.294847) (xy 137.019842 -387.246212) (xy 136.999919 -387.194121) (xy 136.987793 -387.139684)
			(xy 136.983722 -387.084062) (xy 132.936234 -387.084062) (xy 132.935645 -387.117383) (xy 132.925982 -387.183322)
			(xy 132.906856 -387.247161) (xy 132.893308 -387.27761) (xy 132.88905 -387.288072) (xy 132.889164 -387.310635)
			(xy 132.898904 -387.330987) (xy 132.907278 -387.33857) (xy 132.929504 -387.357268) (xy 132.969569 -387.399319)
			(xy 133.003992 -387.446101) (xy 133.03222 -387.496861) (xy 133.053799 -387.550786) (xy 133.068382 -387.607007)
			(xy 133.075735 -387.664621) (xy 133.076188 -387.693662) (xy 133.075698 -387.722666) (xy 133.068388 -387.780213)
			(xy 133.053867 -387.836374) (xy 133.032369 -387.890252) (xy 133.004237 -387.940982) (xy 132.969922 -387.987753)
			(xy 132.929974 -388.029814) (xy 132.907786 -388.0485) (xy 132.900674 -388.054088) (xy 132.89153 -388.069328)
			(xy 132.87629 -388.152132) (xy 132.879084 -388.169404) (xy 132.883656 -388.177532) (xy 132.896232 -388.200718)
			(xy 132.914106 -388.25034) (xy 132.923206 -388.302291) (xy 132.923788 -388.328662) (xy 132.92372 -388.338021)
			(xy 132.922576 -388.356703) (xy 132.921502 -388.366) (xy 132.920486 -388.37489) (xy 132.924296 -388.391654)
			(xy 132.968238 -388.461504) (xy 132.981954 -388.471918) (xy 132.990336 -388.474712) (xy 133.014364 -388.483182)
			(xy 133.059536 -388.506734) (xy 133.100341 -388.537233) (xy 133.13572 -388.573888) (xy 133.164756 -388.615747)
			(xy 133.186695 -388.661725) (xy 133.194298 -388.68604) (xy 133.195822 -388.691882) (xy 133.516116 -389.245602)
			(xy 133.52018 -389.24992) (xy 133.536368 -389.267642) (xy 133.563796 -389.307028) (xy 133.584942 -389.350114)
			(xy 133.599319 -389.395906) (xy 133.606596 -389.443346) (xy 133.607048 -389.467344) (xy 133.606647 -389.49215)
			(xy 133.598875 -389.541151) (xy 133.58353 -389.588332) (xy 133.560991 -389.632529) (xy 133.531811 -389.672654)
			(xy 133.496712 -389.707718) (xy 133.456557 -389.736857) (xy 133.412337 -389.759352) (xy 133.365141 -389.774649)
			(xy 133.316133 -389.782371) (xy 133.291326 -389.782812) (xy 133.265932 -389.782289) (xy 133.2158 -389.774162)
			(xy 133.167615 -389.758114) (xy 133.12262 -389.73456) (xy 133.081977 -389.704105) (xy 133.046734 -389.667537)
			(xy 133.0178 -389.625798) (xy 132.995921 -389.579966) (xy 132.988304 -389.555736) (xy 132.98678 -389.549894)
			(xy 132.666486 -388.996174) (xy 132.662422 -388.991856) (xy 132.646257 -388.974127) (xy 132.618891 -388.934723)
			(xy 132.597802 -388.891632) (xy 132.583476 -388.845846) (xy 132.576242 -388.79842) (xy 132.575808 -388.774432)
			(xy 132.575889 -388.762384) (xy 132.577672 -388.738355) (xy 132.579364 -388.726426) (xy 132.580634 -388.717536)
			(xy 132.577586 -388.700518) (xy 132.535422 -388.629652) (xy 132.522214 -388.618476) (xy 132.513832 -388.615428)
			(xy 132.492076 -388.607054) (xy 132.451219 -388.584608) (xy 132.414249 -388.55621) (xy 132.382028 -388.522522)
			(xy 132.355304 -388.484325) (xy 132.3347 -388.442509) (xy 132.320693 -388.398046) (xy 132.31361 -388.351971)
			(xy 132.313172 -388.328662) (xy 132.313741 -388.302289) (xy 132.322823 -388.250331) (xy 132.34071 -388.200711)
			(xy 132.353304 -388.177532) (xy 132.357876 -388.169404) (xy 132.36067 -388.152132) (xy 132.34543 -388.069328)
			(xy 132.336286 -388.054088) (xy 132.329174 -388.0485) (xy 132.306998 -388.0298) (xy 132.267052 -387.987737)
			(xy 132.232736 -387.940968) (xy 132.204598 -387.890241) (xy 132.183089 -387.836367) (xy 132.168553 -387.78021)
			(xy 132.161223 -387.722666) (xy 132.160772 -387.693662) (xy 132.161369 -387.660341) (xy 132.171028 -387.594403)
			(xy 132.190152 -387.530563) (xy 132.203698 -387.500114) (xy 132.207931 -387.489644) (xy 132.207826 -387.467088)
			(xy 132.198097 -387.446738) (xy 132.189728 -387.439154) (xy 132.167467 -387.420496) (xy 132.127403 -387.378439)
			(xy 132.092983 -387.33165) (xy 132.06476 -387.280882) (xy 132.043187 -387.226951) (xy 132.028611 -387.170724)
			(xy 132.021266 -387.113105) (xy 132.020818 -387.084062) (xy 132.021282 -387.055136) (xy 132.028565 -386.997745)
			(xy 132.043023 -386.941729) (xy 132.064425 -386.887982) (xy 132.09243 -386.83736) (xy 132.126591 -386.790672)
			(xy 132.166364 -386.748661) (xy 132.188458 -386.729986) (xy 132.19543 -386.723638) (xy 132.204688 -386.707235)
			(xy 132.206492 -386.697982) (xy 132.21081 -386.666994) (xy 132.21172 -386.657758) (xy 132.207693 -386.639657)
			(xy 132.202936 -386.631688) (xy 132.186631 -386.605841) (xy 132.162726 -386.549606) (xy 132.155438 -386.519928)
			(xy 132.153369 -386.511769) (xy 132.144674 -386.497367) (xy 132.13842 -386.491734) (xy 132.115306 -386.472684)
			(xy 132.108419 -386.467448) (xy 132.092194 -386.461476) (xy 132.083556 -386.461) (xy 132.053919 -386.459996)
			(xy 131.995254 -386.451346) (xy 131.938197 -386.435195) (xy 131.883703 -386.411811) (xy 131.832684 -386.381588)
			(xy 131.785994 -386.345031) (xy 131.744415 -386.302751) (xy 131.708643 -386.255456) (xy 131.679276 -386.203939)
			(xy 131.656807 -386.149062) (xy 131.641611 -386.091743) (xy 131.633943 -386.032942) (xy 131.633468 -386.003292)
			(xy 131.633989 -385.972229) (xy 131.642405 -385.910675) (xy 131.650232 -385.88061) (xy 131.653026 -385.87045)
			(xy 131.650486 -385.850638) (xy 131.602988 -385.768342) (xy 131.586986 -385.75615) (xy 131.576826 -385.75361)
			(xy 131.547737 -385.745583) (xy 131.49181 -385.722915) (xy 131.439344 -385.693099) (xy 131.39125 -385.656649)
			(xy 131.34836 -385.614198) (xy 131.311418 -385.566482) (xy 131.281063 -385.514326) (xy 131.257821 -385.458635)
			(xy 131.242096 -385.400375) (xy 131.234159 -385.340553) (xy 131.233672 -385.31038) (xy 131.234202 -385.279492)
			(xy 131.242506 -385.218277) (xy 131.258962 -385.158733) (xy 131.28327 -385.101941) (xy 131.298696 -385.075176)
			(xy 131.304538 -385.06527) (xy 131.306824 -385.042918) (xy 131.27355 -384.947668) (xy 131.257802 -384.931666)
			(xy 131.247134 -384.927602) (xy 131.223739 -384.918452) (xy 131.179844 -384.894025) (xy 131.14015 -384.863238)
			(xy 131.105571 -384.826799) (xy 131.076904 -384.785548) (xy 131.054808 -384.740434) (xy 131.039793 -384.692497)
			(xy 131.032204 -384.642839) (xy 131.031742 -384.617722) (xy 130.493008 -384.617722) (xy 130.492475 -384.644824)
			(xy 130.483667 -384.698306) (xy 130.475482 -384.724148) (xy 130.471672 -384.73507) (xy 130.474212 -384.757422)
			(xy 130.52679 -384.843274) (xy 130.54584 -384.85572) (xy 130.557016 -384.857498) (xy 130.586332 -384.862217)
			(xy 130.643503 -384.878264) (xy 130.698117 -384.901572) (xy 130.749256 -384.931749) (xy 130.796062 -384.968289)
			(xy 130.837748 -385.010577) (xy 130.873612 -385.057903) (xy 130.903053 -385.10947) (xy 130.925575 -385.164413)
			(xy 130.940799 -385.221808) (xy 130.948471 -385.28069) (xy 130.948938 -385.31038) (xy 130.948412 -385.341443)
			(xy 130.939999 -385.402996) (xy 130.932174 -385.433062) (xy 130.92938 -385.443222) (xy 130.93192 -385.463034)
			(xy 130.979418 -385.54533) (xy 130.99542 -385.557522) (xy 131.00558 -385.560062) (xy 131.034695 -385.568043)
			(xy 131.090661 -385.590681) (xy 131.143166 -385.620478) (xy 131.191298 -385.656918) (xy 131.234224 -385.699369)
			(xy 131.271197 -385.747094) (xy 131.301576 -385.799264) (xy 131.324835 -385.854975) (xy 131.340569 -385.91326)
			(xy 131.348505 -385.973107) (xy 131.348988 -386.003292) (xy 131.348863 -386.017427) (xy 131.347081 -386.045641)
			(xy 131.345432 -386.05968) (xy 131.344675 -386.068287) (xy 131.348313 -386.085167) (xy 131.352544 -386.0927)
			(xy 131.368292 -386.1181) (xy 131.373001 -386.12516) (xy 131.386107 -386.135929) (xy 131.393946 -386.139182)
			(xy 131.417331 -386.148357) (xy 131.461226 -386.172779) (xy 131.500921 -386.203562) (xy 131.5355 -386.239997)
			(xy 131.564169 -386.281245) (xy 131.586266 -386.326356) (xy 131.601284 -386.374291) (xy 131.608875 -386.423946)
			(xy 131.609338 -386.449062) (xy 131.608923 -386.473265) (xy 131.601848 -386.52115) (xy 131.587859 -386.56749)
			(xy 131.567255 -386.611291) (xy 131.55422 -386.631688) (xy 131.549429 -386.639643) (xy 131.545398 -386.657755)
			(xy 131.546346 -386.666994) (xy 131.550664 -386.697982) (xy 131.552357 -386.707275) (xy 131.561631 -386.723717)
			(xy 131.568698 -386.729986) (xy 131.590772 -386.748684) (xy 131.630547 -386.790691) (xy 131.664712 -386.837376)
			(xy 131.692723 -386.887993) (xy 131.714132 -386.941736) (xy 131.728599 -386.997748) (xy 131.735893 -387.055137)
			(xy 131.736338 -387.084062) (xy 131.735748 -387.117383) (xy 131.726086 -387.183322) (xy 131.70696 -387.247161)
			(xy 131.693412 -387.27761) (xy 131.689153 -387.288072) (xy 131.689266 -387.310635) (xy 131.699007 -387.330988)
			(xy 131.707382 -387.33857) (xy 131.729609 -387.357267) (xy 131.769674 -387.399318) (xy 131.804097 -387.4461)
			(xy 131.832324 -387.496861) (xy 131.853903 -387.550786) (xy 131.868486 -387.607007) (xy 131.875839 -387.664621)
			(xy 131.876292 -387.693662) (xy 131.875801 -387.722666) (xy 131.86849 -387.780212) (xy 131.85397 -387.836374)
			(xy 131.832472 -387.890252) (xy 131.80434 -387.940982) (xy 131.770025 -387.987753) (xy 131.730078 -388.029814)
			(xy 131.70789 -388.0485) (xy 131.700778 -388.054088) (xy 131.691634 -388.069328) (xy 131.676394 -388.152132)
			(xy 131.679188 -388.169404) (xy 131.68376 -388.177532) (xy 131.696337 -388.200718) (xy 131.71421 -388.25034)
			(xy 131.72331 -388.302291) (xy 131.723892 -388.328662) (xy 131.723824 -388.338021) (xy 131.72268 -388.356703)
			(xy 131.721606 -388.366) (xy 131.72059 -388.37489) (xy 131.7244 -388.391654) (xy 131.768342 -388.461504)
			(xy 131.782058 -388.471918) (xy 131.79044 -388.474712) (xy 131.814546 -388.48317) (xy 131.859836 -388.506802)
			(xy 131.900729 -388.537417) (xy 131.936159 -388.574219) (xy 131.9652 -388.616245) (xy 131.987095 -388.6624)
			(xy 131.994656 -388.686802) (xy 131.99618 -388.692644) (xy 132.315966 -389.245602) (xy 132.32003 -389.24992)
			(xy 132.336223 -389.267625) (xy 132.363587 -389.307034) (xy 132.384672 -389.350132) (xy 132.398991 -389.395923)
			(xy 132.406215 -389.443354) (xy 132.406644 -389.467344) (xy 132.406222 -389.492136) (xy 132.398459 -389.541109)
			(xy 132.383131 -389.588264) (xy 132.360615 -389.632441) (xy 132.331466 -389.672552) (xy 132.2964 -389.70761)
			(xy 132.256283 -389.736751) (xy 132.212101 -389.759257) (xy 132.164942 -389.774575) (xy 132.115968 -389.782328)
			(xy 132.091176 -389.782812) (xy 132.065781 -389.782333) (xy 132.015646 -389.774198) (xy 131.96746 -389.758143)
			(xy 131.922466 -389.734582) (xy 131.881823 -389.704121) (xy 131.846581 -389.667548) (xy 131.817648 -389.625804)
			(xy 131.79577 -389.579967) (xy 131.788154 -389.555736) (xy 131.78663 -389.549894) (xy 131.466082 -388.995412)
			(xy 131.462018 -388.991094) (xy 131.445913 -388.973438) (xy 131.418727 -388.934137) (xy 131.397777 -388.891187)
			(xy 131.383542 -388.845569) (xy 131.376347 -388.798326) (xy 131.375912 -388.774432) (xy 131.375993 -388.762384)
			(xy 131.377776 -388.738355) (xy 131.379468 -388.726426) (xy 131.380738 -388.717536) (xy 131.37769 -388.700518)
			(xy 131.335526 -388.629652) (xy 131.322318 -388.618476) (xy 131.313936 -388.615428) (xy 131.292181 -388.607051)
			(xy 131.251323 -388.584606) (xy 131.214354 -388.556209) (xy 131.182133 -388.522521) (xy 131.155409 -388.484324)
			(xy 131.134804 -388.442509) (xy 131.120797 -388.398046) (xy 131.113714 -388.35197) (xy 131.113276 -388.328662)
			(xy 131.113845 -388.302289) (xy 131.122927 -388.250331) (xy 131.140814 -388.20071) (xy 131.153408 -388.177532)
			(xy 131.15798 -388.169404) (xy 131.160774 -388.152132) (xy 131.145534 -388.069328) (xy 131.13639 -388.054088)
			(xy 131.129278 -388.0485) (xy 131.107103 -388.029799) (xy 131.067157 -387.987736) (xy 131.03284 -387.940967)
			(xy 131.004702 -387.89024) (xy 130.983193 -387.836367) (xy 130.968657 -387.780209) (xy 130.961327 -387.722666)
			(xy 130.960876 -387.693662) (xy 130.961473 -387.660341) (xy 130.971132 -387.594402) (xy 130.990256 -387.530563)
			(xy 131.003802 -387.500114) (xy 131.008034 -387.489643) (xy 131.007928 -387.467088) (xy 130.9982 -387.446738)
			(xy 130.989832 -387.439154) (xy 130.967572 -387.420495) (xy 130.927508 -387.378438) (xy 130.893088 -387.331649)
			(xy 130.864864 -387.280882) (xy 130.843291 -387.226951) (xy 130.828715 -387.170724) (xy 130.82137 -387.113105)
			(xy 130.820922 -387.084062) (xy 130.821384 -387.055136) (xy 130.828667 -386.997745) (xy 130.843125 -386.941729)
			(xy 130.864528 -386.887981) (xy 130.892533 -386.83736) (xy 130.926694 -386.790671) (xy 130.966468 -386.74866)
			(xy 130.988562 -386.729986) (xy 130.995534 -386.723639) (xy 131.004792 -386.707235) (xy 131.006596 -386.697982)
			(xy 131.010914 -386.666994) (xy 131.011823 -386.657758) (xy 131.007796 -386.639657) (xy 131.00304 -386.631688)
			(xy 130.986735 -386.60584) (xy 130.96283 -386.549606) (xy 130.955542 -386.519928) (xy 130.953472 -386.51177)
			(xy 130.944778 -386.497367) (xy 130.938524 -386.491734) (xy 130.91541 -386.472684) (xy 130.908522 -386.46745)
			(xy 130.892298 -386.461477) (xy 130.88366 -386.461) (xy 130.854023 -386.459992) (xy 130.795358 -386.451343)
			(xy 130.738301 -386.435192) (xy 130.683807 -386.411809) (xy 130.632788 -386.381586) (xy 130.586098 -386.345029)
			(xy 130.544519 -386.30275) (xy 130.508747 -386.255456) (xy 130.47938 -386.203939) (xy 130.456911 -386.149062)
			(xy 130.441715 -386.091743) (xy 130.434047 -386.032941) (xy 130.433572 -386.003292) (xy 130.434092 -385.972229)
			(xy 130.442509 -385.910675) (xy 130.450336 -385.88061) (xy 130.45313 -385.87045) (xy 130.45059 -385.850638)
			(xy 130.403092 -385.768342) (xy 130.38709 -385.75615) (xy 130.37693 -385.75361) (xy 130.347809 -385.745648)
			(xy 130.291842 -385.72301) (xy 130.239336 -385.693211) (xy 130.191202 -385.656769) (xy 130.148276 -385.614316)
			(xy 130.111303 -385.566589) (xy 130.080925 -385.514416) (xy 130.057668 -385.458703) (xy 130.041937 -385.400416)
			(xy 130.034003 -385.340566) (xy 130.033522 -385.31038) (xy 130.034045 -385.279492) (xy 130.04235 -385.218276)
			(xy 130.058808 -385.158732) (xy 130.083119 -385.101941) (xy 130.098546 -385.075176) (xy 130.104388 -385.06527)
			(xy 130.106674 -385.042918) (xy 130.0734 -384.947668) (xy 130.057652 -384.931666) (xy 130.046984 -384.927602)
			(xy 130.0236 -384.918425) (xy 129.979703 -384.894004) (xy 129.940007 -384.863222) (xy 129.905426 -384.826788)
			(xy 129.876757 -384.78554) (xy 129.85466 -384.740429) (xy 129.839644 -384.692494) (xy 129.832054 -384.642838)
			(xy 129.831592 -384.617722) (xy 129.293112 -384.617722) (xy 129.292579 -384.644824) (xy 129.283771 -384.698306)
			(xy 129.275586 -384.724148) (xy 129.271776 -384.73507) (xy 129.274316 -384.757422) (xy 129.326894 -384.843274)
			(xy 129.345944 -384.85572) (xy 129.35712 -384.857498) (xy 129.386437 -384.862214) (xy 129.443607 -384.878261)
			(xy 129.498221 -384.90157) (xy 129.549361 -384.931747) (xy 129.596167 -384.968288) (xy 129.637852 -385.010576)
			(xy 129.673716 -385.057902) (xy 129.703157 -385.10947) (xy 129.725679 -385.164413) (xy 129.740903 -385.221808)
			(xy 129.748575 -385.28069) (xy 129.749042 -385.31038) (xy 129.748519 -385.341506) (xy 129.740113 -385.403188)
			(xy 129.732278 -385.433316) (xy 129.729484 -385.443476) (xy 129.732024 -385.463542) (xy 129.779268 -385.54533)
			(xy 129.79527 -385.557522) (xy 129.80543 -385.560062) (xy 129.834535 -385.568077) (xy 129.890502 -385.590708)
			(xy 129.943008 -385.6205) (xy 129.991142 -385.656936) (xy 130.034068 -385.699383) (xy 130.071043 -385.747104)
			(xy 130.101423 -385.799271) (xy 130.124683 -385.85498) (xy 130.140418 -385.913262) (xy 130.148354 -385.973107)
			(xy 130.148838 -386.003292) (xy 130.148713 -386.017427) (xy 130.146931 -386.045641) (xy 130.145282 -386.05968)
			(xy 130.144518 -386.068287) (xy 130.148159 -386.085168) (xy 130.152394 -386.0927) (xy 130.168142 -386.1181)
			(xy 130.172835 -386.125173) (xy 130.185952 -386.135935) (xy 130.193796 -386.139182) (xy 130.21717 -386.148384)
			(xy 130.261067 -386.1728) (xy 130.300763 -386.203578) (xy 130.335345 -386.240009) (xy 130.364016 -386.281253)
			(xy 130.386115 -386.326361) (xy 130.401133 -386.374293) (xy 130.408725 -386.423947) (xy 130.409188 -386.449062)
			(xy 130.408765 -386.473264) (xy 130.401691 -386.521149) (xy 130.387704 -386.567489) (xy 130.367104 -386.611291)
			(xy 130.35407 -386.631688) (xy 130.349282 -386.639645) (xy 130.345248 -386.657756) (xy 130.346196 -386.666994)
			(xy 130.350514 -386.697982) (xy 130.352192 -386.707279) (xy 130.361475 -386.723721) (xy 130.368548 -386.729986)
			(xy 130.390633 -386.748672) (xy 130.430406 -386.790682) (xy 130.464568 -386.83737) (xy 130.492576 -386.887989)
			(xy 130.513984 -386.941733) (xy 130.52845 -386.997747) (xy 130.535743 -387.055136) (xy 130.536188 -387.084062)
			(xy 130.535594 -387.117383) (xy 130.525932 -387.183321) (xy 130.506808 -387.247161) (xy 130.493262 -387.27761)
			(xy 130.488986 -387.288068) (xy 130.489099 -387.310637) (xy 130.49885 -387.330991) (xy 130.507232 -387.33857)
			(xy 130.529469 -387.357255) (xy 130.569532 -387.399309) (xy 130.603952 -387.446094) (xy 130.632178 -387.496857)
			(xy 130.653755 -387.550783) (xy 130.668337 -387.607005) (xy 130.675689 -387.664621) (xy 130.676142 -387.693662)
			(xy 130.675669 -387.722667) (xy 130.668358 -387.780215) (xy 130.653836 -387.836377) (xy 130.632335 -387.890256)
			(xy 130.6042 -387.940986) (xy 130.569881 -387.987756) (xy 130.52993 -388.029816) (xy 130.50774 -388.0485)
			(xy 130.500628 -388.054088) (xy 130.491484 -388.069328) (xy 130.476244 -388.152132) (xy 130.479038 -388.169404)
			(xy 130.48361 -388.177532) (xy 130.496183 -388.20072) (xy 130.514058 -388.250341) (xy 130.52316 -388.302292)
			(xy 130.523742 -388.328662) (xy 130.523673 -388.338021) (xy 130.52253 -388.356703) (xy 130.521456 -388.366)
			(xy 130.52044 -388.37489) (xy 130.52425 -388.391654) (xy 130.568192 -388.461504) (xy 130.581908 -388.471918)
			(xy 130.59029 -388.474712) (xy 130.614308 -388.483207) (xy 130.659482 -388.506752) (xy 130.700289 -388.537246)
			(xy 130.73567 -388.573896) (xy 130.764708 -388.615751) (xy 130.786648 -388.661726) (xy 130.794252 -388.68604)
			(xy 130.795776 -388.691882) (xy 131.11607 -389.245602) (xy 131.120134 -389.24992) (xy 131.136328 -389.267624)
			(xy 131.163691 -389.307034) (xy 131.184776 -389.350131) (xy 131.199095 -389.395923) (xy 131.206319 -389.443354)
			(xy 131.206748 -389.467344) (xy 131.206323 -389.492136) (xy 131.198559 -389.541108) (xy 131.183231 -389.588263)
			(xy 131.160716 -389.63244) (xy 131.131567 -389.672551) (xy 131.096502 -389.707608) (xy 131.056385 -389.736749)
			(xy 131.012204 -389.759256) (xy 130.965046 -389.774574) (xy 130.916072 -389.782328) (xy 130.89128 -389.782812)
			(xy 130.865885 -389.782329) (xy 130.815751 -389.774195) (xy 130.767565 -389.758141) (xy 130.72257 -389.73458)
			(xy 130.681928 -389.70412) (xy 130.646685 -389.667547) (xy 130.617752 -389.625804) (xy 130.595874 -389.579967)
			(xy 130.588258 -389.555736) (xy 130.586734 -389.549894) (xy 130.26644 -388.996174) (xy 130.262376 -388.991856)
			(xy 130.246169 -388.974151) (xy 130.218746 -388.934759) (xy 130.197604 -388.891669) (xy 130.183231 -388.845874)
			(xy 130.175958 -388.798431) (xy 130.175508 -388.774432) (xy 130.17565 -388.76238) (xy 130.177556 -388.73835)
			(xy 130.179318 -388.726426) (xy 130.180588 -388.717536) (xy 130.17754 -388.700518) (xy 130.135376 -388.629652)
			(xy 130.122168 -388.618476) (xy 130.113786 -388.615428) (xy 130.092042 -388.607024) (xy 130.051183 -388.584585)
			(xy 130.014211 -388.556194) (xy 129.981988 -388.522509) (xy 129.955262 -388.484317) (xy 129.934656 -388.442504)
			(xy 129.920648 -388.398043) (xy 129.913564 -388.35197) (xy 129.913126 -388.328662) (xy 129.913688 -388.302289)
			(xy 129.922772 -388.25033) (xy 129.940662 -388.20071) (xy 129.953258 -388.177532) (xy 129.95783 -388.169404)
			(xy 129.960624 -388.152132) (xy 129.945384 -388.069328) (xy 129.93624 -388.054088) (xy 129.929128 -388.0485)
			(xy 129.906963 -388.029787) (xy 129.867015 -387.987728) (xy 129.832696 -387.940961) (xy 129.804556 -387.890236)
			(xy 129.783045 -387.836365) (xy 129.768508 -387.780208) (xy 129.761177 -387.722666) (xy 129.760726 -387.693662)
			(xy 129.761327 -387.660341) (xy 129.770986 -387.594403) (xy 129.790107 -387.530563) (xy 129.803652 -387.500114)
			(xy 129.8079 -387.489648) (xy 129.807796 -387.467086) (xy 129.798057 -387.446735) (xy 129.789682 -387.439154)
			(xy 129.767411 -387.420508) (xy 129.72735 -387.378447) (xy 129.692932 -387.331655) (xy 129.664711 -387.280886)
			(xy 129.643139 -387.226953) (xy 129.628564 -387.170725) (xy 129.62122 -387.113105) (xy 129.620772 -387.084062)
			(xy 129.621216 -387.055135) (xy 129.6285 -386.997742) (xy 129.64296 -386.941725) (xy 129.664365 -386.887977)
			(xy 129.692373 -386.837356) (xy 129.726538 -386.790668) (xy 129.766315 -386.748659) (xy 129.788412 -386.729986)
			(xy 129.795376 -386.723631) (xy 129.80464 -386.707233) (xy 129.806446 -386.697982) (xy 129.810764 -386.666994)
			(xy 129.811665 -386.657757) (xy 129.807642 -386.639658) (xy 129.80289 -386.631688) (xy 129.786581 -386.605843)
			(xy 129.762678 -386.549607) (xy 129.755392 -386.519928) (xy 129.753335 -386.511765) (xy 129.744633 -386.497364)
			(xy 129.738374 -386.491734) (xy 129.71526 -386.472684) (xy 129.708385 -386.46743) (xy 129.692151 -386.461469)
			(xy 129.68351 -386.461) (xy 129.653875 -386.459946) (xy 129.595212 -386.451303) (xy 129.538155 -386.435158)
			(xy 129.483661 -386.411781) (xy 129.432642 -386.381563) (xy 129.385952 -386.34501) (xy 129.344372 -386.302734)
			(xy 129.308599 -386.255444) (xy 129.279232 -386.20393) (xy 129.256762 -386.149055) (xy 129.241565 -386.091739)
			(xy 129.233897 -386.03294) (xy 129.233422 -386.003292) (xy 129.233944 -385.972229) (xy 129.242359 -385.910675)
			(xy 129.250186 -385.88061) (xy 129.25298 -385.87045) (xy 129.25044 -385.850638) (xy 129.202942 -385.768342)
			(xy 129.18694 -385.75615) (xy 129.17678 -385.75361) (xy 129.147701 -385.745547) (xy 129.091773 -385.722886)
			(xy 129.039307 -385.693075) (xy 128.991211 -385.656631) (xy 128.94832 -385.614184) (xy 128.911376 -385.566471)
			(xy 128.881019 -385.514319) (xy 128.857776 -385.45863) (xy 128.84205 -385.400372) (xy 128.834113 -385.340552)
			(xy 128.833626 -385.31038) (xy 128.834148 -385.279492) (xy 128.842454 -385.218276) (xy 128.858911 -385.158732)
			(xy 128.883223 -385.101941) (xy 128.89865 -385.075176) (xy 128.904492 -385.06527) (xy 128.906778 -385.042918)
			(xy 128.873504 -384.947668) (xy 128.857756 -384.931666) (xy 128.847088 -384.927602) (xy 128.823705 -384.918422)
			(xy 128.779808 -384.894003) (xy 128.740112 -384.863221) (xy 128.705531 -384.826787) (xy 128.676861 -384.78554)
			(xy 128.654764 -384.740429) (xy 128.639748 -384.692494) (xy 128.632158 -384.642838) (xy 128.631696 -384.617722)
			(xy 128.092962 -384.617722) (xy 128.092431 -384.644824) (xy 128.083622 -384.698307) (xy 128.075436 -384.724148)
			(xy 128.071626 -384.73507) (xy 128.074166 -384.757422) (xy 128.126744 -384.843274) (xy 128.145794 -384.85572)
			(xy 128.15697 -384.857498) (xy 128.186293 -384.862175) (xy 128.243464 -384.878228) (xy 128.298078 -384.901542)
			(xy 128.349217 -384.931725) (xy 128.396022 -384.96827) (xy 128.437706 -385.010562) (xy 128.473569 -385.057891)
			(xy 128.503009 -385.109462) (xy 128.52553 -385.164407) (xy 128.540754 -385.221805) (xy 128.548425 -385.280689)
			(xy 128.548892 -385.31038) (xy 128.548364 -385.341443) (xy 128.539953 -385.402996) (xy 128.532128 -385.433062)
			(xy 128.529334 -385.443222) (xy 128.531874 -385.463034) (xy 128.579372 -385.54533) (xy 128.595374 -385.557522)
			(xy 128.605534 -385.560062) (xy 128.63464 -385.568074) (xy 128.690606 -385.590706) (xy 128.743112 -385.620499)
			(xy 128.791246 -385.656934) (xy 128.834173 -385.699382) (xy 128.871147 -385.747103) (xy 128.901528 -385.799271)
			(xy 128.924787 -385.854979) (xy 128.940522 -385.913262) (xy 128.948458 -385.973107) (xy 128.948942 -386.003292)
			(xy 128.948817 -386.017427) (xy 128.947035 -386.045641) (xy 128.945386 -386.05968) (xy 128.944621 -386.068287)
			(xy 128.948263 -386.085168) (xy 128.952498 -386.0927) (xy 128.968246 -386.1181) (xy 128.972938 -386.125174)
			(xy 128.986056 -386.135935) (xy 128.9939 -386.139182) (xy 129.017275 -386.148381) (xy 129.061172 -386.172798)
			(xy 129.100868 -386.203577) (xy 129.135449 -386.240008) (xy 129.16412 -386.281252) (xy 129.186219 -386.32636)
			(xy 129.201237 -386.374293) (xy 129.208829 -386.423947) (xy 129.209292 -386.449062) (xy 129.208868 -386.473264)
			(xy 129.201794 -386.521149) (xy 129.187808 -386.567489) (xy 129.167207 -386.611291) (xy 129.154174 -386.631688)
			(xy 129.149386 -386.639645) (xy 129.145352 -386.657756) (xy 129.1463 -386.666994) (xy 129.150618 -386.697982)
			(xy 129.152294 -386.70728) (xy 129.161579 -386.723721) (xy 129.168652 -386.729986) (xy 129.190738 -386.748671)
			(xy 129.23051 -386.790682) (xy 129.264673 -386.837369) (xy 129.292681 -386.887988) (xy 129.314088 -386.941733)
			(xy 129.328554 -386.997747) (xy 129.335847 -387.055136) (xy 129.336292 -387.084062) (xy 129.335697 -387.117383)
			(xy 129.326036 -387.183321) (xy 129.306912 -387.247161) (xy 129.293366 -387.27761) (xy 129.289122 -387.288076)
			(xy 129.289236 -387.310633) (xy 129.298968 -387.330984) (xy 129.307336 -387.33857) (xy 129.329574 -387.357254)
			(xy 129.369636 -387.399309) (xy 129.404057 -387.446094) (xy 129.432282 -387.496857) (xy 129.453859 -387.550783)
			(xy 129.468441 -387.607005) (xy 129.475793 -387.664621) (xy 129.476246 -387.693662) (xy 129.475771 -387.722667)
			(xy 129.46846 -387.780214) (xy 129.453938 -387.836377) (xy 129.432438 -387.890255) (xy 129.404303 -387.940986)
			(xy 129.369985 -387.987756) (xy 129.330034 -388.029815) (xy 129.307844 -388.0485) (xy 129.300732 -388.054088)
			(xy 129.291588 -388.069328) (xy 129.276348 -388.152132) (xy 129.279142 -388.169404) (xy 129.283714 -388.177532)
			(xy 129.296287 -388.20072) (xy 129.314162 -388.25034) (xy 129.323264 -388.302291) (xy 129.323846 -388.328662)
			(xy 129.323777 -388.338021) (xy 129.322634 -388.356703) (xy 129.32156 -388.366) (xy 129.320544 -388.37489)
			(xy 129.324354 -388.391654) (xy 129.368296 -388.461504) (xy 129.382012 -388.471918) (xy 129.390394 -388.474712)
			(xy 129.41449 -388.483195) (xy 129.459781 -388.50682) (xy 129.500677 -388.53743) (xy 129.536108 -388.574227)
			(xy 129.565152 -388.61625) (xy 129.587048 -388.662401) (xy 129.59461 -388.686802) (xy 129.596134 -388.692644)
			(xy 129.91592 -389.245602) (xy 129.919984 -389.24992) (xy 129.936173 -389.267641) (xy 129.9636 -389.307028)
			(xy 129.984746 -389.350114) (xy 129.999123 -389.395906) (xy 130.0064 -389.443346) (xy 130.006852 -389.467344)
			(xy 130.006447 -389.49215) (xy 129.998675 -389.54115) (xy 129.983331 -389.588331) (xy 129.960791 -389.632528)
			(xy 129.931613 -389.672653) (xy 129.896514 -389.707717) (xy 129.85636 -389.736856) (xy 129.81214 -389.759351)
			(xy 129.764945 -389.774648) (xy 129.715937 -389.782371) (xy 129.69113 -389.782812) (xy 129.665737 -389.782285)
			(xy 129.615604 -389.774159) (xy 129.567419 -389.758112) (xy 129.522425 -389.734558) (xy 129.481782 -389.704104)
			(xy 129.446538 -389.667536) (xy 129.417604 -389.625798) (xy 129.395725 -389.579965) (xy 129.388108 -389.555736)
			(xy 129.386584 -389.549894) (xy 129.066036 -388.995412) (xy 129.061972 -388.991094) (xy 129.045872 -388.973421)
			(xy 129.018623 -388.934143) (xy 128.997611 -388.891204) (xy 128.983318 -388.845586) (xy 128.976071 -388.798334)
			(xy 128.975612 -388.774432) (xy 128.975754 -388.76238) (xy 128.97766 -388.73835) (xy 128.979422 -388.726426)
			(xy 128.980692 -388.717536) (xy 128.977644 -388.700518) (xy 128.93548 -388.629652) (xy 128.922272 -388.618476)
			(xy 128.91389 -388.615428) (xy 128.892147 -388.607022) (xy 128.851287 -388.584584) (xy 128.814316 -388.556192)
			(xy 128.782093 -388.522509) (xy 128.755367 -388.484316) (xy 128.73476 -388.442503) (xy 128.720752 -388.398043)
			(xy 128.713668 -388.351969) (xy 128.71323 -388.328662) (xy 128.713792 -388.302289) (xy 128.722876 -388.25033)
			(xy 128.740766 -388.20071) (xy 128.753362 -388.177532) (xy 128.757934 -388.169404) (xy 128.760728 -388.152132)
			(xy 128.745488 -388.069328) (xy 128.736344 -388.054088) (xy 128.729232 -388.0485) (xy 128.707068 -388.029786)
			(xy 128.667119 -387.987727) (xy 128.6328 -387.940961) (xy 128.60466 -387.890236) (xy 128.583149 -387.836364)
			(xy 128.568612 -387.780208) (xy 128.561281 -387.722666) (xy 128.56083 -387.693662) (xy 128.561431 -387.660341)
			(xy 128.571089 -387.594403) (xy 128.590211 -387.530563) (xy 128.603756 -387.500114) (xy 128.608003 -387.489647)
			(xy 128.607898 -387.467086) (xy 128.598161 -387.446735) (xy 128.589786 -387.439154) (xy 128.567516 -387.420507)
			(xy 128.527455 -387.378446) (xy 128.493037 -387.331655) (xy 128.464815 -387.280885) (xy 128.443243 -387.226953)
			(xy 128.428668 -387.170725) (xy 128.421324 -387.113105) (xy 128.420876 -387.084062) (xy 128.421319 -387.055135)
			(xy 128.428603 -386.997742) (xy 128.443063 -386.941725) (xy 128.464467 -386.887977) (xy 128.492476 -386.837356)
			(xy 128.526642 -386.790668) (xy 128.566419 -386.748659) (xy 128.588516 -386.729986) (xy 128.595481 -386.723631)
			(xy 128.604744 -386.707233) (xy 128.60655 -386.697982) (xy 128.610868 -386.666994) (xy 128.611769 -386.657757)
			(xy 128.607746 -386.639658) (xy 128.602994 -386.631688) (xy 128.586685 -386.605843) (xy 128.562782 -386.549607)
			(xy 128.555496 -386.519928) (xy 128.553438 -386.511766) (xy 128.544736 -386.497365) (xy 128.538478 -386.491734)
			(xy 128.515364 -386.472684) (xy 128.508488 -386.467431) (xy 128.492255 -386.46147) (xy 128.483614 -386.461)
			(xy 128.453979 -386.459943) (xy 128.395316 -386.4513) (xy 128.33826 -386.435155) (xy 128.283766 -386.411778)
			(xy 128.232746 -386.381561) (xy 128.186056 -386.345008) (xy 128.144476 -386.302733) (xy 128.108703 -386.255443)
			(xy 128.079336 -386.203929) (xy 128.056866 -386.149055) (xy 128.041669 -386.091739) (xy 128.034001 -386.03294)
			(xy 128.033526 -386.003292) (xy 128.034048 -385.972229) (xy 128.042463 -385.910675) (xy 128.05029 -385.88061)
			(xy 128.053084 -385.87045) (xy 128.050544 -385.850638) (xy 128.003046 -385.768342) (xy 127.987044 -385.75615)
			(xy 127.976884 -385.75361) (xy 127.947774 -385.745612) (xy 127.891806 -385.72298) (xy 127.839298 -385.693187)
			(xy 127.791163 -385.65675) (xy 127.748236 -385.614301) (xy 127.711262 -385.566578) (xy 127.680882 -385.514408)
			(xy 127.657624 -385.458697) (xy 127.641892 -385.400413) (xy 127.633958 -385.340565) (xy 127.633476 -385.31038)
			(xy 127.634005 -385.279492) (xy 127.64231 -385.218277) (xy 127.658766 -385.158733) (xy 127.683074 -385.101941)
			(xy 127.6985 -385.075176) (xy 127.704342 -385.06527) (xy 127.706628 -385.042918) (xy 127.673354 -384.947668)
			(xy 127.657606 -384.931666) (xy 127.646938 -384.927602) (xy 127.623544 -384.918449) (xy 127.579649 -384.894023)
			(xy 127.539954 -384.863237) (xy 127.505375 -384.826798) (xy 127.476708 -384.785547) (xy 127.454612 -384.740434)
			(xy 127.439597 -384.692497) (xy 127.432008 -384.642839) (xy 127.431546 -384.617722) (xy 126.893066 -384.617722)
			(xy 126.892535 -384.644824) (xy 126.883726 -384.698307) (xy 126.87554 -384.724148) (xy 126.87173 -384.73507)
			(xy 126.87427 -384.757422) (xy 126.926848 -384.843274) (xy 126.945898 -384.85572) (xy 126.957074 -384.857498)
			(xy 126.986398 -384.862172) (xy 127.043569 -384.878225) (xy 127.098182 -384.90154) (xy 127.149321 -384.931723)
			(xy 127.196126 -384.968268) (xy 127.23781 -385.010561) (xy 127.273674 -385.05789) (xy 127.303113 -385.109461)
			(xy 127.325634 -385.164407) (xy 127.340858 -385.221804) (xy 127.348529 -385.280689) (xy 127.348996 -385.31038)
			(xy 127.348471 -385.341443) (xy 127.340058 -385.402997) (xy 127.332232 -385.433062) (xy 127.329438 -385.443222)
			(xy 127.331978 -385.463034) (xy 127.379476 -385.54533) (xy 127.395478 -385.557522) (xy 127.405638 -385.560062)
			(xy 127.434745 -385.568071) (xy 127.490711 -385.590704) (xy 127.543217 -385.620497) (xy 127.591351 -385.656933)
			(xy 127.634277 -385.69938) (xy 127.671251 -385.747102) (xy 127.701632 -385.79927) (xy 127.724891 -385.854979)
			(xy 127.740626 -385.913262) (xy 127.748562 -385.973107) (xy 127.749046 -386.003292) (xy 127.748921 -386.017427)
			(xy 127.747139 -386.045641) (xy 127.74549 -386.05968) (xy 127.744724 -386.068287) (xy 127.748367 -386.085168)
			(xy 127.752602 -386.0927) (xy 127.76835 -386.1181) (xy 127.77306 -386.125162) (xy 127.786159 -386.135942)
			(xy 127.794004 -386.139182) (xy 127.817347 -386.148424) (xy 127.861191 -386.172876) (xy 127.900836 -386.203672)
			(xy 127.935371 -386.240107) (xy 127.964004 -386.281342) (xy 127.986076 -386.326431) (xy 128.001081 -386.374337)
			(xy 128.008673 -386.423961) (xy 128.009142 -386.449062) (xy 128.008726 -386.473265) (xy 128.001652 -386.52115)
			(xy 127.987663 -386.56749) (xy 127.967059 -386.611291) (xy 127.954024 -386.631688) (xy 127.949233 -386.639643)
			(xy 127.945202 -386.657755) (xy 127.94615 -386.666994) (xy 127.950468 -386.697982) (xy 127.95216 -386.707275)
			(xy 127.961435 -386.723717) (xy 127.968502 -386.729986) (xy 127.990577 -386.748683) (xy 128.030352 -386.790691)
			(xy 128.064517 -386.837375) (xy 128.092527 -386.887993) (xy 128.113936 -386.941736) (xy 128.128403 -386.997748)
			(xy 128.135697 -387.055137) (xy 128.136142 -387.084062) (xy 128.135552 -387.117383) (xy 128.12589 -387.183322)
			(xy 128.106764 -387.247161) (xy 128.093216 -387.27761) (xy 128.088955 -387.288071) (xy 128.089069 -387.310635)
			(xy 128.098811 -387.330988) (xy 128.107186 -387.33857) (xy 128.129413 -387.357266) (xy 128.169478 -387.399317)
			(xy 128.203901 -387.4461) (xy 128.232129 -387.496861) (xy 128.253707 -387.550785) (xy 128.26829 -387.607007)
			(xy 128.275643 -387.664621) (xy 128.276096 -387.693662) (xy 128.275603 -387.722666) (xy 128.268293 -387.780212)
			(xy 128.253773 -387.836374) (xy 128.232274 -387.890251) (xy 128.204143 -387.940982) (xy 128.169829 -387.987753)
			(xy 128.129881 -388.029814) (xy 128.107694 -388.0485) (xy 128.100582 -388.054088) (xy 128.091438 -388.069328)
			(xy 128.076198 -388.152132) (xy 128.078992 -388.169404) (xy 128.083564 -388.177532) (xy 128.096141 -388.200718)
			(xy 128.114014 -388.25034) (xy 128.123114 -388.302291) (xy 128.123696 -388.328662) (xy 128.123628 -388.338021)
			(xy 128.122484 -388.356703) (xy 128.12141 -388.366) (xy 128.120394 -388.37489) (xy 128.124204 -388.391654)
			(xy 128.168146 -388.461504) (xy 128.181862 -388.471918) (xy 128.190244 -388.474712) (xy 128.214273 -388.483178)
			(xy 128.259445 -388.506731) (xy 128.30025 -388.537231) (xy 128.335629 -388.573886) (xy 128.364665 -388.615746)
			(xy 128.386603 -388.661724) (xy 128.394206 -388.68604) (xy 128.39573 -388.691882) (xy 128.716024 -389.245602)
			(xy 128.720088 -389.24992) (xy 128.736278 -389.26764) (xy 128.763704 -389.307028) (xy 128.78485 -389.350114)
			(xy 128.799227 -389.395906) (xy 128.806504 -389.443346) (xy 128.806956 -389.467344) (xy 128.806547 -389.49215)
			(xy 128.798775 -389.54115) (xy 128.783431 -389.58833) (xy 128.760892 -389.632527) (xy 128.731714 -389.672651)
			(xy 128.696615 -389.707715) (xy 128.656462 -389.736854) (xy 128.612243 -389.75935) (xy 128.565048 -389.774648)
			(xy 128.516041 -389.782371) (xy 128.491234 -389.782812) (xy 128.465841 -389.782282) (xy 128.415708 -389.774156)
			(xy 128.367524 -389.75811) (xy 128.322529 -389.734556) (xy 128.281886 -389.704103) (xy 128.246643 -389.667535)
			(xy 128.217708 -389.625797) (xy 128.195829 -389.579965) (xy 128.188212 -389.555736) (xy 128.186688 -389.549894)
			(xy 127.866394 -388.996174) (xy 127.86233 -388.991856) (xy 127.846167 -388.974126) (xy 127.8188 -388.934722)
			(xy 127.79771 -388.891631) (xy 127.783384 -388.845846) (xy 127.77615 -388.79842) (xy 127.775716 -388.774432)
			(xy 127.775797 -388.762384) (xy 127.777579 -388.738355) (xy 127.779272 -388.726426) (xy 127.780542 -388.717536)
			(xy 127.777494 -388.700518) (xy 127.73533 -388.629652) (xy 127.722122 -388.618476) (xy 127.71374 -388.615428)
			(xy 127.691986 -388.607049) (xy 127.651128 -388.584604) (xy 127.614159 -388.556208) (xy 127.581937 -388.52252)
			(xy 127.555213 -388.484324) (xy 127.534608 -388.442508) (xy 127.520601 -388.398046) (xy 127.513518 -388.35197)
			(xy 127.51308 -388.328662) (xy 127.513648 -388.302289) (xy 127.522731 -388.250331) (xy 127.540618 -388.20071)
			(xy 127.553212 -388.177532) (xy 127.557784 -388.169404) (xy 127.560578 -388.152132) (xy 127.545338 -388.069328)
			(xy 127.536194 -388.054088) (xy 127.529082 -388.0485) (xy 127.506908 -388.029798) (xy 127.466961 -387.987736)
			(xy 127.432645 -387.940967) (xy 127.404507 -387.89024) (xy 127.382998 -387.836367) (xy 127.368461 -387.780209)
			(xy 127.361131 -387.722666) (xy 127.36068 -387.693662) (xy 127.361276 -387.660341) (xy 127.370936 -387.594402)
			(xy 127.390059 -387.530563) (xy 127.403606 -387.500114) (xy 127.407836 -387.489643) (xy 127.407731 -387.467088)
			(xy 127.398003 -387.446738) (xy 127.389636 -387.439154) (xy 127.367376 -387.420494) (xy 127.327313 -387.378437)
			(xy 127.292892 -387.331649) (xy 127.264668 -387.280881) (xy 127.243095 -387.226951) (xy 127.228519 -387.170724)
			(xy 127.221174 -387.113105) (xy 127.220726 -387.084062) (xy 127.221187 -387.055136) (xy 127.22847 -386.997744)
			(xy 127.242928 -386.941728) (xy 127.264331 -386.887981) (xy 127.292336 -386.83736) (xy 127.326498 -386.790671)
			(xy 127.366271 -386.74866) (xy 127.388366 -386.729986) (xy 127.395339 -386.72364) (xy 127.404596 -386.707235)
			(xy 127.4064 -386.697982) (xy 127.410718 -386.666994) (xy 127.411627 -386.657757) (xy 127.4076 -386.639657)
			(xy 127.402844 -386.631688) (xy 127.38654 -386.60584) (xy 127.362634 -386.549606) (xy 127.355346 -386.519928)
			(xy 127.353275 -386.51177) (xy 127.344582 -386.497367) (xy 127.338328 -386.491734) (xy 127.315214 -386.472684)
			(xy 127.308383 -386.467479) (xy 127.292291 -386.461508) (xy 127.283718 -386.461) (xy 127.254083 -386.459939)
			(xy 127.19542 -386.451297) (xy 127.138364 -386.435153) (xy 127.08387 -386.411776) (xy 127.032851 -386.381559)
			(xy 126.98616 -386.345007) (xy 126.94458 -386.302732) (xy 126.908807 -386.255442) (xy 126.87944 -386.203929)
			(xy 126.85697 -386.149055) (xy 126.841773 -386.091739) (xy 126.834105 -386.03294) (xy 126.83363 -386.003292)
			(xy 126.834151 -385.972229) (xy 126.842567 -385.910675) (xy 126.850394 -385.88061) (xy 126.853188 -385.87045)
			(xy 126.850648 -385.850638) (xy 126.80315 -385.768342) (xy 126.787148 -385.75615) (xy 126.776988 -385.75361)
			(xy 126.747878 -385.745609) (xy 126.69191 -385.722978) (xy 126.639403 -385.693185) (xy 126.591268 -385.656749)
			(xy 126.548341 -385.6143) (xy 126.511366 -385.566577) (xy 126.480986 -385.514408) (xy 126.457728 -385.458697)
			(xy 126.441996 -385.400412) (xy 126.434062 -385.340565) (xy 126.43358 -385.31038) (xy 126.434109 -385.279492)
			(xy 126.442413 -385.218277) (xy 126.458869 -385.158733) (xy 126.483178 -385.101941) (xy 126.498604 -385.075176)
			(xy 126.504446 -385.06527) (xy 126.506732 -385.042918) (xy 126.473458 -384.947668) (xy 126.45771 -384.931666)
			(xy 126.447042 -384.927602) (xy 126.423649 -384.918447) (xy 126.379753 -384.894022) (xy 126.340059 -384.863235)
			(xy 126.30548 -384.826797) (xy 126.276812 -384.785547) (xy 126.254716 -384.740434) (xy 126.239701 -384.692496)
			(xy 126.232112 -384.642839) (xy 126.23165 -384.617722) (xy 125.69317 -384.617722) (xy 125.692639 -384.644824)
			(xy 125.68383 -384.698307) (xy 125.675644 -384.724148) (xy 125.671834 -384.73507) (xy 125.674374 -384.757422)
			(xy 125.726952 -384.843528) (xy 125.745748 -384.85572) (xy 125.757178 -384.857498) (xy 125.786472 -384.862279)
			(xy 125.843606 -384.878356) (xy 125.898182 -384.901685) (xy 125.949285 -384.931874) (xy 125.996055 -384.968417)
			(xy 126.037709 -385.010699) (xy 126.073547 -385.058011) (xy 126.102968 -385.10956) (xy 126.125477 -385.16448)
			(xy 126.140698 -385.221848) (xy 126.148374 -385.280703) (xy 126.148846 -385.31038) (xy 126.148319 -385.341443)
			(xy 126.139907 -385.402996) (xy 126.132082 -385.433062) (xy 126.129288 -385.443222) (xy 126.131828 -385.463034)
			(xy 126.179326 -385.54533) (xy 126.195328 -385.557522) (xy 126.205488 -385.560062) (xy 126.234604 -385.568038)
			(xy 126.29057 -385.590676) (xy 126.343075 -385.620475) (xy 126.391207 -385.656916) (xy 126.434133 -385.699367)
			(xy 126.471106 -385.747092) (xy 126.501485 -385.799263) (xy 126.524743 -385.854974) (xy 126.540477 -385.913259)
			(xy 126.548413 -385.973106) (xy 126.548896 -386.003292) (xy 126.548771 -386.017427) (xy 126.546989 -386.045641)
			(xy 126.54534 -386.05968) (xy 126.544582 -386.068287) (xy 126.54822 -386.085167) (xy 126.552452 -386.0927)
			(xy 126.5682 -386.1181) (xy 126.572907 -386.125162) (xy 126.586014 -386.13593) (xy 126.593854 -386.139182)
			(xy 126.617241 -386.148352) (xy 126.661136 -386.172776) (xy 126.70083 -386.20356) (xy 126.735409 -386.239996)
			(xy 126.764078 -386.281244) (xy 126.786175 -386.326355) (xy 126.801192 -386.37429) (xy 126.808783 -386.423946)
			(xy 126.809246 -386.449062) (xy 126.80883 -386.473265) (xy 126.801755 -386.52115) (xy 126.787766 -386.56749)
			(xy 126.767163 -386.611291) (xy 126.754128 -386.631688) (xy 126.749337 -386.639643) (xy 126.745306 -386.657756)
			(xy 126.746254 -386.666994) (xy 126.750572 -386.697982) (xy 126.752262 -386.707276) (xy 126.761538 -386.723718)
			(xy 126.768606 -386.729986) (xy 126.790682 -386.748682) (xy 126.830457 -386.79069) (xy 126.864621 -386.837375)
			(xy 126.892631 -386.887992) (xy 126.91404 -386.941735) (xy 126.928507 -386.997748) (xy 126.935801 -387.055137)
			(xy 126.936246 -387.084062) (xy 126.935656 -387.117383) (xy 126.925993 -387.183322) (xy 126.906867 -387.247161)
			(xy 126.89332 -387.27761) (xy 126.889058 -387.288071) (xy 126.889172 -387.310635) (xy 126.898914 -387.330988)
			(xy 126.90729 -387.33857) (xy 126.929518 -387.357265) (xy 126.969583 -387.399317) (xy 127.004005 -387.446099)
			(xy 127.032233 -387.49686) (xy 127.053811 -387.550785) (xy 127.068394 -387.607007) (xy 127.075747 -387.664621)
			(xy 127.0762 -387.693662) (xy 127.075742 -387.722668) (xy 127.06843 -387.780216) (xy 127.053906 -387.83638)
			(xy 127.032403 -387.890259) (xy 127.004266 -387.940989) (xy 126.969944 -387.987758) (xy 126.929989 -388.029816)
			(xy 126.907798 -388.0485) (xy 126.900686 -388.054088) (xy 126.891542 -388.069328) (xy 126.876302 -388.152132)
			(xy 126.879096 -388.169404) (xy 126.883668 -388.177532) (xy 126.896237 -388.200722) (xy 126.914115 -388.250341)
			(xy 126.923218 -388.302292) (xy 126.9238 -388.328662) (xy 126.923732 -388.338021) (xy 126.922588 -388.356703)
			(xy 126.921514 -388.366) (xy 126.920498 -388.37489) (xy 126.924308 -388.391654) (xy 126.96825 -388.461504)
			(xy 126.981966 -388.471918) (xy 126.990348 -388.474712) (xy 127.014378 -388.483175) (xy 127.05955 -388.506729)
			(xy 127.100355 -388.53723) (xy 127.135734 -388.573886) (xy 127.164769 -388.615746) (xy 127.186707 -388.661724)
			(xy 127.19431 -388.68604) (xy 127.195834 -388.691882) (xy 127.516128 -389.245602) (xy 127.520192 -389.24992)
			(xy 127.536382 -389.26764) (xy 127.563809 -389.307027) (xy 127.584954 -389.350114) (xy 127.599331 -389.395906)
			(xy 127.606608 -389.443346) (xy 127.60706 -389.467344) (xy 127.606647 -389.49215) (xy 127.598875 -389.541149)
			(xy 127.583531 -389.588329) (xy 127.560993 -389.632525) (xy 127.531815 -389.67265) (xy 127.496717 -389.707714)
			(xy 127.456564 -389.736853) (xy 127.412346 -389.759349) (xy 127.365151 -389.774647) (xy 127.316144 -389.782371)
			(xy 127.291338 -389.782812) (xy 127.265945 -389.782278) (xy 127.215813 -389.774153) (xy 127.167628 -389.758107)
			(xy 127.122634 -389.734554) (xy 127.08199 -389.704101) (xy 127.046747 -389.667534) (xy 127.017812 -389.625797)
			(xy 126.995933 -389.579965) (xy 126.988316 -389.555736) (xy 126.986792 -389.549894) (xy 126.666498 -388.996174)
			(xy 126.662434 -388.991856) (xy 126.646271 -388.974125) (xy 126.618904 -388.934722) (xy 126.597815 -388.891631)
			(xy 126.583488 -388.845846) (xy 126.576254 -388.79842) (xy 126.57582 -388.774432) (xy 126.575901 -388.762384)
			(xy 126.577683 -388.738355) (xy 126.579376 -388.726426) (xy 126.580646 -388.717536) (xy 126.577598 -388.700518)
			(xy 126.535434 -388.629652) (xy 126.522226 -388.618476) (xy 126.513844 -388.615428) (xy 126.492091 -388.607047)
			(xy 126.451233 -388.584603) (xy 126.414263 -388.556207) (xy 126.382042 -388.522519) (xy 126.355317 -388.484323)
			(xy 126.334712 -388.442508) (xy 126.320705 -388.398046) (xy 126.313622 -388.35197) (xy 126.313184 -388.328662)
			(xy 126.313752 -388.302289) (xy 126.322834 -388.250331) (xy 126.340722 -388.20071) (xy 126.353316 -388.177532)
			(xy 126.357888 -388.169404) (xy 126.360682 -388.152132) (xy 126.345442 -388.069328) (xy 126.336298 -388.054088)
			(xy 126.329186 -388.0485) (xy 126.307012 -388.029797) (xy 126.267066 -387.987735) (xy 126.232749 -387.940966)
			(xy 126.204611 -387.89024) (xy 126.183102 -387.836367) (xy 126.168565 -387.780209) (xy 126.161235 -387.722666)
			(xy 126.160784 -387.693662) (xy 126.16138 -387.660341) (xy 126.17104 -387.594402) (xy 126.190163 -387.530563)
			(xy 126.20371 -387.500114) (xy 126.207939 -387.489643) (xy 126.207834 -387.467088) (xy 126.198107 -387.446739)
			(xy 126.18974 -387.439154) (xy 126.167481 -387.420493) (xy 126.127417 -387.378437) (xy 126.092997 -387.331648)
			(xy 126.064773 -387.280881) (xy 126.043199 -387.226951) (xy 126.028623 -387.170724) (xy 126.021278 -387.113105)
			(xy 126.02083 -387.084062) (xy 126.021289 -387.055136) (xy 126.028573 -386.997744) (xy 126.043031 -386.941728)
			(xy 126.064433 -386.887981) (xy 126.092439 -386.837359) (xy 126.126601 -386.790671) (xy 126.166375 -386.74866)
			(xy 126.18847 -386.729986) (xy 126.195443 -386.72364) (xy 126.2047 -386.707235) (xy 126.206504 -386.697982)
			(xy 126.210822 -386.666994) (xy 126.21173 -386.657757) (xy 126.207704 -386.639657) (xy 126.202948 -386.631688)
			(xy 126.186635 -386.605845) (xy 126.162735 -386.549608) (xy 126.15545 -386.519928) (xy 126.153378 -386.51177)
			(xy 126.144685 -386.497368) (xy 126.138432 -386.491734) (xy 126.115318 -386.472684) (xy 126.108428 -386.467453)
			(xy 126.092205 -386.461478) (xy 126.083568 -386.461) (xy 126.053932 -386.459985) (xy 125.995267 -386.451337)
			(xy 125.93821 -386.435187) (xy 125.883716 -386.411805) (xy 125.832697 -386.381582) (xy 125.786007 -386.345026)
			(xy 125.744427 -386.302747) (xy 125.708655 -386.255454) (xy 125.679288 -386.203937) (xy 125.656819 -386.149061)
			(xy 125.641623 -386.091742) (xy 125.633955 -386.032941) (xy 125.63348 -386.003292) (xy 125.634 -385.972229)
			(xy 125.642417 -385.910675) (xy 125.650244 -385.88061) (xy 125.653038 -385.87045) (xy 125.650498 -385.850638)
			(xy 125.603 -385.768342) (xy 125.586998 -385.75615) (xy 125.576838 -385.75361) (xy 125.547719 -385.745643)
			(xy 125.491751 -385.723005) (xy 125.439245 -385.693207) (xy 125.391111 -385.656766) (xy 125.348185 -385.614314)
			(xy 125.311212 -385.566587) (xy 125.280833 -385.514415) (xy 125.257576 -385.458702) (xy 125.241845 -385.400415)
			(xy 125.233911 -385.340566) (xy 125.23343 -385.31038) (xy 125.233905 -385.279458) (xy 125.242187 -385.218171)
			(xy 125.258652 -385.158559) (xy 125.282999 -385.10171) (xy 125.298454 -385.074922) (xy 125.30455 -385.06527)
			(xy 125.306836 -385.042918) (xy 125.273308 -384.947668) (xy 125.25756 -384.931666) (xy 125.246892 -384.927602)
			(xy 125.223543 -384.918376) (xy 125.179698 -384.893922) (xy 125.140053 -384.863123) (xy 125.105518 -384.826686)
			(xy 125.076886 -384.785449) (xy 125.054815 -384.740358) (xy 125.039812 -384.692449) (xy 125.032222 -384.642823)
			(xy 125.031754 -384.617722) (xy 124.49302 -384.617722) (xy 124.492487 -384.644824) (xy 124.483679 -384.698306)
			(xy 124.475494 -384.724148) (xy 124.471684 -384.73507) (xy 124.474224 -384.757422) (xy 124.526802 -384.843274)
			(xy 124.545852 -384.85572) (xy 124.557028 -384.857498) (xy 124.586346 -384.862208) (xy 124.643516 -384.878256)
			(xy 124.69813 -384.901565) (xy 124.74927 -384.931744) (xy 124.796076 -384.968285) (xy 124.837761 -385.010574)
			(xy 124.873625 -385.0579) (xy 124.903065 -385.109468) (xy 124.925587 -385.164412) (xy 124.940811 -385.221807)
			(xy 124.948483 -385.28069) (xy 124.94895 -385.31038) (xy 124.948423 -385.341443) (xy 124.940011 -385.402996)
			(xy 124.932186 -385.433062) (xy 124.929392 -385.443222) (xy 124.931932 -385.463034) (xy 124.97943 -385.54533)
			(xy 124.995432 -385.557522) (xy 125.005592 -385.560062) (xy 125.034709 -385.568035) (xy 125.090675 -385.590674)
			(xy 125.14318 -385.620473) (xy 125.191312 -385.656914) (xy 125.234237 -385.699366) (xy 125.27121 -385.747091)
			(xy 125.301589 -385.799262) (xy 125.324847 -385.854974) (xy 125.340581 -385.913259) (xy 125.348517 -385.973106)
			(xy 125.349 -386.003292) (xy 125.348875 -386.017427) (xy 125.347093 -386.045641) (xy 125.345444 -386.05968)
			(xy 125.344685 -386.068287) (xy 125.348324 -386.085167) (xy 125.352556 -386.0927) (xy 125.368304 -386.1181)
			(xy 125.372997 -386.125176) (xy 125.386107 -386.135948) (xy 125.393958 -386.139182) (xy 125.417312 -386.148395)
			(xy 125.461155 -386.172853) (xy 125.500798 -386.203656) (xy 125.535331 -386.240095) (xy 125.563962 -386.281334)
			(xy 125.586032 -386.326426) (xy 125.601036 -386.374335) (xy 125.608627 -386.42396) (xy 125.609096 -386.449062)
			(xy 125.608671 -386.473264) (xy 125.601598 -386.521149) (xy 125.587611 -386.567488) (xy 125.567011 -386.61129)
			(xy 125.553978 -386.631688) (xy 125.549191 -386.639645) (xy 125.545156 -386.657756) (xy 125.546104 -386.666994)
			(xy 125.550422 -386.697982) (xy 125.552097 -386.70728) (xy 125.561382 -386.723721) (xy 125.568456 -386.729986)
			(xy 125.590543 -386.74867) (xy 125.630315 -386.790681) (xy 125.664477 -386.837369) (xy 125.692485 -386.887988)
			(xy 125.713892 -386.941733) (xy 125.728358 -386.997747) (xy 125.735651 -387.055136) (xy 125.736096 -387.084062)
			(xy 125.735501 -387.117383) (xy 125.72584 -387.183321) (xy 125.706716 -387.247161) (xy 125.69317 -387.27761)
			(xy 125.688925 -387.288075) (xy 125.689039 -387.310634) (xy 125.698771 -387.330985) (xy 125.70714 -387.33857)
			(xy 125.729358 -387.357278) (xy 125.769425 -387.399326) (xy 125.80385 -387.446105) (xy 125.832079 -387.496864)
			(xy 125.85366 -387.550788) (xy 125.868244 -387.607008) (xy 125.875597 -387.664622) (xy 125.87605 -387.693662)
			(xy 125.875574 -387.722667) (xy 125.868263 -387.780214) (xy 125.853741 -387.836377) (xy 125.832241 -387.890255)
			(xy 125.804106 -387.940985) (xy 125.769788 -387.987755) (xy 125.729837 -388.029815) (xy 125.707648 -388.0485)
			(xy 125.700536 -388.054088) (xy 125.691392 -388.069328) (xy 125.676152 -388.152132) (xy 125.678946 -388.169404)
			(xy 125.683518 -388.177532) (xy 125.696091 -388.20072) (xy 125.713966 -388.25034) (xy 125.723068 -388.302291)
			(xy 125.72365 -388.328662) (xy 125.723581 -388.338021) (xy 125.722438 -388.356703) (xy 125.721364 -388.366)
			(xy 125.720348 -388.37489) (xy 125.724158 -388.391654) (xy 125.7681 -388.461504) (xy 125.781816 -388.471918)
			(xy 125.790198 -388.474712) (xy 125.814218 -388.483202) (xy 125.859391 -388.506749) (xy 125.900198 -388.537244)
			(xy 125.935579 -388.573894) (xy 125.964616 -388.61575) (xy 125.986556 -388.661726) (xy 125.99416 -388.68604)
			(xy 125.995684 -388.691882) (xy 126.315978 -389.245602) (xy 126.320042 -389.24992) (xy 126.336237 -389.267623)
			(xy 126.3636 -389.307033) (xy 126.384684 -389.350131) (xy 126.399003 -389.395923) (xy 126.406228 -389.443354)
			(xy 126.406656 -389.467344) (xy 126.406223 -389.492135) (xy 126.39846 -389.541107) (xy 126.383132 -389.588261)
			(xy 126.360617 -389.632438) (xy 126.331469 -389.672548) (xy 126.296405 -389.707605) (xy 126.25629 -389.736746)
			(xy 126.212109 -389.759254) (xy 126.164952 -389.774573) (xy 126.115979 -389.782327) (xy 126.091188 -389.782812)
			(xy 126.065793 -389.782322) (xy 126.015659 -389.77419) (xy 125.967473 -389.758136) (xy 125.922479 -389.734576)
			(xy 125.881836 -389.704118) (xy 125.846594 -389.667545) (xy 125.81766 -389.625803) (xy 125.795782 -389.579967)
			(xy 125.788166 -389.555736) (xy 125.786642 -389.549894) (xy 125.466348 -388.996174) (xy 125.462284 -388.991856)
			(xy 125.446078 -388.97415) (xy 125.418655 -388.934758) (xy 125.397513 -388.891668) (xy 125.383139 -388.845874)
			(xy 125.375866 -388.798431) (xy 125.375416 -388.774432) (xy 125.375558 -388.76238) (xy 125.377464 -388.73835)
			(xy 125.379226 -388.726426) (xy 125.380496 -388.717536) (xy 125.377448 -388.700518) (xy 125.335284 -388.629652)
			(xy 125.322076 -388.618476) (xy 125.313694 -388.615428) (xy 125.291951 -388.60702) (xy 125.251092 -388.584582)
			(xy 125.214121 -388.556191) (xy 125.181897 -388.522508) (xy 125.155171 -388.484315) (xy 125.134564 -388.442503)
			(xy 125.120556 -388.398043) (xy 125.113472 -388.351969) (xy 125.113034 -388.328662) (xy 125.113595 -388.302289)
			(xy 125.122679 -388.25033) (xy 125.14057 -388.20071) (xy 125.153166 -388.177532) (xy 125.157738 -388.169404)
			(xy 125.160532 -388.152132) (xy 125.145292 -388.069328) (xy 125.136148 -388.054088) (xy 125.129036 -388.0485)
			(xy 125.106873 -388.029785) (xy 125.066924 -387.987726) (xy 125.032605 -387.94096) (xy 125.004464 -387.890236)
			(xy 124.982953 -387.836364) (xy 124.968416 -387.780208) (xy 124.961085 -387.722666) (xy 124.960634 -387.693662)
			(xy 124.961235 -387.660341) (xy 124.970893 -387.594403) (xy 124.990015 -387.530563) (xy 125.00356 -387.500114)
			(xy 125.007806 -387.489647) (xy 125.007701 -387.467087) (xy 124.997964 -387.446735) (xy 124.98959 -387.439154)
			(xy 124.967321 -387.420506) (xy 124.927259 -387.378445) (xy 124.892841 -387.331654) (xy 124.864619 -387.280885)
			(xy 124.843047 -387.226953) (xy 124.828472 -387.170725) (xy 124.821128 -387.113105) (xy 124.82068 -387.084062)
			(xy 124.821121 -387.055135) (xy 124.828405 -386.997742) (xy 124.842865 -386.941725) (xy 124.86427 -386.887977)
			(xy 124.892279 -386.837355) (xy 124.926445 -386.790668) (xy 124.966223 -386.748659) (xy 124.98832 -386.729986)
			(xy 124.995285 -386.723632) (xy 125.004548 -386.707234) (xy 125.006354 -386.697982) (xy 125.010672 -386.666994)
			(xy 125.011572 -386.657757) (xy 125.00755 -386.639658) (xy 125.002798 -386.631688) (xy 124.986489 -386.605843)
			(xy 124.962586 -386.549607) (xy 124.9553 -386.519928) (xy 124.953241 -386.511766) (xy 124.94454 -386.497365)
			(xy 124.938282 -386.491734) (xy 124.915168 -386.472684) (xy 124.908349 -386.46746) (xy 124.892248 -386.461501)
			(xy 124.883672 -386.461) (xy 124.854036 -386.459981) (xy 124.795371 -386.451334) (xy 124.738314 -386.435184)
			(xy 124.68382 -386.411802) (xy 124.632801 -386.381581) (xy 124.586111 -386.345024) (xy 124.544532 -386.302746)
			(xy 124.508759 -386.255453) (xy 124.479393 -386.203937) (xy 124.456923 -386.14906) (xy 124.441727 -386.091742)
			(xy 124.434059 -386.032941) (xy 124.433584 -386.003292) (xy 124.434104 -385.972229) (xy 124.442521 -385.910675)
			(xy 124.450348 -385.88061) (xy 124.453142 -385.87045) (xy 124.450602 -385.850638) (xy 124.403104 -385.768342)
			(xy 124.387102 -385.75615) (xy 124.376942 -385.75361) (xy 124.347824 -385.74564) (xy 124.291856 -385.723003)
			(xy 124.23935 -385.693206) (xy 124.191216 -385.656765) (xy 124.14829 -385.614313) (xy 124.111316 -385.566587)
			(xy 124.080938 -385.514414) (xy 124.057681 -385.458701) (xy 124.041949 -385.400415) (xy 124.034015 -385.340566)
			(xy 124.033534 -385.31038) (xy 124.034055 -385.279492) (xy 124.042361 -385.218276) (xy 124.058819 -385.158732)
			(xy 124.08313 -385.10194) (xy 124.098558 -385.075176) (xy 124.1044 -385.06527) (xy 124.106686 -385.042918)
			(xy 124.073412 -384.947668) (xy 124.057664 -384.931666) (xy 124.046996 -384.927602) (xy 124.023615 -384.918418)
			(xy 123.979717 -384.893999) (xy 123.940021 -384.863219) (xy 123.90544 -384.826785) (xy 123.87677 -384.785539)
			(xy 123.854672 -384.740428) (xy 123.839656 -384.692493) (xy 123.832066 -384.642838) (xy 123.831604 -384.617722)
			(xy 123.293124 -384.617722) (xy 123.292595 -384.644824) (xy 123.283785 -384.698307) (xy 123.275598 -384.724148)
			(xy 123.271788 -384.73507) (xy 123.274328 -384.757422) (xy 123.326906 -384.843274) (xy 123.345956 -384.85572)
			(xy 123.357132 -384.857498) (xy 123.38645 -384.862204) (xy 123.443621 -384.878253) (xy 123.498235 -384.901563)
			(xy 123.549374 -384.931742) (xy 123.59618 -384.968283) (xy 123.637865 -385.010573) (xy 123.673729 -385.057899)
			(xy 123.703169 -385.109468) (xy 123.725691 -385.164411) (xy 123.740915 -385.221807) (xy 123.748587 -385.28069)
			(xy 123.749054 -385.31038) (xy 123.748531 -385.341506) (xy 123.740125 -385.403188) (xy 123.73229 -385.433316)
			(xy 123.729496 -385.443476) (xy 123.732036 -385.463542) (xy 123.77928 -385.54533) (xy 123.795282 -385.557522)
			(xy 123.805442 -385.560062) (xy 123.834549 -385.568069) (xy 123.890516 -385.590702) (xy 123.943021 -385.620495)
			(xy 123.991155 -385.656932) (xy 124.034082 -385.699379) (xy 124.071056 -385.747101) (xy 124.101436 -385.79927)
			(xy 124.124695 -385.854979) (xy 124.14043 -385.913262) (xy 124.148366 -385.973107) (xy 124.14885 -386.003292)
			(xy 124.148725 -386.017427) (xy 124.146943 -386.045641) (xy 124.145294 -386.05968) (xy 124.144528 -386.068287)
			(xy 124.14817 -386.085168) (xy 124.152406 -386.0927) (xy 124.168154 -386.1181) (xy 124.172875 -386.125151)
			(xy 124.185973 -386.135925) (xy 124.193808 -386.139182) (xy 124.217185 -386.148377) (xy 124.261081 -386.172795)
			(xy 124.300777 -386.203574) (xy 124.335358 -386.240006) (xy 124.364028 -386.281251) (xy 124.386127 -386.32636)
			(xy 124.401145 -386.374293) (xy 124.408737 -386.423947) (xy 124.4092 -386.449062) (xy 124.408775 -386.473264)
			(xy 124.401701 -386.521149) (xy 124.387715 -386.567488) (xy 124.367115 -386.61129) (xy 124.354082 -386.631688)
			(xy 124.349295 -386.639645) (xy 124.34526 -386.657756) (xy 124.346208 -386.666994) (xy 124.350526 -386.697982)
			(xy 124.3522 -386.70728) (xy 124.361486 -386.723721) (xy 124.36856 -386.729986) (xy 124.390648 -386.748669)
			(xy 124.430419 -386.79068) (xy 124.464581 -386.837368) (xy 124.492589 -386.887988) (xy 124.513997 -386.941733)
			(xy 124.528462 -386.997746) (xy 124.535755 -387.055136) (xy 124.5362 -387.084062) (xy 124.535614 -387.117384)
			(xy 124.525951 -387.183322) (xy 124.506823 -387.247161) (xy 124.493274 -387.27761) (xy 124.489027 -387.288075)
			(xy 124.489141 -387.310634) (xy 124.498875 -387.330985) (xy 124.507244 -387.33857) (xy 124.529463 -387.357277)
			(xy 124.56953 -387.399325) (xy 124.603954 -387.446105) (xy 124.632184 -387.496864) (xy 124.653764 -387.550787)
			(xy 124.668348 -387.607008) (xy 124.675701 -387.664621) (xy 124.676154 -387.693662) (xy 124.675676 -387.722667)
			(xy 124.668366 -387.780214) (xy 124.653844 -387.836377) (xy 124.632344 -387.890255) (xy 124.604209 -387.940985)
			(xy 124.569892 -387.987755) (xy 124.529941 -388.029815) (xy 124.507752 -388.0485) (xy 124.50064 -388.054088)
			(xy 124.491496 -388.069328) (xy 124.476256 -388.152132) (xy 124.47905 -388.169404) (xy 124.483622 -388.177532)
			(xy 124.496196 -388.200719) (xy 124.514071 -388.25034) (xy 124.523172 -388.302291) (xy 124.523754 -388.328662)
			(xy 124.523685 -388.338021) (xy 124.522542 -388.356703) (xy 124.521468 -388.366) (xy 124.520452 -388.37489)
			(xy 124.524262 -388.391654) (xy 124.568204 -388.461504) (xy 124.58192 -388.471918) (xy 124.590302 -388.474712)
			(xy 124.614323 -388.4832) (xy 124.659496 -388.506748) (xy 124.700302 -388.537243) (xy 124.735683 -388.573894)
			(xy 124.76472 -388.61575) (xy 124.78666 -388.661725) (xy 124.794264 -388.68604) (xy 124.795788 -388.691882)
			(xy 125.116082 -389.245602) (xy 125.120146 -389.24992) (xy 125.136342 -389.267622) (xy 125.163705 -389.307033)
			(xy 125.184789 -389.350131) (xy 125.199107 -389.395923) (xy 125.206332 -389.443354) (xy 125.20676 -389.467344)
			(xy 125.206323 -389.492135) (xy 125.19856 -389.541106) (xy 125.183233 -389.58826) (xy 125.160718 -389.632436)
			(xy 125.13157 -389.672547) (xy 125.096507 -389.707604) (xy 125.056392 -389.736745) (xy 125.012212 -389.759252)
			(xy 124.965056 -389.774572) (xy 124.916083 -389.782327) (xy 124.891292 -389.782812) (xy 124.865897 -389.782319)
			(xy 124.815763 -389.774187) (xy 124.767578 -389.758134) (xy 124.722583 -389.734575) (xy 124.681941 -389.704116)
			(xy 124.646698 -389.667544) (xy 124.617765 -389.625802) (xy 124.595887 -389.579967) (xy 124.58827 -389.555736)
			(xy 124.586746 -389.549894) (xy 124.266452 -388.996174) (xy 124.262388 -388.991856) (xy 124.246183 -388.974149)
			(xy 124.218759 -388.934758) (xy 124.197617 -388.891668) (xy 124.183243 -388.845874) (xy 124.17597 -388.798431)
			(xy 124.17552 -388.774432) (xy 124.175662 -388.76238) (xy 124.177568 -388.73835) (xy 124.17933 -388.726426)
			(xy 124.1806 -388.717536) (xy 124.177552 -388.700518) (xy 124.135388 -388.629652) (xy 124.12218 -388.618476)
			(xy 124.113798 -388.615428) (xy 124.092056 -388.607017) (xy 124.051197 -388.58458) (xy 124.014225 -388.55619)
			(xy 123.982001 -388.522507) (xy 123.955275 -388.484315) (xy 123.934668 -388.442503) (xy 123.92066 -388.398043)
			(xy 123.913576 -388.351969) (xy 123.913138 -388.328662) (xy 123.913699 -388.302289) (xy 123.922783 -388.25033)
			(xy 123.940674 -388.20071) (xy 123.95327 -388.177532) (xy 123.957842 -388.169404) (xy 123.960636 -388.152132)
			(xy 123.945396 -388.069328) (xy 123.936252 -388.054088) (xy 123.92914 -388.0485) (xy 123.906978 -388.029784)
			(xy 123.867029 -387.987726) (xy 123.832709 -387.94096) (xy 123.804569 -387.890235) (xy 123.783058 -387.836364)
			(xy 123.76852 -387.780208) (xy 123.761189 -387.722666) (xy 123.760738 -387.693662) (xy 123.761338 -387.660341)
			(xy 123.770997 -387.594403) (xy 123.790119 -387.530563) (xy 123.803664 -387.500114) (xy 123.807908 -387.489647)
			(xy 123.807804 -387.467087) (xy 123.798067 -387.446736) (xy 123.789694 -387.439154) (xy 123.767426 -387.420505)
			(xy 123.727364 -387.378445) (xy 123.692945 -387.331654) (xy 123.664723 -387.280885) (xy 123.643151 -387.226953)
			(xy 123.628576 -387.170725) (xy 123.621232 -387.113105) (xy 123.620784 -387.084062) (xy 123.621224 -387.055135)
			(xy 123.628508 -386.997742) (xy 123.642968 -386.941725) (xy 123.664373 -386.887976) (xy 123.692382 -386.837355)
			(xy 123.726549 -386.790668) (xy 123.766327 -386.748659) (xy 123.788424 -386.729986) (xy 123.79539 -386.723633)
			(xy 123.804652 -386.707234) (xy 123.806458 -386.697982) (xy 123.810776 -386.666994) (xy 123.811676 -386.657757)
			(xy 123.807654 -386.639658) (xy 123.802902 -386.631688) (xy 123.786594 -386.605843) (xy 123.76269 -386.549607)
			(xy 123.755404 -386.519928) (xy 123.753344 -386.511766) (xy 123.744644 -386.497365) (xy 123.738386 -386.491734)
			(xy 123.715272 -386.472684) (xy 123.708394 -386.467435) (xy 123.692162 -386.461471) (xy 123.683522 -386.461)
			(xy 123.653884 -386.460027) (xy 123.595218 -386.451373) (xy 123.53816 -386.435218) (xy 123.483666 -386.411831)
			(xy 123.432647 -386.381604) (xy 123.385957 -386.345044) (xy 123.344379 -386.302761) (xy 123.308607 -386.255465)
			(xy 123.279241 -386.203945) (xy 123.256772 -386.149066) (xy 123.241577 -386.091745) (xy 123.233909 -386.032942)
			(xy 123.233434 -386.003292) (xy 123.233955 -385.972229) (xy 123.242371 -385.910675) (xy 123.250198 -385.88061)
			(xy 123.252992 -385.87045) (xy 123.250452 -385.850638) (xy 123.202954 -385.768342) (xy 123.186952 -385.75615)
			(xy 123.176792 -385.75361) (xy 123.147696 -385.745605) (xy 123.09177 -385.722934) (xy 123.039305 -385.693113)
			(xy 122.991212 -385.656661) (xy 122.948323 -385.614207) (xy 122.911381 -385.566488) (xy 122.881027 -385.514331)
			(xy 122.857786 -385.458639) (xy 122.842061 -385.400376) (xy 122.834125 -385.340553) (xy 122.833638 -385.31038)
			(xy 122.834158 -385.279492) (xy 122.842464 -385.218276) (xy 122.858922 -385.158732) (xy 122.883234 -385.10194)
			(xy 122.898662 -385.075176) (xy 122.904504 -385.06527) (xy 122.90679 -385.042918) (xy 122.873516 -384.947668)
			(xy 122.857768 -384.931666) (xy 122.8471 -384.927602) (xy 122.82372 -384.918416) (xy 122.779822 -384.893998)
			(xy 122.740126 -384.863217) (xy 122.705544 -384.826785) (xy 122.676874 -384.785538) (xy 122.654777 -384.740428)
			(xy 122.63976 -384.692493) (xy 122.63217 -384.642838) (xy 122.631708 -384.617722) (xy 122.092974 -384.617722)
			(xy 122.092443 -384.644824) (xy 122.083634 -384.698307) (xy 122.075448 -384.724148) (xy 122.071638 -384.73507)
			(xy 122.074178 -384.757422) (xy 122.126756 -384.843274) (xy 122.145806 -384.85572) (xy 122.156982 -384.857498)
			(xy 122.186307 -384.862165) (xy 122.243478 -384.87822) (xy 122.298092 -384.901536) (xy 122.34923 -384.93172)
			(xy 122.396035 -384.968266) (xy 122.437719 -385.010559) (xy 122.473582 -385.057889) (xy 122.503021 -385.10946)
			(xy 122.525542 -385.164406) (xy 122.540766 -385.221804) (xy 122.548437 -385.280689) (xy 122.548904 -385.31038)
			(xy 122.548379 -385.341443) (xy 122.539966 -385.402997) (xy 122.53214 -385.433062) (xy 122.529346 -385.443222)
			(xy 122.531886 -385.463034) (xy 122.579384 -385.54533) (xy 122.595386 -385.557522) (xy 122.605546 -385.560062)
			(xy 122.634654 -385.568066) (xy 122.690621 -385.590699) (xy 122.743126 -385.620493) (xy 122.79126 -385.65693)
			(xy 122.834186 -385.699378) (xy 122.87116 -385.7471) (xy 122.901541 -385.799269) (xy 122.9248 -385.854978)
			(xy 122.940534 -385.913261) (xy 122.948471 -385.973107) (xy 122.948954 -386.003292) (xy 122.948829 -386.017427)
			(xy 122.947047 -386.045641) (xy 122.945398 -386.05968) (xy 122.944632 -386.068287) (xy 122.948274 -386.085168)
			(xy 122.95251 -386.0927) (xy 122.968258 -386.1181) (xy 122.972978 -386.125152) (xy 122.986076 -386.135926)
			(xy 122.993912 -386.139182) (xy 123.017289 -386.148375) (xy 123.061186 -386.172793) (xy 123.100882 -386.203573)
			(xy 123.135463 -386.240005) (xy 123.164133 -386.28125) (xy 123.186231 -386.326359) (xy 123.201249 -386.374293)
			(xy 123.208841 -386.423946) (xy 123.209304 -386.449062) (xy 123.208878 -386.473264) (xy 123.201805 -386.521149)
			(xy 123.187818 -386.567488) (xy 123.167219 -386.61129) (xy 123.154186 -386.631688) (xy 123.149399 -386.639645)
			(xy 123.145364 -386.657756) (xy 123.146312 -386.666994) (xy 123.15063 -386.697982) (xy 123.152303 -386.707281)
			(xy 123.161589 -386.723722) (xy 123.168664 -386.729986) (xy 123.190752 -386.748668) (xy 123.230524 -386.79068)
			(xy 123.264686 -386.837368) (xy 123.292694 -386.887987) (xy 123.314101 -386.941733) (xy 123.328566 -386.997746)
			(xy 123.335859 -387.055136) (xy 123.336304 -387.084062) (xy 123.335718 -387.117384) (xy 123.326054 -387.183322)
			(xy 123.306927 -387.247161) (xy 123.293378 -387.27761) (xy 123.28913 -387.288075) (xy 123.289244 -387.310634)
			(xy 123.298978 -387.330985) (xy 123.307348 -387.33857) (xy 123.329567 -387.357276) (xy 123.369634 -387.399324)
			(xy 123.404059 -387.446104) (xy 123.432288 -387.496864) (xy 123.453868 -387.550787) (xy 123.468452 -387.607008)
			(xy 123.475805 -387.664621) (xy 123.476258 -387.693662) (xy 123.475779 -387.722667) (xy 123.468468 -387.780214)
			(xy 123.453947 -387.836376) (xy 123.432446 -387.890254) (xy 123.404313 -387.940985) (xy 123.369995 -387.987755)
			(xy 123.330045 -388.029815) (xy 123.307856 -388.0485) (xy 123.300744 -388.054088) (xy 123.2916 -388.069328)
			(xy 123.27636 -388.152132) (xy 123.279154 -388.169404) (xy 123.283726 -388.177532) (xy 123.2963 -388.200719)
			(xy 123.314175 -388.25034) (xy 123.323276 -388.302291) (xy 123.323858 -388.328662) (xy 123.323789 -388.338021)
			(xy 123.322646 -388.356703) (xy 123.321572 -388.366) (xy 123.320556 -388.37489) (xy 123.324366 -388.391654)
			(xy 123.368308 -388.461504) (xy 123.382024 -388.471918) (xy 123.390406 -388.474712) (xy 123.414505 -388.483189)
			(xy 123.459796 -388.506815) (xy 123.50069 -388.537427) (xy 123.536122 -388.574225) (xy 123.565164 -388.616248)
			(xy 123.58706 -388.662401) (xy 123.594622 -388.686802) (xy 123.596146 -388.692644) (xy 123.915932 -389.245602)
			(xy 123.919996 -389.24992) (xy 123.936187 -389.267639) (xy 123.963613 -389.307027) (xy 123.984759 -389.350114)
			(xy 123.999135 -389.395905) (xy 124.006412 -389.443346) (xy 124.006864 -389.467344) (xy 124.006447 -389.49215)
			(xy 123.998676 -389.541149) (xy 123.983332 -389.588328) (xy 123.960793 -389.632524) (xy 123.931616 -389.672649)
			(xy 123.896519 -389.707713) (xy 123.856366 -389.736851) (xy 123.812148 -389.759347) (xy 123.764955 -389.774646)
			(xy 123.715948 -389.78237) (xy 123.691142 -389.782812) (xy 123.665749 -389.782275) (xy 123.615617 -389.77415)
			(xy 123.567432 -389.758105) (xy 123.522438 -389.734552) (xy 123.481795 -389.7041) (xy 123.446551 -389.667534)
			(xy 123.417617 -389.625796) (xy 123.395737 -389.579965) (xy 123.38812 -389.555736) (xy 123.386596 -389.549894)
			(xy 123.066048 -388.995412) (xy 123.061984 -388.991094) (xy 123.045886 -388.973419) (xy 123.018636 -388.934142)
			(xy 122.997624 -388.891203) (xy 122.98333 -388.845586) (xy 122.976083 -388.798334) (xy 122.975624 -388.774432)
			(xy 122.975766 -388.76238) (xy 122.977672 -388.73835) (xy 122.979434 -388.726426) (xy 122.980704 -388.717536)
			(xy 122.977656 -388.700518) (xy 122.935492 -388.629652) (xy 122.922284 -388.618476) (xy 122.913902 -388.615428)
			(xy 122.892161 -388.607015) (xy 122.851302 -388.584578) (xy 122.81433 -388.556189) (xy 122.782106 -388.522506)
			(xy 122.755379 -388.484314) (xy 122.734772 -388.442502) (xy 122.720764 -388.398042) (xy 122.71368 -388.351969)
			(xy 122.713242 -388.328662) (xy 122.713802 -388.302289) (xy 122.722887 -388.25033) (xy 122.740778 -388.20071)
			(xy 122.753374 -388.177532) (xy 122.757946 -388.169404) (xy 122.76074 -388.152132) (xy 122.7455 -388.069328)
			(xy 122.736356 -388.054088) (xy 122.729244 -388.0485) (xy 122.707083 -388.029783) (xy 122.667133 -387.987725)
			(xy 122.632814 -387.940959) (xy 122.604673 -387.890235) (xy 122.583162 -387.836364) (xy 122.568624 -387.780208)
			(xy 122.561293 -387.722666) (xy 122.560842 -387.693662) (xy 122.561442 -387.660341) (xy 122.5711 -387.594403)
			(xy 122.590222 -387.530563) (xy 122.603768 -387.500114) (xy 122.608011 -387.489646) (xy 122.607906 -387.467087)
			(xy 122.598171 -387.446736) (xy 122.589798 -387.439154) (xy 122.567531 -387.420504) (xy 122.527469 -387.378444)
			(xy 122.49305 -387.331654) (xy 122.464828 -387.280884) (xy 122.443256 -387.226953) (xy 122.42868 -387.170725)
			(xy 122.421336 -387.113105) (xy 122.420888 -387.084062) (xy 122.421326 -387.055135) (xy 122.428611 -386.997742)
			(xy 122.443071 -386.941724) (xy 122.464476 -386.887976) (xy 122.492486 -386.837355) (xy 122.526652 -386.790667)
			(xy 122.566431 -386.748659) (xy 122.588528 -386.729986) (xy 122.595494 -386.723633) (xy 122.604756 -386.707234)
			(xy 122.606562 -386.697982) (xy 122.61088 -386.666994) (xy 122.611779 -386.657757) (xy 122.607757 -386.639658)
			(xy 122.603006 -386.631688) (xy 122.586698 -386.605842) (xy 122.562795 -386.549607) (xy 122.555508 -386.519928)
			(xy 122.553447 -386.511767) (xy 122.544747 -386.497365) (xy 122.53849 -386.491734) (xy 122.515376 -386.472684)
			(xy 122.508497 -386.467436) (xy 122.492266 -386.461472) (xy 122.483626 -386.461) (xy 122.453988 -386.460024)
			(xy 122.395322 -386.45137) (xy 122.338265 -386.435215) (xy 122.28377 -386.411829) (xy 122.232751 -386.381602)
			(xy 122.186062 -386.345042) (xy 122.144483 -386.30276) (xy 122.108711 -386.255464) (xy 122.079345 -386.203945)
			(xy 122.056876 -386.149066) (xy 122.041681 -386.091745) (xy 122.034013 -386.032942) (xy 122.033538 -386.003292)
			(xy 122.034059 -385.972229) (xy 122.042475 -385.910675) (xy 122.050302 -385.88061) (xy 122.053096 -385.87045)
			(xy 122.050556 -385.850638) (xy 122.003058 -385.768342) (xy 121.987056 -385.75615) (xy 121.976896 -385.75361)
			(xy 121.947788 -385.745604) (xy 121.89182 -385.722973) (xy 121.839312 -385.693182) (xy 121.791177 -385.656746)
			(xy 121.748249 -385.614298) (xy 121.711275 -385.566576) (xy 121.680895 -385.514406) (xy 121.657636 -385.458696)
			(xy 121.641904 -385.400412) (xy 121.63397 -385.340565) (xy 121.633488 -385.31038) (xy 121.634015 -385.279492)
			(xy 121.64232 -385.218277) (xy 121.658777 -385.158733) (xy 121.683086 -385.101941) (xy 121.698512 -385.075176)
			(xy 121.704354 -385.06527) (xy 121.70664 -385.042918) (xy 121.673366 -384.947668) (xy 121.657618 -384.931666)
			(xy 121.64695 -384.927602) (xy 121.623559 -384.918443) (xy 121.579663 -384.894018) (xy 121.539968 -384.863233)
			(xy 121.505389 -384.826796) (xy 121.476721 -384.785546) (xy 121.454625 -384.740433) (xy 121.439609 -384.692496)
			(xy 121.43202 -384.642839) (xy 121.431558 -384.617722) (xy 120.893078 -384.617722) (xy 120.892547 -384.644824)
			(xy 120.883738 -384.698307) (xy 120.875552 -384.724148) (xy 120.871742 -384.73507) (xy 120.874282 -384.757422)
			(xy 120.92686 -384.843274) (xy 120.94591 -384.85572) (xy 120.957086 -384.857498) (xy 120.986411 -384.862162)
			(xy 121.043582 -384.878218) (xy 121.098196 -384.901533) (xy 121.149335 -384.931718) (xy 121.196139 -384.968264)
			(xy 121.237823 -385.010558) (xy 121.273686 -385.057888) (xy 121.303125 -385.109459) (xy 121.325646 -385.164406)
			(xy 121.34087 -385.221804) (xy 121.348541 -385.280689) (xy 121.349008 -385.31038) (xy 121.348483 -385.341443)
			(xy 121.34007 -385.402997) (xy 121.332244 -385.433062) (xy 121.32945 -385.443222) (xy 121.33199 -385.463034)
			(xy 121.379488 -385.54533) (xy 121.39549 -385.557522) (xy 121.40565 -385.560062) (xy 121.434759 -385.568063)
			(xy 121.490725 -385.590697) (xy 121.543231 -385.620491) (xy 121.591364 -385.656929) (xy 121.634291 -385.699377)
			(xy 121.671265 -385.7471) (xy 121.701645 -385.799268) (xy 121.724904 -385.854978) (xy 121.740638 -385.913261)
			(xy 121.748575 -385.973107) (xy 121.749058 -386.003292) (xy 121.748933 -386.017427) (xy 121.747151 -386.045641)
			(xy 121.745502 -386.05968) (xy 121.744735 -386.068287) (xy 121.748378 -386.085168) (xy 121.752614 -386.0927)
			(xy 121.768362 -386.1181) (xy 121.773068 -386.125165) (xy 121.78617 -386.135943) (xy 121.794016 -386.139182)
			(xy 121.817361 -386.148417) (xy 121.861205 -386.172871) (xy 121.900849 -386.203669) (xy 121.935385 -386.240104)
			(xy 121.964017 -386.28134) (xy 121.986089 -386.32643) (xy 122.001093 -386.374337) (xy 122.008685 -386.423961)
			(xy 122.009154 -386.449062) (xy 122.008736 -386.473264) (xy 122.001662 -386.52115) (xy 121.987673 -386.567489)
			(xy 121.967071 -386.611291) (xy 121.954036 -386.631688) (xy 121.949246 -386.639643) (xy 121.945214 -386.657756)
			(xy 121.946162 -386.666994) (xy 121.95048 -386.697982) (xy 121.952168 -386.707276) (xy 121.961445 -386.723718)
			(xy 121.968514 -386.729986) (xy 121.990592 -386.74868) (xy 122.030366 -386.790689) (xy 122.06453 -386.837374)
			(xy 122.09254 -386.887992) (xy 122.113948 -386.941735) (xy 122.128415 -386.997748) (xy 122.135709 -387.055137)
			(xy 122.136154 -387.084062) (xy 122.135563 -387.117383) (xy 122.125901 -387.183322) (xy 122.106775 -387.247161)
			(xy 122.093228 -387.27761) (xy 122.088964 -387.288071) (xy 122.089077 -387.310635) (xy 122.098821 -387.330988)
			(xy 122.107198 -387.33857) (xy 122.129428 -387.357263) (xy 122.169492 -387.399315) (xy 122.203914 -387.446098)
			(xy 122.232141 -387.49686) (xy 122.25372 -387.550785) (xy 122.268302 -387.607006) (xy 122.275655 -387.664621)
			(xy 122.276108 -387.693662) (xy 122.275647 -387.722668) (xy 122.268336 -387.780216) (xy 122.253812 -387.83638)
			(xy 122.23231 -387.890258) (xy 122.204172 -387.940989) (xy 122.169852 -387.987758) (xy 122.129897 -388.029816)
			(xy 122.107706 -388.0485) (xy 122.100594 -388.054088) (xy 122.09145 -388.069328) (xy 122.07621 -388.152132)
			(xy 122.079004 -388.169404) (xy 122.083576 -388.177532) (xy 122.096146 -388.200721) (xy 122.114023 -388.250341)
			(xy 122.123126 -388.302292) (xy 122.123708 -388.328662) (xy 122.123639 -388.338021) (xy 122.122496 -388.356703)
			(xy 122.121422 -388.366) (xy 122.120406 -388.37489) (xy 122.124216 -388.391654) (xy 122.168158 -388.461504)
			(xy 122.181874 -388.471918) (xy 122.190256 -388.474712) (xy 122.214287 -388.483171) (xy 122.259459 -388.506726)
			(xy 122.300264 -388.537228) (xy 122.335642 -388.573884) (xy 122.364677 -388.615745) (xy 122.386615 -388.661724)
			(xy 122.394218 -388.68604) (xy 122.395742 -388.691882) (xy 122.716036 -389.245602) (xy 122.7201 -389.24992)
			(xy 122.736292 -389.267639) (xy 122.763718 -389.307027) (xy 122.784863 -389.350113) (xy 122.799239 -389.395905)
			(xy 122.806516 -389.443346) (xy 122.806968 -389.467344) (xy 122.806547 -389.492149) (xy 122.798776 -389.541148)
			(xy 122.783432 -389.588327) (xy 122.760894 -389.632523) (xy 122.731717 -389.672647) (xy 122.69662 -389.707711)
			(xy 122.656468 -389.73685) (xy 122.612251 -389.759346) (xy 122.565058 -389.774645) (xy 122.516052 -389.78237)
			(xy 122.491246 -389.782812) (xy 122.465853 -389.782271) (xy 122.415721 -389.774148) (xy 122.367537 -389.758103)
			(xy 122.322542 -389.734551) (xy 122.281899 -389.704099) (xy 122.246656 -389.667533) (xy 122.217721 -389.625796)
			(xy 122.195841 -389.579965) (xy 122.188224 -389.555736) (xy 122.1867 -389.549894) (xy 121.866406 -388.996174)
			(xy 121.862342 -388.991856) (xy 121.846181 -388.974124) (xy 121.818813 -388.934721) (xy 121.797723 -388.891631)
			(xy 121.783396 -388.845846) (xy 121.776162 -388.79842) (xy 121.775728 -388.774432) (xy 121.775809 -388.762384)
			(xy 121.777591 -388.738355) (xy 121.779284 -388.726426) (xy 121.780554 -388.717536) (xy 121.777506 -388.700518)
			(xy 121.735342 -388.629652) (xy 121.722134 -388.618476) (xy 121.713752 -388.615428) (xy 121.692 -388.607043)
			(xy 121.651142 -388.584599) (xy 121.614172 -388.556204) (xy 121.58195 -388.522517) (xy 121.555226 -388.484322)
			(xy 121.53462 -388.442507) (xy 121.520613 -388.398045) (xy 121.51353 -388.35197) (xy 121.513092 -388.328662)
			(xy 121.513659 -388.302289) (xy 121.522742 -388.250331) (xy 121.54063 -388.20071) (xy 121.553224 -388.177532)
			(xy 121.557796 -388.169404) (xy 121.56059 -388.152132) (xy 121.54535 -388.069328) (xy 121.536206 -388.054088)
			(xy 121.529094 -388.0485) (xy 121.506922 -388.029795) (xy 121.466975 -387.987734) (xy 121.432658 -387.940965)
			(xy 121.40452 -387.890239) (xy 121.38301 -387.836366) (xy 121.368473 -387.780209) (xy 121.361143 -387.722666)
			(xy 121.360692 -387.693662) (xy 121.361287 -387.660341) (xy 121.370947 -387.594402) (xy 121.390071 -387.530563)
			(xy 121.403618 -387.500114) (xy 121.407845 -387.489642) (xy 121.407739 -387.467088) (xy 121.398014 -387.446739)
			(xy 121.389648 -387.439154) (xy 121.367391 -387.420491) (xy 121.327326 -387.378435) (xy 121.292905 -387.331647)
			(xy 121.264681 -387.28088) (xy 121.243107 -387.22695) (xy 121.228531 -387.170724) (xy 121.221186 -387.113105)
			(xy 121.220738 -387.084062) (xy 121.221195 -387.055136) (xy 121.228478 -386.997744) (xy 121.242936 -386.941728)
			(xy 121.264339 -386.88798) (xy 121.292346 -386.837359) (xy 121.326508 -386.79067) (xy 121.366283 -386.74866)
			(xy 121.388378 -386.729986) (xy 121.395353 -386.723641) (xy 121.404608 -386.707236) (xy 121.406412 -386.697982)
			(xy 121.41073 -386.666994) (xy 121.411637 -386.657757) (xy 121.407611 -386.639657) (xy 121.402856 -386.631688)
			(xy 121.386544 -386.605845) (xy 121.362643 -386.549607) (xy 121.355358 -386.519928) (xy 121.35331 -386.511762)
			(xy 121.344602 -386.497362) (xy 121.33834 -386.491734) (xy 121.315226 -386.472684) (xy 121.308392 -386.467483)
			(xy 121.292302 -386.46151) (xy 121.28373 -386.461) (xy 121.254092 -386.46002) (xy 121.195426 -386.451367)
			(xy 121.138369 -386.435212) (xy 121.083875 -386.411826) (xy 121.032856 -386.3816) (xy 120.986166 -386.345041)
			(xy 120.944587 -386.302759) (xy 120.908816 -386.255463) (xy 120.879449 -386.203944) (xy 120.856981 -386.149065)
			(xy 120.841785 -386.091745) (xy 120.834117 -386.032942) (xy 120.833642 -386.003292) (xy 120.834163 -385.972229)
			(xy 120.842579 -385.910675) (xy 120.850406 -385.88061) (xy 120.8532 -385.87045) (xy 120.85066 -385.850638)
			(xy 120.803162 -385.768342) (xy 120.78716 -385.75615) (xy 120.777 -385.75361) (xy 120.747874 -385.745668)
			(xy 120.691907 -385.723026) (xy 120.639401 -385.693224) (xy 120.591268 -385.656779) (xy 120.548343 -385.614324)
			(xy 120.511371 -385.566595) (xy 120.480994 -385.51442) (xy 120.457737 -385.458705) (xy 120.442006 -385.400417)
			(xy 120.434073 -385.340567) (xy 120.433592 -385.31038) (xy 120.434119 -385.279492) (xy 120.442424 -385.218277)
			(xy 120.45888 -385.158733) (xy 120.48319 -385.101941) (xy 120.498616 -385.075176) (xy 120.504458 -385.06527)
			(xy 120.506744 -385.042918) (xy 120.47347 -384.947668) (xy 120.457722 -384.931666) (xy 120.447054 -384.927602)
			(xy 120.423664 -384.918441) (xy 120.379768 -384.894017) (xy 120.340073 -384.863232) (xy 120.305493 -384.826795)
			(xy 120.276825 -384.785545) (xy 120.254729 -384.740432) (xy 120.239713 -384.692496) (xy 120.232124 -384.642839)
			(xy 120.231662 -384.617722) (xy 119.693182 -384.617722) (xy 119.69265 -384.644824) (xy 119.683842 -384.698307)
			(xy 119.675656 -384.724148) (xy 119.671846 -384.73507) (xy 119.674386 -384.757422) (xy 119.726964 -384.843528)
			(xy 119.74576 -384.85572) (xy 119.75719 -384.857498) (xy 119.786485 -384.862269) (xy 119.84362 -384.878348)
			(xy 119.898196 -384.901679) (xy 119.949298 -384.931869) (xy 119.996069 -384.968412) (xy 120.037722 -385.010695)
			(xy 120.07356 -385.058009) (xy 120.10298 -385.109558) (xy 120.125489 -385.164478) (xy 120.14071 -385.221848)
			(xy 120.148386 -385.280703) (xy 120.148858 -385.31038) (xy 120.148331 -385.341443) (xy 120.139919 -385.402996)
			(xy 120.132094 -385.433062) (xy 120.1293 -385.443222) (xy 120.13184 -385.463034) (xy 120.179338 -385.54533)
			(xy 120.19534 -385.557522) (xy 120.2055 -385.560062) (xy 120.234619 -385.56803) (xy 120.290584 -385.59067)
			(xy 120.343089 -385.620469) (xy 120.391221 -385.656911) (xy 120.434146 -385.699364) (xy 120.471118 -385.74709)
			(xy 120.501497 -385.799261) (xy 120.524755 -385.854973) (xy 120.540489 -385.913258) (xy 120.548425 -385.973106)
			(xy 120.548908 -386.003292) (xy 120.548783 -386.017427) (xy 120.547001 -386.045641) (xy 120.545352 -386.05968)
			(xy 120.544592 -386.068287) (xy 120.548231 -386.085167) (xy 120.552464 -386.0927) (xy 120.568212 -386.1181)
			(xy 120.572915 -386.125165) (xy 120.586025 -386.135931) (xy 120.593866 -386.139182) (xy 120.617255 -386.148346)
			(xy 120.66115 -386.172771) (xy 120.700844 -386.203556) (xy 120.735423 -386.239993) (xy 120.764091 -386.281242)
			(xy 120.786187 -386.326354) (xy 120.801204 -386.37429) (xy 120.808795 -386.423946) (xy 120.809258 -386.449062)
			(xy 120.80884 -386.473264) (xy 120.801765 -386.52115) (xy 120.787777 -386.567489) (xy 120.767175 -386.611291)
			(xy 120.75414 -386.631688) (xy 120.74935 -386.639643) (xy 120.745318 -386.657756) (xy 120.746266 -386.666994)
			(xy 120.750584 -386.697982) (xy 120.752271 -386.707277) (xy 120.761549 -386.723719) (xy 120.768618 -386.729986)
			(xy 120.790697 -386.748679) (xy 120.83047 -386.790688) (xy 120.864634 -386.837373) (xy 120.892644 -386.887991)
			(xy 120.914053 -386.941735) (xy 120.928519 -386.997748) (xy 120.935813 -387.055137) (xy 120.936258 -387.084062)
			(xy 120.935667 -387.117383) (xy 120.926004 -387.183322) (xy 120.906879 -387.247161) (xy 120.893332 -387.27761)
			(xy 120.889066 -387.28807) (xy 120.88918 -387.310636) (xy 120.898925 -387.330989) (xy 120.907302 -387.33857)
			(xy 120.929533 -387.357262) (xy 120.969597 -387.399315) (xy 121.004019 -387.446098) (xy 121.032246 -387.49686)
			(xy 121.053824 -387.550785) (xy 121.068406 -387.607006) (xy 121.075759 -387.664621) (xy 121.076212 -387.693662)
			(xy 121.07575 -387.722668) (xy 121.068438 -387.780216) (xy 121.053915 -387.836379) (xy 121.032413 -387.890258)
			(xy 121.004276 -387.940988) (xy 120.969955 -387.987758) (xy 120.930001 -388.029816) (xy 120.90781 -388.0485)
			(xy 120.900698 -388.054088) (xy 120.891554 -388.069328) (xy 120.876314 -388.152132) (xy 120.879108 -388.169404)
			(xy 120.88368 -388.177532) (xy 120.89625 -388.200721) (xy 120.914127 -388.250341) (xy 120.92323 -388.302292)
			(xy 120.923812 -388.328662) (xy 120.923743 -388.338021) (xy 120.9226 -388.356703) (xy 120.921526 -388.366)
			(xy 120.92051 -388.37489) (xy 120.92432 -388.391654) (xy 120.968262 -388.461504) (xy 120.981978 -388.471918)
			(xy 120.99036 -388.474712) (xy 121.014392 -388.483169) (xy 121.059564 -388.506725) (xy 121.100368 -388.537227)
			(xy 121.135747 -388.573884) (xy 121.164781 -388.615745) (xy 121.186719 -388.661724) (xy 121.194322 -388.68604)
			(xy 121.195846 -388.691882) (xy 121.51614 -389.245602) (xy 121.520204 -389.24992) (xy 121.536396 -389.267638)
			(xy 121.563822 -389.307026) (xy 121.584967 -389.350113) (xy 121.599343 -389.395905) (xy 121.60662 -389.443346)
			(xy 121.607072 -389.467344) (xy 121.606647 -389.492149) (xy 121.598876 -389.541148) (xy 121.583533 -389.588326)
			(xy 121.560995 -389.632522) (xy 121.531818 -389.672646) (xy 121.496722 -389.70771) (xy 121.456571 -389.736849)
			(xy 121.412354 -389.759345) (xy 121.365161 -389.774644) (xy 121.316156 -389.78237) (xy 121.29135 -389.782812)
			(xy 121.265957 -389.782268) (xy 121.215826 -389.774145) (xy 121.167641 -389.7581) (xy 121.122647 -389.734549)
			(xy 121.082003 -389.704097) (xy 121.04676 -389.667532) (xy 121.017825 -389.625795) (xy 120.995945 -389.579965)
			(xy 120.988328 -389.555736) (xy 120.986804 -389.549894) (xy 120.66651 -388.996174) (xy 120.662446 -388.991856)
			(xy 120.646285 -388.974123) (xy 120.618918 -388.934721) (xy 120.597827 -388.891631) (xy 120.5835 -388.845845)
			(xy 120.576266 -388.798419) (xy 120.575832 -388.774432) (xy 120.575913 -388.762384) (xy 120.577695 -388.738355)
			(xy 120.579388 -388.726426) (xy 120.580658 -388.717536) (xy 120.57761 -388.700518) (xy 120.535446 -388.629652)
			(xy 120.522238 -388.618476) (xy 120.513856 -388.615428) (xy 120.492105 -388.60704) (xy 120.451247 -388.584598)
			(xy 120.414277 -388.556203) (xy 120.382055 -388.522516) (xy 120.35533 -388.484321) (xy 120.334724 -388.442507)
			(xy 120.320717 -388.398045) (xy 120.313634 -388.35197) (xy 120.313196 -388.328662) (xy 120.313762 -388.302289)
			(xy 120.322845 -388.250331) (xy 120.340733 -388.20071) (xy 120.353328 -388.177532) (xy 120.3579 -388.169404)
			(xy 120.360694 -388.152132) (xy 120.345454 -388.069328) (xy 120.33631 -388.054088) (xy 120.329198 -388.0485)
			(xy 120.307027 -388.029794) (xy 120.26708 -387.987733) (xy 120.232763 -387.940965) (xy 120.204624 -387.890239)
			(xy 120.183114 -387.836366) (xy 120.168577 -387.780209) (xy 120.161247 -387.722666) (xy 120.160796 -387.693662)
			(xy 120.161391 -387.660341) (xy 120.171051 -387.594402) (xy 120.190175 -387.530563) (xy 120.203722 -387.500114)
			(xy 120.207947 -387.489642) (xy 120.207842 -387.467089) (xy 120.198118 -387.446739) (xy 120.189752 -387.439154)
			(xy 120.167496 -387.420491) (xy 120.127431 -387.378434) (xy 120.09301 -387.331647) (xy 120.064785 -387.28088)
			(xy 120.043212 -387.22695) (xy 120.028635 -387.170724) (xy 120.02129 -387.113105) (xy 120.020842 -387.084062)
			(xy 120.021297 -387.055136) (xy 120.028581 -386.997744) (xy 120.043039 -386.941727) (xy 120.064442 -386.88798)
			(xy 120.092449 -386.837358) (xy 120.126612 -386.79067) (xy 120.166387 -386.74866) (xy 120.188482 -386.729986)
			(xy 120.195457 -386.723642) (xy 120.204713 -386.707236) (xy 120.206516 -386.697982) (xy 120.210834 -386.666994)
			(xy 120.21174 -386.657757) (xy 120.207715 -386.639657) (xy 120.20296 -386.631688) (xy 120.186648 -386.605845)
			(xy 120.162748 -386.549607) (xy 120.155462 -386.519928) (xy 120.153413 -386.511762) (xy 120.144706 -386.497362)
			(xy 120.138444 -386.491734) (xy 120.11533 -386.472684) (xy 120.108437 -386.467458) (xy 120.092216 -386.46148)
			(xy 120.08358 -386.461) (xy 120.053944 -386.459974) (xy 119.99528 -386.451327) (xy 119.938223 -386.435178)
			(xy 119.883729 -386.411798) (xy 119.83271 -386.381577) (xy 119.78602 -386.345021) (xy 119.74444 -386.302743)
			(xy 119.708668 -386.255451) (xy 119.679301 -386.203935) (xy 119.656831 -386.149059) (xy 119.641635 -386.091741)
			(xy 119.633967 -386.032941) (xy 119.633492 -386.003292) (xy 119.634012 -385.972229) (xy 119.642428 -385.910675)
			(xy 119.650256 -385.88061) (xy 119.65305 -385.87045) (xy 119.65051 -385.850638) (xy 119.603012 -385.768342)
			(xy 119.58701 -385.75615) (xy 119.57685 -385.75361) (xy 119.547733 -385.745635) (xy 119.491765 -385.722999)
			(xy 119.439259 -385.693202) (xy 119.391125 -385.656762) (xy 119.348198 -385.614311) (xy 119.311225 -385.566585)
			(xy 119.280846 -385.514413) (xy 119.257589 -385.458701) (xy 119.241857 -385.400414) (xy 119.233923 -385.340566)
			(xy 119.233442 -385.31038) (xy 119.233915 -385.279458) (xy 119.242197 -385.218171) (xy 119.258663 -385.158559)
			(xy 119.283011 -385.10171) (xy 119.298466 -385.074922) (xy 119.304562 -385.06527) (xy 119.306848 -385.042918)
			(xy 119.27332 -384.947668) (xy 119.257572 -384.931666) (xy 119.246904 -384.927602) (xy 119.223557 -384.918369)
			(xy 119.179713 -384.893917) (xy 119.140067 -384.863119) (xy 119.105531 -384.826683) (xy 119.076899 -384.785447)
			(xy 119.054827 -384.740356) (xy 119.039824 -384.692448) (xy 119.032234 -384.642823) (xy 119.031766 -384.617722)
			(xy 118.493032 -384.617722) (xy 118.492503 -384.644824) (xy 118.483693 -384.698307) (xy 118.475506 -384.724148)
			(xy 118.471696 -384.73507) (xy 118.474236 -384.757422) (xy 118.526814 -384.843274) (xy 118.545864 -384.85572)
			(xy 118.55704 -384.857498) (xy 118.586359 -384.862198) (xy 118.64353 -384.878248) (xy 118.698144 -384.901559)
			(xy 118.749283 -384.931739) (xy 118.796089 -384.968281) (xy 118.837774 -385.01057) (xy 118.873638 -385.057898)
			(xy 118.903078 -385.109466) (xy 118.925599 -385.164411) (xy 118.940823 -385.221806) (xy 118.948495 -385.28069)
			(xy 118.948962 -385.31038) (xy 118.948435 -385.341443) (xy 118.940023 -385.402996) (xy 118.932198 -385.433062)
			(xy 118.929404 -385.443222) (xy 118.931944 -385.463034) (xy 118.979442 -385.54533) (xy 118.995444 -385.557522)
			(xy 119.005604 -385.560062) (xy 119.034704 -385.568094) (xy 119.090671 -385.590722) (xy 119.143177 -385.620512)
			(xy 119.191312 -385.656945) (xy 119.23424 -385.699389) (xy 119.271215 -385.747109) (xy 119.301596 -385.799275)
			(xy 119.324856 -385.854982) (xy 119.340591 -385.913264) (xy 119.348528 -385.973108) (xy 119.349012 -386.003292)
			(xy 119.348887 -386.017427) (xy 119.347105 -386.045641) (xy 119.345456 -386.05968) (xy 119.344695 -386.068287)
			(xy 119.348335 -386.085167) (xy 119.352568 -386.0927) (xy 119.368316 -386.1181) (xy 119.373037 -386.125154)
			(xy 119.386128 -386.135938) (xy 119.39397 -386.139182) (xy 119.417327 -386.148388) (xy 119.461169 -386.172848)
			(xy 119.500812 -386.203652) (xy 119.535345 -386.240092) (xy 119.563975 -386.281332) (xy 119.586045 -386.326424)
			(xy 119.601048 -386.374334) (xy 119.60864 -386.42396) (xy 119.609108 -386.449062) (xy 119.608681 -386.473264)
			(xy 119.601608 -386.521149) (xy 119.587622 -386.567488) (xy 119.567023 -386.61129) (xy 119.55399 -386.631688)
			(xy 119.549203 -386.639646) (xy 119.545168 -386.657756) (xy 119.546116 -386.666994) (xy 119.550434 -386.697982)
			(xy 119.552106 -386.707281) (xy 119.561393 -386.723722) (xy 119.568468 -386.729986) (xy 119.590557 -386.748667)
			(xy 119.630329 -386.790679) (xy 119.66449 -386.837367) (xy 119.692498 -386.887987) (xy 119.713905 -386.941732)
			(xy 119.72837 -386.997746) (xy 119.735663 -387.055136) (xy 119.736108 -387.084062) (xy 119.735521 -387.117384)
			(xy 119.725858 -387.183322) (xy 119.706731 -387.247161) (xy 119.693182 -387.27761) (xy 119.688933 -387.288074)
			(xy 119.689047 -387.310634) (xy 119.698781 -387.330985) (xy 119.707152 -387.33857) (xy 119.729372 -387.357275)
			(xy 119.769439 -387.399323) (xy 119.803863 -387.446104) (xy 119.832092 -387.496863) (xy 119.853672 -387.550787)
			(xy 119.868256 -387.607008) (xy 119.875609 -387.664621) (xy 119.876062 -387.693662) (xy 119.875581 -387.722667)
			(xy 119.868271 -387.780214) (xy 119.853749 -387.836376) (xy 119.832249 -387.890254) (xy 119.804116 -387.940985)
			(xy 119.769799 -387.987755) (xy 119.729849 -388.029815) (xy 119.70766 -388.0485) (xy 119.700548 -388.054088)
			(xy 119.691404 -388.069328) (xy 119.676164 -388.152132) (xy 119.678958 -388.169404) (xy 119.68353 -388.177532)
			(xy 119.696104 -388.200719) (xy 119.713979 -388.25034) (xy 119.72308 -388.302291) (xy 119.723662 -388.328662)
			(xy 119.723593 -388.338021) (xy 119.72245 -388.356703) (xy 119.721376 -388.366) (xy 119.72036 -388.37489)
			(xy 119.72417 -388.391654) (xy 119.768112 -388.461504) (xy 119.781828 -388.471918) (xy 119.79021 -388.474712)
			(xy 119.814232 -388.483196) (xy 119.859405 -388.506744) (xy 119.900211 -388.53724) (xy 119.935592 -388.573892)
			(xy 119.964629 -388.615749) (xy 119.986568 -388.661725) (xy 119.994172 -388.68604) (xy 119.995696 -388.691882)
			(xy 120.31599 -389.245602) (xy 120.320054 -389.24992) (xy 120.336251 -389.267621) (xy 120.363614 -389.307032)
			(xy 120.384697 -389.35013) (xy 120.399016 -389.395923) (xy 120.40624 -389.443354) (xy 120.406668 -389.467344)
			(xy 120.406223 -389.492135) (xy 120.39846 -389.541105) (xy 120.383133 -389.588259) (xy 120.360619 -389.632434)
			(xy 120.331473 -389.672544) (xy 120.296411 -389.707601) (xy 120.256296 -389.736742) (xy 120.212118 -389.75925)
			(xy 120.164962 -389.77457) (xy 120.115991 -389.782326) (xy 120.0912 -389.782812) (xy 120.065806 -389.782312)
			(xy 120.015672 -389.774181) (xy 119.967486 -389.758129) (xy 119.922492 -389.734571) (xy 119.881849 -389.704114)
			(xy 119.846607 -389.667543) (xy 119.817673 -389.625801) (xy 119.795795 -389.579967) (xy 119.788178 -389.555736)
			(xy 119.786654 -389.549894) (xy 119.46636 -388.996174) (xy 119.462296 -388.991856) (xy 119.446092 -388.974148)
			(xy 119.418668 -388.934757) (xy 119.397525 -388.891668) (xy 119.383152 -388.845873) (xy 119.375878 -388.79843)
			(xy 119.375428 -388.774432) (xy 119.37557 -388.76238) (xy 119.377476 -388.73835) (xy 119.379238 -388.726426)
			(xy 119.380508 -388.717536) (xy 119.37746 -388.700518) (xy 119.335296 -388.629652) (xy 119.322088 -388.618476)
			(xy 119.313706 -388.615428) (xy 119.291966 -388.607013) (xy 119.251106 -388.584577) (xy 119.214134 -388.556187)
			(xy 119.18191 -388.522505) (xy 119.155184 -388.484314) (xy 119.134576 -388.442502) (xy 119.120568 -388.398042)
			(xy 119.113484 -388.351969) (xy 119.113046 -388.328662) (xy 119.113606 -388.302289) (xy 119.12269 -388.25033)
			(xy 119.140581 -388.20071) (xy 119.153178 -388.177532) (xy 119.15775 -388.169404) (xy 119.160544 -388.152132)
			(xy 119.145304 -388.069328) (xy 119.13616 -388.054088) (xy 119.129048 -388.0485) (xy 119.106867 -388.029807)
			(xy 119.066922 -387.987742) (xy 119.032607 -387.940971) (xy 119.00447 -387.890243) (xy 118.982962 -387.836368)
			(xy 118.968427 -387.78021) (xy 118.961096 -387.722666) (xy 118.960646 -387.693662) (xy 118.961245 -387.660341)
			(xy 118.970904 -387.594403) (xy 118.990026 -387.530563) (xy 119.003572 -387.500114) (xy 119.007814 -387.489646)
			(xy 119.007709 -387.467087) (xy 118.997974 -387.446736) (xy 118.989602 -387.439154) (xy 118.967335 -387.420503)
			(xy 118.927273 -387.378443) (xy 118.892854 -387.331653) (xy 118.864632 -387.280884) (xy 118.84306 -387.226952)
			(xy 118.828484 -387.170725) (xy 118.82114 -387.113105) (xy 118.820692 -387.084062) (xy 118.821129 -387.055135)
			(xy 118.828413 -386.997742) (xy 118.842874 -386.941724) (xy 118.864279 -386.887976) (xy 118.892289 -386.837354)
			(xy 118.926456 -386.790667) (xy 118.966235 -386.748659) (xy 118.988332 -386.729986) (xy 118.995299 -386.723634)
			(xy 119.00456 -386.707234) (xy 119.006366 -386.697982) (xy 119.010684 -386.666994) (xy 119.011582 -386.657757)
			(xy 119.007561 -386.639658) (xy 119.00281 -386.631688) (xy 118.986502 -386.605842) (xy 118.962599 -386.549607)
			(xy 118.955312 -386.519928) (xy 118.95325 -386.511767) (xy 118.944551 -386.497366) (xy 118.938294 -386.491734)
			(xy 118.91518 -386.472684) (xy 118.908358 -386.467465) (xy 118.892259 -386.461503) (xy 118.883684 -386.461)
			(xy 118.854048 -386.45997) (xy 118.795384 -386.451324) (xy 118.738327 -386.435176) (xy 118.683833 -386.411796)
			(xy 118.632814 -386.381575) (xy 118.586124 -386.34502) (xy 118.544544 -386.302742) (xy 118.508772 -386.25545)
			(xy 118.479405 -386.203935) (xy 118.456935 -386.149059) (xy 118.441739 -386.091741) (xy 118.434071 -386.032941)
			(xy 118.433596 -386.003292) (xy 118.434116 -385.972229) (xy 118.442532 -385.910675) (xy 118.45036 -385.88061)
			(xy 118.453154 -385.87045) (xy 118.450614 -385.850638) (xy 118.403116 -385.768342) (xy 118.387114 -385.75615)
			(xy 118.376954 -385.75361) (xy 118.347838 -385.745632) (xy 118.29187 -385.722997) (xy 118.239363 -385.6932)
			(xy 118.191229 -385.656761) (xy 118.148303 -385.61431) (xy 118.111329 -385.566584) (xy 118.08095 -385.514413)
			(xy 118.057693 -385.4587) (xy 118.041961 -385.400414) (xy 118.034027 -385.340566) (xy 118.033546 -385.31038)
			(xy 118.034065 -385.279492) (xy 118.042371 -385.218276) (xy 118.05883 -385.158732) (xy 118.083142 -385.10194)
			(xy 118.09857 -385.075176) (xy 118.104412 -385.06527) (xy 118.106698 -385.042918) (xy 118.073424 -384.947668)
			(xy 118.057676 -384.931666) (xy 118.047008 -384.927602) (xy 118.023629 -384.918412) (xy 117.979732 -384.893994)
			(xy 117.940035 -384.863215) (xy 117.905453 -384.826783) (xy 117.876783 -384.785537) (xy 117.854685 -384.740427)
			(xy 117.839668 -384.692493) (xy 117.832078 -384.642838) (xy 117.831616 -384.617722) (xy 117.293136 -384.617722)
			(xy 117.292607 -384.644824) (xy 117.283797 -384.698307) (xy 117.27561 -384.724148) (xy 117.2718 -384.73507)
			(xy 117.27434 -384.757422) (xy 117.326918 -384.843274) (xy 117.345968 -384.85572) (xy 117.357144 -384.857498)
			(xy 117.386464 -384.862195) (xy 117.443634 -384.878245) (xy 117.498248 -384.901556) (xy 117.549388 -384.931737)
			(xy 117.596193 -384.968279) (xy 117.637878 -385.010569) (xy 117.673742 -385.057897) (xy 117.703182 -385.109466)
			(xy 117.725703 -385.16441) (xy 117.740927 -385.221806) (xy 117.748599 -385.280689) (xy 117.749066 -385.31038)
			(xy 117.748542 -385.341506) (xy 117.740137 -385.403188) (xy 117.732302 -385.433316) (xy 117.729508 -385.443476)
			(xy 117.732048 -385.463542) (xy 117.779292 -385.54533) (xy 117.795294 -385.557522) (xy 117.805454 -385.560062)
			(xy 117.834564 -385.56806) (xy 117.89053 -385.590695) (xy 117.943036 -385.620489) (xy 117.991169 -385.656927)
			(xy 118.034095 -385.699376) (xy 118.071069 -385.747099) (xy 118.101449 -385.799268) (xy 118.124708 -385.854977)
			(xy 118.140442 -385.913261) (xy 118.148379 -385.973107) (xy 118.148862 -386.003292) (xy 118.148737 -386.017427)
			(xy 118.146955 -386.045641) (xy 118.145306 -386.05968) (xy 118.144539 -386.068287) (xy 118.148182 -386.085168)
			(xy 118.152418 -386.0927) (xy 118.168166 -386.1181) (xy 118.172884 -386.125154) (xy 118.185984 -386.135926)
			(xy 118.19382 -386.139182) (xy 118.217199 -386.148371) (xy 118.261095 -386.17279) (xy 118.300791 -386.20357)
			(xy 118.335372 -386.240003) (xy 118.364041 -386.281249) (xy 118.386139 -386.326358) (xy 118.401157 -386.374292)
			(xy 118.408749 -386.423946) (xy 118.409212 -386.449062) (xy 118.408785 -386.473264) (xy 118.401712 -386.521148)
			(xy 118.387726 -386.567488) (xy 118.367127 -386.61129) (xy 118.354094 -386.631688) (xy 118.349308 -386.639646)
			(xy 118.345272 -386.657756) (xy 118.34622 -386.666994) (xy 118.350538 -386.697982) (xy 118.352209 -386.707281)
			(xy 118.361497 -386.723722) (xy 118.368572 -386.729986) (xy 118.390662 -386.748666) (xy 118.430433 -386.790678)
			(xy 118.464595 -386.837367) (xy 118.492602 -386.887987) (xy 118.514009 -386.941732) (xy 118.528474 -386.997746)
			(xy 118.535767 -387.055136) (xy 118.536212 -387.084062) (xy 118.535625 -387.117384) (xy 118.525962 -387.183322)
			(xy 118.506834 -387.247161) (xy 118.493286 -387.27761) (xy 118.489035 -387.288074) (xy 118.489149 -387.310634)
			(xy 118.498885 -387.330986) (xy 118.507256 -387.33857) (xy 118.529477 -387.357274) (xy 118.569543 -387.399323)
			(xy 118.603968 -387.446103) (xy 118.632196 -387.496863) (xy 118.653776 -387.550787) (xy 118.66836 -387.607007)
			(xy 118.675713 -387.664621) (xy 118.676166 -387.693662) (xy 118.675684 -387.722667) (xy 118.668373 -387.780214)
			(xy 118.653852 -387.836376) (xy 118.632352 -387.890254) (xy 118.604219 -387.940984) (xy 118.569902 -387.987754)
			(xy 118.529953 -388.029815) (xy 118.507764 -388.0485) (xy 118.500652 -388.054088) (xy 118.491508 -388.069328)
			(xy 118.476268 -388.152132) (xy 118.479062 -388.169404) (xy 118.483634 -388.177532) (xy 118.496209 -388.200719)
			(xy 118.514083 -388.25034) (xy 118.523184 -388.302291) (xy 118.523766 -388.328662) (xy 118.523697 -388.338021)
			(xy 118.522554 -388.356703) (xy 118.52148 -388.366) (xy 118.520464 -388.37489) (xy 118.524274 -388.391654)
			(xy 118.568216 -388.461504) (xy 118.581932 -388.471918) (xy 118.590314 -388.474712) (xy 118.614337 -388.483194)
			(xy 118.65951 -388.506743) (xy 118.700316 -388.537239) (xy 118.735696 -388.573892) (xy 118.764733 -388.615749)
			(xy 118.786672 -388.661725) (xy 118.794276 -388.68604) (xy 118.7958 -388.691882) (xy 119.116094 -389.245602)
			(xy 119.120158 -389.24992) (xy 119.136356 -389.267621) (xy 119.163718 -389.307032) (xy 119.184801 -389.35013)
			(xy 119.19912 -389.395923) (xy 119.206344 -389.443354) (xy 119.206772 -389.467344) (xy 119.206323 -389.492135)
			(xy 119.19856 -389.541105) (xy 119.183234 -389.588258) (xy 119.16072 -389.632433) (xy 119.131574 -389.672543)
			(xy 119.096512 -389.7076) (xy 119.056399 -389.736741) (xy 119.012221 -389.759249) (xy 118.965066 -389.77457)
			(xy 118.916095 -389.782326) (xy 118.891304 -389.782812) (xy 118.86591 -389.782308) (xy 118.815776 -389.774178)
			(xy 118.767591 -389.758127) (xy 118.722596 -389.734569) (xy 118.681954 -389.704112) (xy 118.646711 -389.667542)
			(xy 118.617777 -389.625801) (xy 118.595899 -389.579966) (xy 118.588282 -389.555736) (xy 118.586758 -389.549894)
			(xy 118.266464 -388.996174) (xy 118.2624 -388.991856) (xy 118.246197 -388.974147) (xy 118.218772 -388.934757)
			(xy 118.19763 -388.891667) (xy 118.183256 -388.845873) (xy 118.175982 -388.79843) (xy 118.175532 -388.774432)
			(xy 118.175674 -388.76238) (xy 118.17758 -388.73835) (xy 118.179342 -388.726426) (xy 118.180612 -388.717536)
			(xy 118.177564 -388.700518) (xy 118.1354 -388.629652) (xy 118.122192 -388.618476) (xy 118.11381 -388.615428)
			(xy 118.092071 -388.607011) (xy 118.051211 -388.584575) (xy 118.014239 -388.556186) (xy 117.982015 -388.522504)
			(xy 117.955288 -388.484313) (xy 117.934681 -388.442501) (xy 117.920672 -388.398042) (xy 117.913588 -388.351969)
			(xy 117.91315 -388.328662) (xy 117.913722 -388.302289) (xy 117.922804 -388.250331) (xy 117.940689 -388.200711)
			(xy 117.953282 -388.177532) (xy 117.957854 -388.169404) (xy 117.960648 -388.152132) (xy 117.945408 -388.069328)
			(xy 117.936264 -388.054088) (xy 117.929152 -388.0485) (xy 117.906971 -388.029806) (xy 117.867027 -387.987741)
			(xy 117.832711 -387.94097) (xy 117.804575 -387.890242) (xy 117.783066 -387.836368) (xy 117.768531 -387.78021)
			(xy 117.7612 -387.722666) (xy 117.76075 -387.693662) (xy 117.761349 -387.660341) (xy 117.771008 -387.594403)
			(xy 117.79013 -387.530563) (xy 117.803676 -387.500114) (xy 117.807916 -387.489646) (xy 117.807811 -387.467087)
			(xy 117.798078 -387.446736) (xy 117.789706 -387.439154) (xy 117.76744 -387.420502) (xy 117.727378 -387.378443)
			(xy 117.692959 -387.331653) (xy 117.664736 -387.280884) (xy 117.643164 -387.226952) (xy 117.628588 -387.170725)
			(xy 117.621244 -387.113105) (xy 117.620796 -387.084062) (xy 117.621231 -387.055135) (xy 117.628516 -386.997741)
			(xy 117.642976 -386.941724) (xy 117.664382 -386.887975) (xy 117.692392 -386.837354) (xy 117.726559 -386.790667)
			(xy 117.766338 -386.748659) (xy 117.788436 -386.729986) (xy 117.795404 -386.723634) (xy 117.804665 -386.707234)
			(xy 117.80647 -386.697982) (xy 117.810788 -386.666994) (xy 117.811686 -386.657757) (xy 117.807665 -386.639658)
			(xy 117.802914 -386.631688) (xy 117.786607 -386.605842) (xy 117.762703 -386.549607) (xy 117.755416 -386.519928)
			(xy 117.753353 -386.511767) (xy 117.744655 -386.497366) (xy 117.738398 -386.491734) (xy 117.715284 -386.472684)
			(xy 117.708403 -386.467439) (xy 117.692173 -386.461473) (xy 117.683534 -386.461) (xy 117.653896 -386.460016)
			(xy 117.595231 -386.451364) (xy 117.538173 -386.43521) (xy 117.483679 -386.411824) (xy 117.43266 -386.381599)
			(xy 117.38597 -386.345039) (xy 117.344392 -386.302757) (xy 117.30862 -386.255462) (xy 117.279254 -386.203943)
			(xy 117.256785 -386.149065) (xy 117.241589 -386.091744) (xy 117.233921 -386.032942) (xy 117.233446 -386.003292)
			(xy 117.233967 -385.972229) (xy 117.242383 -385.910675) (xy 117.25021 -385.88061) (xy 117.253004 -385.87045)
			(xy 117.250464 -385.850638) (xy 117.202966 -385.768342) (xy 117.186964 -385.75615) (xy 117.176804 -385.75361)
			(xy 117.14771 -385.745597) (xy 117.091784 -385.722927) (xy 117.039319 -385.693108) (xy 116.991225 -385.656657)
			(xy 116.948336 -385.614204) (xy 116.911394 -385.566486) (xy 116.88104 -385.514329) (xy 116.857798 -385.458638)
			(xy 116.842073 -385.400376) (xy 116.834137 -385.340553) (xy 116.83365 -385.31038) (xy 116.834169 -385.279492)
			(xy 116.842475 -385.218276) (xy 116.858933 -385.158732) (xy 116.883246 -385.10194) (xy 116.898674 -385.075176)
			(xy 116.904516 -385.06527) (xy 116.906802 -385.042918) (xy 116.873528 -384.947668) (xy 116.85778 -384.931666)
			(xy 116.847112 -384.927602) (xy 116.823734 -384.918409) (xy 116.779836 -384.893993) (xy 116.740139 -384.863214)
			(xy 116.705557 -384.826782) (xy 116.676887 -384.785536) (xy 116.654789 -384.740427) (xy 116.639772 -384.692492)
			(xy 116.632182 -384.642838) (xy 116.63172 -384.617722) (xy 116.092986 -384.617722) (xy 116.092454 -384.644824)
			(xy 116.083646 -384.698307) (xy 116.07546 -384.724148) (xy 116.07165 -384.73507) (xy 116.07419 -384.757422)
			(xy 116.126768 -384.843274) (xy 116.145818 -384.85572) (xy 116.156994 -384.857498) (xy 116.186307 -384.862234)
			(xy 116.243478 -384.878278) (xy 116.298092 -384.901584) (xy 116.349232 -384.931759) (xy 116.396038 -384.968297)
			(xy 116.437724 -385.010583) (xy 116.473589 -385.057907) (xy 116.50303 -385.109474) (xy 116.525552 -385.164415)
			(xy 116.540777 -385.221809) (xy 116.548449 -385.28069) (xy 116.548916 -385.31038) (xy 116.54839 -385.341443)
			(xy 116.539978 -385.402996) (xy 116.532152 -385.433062) (xy 116.529358 -385.443222) (xy 116.531898 -385.463034)
			(xy 116.579396 -385.54533) (xy 116.595398 -385.557522) (xy 116.605558 -385.560062) (xy 116.634669 -385.568058)
			(xy 116.690635 -385.590693) (xy 116.74314 -385.620488) (xy 116.791274 -385.656926) (xy 116.8342 -385.699375)
			(xy 116.871173 -385.747098) (xy 116.901553 -385.799267) (xy 116.924812 -385.854977) (xy 116.940546 -385.913261)
			(xy 116.948483 -385.973107) (xy 116.948966 -386.003292) (xy 116.948841 -386.017427) (xy 116.947059 -386.045641)
			(xy 116.94541 -386.05968) (xy 116.944656 -386.068287) (xy 116.948292 -386.085166) (xy 116.952522 -386.0927)
			(xy 116.96827 -386.1181) (xy 116.972986 -386.125155) (xy 116.986087 -386.135927) (xy 116.993924 -386.139182)
			(xy 117.017304 -386.148368) (xy 117.0612 -386.172788) (xy 117.100895 -386.203569) (xy 117.135476 -386.240002)
			(xy 117.164146 -386.281249) (xy 117.186244 -386.326358) (xy 117.201261 -386.374292) (xy 117.208853 -386.423946)
			(xy 117.209316 -386.449062) (xy 117.208888 -386.473264) (xy 117.201815 -386.521148) (xy 117.187829 -386.567488)
			(xy 117.167231 -386.61129) (xy 117.154198 -386.631688) (xy 117.149412 -386.639646) (xy 117.145376 -386.657756)
			(xy 117.146324 -386.666994) (xy 117.150642 -386.697982) (xy 117.152312 -386.707281) (xy 117.1616 -386.723722)
			(xy 117.168676 -386.729986) (xy 117.190767 -386.748665) (xy 117.230538 -386.790678) (xy 117.264699 -386.837366)
			(xy 117.292706 -386.887987) (xy 117.314113 -386.941732) (xy 117.328578 -386.997746) (xy 117.335871 -387.055136)
			(xy 117.336316 -387.084062) (xy 117.335728 -387.117384) (xy 117.326065 -387.183322) (xy 117.306938 -387.247161)
			(xy 117.29339 -387.27761) (xy 117.289138 -387.288074) (xy 117.289252 -387.310634) (xy 117.298988 -387.330986)
			(xy 117.30736 -387.33857) (xy 117.329582 -387.357273) (xy 117.369648 -387.399322) (xy 117.404072 -387.446103)
			(xy 117.432301 -387.496863) (xy 117.45388 -387.550787) (xy 117.468464 -387.607007) (xy 117.475817 -387.664621)
			(xy 117.47627 -387.693662) (xy 117.475787 -387.722667) (xy 117.468476 -387.780213) (xy 117.453955 -387.836376)
			(xy 117.432455 -387.890253) (xy 117.404322 -387.940984) (xy 117.370006 -387.987754) (xy 117.330057 -388.029815)
			(xy 117.307868 -388.0485) (xy 117.300756 -388.054088) (xy 117.291612 -388.069328) (xy 117.276372 -388.152132)
			(xy 117.279166 -388.169404) (xy 117.283738 -388.177532) (xy 117.296313 -388.200719) (xy 117.314187 -388.25034)
			(xy 117.323288 -388.302291) (xy 117.32387 -388.328662) (xy 117.323801 -388.338021) (xy 117.322658 -388.356703)
			(xy 117.321584 -388.366) (xy 117.320568 -388.37489) (xy 117.324378 -388.391654) (xy 117.36832 -388.461504)
			(xy 117.382036 -388.471918) (xy 117.390418 -388.474712) (xy 117.414519 -388.483182) (xy 117.45981 -388.50681)
			(xy 117.500704 -388.537423) (xy 117.536135 -388.574223) (xy 117.565177 -388.616247) (xy 117.587072 -388.6624)
			(xy 117.594634 -388.686802) (xy 117.596158 -388.692644) (xy 117.915944 -389.245602) (xy 117.920008 -389.24992)
			(xy 117.936201 -389.267637) (xy 117.963627 -389.307026) (xy 117.984771 -389.350113) (xy 117.999147 -389.395905)
			(xy 118.006424 -389.443346) (xy 118.006876 -389.467344) (xy 118.006447 -389.492149) (xy 117.998676 -389.541147)
			(xy 117.983333 -389.588325) (xy 117.960796 -389.632521) (xy 117.93162 -389.672645) (xy 117.896524 -389.707708)
			(xy 117.856373 -389.736847) (xy 117.812157 -389.759344) (xy 117.764964 -389.774644) (xy 117.715959 -389.782369)
			(xy 117.691154 -389.782812) (xy 117.665758 -389.782352) (xy 117.615623 -389.774214) (xy 117.567436 -389.758156)
			(xy 117.522442 -389.734592) (xy 117.4818 -389.704129) (xy 117.446558 -389.667553) (xy 117.417625 -389.625807)
			(xy 117.395748 -389.579968) (xy 117.388132 -389.555736) (xy 117.386608 -389.549894) (xy 117.06606 -388.995412)
			(xy 117.061996 -388.991094) (xy 117.0459 -388.973418) (xy 117.018649 -388.934141) (xy 116.997636 -388.891203)
			(xy 116.983343 -388.845586) (xy 116.976095 -388.798334) (xy 116.975636 -388.774432) (xy 116.975778 -388.76238)
			(xy 116.977684 -388.73835) (xy 116.979446 -388.726426) (xy 116.980716 -388.717536) (xy 116.977668 -388.700518)
			(xy 116.935504 -388.629652) (xy 116.922296 -388.618476) (xy 116.913914 -388.615428) (xy 116.892176 -388.607009)
			(xy 116.851316 -388.584573) (xy 116.814344 -388.556185) (xy 116.782119 -388.522503) (xy 116.755392 -388.484312)
			(xy 116.734785 -388.442501) (xy 116.720776 -388.398042) (xy 116.713692 -388.351969) (xy 116.713254 -388.328662)
			(xy 116.713826 -388.302289) (xy 116.722907 -388.250331) (xy 116.740793 -388.200711) (xy 116.753386 -388.177532)
			(xy 116.757958 -388.169404) (xy 116.760752 -388.152132) (xy 116.745512 -388.069328) (xy 116.736368 -388.054088)
			(xy 116.729256 -388.0485) (xy 116.707076 -388.029805) (xy 116.667131 -387.98774) (xy 116.632816 -387.94097)
			(xy 116.604679 -387.890242) (xy 116.583171 -387.836368) (xy 116.568635 -387.78021) (xy 116.561305 -387.722666)
			(xy 116.560854 -387.693662) (xy 116.561453 -387.660341) (xy 116.571112 -387.594403) (xy 116.590234 -387.530563)
			(xy 116.60378 -387.500114) (xy 116.608019 -387.489645) (xy 116.607914 -387.467087) (xy 116.598181 -387.446737)
			(xy 116.58981 -387.439154) (xy 116.567545 -387.420501) (xy 116.527482 -387.378442) (xy 116.493063 -387.331652)
			(xy 116.46484 -387.280883) (xy 116.443268 -387.226952) (xy 116.428692 -387.170725) (xy 116.421348 -387.113105)
			(xy 116.4209 -387.084062) (xy 116.421334 -387.055135) (xy 116.428618 -386.997741) (xy 116.443079 -386.941723)
			(xy 116.464485 -386.887975) (xy 116.492495 -386.837354) (xy 116.526663 -386.790667) (xy 116.566442 -386.748658)
			(xy 116.58854 -386.729986) (xy 116.595508 -386.723635) (xy 116.604769 -386.707234) (xy 116.606574 -386.697982)
			(xy 116.610892 -386.666994) (xy 116.611789 -386.657757) (xy 116.607768 -386.639658) (xy 116.603018 -386.631688)
			(xy 116.586711 -386.605842) (xy 116.562807 -386.549607) (xy 116.55552 -386.519928) (xy 116.553456 -386.511768)
			(xy 116.544758 -386.497366) (xy 116.538502 -386.491734) (xy 116.515388 -386.472684) (xy 116.508506 -386.467441)
			(xy 116.492277 -386.461474) (xy 116.483638 -386.461) (xy 116.454 -386.460013) (xy 116.395335 -386.451361)
			(xy 116.338278 -386.435207) (xy 116.283783 -386.411822) (xy 116.232764 -386.381597) (xy 116.186075 -386.345037)
			(xy 116.144496 -386.302756) (xy 116.108724 -386.255461) (xy 116.079358 -386.203943) (xy 116.056889 -386.149064)
			(xy 116.041693 -386.091744) (xy 116.034025 -386.032942) (xy 116.03355 -386.003292) (xy 116.034071 -385.972229)
			(xy 116.042487 -385.910675) (xy 116.050314 -385.88061) (xy 116.053108 -385.87045) (xy 116.050568 -385.850638)
			(xy 116.00307 -385.768342) (xy 115.987068 -385.75615) (xy 115.976908 -385.75361) (xy 115.947783 -385.745662)
			(xy 115.891816 -385.723021) (xy 115.83931 -385.69322) (xy 115.791177 -385.656776) (xy 115.748252 -385.614322)
			(xy 115.71128 -385.566593) (xy 115.680902 -385.514419) (xy 115.657646 -385.458705) (xy 115.641914 -385.400417)
			(xy 115.633981 -385.340567) (xy 115.6335 -385.31038) (xy 115.634026 -385.279492) (xy 115.642331 -385.218277)
			(xy 115.658788 -385.158733) (xy 115.683098 -385.101941) (xy 115.698524 -385.075176) (xy 115.704366 -385.06527)
			(xy 115.706652 -385.042918) (xy 115.673378 -384.947668) (xy 115.65763 -384.931666) (xy 115.646962 -384.927602)
			(xy 115.623573 -384.918436) (xy 115.579677 -384.894013) (xy 115.539982 -384.863229) (xy 115.505402 -384.826793)
			(xy 115.476734 -384.785544) (xy 115.454637 -384.740432) (xy 115.439621 -384.692495) (xy 115.432032 -384.642839)
			(xy 115.43157 -384.617722) (xy 114.89309 -384.617722) (xy 114.892558 -384.644824) (xy 114.88375 -384.698306)
			(xy 114.875564 -384.724148) (xy 114.871754 -384.73507) (xy 114.874294 -384.757422) (xy 114.926872 -384.843274)
			(xy 114.945922 -384.85572) (xy 114.957098 -384.857498) (xy 114.986412 -384.862231) (xy 115.043582 -384.878276)
			(xy 115.098196 -384.901582) (xy 115.149336 -384.931757) (xy 115.196142 -384.968296) (xy 115.237828 -385.010582)
			(xy 115.273693 -385.057906) (xy 115.303134 -385.109473) (xy 115.325656 -385.164415) (xy 115.340881 -385.221809)
			(xy 115.348553 -385.28069) (xy 115.34902 -385.31038) (xy 115.348494 -385.341443) (xy 115.340082 -385.402996)
			(xy 115.332256 -385.433062) (xy 115.329462 -385.443222) (xy 115.332002 -385.463034) (xy 115.3795 -385.54533)
			(xy 115.395502 -385.557522) (xy 115.405662 -385.560062) (xy 115.434773 -385.568055) (xy 115.49074 -385.59069)
			(xy 115.543245 -385.620486) (xy 115.591378 -385.656924) (xy 115.634304 -385.699374) (xy 115.671278 -385.747097)
			(xy 115.701657 -385.799267) (xy 115.724916 -385.854977) (xy 115.74065 -385.91326) (xy 115.748587 -385.973107)
			(xy 115.74907 -386.003292) (xy 115.748944 -386.017427) (xy 115.747163 -386.045641) (xy 115.745514 -386.05968)
			(xy 115.744759 -386.068287) (xy 115.748396 -386.085166) (xy 115.752626 -386.0927) (xy 115.768374 -386.1181)
			(xy 115.773076 -386.125168) (xy 115.78618 -386.135945) (xy 115.794028 -386.139182) (xy 115.817376 -386.148411)
			(xy 115.861219 -386.172866) (xy 115.900863 -386.203665) (xy 115.935398 -386.240102) (xy 115.96403 -386.281339)
			(xy 115.986101 -386.326429) (xy 116.001105 -386.374336) (xy 116.008697 -386.423961) (xy 116.009166 -386.449062)
			(xy 116.008746 -386.473264) (xy 116.001672 -386.521149) (xy 115.987684 -386.567489) (xy 115.967082 -386.611291)
			(xy 115.954048 -386.631688) (xy 115.949258 -386.639644) (xy 115.945226 -386.657756) (xy 115.946174 -386.666994)
			(xy 115.950492 -386.697982) (xy 115.952176 -386.707277) (xy 115.961456 -386.723719) (xy 115.968526 -386.729986)
			(xy 115.990606 -386.748677) (xy 116.03038 -386.790687) (xy 116.064543 -386.837372) (xy 116.092552 -386.887991)
			(xy 116.113961 -386.941735) (xy 116.128427 -386.997747) (xy 116.135721 -387.055137) (xy 116.136166 -387.084062)
			(xy 116.135574 -387.117383) (xy 116.125912 -387.183322) (xy 116.106787 -387.247161) (xy 116.09324 -387.27761)
			(xy 116.088972 -387.28807) (xy 116.089085 -387.310636) (xy 116.098832 -387.330989) (xy 116.10721 -387.33857)
			(xy 116.129442 -387.35726) (xy 116.169506 -387.399313) (xy 116.203928 -387.446097) (xy 116.232154 -387.496859)
			(xy 116.253732 -387.550784) (xy 116.268315 -387.607006) (xy 116.275667 -387.664621) (xy 116.27612 -387.693662)
			(xy 116.275655 -387.722667) (xy 116.268343 -387.780216) (xy 116.25382 -387.836379) (xy 116.232318 -387.890257)
			(xy 116.204182 -387.940988) (xy 116.169862 -387.987757) (xy 116.129909 -388.029816) (xy 116.107718 -388.0485)
			(xy 116.100606 -388.054088) (xy 116.091462 -388.069328) (xy 116.076222 -388.152132) (xy 116.079016 -388.169404)
			(xy 116.083588 -388.177532) (xy 116.096159 -388.200721) (xy 116.114036 -388.250341) (xy 116.123138 -388.302292)
			(xy 116.12372 -388.328662) (xy 116.123651 -388.338021) (xy 116.122508 -388.356703) (xy 116.121434 -388.366)
			(xy 116.120418 -388.37489) (xy 116.124228 -388.391654) (xy 116.16817 -388.461504) (xy 116.181886 -388.471918)
			(xy 116.190268 -388.474712) (xy 116.214282 -388.483218) (xy 116.259456 -388.506761) (xy 116.300264 -388.537252)
			(xy 116.335646 -388.5739) (xy 116.364684 -388.615753) (xy 116.386626 -388.661726) (xy 116.39423 -388.68604)
			(xy 116.395754 -388.691882) (xy 116.716048 -389.245602) (xy 116.720112 -389.24992) (xy 116.736306 -389.267637)
			(xy 116.763731 -389.307025) (xy 116.784875 -389.350113) (xy 116.799252 -389.395905) (xy 116.806528 -389.443346)
			(xy 116.80698 -389.467344) (xy 116.806547 -389.492149) (xy 116.798776 -389.541146) (xy 116.783433 -389.588324)
			(xy 116.760896 -389.632519) (xy 116.731721 -389.672643) (xy 116.696625 -389.707707) (xy 116.656475 -389.736846)
			(xy 116.612259 -389.759343) (xy 116.565068 -389.774643) (xy 116.516063 -389.782369) (xy 116.491258 -389.782812)
			(xy 116.465862 -389.782348) (xy 116.415727 -389.774211) (xy 116.367541 -389.758154) (xy 116.322546 -389.73459)
			(xy 116.281904 -389.704127) (xy 116.246662 -389.667552) (xy 116.217729 -389.625806) (xy 116.195852 -389.579968)
			(xy 116.188236 -389.555736) (xy 116.186712 -389.549894) (xy 115.866418 -388.996174) (xy 115.862354 -388.991856)
			(xy 115.846195 -388.974122) (xy 115.818826 -388.93472) (xy 115.797736 -388.89163) (xy 115.783408 -388.845845)
			(xy 115.776174 -388.798419) (xy 115.77574 -388.774432) (xy 115.775821 -388.762384) (xy 115.777603 -388.738355)
			(xy 115.779296 -388.726426) (xy 115.780566 -388.717536) (xy 115.777518 -388.700518) (xy 115.735354 -388.629652)
			(xy 115.722146 -388.618476) (xy 115.713764 -388.615428) (xy 115.692015 -388.607036) (xy 115.651157 -388.584594)
			(xy 115.614186 -388.5562) (xy 115.581964 -388.522514) (xy 115.555239 -388.48432) (xy 115.534633 -388.442506)
			(xy 115.520625 -388.398044) (xy 115.513542 -388.35197) (xy 115.513104 -388.328662) (xy 115.513669 -388.302289)
			(xy 115.522752 -388.25033) (xy 115.540641 -388.20071) (xy 115.553236 -388.177532) (xy 115.557808 -388.169404)
			(xy 115.560602 -388.152132) (xy 115.545362 -388.069328) (xy 115.536218 -388.054088) (xy 115.529106 -388.0485)
			(xy 115.506937 -388.029792) (xy 115.466989 -387.987731) (xy 115.432671 -387.940964) (xy 115.404532 -387.890238)
			(xy 115.383022 -387.836366) (xy 115.368486 -387.780209) (xy 115.361155 -387.722666) (xy 115.360704 -387.693662)
			(xy 115.361307 -387.660341) (xy 115.370965 -387.594403) (xy 115.390086 -387.530564) (xy 115.40363 -387.500114)
			(xy 115.407853 -387.489641) (xy 115.407747 -387.467089) (xy 115.398024 -387.44674) (xy 115.38966 -387.439154)
			(xy 115.367405 -387.420489) (xy 115.32734 -387.378433) (xy 115.292919 -387.331646) (xy 115.264694 -387.28088)
			(xy 115.24312 -387.22695) (xy 115.228543 -387.170723) (xy 115.221198 -387.113105) (xy 115.22075 -387.084062)
			(xy 115.221202 -387.055136) (xy 115.228486 -386.997743) (xy 115.242945 -386.941727) (xy 115.264348 -386.887979)
			(xy 115.292355 -386.837358) (xy 115.326519 -386.79067) (xy 115.366294 -386.74866) (xy 115.38839 -386.729986)
			(xy 115.395367 -386.723643) (xy 115.404621 -386.707236) (xy 115.406424 -386.697982) (xy 115.410742 -386.666994)
			(xy 115.411647 -386.657757) (xy 115.407622 -386.639657) (xy 115.402868 -386.631688) (xy 115.386557 -386.605844)
			(xy 115.362656 -386.549607) (xy 115.35537 -386.519928) (xy 115.353319 -386.511763) (xy 115.344613 -386.497363)
			(xy 115.338352 -386.491734) (xy 115.315238 -386.472684) (xy 115.308401 -386.467488) (xy 115.292314 -386.461512)
			(xy 115.283742 -386.461) (xy 115.254105 -386.460009) (xy 115.195439 -386.451357) (xy 115.138382 -386.435204)
			(xy 115.083888 -386.411819) (xy 115.032869 -386.381595) (xy 114.986179 -386.345036) (xy 114.9446 -386.302755)
			(xy 114.908828 -386.25546) (xy 114.879462 -386.203942) (xy 114.856993 -386.149064) (xy 114.841797 -386.091744)
			(xy 114.834129 -386.032942) (xy 114.833654 -386.003292) (xy 114.834175 -385.972229) (xy 114.842591 -385.910675)
			(xy 114.850418 -385.88061) (xy 114.853212 -385.87045) (xy 114.850672 -385.850638) (xy 114.803174 -385.768342)
			(xy 114.787172 -385.75615) (xy 114.777012 -385.75361) (xy 114.765291 -385.750463) (xy 114.742165 -385.743093)
			(xy 114.730784 -385.738878) (xy 114.718338 -385.734306) (xy 114.69243 -385.738116) (xy 114.603022 -385.806696)
			(xy 114.592608 -385.830826) (xy 114.593878 -385.84378) (xy 114.595402 -385.87553) (xy 114.595014 -385.899206)
			(xy 114.588283 -385.946077) (xy 114.574919 -385.991503) (xy 114.56543 -386.013198) (xy 114.561112 -386.022596)
			(xy 114.56035 -386.042662) (xy 114.592608 -386.129022) (xy 114.606324 -386.143754) (xy 114.615722 -386.148072)
			(xy 114.640084 -386.159776) (xy 114.684956 -386.189899) (xy 114.724335 -386.226914) (xy 114.757175 -386.269837)
			(xy 114.782602 -386.317526) (xy 114.799941 -386.368714) (xy 114.80873 -386.42204) (xy 114.80927 -386.449062)
			(xy 114.80885 -386.473264) (xy 114.801776 -386.521149) (xy 114.787788 -386.567489) (xy 114.767186 -386.611291)
			(xy 114.754152 -386.631688) (xy 114.749363 -386.639644) (xy 114.74533 -386.657756) (xy 114.746278 -386.666994)
			(xy 114.750596 -386.697982) (xy 114.752279 -386.707278) (xy 114.761559 -386.723719) (xy 114.76863 -386.729986)
			(xy 114.790711 -386.748676) (xy 114.830484 -386.790686) (xy 114.864648 -386.837372) (xy 114.892657 -386.88799)
			(xy 114.914065 -386.941734) (xy 114.928531 -386.997747) (xy 114.935825 -387.055137) (xy 114.93627 -387.084062)
			(xy 114.935678 -387.117383) (xy 114.926016 -387.183322) (xy 114.906891 -387.247161) (xy 114.893344 -387.27761)
			(xy 114.889074 -387.288069) (xy 114.889188 -387.310636) (xy 114.898935 -387.330989) (xy 114.907314 -387.33857)
			(xy 114.929547 -387.357259) (xy 114.969611 -387.399313) (xy 115.004032 -387.446096) (xy 115.032259 -387.496859)
			(xy 115.053836 -387.550784) (xy 115.068419 -387.607006) (xy 115.075771 -387.664621) (xy 115.076224 -387.693662)
			(xy 115.075757 -387.722667) (xy 115.068446 -387.780215) (xy 115.053923 -387.836379) (xy 115.032421 -387.890257)
			(xy 115.004285 -387.940988) (xy 114.969966 -387.987757) (xy 114.930012 -388.029816) (xy 114.907822 -388.0485)
			(xy 114.90071 -388.054088) (xy 114.891566 -388.069328) (xy 114.876326 -388.152132) (xy 114.87912 -388.169404)
			(xy 114.883692 -388.177532) (xy 114.896263 -388.200721) (xy 114.91414 -388.250341) (xy 114.923242 -388.302292)
			(xy 114.923824 -388.328662) (xy 114.923755 -388.338021) (xy 114.922612 -388.356703) (xy 114.921538 -388.366)
			(xy 114.920522 -388.37489) (xy 114.924332 -388.391654) (xy 114.968274 -388.461504) (xy 114.98199 -388.471918)
			(xy 114.990372 -388.474712) (xy 115.014387 -388.483216) (xy 115.059561 -388.50676) (xy 115.100368 -388.537251)
			(xy 115.13575 -388.573899) (xy 115.164789 -388.615753) (xy 115.18673 -388.661726) (xy 115.194334 -388.68604)
			(xy 115.195858 -388.691882) (xy 115.516152 -389.245602) (xy 115.520216 -389.24992) (xy 115.53641 -389.267636)
			(xy 115.563835 -389.307025) (xy 115.58498 -389.350113) (xy 115.599356 -389.395905) (xy 115.606632 -389.443346)
			(xy 115.607084 -389.467344) (xy 115.606647 -389.492149) (xy 115.598876 -389.541146) (xy 115.583534 -389.588323)
			(xy 115.560997 -389.632518) (xy 115.531822 -389.672642) (xy 115.496727 -389.707705) (xy 115.456577 -389.736845)
			(xy 115.412362 -389.759342) (xy 115.365171 -389.774642) (xy 115.316167 -389.782369) (xy 115.291362 -389.782812)
			(xy 115.265966 -389.782345) (xy 115.215831 -389.774208) (xy 115.167645 -389.758151) (xy 115.122651 -389.734588)
			(xy 115.082008 -389.704126) (xy 115.046766 -389.667551) (xy 115.017833 -389.625806) (xy 114.995956 -389.579968)
			(xy 114.98834 -389.555736) (xy 114.986816 -389.549894) (xy 114.666522 -388.996174) (xy 114.662458 -388.991856)
			(xy 114.646299 -388.974121) (xy 114.618931 -388.93472) (xy 114.59784 -388.89163) (xy 114.583512 -388.845845)
			(xy 114.576278 -388.798419) (xy 114.575844 -388.774432) (xy 114.575925 -388.762384) (xy 114.577707 -388.738355)
			(xy 114.5794 -388.726426) (xy 114.58067 -388.717536) (xy 114.577622 -388.700518) (xy 114.535458 -388.629652)
			(xy 114.52225 -388.618476) (xy 114.513868 -388.615428) (xy 114.49212 -388.607034) (xy 114.451261 -388.584593)
			(xy 114.414291 -388.556199) (xy 114.382068 -388.522514) (xy 114.355343 -388.484319) (xy 114.334737 -388.442506)
			(xy 114.320729 -388.398044) (xy 114.313646 -388.35197) (xy 114.313208 -388.328662) (xy 114.313773 -388.302289)
			(xy 114.322856 -388.25033) (xy 114.340745 -388.20071) (xy 114.35334 -388.177532) (xy 114.357912 -388.169404)
			(xy 114.360706 -388.152132) (xy 114.345466 -388.069328) (xy 114.336322 -388.054088) (xy 114.32921 -388.0485)
			(xy 114.307041 -388.029791) (xy 114.267094 -387.987731) (xy 114.232776 -387.940963) (xy 114.204637 -387.890238)
			(xy 114.183127 -387.836365) (xy 114.16859 -387.780209) (xy 114.161259 -387.722666) (xy 114.160808 -387.693662)
			(xy 114.161411 -387.660341) (xy 114.171069 -387.594403) (xy 114.190189 -387.530564) (xy 114.203734 -387.500114)
			(xy 114.207955 -387.489641) (xy 114.20785 -387.467089) (xy 114.198128 -387.44674) (xy 114.189764 -387.439154)
			(xy 114.167489 -387.420512) (xy 114.127429 -387.37845) (xy 114.093012 -387.331658) (xy 114.064791 -387.280887)
			(xy 114.04322 -387.226954) (xy 114.028646 -387.170726) (xy 114.021302 -387.113105) (xy 114.020854 -387.084062)
			(xy 114.021305 -387.055136) (xy 114.028588 -386.997743) (xy 114.043047 -386.941726) (xy 114.064451 -386.887979)
			(xy 114.092458 -386.837357) (xy 114.126622 -386.790669) (xy 114.166398 -386.74866) (xy 114.188494 -386.729986)
			(xy 114.195471 -386.723644) (xy 114.204725 -386.707236) (xy 114.206528 -386.697982) (xy 114.210846 -386.666994)
			(xy 114.21175 -386.657757) (xy 114.207726 -386.639658) (xy 114.202972 -386.631688) (xy 114.189981 -386.611267)
			(xy 114.169402 -386.567464) (xy 114.155416 -386.521133) (xy 114.148321 -386.47326) (xy 114.147854 -386.449062)
			(xy 114.148234 -386.425386) (xy 114.154968 -386.378515) (xy 114.168335 -386.333088) (xy 114.177826 -386.311394)
			(xy 114.182144 -386.301996) (xy 114.182906 -386.28193) (xy 114.150648 -386.19557) (xy 114.136932 -386.180838)
			(xy 114.127534 -386.17652) (xy 114.103158 -386.164843) (xy 114.058289 -386.134713) (xy 114.018912 -386.097693)
			(xy 113.986074 -386.054765) (xy 113.960649 -386.007072) (xy 113.943312 -385.955881) (xy 113.934525 -385.902553)
			(xy 113.933986 -385.87553) (xy 112.446939 -385.87553) (xy 112.417521 -385.912288) (xy 112.395508 -385.93395)
			(xy 112.386872 -385.942332) (xy 112.378744 -385.964684) (xy 112.390682 -386.069078) (xy 112.403636 -386.08889)
			(xy 112.41405 -386.09524) (xy 112.439386 -386.110753) (xy 112.48624 -386.147278) (xy 112.527972 -386.189559)
			(xy 112.563881 -386.236886) (xy 112.593362 -386.288463) (xy 112.615921 -386.343421) (xy 112.631176 -386.400837)
			(xy 112.638871 -386.459744) (xy 112.639348 -386.489448) (xy 112.638876 -386.520107) (xy 112.630684 -386.580875)
			(xy 112.614453 -386.640006) (xy 112.590474 -386.696441) (xy 112.559177 -386.749169) (xy 112.52112 -386.797248)
			(xy 112.499394 -386.818886) (xy 112.491657 -386.827199) (xy 112.48366 -386.84842) (xy 112.485567 -386.871017)
			(xy 112.490758 -386.881116) (xy 112.504893 -386.906586) (xy 112.524964 -386.961264) (xy 112.535128 -387.018617)
			(xy 112.535716 -387.04774) (xy 112.535206 -387.073727) (xy 112.527076 -387.125062) (xy 112.511015 -387.174492)
			(xy 112.487419 -387.220802) (xy 112.456869 -387.26285) (xy 112.420118 -387.299601) (xy 112.37807 -387.330151)
			(xy 112.33176 -387.353747) (xy 112.28233 -387.369808) (xy 112.230995 -387.377938) (xy 112.179021 -387.377938)
			(xy 112.127686 -387.369808) (xy 112.078256 -387.353747) (xy 112.031946 -387.330151) (xy 111.989898 -387.299601)
			(xy 111.953147 -387.26285) (xy 111.922597 -387.220802) (xy 111.899001 -387.174492) (xy 111.88294 -387.125062)
			(xy 111.87481 -387.073727) (xy 111.8743 -387.04774) (xy 111.87472 -387.023227) (xy 111.881905 -386.97473)
			(xy 111.896181 -386.927829) (xy 111.906304 -386.9055) (xy 111.910681 -386.895032) (xy 111.910727 -386.872371)
			(xy 111.901 -386.851903) (xy 111.892588 -386.844286) (xy 111.870375 -386.825612) (xy 111.830364 -386.783578)
			(xy 111.795991 -386.736822) (xy 111.767807 -386.686093) (xy 111.746265 -386.632208) (xy 111.731711 -386.576031)
			(xy 111.724378 -386.518464) (xy 111.723932 -386.489448) (xy 111.724423 -386.458568) (xy 111.732741 -386.397369)
			(xy 111.749218 -386.337847) (xy 111.773555 -386.281083) (xy 111.805309 -386.228111) (xy 111.843903 -386.179893)
			(xy 111.865918 -386.158232) (xy 111.874554 -386.14985) (xy 111.882682 -386.127498) (xy 111.870744 -386.023104)
			(xy 111.85779 -386.003292) (xy 111.847376 -385.996942) (xy 111.823986 -385.982728) (xy 111.780477 -385.949521)
			(xy 111.741244 -385.911354) (xy 111.70685 -385.868776) (xy 111.677787 -385.822395) (xy 111.665766 -385.797806)
			(xy 111.65967 -385.785106) (xy 111.63681 -385.769612) (xy 111.51997 -385.762246) (xy 111.495586 -385.774692)
			(xy 111.487966 -385.78663) (xy 111.47288 -385.809512) (xy 111.437189 -385.851104) (xy 111.395913 -385.887161)
			(xy 111.349902 -385.91694) (xy 111.300102 -385.939827) (xy 111.24754 -385.955352) (xy 111.193297 -385.963194)
			(xy 111.165894 -385.963668) (xy 111.13864 -385.963262) (xy 111.084687 -385.955504) (xy 111.032388 -385.940146)
			(xy 110.982806 -385.917503) (xy 110.936952 -385.888033) (xy 110.895758 -385.852338) (xy 110.860063 -385.811143)
			(xy 110.830595 -385.765288) (xy 110.807951 -385.715706) (xy 110.792595 -385.663407) (xy 110.784838 -385.609454)
			(xy 102.292219 -385.609454) (xy 102.300024 -385.61518) (xy 102.326114 -385.632849) (xy 102.374145 -385.673638)
			(xy 102.416772 -385.720045) (xy 102.453343 -385.771359) (xy 102.4833 -385.826796) (xy 102.506184 -385.885508)
			(xy 102.521644 -385.946595) (xy 102.529444 -386.009124) (xy 102.529894 -386.04063) (xy 102.529428 -386.07136)
			(xy 102.522017 -386.13237) (xy 102.507305 -386.192042) (xy 102.485509 -386.249507) (xy 102.456944 -386.303924)
			(xy 102.422029 -386.354503) (xy 102.381272 -386.400504) (xy 102.335268 -386.441257) (xy 102.284687 -386.476167)
			(xy 102.230266 -386.504727) (xy 102.1728 -386.526518) (xy 102.113127 -386.541225) (xy 102.052116 -386.548631)
			(xy 102.021386 -386.549138) (xy 101.989172 -386.54864) (xy 101.92526 -386.540497) (xy 101.86289 -386.524344)
			(xy 101.80306 -386.500439) (xy 101.746731 -386.469165) (xy 101.694805 -386.431025) (xy 101.67112 -386.409184)
			(xy 101.65588 -386.39496) (xy 101.614732 -386.395468) (xy 101.580442 -386.429758) (xy 101.572822 -386.447538)
			(xy 101.572568 -386.457444) (xy 101.571238 -386.490183) (xy 101.561197 -386.554933) (xy 101.542925 -386.617858)
			(xy 101.516723 -386.677916) (xy 101.483026 -386.734111) (xy 101.44239 -386.785513) (xy 101.395491 -386.831272)
			(xy 101.343103 -386.870628) (xy 101.286095 -386.902931) (xy 101.22541 -386.927646) (xy 101.162054 -386.944362)
			(xy 101.097076 -386.952804) (xy 101.064314 -386.953252) (xy 101.034342 -386.95249) (xy 101.023674 -386.951728)
			(xy 101.00437 -386.95884) (xy 100.942902 -387.016752) (xy 100.935677 -387.0242) (xy 100.927427 -387.043217)
			(xy 100.9269 -387.053582) (xy 100.9269 -387.084062) (xy 102.411528 -387.084062) (xy 102.415599 -387.02844)
			(xy 102.427725 -386.974003) (xy 102.447648 -386.921912) (xy 102.474944 -386.873277) (xy 102.50903 -386.829134)
			(xy 102.549179 -386.790425) (xy 102.594537 -386.757974) (xy 102.644137 -386.732473) (xy 102.696921 -386.714466)
			(xy 102.751764 -386.704336) (xy 102.807498 -386.702299) (xy 102.862935 -386.708399) (xy 102.916892 -386.722505)
			(xy 102.968221 -386.744317) (xy 103.015827 -386.773371) (xy 103.058695 -386.809046) (xy 103.095912 -386.850583)
			(xy 103.126685 -386.897096) (xy 103.150357 -386.947593) (xy 103.166425 -387.001) (xy 103.174545 -387.056176)
			(xy 103.175054 -387.084062) (xy 103.174545 -387.111948) (xy 103.166425 -387.167124) (xy 103.150357 -387.220531)
			(xy 103.126685 -387.271028) (xy 103.095912 -387.317541) (xy 103.058695 -387.359078) (xy 103.015827 -387.394753)
			(xy 102.968221 -387.423807) (xy 102.916892 -387.445619) (xy 102.862935 -387.459725) (xy 102.807498 -387.465825)
			(xy 102.751764 -387.463788) (xy 102.696921 -387.453658) (xy 102.644137 -387.435651) (xy 102.594537 -387.41015)
			(xy 102.549179 -387.377699) (xy 102.50903 -387.33899) (xy 102.474944 -387.294847) (xy 102.447648 -387.246212)
			(xy 102.427725 -387.194121) (xy 102.415599 -387.139684) (xy 102.411528 -387.084062) (xy 100.9269 -387.084062)
			(xy 100.9269 -387.7945) (xy 104.48493 -387.7945) (xy 104.489001 -387.738878) (xy 104.501127 -387.684441)
			(xy 104.52105 -387.63235) (xy 104.548346 -387.583715) (xy 104.582432 -387.539572) (xy 104.622581 -387.500863)
			(xy 104.667939 -387.468412) (xy 104.717539 -387.442911) (xy 104.770323 -387.424904) (xy 104.825166 -387.414774)
			(xy 104.8809 -387.412737) (xy 104.936337 -387.418837) (xy 104.990294 -387.432943) (xy 105.041623 -387.454755)
			(xy 105.089229 -387.483809) (xy 105.132097 -387.519484) (xy 105.169314 -387.561021) (xy 105.200087 -387.607534)
			(xy 105.223759 -387.658031) (xy 105.239827 -387.711438) (xy 105.247947 -387.766614) (xy 105.248368 -387.789674)
			(xy 107.874308 -387.789674) (xy 107.874873 -387.754718) (xy 107.884438 -387.685464) (xy 107.903399 -387.618173)
			(xy 107.931398 -387.554113) (xy 107.967907 -387.494491) (xy 107.989624 -387.467094) (xy 107.994924 -387.460097)
			(xy 108.000897 -387.443604) (xy 108.001308 -387.434836) (xy 108.001308 -387.280912) (xy 108.00094 -387.272135)
			(xy 107.994959 -387.255633) (xy 107.989624 -387.248654) (xy 107.967939 -387.221233) (xy 107.931437 -387.161614)
			(xy 107.903438 -387.097559) (xy 107.884471 -387.030275) (xy 107.874892 -386.961027) (xy 107.874308 -386.926074)
			(xy 107.874732 -386.895342) (xy 107.882143 -386.834326) (xy 107.896856 -386.774648) (xy 107.918654 -386.717179)
			(xy 107.94722 -386.662757) (xy 107.982138 -386.612174) (xy 108.022899 -386.566169) (xy 108.068907 -386.525412)
			(xy 108.119492 -386.490499) (xy 108.173918 -386.461937) (xy 108.231389 -386.440143) (xy 108.291067 -386.425436)
			(xy 108.352084 -386.418029) (xy 108.382816 -386.417566) (xy 108.403551 -386.417797) (xy 108.444878 -386.421229)
			(xy 108.465366 -386.424424) (xy 108.474022 -386.425479) (xy 108.491166 -386.422366) (xy 108.498894 -386.418328)
			(xy 108.524802 -386.403342) (xy 108.532111 -386.398792) (xy 108.543406 -386.385811) (xy 108.5469 -386.377942)
			(xy 108.557909 -386.351693) (xy 108.586524 -386.302493) (xy 108.622131 -386.25809) (xy 108.663941 -386.219471)
			(xy 108.711025 -386.187493) (xy 108.762338 -386.162866) (xy 108.816741 -386.146137) (xy 108.873026 -386.137678)
			(xy 108.901484 -386.13715) (xy 108.928733 -386.137693) (xy 108.982676 -386.145446) (xy 109.034967 -386.160797)
			(xy 109.084542 -386.183433) (xy 109.13039 -386.212894) (xy 109.171579 -386.24858) (xy 109.207271 -386.289763)
			(xy 109.236739 -386.335607) (xy 109.259382 -386.385178) (xy 109.274741 -386.437467) (xy 109.282503 -386.491409)
			(xy 109.282992 -386.518658) (xy 109.282575 -386.546005) (xy 109.274783 -386.60014) (xy 109.259339 -386.652608)
			(xy 109.23656 -386.702331) (xy 109.206912 -386.748292) (xy 109.171004 -386.789546) (xy 109.129571 -386.825249)
			(xy 109.083464 -386.854668) (xy 109.033628 -386.8772) (xy 108.981084 -386.892383) (xy 108.954062 -386.89661)
			(xy 108.945648 -386.898089) (xy 108.930459 -386.905885) (xy 108.924344 -386.91185) (xy 108.90377 -386.93344)
			(xy 108.897954 -386.939992) (xy 108.890815 -386.955979) (xy 108.8898 -386.964682) (xy 108.886969 -386.99564)
			(xy 108.874755 -387.056594) (xy 108.855202 -387.115605) (xy 108.828602 -387.171792) (xy 108.79535 -387.224318)
			(xy 108.776008 -387.248654) (xy 108.770721 -387.255659) (xy 108.764742 -387.272146) (xy 108.764324 -387.280912)
			(xy 108.764324 -387.434836) (xy 108.764684 -387.443613) (xy 108.770672 -387.460115) (xy 108.776008 -387.467094)
			(xy 108.797719 -387.494494) (xy 108.834217 -387.55412) (xy 108.86221 -387.61818) (xy 108.881171 -387.685469)
			(xy 108.890743 -387.754719) (xy 108.891324 -387.789674) (xy 108.890874 -387.820891) (xy 108.883258 -387.88286)
			(xy 108.868113 -387.943429) (xy 108.845666 -388.001689) (xy 108.83138 -388.02945) (xy 108.826808 -388.037578)
			(xy 108.824522 -388.055612) (xy 108.843572 -388.138924) (xy 108.853478 -388.15391) (xy 108.861098 -388.159498)
			(xy 108.881623 -388.174953) (xy 108.91876 -388.210458) (xy 108.950795 -388.250627) (xy 108.977147 -388.294733)
			(xy 108.978404 -388.297674) (xy 110.908844 -388.297674) (xy 110.912915 -388.242052) (xy 110.925041 -388.187615)
			(xy 110.944964 -388.135524) (xy 110.97226 -388.086889) (xy 111.006346 -388.042746) (xy 111.046495 -388.004037)
			(xy 111.091853 -387.971586) (xy 111.141453 -387.946085) (xy 111.194237 -387.928078) (xy 111.24908 -387.917948)
			(xy 111.304814 -387.915911) (xy 111.360251 -387.922011) (xy 111.414208 -387.936117) (xy 111.465537 -387.957929)
			(xy 111.513143 -387.986983) (xy 111.556011 -388.022658) (xy 111.593228 -388.064195) (xy 111.624001 -388.110708)
			(xy 111.647673 -388.161205) (xy 111.663741 -388.214612) (xy 111.671861 -388.269788) (xy 111.67237 -388.297674)
			(xy 111.671923 -388.322137) (xy 111.87481 -388.322137) (xy 111.87481 -388.270163) (xy 111.88294 -388.218828)
			(xy 111.899001 -388.169398) (xy 111.922597 -388.123088) (xy 111.953147 -388.08104) (xy 111.989898 -388.044289)
			(xy 112.031946 -388.013739) (xy 112.078256 -387.990143) (xy 112.127686 -387.974082) (xy 112.179021 -387.965952)
			(xy 112.230995 -387.965952) (xy 112.28233 -387.974082) (xy 112.33176 -387.990143) (xy 112.37807 -388.013739)
			(xy 112.420118 -388.044289) (xy 112.456869 -388.08104) (xy 112.487419 -388.123088) (xy 112.511015 -388.169398)
			(xy 112.527076 -388.218828) (xy 112.535206 -388.270163) (xy 112.535716 -388.29615) (xy 112.535206 -388.322137)
			(xy 112.527076 -388.373472) (xy 112.511015 -388.422902) (xy 112.487419 -388.469212) (xy 112.456869 -388.51126)
			(xy 112.420118 -388.548011) (xy 112.37807 -388.578561) (xy 112.33176 -388.602157) (xy 112.28233 -388.618218)
			(xy 112.230995 -388.626348) (xy 112.179021 -388.626348) (xy 112.127686 -388.618218) (xy 112.078256 -388.602157)
			(xy 112.031946 -388.578561) (xy 111.989898 -388.548011) (xy 111.953147 -388.51126) (xy 111.922597 -388.469212)
			(xy 111.899001 -388.422902) (xy 111.88294 -388.373472) (xy 111.87481 -388.322137) (xy 111.671923 -388.322137)
			(xy 111.671861 -388.32556) (xy 111.663741 -388.380736) (xy 111.647673 -388.434143) (xy 111.624001 -388.48464)
			(xy 111.593228 -388.531153) (xy 111.556011 -388.57269) (xy 111.513143 -388.608365) (xy 111.465537 -388.637419)
			(xy 111.414208 -388.659231) (xy 111.360251 -388.673337) (xy 111.304814 -388.679437) (xy 111.24908 -388.6774)
			(xy 111.194237 -388.66727) (xy 111.141453 -388.649263) (xy 111.091853 -388.623762) (xy 111.046495 -388.591311)
			(xy 111.006346 -388.552602) (xy 110.97226 -388.508459) (xy 110.944964 -388.459824) (xy 110.925041 -388.407733)
			(xy 110.912915 -388.353296) (xy 110.908844 -388.297674) (xy 108.978404 -388.297674) (xy 108.997341 -388.341977)
			(xy 109.011009 -388.391505) (xy 109.017905 -388.442419) (xy 109.018324 -388.468108) (xy 109.017881 -388.495479)
			(xy 109.010061 -388.54966) (xy 108.994567 -388.602164) (xy 108.97172 -388.651911) (xy 108.941989 -388.697876)
			(xy 108.924344 -388.718806) (xy 108.918248 -388.725918) (xy 108.911898 -388.742936) (xy 108.911898 -388.82828)
			(xy 108.918248 -388.845298) (xy 108.924344 -388.85241) (xy 108.942008 -388.873322) (xy 108.971715 -388.919301)
			(xy 108.994546 -388.969053) (xy 109.010031 -389.021558) (xy 109.017853 -389.075738) (xy 109.018324 -389.103108)
			(xy 109.017838 -389.130359) (xy 109.010082 -389.184307) (xy 108.994727 -389.236602) (xy 108.974724 -389.2804)
			(xy 111.234982 -389.2804) (xy 111.235484 -389.248439) (xy 111.243495 -389.185021) (xy 111.259392 -389.123107)
			(xy 111.282924 -389.063674) (xy 111.313718 -389.007659) (xy 111.351291 -388.955944) (xy 111.395048 -388.909347)
			(xy 111.444301 -388.868602) (xy 111.498272 -388.834351) (xy 111.556111 -388.807134) (xy 111.616904 -388.787381)
			(xy 111.679694 -388.775403) (xy 111.74349 -388.77139) (xy 111.807286 -388.775403) (xy 111.870076 -388.787381)
			(xy 111.930869 -388.807134) (xy 111.988708 -388.834351) (xy 112.042679 -388.868602) (xy 112.091932 -388.909347)
			(xy 112.135689 -388.955944) (xy 112.173262 -389.007659) (xy 112.204056 -389.063674) (xy 112.227588 -389.123107)
			(xy 112.243485 -389.185021) (xy 112.251496 -389.248439) (xy 112.251998 -389.2804) (xy 112.251432 -389.314517)
			(xy 112.242305 -389.382137) (xy 112.224215 -389.44793) (xy 112.211358 -389.479536) (xy 112.206786 -389.490204)
			(xy 112.207802 -389.512556) (xy 112.2553 -389.60298) (xy 112.273334 -389.616442) (xy 112.28451 -389.618728)
			(xy 112.315147 -389.625504) (xy 112.37435 -389.646287) (xy 112.430159 -389.674963) (xy 112.481528 -389.710992)
			(xy 112.527495 -389.753701) (xy 112.567197 -389.802287) (xy 112.599891 -389.855841) (xy 112.624963 -389.913359)
			(xy 112.641944 -389.973763) (xy 112.650515 -390.03592) (xy 112.651032 -390.067292) (xy 112.650461 -390.100584)
			(xy 112.641788 -390.160002) (xy 114.185204 -390.160002) (xy 114.189164 -390.110948) (xy 114.200941 -390.063164)
			(xy 114.220232 -390.017888) (xy 114.246535 -389.976292) (xy 114.27917 -389.939455) (xy 114.317291 -389.90833)
			(xy 114.359912 -389.883723) (xy 114.405928 -389.866271) (xy 114.454147 -389.856427) (xy 114.503322 -389.854446)
			(xy 114.552177 -389.860378) (xy 114.599448 -389.87407) (xy 114.64391 -389.895168) (xy 114.684413 -389.923124)
			(xy 114.719906 -389.957216) (xy 114.749471 -389.99656) (xy 114.772342 -390.040137) (xy 114.787926 -390.086818)
			(xy 114.795821 -390.135395) (xy 114.796316 -390.160002) (xy 115.385354 -390.160002) (xy 115.389314 -390.110948)
			(xy 115.401091 -390.063164) (xy 115.420382 -390.017888) (xy 115.446685 -389.976292) (xy 115.47932 -389.939455)
			(xy 115.517441 -389.90833) (xy 115.560062 -389.883723) (xy 115.606078 -389.866271) (xy 115.654297 -389.856427)
			(xy 115.703472 -389.854446) (xy 115.752327 -389.860378) (xy 115.799598 -389.87407) (xy 115.84406 -389.895168)
			(xy 115.884563 -389.923124) (xy 115.920056 -389.957216) (xy 115.949621 -389.99656) (xy 115.972492 -390.040137)
			(xy 115.988076 -390.086818) (xy 115.995971 -390.135395) (xy 115.996466 -390.160002) (xy 116.585504 -390.160002)
			(xy 116.589464 -390.110948) (xy 116.601241 -390.063164) (xy 116.620532 -390.017888) (xy 116.646835 -389.976292)
			(xy 116.67947 -389.939455) (xy 116.717591 -389.90833) (xy 116.760212 -389.883723) (xy 116.806228 -389.866271)
			(xy 116.854447 -389.856427) (xy 116.903622 -389.854446) (xy 116.952477 -389.860378) (xy 116.999748 -389.87407)
			(xy 117.04421 -389.895168) (xy 117.084713 -389.923124) (xy 117.120206 -389.957216) (xy 117.149771 -389.99656)
			(xy 117.172642 -390.040137) (xy 117.188226 -390.086818) (xy 117.196121 -390.135395) (xy 117.196616 -390.160002)
			(xy 117.7854 -390.160002) (xy 117.78936 -390.110948) (xy 117.801137 -390.063164) (xy 117.820428 -390.017888)
			(xy 117.846731 -389.976292) (xy 117.879366 -389.939455) (xy 117.917487 -389.90833) (xy 117.960108 -389.883723)
			(xy 118.006124 -389.866271) (xy 118.054343 -389.856427) (xy 118.103518 -389.854446) (xy 118.152373 -389.860378)
			(xy 118.199644 -389.87407) (xy 118.244106 -389.895168) (xy 118.284609 -389.923124) (xy 118.320102 -389.957216)
			(xy 118.349667 -389.99656) (xy 118.372538 -390.040137) (xy 118.388122 -390.086818) (xy 118.396017 -390.135395)
			(xy 118.396512 -390.160002) (xy 118.98555 -390.160002) (xy 118.98951 -390.110948) (xy 119.001287 -390.063164)
			(xy 119.020578 -390.017888) (xy 119.046881 -389.976292) (xy 119.079516 -389.939455) (xy 119.117637 -389.90833)
			(xy 119.160258 -389.883723) (xy 119.206274 -389.866271) (xy 119.254493 -389.856427) (xy 119.303668 -389.854446)
			(xy 119.352523 -389.860378) (xy 119.399794 -389.87407) (xy 119.444256 -389.895168) (xy 119.484759 -389.923124)
			(xy 119.520252 -389.957216) (xy 119.549817 -389.99656) (xy 119.572688 -390.040137) (xy 119.588272 -390.086818)
			(xy 119.596167 -390.135395) (xy 119.596662 -390.160002) (xy 120.185446 -390.160002) (xy 120.189406 -390.110948)
			(xy 120.201183 -390.063164) (xy 120.220474 -390.017888) (xy 120.246777 -389.976292) (xy 120.279412 -389.939455)
			(xy 120.317533 -389.90833) (xy 120.360154 -389.883723) (xy 120.40617 -389.866271) (xy 120.454389 -389.856427)
			(xy 120.503564 -389.854446) (xy 120.552419 -389.860378) (xy 120.59969 -389.87407) (xy 120.644152 -389.895168)
			(xy 120.684655 -389.923124) (xy 120.720148 -389.957216) (xy 120.749713 -389.99656) (xy 120.772584 -390.040137)
			(xy 120.788168 -390.086818) (xy 120.796063 -390.135395) (xy 120.796558 -390.160002) (xy 121.385342 -390.160002)
			(xy 121.389302 -390.110948) (xy 121.401079 -390.063164) (xy 121.42037 -390.017888) (xy 121.446673 -389.976292)
			(xy 121.479308 -389.939455) (xy 121.517429 -389.90833) (xy 121.56005 -389.883723) (xy 121.606066 -389.866271)
			(xy 121.654285 -389.856427) (xy 121.70346 -389.854446) (xy 121.752315 -389.860378) (xy 121.799586 -389.87407)
			(xy 121.844048 -389.895168) (xy 121.884551 -389.923124) (xy 121.920044 -389.957216) (xy 121.949609 -389.99656)
			(xy 121.97248 -390.040137) (xy 121.988064 -390.086818) (xy 121.995959 -390.135395) (xy 121.996454 -390.160002)
			(xy 122.585492 -390.160002) (xy 122.589452 -390.110948) (xy 122.601229 -390.063164) (xy 122.62052 -390.017888)
			(xy 122.646823 -389.976292) (xy 122.679458 -389.939455) (xy 122.717579 -389.90833) (xy 122.7602 -389.883723)
			(xy 122.806216 -389.866271) (xy 122.854435 -389.856427) (xy 122.90361 -389.854446) (xy 122.952465 -389.860378)
			(xy 122.999736 -389.87407) (xy 123.044198 -389.895168) (xy 123.084701 -389.923124) (xy 123.120194 -389.957216)
			(xy 123.149759 -389.99656) (xy 123.17263 -390.040137) (xy 123.188214 -390.086818) (xy 123.196109 -390.135395)
			(xy 123.196604 -390.160002) (xy 123.785388 -390.160002) (xy 123.789348 -390.110948) (xy 123.801125 -390.063164)
			(xy 123.820416 -390.017888) (xy 123.846719 -389.976292) (xy 123.879354 -389.939455) (xy 123.917475 -389.90833)
			(xy 123.960096 -389.883723) (xy 124.006112 -389.866271) (xy 124.054331 -389.856427) (xy 124.103506 -389.854446)
			(xy 124.152361 -389.860378) (xy 124.199632 -389.87407) (xy 124.244094 -389.895168) (xy 124.284597 -389.923124)
			(xy 124.32009 -389.957216) (xy 124.349655 -389.99656) (xy 124.372526 -390.040137) (xy 124.38811 -390.086818)
			(xy 124.396005 -390.135395) (xy 124.3965 -390.160002) (xy 124.985538 -390.160002) (xy 124.989498 -390.110948)
			(xy 125.001275 -390.063164) (xy 125.020566 -390.017888) (xy 125.046869 -389.976292) (xy 125.079504 -389.939455)
			(xy 125.117625 -389.90833) (xy 125.160246 -389.883723) (xy 125.206262 -389.866271) (xy 125.254481 -389.856427)
			(xy 125.303656 -389.854446) (xy 125.352511 -389.860378) (xy 125.399782 -389.87407) (xy 125.444244 -389.895168)
			(xy 125.484747 -389.923124) (xy 125.52024 -389.957216) (xy 125.549805 -389.99656) (xy 125.572676 -390.040137)
			(xy 125.58826 -390.086818) (xy 125.596155 -390.135395) (xy 125.59665 -390.160002) (xy 126.185434 -390.160002)
			(xy 126.189394 -390.110948) (xy 126.201171 -390.063164) (xy 126.220462 -390.017888) (xy 126.246765 -389.976292)
			(xy 126.2794 -389.939455) (xy 126.317521 -389.90833) (xy 126.360142 -389.883723) (xy 126.406158 -389.866271)
			(xy 126.454377 -389.856427) (xy 126.503552 -389.854446) (xy 126.552407 -389.860378) (xy 126.599678 -389.87407)
			(xy 126.64414 -389.895168) (xy 126.684643 -389.923124) (xy 126.720136 -389.957216) (xy 126.749701 -389.99656)
			(xy 126.772572 -390.040137) (xy 126.788156 -390.086818) (xy 126.796051 -390.135395) (xy 126.796546 -390.160002)
			(xy 127.38533 -390.160002) (xy 127.38929 -390.110948) (xy 127.401067 -390.063164) (xy 127.420358 -390.017888)
			(xy 127.446661 -389.976292) (xy 127.479296 -389.939455) (xy 127.517417 -389.90833) (xy 127.560038 -389.883723)
			(xy 127.606054 -389.866271) (xy 127.654273 -389.856427) (xy 127.703448 -389.854446) (xy 127.752303 -389.860378)
			(xy 127.799574 -389.87407) (xy 127.844036 -389.895168) (xy 127.884539 -389.923124) (xy 127.920032 -389.957216)
			(xy 127.949597 -389.99656) (xy 127.972468 -390.040137) (xy 127.988052 -390.086818) (xy 127.995947 -390.135395)
			(xy 127.996442 -390.160002) (xy 128.58548 -390.160002) (xy 128.58944 -390.110948) (xy 128.601217 -390.063164)
			(xy 128.620508 -390.017888) (xy 128.646811 -389.976292) (xy 128.679446 -389.939455) (xy 128.717567 -389.90833)
			(xy 128.760188 -389.883723) (xy 128.806204 -389.866271) (xy 128.854423 -389.856427) (xy 128.903598 -389.854446)
			(xy 128.952453 -389.860378) (xy 128.999724 -389.87407) (xy 129.044186 -389.895168) (xy 129.084689 -389.923124)
			(xy 129.120182 -389.957216) (xy 129.149747 -389.99656) (xy 129.172618 -390.040137) (xy 129.188202 -390.086818)
			(xy 129.196097 -390.135395) (xy 129.196592 -390.160002) (xy 129.785376 -390.160002) (xy 129.789336 -390.110948)
			(xy 129.801113 -390.063164) (xy 129.820404 -390.017888) (xy 129.846707 -389.976292) (xy 129.879342 -389.939455)
			(xy 129.917463 -389.90833) (xy 129.960084 -389.883723) (xy 130.0061 -389.866271) (xy 130.054319 -389.856427)
			(xy 130.103494 -389.854446) (xy 130.152349 -389.860378) (xy 130.19962 -389.87407) (xy 130.244082 -389.895168)
			(xy 130.284585 -389.923124) (xy 130.320078 -389.957216) (xy 130.349643 -389.99656) (xy 130.372514 -390.040137)
			(xy 130.388098 -390.086818) (xy 130.395993 -390.135395) (xy 130.396488 -390.160002) (xy 130.985526 -390.160002)
			(xy 130.989486 -390.110948) (xy 131.001263 -390.063164) (xy 131.020554 -390.017888) (xy 131.046857 -389.976292)
			(xy 131.079492 -389.939455) (xy 131.117613 -389.90833) (xy 131.160234 -389.883723) (xy 131.20625 -389.866271)
			(xy 131.254469 -389.856427) (xy 131.303644 -389.854446) (xy 131.352499 -389.860378) (xy 131.39977 -389.87407)
			(xy 131.444232 -389.895168) (xy 131.484735 -389.923124) (xy 131.520228 -389.957216) (xy 131.549793 -389.99656)
			(xy 131.572664 -390.040137) (xy 131.588248 -390.086818) (xy 131.596143 -390.135395) (xy 131.596638 -390.160002)
			(xy 132.185422 -390.160002) (xy 132.189382 -390.110948) (xy 132.201159 -390.063164) (xy 132.22045 -390.017888)
			(xy 132.246753 -389.976292) (xy 132.279388 -389.939455) (xy 132.317509 -389.90833) (xy 132.36013 -389.883723)
			(xy 132.406146 -389.866271) (xy 132.454365 -389.856427) (xy 132.50354 -389.854446) (xy 132.552395 -389.860378)
			(xy 132.599666 -389.87407) (xy 132.644128 -389.895168) (xy 132.684631 -389.923124) (xy 132.720124 -389.957216)
			(xy 132.749689 -389.99656) (xy 132.77256 -390.040137) (xy 132.788144 -390.086818) (xy 132.796039 -390.135395)
			(xy 132.796534 -390.160002) (xy 132.796039 -390.184609) (xy 132.795815 -390.185989) (xy 133.515102 -390.185989)
			(xy 133.515102 -390.134015) (xy 133.523232 -390.08268) (xy 133.539293 -390.03325) (xy 133.562889 -389.98694)
			(xy 133.593439 -389.944892) (xy 133.63019 -389.908141) (xy 133.672238 -389.877591) (xy 133.718548 -389.853995)
			(xy 133.767978 -389.837934) (xy 133.819313 -389.829804) (xy 133.871287 -389.829804) (xy 133.922622 -389.837934)
			(xy 133.972052 -389.853995) (xy 134.018362 -389.877591) (xy 134.06041 -389.908141) (xy 134.097161 -389.944892)
			(xy 134.127711 -389.98694) (xy 134.151307 -390.03325) (xy 134.167368 -390.08268) (xy 134.175498 -390.134015)
			(xy 134.176008 -390.160002) (xy 134.175498 -390.185989) (xy 134.167368 -390.237324) (xy 134.151307 -390.286754)
			(xy 134.127711 -390.333064) (xy 134.097161 -390.375112) (xy 134.06041 -390.411863) (xy 134.018362 -390.442413)
			(xy 133.972052 -390.466009) (xy 133.922622 -390.48207) (xy 133.871287 -390.4902) (xy 133.819313 -390.4902)
			(xy 133.767978 -390.48207) (xy 133.718548 -390.466009) (xy 133.672238 -390.442413) (xy 133.63019 -390.411863)
			(xy 133.593439 -390.375112) (xy 133.562889 -390.333064) (xy 133.539293 -390.286754) (xy 133.523232 -390.237324)
			(xy 133.515102 -390.185989) (xy 132.795815 -390.185989) (xy 132.788144 -390.233186) (xy 132.77256 -390.279867)
			(xy 132.749689 -390.323444) (xy 132.720124 -390.362788) (xy 132.684631 -390.39688) (xy 132.644128 -390.424836)
			(xy 132.599666 -390.445934) (xy 132.552395 -390.459626) (xy 132.50354 -390.465558) (xy 132.454365 -390.463577)
			(xy 132.406146 -390.453733) (xy 132.36013 -390.436281) (xy 132.317509 -390.411674) (xy 132.279388 -390.380549)
			(xy 132.246753 -390.343712) (xy 132.22045 -390.302116) (xy 132.201159 -390.25684) (xy 132.189382 -390.209056)
			(xy 132.185422 -390.160002) (xy 131.596638 -390.160002) (xy 131.596143 -390.184609) (xy 131.588248 -390.233186)
			(xy 131.572664 -390.279867) (xy 131.549793 -390.323444) (xy 131.520228 -390.362788) (xy 131.484735 -390.39688)
			(xy 131.444232 -390.424836) (xy 131.39977 -390.445934) (xy 131.352499 -390.459626) (xy 131.303644 -390.465558)
			(xy 131.254469 -390.463577) (xy 131.20625 -390.453733) (xy 131.160234 -390.436281) (xy 131.117613 -390.411674)
			(xy 131.079492 -390.380549) (xy 131.046857 -390.343712) (xy 131.020554 -390.302116) (xy 131.001263 -390.25684)
			(xy 130.989486 -390.209056) (xy 130.985526 -390.160002) (xy 130.396488 -390.160002) (xy 130.395993 -390.184609)
			(xy 130.388098 -390.233186) (xy 130.372514 -390.279867) (xy 130.349643 -390.323444) (xy 130.320078 -390.362788)
			(xy 130.284585 -390.39688) (xy 130.244082 -390.424836) (xy 130.19962 -390.445934) (xy 130.152349 -390.459626)
			(xy 130.103494 -390.465558) (xy 130.054319 -390.463577) (xy 130.0061 -390.453733) (xy 129.960084 -390.436281)
			(xy 129.917463 -390.411674) (xy 129.879342 -390.380549) (xy 129.846707 -390.343712) (xy 129.820404 -390.302116)
			(xy 129.801113 -390.25684) (xy 129.789336 -390.209056) (xy 129.785376 -390.160002) (xy 129.196592 -390.160002)
			(xy 129.196097 -390.184609) (xy 129.188202 -390.233186) (xy 129.172618 -390.279867) (xy 129.149747 -390.323444)
			(xy 129.120182 -390.362788) (xy 129.084689 -390.39688) (xy 129.044186 -390.424836) (xy 128.999724 -390.445934)
			(xy 128.952453 -390.459626) (xy 128.903598 -390.465558) (xy 128.854423 -390.463577) (xy 128.806204 -390.453733)
			(xy 128.760188 -390.436281) (xy 128.717567 -390.411674) (xy 128.679446 -390.380549) (xy 128.646811 -390.343712)
			(xy 128.620508 -390.302116) (xy 128.601217 -390.25684) (xy 128.58944 -390.209056) (xy 128.58548 -390.160002)
			(xy 127.996442 -390.160002) (xy 127.995947 -390.184609) (xy 127.988052 -390.233186) (xy 127.972468 -390.279867)
			(xy 127.949597 -390.323444) (xy 127.920032 -390.362788) (xy 127.884539 -390.39688) (xy 127.844036 -390.424836)
			(xy 127.799574 -390.445934) (xy 127.752303 -390.459626) (xy 127.703448 -390.465558) (xy 127.654273 -390.463577)
			(xy 127.606054 -390.453733) (xy 127.560038 -390.436281) (xy 127.517417 -390.411674) (xy 127.479296 -390.380549)
			(xy 127.446661 -390.343712) (xy 127.420358 -390.302116) (xy 127.401067 -390.25684) (xy 127.38929 -390.209056)
			(xy 127.38533 -390.160002) (xy 126.796546 -390.160002) (xy 126.796051 -390.184609) (xy 126.788156 -390.233186)
			(xy 126.772572 -390.279867) (xy 126.749701 -390.323444) (xy 126.720136 -390.362788) (xy 126.684643 -390.39688)
			(xy 126.64414 -390.424836) (xy 126.599678 -390.445934) (xy 126.552407 -390.459626) (xy 126.503552 -390.465558)
			(xy 126.454377 -390.463577) (xy 126.406158 -390.453733) (xy 126.360142 -390.436281) (xy 126.317521 -390.411674)
			(xy 126.2794 -390.380549) (xy 126.246765 -390.343712) (xy 126.220462 -390.302116) (xy 126.201171 -390.25684)
			(xy 126.189394 -390.209056) (xy 126.185434 -390.160002) (xy 125.59665 -390.160002) (xy 125.596155 -390.184609)
			(xy 125.58826 -390.233186) (xy 125.572676 -390.279867) (xy 125.549805 -390.323444) (xy 125.52024 -390.362788)
			(xy 125.484747 -390.39688) (xy 125.444244 -390.424836) (xy 125.399782 -390.445934) (xy 125.352511 -390.459626)
			(xy 125.303656 -390.465558) (xy 125.254481 -390.463577) (xy 125.206262 -390.453733) (xy 125.160246 -390.436281)
			(xy 125.117625 -390.411674) (xy 125.079504 -390.380549) (xy 125.046869 -390.343712) (xy 125.020566 -390.302116)
			(xy 125.001275 -390.25684) (xy 124.989498 -390.209056) (xy 124.985538 -390.160002) (xy 124.3965 -390.160002)
			(xy 124.396005 -390.184609) (xy 124.38811 -390.233186) (xy 124.372526 -390.279867) (xy 124.349655 -390.323444)
			(xy 124.32009 -390.362788) (xy 124.284597 -390.39688) (xy 124.244094 -390.424836) (xy 124.199632 -390.445934)
			(xy 124.152361 -390.459626) (xy 124.103506 -390.465558) (xy 124.054331 -390.463577) (xy 124.006112 -390.453733)
			(xy 123.960096 -390.436281) (xy 123.917475 -390.411674) (xy 123.879354 -390.380549) (xy 123.846719 -390.343712)
			(xy 123.820416 -390.302116) (xy 123.801125 -390.25684) (xy 123.789348 -390.209056) (xy 123.785388 -390.160002)
			(xy 123.196604 -390.160002) (xy 123.196109 -390.184609) (xy 123.188214 -390.233186) (xy 123.17263 -390.279867)
			(xy 123.149759 -390.323444) (xy 123.120194 -390.362788) (xy 123.084701 -390.39688) (xy 123.044198 -390.424836)
			(xy 122.999736 -390.445934) (xy 122.952465 -390.459626) (xy 122.90361 -390.465558) (xy 122.854435 -390.463577)
			(xy 122.806216 -390.453733) (xy 122.7602 -390.436281) (xy 122.717579 -390.411674) (xy 122.679458 -390.380549)
			(xy 122.646823 -390.343712) (xy 122.62052 -390.302116) (xy 122.601229 -390.25684) (xy 122.589452 -390.209056)
			(xy 122.585492 -390.160002) (xy 121.996454 -390.160002) (xy 121.995959 -390.184609) (xy 121.988064 -390.233186)
			(xy 121.97248 -390.279867) (xy 121.949609 -390.323444) (xy 121.920044 -390.362788) (xy 121.884551 -390.39688)
			(xy 121.844048 -390.424836) (xy 121.799586 -390.445934) (xy 121.752315 -390.459626) (xy 121.70346 -390.465558)
			(xy 121.654285 -390.463577) (xy 121.606066 -390.453733) (xy 121.56005 -390.436281) (xy 121.517429 -390.411674)
			(xy 121.479308 -390.380549) (xy 121.446673 -390.343712) (xy 121.42037 -390.302116) (xy 121.401079 -390.25684)
			(xy 121.389302 -390.209056) (xy 121.385342 -390.160002) (xy 120.796558 -390.160002) (xy 120.796063 -390.184609)
			(xy 120.788168 -390.233186) (xy 120.772584 -390.279867) (xy 120.749713 -390.323444) (xy 120.720148 -390.362788)
			(xy 120.684655 -390.39688) (xy 120.644152 -390.424836) (xy 120.59969 -390.445934) (xy 120.552419 -390.459626)
			(xy 120.503564 -390.465558) (xy 120.454389 -390.463577) (xy 120.40617 -390.453733) (xy 120.360154 -390.436281)
			(xy 120.317533 -390.411674) (xy 120.279412 -390.380549) (xy 120.246777 -390.343712) (xy 120.220474 -390.302116)
			(xy 120.201183 -390.25684) (xy 120.189406 -390.209056) (xy 120.185446 -390.160002) (xy 119.596662 -390.160002)
			(xy 119.596167 -390.184609) (xy 119.588272 -390.233186) (xy 119.572688 -390.279867) (xy 119.549817 -390.323444)
			(xy 119.520252 -390.362788) (xy 119.484759 -390.39688) (xy 119.444256 -390.424836) (xy 119.399794 -390.445934)
			(xy 119.352523 -390.459626) (xy 119.303668 -390.465558) (xy 119.254493 -390.463577) (xy 119.206274 -390.453733)
			(xy 119.160258 -390.436281) (xy 119.117637 -390.411674) (xy 119.079516 -390.380549) (xy 119.046881 -390.343712)
			(xy 119.020578 -390.302116) (xy 119.001287 -390.25684) (xy 118.98951 -390.209056) (xy 118.98555 -390.160002)
			(xy 118.396512 -390.160002) (xy 118.396017 -390.184609) (xy 118.388122 -390.233186) (xy 118.372538 -390.279867)
			(xy 118.349667 -390.323444) (xy 118.320102 -390.362788) (xy 118.284609 -390.39688) (xy 118.244106 -390.424836)
			(xy 118.199644 -390.445934) (xy 118.152373 -390.459626) (xy 118.103518 -390.465558) (xy 118.054343 -390.463577)
			(xy 118.006124 -390.453733) (xy 117.960108 -390.436281) (xy 117.917487 -390.411674) (xy 117.879366 -390.380549)
			(xy 117.846731 -390.343712) (xy 117.820428 -390.302116) (xy 117.801137 -390.25684) (xy 117.78936 -390.209056)
			(xy 117.7854 -390.160002) (xy 117.196616 -390.160002) (xy 117.196121 -390.184609) (xy 117.188226 -390.233186)
			(xy 117.172642 -390.279867) (xy 117.149771 -390.323444) (xy 117.120206 -390.362788) (xy 117.084713 -390.39688)
			(xy 117.04421 -390.424836) (xy 116.999748 -390.445934) (xy 116.952477 -390.459626) (xy 116.903622 -390.465558)
			(xy 116.854447 -390.463577) (xy 116.806228 -390.453733) (xy 116.760212 -390.436281) (xy 116.717591 -390.411674)
			(xy 116.67947 -390.380549) (xy 116.646835 -390.343712) (xy 116.620532 -390.302116) (xy 116.601241 -390.25684)
			(xy 116.589464 -390.209056) (xy 116.585504 -390.160002) (xy 115.996466 -390.160002) (xy 115.995971 -390.184609)
			(xy 115.988076 -390.233186) (xy 115.972492 -390.279867) (xy 115.949621 -390.323444) (xy 115.920056 -390.362788)
			(xy 115.884563 -390.39688) (xy 115.84406 -390.424836) (xy 115.799598 -390.445934) (xy 115.752327 -390.459626)
			(xy 115.703472 -390.465558) (xy 115.654297 -390.463577) (xy 115.606078 -390.453733) (xy 115.560062 -390.436281)
			(xy 115.517441 -390.411674) (xy 115.47932 -390.380549) (xy 115.446685 -390.343712) (xy 115.420382 -390.302116)
			(xy 115.401091 -390.25684) (xy 115.389314 -390.209056) (xy 115.385354 -390.160002) (xy 114.796316 -390.160002)
			(xy 114.795821 -390.184609) (xy 114.787926 -390.233186) (xy 114.772342 -390.279867) (xy 114.749471 -390.323444)
			(xy 114.719906 -390.362788) (xy 114.684413 -390.39688) (xy 114.64391 -390.424836) (xy 114.599448 -390.445934)
			(xy 114.552177 -390.459626) (xy 114.503322 -390.465558) (xy 114.454147 -390.463577) (xy 114.405928 -390.453733)
			(xy 114.359912 -390.436281) (xy 114.317291 -390.411674) (xy 114.27917 -390.380549) (xy 114.246535 -390.343712)
			(xy 114.220232 -390.302116) (xy 114.200941 -390.25684) (xy 114.189164 -390.209056) (xy 114.185204 -390.160002)
			(xy 112.641788 -390.160002) (xy 112.640844 -390.166468) (xy 112.621769 -390.230259) (xy 112.59364 -390.290608)
			(xy 112.575848 -390.318752) (xy 112.570803 -390.327277) (xy 112.566985 -390.346693) (xy 112.570798 -390.366111)
			(xy 112.575848 -390.374632) (xy 112.593623 -390.402783) (xy 112.621716 -390.463142) (xy 112.640786 -390.526929)
			(xy 112.650429 -390.592804) (xy 112.651032 -390.626092) (xy 112.650587 -390.655392) (xy 112.643141 -390.713515)
			(xy 112.628318 -390.770208) (xy 112.617758 -390.797542) (xy 112.613694 -390.807194) (xy 112.614202 -390.82726)
			(xy 112.652048 -390.913112) (xy 112.666526 -390.927082) (xy 112.676432 -390.930638) (xy 112.699801 -390.939818)
			(xy 112.743646 -390.964279) (xy 112.783291 -390.995085) (xy 112.817825 -391.031528) (xy 112.846454 -391.072773)
			(xy 112.868522 -391.11787) (xy 112.88352 -391.165784) (xy 112.891105 -391.215415) (xy 112.89157 -391.240518)
			(xy 112.89106 -391.266505) (xy 112.88293 -391.31784) (xy 112.866869 -391.36727) (xy 112.843273 -391.41358)
			(xy 112.812723 -391.455628) (xy 112.775972 -391.492379) (xy 112.733924 -391.522929) (xy 112.687614 -391.546525)
			(xy 112.638184 -391.562586) (xy 112.586849 -391.570716) (xy 112.534875 -391.570716) (xy 112.48354 -391.562586)
			(xy 112.43411 -391.546525) (xy 112.3878 -391.522929) (xy 112.345752 -391.492379) (xy 112.309001 -391.455628)
			(xy 112.278451 -391.41358) (xy 112.254855 -391.36727) (xy 112.238794 -391.31784) (xy 112.230664 -391.266505)
			(xy 112.230154 -391.240518) (xy 112.230256 -391.229307) (xy 112.231782 -391.206936) (xy 112.233202 -391.195814)
			(xy 112.234726 -391.1854) (xy 112.229392 -391.165842) (xy 112.171734 -391.091928) (xy 112.153954 -391.082276)
			(xy 112.14354 -391.081006) (xy 112.113355 -391.077184) (xy 112.054279 -391.062624) (xy 111.997654 -391.040363)
			(xy 111.944478 -391.010794) (xy 111.895691 -390.974439) (xy 111.852151 -390.931939) (xy 111.814628 -390.884044)
			(xy 111.783783 -390.831598) (xy 111.76016 -390.775528) (xy 111.744177 -390.716821) (xy 111.736115 -390.656514)
			(xy 111.735616 -390.626092) (xy 111.736172 -390.5928) (xy 111.745792 -390.526915) (xy 111.764871 -390.463123)
			(xy 111.793006 -390.402776) (xy 111.8108 -390.374632) (xy 111.815862 -390.366115) (xy 111.81968 -390.346693)
			(xy 111.815857 -390.327272) (xy 111.8108 -390.318752) (xy 111.793024 -390.290601) (xy 111.76493 -390.230242)
			(xy 111.745861 -390.166455) (xy 111.736218 -390.10058) (xy 111.735616 -390.067292) (xy 111.735953 -390.042018)
			(xy 111.741526 -389.991777) (xy 111.752604 -389.942457) (xy 111.760508 -389.918448) (xy 111.764318 -389.907272)
			(xy 111.761778 -389.88492) (xy 111.708184 -389.798306) (xy 111.689134 -389.786114) (xy 111.677704 -389.78459)
			(xy 111.644735 -389.779733) (xy 111.580345 -389.762563) (xy 111.51875 -389.737128) (xy 111.461006 -389.703863)
			(xy 111.408102 -389.66334) (xy 111.360947 -389.616253) (xy 111.320347 -389.563408) (xy 111.286999 -389.505712)
			(xy 111.261474 -389.444154) (xy 111.244211 -389.379789) (xy 111.235505 -389.31372) (xy 111.234982 -389.2804)
			(xy 108.974724 -389.2804) (xy 108.972085 -389.286179) (xy 108.942619 -389.332029) (xy 108.906928 -389.37322)
			(xy 108.865737 -389.408911) (xy 108.819887 -389.438377) (xy 108.77031 -389.461019) (xy 108.718015 -389.476374)
			(xy 108.664067 -389.48413) (xy 108.609565 -389.48413) (xy 108.555617 -389.476374) (xy 108.503322 -389.461019)
			(xy 108.453745 -389.438377) (xy 108.407895 -389.408911) (xy 108.366704 -389.37322) (xy 108.331013 -389.332029)
			(xy 108.301547 -389.286179) (xy 108.278905 -389.236602) (xy 108.26355 -389.184307) (xy 108.255794 -389.130359)
			(xy 108.255308 -389.103108) (xy 108.255777 -389.075738) (xy 108.263594 -389.021559) (xy 108.279082 -388.969056)
			(xy 108.301923 -388.919309) (xy 108.331647 -388.873342) (xy 108.349288 -388.85241) (xy 108.355384 -388.845298)
			(xy 108.361734 -388.82828) (xy 108.361734 -388.742936) (xy 108.355384 -388.725918) (xy 108.349288 -388.718806)
			(xy 108.331636 -388.697884) (xy 108.301927 -388.651908) (xy 108.279094 -388.602158) (xy 108.263605 -388.549655)
			(xy 108.25578 -388.495478) (xy 108.255308 -388.468108) (xy 108.255595 -388.446584) (xy 108.260432 -388.403809)
			(xy 108.26496 -388.382764) (xy 108.266992 -388.37362) (xy 108.264706 -388.355586) (xy 108.22432 -388.280148)
			(xy 108.210858 -388.26821) (xy 108.201968 -388.264908) (xy 108.173445 -388.25354) (xy 108.119099 -388.224958)
			(xy 108.068592 -388.190039) (xy 108.022659 -388.14929) (xy 107.981968 -388.103306) (xy 107.947112 -388.052755)
			(xy 107.918598 -387.998374) (xy 107.896843 -387.940954) (xy 107.882162 -387.881332) (xy 107.874769 -387.820376)
			(xy 107.874308 -387.789674) (xy 105.248368 -387.789674) (xy 105.248456 -387.7945) (xy 105.247947 -387.822386)
			(xy 105.239827 -387.877562) (xy 105.223759 -387.930969) (xy 105.200087 -387.981466) (xy 105.169314 -388.027979)
			(xy 105.132097 -388.069516) (xy 105.089229 -388.105191) (xy 105.041623 -388.134245) (xy 104.990294 -388.156057)
			(xy 104.936337 -388.170163) (xy 104.8809 -388.176263) (xy 104.825166 -388.174226) (xy 104.770323 -388.164096)
			(xy 104.717539 -388.146089) (xy 104.667939 -388.120588) (xy 104.622581 -388.088137) (xy 104.582432 -388.049428)
			(xy 104.548346 -388.005285) (xy 104.52105 -387.95665) (xy 104.501127 -387.904559) (xy 104.489001 -387.850122)
			(xy 104.48493 -387.7945) (xy 100.9269 -387.7945) (xy 100.9269 -388.398258) (xy 100.92743 -388.408249)
			(xy 100.935133 -388.426692) (xy 100.941886 -388.434072) (xy 101.03739 -388.529576) (xy 101.050598 -388.5438)
			(xy 101.058587 -388.551913) (xy 101.079498 -388.560846) (xy 101.10222 -388.559965) (xy 101.112574 -388.55523)
			(xy 101.140168 -388.541313) (xy 101.198743 -388.521615) (xy 101.259729 -388.51163) (xy 101.290628 -388.511034)
			(xy 101.317997 -388.511508) (xy 101.372173 -388.519336) (xy 101.424674 -388.534827) (xy 101.474421 -388.557663)
			(xy 101.520393 -388.587376) (xy 101.541326 -388.605014) (xy 101.548438 -388.61111) (xy 101.565456 -388.61746)
			(xy 101.6508 -388.61746) (xy 101.667818 -388.61111) (xy 101.67493 -388.605014) (xy 101.695863 -388.587373)
			(xy 101.741831 -388.557649) (xy 101.791577 -388.534803) (xy 101.844079 -388.519307) (xy 101.898257 -388.511478)
			(xy 101.952999 -388.511478) (xy 102.007177 -388.519307) (xy 102.059679 -388.534803) (xy 102.109425 -388.557649)
			(xy 102.155393 -388.587373) (xy 102.176326 -388.605014) (xy 102.183438 -388.61111) (xy 102.200456 -388.61746)
			(xy 102.2858 -388.61746) (xy 102.302818 -388.61111) (xy 102.30993 -388.605014) (xy 102.330862 -388.587373)
			(xy 102.376829 -388.55765) (xy 102.426576 -388.53481) (xy 102.479079 -388.519323) (xy 102.533258 -388.511508)
			(xy 102.560628 -388.511034) (xy 102.587875 -388.511522) (xy 102.641814 -388.519281) (xy 102.694099 -388.534637)
			(xy 102.743667 -388.557277) (xy 102.789509 -388.586741) (xy 102.830691 -388.622428) (xy 102.866376 -388.663613)
			(xy 102.895836 -388.709457) (xy 102.918473 -388.759027) (xy 102.933825 -388.811314) (xy 102.94158 -388.865253)
			(xy 102.94158 -388.919747) (xy 102.933825 -388.973686) (xy 102.918473 -389.025973) (xy 102.895836 -389.075543)
			(xy 102.866376 -389.121387) (xy 102.830691 -389.162572) (xy 102.789509 -389.198259) (xy 102.743667 -389.227723)
			(xy 102.694099 -389.250363) (xy 102.641814 -389.265719) (xy 102.587875 -389.273478) (xy 102.560628 -389.27405)
			(xy 102.53326 -389.273573) (xy 102.479088 -389.265739) (xy 102.426591 -389.250243) (xy 102.376848 -389.227402)
			(xy 102.330882 -389.197685) (xy 102.30993 -389.18007) (xy 102.302818 -389.173974) (xy 102.2858 -389.167624)
			(xy 102.200456 -389.167624) (xy 102.183438 -389.173974) (xy 102.176326 -389.18007) (xy 102.155393 -389.197711)
			(xy 102.109425 -389.227435) (xy 102.059679 -389.250281) (xy 102.007177 -389.265777) (xy 101.952999 -389.273606)
			(xy 101.898257 -389.273606) (xy 101.844079 -389.265777) (xy 101.791577 -389.250281) (xy 101.741831 -389.227435)
			(xy 101.695863 -389.197711) (xy 101.67493 -389.18007) (xy 101.667818 -389.173974) (xy 101.6508 -389.167624)
			(xy 101.565456 -389.167624) (xy 101.548438 -389.173974) (xy 101.541326 -389.18007) (xy 101.5111 -389.203946)
			(xy 101.501702 -389.21055) (xy 101.49078 -389.229854) (xy 101.48316 -389.3185) (xy 101.482763 -389.329602)
			(xy 101.490396 -389.350435) (xy 101.497892 -389.358632) (xy 102.390194 -390.250934) (xy 102.407269 -390.268636)
			(xy 102.436195 -390.308412) (xy 102.458536 -390.352227) (xy 102.473739 -390.399) (xy 102.48143 -390.447577)
			(xy 102.481888 -390.472168) (xy 102.481888 -393.52093) (xy 105.06837 -393.52093) (xy 105.068832 -393.490233)
			(xy 105.076238 -393.429288) (xy 105.090933 -393.36968) (xy 105.112703 -393.312276) (xy 105.141232 -393.257913)
			(xy 105.158286 -393.232386) (xy 105.163734 -393.223621) (xy 105.167872 -393.203425) (xy 105.163753 -393.183225)
			(xy 105.158286 -393.174474) (xy 105.141252 -393.148935) (xy 105.11274 -393.094568) (xy 105.090976 -393.037166)
			(xy 105.076275 -392.977563) (xy 105.068851 -392.916624) (xy 105.06837 -392.88593) (xy 105.068832 -392.855233)
			(xy 105.076238 -392.794288) (xy 105.090933 -392.73468) (xy 105.112703 -392.677276) (xy 105.141232 -392.622913)
			(xy 105.158286 -392.597386) (xy 105.163734 -392.588621) (xy 105.167872 -392.568425) (xy 105.163753 -392.548225)
			(xy 105.158286 -392.539474) (xy 105.141252 -392.513935) (xy 105.11274 -392.459568) (xy 105.090976 -392.402166)
			(xy 105.076275 -392.342563) (xy 105.068851 -392.281624) (xy 105.06837 -392.25093) (xy 105.068832 -392.220233)
			(xy 105.076238 -392.159288) (xy 105.090933 -392.09968) (xy 105.112703 -392.042276) (xy 105.141232 -391.987913)
			(xy 105.158286 -391.962386) (xy 105.163734 -391.953621) (xy 105.167872 -391.933425) (xy 105.163753 -391.913225)
			(xy 105.158286 -391.904474) (xy 105.141252 -391.878935) (xy 105.11274 -391.824568) (xy 105.090976 -391.767166)
			(xy 105.076275 -391.707563) (xy 105.068851 -391.646624) (xy 105.06837 -391.61593) (xy 105.068828 -391.585437)
			(xy 105.076141 -391.524889) (xy 105.090642 -391.465651) (xy 105.112122 -391.408572) (xy 105.140274 -391.354471)
			(xy 105.174693 -391.304125) (xy 105.214886 -391.258256) (xy 105.260275 -391.217522) (xy 105.31021 -391.182508)
			(xy 105.363973 -391.153716) (xy 105.39222 -391.14222) (xy 105.40111 -391.138664) (xy 105.414826 -391.126218)
			(xy 105.453942 -391.047986) (xy 105.45572 -391.029444) (xy 105.45318 -391.020046) (xy 105.444416 -390.986564)
			(xy 105.434984 -390.917999) (xy 105.434384 -390.883394) (xy 105.434876 -390.852698) (xy 105.442274 -390.791754)
			(xy 105.456962 -390.732146) (xy 105.478726 -390.674742) (xy 105.507248 -390.620378) (xy 105.5243 -390.59485)
			(xy 105.529777 -390.586101) (xy 105.533904 -390.565895) (xy 105.529773 -390.54569) (xy 105.5243 -390.536938)
			(xy 105.50724 -390.511416) (xy 105.478735 -390.457044) (xy 105.456977 -390.399637) (xy 105.442282 -390.340031)
			(xy 105.434862 -390.279089) (xy 105.434384 -390.248394) (xy 105.434853 -390.217842) (xy 105.442166 -390.157177)
			(xy 105.456698 -390.097825) (xy 105.478239 -390.040644) (xy 105.506479 -389.986457) (xy 105.541011 -389.936045)
			(xy 105.581336 -389.890136) (xy 105.603802 -389.869426) (xy 105.61025 -389.863229) (xy 105.618716 -389.847491)
			(xy 105.620312 -389.838692) (xy 105.624376 -389.80872) (xy 105.625278 -389.800006) (xy 105.621762 -389.782856)
			(xy 105.617518 -389.775192) (xy 105.604224 -389.75261) (xy 105.583229 -389.704598) (xy 105.569006 -389.654164)
			(xy 105.561822 -389.602257) (xy 105.561384 -389.576056) (xy 105.561862 -389.548686) (xy 105.569674 -389.494507)
			(xy 105.585159 -389.442003) (xy 105.607999 -389.392256) (xy 105.637723 -389.346289) (xy 105.655364 -389.325358)
			(xy 105.66146 -389.318246) (xy 105.66781 -389.301228) (xy 105.66781 -389.215884) (xy 105.66146 -389.198866)
			(xy 105.655364 -389.191754) (xy 105.637731 -389.170817) (xy 105.60802 -389.124845) (xy 105.585183 -389.075099)
			(xy 105.56969 -389.022599) (xy 105.56186 -388.968425) (xy 105.561384 -388.941056) (xy 105.561837 -388.913804)
			(xy 105.569599 -388.859856) (xy 105.584959 -388.807561) (xy 105.607605 -388.757984) (xy 105.637075 -388.712134)
			(xy 105.67277 -388.670945) (xy 105.713963 -388.635254) (xy 105.759815 -388.605788) (xy 105.809394 -388.583147)
			(xy 105.861691 -388.567791) (xy 105.91564 -388.560034) (xy 105.942892 -388.559548) (xy 105.969653 -388.559964)
			(xy 106.02265 -388.56744) (xy 106.074084 -388.582247) (xy 106.122944 -388.604094) (xy 106.168273 -388.632552)
			(xy 106.189018 -388.649464) (xy 106.198162 -388.657338) (xy 106.221022 -388.662926) (xy 106.323638 -388.639558)
			(xy 106.341926 -388.624826) (xy 106.347006 -388.61365) (xy 106.358728 -388.588968) (xy 106.388149 -388.542925)
			(xy 106.423838 -388.50155) (xy 106.465065 -388.465691) (xy 106.510986 -388.436081) (xy 106.560663 -388.413326)
			(xy 106.613077 -388.397891) (xy 106.667158 -388.390092) (xy 106.694478 -388.389622) (xy 106.721848 -388.390096)
			(xy 106.776027 -388.397911) (xy 106.82853 -388.413398) (xy 106.878277 -388.436238) (xy 106.924244 -388.465961)
			(xy 106.945176 -388.483602) (xy 106.952288 -388.489698) (xy 106.969306 -388.496048) (xy 107.05465 -388.496048)
			(xy 107.071668 -388.489698) (xy 107.07878 -388.483602) (xy 107.099709 -388.465959) (xy 107.145683 -388.436248)
			(xy 107.195431 -388.413413) (xy 107.247932 -388.397922) (xy 107.302109 -388.390095) (xy 107.329478 -388.389622)
			(xy 107.356734 -388.390023) (xy 107.410692 -388.397778) (xy 107.462996 -388.413134) (xy 107.512583 -388.435777)
			(xy 107.558443 -388.465247) (xy 107.599641 -388.500943) (xy 107.63534 -388.54214) (xy 107.664813 -388.587997)
			(xy 107.687458 -388.637583) (xy 107.702817 -388.689887) (xy 107.710575 -388.743844) (xy 107.710575 -388.798356)
			(xy 107.702817 -388.852313) (xy 107.687458 -388.904617) (xy 107.664813 -388.954203) (xy 107.63534 -389.00006)
			(xy 107.599641 -389.041257) (xy 107.558443 -389.076953) (xy 107.512583 -389.106423) (xy 107.462996 -389.129066)
			(xy 107.410692 -389.144422) (xy 107.356734 -389.152177) (xy 107.329478 -389.152638) (xy 107.302107 -389.1522)
			(xy 107.247926 -389.144378) (xy 107.195422 -389.128883) (xy 107.145675 -389.106035) (xy 107.09971 -389.076303)
			(xy 107.07878 -389.058658) (xy 107.071668 -389.052562) (xy 107.05465 -389.046212) (xy 106.969306 -389.046212)
			(xy 106.952288 -389.052562) (xy 106.945176 -389.058658) (xy 106.924221 -389.076268) (xy 106.878255 -389.105986)
			(xy 106.828513 -389.128828) (xy 106.776018 -389.144326) (xy 106.721846 -389.152161) (xy 106.694478 -389.152638)
			(xy 106.667718 -389.152185) (xy 106.614722 -389.144718) (xy 106.563289 -389.12992) (xy 106.514428 -389.108081)
			(xy 106.469098 -389.07963) (xy 106.448352 -389.062722) (xy 106.439208 -389.054848) (xy 106.416348 -389.04926)
			(xy 106.313732 -389.072628) (xy 106.295444 -389.08736) (xy 106.290364 -389.098536) (xy 106.278417 -389.123663)
			(xy 106.248322 -389.170456) (xy 106.23042 -389.191754) (xy 106.224324 -389.198866) (xy 106.217974 -389.215884)
			(xy 106.217974 -389.301228) (xy 106.224324 -389.318246) (xy 106.23042 -389.325358) (xy 106.248056 -389.346293)
			(xy 106.277768 -389.392265) (xy 106.300604 -389.442012) (xy 106.316096 -389.494512) (xy 106.323925 -389.548687)
			(xy 106.3244 -389.576056) (xy 106.323958 -389.602258) (xy 106.316785 -389.654167) (xy 106.30257 -389.704606)
			(xy 106.28158 -389.752621) (xy 106.268266 -389.775192) (xy 106.26404 -389.782861) (xy 106.26054 -389.800006)
			(xy 106.261408 -389.80872) (xy 106.265472 -389.838692) (xy 106.26717 -389.847459) (xy 106.275598 -389.863184)
			(xy 106.281982 -389.869426) (xy 106.305439 -389.891063) (xy 106.347308 -389.939224) (xy 106.382814 -389.992251)
			(xy 106.397552 -390.020556) (xy 106.401616 -390.028938) (xy 106.415332 -390.041384) (xy 106.495342 -390.073388)
			(xy 106.513884 -390.073642) (xy 106.52252 -390.070594) (xy 106.550182 -390.061092) (xy 106.60713 -390.047751)
			(xy 106.665233 -390.041034) (xy 106.694478 -390.040622) (xy 106.725175 -390.041071) (xy 106.786121 -390.048478)
			(xy 106.84573 -390.063176) (xy 106.903134 -390.084949) (xy 106.957495 -390.113481) (xy 106.983022 -390.130538)
			(xy 106.991774 -390.136009) (xy 107.011978 -390.140137) (xy 107.032182 -390.136009) (xy 107.040934 -390.130538)
			(xy 107.066467 -390.113495) (xy 107.120836 -390.084986) (xy 107.178239 -390.063224) (xy 107.237844 -390.048525)
			(xy 107.298783 -390.041102) (xy 107.329478 -390.040622) (xy 107.360211 -390.041058) (xy 107.421228 -390.048465)
			(xy 107.480908 -390.063173) (xy 107.53838 -390.084968) (xy 107.592805 -390.113532) (xy 107.643391 -390.148448)
			(xy 107.689398 -390.189207) (xy 107.730157 -390.235216) (xy 107.765072 -390.285801) (xy 107.793635 -390.340227)
			(xy 107.815429 -390.397699) (xy 107.830136 -390.457379) (xy 107.837542 -390.518397) (xy 107.837986 -390.54913)
			(xy 107.83742 -390.583316) (xy 107.828282 -390.651074) (xy 107.810149 -390.716997) (xy 107.783346 -390.779896)
			(xy 107.748358 -390.838637) (xy 107.705815 -390.89216) (xy 107.656485 -390.939501) (xy 107.629198 -390.960102)
			(xy 107.617514 -390.968484) (xy 107.606846 -390.994138) (xy 107.623356 -391.111232) (xy 107.641136 -391.132822)
			(xy 107.654598 -391.137648) (xy 107.686136 -391.149661) (xy 107.746007 -391.180809) (xy 107.801236 -391.219596)
			(xy 107.850855 -391.265341) (xy 107.893993 -391.317243) (xy 107.929895 -391.374389) (xy 107.944412 -391.404856)
			(xy 107.950762 -391.418572) (xy 107.975654 -391.43432) (xy 108.098082 -391.43432) (xy 108.122974 -391.418572)
			(xy 108.129324 -391.404856) (xy 108.142939 -391.376116) (xy 108.17631 -391.321977) (xy 108.216174 -391.272425)
			(xy 108.261908 -391.228233) (xy 108.287058 -391.208768) (xy 108.294166 -391.203012) (xy 108.304064 -391.187649)
			(xy 108.306362 -391.178796) (xy 108.312712 -391.149078) (xy 108.314238 -391.14019) (xy 108.311637 -391.122359)
			(xy 108.307632 -391.11428) (xy 108.293233 -391.086244) (xy 108.272847 -391.026609) (xy 108.262536 -390.964436)
			(xy 108.261912 -390.932924) (xy 108.262389 -390.905554) (xy 108.270204 -390.851375) (xy 108.28569 -390.798872)
			(xy 108.30853 -390.749125) (xy 108.338252 -390.703158) (xy 108.355892 -390.682226) (xy 108.361988 -390.675114)
			(xy 108.368338 -390.658096) (xy 108.368338 -390.572752) (xy 108.361988 -390.555734) (xy 108.355892 -390.548622)
			(xy 108.338249 -390.527693) (xy 108.308538 -390.48172) (xy 108.285703 -390.431971) (xy 108.270213 -390.37947)
			(xy 108.262385 -390.325293) (xy 108.261912 -390.297924) (xy 108.262398 -390.270673) (xy 108.270154 -390.216725)
			(xy 108.285509 -390.16443) (xy 108.308151 -390.114853) (xy 108.337617 -390.069003) (xy 108.373308 -390.027812)
			(xy 108.414499 -389.992121) (xy 108.460349 -389.962655) (xy 108.509926 -389.940013) (xy 108.562221 -389.924658)
			(xy 108.616169 -389.916902) (xy 108.670671 -389.916902) (xy 108.724619 -389.924658) (xy 108.776914 -389.940013)
			(xy 108.826491 -389.962655) (xy 108.872341 -389.992121) (xy 108.913532 -390.027812) (xy 108.949223 -390.069003)
			(xy 108.978689 -390.114853) (xy 109.001331 -390.16443) (xy 109.016686 -390.216725) (xy 109.024442 -390.270673)
			(xy 109.024928 -390.297924) (xy 109.024494 -390.325296) (xy 109.016671 -390.379477) (xy 109.001175 -390.431981)
			(xy 108.978326 -390.481727) (xy 108.948593 -390.527692) (xy 108.930948 -390.548622) (xy 108.924852 -390.555734)
			(xy 108.918502 -390.572752) (xy 108.918502 -390.658096) (xy 108.924852 -390.675114) (xy 108.930948 -390.682226)
			(xy 108.948558 -390.703182) (xy 108.978276 -390.749147) (xy 109.001118 -390.798889) (xy 109.016616 -390.851384)
			(xy 109.024451 -390.905556) (xy 109.024928 -390.932924) (xy 109.024754 -390.949262) (xy 109.021954 -390.981819)
			(xy 109.01934 -390.997948) (xy 109.017308 -391.010394) (xy 109.024674 -391.034016) (xy 109.101382 -391.110216)
			(xy 109.125004 -391.117582) (xy 109.137196 -391.115296) (xy 109.159426 -391.111591) (xy 109.204323 -391.107644)
			(xy 109.226858 -391.107422) (xy 109.257555 -391.107881) (xy 109.3185 -391.115286) (xy 109.378109 -391.129981)
			(xy 109.435513 -391.151753) (xy 109.489875 -391.180283) (xy 109.515402 -391.197338) (xy 109.524154 -391.202809)
			(xy 109.544358 -391.206937) (xy 109.564562 -391.202809) (xy 109.573314 -391.197338) (xy 109.598852 -391.180303)
			(xy 109.65322 -391.151793) (xy 109.710622 -391.130029) (xy 109.770225 -391.115328) (xy 109.831164 -391.107903)
			(xy 109.861858 -391.107422) (xy 109.892555 -391.107881) (xy 109.9535 -391.115286) (xy 110.013109 -391.129981)
			(xy 110.070513 -391.151753) (xy 110.124875 -391.180283) (xy 110.150402 -391.197338) (xy 110.159154 -391.202809)
			(xy 110.179358 -391.206937) (xy 110.199562 -391.202809) (xy 110.208314 -391.197338) (xy 110.233852 -391.180303)
			(xy 110.28822 -391.151793) (xy 110.345622 -391.130029) (xy 110.405225 -391.115328) (xy 110.466164 -391.107903)
			(xy 110.496858 -391.107422) (xy 110.52759 -391.107877) (xy 110.588607 -391.115282) (xy 110.648287 -391.129987)
			(xy 110.705759 -391.15178) (xy 110.760184 -391.180342) (xy 110.810769 -391.215257) (xy 110.856777 -391.256014)
			(xy 110.897536 -391.302021) (xy 110.932452 -391.352606) (xy 110.961015 -391.407031) (xy 110.982809 -391.464502)
			(xy 110.997516 -391.524181) (xy 111.004922 -391.585198) (xy 111.005366 -391.61593) (xy 111.005314 -391.627376)
			(xy 111.004296 -391.650245) (xy 111.003334 -391.66165) (xy 111.002318 -391.673334) (xy 111.010192 -391.69467)
			(xy 111.084614 -391.766044) (xy 111.106204 -391.773156) (xy 111.117888 -391.771378) (xy 111.134575 -391.769318)
			(xy 111.168131 -391.76716) (xy 111.184944 -391.76706) (xy 111.215675 -391.767514) (xy 111.276688 -391.774927)
			(xy 111.336362 -391.78964) (xy 111.393829 -391.811437) (xy 111.448249 -391.840002) (xy 111.49883 -391.874918)
			(xy 111.544834 -391.915675) (xy 111.58559 -391.96168) (xy 111.620504 -392.012261) (xy 111.649068 -392.066682)
			(xy 111.670864 -392.124149) (xy 111.685575 -392.183824) (xy 111.692987 -392.244837) (xy 111.693452 -392.275568)
			(xy 111.692989 -392.307582) (xy 111.68956 -392.33475) (xy 113.264188 -392.33475) (xy 113.264577 -392.311516)
			(xy 113.271077 -392.265505) (xy 113.283955 -392.220857) (xy 113.302958 -392.178452) (xy 113.327712 -392.139127)
			(xy 113.34242 -392.121136) (xy 113.348516 -392.114024) (xy 113.354612 -392.097514) (xy 113.354612 -392.013186)
			(xy 113.348516 -391.996676) (xy 113.34242 -391.989564) (xy 113.32773 -391.97156) (xy 113.30298 -391.932235)
			(xy 113.283977 -391.889833) (xy 113.271094 -391.84519) (xy 113.264585 -391.799183) (xy 113.264188 -391.77595)
			(xy 113.264698 -391.749963) (xy 113.272828 -391.698628) (xy 113.288889 -391.649198) (xy 113.312485 -391.602888)
			(xy 113.343035 -391.56084) (xy 113.379786 -391.524089) (xy 113.421834 -391.493539) (xy 113.468144 -391.469943)
			(xy 113.517574 -391.453882) (xy 113.568909 -391.445752) (xy 113.620883 -391.445752) (xy 113.672218 -391.453882)
			(xy 113.721648 -391.469943) (xy 113.767958 -391.493539) (xy 113.810006 -391.524089) (xy 113.846757 -391.56084)
			(xy 113.877307 -391.602888) (xy 113.900903 -391.649198) (xy 113.916964 -391.698628) (xy 113.925094 -391.749963)
			(xy 113.925604 -391.77595) (xy 113.925217 -391.799184) (xy 113.918717 -391.845196) (xy 113.905838 -391.889843)
			(xy 113.886834 -391.932248) (xy 113.86208 -391.971574) (xy 113.847372 -391.989564) (xy 113.841276 -391.996676)
			(xy 113.83518 -392.013186) (xy 113.83518 -392.097514) (xy 113.841276 -392.114024) (xy 113.847372 -392.121136)
			(xy 113.862061 -392.139141) (xy 113.886811 -392.178465) (xy 113.905815 -392.220867) (xy 113.918698 -392.26551)
			(xy 113.925207 -392.311517) (xy 113.925604 -392.33475) (xy 113.925094 -392.360737) (xy 113.916964 -392.412072)
			(xy 113.900903 -392.461502) (xy 113.877307 -392.507812) (xy 113.846757 -392.54986) (xy 113.810006 -392.586611)
			(xy 113.767958 -392.617161) (xy 113.721648 -392.640757) (xy 113.672218 -392.656818) (xy 113.620883 -392.664948)
			(xy 113.568909 -392.664948) (xy 113.517574 -392.656818) (xy 113.468144 -392.640757) (xy 113.421834 -392.617161)
			(xy 113.379786 -392.586611) (xy 113.343035 -392.54986) (xy 113.312485 -392.507812) (xy 113.288889 -392.461502)
			(xy 113.272828 -392.412072) (xy 113.264698 -392.360737) (xy 113.264188 -392.33475) (xy 111.68956 -392.33475)
			(xy 111.684971 -392.371106) (xy 111.669047 -392.433122) (xy 111.645467 -392.492649) (xy 111.63046 -392.520932)
			(xy 111.626189 -392.529407) (xy 111.62372 -392.548211) (xy 111.625634 -392.557508) (xy 111.633 -392.58748)
			(xy 111.635489 -392.596489) (xy 111.646067 -392.611883) (xy 111.653574 -392.617452) (xy 111.675103 -392.632815)
			(xy 111.714189 -392.668442) (xy 111.747979 -392.709127) (xy 111.775825 -392.75409) (xy 111.797192 -392.802469)
			(xy 111.81167 -392.853335) (xy 111.818982 -392.905715) (xy 111.819436 -392.932158) (xy 111.818906 -392.959409)
			(xy 111.811155 -393.013356) (xy 111.795806 -393.065651) (xy 111.77317 -393.115229) (xy 111.743709 -393.161081)
			(xy 111.708023 -393.202273) (xy 111.666837 -393.237967) (xy 111.62099 -393.267437) (xy 111.571416 -393.290081)
			(xy 111.562029 -393.292838) (xy 114.534696 -393.292838) (xy 114.534696 -392.429238) (xy 114.535158 -392.402882)
			(xy 114.542422 -392.350671) (xy 114.556803 -392.299958) (xy 114.578028 -392.251707) (xy 114.605692 -392.206837)
			(xy 114.639269 -392.166201) (xy 114.658394 -392.14806) (xy 114.665506 -392.14171) (xy 114.673634 -392.124946)
			(xy 114.682016 -392.038332) (xy 114.676936 -392.020552) (xy 114.671348 -392.012678) (xy 114.657197 -391.992832)
			(xy 114.63474 -391.949573) (xy 114.619428 -391.9033) (xy 114.611648 -391.855184) (xy 114.61115 -391.830814)
			(xy 114.611672 -391.805559) (xy 114.619985 -391.755737) (xy 114.636386 -391.707963) (xy 114.660427 -391.66354)
			(xy 114.691451 -391.62368) (xy 114.728613 -391.58947) (xy 114.770899 -391.561844) (xy 114.817155 -391.541554)
			(xy 114.86612 -391.529154) (xy 114.916458 -391.524983) (xy 114.966796 -391.529154) (xy 115.015761 -391.541554)
			(xy 115.062017 -391.561844) (xy 115.104303 -391.58947) (xy 115.141465 -391.62368) (xy 115.172489 -391.66354)
			(xy 115.19653 -391.707963) (xy 115.212931 -391.755737) (xy 115.221244 -391.805559) (xy 115.221766 -391.830814)
			(xy 115.221285 -391.855186) (xy 115.213526 -391.903309) (xy 115.198209 -391.949584) (xy 115.175724 -391.992833)
			(xy 115.161568 -392.012678) (xy 115.15598 -392.020552) (xy 115.1509 -392.038332) (xy 115.159282 -392.124946)
			(xy 115.16741 -392.14171) (xy 115.174522 -392.14806) (xy 115.193651 -392.166199) (xy 115.22724 -392.206828)
			(xy 115.254913 -392.251697) (xy 115.276141 -392.299949) (xy 115.290521 -392.350666) (xy 115.297777 -392.40288)
			(xy 115.29822 -392.429238) (xy 115.29822 -393.292838) (xy 115.734592 -393.292838) (xy 115.734592 -392.429238)
			(xy 115.735055 -392.402882) (xy 115.742319 -392.350672) (xy 115.7567 -392.299958) (xy 115.777925 -392.251707)
			(xy 115.805589 -392.206837) (xy 115.839165 -392.166201) (xy 115.85829 -392.14806) (xy 115.865402 -392.141456)
			(xy 115.873784 -392.124946) (xy 115.881912 -392.038078) (xy 115.877086 -392.020298) (xy 115.871244 -392.012678)
			(xy 115.857133 -391.992814) (xy 115.834713 -391.949557) (xy 115.819457 -391.903285) (xy 115.811754 -391.855175)
			(xy 115.8113 -391.830814) (xy 115.811822 -391.805559) (xy 115.820135 -391.755737) (xy 115.836536 -391.707963)
			(xy 115.860577 -391.66354) (xy 115.891601 -391.62368) (xy 115.928763 -391.58947) (xy 115.971049 -391.561844)
			(xy 116.017305 -391.541554) (xy 116.06627 -391.529154) (xy 116.116608 -391.524983) (xy 116.166946 -391.529154)
			(xy 116.215911 -391.541554) (xy 116.262167 -391.561844) (xy 116.304453 -391.58947) (xy 116.341615 -391.62368)
			(xy 116.372639 -391.66354) (xy 116.39668 -391.707963) (xy 116.413081 -391.755737) (xy 116.421394 -391.805559)
			(xy 116.421916 -391.830814) (xy 116.421459 -391.855217) (xy 116.413698 -391.903402) (xy 116.398375 -391.949741)
			(xy 116.375881 -391.993054) (xy 116.361718 -392.012932) (xy 116.35613 -392.020552) (xy 116.35105 -392.038332)
			(xy 116.359178 -392.1252) (xy 116.36756 -392.14171) (xy 116.374672 -392.148314) (xy 116.393732 -392.166476)
			(xy 116.427225 -392.207095) (xy 116.454824 -392.251928) (xy 116.476008 -392.300125) (xy 116.490374 -392.350773)
			(xy 116.497651 -392.402915) (xy 116.498116 -392.429238) (xy 116.498116 -393.292838) (xy 116.934996 -393.292838)
			(xy 116.934996 -392.429238) (xy 116.935451 -392.402891) (xy 116.942681 -392.350697) (xy 116.957021 -392.299992)
			(xy 116.9782 -392.251743) (xy 117.005815 -392.206866) (xy 117.039341 -392.166213) (xy 117.05844 -392.14806)
			(xy 117.065552 -392.14171) (xy 117.07368 -392.124946) (xy 117.082062 -392.038332) (xy 117.076982 -392.020552)
			(xy 117.071394 -392.012678) (xy 117.057249 -391.992828) (xy 117.034789 -391.949571) (xy 117.019475 -391.903299)
			(xy 117.011695 -391.855184) (xy 117.011196 -391.830814) (xy 117.011718 -391.805559) (xy 117.020031 -391.755737)
			(xy 117.036432 -391.707963) (xy 117.060473 -391.66354) (xy 117.091497 -391.62368) (xy 117.128659 -391.58947)
			(xy 117.170945 -391.561844) (xy 117.217201 -391.541554) (xy 117.266166 -391.529154) (xy 117.316504 -391.524983)
			(xy 117.366842 -391.529154) (xy 117.415807 -391.541554) (xy 117.462063 -391.561844) (xy 117.504349 -391.58947)
			(xy 117.541511 -391.62368) (xy 117.572535 -391.66354) (xy 117.596576 -391.707963) (xy 117.612977 -391.755737)
			(xy 117.62129 -391.805559) (xy 117.621812 -391.830814) (xy 117.621341 -391.855187) (xy 117.613581 -391.903311)
			(xy 117.598262 -391.949586) (xy 117.575773 -391.992834) (xy 117.561614 -392.012678) (xy 117.556026 -392.020552)
			(xy 117.550946 -392.038332) (xy 117.559328 -392.124946) (xy 117.567456 -392.14171) (xy 117.574568 -392.14806)
			(xy 117.593686 -392.166198) (xy 117.627232 -392.206842) (xy 117.65486 -392.251718) (xy 117.676043 -392.299972)
			(xy 117.690378 -392.350685) (xy 117.69759 -392.402888) (xy 117.698012 -392.429238) (xy 117.698012 -393.292838)
			(xy 117.697536 -393.319001) (xy 117.690386 -393.370835) (xy 117.676226 -393.421208) (xy 117.655321 -393.469176)
			(xy 117.628063 -393.51384) (xy 117.594961 -393.554364) (xy 117.576092 -393.572492) (xy 117.568726 -393.57935)
			(xy 117.560598 -393.596876) (xy 117.555264 -393.687046) (xy 117.56136 -393.705334) (xy 117.567964 -393.712954)
			(xy 117.582858 -393.731003) (xy 117.607925 -393.770518) (xy 117.627174 -393.813171) (xy 117.640223 -393.858111)
			(xy 117.64681 -393.90444) (xy 117.647212 -393.927838) (xy 117.646702 -393.953825) (xy 117.638572 -394.00516)
			(xy 117.622511 -394.05459) (xy 117.598915 -394.1009) (xy 117.568365 -394.142948) (xy 117.531614 -394.179699)
			(xy 117.489566 -394.210249) (xy 117.443256 -394.233845) (xy 117.393826 -394.249906) (xy 117.342491 -394.258036)
			(xy 117.290517 -394.258036) (xy 117.239182 -394.249906) (xy 117.189752 -394.233845) (xy 117.143442 -394.210249)
			(xy 117.101394 -394.179699) (xy 117.064643 -394.142948) (xy 117.034093 -394.1009) (xy 117.010497 -394.05459)
			(xy 116.994436 -394.00516) (xy 116.986306 -393.953825) (xy 116.985796 -393.927838) (xy 116.986234 -393.904442)
			(xy 116.992819 -393.858117) (xy 117.005863 -393.81318) (xy 117.025106 -393.770529) (xy 117.050164 -393.731013)
			(xy 117.065044 -393.712954) (xy 117.071648 -393.705334) (xy 117.077744 -393.687046) (xy 117.07241 -393.596876)
			(xy 117.064282 -393.57935) (xy 117.056916 -393.572492) (xy 117.038025 -393.554383) (xy 117.004907 -393.513863)
			(xy 116.977636 -393.469198) (xy 116.956725 -393.421226) (xy 116.942565 -393.370846) (xy 116.935423 -393.319004)
			(xy 116.934996 -393.292838) (xy 116.498116 -393.292838) (xy 116.497514 -393.322996) (xy 116.488019 -393.382561)
			(xy 116.469272 -393.43989) (xy 116.441739 -393.493556) (xy 116.406107 -393.542223) (xy 116.385086 -393.563856)
			(xy 116.378482 -393.57046) (xy 116.370862 -393.587224) (xy 116.365528 -393.67333) (xy 116.370862 -393.69111)
			(xy 116.376704 -393.698476) (xy 116.393217 -393.72046) (xy 116.419489 -393.768755) (xy 116.437419 -393.820728)
			(xy 116.446514 -393.874949) (xy 116.447062 -393.902438) (xy 116.446552 -393.928425) (xy 116.438422 -393.97976)
			(xy 116.422361 -394.02919) (xy 116.398765 -394.0755) (xy 116.368215 -394.117548) (xy 116.331464 -394.154299)
			(xy 116.289416 -394.184849) (xy 116.243106 -394.208445) (xy 116.193676 -394.224506) (xy 116.142341 -394.232636)
			(xy 116.090367 -394.232636) (xy 116.039032 -394.224506) (xy 115.989602 -394.208445) (xy 115.943292 -394.184849)
			(xy 115.901244 -394.154299) (xy 115.864493 -394.117548) (xy 115.833943 -394.0755) (xy 115.810347 -394.02919)
			(xy 115.794286 -393.97976) (xy 115.786156 -393.928425) (xy 115.785646 -393.902438) (xy 115.78621 -393.874948)
			(xy 115.795285 -393.820723) (xy 115.813206 -393.768747) (xy 115.839482 -393.720453) (xy 115.856004 -393.698476)
			(xy 115.861846 -393.69111) (xy 115.86718 -393.67333) (xy 115.861846 -393.587224) (xy 115.854226 -393.57046)
			(xy 115.847622 -393.563856) (xy 115.826569 -393.54225) (xy 115.790927 -393.493582) (xy 115.76339 -393.43991)
			(xy 115.744645 -393.382573) (xy 115.735159 -393.323) (xy 115.734592 -393.292838) (xy 115.29822 -393.292838)
			(xy 115.297617 -393.322996) (xy 115.288122 -393.382561) (xy 115.269375 -393.43989) (xy 115.241843 -393.493556)
			(xy 115.20621 -393.542223) (xy 115.18519 -393.563856) (xy 115.178586 -393.57046) (xy 115.170966 -393.587224)
			(xy 115.165632 -393.67333) (xy 115.170966 -393.69111) (xy 115.176808 -393.698476) (xy 115.193321 -393.720459)
			(xy 115.219593 -393.768755) (xy 115.237523 -393.820728) (xy 115.246618 -393.874949) (xy 115.247166 -393.902438)
			(xy 115.246656 -393.928425) (xy 115.238526 -393.97976) (xy 115.222465 -394.02919) (xy 115.198869 -394.0755)
			(xy 115.168319 -394.117548) (xy 115.131568 -394.154299) (xy 115.08952 -394.184849) (xy 115.04321 -394.208445)
			(xy 114.99378 -394.224506) (xy 114.942445 -394.232636) (xy 114.890471 -394.232636) (xy 114.839136 -394.224506)
			(xy 114.789706 -394.208445) (xy 114.743396 -394.184849) (xy 114.701348 -394.154299) (xy 114.664597 -394.117548)
			(xy 114.634047 -394.0755) (xy 114.610451 -394.02919) (xy 114.59439 -393.97976) (xy 114.58626 -393.928425)
			(xy 114.58575 -393.902438) (xy 114.586313 -393.874948) (xy 114.595388 -393.820723) (xy 114.61331 -393.768747)
			(xy 114.639585 -393.720453) (xy 114.656108 -393.698476) (xy 114.66195 -393.69111) (xy 114.667284 -393.67333)
			(xy 114.66195 -393.587224) (xy 114.65433 -393.57046) (xy 114.647726 -393.563856) (xy 114.626674 -393.54225)
			(xy 114.591032 -393.493582) (xy 114.563494 -393.43991) (xy 114.544749 -393.382573) (xy 114.535263 -393.323)
			(xy 114.534696 -393.292838) (xy 111.562029 -393.292838) (xy 111.519124 -393.30544) (xy 111.465178 -393.313201)
			(xy 111.437928 -393.313666) (xy 111.41025 -393.313184) (xy 111.355478 -393.305163) (xy 111.302439 -393.289314)
			(xy 111.252246 -393.265969) (xy 111.205952 -393.235619) (xy 111.164528 -393.198899) (xy 111.128842 -393.156581)
			(xy 111.113824 -393.133326) (xy 111.106712 -393.121896) (xy 111.083344 -393.109196) (xy 110.968536 -393.111482)
			(xy 110.94593 -393.124944) (xy 110.939072 -393.136882) (xy 110.91545 -393.174474) (xy 110.909956 -393.183213)
			(xy 110.90584 -393.203425) (xy 110.909976 -393.223633) (xy 110.91545 -393.232386) (xy 110.932471 -393.257933)
			(xy 110.960984 -393.312298) (xy 110.982751 -393.369698) (xy 110.997455 -393.429299) (xy 111.004883 -393.490236)
			(xy 111.005366 -393.52093) (xy 111.00499 -393.551664) (xy 110.997578 -393.612685) (xy 110.982863 -393.672366)
			(xy 110.961063 -393.729839) (xy 110.932493 -393.784265) (xy 110.897571 -393.83485) (xy 110.856807 -393.880858)
			(xy 110.810794 -393.921616) (xy 110.760203 -393.95653) (xy 110.705773 -393.985092) (xy 110.648297 -394.006885)
			(xy 110.588614 -394.021591) (xy 110.527592 -394.028995) (xy 110.496858 -394.029438) (xy 110.466162 -394.02896)
			(xy 110.405217 -394.021558) (xy 110.345609 -394.006866) (xy 110.288205 -393.9851) (xy 110.233842 -393.956575)
			(xy 110.208314 -393.939522) (xy 110.199562 -393.934051) (xy 110.179358 -393.929923) (xy 110.159154 -393.934051)
			(xy 110.150402 -393.939522) (xy 110.124856 -393.956545) (xy 110.070491 -393.985058) (xy 110.013091 -394.006825)
			(xy 109.953489 -394.021528) (xy 109.892552 -394.028956) (xy 109.861858 -394.029438) (xy 109.831162 -394.02896)
			(xy 109.770217 -394.021558) (xy 109.710609 -394.006866) (xy 109.653205 -393.9851) (xy 109.598842 -393.956575)
			(xy 109.573314 -393.939522) (xy 109.564562 -393.934051) (xy 109.544358 -393.929923) (xy 109.524154 -393.934051)
			(xy 109.515402 -393.939522) (xy 109.489856 -393.956545) (xy 109.435491 -393.985058) (xy 109.378091 -394.006825)
			(xy 109.318489 -394.021528) (xy 109.257552 -394.028956) (xy 109.226858 -394.029438) (xy 109.196162 -394.02896)
			(xy 109.135217 -394.021558) (xy 109.075609 -394.006866) (xy 109.018205 -393.9851) (xy 108.963842 -393.956575)
			(xy 108.938314 -393.939522) (xy 108.929562 -393.934051) (xy 108.909358 -393.929923) (xy 108.889154 -393.934051)
			(xy 108.880402 -393.939522) (xy 108.865162 -393.949682) (xy 108.856012 -393.956277) (xy 108.844058 -393.975368)
			(xy 108.841357 -393.997732) (xy 108.844334 -394.00861) (xy 108.852475 -394.03445) (xy 108.863901 -394.087411)
			(xy 108.869637 -394.141286) (xy 108.869988 -394.168376) (xy 108.86954 -394.199108) (xy 108.862133 -394.260125)
			(xy 108.847426 -394.319804) (xy 108.83521 -394.352018) (xy 113.30508 -394.352018) (xy 113.309151 -394.296396)
			(xy 113.321277 -394.241959) (xy 113.3412 -394.189868) (xy 113.368496 -394.141233) (xy 113.402582 -394.09709)
			(xy 113.442731 -394.058381) (xy 113.488089 -394.02593) (xy 113.537689 -394.000429) (xy 113.590473 -393.982422)
			(xy 113.645316 -393.972292) (xy 113.70105 -393.970255) (xy 113.756487 -393.976355) (xy 113.810444 -393.990461)
			(xy 113.861773 -394.012273) (xy 113.909379 -394.041327) (xy 113.952247 -394.077002) (xy 113.989464 -394.118539)
			(xy 114.020237 -394.165052) (xy 114.043909 -394.215549) (xy 114.059977 -394.268956) (xy 114.068097 -394.324132)
			(xy 114.068606 -394.352018) (xy 114.068097 -394.379904) (xy 114.059977 -394.43508) (xy 114.043909 -394.488487)
			(xy 114.020237 -394.538984) (xy 113.989464 -394.585497) (xy 113.952247 -394.627034) (xy 113.909379 -394.662709)
			(xy 113.861773 -394.691763) (xy 113.810444 -394.713575) (xy 113.756487 -394.727681) (xy 113.70105 -394.733781)
			(xy 113.645316 -394.731744) (xy 113.590473 -394.721614) (xy 113.537689 -394.703607) (xy 113.488089 -394.678106)
			(xy 113.442731 -394.645655) (xy 113.402582 -394.606946) (xy 113.368496 -394.562803) (xy 113.3412 -394.514168)
			(xy 113.321277 -394.462077) (xy 113.309151 -394.40764) (xy 113.30508 -394.352018) (xy 108.83521 -394.352018)
			(xy 108.825632 -394.377275) (xy 108.797069 -394.4317) (xy 108.762154 -394.482285) (xy 108.721395 -394.528293)
			(xy 108.675388 -394.569051) (xy 108.624804 -394.603967) (xy 108.570379 -394.63253) (xy 108.512908 -394.654325)
			(xy 108.453229 -394.669033) (xy 108.392212 -394.67644) (xy 108.36148 -394.676884) (xy 108.327893 -394.67637)
			(xy 108.261305 -394.667524) (xy 108.196462 -394.649987) (xy 108.134492 -394.624065) (xy 108.076474 -394.59021)
			(xy 108.023419 -394.549011) (xy 107.97625 -394.501185) (xy 107.955588 -394.4747) (xy 107.948633 -394.466371)
			(xy 107.929645 -394.455924) (xy 107.90804 -394.454224) (xy 107.897676 -394.457428) (xy 107.869939 -394.466991)
			(xy 107.812826 -394.480436) (xy 107.754546 -394.487221) (xy 107.72521 -394.487654) (xy 107.685364 -394.486921)
			(xy 107.606642 -394.474541) (xy 107.568492 -394.463016) (xy 107.558476 -394.460314) (xy 107.537844 -394.462262)
			(xy 107.51965 -394.472186) (xy 107.512866 -394.480034) (xy 107.492142 -394.505856) (xy 107.445114 -394.552462)
			(xy 107.392436 -394.592572) (xy 107.334998 -394.625507) (xy 107.273772 -394.650709) (xy 107.209793 -394.667753)
			(xy 107.144143 -394.67635) (xy 107.111038 -394.676884) (xy 107.080306 -394.676427) (xy 107.019289 -394.669022)
			(xy 106.95961 -394.654316) (xy 106.902139 -394.632523) (xy 106.847714 -394.603961) (xy 106.797128 -394.569047)
			(xy 106.751121 -394.528289) (xy 106.710362 -394.482283) (xy 106.675446 -394.431698) (xy 106.646883 -394.377274)
			(xy 106.625088 -394.319804) (xy 106.610381 -394.260125) (xy 106.602974 -394.199108) (xy 106.60253 -394.168376)
			(xy 106.603152 -394.131791) (xy 106.613607 -394.059371) (xy 106.623358 -394.024104) (xy 106.626129 -394.012907)
			(xy 106.622474 -393.990157) (xy 106.609272 -393.971273) (xy 106.599482 -393.965176) (xy 106.588928 -393.959202)
			(xy 106.568346 -393.946367) (xy 106.558334 -393.939522) (xy 106.549582 -393.934051) (xy 106.529378 -393.929923)
			(xy 106.509174 -393.934051) (xy 106.500422 -393.939522) (xy 106.474898 -393.95658) (xy 106.420527 -393.985087)
			(xy 106.363121 -394.006846) (xy 106.303515 -394.021542) (xy 106.242573 -394.028961) (xy 106.211878 -394.029438)
			(xy 106.181182 -394.02895) (xy 106.120238 -394.02155) (xy 106.06063 -394.006861) (xy 106.003226 -393.985097)
			(xy 105.948862 -393.956574) (xy 105.923334 -393.939522) (xy 105.914582 -393.934051) (xy 105.894378 -393.929923)
			(xy 105.874174 -393.934051) (xy 105.865422 -393.939522) (xy 105.839898 -393.95658) (xy 105.785527 -393.985087)
			(xy 105.728121 -394.006846) (xy 105.668515 -394.021542) (xy 105.607573 -394.028961) (xy 105.576878 -394.029438)
			(xy 105.546148 -394.028965) (xy 105.485135 -394.021554) (xy 105.425461 -394.006844) (xy 105.367995 -393.985049)
			(xy 105.313574 -393.956486) (xy 105.262993 -393.921572) (xy 105.216989 -393.880816) (xy 105.176233 -393.834813)
			(xy 105.141318 -393.784232) (xy 105.112755 -393.729812) (xy 105.090958 -393.672347) (xy 105.076247 -393.612672)
			(xy 105.068836 -393.55166) (xy 105.06837 -393.52093) (xy 102.481888 -393.52093) (xy 102.481888 -394.424154)
			(xy 102.481794 -394.434024) (xy 102.480525 -394.453724) (xy 102.479348 -394.463524) (xy 102.477824 -394.475462)
			(xy 102.48519 -394.497306) (xy 103.202486 -395.214602) (xy 103.212646 -395.220698) (xy 103.218488 -395.222476)
			(xy 103.248356 -395.232591) (xy 103.30553 -395.259195) (xy 103.358972 -395.292671) (xy 103.407861 -395.332503)
			(xy 103.451444 -395.378079) (xy 103.489051 -395.428698) (xy 103.505 -395.455902) (xy 103.510842 -395.466316)
			(xy 103.5304 -395.479524) (xy 103.622348 -395.49197) (xy 103.634097 -395.493009) (xy 103.656456 -395.485582)
			(xy 103.665274 -395.477746) (xy 103.841804 -395.300962) (xy 103.848215 -395.294087) (xy 103.855886 -395.276941)
			(xy 103.856844 -395.258181) (xy 103.85425 -395.249146) (xy 103.82123 -395.14907) (xy 103.799386 -395.130782)
			(xy 103.784908 -395.128496) (xy 103.752413 -395.123179) (xy 103.689057 -395.105244) (xy 103.628549 -395.079275)
			(xy 103.571903 -395.045707) (xy 103.520067 -395.005104) (xy 103.47391 -394.958144) (xy 103.434206 -394.905616)
			(xy 103.40162 -394.848399) (xy 103.376698 -394.787452) (xy 103.359857 -394.723797) (xy 103.35138 -394.658499)
			(xy 103.350822 -394.625576) (xy 103.351324 -394.593615) (xy 103.359335 -394.530197) (xy 103.375232 -394.468283)
			(xy 103.398764 -394.40885) (xy 103.429558 -394.352835) (xy 103.467131 -394.30112) (xy 103.510888 -394.254523)
			(xy 103.560141 -394.213778) (xy 103.614112 -394.179527) (xy 103.671951 -394.15231) (xy 103.732744 -394.132557)
			(xy 103.795534 -394.120579) (xy 103.85933 -394.116566) (xy 103.923126 -394.120579) (xy 103.985916 -394.132557)
			(xy 104.046709 -394.15231) (xy 104.104548 -394.179527) (xy 104.158519 -394.213778) (xy 104.207772 -394.254523)
			(xy 104.251529 -394.30112) (xy 104.289102 -394.352835) (xy 104.319896 -394.40885) (xy 104.343428 -394.468283)
			(xy 104.359325 -394.530197) (xy 104.367336 -394.593615) (xy 104.367838 -394.625576) (xy 104.367349 -394.657701)
			(xy 104.359262 -394.721441) (xy 104.343213 -394.783655) (xy 104.319459 -394.843354) (xy 104.304338 -394.871702)
			(xy 104.297734 -394.883386) (xy 104.297734 -394.909294) (xy 104.352344 -395.007846) (xy 104.374188 -395.021562)
			(xy 104.38765 -395.022324) (xy 104.422749 -395.024831) (xy 104.491979 -395.037441) (xy 104.559121 -395.058508)
			(xy 104.591358 -395.072616) (xy 104.601636 -395.076689) (xy 104.623721 -395.076567) (xy 104.643726 -395.067209)
			(xy 104.651302 -395.059154) (xy 104.672059 -395.035432) (xy 104.718473 -394.992781) (xy 104.7698 -394.956188)
			(xy 104.825253 -394.926215) (xy 104.883984 -394.903319) (xy 104.945092 -394.887852) (xy 105.007642 -394.88005)
			(xy 105.03916 -394.879576) (xy 105.071125 -394.880055) (xy 105.134551 -394.888063) (xy 105.196474 -394.903957)
			(xy 105.255916 -394.927488) (xy 105.31194 -394.958283) (xy 105.363662 -394.995858) (xy 105.410267 -395.039619)
			(xy 105.451019 -395.088876) (xy 105.485276 -395.142853) (xy 105.512497 -395.200698) (xy 105.532253 -395.261499)
			(xy 105.544233 -395.324296) (xy 105.548248 -395.3881) (xy 105.544233 -395.451904) (xy 105.532253 -395.514701)
			(xy 105.512497 -395.575502) (xy 105.485276 -395.633347) (xy 105.451019 -395.687324) (xy 105.410267 -395.736581)
			(xy 105.363662 -395.780342) (xy 105.31194 -395.817917) (xy 105.255916 -395.848712) (xy 105.196474 -395.872243)
			(xy 105.134551 -395.888137) (xy 105.071125 -395.896145) (xy 105.03916 -395.896592) (xy 105.001311 -395.895901)
			(xy 104.926448 -395.884685) (xy 104.890062 -395.87424) (xy 104.87533 -395.871954) (xy 104.832658 -395.895322)
			(xy 104.815955 -395.920464) (xy 104.77803 -395.967428) (xy 104.756966 -395.989048) (xy 104.600756 -396.145258)
			(xy 104.594228 -396.152329) (xy 104.58654 -396.169954) (xy 104.58577 -396.179548) (xy 104.583484 -396.258796)
			(xy 104.590088 -396.277084) (xy 104.596438 -396.28445) (xy 104.61418 -396.305216) (xy 104.644163 -396.35087)
			(xy 104.667336 -396.400329) (xy 104.683225 -396.452586) (xy 104.691505 -396.506574) (xy 104.692196 -396.533878)
			(xy 104.692196 -396.544038) (xy 104.70007 -396.562072) (xy 104.757982 -396.61973) (xy 104.765392 -396.626414)
			(xy 104.783828 -396.633998) (xy 104.793796 -396.634462) (xy 105.56875 -396.634462) (xy 105.578815 -396.634029)
			(xy 105.597403 -396.626298) (xy 105.604818 -396.619476) (xy 106.325416 -395.898878) (xy 106.348201 -395.876739)
			(xy 106.397884 -395.837142) (xy 106.451683 -395.80335) (xy 106.508924 -395.775786) (xy 106.568889 -395.754797)
			(xy 106.630824 -395.740645) (xy 106.693954 -395.733509) (xy 106.72572 -395.733016) (xy 106.96194 -395.733016)
			(xy 106.993298 -395.73345) (xy 107.055629 -395.7404) (xy 107.116811 -395.754189) (xy 107.176097 -395.774648)
			(xy 107.232762 -395.801527) (xy 107.286113 -395.834497) (xy 107.335499 -395.873156) (xy 107.35818 -395.894814)
			(xy 107.365292 -395.901926) (xy 107.38358 -395.909292) (xy 107.474258 -395.9098) (xy 107.492546 -395.902434)
			(xy 107.499658 -395.895576) (xy 107.523431 -395.873409) (xy 107.575622 -395.834665) (xy 107.632322 -395.802881)
			(xy 107.692606 -395.778575) (xy 107.755495 -395.762141) (xy 107.819964 -395.753848) (xy 107.852464 -395.753336)
			(xy 107.883197 -395.75378) (xy 107.944214 -395.761185) (xy 108.003894 -395.775892) (xy 108.061365 -395.797685)
			(xy 108.11579 -395.826248) (xy 108.166376 -395.861164) (xy 108.212383 -395.901923) (xy 108.253141 -395.947931)
			(xy 108.288056 -395.998516) (xy 108.316618 -396.052942) (xy 108.338411 -396.110414) (xy 108.353117 -396.170094)
			(xy 108.360521 -396.231111) (xy 108.360972 -396.261844) (xy 108.360476 -396.293998) (xy 108.352362 -396.357793)
			(xy 108.336268 -396.420056) (xy 108.331007 -396.433251) (xy 109.232948 -396.433251) (xy 109.232948 -396.369329)
			(xy 109.240959 -396.305911) (xy 109.256856 -396.243997) (xy 109.280388 -396.184564) (xy 109.311182 -396.128549)
			(xy 109.348755 -396.076834) (xy 109.392512 -396.030237) (xy 109.441765 -395.989492) (xy 109.495736 -395.955241)
			(xy 109.553575 -395.928024) (xy 109.614368 -395.908271) (xy 109.677158 -395.896293) (xy 109.740954 -395.89228)
			(xy 109.80475 -395.896293) (xy 109.86754 -395.908271) (xy 109.928333 -395.928024) (xy 109.986172 -395.955241)
			(xy 110.040143 -395.989492) (xy 110.089396 -396.030237) (xy 110.133153 -396.076834) (xy 110.170726 -396.128549)
			(xy 110.20152 -396.184564) (xy 110.225052 -396.243997) (xy 110.240949 -396.305911) (xy 110.24896 -396.369329)
			(xy 110.249462 -396.40129) (xy 110.24896 -396.433251) (xy 110.240949 -396.496669) (xy 110.225052 -396.558583)
			(xy 110.20152 -396.618016) (xy 110.170726 -396.674031) (xy 110.133153 -396.725746) (xy 110.089396 -396.772343)
			(xy 110.040143 -396.813088) (xy 109.986172 -396.847339) (xy 109.928333 -396.874556) (xy 109.86754 -396.894309)
			(xy 109.80475 -396.906287) (xy 109.740954 -396.910301) (xy 109.677158 -396.906287) (xy 109.614368 -396.894309)
			(xy 109.553575 -396.874556) (xy 109.495736 -396.847339) (xy 109.441765 -396.813088) (xy 109.392512 -396.772343)
			(xy 109.348755 -396.725746) (xy 109.311182 -396.674031) (xy 109.280388 -396.618016) (xy 109.256856 -396.558583)
			(xy 109.240959 -396.496669) (xy 109.232948 -396.433251) (xy 108.331007 -396.433251) (xy 108.312452 -396.479792)
			(xy 108.281293 -396.536049) (xy 108.24329 -396.587928) (xy 108.221526 -396.611602) (xy 108.207302 -396.626842)
			(xy 108.20781 -396.66799) (xy 108.964984 -397.425164) (xy 108.971822 -397.432565) (xy 108.979536 -397.451164)
			(xy 108.97997 -397.461232) (xy 108.97997 -397.742621) (xy 109.200436 -397.742621) (xy 109.200436 -397.678699)
			(xy 109.208447 -397.615281) (xy 109.224344 -397.553367) (xy 109.247876 -397.493934) (xy 109.27867 -397.437919)
			(xy 109.316243 -397.386204) (xy 109.36 -397.339607) (xy 109.409253 -397.298862) (xy 109.463224 -397.264611)
			(xy 109.521063 -397.237394) (xy 109.581856 -397.217641) (xy 109.644646 -397.205663) (xy 109.708442 -397.20165)
			(xy 109.772238 -397.205663) (xy 109.835028 -397.217641) (xy 109.895821 -397.237394) (xy 109.95366 -397.264611)
			(xy 110.007631 -397.298862) (xy 110.056884 -397.339607) (xy 110.100641 -397.386204) (xy 110.138214 -397.437919)
			(xy 110.169008 -397.493934) (xy 110.177381 -397.51508) (xy 112.981232 -397.51508) (xy 112.981672 -397.484335)
			(xy 112.989099 -397.423294) (xy 113.00383 -397.363594) (xy 113.02565 -397.306106) (xy 113.054241 -397.251666)
			(xy 113.089187 -397.201071) (xy 113.109248 -397.177768) (xy 113.114724 -397.17095) (xy 113.121228 -397.154732)
			(xy 113.121948 -397.146018) (xy 113.122964 -397.116046) (xy 113.122881 -397.107224) (xy 113.11742 -397.090462)
			(xy 113.112296 -397.08328) (xy 113.092339 -397.056496) (xy 113.05886 -396.998698) (xy 113.033233 -396.937015)
			(xy 113.0159 -396.872509) (xy 113.007159 -396.806289) (xy 113.006632 -396.772892) (xy 113.007134 -396.740931)
			(xy 113.015145 -396.677513) (xy 113.031042 -396.615599) (xy 113.054574 -396.556166) (xy 113.085368 -396.500151)
			(xy 113.122941 -396.448436) (xy 113.166698 -396.401839) (xy 113.215951 -396.361094) (xy 113.269922 -396.326843)
			(xy 113.327761 -396.299626) (xy 113.388554 -396.279873) (xy 113.451344 -396.267895) (xy 113.51514 -396.263882)
			(xy 113.578936 -396.267895) (xy 113.641726 -396.279873) (xy 113.702519 -396.299626) (xy 113.760358 -396.326843)
			(xy 113.814329 -396.361094) (xy 113.863582 -396.401839) (xy 113.907339 -396.448436) (xy 113.944912 -396.500151)
			(xy 113.975706 -396.556166) (xy 113.999238 -396.615599) (xy 114.015135 -396.677513) (xy 114.023146 -396.740931)
			(xy 114.023648 -396.772892) (xy 114.023196 -396.803637) (xy 114.015772 -396.864677) (xy 114.001044 -396.924377)
			(xy 113.979226 -396.981866) (xy 113.950637 -397.036305) (xy 113.915693 -397.086901) (xy 113.895632 -397.110204)
			(xy 113.890125 -397.117) (xy 113.88364 -397.133235) (xy 113.882932 -397.141954) (xy 113.881916 -397.171926)
			(xy 113.881997 -397.180748) (xy 113.887458 -397.197511) (xy 113.892584 -397.204692) (xy 113.912525 -397.231487)
			(xy 113.946008 -397.289282) (xy 113.971638 -397.350962) (xy 113.988975 -397.415465) (xy 113.997719 -397.481684)
			(xy 113.998248 -397.51508) (xy 113.997746 -397.547041) (xy 113.989735 -397.610459) (xy 113.973838 -397.672373)
			(xy 113.950306 -397.731806) (xy 113.919512 -397.787821) (xy 113.881939 -397.839536) (xy 113.838182 -397.886133)
			(xy 113.788929 -397.926878) (xy 113.734958 -397.961129) (xy 113.677119 -397.988346) (xy 113.616326 -398.008099)
			(xy 113.553536 -398.020077) (xy 113.48974 -398.024091) (xy 113.425944 -398.020077) (xy 113.363154 -398.008099)
			(xy 113.302361 -397.988346) (xy 113.244522 -397.961129) (xy 113.190551 -397.926878) (xy 113.141298 -397.886133)
			(xy 113.097541 -397.839536) (xy 113.059968 -397.787821) (xy 113.029174 -397.731806) (xy 113.005642 -397.672373)
			(xy 112.989745 -397.610459) (xy 112.981734 -397.547041) (xy 112.981232 -397.51508) (xy 110.177381 -397.51508)
			(xy 110.19254 -397.553367) (xy 110.208437 -397.615281) (xy 110.216448 -397.678699) (xy 110.21695 -397.71066)
			(xy 110.216448 -397.742621) (xy 110.208437 -397.806039) (xy 110.19254 -397.867953) (xy 110.169008 -397.927386)
			(xy 110.138214 -397.983401) (xy 110.100641 -398.035116) (xy 110.056884 -398.081713) (xy 110.007631 -398.122458)
			(xy 109.95366 -398.156709) (xy 109.895821 -398.183926) (xy 109.835028 -398.203679) (xy 109.772238 -398.215657)
			(xy 109.708442 -398.219671) (xy 109.644646 -398.215657) (xy 109.581856 -398.203679) (xy 109.521063 -398.183926)
			(xy 109.463224 -398.156709) (xy 109.409253 -398.122458) (xy 109.36 -398.081713) (xy 109.316243 -398.035116)
			(xy 109.27867 -397.983401) (xy 109.247876 -397.927386) (xy 109.224344 -397.867953) (xy 109.208447 -397.806039)
			(xy 109.200436 -397.742621) (xy 108.97997 -397.742621) (xy 108.97997 -399.641017) (xy 112.941856 -399.641017)
			(xy 112.941856 -399.577095) (xy 112.949867 -399.513677) (xy 112.965764 -399.451763) (xy 112.989296 -399.39233)
			(xy 113.02009 -399.336315) (xy 113.057663 -399.2846) (xy 113.10142 -399.238003) (xy 113.150673 -399.197258)
			(xy 113.204644 -399.163007) (xy 113.262483 -399.13579) (xy 113.323276 -399.116037) (xy 113.386066 -399.104059)
			(xy 113.449862 -399.100046) (xy 113.513658 -399.104059) (xy 113.576448 -399.116037) (xy 113.637241 -399.13579)
			(xy 113.69508 -399.163007) (xy 113.749051 -399.197258) (xy 113.798304 -399.238003) (xy 113.842061 -399.2846)
			(xy 113.879634 -399.336315) (xy 113.910428 -399.39233) (xy 113.93396 -399.451763) (xy 113.949857 -399.513677)
			(xy 113.957868 -399.577095) (xy 113.95837 -399.609056) (xy 113.957868 -399.641017) (xy 113.949857 -399.704435)
			(xy 113.93396 -399.766349) (xy 113.910428 -399.825782) (xy 113.879634 -399.881797) (xy 113.842061 -399.933512)
			(xy 113.798304 -399.980109) (xy 113.749051 -400.020854) (xy 113.69508 -400.055105) (xy 113.637241 -400.082322)
			(xy 113.576448 -400.102075) (xy 113.513658 -400.114053) (xy 113.449862 -400.118067) (xy 113.386066 -400.114053)
			(xy 113.323276 -400.102075) (xy 113.262483 -400.082322) (xy 113.204644 -400.055105) (xy 113.150673 -400.020854)
			(xy 113.10142 -399.980109) (xy 113.057663 -399.933512) (xy 113.02009 -399.881797) (xy 112.989296 -399.825782)
			(xy 112.965764 -399.766349) (xy 112.949867 -399.704435) (xy 112.941856 -399.641017) (xy 108.97997 -399.641017)
			(xy 108.97997 -400.437604) (xy 111.592866 -400.437604) (xy 111.596937 -400.381982) (xy 111.609063 -400.327545)
			(xy 111.628986 -400.275454) (xy 111.656282 -400.226819) (xy 111.690368 -400.182676) (xy 111.730517 -400.143967)
			(xy 111.775875 -400.111516) (xy 111.825475 -400.086015) (xy 111.878259 -400.068008) (xy 111.933102 -400.057878)
			(xy 111.988836 -400.055841) (xy 112.044273 -400.061941) (xy 112.09823 -400.076047) (xy 112.149559 -400.097859)
			(xy 112.197165 -400.126913) (xy 112.240033 -400.162588) (xy 112.27725 -400.204125) (xy 112.308023 -400.250638)
			(xy 112.331695 -400.301135) (xy 112.347763 -400.354542) (xy 112.355883 -400.409718) (xy 112.356392 -400.437604)
			(xy 112.355883 -400.46549) (xy 112.347763 -400.520666) (xy 112.331695 -400.574073) (xy 112.308023 -400.62457)
			(xy 112.27725 -400.671083) (xy 112.240033 -400.71262) (xy 112.197165 -400.748295) (xy 112.149559 -400.777349)
			(xy 112.09823 -400.799161) (xy 112.044273 -400.813267) (xy 111.988836 -400.819367) (xy 111.933102 -400.81733)
			(xy 111.878259 -400.8072) (xy 111.825475 -400.789193) (xy 111.775875 -400.763692) (xy 111.730517 -400.731241)
			(xy 111.690368 -400.692532) (xy 111.656282 -400.648389) (xy 111.628986 -400.599754) (xy 111.609063 -400.547663)
			(xy 111.596937 -400.493226) (xy 111.592866 -400.437604) (xy 108.97997 -400.437604) (xy 108.97997 -401.318222)
			(xy 108.980279 -401.326709) (xy 108.985833 -401.342748) (xy 108.996349 -401.35607) (xy 109.003338 -401.360894)
			(xy 109.085888 -401.414234) (xy 109.111542 -401.416266) (xy 109.12348 -401.410932) (xy 109.148289 -401.400202)
			(xy 109.200176 -401.385055) (xy 109.25368 -401.377377) (xy 109.280706 -401.376896) (xy 109.308145 -401.377375)
			(xy 109.362456 -401.385247) (xy 109.415076 -401.400828) (xy 109.464917 -401.423795) (xy 109.510948 -401.453673)
			(xy 109.531912 -401.471384) (xy 109.54004 -401.478496) (xy 109.560614 -401.484846) (xy 109.656626 -401.473924)
			(xy 109.674914 -401.463002) (xy 109.681264 -401.454366) (xy 109.699215 -401.430229) (xy 109.739911 -401.38593)
			(xy 109.785551 -401.346744) (xy 109.835497 -401.313218) (xy 109.889051 -401.285822) (xy 109.945463 -401.264937)
			(xy 110.003946 -401.250855) (xy 110.063683 -401.243775) (xy 110.09376 -401.243292) (xy 110.125724 -401.243771)
			(xy 110.189148 -401.251778) (xy 110.251069 -401.267672) (xy 110.310509 -401.291202) (xy 110.366531 -401.321997)
			(xy 110.418252 -401.35957) (xy 110.464855 -401.40333) (xy 110.505606 -401.452586) (xy 110.539862 -401.506561)
			(xy 110.567082 -401.564404) (xy 110.586838 -401.625203) (xy 110.598817 -401.687998) (xy 110.602832 -401.7518)
			(xy 110.601428 -401.774109) (xy 111.742468 -401.774109) (xy 111.742468 -401.710187) (xy 111.750479 -401.646769)
			(xy 111.766376 -401.584855) (xy 111.789908 -401.525422) (xy 111.820702 -401.469407) (xy 111.858275 -401.417692)
			(xy 111.902032 -401.371095) (xy 111.951285 -401.33035) (xy 112.005256 -401.296099) (xy 112.063095 -401.268882)
			(xy 112.123888 -401.249129) (xy 112.186678 -401.237151) (xy 112.250474 -401.233138) (xy 112.31427 -401.237151)
			(xy 112.37706 -401.249129) (xy 112.437853 -401.268882) (xy 112.495692 -401.296099) (xy 112.549663 -401.33035)
			(xy 112.598916 -401.371095) (xy 112.642673 -401.417692) (xy 112.680246 -401.469407) (xy 112.71104 -401.525422)
			(xy 112.734572 -401.584855) (xy 112.750469 -401.646769) (xy 112.75848 -401.710187) (xy 112.758982 -401.742148)
			(xy 112.75848 -401.774109) (xy 112.750469 -401.837527) (xy 112.734572 -401.899441) (xy 112.71104 -401.958874)
			(xy 112.680246 -402.014889) (xy 112.642673 -402.066604) (xy 112.598916 -402.113201) (xy 112.549663 -402.153946)
			(xy 112.495692 -402.188197) (xy 112.437853 -402.215414) (xy 112.37706 -402.235167) (xy 112.31427 -402.247145)
			(xy 112.250474 -402.251159) (xy 112.186678 -402.247145) (xy 112.123888 -402.235167) (xy 112.063095 -402.215414)
			(xy 112.005256 -402.188197) (xy 111.951285 -402.153946) (xy 111.902032 -402.113201) (xy 111.858275 -402.066604)
			(xy 111.820702 -402.014889) (xy 111.789908 -401.958874) (xy 111.766376 -401.899441) (xy 111.750479 -401.837527)
			(xy 111.742468 -401.774109) (xy 110.601428 -401.774109) (xy 110.598817 -401.815602) (xy 110.586838 -401.878397)
			(xy 110.567082 -401.939196) (xy 110.539862 -401.997039) (xy 110.505606 -402.051014) (xy 110.464855 -402.10027)
			(xy 110.418252 -402.14403) (xy 110.366531 -402.181603) (xy 110.310509 -402.212398) (xy 110.251069 -402.235928)
			(xy 110.189148 -402.251822) (xy 110.125724 -402.259829) (xy 110.09376 -402.260308) (xy 110.059966 -402.259758)
			(xy 109.992973 -402.250813) (xy 109.927755 -402.233071) (xy 109.865463 -402.206846) (xy 109.807193 -402.172601)
			(xy 109.753974 -402.130938) (xy 109.706743 -402.082592) (xy 109.68609 -402.055838) (xy 109.67974 -402.047202)
			(xy 109.661198 -402.036788) (xy 109.564932 -402.02739) (xy 109.544612 -402.033994) (xy 109.536738 -402.04136)
			(xy 109.515578 -402.059821) (xy 109.468858 -402.090971) (xy 109.418077 -402.114938) (xy 109.364331 -402.131205)
			(xy 109.308783 -402.13942) (xy 109.280706 -402.139912) (xy 109.25368 -402.139427) (xy 109.200173 -402.131762)
			(xy 109.148286 -402.116615) (xy 109.12348 -402.105876) (xy 109.111542 -402.100542) (xy 109.085888 -402.102574)
			(xy 109.003338 -402.155914) (xy 108.996381 -402.16077) (xy 108.985895 -402.174097) (xy 108.980313 -402.190109)
			(xy 108.97997 -402.198586) (xy 108.97997 -404.379938) (xy 108.980579 -404.391265) (xy 108.990349 -404.411701)
			(xy 108.998766 -404.419308) (xy 109.06887 -404.476204) (xy 109.091222 -404.481792) (xy 109.102398 -404.479252)
			(xy 109.128138 -404.474226) (xy 109.180313 -404.468879) (xy 109.206538 -404.468584) (xy 109.238498 -404.469088)
			(xy 109.301913 -404.477104) (xy 109.363824 -404.493004) (xy 109.423254 -404.516538) (xy 109.479266 -404.547335)
			(xy 109.530977 -404.584908) (xy 109.577571 -404.628666) (xy 109.618314 -404.677919) (xy 109.652562 -404.731889)
			(xy 109.679777 -404.789726) (xy 109.699528 -404.850518) (xy 109.711505 -404.913306) (xy 109.715519 -404.9771)
			(xy 109.711505 -405.040894) (xy 109.699528 -405.103682) (xy 109.679777 -405.164474) (xy 109.652562 -405.222311)
			(xy 109.618314 -405.276281) (xy 109.577571 -405.325534) (xy 109.530977 -405.369292) (xy 109.479266 -405.406865)
			(xy 109.423254 -405.437662) (xy 109.363824 -405.461196) (xy 109.301913 -405.477096) (xy 109.238498 -405.485112)
			(xy 109.206538 -405.4856) (xy 109.180314 -405.485296) (xy 109.12814 -405.479946) (xy 109.102398 -405.474932)
			(xy 109.091222 -405.472392) (xy 109.06887 -405.47798) (xy 108.998766 -405.534876) (xy 108.990357 -405.542488)
			(xy 108.980576 -405.562922) (xy 108.97997 -405.574246) (xy 108.97997 -407.332942) (xy 108.98035 -407.341505)
			(xy 108.986073 -407.35765) (xy 108.996773 -407.371026) (xy 109.003846 -407.375868) (xy 109.08792 -407.4287)
			(xy 109.113828 -407.42997) (xy 109.125766 -407.424128) (xy 109.151655 -407.412082) (xy 109.20554 -407.393183)
			(xy 109.261202 -407.380435) (xy 109.317941 -407.373997) (xy 109.346492 -407.373582) (xy 109.347 -407.373582)
			(xy 109.378962 -407.374084) (xy 109.442381 -407.382096) (xy 109.504296 -407.397993) (xy 109.56373 -407.421524)
			(xy 109.619747 -407.45232) (xy 109.671462 -407.489893) (xy 109.71806 -407.533651) (xy 109.758806 -407.582905)
			(xy 109.793058 -407.636878) (xy 109.820275 -407.694717) (xy 109.840029 -407.755512) (xy 109.852007 -407.818303)
			(xy 109.856021 -407.8821) (xy 109.852007 -407.945897) (xy 109.840029 -408.008688) (xy 109.820275 -408.069483)
			(xy 109.793058 -408.127322) (xy 109.758806 -408.181295) (xy 109.71806 -408.230549) (xy 109.671462 -408.274307)
			(xy 109.619747 -408.31188) (xy 109.56373 -408.342676) (xy 109.504296 -408.366207) (xy 109.442381 -408.382104)
			(xy 109.378962 -408.390116) (xy 109.347 -408.390598) (xy 109.346492 -408.390598) (xy 109.317939 -408.390199)
			(xy 109.261196 -408.383773) (xy 109.205532 -408.371025) (xy 109.151648 -408.352117) (xy 109.125766 -408.340052)
			(xy 109.113828 -408.33421) (xy 109.08792 -408.33548) (xy 109.003846 -408.388312) (xy 108.996744 -408.393123)
			(xy 108.986016 -408.406493) (xy 108.980335 -408.422667) (xy 108.97997 -408.431238) (xy 108.97997 -409.332938)
			(xy 108.980349 -409.341501) (xy 108.986072 -409.357647) (xy 108.996772 -409.371025) (xy 109.003846 -409.375864)
			(xy 109.08792 -409.428696) (xy 109.113828 -409.429966) (xy 109.125766 -409.424124) (xy 109.151655 -409.412078)
			(xy 109.20554 -409.39318) (xy 109.261202 -409.380431) (xy 109.317941 -409.373994) (xy 109.346492 -409.373578)
			(xy 109.347 -409.373578) (xy 109.378962 -409.37408) (xy 109.442382 -409.382092) (xy 109.504297 -409.397989)
			(xy 109.563732 -409.421521) (xy 109.619749 -409.452316) (xy 109.671464 -409.48989) (xy 109.718063 -409.533649)
			(xy 109.758809 -409.582903) (xy 109.793062 -409.636876) (xy 109.820279 -409.694716) (xy 109.840033 -409.755511)
			(xy 109.852011 -409.818302) (xy 109.856025 -409.8821) (xy 109.854667 -409.903676) (xy 110.432596 -409.903676)
			(xy 110.433165 -409.86872) (xy 110.44273 -409.799467) (xy 110.46169 -409.732175) (xy 110.489688 -409.668115)
			(xy 110.526196 -409.608494) (xy 110.547912 -409.581096) (xy 110.55321 -409.574098) (xy 110.559184 -409.557606)
			(xy 110.559596 -409.548838) (xy 110.559596 -409.394914) (xy 110.55923 -409.386137) (xy 110.553248 -409.369635)
			(xy 110.547912 -409.362656) (xy 110.52618 -409.335271) (xy 110.489685 -409.275641) (xy 110.461696 -409.211577)
			(xy 110.44274 -409.144285) (xy 110.433173 -409.075032) (xy 110.432596 -409.040076) (xy 110.433034 -409.009344)
			(xy 110.440445 -408.948329) (xy 110.455156 -408.888653) (xy 110.476954 -408.831184) (xy 110.505519 -408.776762)
			(xy 110.540436 -408.72618) (xy 110.581195 -408.680175) (xy 110.627202 -408.639419) (xy 110.677786 -408.604505)
			(xy 110.73221 -408.575942) (xy 110.789679 -408.554148) (xy 110.849357 -408.53944) (xy 110.910372 -408.532032)
			(xy 110.941104 -408.531568) (xy 110.978952 -408.53227) (xy 111.053813 -408.54349) (xy 111.090202 -408.55392)
			(xy 111.099854 -408.556968) (xy 111.119412 -408.55519) (xy 111.200184 -408.513534) (xy 111.213138 -408.498548)
			(xy 111.216186 -408.48915) (xy 111.225015 -408.464234) (xy 111.248636 -408.416943) (xy 111.278559 -408.373365)
			(xy 111.31421 -408.334334) (xy 111.354907 -408.300598) (xy 111.399872 -408.272803) (xy 111.448242 -408.251479)
			(xy 111.499093 -408.237037) (xy 111.551451 -408.229752) (xy 111.577882 -408.229308) (xy 111.605137 -408.229738)
			(xy 111.659092 -408.237493) (xy 111.711394 -408.252848) (xy 111.760979 -408.27549) (xy 111.806836 -408.304959)
			(xy 111.848033 -408.340654) (xy 111.88373 -408.381849) (xy 111.913201 -408.427705) (xy 111.935846 -408.477289)
			(xy 111.951203 -408.52959) (xy 111.958961 -408.583545) (xy 111.958961 -408.638055) (xy 111.951203 -408.69201)
			(xy 111.935846 -408.744311) (xy 111.913201 -408.793895) (xy 111.88373 -408.839751) (xy 111.848033 -408.880946)
			(xy 111.806836 -408.916641) (xy 111.760979 -408.94611) (xy 111.711394 -408.968752) (xy 111.659092 -408.984107)
			(xy 111.605137 -408.991862) (xy 111.577882 -408.992324) (xy 111.555022 -408.991562) (xy 111.545116 -408.991054)
			(xy 111.52632 -408.997404) (xy 111.457486 -409.056586) (xy 111.448596 -409.074366) (xy 111.44758 -409.084272)
			(xy 111.44449 -409.11464) (xy 111.431991 -409.174388) (xy 111.412421 -409.232208) (xy 111.386063 -409.287265)
			(xy 111.353297 -409.338767) (xy 111.334296 -409.362656) (xy 111.329007 -409.36966) (xy 111.323029 -409.386148)
			(xy 111.322612 -409.394914) (xy 111.322612 -409.548838) (xy 111.323 -409.557613) (xy 111.328967 -409.574115)
			(xy 111.334296 -409.581096) (xy 111.352707 -409.604235) (xy 111.384646 -409.654003) (xy 111.410604 -409.707135)
			(xy 111.430232 -409.762916) (xy 111.437166 -409.791662) (xy 111.439198 -409.801314) (xy 111.449866 -409.817062)
			(xy 111.523272 -409.8671) (xy 111.541814 -409.871418) (xy 111.551466 -409.869894) (xy 111.565666 -409.867865)
			(xy 111.594272 -409.865707) (xy 111.608616 -409.865576) (xy 111.635865 -409.866095) (xy 111.689809 -409.873853)
			(xy 111.7421 -409.889209) (xy 111.791673 -409.91185) (xy 111.837519 -409.941316) (xy 111.878706 -409.977006)
			(xy 111.914394 -410.018194) (xy 111.943857 -410.064041) (xy 111.966496 -410.113615) (xy 111.98185 -410.165907)
			(xy 111.989606 -410.219851) (xy 111.989606 -410.274349) (xy 111.98185 -410.328293) (xy 111.966496 -410.380585)
			(xy 111.943857 -410.430159) (xy 111.914394 -410.476006) (xy 111.878706 -410.517194) (xy 111.837519 -410.552884)
			(xy 111.791673 -410.58235) (xy 111.7421 -410.604991) (xy 111.689809 -410.620347) (xy 111.635865 -410.628105)
			(xy 111.608616 -410.628592) (xy 111.582358 -410.628148) (xy 111.530342 -410.620923) (xy 111.479807 -410.606636)
			(xy 111.431708 -410.585555) (xy 111.386953 -410.55808) (xy 111.346387 -410.524729) (xy 111.310777 -410.486131)
			(xy 111.280794 -410.443015) (xy 111.26851 -410.419804) (xy 111.263938 -410.411168) (xy 111.249968 -410.398722)
			(xy 111.166402 -410.367988) (xy 111.147606 -410.368496) (xy 111.138462 -410.372306) (xy 111.107105 -410.384919)
			(xy 111.04189 -410.402673) (xy 110.974898 -410.41163) (xy 110.941104 -410.412184) (xy 110.910371 -410.411759)
			(xy 110.849353 -410.40435) (xy 110.789673 -410.38964) (xy 110.732202 -410.367844) (xy 110.677777 -410.339279)
			(xy 110.627192 -410.304361) (xy 110.581185 -410.263601) (xy 110.540426 -410.217592) (xy 110.505511 -410.167006)
			(xy 110.476948 -410.11258) (xy 110.455154 -410.055107) (xy 110.440447 -409.995427) (xy 110.43304 -409.934409)
			(xy 110.432596 -409.903676) (xy 109.854667 -409.903676) (xy 109.852011 -409.945898) (xy 109.840033 -410.008689)
			(xy 109.820279 -410.069484) (xy 109.793062 -410.127324) (xy 109.758809 -410.181297) (xy 109.718063 -410.230551)
			(xy 109.671464 -410.27431) (xy 109.619749 -410.311884) (xy 109.563732 -410.342679) (xy 109.504297 -410.366211)
			(xy 109.442382 -410.382108) (xy 109.378962 -410.39012) (xy 109.347 -410.390594) (xy 109.346492 -410.390594)
			(xy 109.317939 -410.390195) (xy 109.261196 -410.383769) (xy 109.205532 -410.371021) (xy 109.151648 -410.352113)
			(xy 109.125766 -410.340048) (xy 109.113828 -410.334206) (xy 109.08792 -410.335476) (xy 109.003846 -410.388308)
			(xy 108.996744 -410.393119) (xy 108.986014 -410.406488) (xy 108.980333 -410.422662) (xy 108.97997 -410.431234)
			(xy 108.97997 -412.582868) (xy 109.134148 -412.582868) (xy 109.134683 -412.549385) (xy 109.143485 -412.483)
			(xy 109.160917 -412.418343) (xy 109.186681 -412.356531) (xy 109.220329 -412.298632) (xy 109.261281 -412.245648)
			(xy 109.30883 -412.198492) (xy 109.362153 -412.157982) (xy 109.420329 -412.124815) (xy 109.45114 -412.111698)
			(xy 109.459549 -412.107898) (xy 109.473098 -412.095393) (xy 109.477556 -412.087314) (xy 109.491272 -412.059882)
			(xy 109.494982 -412.051359) (xy 109.496683 -412.032866) (xy 109.494574 -412.023814) (xy 109.486112 -411.99087)
			(xy 109.477065 -411.923457) (xy 109.47654 -411.889448) (xy 109.477042 -411.857487) (xy 109.485053 -411.794069)
			(xy 109.50095 -411.732155) (xy 109.524482 -411.672722) (xy 109.555276 -411.616707) (xy 109.592849 -411.564992)
			(xy 109.636606 -411.518395) (xy 109.685859 -411.47765) (xy 109.73983 -411.443399) (xy 109.797669 -411.416182)
			(xy 109.858462 -411.396429) (xy 109.921252 -411.384451) (xy 109.985048 -411.380438) (xy 110.048844 -411.384451)
			(xy 110.111634 -411.396429) (xy 110.172427 -411.416182) (xy 110.230266 -411.443399) (xy 110.284237 -411.47765)
			(xy 110.33349 -411.518395) (xy 110.377247 -411.564992) (xy 110.41482 -411.616707) (xy 110.445614 -411.672722)
			(xy 110.469146 -411.732155) (xy 110.485043 -411.794069) (xy 110.493054 -411.857487) (xy 110.493556 -411.889448)
			(xy 110.493032 -411.922931) (xy 110.484229 -411.989317) (xy 110.466794 -412.053974) (xy 110.441029 -412.115786)
			(xy 110.407379 -412.173685) (xy 110.366426 -412.226669) (xy 110.318876 -412.273824) (xy 110.265552 -412.314334)
			(xy 110.207376 -412.347501) (xy 110.176564 -412.360618) (xy 110.168152 -412.364413) (xy 110.154605 -412.376921)
			(xy 110.150148 -412.385002) (xy 110.136432 -412.412434) (xy 110.132713 -412.420953) (xy 110.13102 -412.439449)
			(xy 110.13313 -412.448502) (xy 110.141592 -412.481446) (xy 110.15064 -412.548859) (xy 110.151164 -412.582868)
			(xy 110.150572 -412.617695) (xy 110.14108 -412.686698) (xy 110.122256 -412.753759) (xy 110.094451 -412.817621)
			(xy 110.058188 -412.87709) (xy 110.03661 -412.904432) (xy 110.029498 -412.913068) (xy 110.02391 -412.934658)
			(xy 110.041436 -413.032448) (xy 110.054136 -413.050736) (xy 110.063534 -413.056324) (xy 110.087685 -413.071112)
			(xy 110.131706 -413.106735) (xy 110.169976 -413.148476) (xy 110.201653 -413.195417) (xy 110.226041 -413.246525)
			(xy 110.242604 -413.300679) (xy 110.250977 -413.356685) (xy 110.251494 -413.385) (xy 110.251008 -413.412251)
			(xy 110.243252 -413.466199) (xy 110.227897 -413.518494) (xy 110.205255 -413.568071) (xy 110.175789 -413.613921)
			(xy 110.140098 -413.655112) (xy 110.098907 -413.690803) (xy 110.053057 -413.720269) (xy 110.00348 -413.742911)
			(xy 109.951185 -413.758266) (xy 109.897237 -413.766022) (xy 109.842735 -413.766022) (xy 109.788787 -413.758266)
			(xy 109.736492 -413.742911) (xy 109.686915 -413.720269) (xy 109.641065 -413.690803) (xy 109.599874 -413.655112)
			(xy 109.564183 -413.613921) (xy 109.534717 -413.568071) (xy 109.512075 -413.518494) (xy 109.49672 -413.466199)
			(xy 109.488964 -413.412251) (xy 109.488478 -413.385) (xy 109.48907 -413.35406) (xy 109.499051 -413.29299)
			(xy 109.518752 -413.234329) (xy 109.532674 -413.206692) (xy 109.537754 -413.19704) (xy 109.539024 -413.174688)
			(xy 109.502702 -413.082232) (xy 109.4867 -413.066992) (xy 109.476032 -413.063436) (xy 109.446459 -413.052675)
			(xy 109.390004 -413.024865) (xy 109.337411 -412.990302) (xy 109.289484 -412.949515) (xy 109.246955 -412.903127)
			(xy 109.210473 -412.851847) (xy 109.180597 -412.796458) (xy 109.157781 -412.737806) (xy 109.142376 -412.676787)
			(xy 109.134616 -412.614335) (xy 109.134148 -412.582868) (xy 108.97997 -412.582868) (xy 108.97997 -416.219894)
			(xy 108.980379 -416.229547) (xy 108.987526 -416.247479) (xy 109.000835 -416.261463) (xy 109.009434 -416.265868)
			(xy 109.106208 -416.31108) (xy 109.135418 -416.30727) (xy 109.146848 -416.297618) (xy 109.169799 -416.278886)
			(xy 109.219287 -416.246315) (xy 109.272222 -416.219713) (xy 109.32789 -416.19944) (xy 109.385535 -416.18577)
			(xy 109.444378 -416.178888) (xy 109.474 -416.178492) (xy 109.506172 -416.178992) (xy 109.570001 -416.187119)
			(xy 109.632295 -416.203229) (xy 109.69206 -416.227067) (xy 109.748343 -416.25825) (xy 109.800244 -416.296282)
			(xy 109.846934 -416.340556) (xy 109.887669 -416.390364) (xy 109.921798 -416.44491) (xy 109.935772 -416.473894)
			(xy 109.940344 -416.4838) (xy 109.957108 -416.498278) (xy 110.052612 -416.525456) (xy 110.074456 -416.522154)
			(xy 110.0836 -416.516058) (xy 110.108561 -416.50017) (xy 110.161449 -416.473633) (xy 110.217059 -416.453413)
			(xy 110.27464 -416.439784) (xy 110.333414 -416.432928) (xy 110.363 -416.432492) (xy 110.394961 -416.432994)
			(xy 110.458379 -416.441005) (xy 110.520293 -416.456902) (xy 110.579726 -416.480434) (xy 110.635741 -416.511228)
			(xy 110.687456 -416.548801) (xy 110.734053 -416.592558) (xy 110.774798 -416.641811) (xy 110.809049 -416.695782)
			(xy 110.836266 -416.753621) (xy 110.856019 -416.814414) (xy 110.867997 -416.877204) (xy 110.872011 -416.941)
			(xy 110.867997 -417.004796) (xy 110.856019 -417.067586) (xy 110.836266 -417.128379) (xy 110.809049 -417.186218)
			(xy 110.774798 -417.240189) (xy 110.734053 -417.289442) (xy 110.687456 -417.333199) (xy 110.635741 -417.370772)
			(xy 110.579726 -417.401566) (xy 110.520293 -417.425098) (xy 110.458379 -417.440995) (xy 110.394961 -417.449006)
			(xy 110.363 -417.449508) (xy 110.330828 -417.449008) (xy 110.266999 -417.440881) (xy 110.204705 -417.424771)
			(xy 110.14494 -417.400933) (xy 110.088657 -417.36975) (xy 110.036756 -417.331718) (xy 109.990066 -417.287444)
			(xy 109.949331 -417.237636) (xy 109.915202 -417.18309) (xy 109.901228 -417.154106) (xy 109.896656 -417.1442)
			(xy 109.879892 -417.129722) (xy 109.784388 -417.102544) (xy 109.762544 -417.105846) (xy 109.7534 -417.111942)
			(xy 109.728439 -417.12783) (xy 109.675551 -417.154367) (xy 109.619941 -417.174587) (xy 109.56236 -417.188216)
			(xy 109.503586 -417.195072) (xy 109.474 -417.195508) (xy 109.444379 -417.195093) (xy 109.385537 -417.188213)
			(xy 109.327892 -417.174546) (xy 109.272224 -417.154276) (xy 109.219288 -417.127679) (xy 109.169798 -417.095114)
			(xy 109.146848 -417.076382) (xy 109.135418 -417.06673) (xy 109.106208 -417.06292) (xy 109.009434 -417.108132)
			(xy 109.000869 -417.112576) (xy 108.987608 -417.126575) (xy 108.980419 -417.144467) (xy 108.97997 -417.154106)
			(xy 108.97997 -418.727128) (xy 108.99521 -418.751766) (xy 109.008164 -418.758116) (xy 109.030852 -418.769818)
			(xy 109.073184 -418.798348) (xy 109.111345 -418.832256) (xy 109.128306 -418.851334) (xy 109.136434 -418.860732)
			(xy 109.15904 -418.869876) (xy 109.265466 -418.860986) (xy 109.28604 -418.848032) (xy 109.29239 -418.837618)
			(xy 109.309697 -418.809862) (xy 109.350352 -418.758618) (xy 109.397244 -418.713012) (xy 109.449598 -418.673797)
			(xy 109.506549 -418.641621) (xy 109.567157 -418.617015) (xy 109.63042 -418.600387) (xy 109.695294 -418.59201)
			(xy 109.728 -418.591492) (xy 109.759961 -418.591994) (xy 109.823379 -418.600005) (xy 109.885293 -418.615902)
			(xy 109.944726 -418.639434) (xy 110.000741 -418.670228) (xy 110.052456 -418.707801) (xy 110.099053 -418.751558)
			(xy 110.139798 -418.800811) (xy 110.174049 -418.854782) (xy 110.201266 -418.912621) (xy 110.221019 -418.973414)
			(xy 110.227037 -419.004961) (xy 110.470944 -419.004961) (xy 110.470944 -418.941039) (xy 110.478955 -418.877621)
			(xy 110.494852 -418.815707) (xy 110.518384 -418.756274) (xy 110.549178 -418.700259) (xy 110.586751 -418.648544)
			(xy 110.630508 -418.601947) (xy 110.679761 -418.561202) (xy 110.733732 -418.526951) (xy 110.791571 -418.499734)
			(xy 110.852364 -418.479981) (xy 110.915154 -418.468003) (xy 110.97895 -418.46399) (xy 111.042746 -418.468003)
			(xy 111.105536 -418.479981) (xy 111.166329 -418.499734) (xy 111.224168 -418.526951) (xy 111.278139 -418.561202)
			(xy 111.327392 -418.601947) (xy 111.371149 -418.648544) (xy 111.408722 -418.700259) (xy 111.439516 -418.756274)
			(xy 111.463048 -418.815707) (xy 111.478945 -418.877621) (xy 111.486956 -418.941039) (xy 111.487458 -418.973)
			(xy 111.486956 -419.004961) (xy 111.478945 -419.068379) (xy 111.463048 -419.130293) (xy 111.439516 -419.189726)
			(xy 111.408722 -419.245741) (xy 111.371149 -419.297456) (xy 111.327392 -419.344053) (xy 111.278139 -419.384798)
			(xy 111.224168 -419.419049) (xy 111.166329 -419.446266) (xy 111.105536 -419.466019) (xy 111.042746 -419.477997)
			(xy 110.97895 -419.482011) (xy 110.915154 -419.477997) (xy 110.852364 -419.466019) (xy 110.791571 -419.446266)
			(xy 110.733732 -419.419049) (xy 110.679761 -419.384798) (xy 110.630508 -419.344053) (xy 110.586751 -419.297456)
			(xy 110.549178 -419.245741) (xy 110.518384 -419.189726) (xy 110.494852 -419.130293) (xy 110.478955 -419.068379)
			(xy 110.470944 -419.004961) (xy 110.227037 -419.004961) (xy 110.232997 -419.036204) (xy 110.237011 -419.1)
			(xy 110.232997 -419.163796) (xy 110.221019 -419.226586) (xy 110.201266 -419.287379) (xy 110.174049 -419.345218)
			(xy 110.139798 -419.399189) (xy 110.099053 -419.448442) (xy 110.052456 -419.492199) (xy 110.000741 -419.529772)
			(xy 109.944726 -419.560566) (xy 109.885293 -419.584098) (xy 109.823379 -419.599995) (xy 109.759961 -419.608006)
			(xy 109.728 -419.608508) (xy 109.695294 -419.608002) (xy 109.630421 -419.599616) (xy 109.567159 -419.582981)
			(xy 109.506551 -419.558373) (xy 109.449599 -419.526198) (xy 109.397241 -419.486987) (xy 109.350343 -419.441386)
			(xy 109.309679 -419.390149) (xy 109.29239 -419.362382) (xy 109.28604 -419.351968) (xy 109.265466 -419.339014)
			(xy 109.15904 -419.330124) (xy 109.136434 -419.339268) (xy 109.128306 -419.348666) (xy 109.110101 -419.369122)
			(xy 109.068838 -419.405119) (xy 109.022853 -419.43485) (xy 108.973091 -419.457703) (xy 108.920574 -419.473209)
			(xy 108.866379 -419.48105) (xy 108.839 -419.481508) (xy 108.838492 -419.481508) (xy 108.815398 -419.481154)
			(xy 108.769552 -419.475547) (xy 108.747052 -419.470332) (xy 108.734098 -419.46703) (xy 108.708444 -419.474142)
			(xy 106.37266 -421.809926) (xy 106.365263 -421.816774) (xy 106.346664 -421.824506) (xy 106.336592 -421.824912)
			(xy 97.806764 -421.824912) (xy 97.796696 -421.824483) (xy 97.7781 -421.816761) (xy 97.770696 -421.809926)
			(xy 97.712276 -421.751506) (xy 97.70542 -421.744112) (xy 97.697671 -421.725513) (xy 97.69729 -421.715438)
			(xy 97.69729 -421.224456) (xy 97.696898 -421.214876) (xy 97.689899 -421.197039) (xy 97.676853 -421.183007)
			(xy 97.659574 -421.174729) (xy 97.650046 -421.173656) (xy 97.149412 -421.173656) (xy 97.149412 -417.00831)
			(xy 97.148405 -416.999267) (xy 97.140864 -416.982725) (xy 97.13468 -416.976052) (xy 97.074736 -416.916108)
			(xy 97.067335 -416.909271) (xy 97.048736 -416.901558) (xy 97.038668 -416.901122) (xy 96.95053 -416.901122)
			(xy 96.940541 -416.901654) (xy 96.922103 -416.909363) (xy 96.914716 -416.916108) (xy 96.05137 -417.779454)
			(xy 96.04456 -417.786799) (xy 96.036836 -417.805262) (xy 96.036384 -417.815268) (xy 96.036384 -418.918898)
			(xy 96.035883 -418.943424) (xy 96.028179 -418.991868) (xy 96.013008 -419.038516) (xy 95.990741 -419.082223)
			(xy 95.961924 -419.121919) (xy 95.944944 -419.139624) (xy 95.941134 -419.143434) (xy 95.934325 -419.150779)
			(xy 95.926599 -419.169242) (xy 95.926148 -419.179248) (xy 95.926148 -422.064391) (xy 96.549204 -422.064391)
			(xy 96.549204 -422.000469) (xy 96.557215 -421.937051) (xy 96.573112 -421.875137) (xy 96.596644 -421.815704)
			(xy 96.627438 -421.759689) (xy 96.665011 -421.707974) (xy 96.708768 -421.661377) (xy 96.758021 -421.620632)
			(xy 96.811992 -421.586381) (xy 96.869831 -421.559164) (xy 96.930624 -421.539411) (xy 96.993414 -421.527433)
			(xy 97.05721 -421.52342) (xy 97.121006 -421.527433) (xy 97.183796 -421.539411) (xy 97.244589 -421.559164)
			(xy 97.302428 -421.586381) (xy 97.356399 -421.620632) (xy 97.405652 -421.661377) (xy 97.449409 -421.707974)
			(xy 97.486982 -421.759689) (xy 97.517776 -421.815704) (xy 97.541308 -421.875137) (xy 97.557205 -421.937051)
			(xy 97.565216 -422.000469) (xy 97.565718 -422.03243) (xy 97.565216 -422.064391) (xy 97.557205 -422.127809)
			(xy 97.541308 -422.189723) (xy 97.517776 -422.249156) (xy 97.486982 -422.305171) (xy 97.449409 -422.356886)
			(xy 97.405652 -422.403483) (xy 97.356399 -422.444228) (xy 97.302428 -422.478479) (xy 97.244589 -422.505696)
			(xy 97.183796 -422.525449) (xy 97.121006 -422.537427) (xy 97.05721 -422.541441) (xy 96.993414 -422.537427)
			(xy 96.930624 -422.525449) (xy 96.869831 -422.505696) (xy 96.811992 -422.478479) (xy 96.758021 -422.444228)
			(xy 96.708768 -422.403483) (xy 96.665011 -422.356886) (xy 96.627438 -422.305171) (xy 96.596644 -422.249156)
			(xy 96.573112 -422.189723) (xy 96.557215 -422.127809) (xy 96.549204 -422.064391) (xy 95.926148 -422.064391)
			(xy 95.926148 -423.457116) (xy 97.53549 -423.457116) (xy 97.539561 -423.401494) (xy 97.551687 -423.347057)
			(xy 97.57161 -423.294966) (xy 97.598906 -423.246331) (xy 97.632992 -423.202188) (xy 97.673141 -423.163479)
			(xy 97.718499 -423.131028) (xy 97.768099 -423.105527) (xy 97.820883 -423.08752) (xy 97.875726 -423.07739)
			(xy 97.93146 -423.075353) (xy 97.986897 -423.081453) (xy 98.040854 -423.095559) (xy 98.092183 -423.117371)
			(xy 98.139789 -423.146425) (xy 98.182657 -423.1821) (xy 98.219874 -423.223637) (xy 98.250647 -423.27015)
			(xy 98.274319 -423.320647) (xy 98.290387 -423.374054) (xy 98.298507 -423.42923) (xy 98.298858 -423.44848)
			(xy 98.633278 -423.44848) (xy 98.637349 -423.392858) (xy 98.649475 -423.338421) (xy 98.669398 -423.28633)
			(xy 98.696694 -423.237695) (xy 98.73078 -423.193552) (xy 98.770929 -423.154843) (xy 98.816287 -423.122392)
			(xy 98.865887 -423.096891) (xy 98.918671 -423.078884) (xy 98.973514 -423.068754) (xy 99.029248 -423.066717)
			(xy 99.084685 -423.072817) (xy 99.138642 -423.086923) (xy 99.189971 -423.108735) (xy 99.237577 -423.137789)
			(xy 99.280445 -423.173464) (xy 99.317662 -423.215001) (xy 99.348435 -423.261514) (xy 99.372107 -423.312011)
			(xy 99.388175 -423.365418) (xy 99.396295 -423.420594) (xy 99.396804 -423.44848) (xy 99.903278 -423.44848)
			(xy 99.907349 -423.392858) (xy 99.919475 -423.338421) (xy 99.939398 -423.28633) (xy 99.966694 -423.237695)
			(xy 100.00078 -423.193552) (xy 100.040929 -423.154843) (xy 100.086287 -423.122392) (xy 100.135887 -423.096891)
			(xy 100.188671 -423.078884) (xy 100.243514 -423.068754) (xy 100.299248 -423.066717) (xy 100.354685 -423.072817)
			(xy 100.408642 -423.086923) (xy 100.459971 -423.108735) (xy 100.507577 -423.137789) (xy 100.550445 -423.173464)
			(xy 100.587662 -423.215001) (xy 100.618435 -423.261514) (xy 100.642107 -423.312011) (xy 100.658175 -423.365418)
			(xy 100.666295 -423.420594) (xy 100.666804 -423.44848) (xy 101.173278 -423.44848) (xy 101.177349 -423.392858)
			(xy 101.189475 -423.338421) (xy 101.209398 -423.28633) (xy 101.236694 -423.237695) (xy 101.27078 -423.193552)
			(xy 101.310929 -423.154843) (xy 101.356287 -423.122392) (xy 101.405887 -423.096891) (xy 101.458671 -423.078884)
			(xy 101.513514 -423.068754) (xy 101.569248 -423.066717) (xy 101.624685 -423.072817) (xy 101.678642 -423.086923)
			(xy 101.729971 -423.108735) (xy 101.776754 -423.137287) (xy 102.06837 -423.137287) (xy 102.06837 -423.073365)
			(xy 102.076381 -423.009947) (xy 102.092278 -422.948033) (xy 102.11581 -422.8886) (xy 102.146604 -422.832585)
			(xy 102.184177 -422.78087) (xy 102.227934 -422.734273) (xy 102.277187 -422.693528) (xy 102.331158 -422.659277)
			(xy 102.388997 -422.63206) (xy 102.44979 -422.612307) (xy 102.51258 -422.600329) (xy 102.576376 -422.596316)
			(xy 102.640172 -422.600329) (xy 102.702962 -422.612307) (xy 102.763755 -422.63206) (xy 102.821594 -422.659277)
			(xy 102.875565 -422.693528) (xy 102.924818 -422.734273) (xy 102.968575 -422.78087) (xy 103.006148 -422.832585)
			(xy 103.036942 -422.8886) (xy 103.037872 -422.89095) (xy 106.171492 -422.89095) (xy 106.171994 -422.858989)
			(xy 106.180005 -422.795571) (xy 106.195902 -422.733657) (xy 106.219434 -422.674224) (xy 106.250228 -422.618209)
			(xy 106.287801 -422.566494) (xy 106.331558 -422.519897) (xy 106.380811 -422.479152) (xy 106.434782 -422.444901)
			(xy 106.492621 -422.417684) (xy 106.553414 -422.397931) (xy 106.616204 -422.385953) (xy 106.68 -422.38194)
			(xy 106.743796 -422.385953) (xy 106.806586 -422.397931) (xy 106.867379 -422.417684) (xy 106.925218 -422.444901)
			(xy 106.979189 -422.479152) (xy 107.028442 -422.519897) (xy 107.072199 -422.566494) (xy 107.109772 -422.618209)
			(xy 107.140566 -422.674224) (xy 107.164098 -422.733657) (xy 107.179995 -422.795571) (xy 107.188006 -422.858989)
			(xy 107.188508 -422.89095) (xy 107.187954 -422.924507) (xy 107.179109 -422.991036) (xy 107.161592 -423.055824)
			(xy 107.135707 -423.117747) (xy 107.101905 -423.175727) (xy 107.060772 -423.22876) (xy 107.013022 -423.275922)
			(xy 106.986578 -423.296588) (xy 106.977942 -423.303192) (xy 106.967782 -423.320972) (xy 106.957368 -423.415968)
			(xy 106.963464 -423.435526) (xy 106.970322 -423.443654) (xy 106.987458 -423.46444) (xy 107.016303 -423.509938)
			(xy 107.038453 -423.559044) (xy 107.053467 -423.61078) (xy 107.061046 -423.664115) (xy 107.061508 -423.69105)
			(xy 107.061022 -423.718301) (xy 107.053266 -423.772249) (xy 107.037911 -423.824544) (xy 107.015269 -423.874121)
			(xy 106.985803 -423.919971) (xy 106.950112 -423.961162) (xy 106.908921 -423.996853) (xy 106.863071 -424.026319)
			(xy 106.813494 -424.048961) (xy 106.761199 -424.064316) (xy 106.707251 -424.072072) (xy 106.652749 -424.072072)
			(xy 106.598801 -424.064316) (xy 106.546506 -424.048961) (xy 106.496929 -424.026319) (xy 106.451079 -423.996853)
			(xy 106.409888 -423.961162) (xy 106.374197 -423.919971) (xy 106.344731 -423.874121) (xy 106.322089 -423.824544)
			(xy 106.306734 -423.772249) (xy 106.298978 -423.718301) (xy 106.298492 -423.69105) (xy 106.298954 -423.664116)
			(xy 106.306542 -423.610784) (xy 106.321561 -423.559051) (xy 106.343712 -423.509946) (xy 106.372553 -423.464448)
			(xy 106.389678 -423.443654) (xy 106.396536 -423.435526) (xy 106.402632 -423.415968) (xy 106.392218 -423.320972)
			(xy 106.382058 -423.303192) (xy 106.373422 -423.296588) (xy 106.346964 -423.275936) (xy 106.299197 -423.228783)
			(xy 106.258052 -423.175754) (xy 106.224244 -423.117771) (xy 106.198362 -423.055842) (xy 106.180855 -422.991046)
			(xy 106.172028 -422.92451) (xy 106.171492 -422.89095) (xy 103.037872 -422.89095) (xy 103.060474 -422.948033)
			(xy 103.076371 -423.009947) (xy 103.084382 -423.073365) (xy 103.084884 -423.105326) (xy 103.084382 -423.137287)
			(xy 103.076371 -423.200705) (xy 103.060474 -423.262619) (xy 103.036942 -423.322052) (xy 103.006148 -423.378067)
			(xy 102.972522 -423.42435) (xy 103.503982 -423.42435) (xy 103.508053 -423.368728) (xy 103.520179 -423.314291)
			(xy 103.540102 -423.2622) (xy 103.567398 -423.213565) (xy 103.601484 -423.169422) (xy 103.641633 -423.130713)
			(xy 103.686991 -423.098262) (xy 103.736591 -423.072761) (xy 103.789375 -423.054754) (xy 103.844218 -423.044624)
			(xy 103.899952 -423.042587) (xy 103.955389 -423.048687) (xy 104.009346 -423.062793) (xy 104.060675 -423.084605)
			(xy 104.108281 -423.113659) (xy 104.151149 -423.149334) (xy 104.188366 -423.190871) (xy 104.219139 -423.237384)
			(xy 104.242811 -423.287881) (xy 104.258879 -423.341288) (xy 104.266999 -423.396464) (xy 104.267508 -423.42435)
			(xy 104.266999 -423.452236) (xy 104.258879 -423.507412) (xy 104.242811 -423.560819) (xy 104.219139 -423.611316)
			(xy 104.188366 -423.657829) (xy 104.151149 -423.699366) (xy 104.108281 -423.735041) (xy 104.060675 -423.764095)
			(xy 104.009346 -423.785907) (xy 103.955389 -423.800013) (xy 103.899952 -423.806113) (xy 103.844218 -423.804076)
			(xy 103.789375 -423.793946) (xy 103.736591 -423.775939) (xy 103.686991 -423.750438) (xy 103.641633 -423.717987)
			(xy 103.601484 -423.679278) (xy 103.567398 -423.635135) (xy 103.540102 -423.5865) (xy 103.520179 -423.534409)
			(xy 103.508053 -423.479972) (xy 103.503982 -423.42435) (xy 102.972522 -423.42435) (xy 102.968575 -423.429782)
			(xy 102.924818 -423.476379) (xy 102.875565 -423.517124) (xy 102.821594 -423.551375) (xy 102.763755 -423.578592)
			(xy 102.702962 -423.598345) (xy 102.640172 -423.610323) (xy 102.576376 -423.614337) (xy 102.51258 -423.610323)
			(xy 102.44979 -423.598345) (xy 102.388997 -423.578592) (xy 102.331158 -423.551375) (xy 102.277187 -423.517124)
			(xy 102.227934 -423.476379) (xy 102.184177 -423.429782) (xy 102.146604 -423.378067) (xy 102.11581 -423.322052)
			(xy 102.092278 -423.262619) (xy 102.076381 -423.200705) (xy 102.06837 -423.137287) (xy 101.776754 -423.137287)
			(xy 101.777577 -423.137789) (xy 101.820445 -423.173464) (xy 101.857662 -423.215001) (xy 101.888435 -423.261514)
			(xy 101.912107 -423.312011) (xy 101.928175 -423.365418) (xy 101.936295 -423.420594) (xy 101.936804 -423.44848)
			(xy 101.936295 -423.476366) (xy 101.928175 -423.531542) (xy 101.912107 -423.584949) (xy 101.888435 -423.635446)
			(xy 101.857662 -423.681959) (xy 101.820445 -423.723496) (xy 101.777577 -423.759171) (xy 101.729971 -423.788225)
			(xy 101.678642 -423.810037) (xy 101.624685 -423.824143) (xy 101.569248 -423.830243) (xy 101.513514 -423.828206)
			(xy 101.458671 -423.818076) (xy 101.405887 -423.800069) (xy 101.356287 -423.774568) (xy 101.310929 -423.742117)
			(xy 101.27078 -423.703408) (xy 101.236694 -423.659265) (xy 101.209398 -423.61063) (xy 101.189475 -423.558539)
			(xy 101.177349 -423.504102) (xy 101.173278 -423.44848) (xy 100.666804 -423.44848) (xy 100.666295 -423.476366)
			(xy 100.658175 -423.531542) (xy 100.642107 -423.584949) (xy 100.618435 -423.635446) (xy 100.587662 -423.681959)
			(xy 100.550445 -423.723496) (xy 100.507577 -423.759171) (xy 100.459971 -423.788225) (xy 100.408642 -423.810037)
			(xy 100.354685 -423.824143) (xy 100.299248 -423.830243) (xy 100.243514 -423.828206) (xy 100.188671 -423.818076)
			(xy 100.135887 -423.800069) (xy 100.086287 -423.774568) (xy 100.040929 -423.742117) (xy 100.00078 -423.703408)
			(xy 99.966694 -423.659265) (xy 99.939398 -423.61063) (xy 99.919475 -423.558539) (xy 99.907349 -423.504102)
			(xy 99.903278 -423.44848) (xy 99.396804 -423.44848) (xy 99.396295 -423.476366) (xy 99.388175 -423.531542)
			(xy 99.372107 -423.584949) (xy 99.348435 -423.635446) (xy 99.317662 -423.681959) (xy 99.280445 -423.723496)
			(xy 99.237577 -423.759171) (xy 99.189971 -423.788225) (xy 99.138642 -423.810037) (xy 99.084685 -423.824143)
			(xy 99.029248 -423.830243) (xy 98.973514 -423.828206) (xy 98.918671 -423.818076) (xy 98.865887 -423.800069)
			(xy 98.816287 -423.774568) (xy 98.770929 -423.742117) (xy 98.73078 -423.703408) (xy 98.696694 -423.659265)
			(xy 98.669398 -423.61063) (xy 98.649475 -423.558539) (xy 98.637349 -423.504102) (xy 98.633278 -423.44848)
			(xy 98.298858 -423.44848) (xy 98.299016 -423.457116) (xy 98.298507 -423.485002) (xy 98.290387 -423.540178)
			(xy 98.274319 -423.593585) (xy 98.250647 -423.644082) (xy 98.219874 -423.690595) (xy 98.182657 -423.732132)
			(xy 98.139789 -423.767807) (xy 98.092183 -423.796861) (xy 98.040854 -423.818673) (xy 97.986897 -423.832779)
			(xy 97.93146 -423.838879) (xy 97.875726 -423.836842) (xy 97.820883 -423.826712) (xy 97.768099 -423.808705)
			(xy 97.718499 -423.783204) (xy 97.673141 -423.750753) (xy 97.632992 -423.712044) (xy 97.598906 -423.667901)
			(xy 97.57161 -423.619266) (xy 97.551687 -423.567175) (xy 97.539561 -423.512738) (xy 97.53549 -423.457116)
			(xy 95.926148 -423.457116) (xy 95.926148 -423.893742) (xy 95.92658 -423.903808) (xy 95.934311 -423.922397)
			(xy 95.941134 -423.92981) (xy 96.01454 -424.003216) (xy 96.023062 -424.010788) (xy 96.044556 -424.01829)
			(xy 96.055942 -424.017694) (xy 96.146112 -424.008042) (xy 96.16567 -423.99585) (xy 96.17202 -423.986198)
			(xy 96.187115 -423.963433) (xy 96.222786 -423.922068) (xy 96.263995 -423.886216) (xy 96.309899 -423.856613)
			(xy 96.359559 -423.833865) (xy 96.411956 -423.818438) (xy 96.466019 -423.810646) (xy 96.49333 -423.810176)
			(xy 96.52058 -423.810664) (xy 96.574526 -423.818424) (xy 96.626818 -423.833781) (xy 96.676392 -423.856424)
			(xy 96.72224 -423.885891) (xy 96.763428 -423.921582) (xy 96.799118 -423.962771) (xy 96.828583 -424.00862)
			(xy 96.851224 -424.058195) (xy 96.866579 -424.110488) (xy 96.874337 -424.164434) (xy 96.874838 -424.191684)
			(xy 96.874371 -424.218995) (xy 96.866578 -424.273058) (xy 96.851149 -424.325455) (xy 96.8284 -424.375114)
			(xy 96.798797 -424.421017) (xy 96.762945 -424.462227) (xy 96.72158 -424.497897) (xy 96.698816 -424.512994)
			(xy 96.689164 -424.519344) (xy 96.676972 -424.538902) (xy 96.66732 -424.629072) (xy 96.666679 -424.640462)
			(xy 96.674195 -424.661969) (xy 96.681798 -424.670474) (xy 96.746822 -424.735498) (xy 96.754222 -424.742341)
			(xy 96.77282 -424.750068) (xy 96.78289 -424.750484) (xy 105.007918 -424.750484)
		)
		(stroke
			(width 0)
			(type solid)
		)
		(fill yes)
		(layer "In11.Cu")
		(net "P1V8_CPU1_RT_1D")
	)
	(gr_poly
		(pts
			(xy 357.669846 -407.44394) (xy 357.676798 -407.443703) (xy 357.690192 -407.43997) (xy 357.696262 -407.436574)
			(xy 357.722749 -407.421164) (xy 357.778667 -407.396094) (xy 357.837191 -407.377924) (xy 357.897475 -407.366915)
			(xy 357.958644 -407.363228) (xy 358.019813 -407.366915) (xy 358.080097 -407.377924) (xy 358.138621 -407.396094)
			(xy 358.194539 -407.421164) (xy 358.221026 -407.436574) (xy 358.227122 -407.440384) (xy 358.24033 -407.44394)
			(xy 358.285288 -407.44394) (xy 358.294779 -407.443545) (xy 358.312468 -407.436655) (xy 358.326473 -407.423838)
			(xy 358.331008 -407.415492) (xy 358.37749 -407.320242) (xy 358.374442 -407.29154) (xy 358.365552 -407.279856)
			(xy 358.345285 -407.252974) (xy 358.311263 -407.194881) (xy 358.28521 -407.132803) (xy 358.267582 -407.06783)
			(xy 358.258688 -407.001097) (xy 358.25811 -406.967436) (xy 358.258612 -406.935475) (xy 358.266623 -406.872057)
			(xy 358.28252 -406.810143) (xy 358.306052 -406.75071) (xy 358.336846 -406.694695) (xy 358.374419 -406.64298)
			(xy 358.418176 -406.596383) (xy 358.467429 -406.555638) (xy 358.5214 -406.521387) (xy 358.579239 -406.49417)
			(xy 358.640032 -406.474417) (xy 358.702822 -406.462439) (xy 358.766618 -406.458426) (xy 358.830414 -406.462439)
			(xy 358.893204 -406.474417) (xy 358.953997 -406.49417) (xy 359.011836 -406.521387) (xy 359.065807 -406.555638)
			(xy 359.11506 -406.596383) (xy 359.158817 -406.64298) (xy 359.19639 -406.694695) (xy 359.227184 -406.75071)
			(xy 359.250716 -406.810143) (xy 359.266613 -406.872057) (xy 359.274624 -406.935475) (xy 359.275126 -406.967436)
			(xy 359.27456 -407.001096) (xy 359.265639 -407.067822) (xy 359.247996 -407.132789) (xy 359.221941 -407.194862)
			(xy 359.187927 -407.252957) (xy 359.167684 -407.279856) (xy 359.158794 -407.29154) (xy 359.155746 -407.320242)
			(xy 359.202228 -407.415492) (xy 359.206748 -407.423853) (xy 359.220736 -407.436699) (xy 359.23845 -407.443549)
			(xy 359.247948 -407.44394) (xy 360.096054 -407.44394) (xy 360.108601 -407.443284) (xy 360.130707 -407.431409)
			(xy 360.138218 -407.421334) (xy 360.192066 -407.340054) (xy 360.194606 -407.314654) (xy 360.189526 -407.30297)
			(xy 360.176907 -407.27157) (xy 360.159144 -407.206271) (xy 360.150193 -407.139194) (xy 360.149648 -407.105358)
			(xy 360.150104 -407.074499) (xy 360.157583 -407.013236) (xy 360.172425 -406.95333) (xy 360.194412 -406.895662)
			(xy 360.22322 -406.84108) (xy 360.258426 -406.790389) (xy 360.299511 -406.744334) (xy 360.322368 -406.723596)
			(xy 360.331004 -406.715976) (xy 360.339894 -406.695402) (xy 360.3371 -406.594564) (xy 360.32694 -406.574244)
			(xy 360.31805 -406.567386) (xy 360.292487 -406.546668) (xy 360.246393 -406.49971) (xy 360.206743 -406.447198)
			(xy 360.174198 -406.390009) (xy 360.149304 -406.3291) (xy 360.132476 -406.265488) (xy 360.123995 -406.200236)
			(xy 360.123486 -406.167336) (xy 360.123988 -406.135375) (xy 360.131999 -406.071957) (xy 360.147896 -406.010043)
			(xy 360.171428 -405.95061) (xy 360.202222 -405.894595) (xy 360.239795 -405.84288) (xy 360.283552 -405.796283)
			(xy 360.332805 -405.755538) (xy 360.386776 -405.721287) (xy 360.444615 -405.69407) (xy 360.505408 -405.674317)
			(xy 360.568198 -405.662339) (xy 360.631994 -405.658326) (xy 360.69579 -405.662339) (xy 360.75858 -405.674317)
			(xy 360.819373 -405.69407) (xy 360.877212 -405.721287) (xy 360.931183 -405.755538) (xy 360.980436 -405.796283)
			(xy 361.024193 -405.84288) (xy 361.061766 -405.894595) (xy 361.09256 -405.95061) (xy 361.116092 -406.010043)
			(xy 361.131989 -406.071957) (xy 361.14 -406.135375) (xy 361.140502 -406.167336) (xy 361.140046 -406.198195)
			(xy 361.132569 -406.259459) (xy 361.117728 -406.319367) (xy 361.095743 -406.377037) (xy 361.066937 -406.431621)
			(xy 361.031734 -406.482315) (xy 360.990652 -406.528374) (xy 360.967782 -406.549098) (xy 360.959146 -406.556718)
			(xy 360.950256 -406.577292) (xy 360.95305 -406.67813) (xy 360.96321 -406.69845) (xy 360.9721 -406.705308)
			(xy 360.981752 -406.713182) (xy 361.037378 -406.697942) (xy 361.048187 -406.694385) (xy 361.065461 -406.67962)
			(xy 361.070652 -406.669494) (xy 361.082176 -406.644373) (xy 361.111399 -406.597464) (xy 361.147086 -406.555263)
			(xy 361.188487 -406.518652) (xy 361.234738 -406.488397) (xy 361.28487 -406.465133) (xy 361.337834 -406.449345)
			(xy 361.392522 -406.441365) (xy 361.420156 -406.440894) (xy 361.447411 -406.441354) (xy 361.501366 -406.449106)
			(xy 361.553669 -406.464458) (xy 361.603254 -406.487098) (xy 361.649113 -406.516565) (xy 361.661157 -406.527)
			(xy 366.77499 -406.527) (xy 366.779003 -406.463204) (xy 366.790981 -406.400414) (xy 366.810734 -406.339621)
			(xy 366.837951 -406.281782) (xy 366.872202 -406.227811) (xy 366.912947 -406.178558) (xy 366.959544 -406.134801)
			(xy 367.011259 -406.097228) (xy 367.067274 -406.066434) (xy 367.126707 -406.042902) (xy 367.188621 -406.027005)
			(xy 367.252039 -406.018994) (xy 367.284 -406.018492) (xy 367.317718 -406.01904) (xy 367.384563 -406.027941)
			(xy 367.449644 -406.045602) (xy 367.51182 -406.071712) (xy 367.569998 -406.105812) (xy 367.623157 -406.147304)
			(xy 367.670364 -406.19546) (xy 367.710791 -406.249434) (xy 367.727738 -406.278588) (xy 367.73228 -406.286068)
			(xy 367.7454 -406.297629) (xy 367.753392 -406.301194) (xy 367.781332 -406.312116) (xy 367.789431 -406.314953)
			(xy 367.806569 -406.315602) (xy 367.81486 -406.313386) (xy 367.84028 -406.306127) (xy 367.892568 -406.298352)
			(xy 367.919 -406.297892) (xy 367.946967 -406.298405) (xy 368.002209 -406.307187) (xy 368.055396 -406.324504)
			(xy 368.080544 -406.336754) (xy 368.08815 -406.340303) (xy 368.104764 -406.342631) (xy 368.113056 -406.341326)
			(xy 368.142012 -406.335992) (xy 368.150328 -406.334126) (xy 368.165125 -406.325688) (xy 368.170968 -406.319482)
			(xy 368.191682 -406.296427) (xy 368.237836 -406.255056) (xy 368.288675 -406.219599) (xy 368.343445 -406.190581)
			(xy 368.401334 -406.168433) (xy 368.461486 -406.153483) (xy 368.523009 -406.145952) (xy 368.554 -406.145492)
			(xy 368.585961 -406.145994) (xy 368.649379 -406.154005) (xy 368.711293 -406.169902) (xy 368.770726 -406.193434)
			(xy 368.826741 -406.224228) (xy 368.878456 -406.261801) (xy 368.925053 -406.305558) (xy 368.965798 -406.354811)
			(xy 369.000049 -406.408782) (xy 369.027266 -406.466621) (xy 369.047019 -406.527414) (xy 369.058997 -406.590204)
			(xy 369.063011 -406.654) (xy 369.058997 -406.717796) (xy 369.047019 -406.780586) (xy 369.027266 -406.841379)
			(xy 369.000049 -406.899218) (xy 368.965798 -406.953189) (xy 368.925053 -407.002442) (xy 368.878456 -407.046199)
			(xy 368.826741 -407.083772) (xy 368.770726 -407.114566) (xy 368.711293 -407.138098) (xy 368.649379 -407.153995)
			(xy 368.585961 -407.162006) (xy 368.554 -407.162508) (xy 368.523008 -407.16208) (xy 368.461482 -407.154555)
			(xy 368.401327 -407.139605) (xy 368.343437 -407.117452) (xy 368.28867 -407.088423) (xy 368.237839 -407.052951)
			(xy 368.191699 -407.011561) (xy 368.170968 -406.988518) (xy 368.165107 -406.982336) (xy 368.150319 -406.973897)
			(xy 368.142012 -406.972008) (xy 368.113056 -406.966674) (xy 368.104764 -406.965464) (xy 368.088179 -406.967793)
			(xy 368.080544 -406.971246) (xy 368.05538 -406.983455) (xy 368.002197 -407.000756) (xy 367.946963 -407.009538)
			(xy 367.919 -407.010108) (xy 367.894366 -407.009694) (xy 367.845569 -407.002902) (xy 367.798174 -406.989449)
			(xy 367.753086 -406.969591) (xy 367.711166 -406.943707) (xy 367.691924 -406.92832) (xy 367.685088 -406.923123)
			(xy 367.669 -406.917147) (xy 367.660428 -406.916636) (xy 367.630456 -406.916128) (xy 367.621765 -406.916305)
			(xy 367.605269 -406.921742) (xy 367.598198 -406.926796) (xy 367.571204 -406.947283) (xy 367.512841 -406.981719)
			(xy 367.45042 -407.008095) (xy 367.385047 -407.025944) (xy 367.317883 -407.034948) (xy 367.284 -407.035508)
			(xy 367.252039 -407.035006) (xy 367.188621 -407.026995) (xy 367.126707 -407.011098) (xy 367.067274 -406.987566)
			(xy 367.011259 -406.956772) (xy 366.959544 -406.919199) (xy 366.912947 -406.875442) (xy 366.872202 -406.826189)
			(xy 366.837951 -406.772218) (xy 366.810734 -406.714379) (xy 366.790981 -406.653586) (xy 366.779003 -406.590796)
			(xy 366.77499 -406.527) (xy 361.661157 -406.527) (xy 361.690311 -406.552258) (xy 361.726009 -406.593452)
			(xy 361.755481 -406.639307) (xy 361.778126 -406.68889) (xy 361.793484 -406.741191) (xy 361.801243 -406.795145)
			(xy 361.801243 -406.849655) (xy 361.793484 -406.903609) (xy 361.778126 -406.95591) (xy 361.755481 -407.005493)
			(xy 361.726009 -407.051348) (xy 361.690311 -407.092542) (xy 361.649113 -407.128235) (xy 361.603254 -407.157702)
			(xy 361.553669 -407.180342) (xy 361.501366 -407.195694) (xy 361.447411 -407.203446) (xy 361.420156 -407.20391)
			(xy 361.39654 -407.203572) (xy 361.349666 -407.19777) (xy 361.303868 -407.186223) (xy 361.281726 -407.178002)
			(xy 361.27182 -407.173938) (xy 361.250484 -407.174954) (xy 361.16387 -407.21788) (xy 361.150154 -407.23439)
			(xy 361.147106 -407.244804) (xy 361.142797 -407.259604) (xy 361.132628 -407.288706) (xy 361.126786 -407.30297)
			(xy 361.121706 -407.314654) (xy 361.124246 -407.340054) (xy 361.178094 -407.421334) (xy 361.185609 -407.431398)
			(xy 361.207717 -407.44326) (xy 361.220258 -407.44394) (xy 362.37926 -407.44394) (xy 362.389166 -407.439622)
			(xy 362.413761 -407.429106) (xy 362.465159 -407.414291) (xy 362.518123 -407.406808) (xy 362.544868 -407.406348)
			(xy 392.76528 -407.406348) (xy 392.775294 -407.405864) (xy 392.793801 -407.39821) (xy 392.807972 -407.384058)
			(xy 392.815651 -407.365561) (xy 392.81608 -407.355548) (xy 392.81608 -402.743162) (xy 392.816509 -402.733094)
			(xy 392.824231 -402.714498) (xy 392.831066 -402.707094) (xy 392.955272 -402.582888) (xy 392.9622 -402.575211)
			(xy 392.969805 -402.556) (xy 392.969262 -402.535346) (xy 392.965432 -402.525738) (xy 392.918696 -402.424392)
			(xy 392.891264 -402.408644) (xy 392.875262 -402.409914) (xy 392.834622 -402.411438) (xy 392.803889 -402.410975)
			(xy 392.742872 -402.403569) (xy 392.683193 -402.388862) (xy 392.625721 -402.367069) (xy 392.571295 -402.338508)
			(xy 392.520709 -402.303594) (xy 392.474699 -402.262838) (xy 392.433938 -402.216832) (xy 392.399019 -402.16625)
			(xy 392.370452 -402.111827) (xy 392.348653 -402.054357) (xy 392.33394 -401.994679) (xy 392.326528 -401.933662)
			(xy 392.326114 -401.90293) (xy 392.326597 -401.872236) (xy 392.334025 -401.811299) (xy 392.348729 -401.751697)
			(xy 392.370495 -401.694297) (xy 392.399007 -401.639931) (xy 392.41603 -401.614386) (xy 392.421506 -401.605633)
			(xy 392.425643 -401.585425) (xy 392.421525 -401.565213) (xy 392.41603 -401.556474) (xy 392.398976 -401.530947)
			(xy 392.37045 -401.476584) (xy 392.348682 -401.41918) (xy 392.33399 -401.359571) (xy 392.326589 -401.298626)
			(xy 392.326114 -401.26793) (xy 392.326558 -401.237197) (xy 392.333964 -401.176179) (xy 392.348671 -401.116499)
			(xy 392.370465 -401.059027) (xy 392.399028 -401.004601) (xy 392.433943 -400.954016) (xy 392.474702 -400.908007)
			(xy 392.520709 -400.867248) (xy 392.571295 -400.832332) (xy 392.62572 -400.803768) (xy 392.683192 -400.781973)
			(xy 392.742872 -400.767265) (xy 392.803889 -400.759858) (xy 392.834622 -400.759422) (xy 392.865317 -400.759902)
			(xy 392.926256 -400.767325) (xy 392.985861 -400.782024) (xy 393.043264 -400.803786) (xy 393.097633 -400.832295)
			(xy 393.123166 -400.849338) (xy 393.131918 -400.854809) (xy 393.152122 -400.858937) (xy 393.172326 -400.854809)
			(xy 393.181078 -400.849338) (xy 393.206605 -400.832281) (xy 393.260966 -400.803749) (xy 393.31837 -400.781976)
			(xy 393.377979 -400.767278) (xy 393.438925 -400.759871) (xy 393.469622 -400.759422) (xy 393.500317 -400.759902)
			(xy 393.561256 -400.767325) (xy 393.620861 -400.782024) (xy 393.678264 -400.803786) (xy 393.732633 -400.832295)
			(xy 393.758166 -400.849338) (xy 393.766918 -400.854809) (xy 393.787122 -400.858937) (xy 393.807326 -400.854809)
			(xy 393.816078 -400.849338) (xy 393.841605 -400.832281) (xy 393.895966 -400.803749) (xy 393.95337 -400.781976)
			(xy 394.012979 -400.767278) (xy 394.073925 -400.759871) (xy 394.104622 -400.759422) (xy 394.125704 -400.75993)
			(xy 394.136626 -400.760438) (xy 394.156184 -400.752818) (xy 394.22451 -400.684492) (xy 394.23213 -400.664934)
			(xy 394.231622 -400.654012) (xy 394.231114 -400.63293) (xy 394.231597 -400.602236) (xy 394.239025 -400.541299)
			(xy 394.253729 -400.481697) (xy 394.275495 -400.424297) (xy 394.304007 -400.369931) (xy 394.32103 -400.344386)
			(xy 394.326506 -400.335633) (xy 394.330643 -400.315425) (xy 394.326525 -400.295213) (xy 394.32103 -400.286474)
			(xy 394.303976 -400.260947) (xy 394.27545 -400.206584) (xy 394.253682 -400.14918) (xy 394.23899 -400.089571)
			(xy 394.231589 -400.028626) (xy 394.231114 -399.99793) (xy 394.231652 -399.964702) (xy 394.240306 -399.898812)
			(xy 394.25747 -399.83461) (xy 394.282851 -399.773192) (xy 394.316018 -399.715604) (xy 394.356404 -399.662827)
			(xy 394.403322 -399.615761) (xy 394.455971 -399.575209) (xy 394.513454 -399.541861) (xy 394.574792 -399.516287)
			(xy 394.638939 -399.498921) (xy 394.671804 -399.493994) (xy 394.683234 -399.49247) (xy 394.701776 -399.480532)
			(xy 394.755624 -399.395188) (xy 394.758418 -399.373344) (xy 394.754862 -399.362422) (xy 394.74357 -399.324622)
			(xy 394.731444 -399.246672) (xy 394.730732 -399.207228) (xy 394.731176 -399.176496) (xy 394.738582 -399.115479)
			(xy 394.753289 -399.0558) (xy 394.775084 -398.998329) (xy 394.803647 -398.943904) (xy 394.838563 -398.89332)
			(xy 394.879322 -398.847313) (xy 394.925329 -398.806555) (xy 394.975915 -398.771641) (xy 395.03034 -398.743079)
			(xy 395.087811 -398.721286) (xy 395.147491 -398.70658) (xy 395.208508 -398.699175) (xy 395.23924 -398.69872)
			(xy 395.269934 -398.699201) (xy 395.330873 -398.706626) (xy 395.390476 -398.721327) (xy 395.447879 -398.74309)
			(xy 395.502246 -398.7716) (xy 395.527784 -398.788636) (xy 395.536536 -398.794107) (xy 395.55674 -398.798235)
			(xy 395.576944 -398.794107) (xy 395.585696 -398.788636) (xy 395.611223 -398.77158) (xy 395.665585 -398.74305)
			(xy 395.722989 -398.721279) (xy 395.782598 -398.706584) (xy 395.843543 -398.699178) (xy 395.87424 -398.69872)
			(xy 395.906928 -398.699221) (xy 395.971766 -398.707591) (xy 396.034997 -398.7242) (xy 396.095578 -398.748775)
			(xy 396.15251 -398.780911) (xy 396.204855 -398.820077) (xy 396.25175 -398.865627) (xy 396.292421 -398.916812)
			(xy 396.326198 -398.972786) (xy 396.339822 -399.002504) (xy 396.344902 -399.014442) (xy 396.364206 -399.029682)
			(xy 396.459202 -399.047462) (xy 396.471572 -399.049223) (xy 396.495427 -399.0419) (xy 396.504668 -399.033492)
			(xy 396.567152 -398.971008) (xy 396.57457 -398.962726) (xy 396.582143 -398.941848) (xy 396.580295 -398.919715)
			(xy 396.57528 -398.909794) (xy 396.563138 -398.887997) (xy 396.544034 -398.841903) (xy 396.531114 -398.79371)
			(xy 396.524598 -398.744242) (xy 396.524226 -398.719294) (xy 396.52469 -398.692042) (xy 396.532448 -398.638094)
			(xy 396.547805 -398.585799) (xy 396.570448 -398.536221) (xy 396.599917 -398.490372) (xy 396.635611 -398.449182)
			(xy 396.676804 -398.413493) (xy 396.722657 -398.384029) (xy 396.772236 -398.361391) (xy 396.824533 -398.346039)
			(xy 396.878482 -398.338287) (xy 396.905734 -398.337786) (xy 396.930678 -398.338212) (xy 396.980137 -398.344744)
			(xy 397.028326 -398.357654) (xy 397.074427 -398.376723) (xy 397.096234 -398.38884) (xy 397.106151 -398.39392)
			(xy 397.128321 -398.395859) (xy 397.149226 -398.388228) (xy 397.157448 -398.380712) (xy 400.289014 -395.249146)
			(xy 400.295861 -395.241749) (xy 400.303589 -395.223149) (xy 400.304 -395.213078) (xy 400.304 -395.090142)
			(xy 400.30146 -395.078966) (xy 400.298666 -395.073632) (xy 400.283855 -395.042007) (xy 400.262922 -394.975387)
			(xy 400.252336 -394.906364) (xy 400.251676 -394.871448) (xy 400.252311 -394.83653) (xy 400.262883 -394.7675)
			(xy 400.283833 -394.700881) (xy 400.298666 -394.669264) (xy 400.301129 -394.663939) (xy 400.303825 -394.652523)
			(xy 400.304 -394.646658) (xy 400.304 -394.349478) (xy 400.30349 -394.339301) (xy 400.295491 -394.320577)
			(xy 400.288506 -394.313156) (xy 400.269127 -394.29372) (xy 400.234665 -394.251) (xy 400.205554 -394.204469)
			(xy 400.19351 -394.179806) (xy 400.187414 -394.167106) (xy 400.164554 -394.151612) (xy 400.047714 -394.144246)
			(xy 400.02333 -394.156692) (xy 400.01571 -394.16863) (xy 400.000622 -394.191509) (xy 399.964927 -394.233096)
			(xy 399.923649 -394.269148) (xy 399.877638 -394.298924) (xy 399.827841 -394.32181) (xy 399.775281 -394.337336)
			(xy 399.72104 -394.345183) (xy 399.693638 -394.345668) (xy 399.666386 -394.345207) (xy 399.612437 -394.337456)
			(xy 399.56014 -394.322104) (xy 399.51056 -394.299467) (xy 399.464707 -394.270003) (xy 399.423514 -394.234313)
			(xy 399.38782 -394.193123) (xy 399.358352 -394.147273) (xy 399.335709 -394.097696) (xy 399.320352 -394.0454)
			(xy 399.312595 -393.991452) (xy 399.312595 -393.936948) (xy 399.320352 -393.883) (xy 399.335709 -393.830704)
			(xy 399.358352 -393.781127) (xy 399.38782 -393.735277) (xy 399.423514 -393.694087) (xy 399.464707 -393.658397)
			(xy 399.51056 -393.628934) (xy 399.56014 -393.606296) (xy 399.612437 -393.590944) (xy 399.666386 -393.583193)
			(xy 399.693638 -393.582652) (xy 399.722275 -393.583161) (xy 399.778905 -393.591714) (xy 399.833621 -393.608638)
			(xy 399.885191 -393.633551) (xy 399.932457 -393.665895) (xy 399.974357 -393.704942) (xy 400.009948 -393.749813)
			(xy 400.0246 -393.774422) (xy 400.031712 -393.786614) (xy 400.055588 -393.80033) (xy 400.172682 -393.798044)
			(xy 400.19605 -393.78382) (xy 400.202654 -393.771374) (xy 400.220015 -393.739761) (xy 400.263146 -393.681958)
			(xy 400.288506 -393.656312) (xy 400.295519 -393.648913) (xy 400.303502 -393.630173) (xy 400.304 -393.61999)
			(xy 400.304 -393.185142) (xy 400.304434 -393.175077) (xy 400.312163 -393.156487) (xy 400.318986 -393.149074)
			(xy 400.580606 -392.887454) (xy 400.587718 -392.8618) (xy 400.584416 -392.848846) (xy 400.578206 -392.821906)
			(xy 400.571583 -392.767016) (xy 400.571208 -392.739372) (xy 400.5717 -392.709406) (xy 400.579526 -392.649987)
			(xy 400.595041 -392.592098) (xy 400.617979 -392.536729) (xy 400.647948 -392.484828) (xy 400.684435 -392.437282)
			(xy 400.726815 -392.394906) (xy 400.774364 -392.358423) (xy 400.826268 -392.32846) (xy 400.881639 -392.305527)
			(xy 400.93953 -392.290017) (xy 400.99895 -392.282197) (xy 401.028916 -392.281664) (xy 401.056558 -392.282067)
			(xy 401.111445 -392.288691) (xy 401.13839 -392.294872) (xy 401.151344 -392.298174) (xy 401.176998 -392.291062)
			(xy 401.724114 -391.743946) (xy 401.731511 -391.737097) (xy 401.75011 -391.72936) (xy 401.760182 -391.72896)
			(xy 420.651178 -391.72896) (xy 420.661241 -391.729399) (xy 420.679819 -391.73714) (xy 420.687246 -391.743946)
			(xy 421.294814 -392.351514) (xy 421.301668 -392.358909) (xy 421.30941 -392.377508) (xy 421.3098 -392.387582)
			(xy 421.3098 -392.730736) (xy 421.310281 -392.740701) (xy 421.317861 -392.759133) (xy 421.324532 -392.76655)
			(xy 421.342447 -392.785256) (xy 421.372816 -392.82721) (xy 421.396265 -392.873391) (xy 421.412217 -392.922665)
			(xy 421.420282 -392.973826) (xy 421.420798 -392.999722) (xy 421.420273 -393.026824) (xy 421.41146 -393.080307)
			(xy 421.403272 -393.106148) (xy 421.399462 -393.11707) (xy 421.402002 -393.139422) (xy 421.45458 -393.225274)
			(xy 421.47363 -393.23772) (xy 421.484806 -393.239498) (xy 421.514113 -393.244238) (xy 421.571265 -393.260309)
			(xy 421.62586 -393.283633) (xy 421.676981 -393.31382) (xy 421.72377 -393.350362) (xy 421.765443 -393.392647)
			(xy 421.8013 -393.439964) (xy 421.830738 -393.491519) (xy 421.847071 -393.531344) (xy 422.930066 -393.531344)
			(xy 422.930502 -393.502709) (xy 422.937657 -393.445887) (xy 422.951838 -393.3904) (xy 422.972822 -393.337112)
			(xy 423.000283 -393.286854) (xy 423.01668 -393.263374) (xy 423.022354 -393.254856) (xy 423.02696 -393.23493)
			(xy 423.023396 -393.214792) (xy 423.018204 -393.20597) (xy 423.000721 -393.17799) (xy 422.97309 -393.118078)
			(xy 422.954343 -393.054822) (xy 422.944869 -392.98953) (xy 422.94429 -392.956542) (xy 422.9448 -392.926574)
			(xy 422.952619 -392.86715) (xy 422.968127 -392.809255) (xy 422.991059 -392.75388) (xy 423.021024 -392.701972)
			(xy 423.057508 -392.65442) (xy 423.099887 -392.612037) (xy 423.147436 -392.575548) (xy 423.199341 -392.545579)
			(xy 423.254714 -392.522641) (xy 423.312607 -392.507127) (xy 423.37203 -392.499303) (xy 423.401998 -392.498834)
			(xy 423.43181 -392.499299) (xy 423.490929 -392.507036) (xy 423.548544 -392.52238) (xy 423.603681 -392.545071)
			(xy 423.655407 -392.574725) (xy 423.702847 -392.610842) (xy 423.745199 -392.652809) (xy 423.781746 -392.699917)
			(xy 423.797222 -392.725402) (xy 423.804334 -392.737848) (xy 423.82948 -392.75131) (xy 423.948352 -392.744706)
			(xy 423.971974 -392.72845) (xy 423.977562 -392.715242) (xy 423.99122 -392.685623) (xy 424.025068 -392.629869)
			(xy 424.065764 -392.578897) (xy 424.112641 -392.533545) (xy 424.16493 -392.494556) (xy 424.221773 -392.462569)
			(xy 424.282238 -392.43811) (xy 424.345333 -392.421579) (xy 424.410024 -392.413247) (xy 424.442636 -392.412728)
			(xy 424.473369 -392.413122) (xy 424.534387 -392.420535) (xy 424.594066 -392.435249) (xy 424.651537 -392.45705)
			(xy 424.693394 -392.479022) (xy 430.282348 -392.479022) (xy 430.286419 -392.4234) (xy 430.298545 -392.368963)
			(xy 430.318468 -392.316872) (xy 430.345764 -392.268237) (xy 430.37985 -392.224094) (xy 430.419999 -392.185385)
			(xy 430.465357 -392.152934) (xy 430.514957 -392.127433) (xy 430.567741 -392.109426) (xy 430.622584 -392.099296)
			(xy 430.678318 -392.097259) (xy 430.733755 -392.103359) (xy 430.787712 -392.117465) (xy 430.839041 -392.139277)
			(xy 430.886647 -392.168331) (xy 430.929515 -392.204006) (xy 430.966732 -392.245543) (xy 430.997505 -392.292056)
			(xy 431.021177 -392.342553) (xy 431.037245 -392.39596) (xy 431.045365 -392.451136) (xy 431.045874 -392.479022)
			(xy 431.045365 -392.506908) (xy 431.037245 -392.562084) (xy 431.021177 -392.615491) (xy 430.997505 -392.665988)
			(xy 430.966732 -392.712501) (xy 430.929515 -392.754038) (xy 430.886647 -392.789713) (xy 430.839041 -392.818767)
			(xy 430.787712 -392.840579) (xy 430.733755 -392.854685) (xy 430.678318 -392.860785) (xy 430.622584 -392.858748)
			(xy 430.567741 -392.848618) (xy 430.514957 -392.830611) (xy 430.465357 -392.80511) (xy 430.419999 -392.772659)
			(xy 430.37985 -392.73395) (xy 430.345764 -392.689807) (xy 430.318468 -392.641172) (xy 430.298545 -392.589081)
			(xy 430.286419 -392.534644) (xy 430.282348 -392.479022) (xy 424.693394 -392.479022) (xy 424.70596 -392.485618)
			(xy 424.756544 -392.520539) (xy 424.802549 -392.561302) (xy 424.843306 -392.607313) (xy 424.878219 -392.657901)
			(xy 424.90678 -392.712329) (xy 424.928572 -392.769803) (xy 424.943278 -392.829484) (xy 424.950683 -392.890503)
			(xy 424.951144 -392.921236) (xy 424.950552 -392.956294) (xy 424.940904 -393.025744) (xy 424.92181 -393.093212)
			(xy 424.893633 -393.157418) (xy 424.856904 -393.217146) (xy 424.835066 -393.244578) (xy 424.828055 -393.25399)
			(xy 424.822746 -393.276828) (xy 424.82808 -393.299661) (xy 424.835066 -393.309094) (xy 424.856907 -393.336526)
			(xy 424.893649 -393.396247) (xy 424.921833 -393.460452) (xy 424.940924 -393.527923) (xy 424.950558 -393.597377)
			(xy 424.951144 -393.632436) (xy 424.950662 -393.663132) (xy 424.943261 -393.724076) (xy 424.92857 -393.783685)
			(xy 424.906804 -393.841089) (xy 424.87828 -393.895452) (xy 424.861228 -393.92098) (xy 424.855723 -393.929714)
			(xy 424.851602 -393.94993) (xy 424.855746 -393.970141) (xy 424.861228 -393.978892) (xy 424.878249 -394.004439)
			(xy 424.906762 -394.058804) (xy 424.928529 -394.116204) (xy 424.943233 -394.175805) (xy 424.950661 -394.236742)
			(xy 424.951144 -394.267436) (xy 424.950662 -394.298132) (xy 424.943261 -394.359076) (xy 424.935047 -394.392404)
			(xy 426.988476 -394.392404) (xy 426.992547 -394.336782) (xy 427.004673 -394.282345) (xy 427.024596 -394.230254)
			(xy 427.051892 -394.181619) (xy 427.085978 -394.137476) (xy 427.126127 -394.098767) (xy 427.171485 -394.066316)
			(xy 427.221085 -394.040815) (xy 427.273869 -394.022808) (xy 427.328712 -394.012678) (xy 427.384446 -394.010641)
			(xy 427.439883 -394.016741) (xy 427.49384 -394.030847) (xy 427.545169 -394.052659) (xy 427.592775 -394.081713)
			(xy 427.635643 -394.117388) (xy 427.67286 -394.158925) (xy 427.703633 -394.205438) (xy 427.727305 -394.255935)
			(xy 427.743373 -394.309342) (xy 427.751493 -394.364518) (xy 427.752002 -394.392404) (xy 427.751493 -394.42029)
			(xy 427.743373 -394.475466) (xy 427.727305 -394.528873) (xy 427.724838 -394.534136) (xy 428.518318 -394.534136)
			(xy 428.522389 -394.478514) (xy 428.534515 -394.424077) (xy 428.554438 -394.371986) (xy 428.581734 -394.323351)
			(xy 428.61582 -394.279208) (xy 428.655969 -394.240499) (xy 428.701327 -394.208048) (xy 428.750927 -394.182547)
			(xy 428.803711 -394.16454) (xy 428.858554 -394.15441) (xy 428.914288 -394.152373) (xy 428.969725 -394.158473)
			(xy 429.023682 -394.172579) (xy 429.075011 -394.194391) (xy 429.122617 -394.223445) (xy 429.165485 -394.25912)
			(xy 429.202702 -394.300657) (xy 429.233475 -394.34717) (xy 429.257147 -394.397667) (xy 429.273215 -394.451074)
			(xy 429.281335 -394.50625) (xy 429.281844 -394.534136) (xy 429.281335 -394.562022) (xy 429.273215 -394.617198)
			(xy 429.257147 -394.670605) (xy 429.233475 -394.721102) (xy 429.202702 -394.767615) (xy 429.165485 -394.809152)
			(xy 429.122617 -394.844827) (xy 429.075011 -394.873881) (xy 429.023682 -394.895693) (xy 428.969725 -394.909799)
			(xy 428.914288 -394.915899) (xy 428.858554 -394.913862) (xy 428.803711 -394.903732) (xy 428.750927 -394.885725)
			(xy 428.701327 -394.860224) (xy 428.655969 -394.827773) (xy 428.61582 -394.789064) (xy 428.581734 -394.744921)
			(xy 428.554438 -394.696286) (xy 428.534515 -394.644195) (xy 428.522389 -394.589758) (xy 428.518318 -394.534136)
			(xy 427.724838 -394.534136) (xy 427.703633 -394.57937) (xy 427.67286 -394.625883) (xy 427.635643 -394.66742)
			(xy 427.592775 -394.703095) (xy 427.545169 -394.732149) (xy 427.49384 -394.753961) (xy 427.439883 -394.768067)
			(xy 427.384446 -394.774167) (xy 427.328712 -394.77213) (xy 427.273869 -394.762) (xy 427.221085 -394.743993)
			(xy 427.171485 -394.718492) (xy 427.126127 -394.686041) (xy 427.085978 -394.647332) (xy 427.051892 -394.603189)
			(xy 427.024596 -394.554554) (xy 427.004673 -394.502463) (xy 426.992547 -394.448026) (xy 426.988476 -394.392404)
			(xy 424.935047 -394.392404) (xy 424.92857 -394.418685) (xy 424.906804 -394.476089) (xy 424.87828 -394.530452)
			(xy 424.861228 -394.55598) (xy 424.855723 -394.564714) (xy 424.851602 -394.58493) (xy 424.855746 -394.605141)
			(xy 424.861228 -394.613892) (xy 424.878249 -394.639439) (xy 424.906762 -394.693804) (xy 424.928529 -394.751204)
			(xy 424.943233 -394.810805) (xy 424.950661 -394.871742) (xy 424.951144 -394.902436) (xy 424.950662 -394.933132)
			(xy 424.943261 -394.994076) (xy 424.92857 -395.053685) (xy 424.906804 -395.111089) (xy 424.888875 -395.14526)
			(xy 426.479714 -395.14526) (xy 426.483785 -395.089638) (xy 426.495911 -395.035201) (xy 426.515834 -394.98311)
			(xy 426.54313 -394.934475) (xy 426.577216 -394.890332) (xy 426.617365 -394.851623) (xy 426.662723 -394.819172)
			(xy 426.712323 -394.793671) (xy 426.765107 -394.775664) (xy 426.81995 -394.765534) (xy 426.875684 -394.763497)
			(xy 426.931121 -394.769597) (xy 426.985078 -394.783703) (xy 427.036407 -394.805515) (xy 427.084013 -394.834569)
			(xy 427.126881 -394.870244) (xy 427.164098 -394.911781) (xy 427.194871 -394.958294) (xy 427.218543 -395.008791)
			(xy 427.228804 -395.042898) (xy 429.271174 -395.042898) (xy 429.275245 -394.987276) (xy 429.287371 -394.932839)
			(xy 429.307294 -394.880748) (xy 429.33459 -394.832113) (xy 429.368676 -394.78797) (xy 429.408825 -394.749261)
			(xy 429.454183 -394.71681) (xy 429.503783 -394.691309) (xy 429.556567 -394.673302) (xy 429.61141 -394.663172)
			(xy 429.667144 -394.661135) (xy 429.722581 -394.667235) (xy 429.776538 -394.681341) (xy 429.827867 -394.703153)
			(xy 429.875473 -394.732207) (xy 429.918341 -394.767882) (xy 429.955558 -394.809419) (xy 429.986331 -394.855932)
			(xy 430.010003 -394.906429) (xy 430.026071 -394.959836) (xy 430.034191 -395.015012) (xy 430.0347 -395.042898)
			(xy 430.034191 -395.070784) (xy 430.026071 -395.12596) (xy 430.010003 -395.179367) (xy 429.986331 -395.229864)
			(xy 429.955558 -395.276377) (xy 429.918341 -395.317914) (xy 429.875473 -395.353589) (xy 429.827867 -395.382643)
			(xy 429.776538 -395.404455) (xy 429.722581 -395.418561) (xy 429.667144 -395.424661) (xy 429.61141 -395.422624)
			(xy 429.556567 -395.412494) (xy 429.503783 -395.394487) (xy 429.454183 -395.368986) (xy 429.408825 -395.336535)
			(xy 429.368676 -395.297826) (xy 429.33459 -395.253683) (xy 429.307294 -395.205048) (xy 429.287371 -395.152957)
			(xy 429.275245 -395.09852) (xy 429.271174 -395.042898) (xy 427.228804 -395.042898) (xy 427.234611 -395.062198)
			(xy 427.242731 -395.117374) (xy 427.24324 -395.14526) (xy 427.242731 -395.173146) (xy 427.234611 -395.228322)
			(xy 427.218543 -395.281729) (xy 427.194871 -395.332226) (xy 427.164098 -395.378739) (xy 427.126881 -395.420276)
			(xy 427.084013 -395.455951) (xy 427.036407 -395.485005) (xy 426.985078 -395.506817) (xy 426.931121 -395.520923)
			(xy 426.875684 -395.527023) (xy 426.81995 -395.524986) (xy 426.765107 -395.514856) (xy 426.712323 -395.496849)
			(xy 426.662723 -395.471348) (xy 426.617365 -395.438897) (xy 426.577216 -395.400188) (xy 426.54313 -395.356045)
			(xy 426.515834 -395.30741) (xy 426.495911 -395.255319) (xy 426.483785 -395.200882) (xy 426.479714 -395.14526)
			(xy 424.888875 -395.14526) (xy 424.87828 -395.165452) (xy 424.861228 -395.19098) (xy 424.855723 -395.199714)
			(xy 424.851602 -395.21993) (xy 424.855746 -395.240141) (xy 424.861228 -395.248892) (xy 424.878249 -395.274439)
			(xy 424.906762 -395.328804) (xy 424.928529 -395.386204) (xy 424.943233 -395.445805) (xy 424.950661 -395.506742)
			(xy 424.951144 -395.537436) (xy 424.950725 -395.567177) (xy 424.943778 -395.626253) (xy 424.929985 -395.684114)
			(xy 424.920156 -395.712188) (xy 424.91533 -395.725142) (xy 424.920156 -395.751558) (xy 424.994324 -395.840458)
			(xy 425.01947 -395.849602) (xy 425.033186 -395.847062) (xy 425.055042 -395.843463) (xy 425.099175 -395.839651)
			(xy 425.121324 -395.839442) (xy 425.152054 -395.839933) (xy 425.213064 -395.847344) (xy 425.272737 -395.862053)
			(xy 425.330202 -395.883848) (xy 425.384622 -395.912409) (xy 425.435202 -395.947322) (xy 425.481206 -395.988076)
			(xy 425.521962 -396.034078) (xy 425.556877 -396.084656) (xy 425.585441 -396.139074) (xy 425.607239 -396.196538)
			(xy 425.621952 -396.25621) (xy 425.629365 -396.31722) (xy 425.629832 -396.34795) (xy 425.629274 -396.381899)
			(xy 425.620244 -396.449194) (xy 425.602337 -396.514688) (xy 425.575873 -396.577216) (xy 425.541321 -396.635665)
			(xy 425.499298 -396.688996) (xy 425.450551 -396.736259) (xy 425.423584 -396.75689) (xy 425.414948 -396.76324)
			(xy 425.404788 -396.78102) (xy 425.393358 -396.875762) (xy 425.3992 -396.89532) (xy 425.406058 -396.903702)
			(xy 425.422695 -396.924376) (xy 425.450719 -396.96944) (xy 425.472236 -397.017948) (xy 425.486832 -397.068968)
			(xy 425.494225 -397.121517) (xy 425.494479 -397.135604) (xy 426.361098 -397.135604) (xy 426.361527 -397.105494)
			(xy 426.368659 -397.045698) (xy 426.382802 -396.987162) (xy 426.403757 -396.930706) (xy 426.43123 -396.877118)
			(xy 426.464838 -396.827148) (xy 426.50411 -396.781496) (xy 426.548498 -396.7408) (xy 426.57268 -396.722854)
			(xy 426.582142 -396.715225) (xy 426.593147 -396.693592) (xy 426.593762 -396.681452) (xy 426.593762 -396.599156)
			(xy 426.593089 -396.58703) (xy 426.582099 -396.565417) (xy 426.57268 -396.557754) (xy 426.548466 -396.539849)
			(xy 426.504066 -396.499158) (xy 426.464787 -396.453505) (xy 426.431177 -396.40353) (xy 426.403708 -396.349934)
			(xy 426.382766 -396.293467) (xy 426.368643 -396.234921) (xy 426.361537 -396.175117) (xy 426.361098 -396.145004)
			(xy 426.3616 -396.113043) (xy 426.369611 -396.049625) (xy 426.385508 -395.987711) (xy 426.40904 -395.928278)
			(xy 426.439834 -395.872263) (xy 426.477407 -395.820548) (xy 426.521164 -395.773951) (xy 426.570417 -395.733206)
			(xy 426.624388 -395.698955) (xy 426.682227 -395.671738) (xy 426.74302 -395.651985) (xy 426.80581 -395.640007)
			(xy 426.869606 -395.635994) (xy 426.933402 -395.640007) (xy 426.996192 -395.651985) (xy 427.056985 -395.671738)
			(xy 427.114824 -395.698955) (xy 427.168795 -395.733206) (xy 427.218048 -395.773951) (xy 427.261805 -395.820548)
			(xy 427.299378 -395.872263) (xy 427.330172 -395.928278) (xy 427.353704 -395.987711) (xy 427.369601 -396.049625)
			(xy 427.377612 -396.113043) (xy 427.377715 -396.119604) (xy 429.189386 -396.119604) (xy 429.193457 -396.063982)
			(xy 429.205583 -396.009545) (xy 429.225506 -395.957454) (xy 429.252802 -395.908819) (xy 429.286888 -395.864676)
			(xy 429.327037 -395.825967) (xy 429.372395 -395.793516) (xy 429.421995 -395.768015) (xy 429.474779 -395.750008)
			(xy 429.529622 -395.739878) (xy 429.585356 -395.737841) (xy 429.640793 -395.743941) (xy 429.69475 -395.758047)
			(xy 429.746079 -395.779859) (xy 429.793685 -395.808913) (xy 429.836553 -395.844588) (xy 429.87377 -395.886125)
			(xy 429.904543 -395.932638) (xy 429.928215 -395.983135) (xy 429.944283 -396.036542) (xy 429.952403 -396.091718)
			(xy 429.952912 -396.119604) (xy 429.952403 -396.14749) (xy 429.944283 -396.202666) (xy 429.928215 -396.256073)
			(xy 429.904543 -396.30657) (xy 429.87377 -396.353083) (xy 429.836553 -396.39462) (xy 429.793685 -396.430295)
			(xy 429.746079 -396.459349) (xy 429.69475 -396.481161) (xy 429.640793 -396.495267) (xy 429.585356 -396.501367)
			(xy 429.529622 -396.49933) (xy 429.474779 -396.4892) (xy 429.421995 -396.471193) (xy 429.372395 -396.445692)
			(xy 429.327037 -396.413241) (xy 429.286888 -396.374532) (xy 429.252802 -396.330389) (xy 429.225506 -396.281754)
			(xy 429.205583 -396.229663) (xy 429.193457 -396.175226) (xy 429.189386 -396.119604) (xy 427.377715 -396.119604)
			(xy 427.378114 -396.145004) (xy 427.377686 -396.175114) (xy 427.370553 -396.23491) (xy 427.35641 -396.293445)
			(xy 427.335455 -396.349902) (xy 427.307981 -396.40349) (xy 427.274373 -396.453459) (xy 427.235101 -396.499112)
			(xy 427.190714 -396.539808) (xy 427.166532 -396.557754) (xy 427.157097 -396.56541) (xy 427.146082 -396.587023)
			(xy 427.14545 -396.599156) (xy 427.14545 -396.681452) (xy 427.146114 -396.693579) (xy 427.15711 -396.715193)
			(xy 427.166532 -396.722854) (xy 427.190753 -396.740751) (xy 427.235152 -396.781443) (xy 427.274431 -396.827098)
			(xy 427.308039 -396.877074) (xy 427.335507 -396.930671) (xy 427.356448 -396.987139) (xy 427.370571 -397.045686)
			(xy 427.377675 -397.105491) (xy 427.378114 -397.135604) (xy 429.189386 -397.135604) (xy 429.193457 -397.079982)
			(xy 429.205583 -397.025545) (xy 429.225506 -396.973454) (xy 429.252802 -396.924819) (xy 429.286888 -396.880676)
			(xy 429.327037 -396.841967) (xy 429.372395 -396.809516) (xy 429.421995 -396.784015) (xy 429.474779 -396.766008)
			(xy 429.529622 -396.755878) (xy 429.585356 -396.753841) (xy 429.640793 -396.759941) (xy 429.69475 -396.774047)
			(xy 429.746079 -396.795859) (xy 429.793685 -396.824913) (xy 429.836553 -396.860588) (xy 429.87377 -396.902125)
			(xy 429.904543 -396.948638) (xy 429.928215 -396.999135) (xy 429.944283 -397.052542) (xy 429.952403 -397.107718)
			(xy 429.952912 -397.135604) (xy 429.952403 -397.16349) (xy 429.944283 -397.218666) (xy 429.928215 -397.272073)
			(xy 429.904543 -397.32257) (xy 429.87377 -397.369083) (xy 429.836553 -397.41062) (xy 429.793685 -397.446295)
			(xy 429.746079 -397.475349) (xy 429.69475 -397.497161) (xy 429.640793 -397.511267) (xy 429.585356 -397.517367)
			(xy 429.529622 -397.51533) (xy 429.474779 -397.5052) (xy 429.421995 -397.487193) (xy 429.372395 -397.461692)
			(xy 429.327037 -397.429241) (xy 429.286888 -397.390532) (xy 429.252802 -397.346389) (xy 429.225506 -397.297754)
			(xy 429.205583 -397.245663) (xy 429.193457 -397.191226) (xy 429.189386 -397.135604) (xy 427.378114 -397.135604)
			(xy 427.377612 -397.167565) (xy 427.369601 -397.230983) (xy 427.353704 -397.292897) (xy 427.330172 -397.35233)
			(xy 427.299378 -397.408345) (xy 427.261805 -397.46006) (xy 427.218048 -397.506657) (xy 427.168795 -397.547402)
			(xy 427.114824 -397.581653) (xy 427.056985 -397.60887) (xy 426.996192 -397.628623) (xy 426.933402 -397.640601)
			(xy 426.869606 -397.644615) (xy 426.80581 -397.640601) (xy 426.74302 -397.628623) (xy 426.682227 -397.60887)
			(xy 426.624388 -397.581653) (xy 426.570417 -397.547402) (xy 426.521164 -397.506657) (xy 426.477407 -397.46006)
			(xy 426.439834 -397.408345) (xy 426.40904 -397.35233) (xy 426.385508 -397.292897) (xy 426.369611 -397.230983)
			(xy 426.3616 -397.167565) (xy 426.361098 -397.135604) (xy 425.494479 -397.135604) (xy 425.494704 -397.14805)
			(xy 425.494218 -397.175301) (xy 425.486462 -397.229249) (xy 425.471107 -397.281544) (xy 425.448465 -397.331121)
			(xy 425.418999 -397.376971) (xy 425.383308 -397.418162) (xy 425.342117 -397.453853) (xy 425.296267 -397.483319)
			(xy 425.24669 -397.505961) (xy 425.194395 -397.521316) (xy 425.140447 -397.529072) (xy 425.085945 -397.529072)
			(xy 425.031997 -397.521316) (xy 424.979702 -397.505961) (xy 424.930125 -397.483319) (xy 424.884275 -397.453853)
			(xy 424.843084 -397.418162) (xy 424.807393 -397.376971) (xy 424.777927 -397.331121) (xy 424.755285 -397.281544)
			(xy 424.73993 -397.229249) (xy 424.732174 -397.175301) (xy 424.731688 -397.14805) (xy 424.732163 -397.120716)
			(xy 424.739971 -397.06661) (xy 424.755419 -397.014171) (xy 424.778193 -396.964473) (xy 424.807825 -396.918534)
			(xy 424.825414 -396.897606) (xy 424.832272 -396.889478) (xy 424.838622 -396.86992) (xy 424.829224 -396.775178)
			(xy 424.819318 -396.757144) (xy 424.810682 -396.75054) (xy 424.784708 -396.72986) (xy 424.73787 -396.682802)
			(xy 424.697555 -396.630048) (xy 424.664449 -396.572496) (xy 424.639116 -396.511125) (xy 424.621986 -396.446978)
			(xy 424.613351 -396.381147) (xy 424.612816 -396.34795) (xy 424.613228 -396.318208) (xy 424.620176 -396.259132)
			(xy 424.633973 -396.201271) (xy 424.643804 -396.173198) (xy 424.64863 -396.160244) (xy 424.643804 -396.133828)
			(xy 424.569636 -396.044928) (xy 424.54449 -396.035784) (xy 424.530774 -396.038324) (xy 424.508917 -396.041915)
			(xy 424.464785 -396.045733) (xy 424.442636 -396.045944) (xy 424.411907 -396.04541) (xy 424.350897 -396.038007)
			(xy 424.291224 -396.023303) (xy 424.233759 -396.001514) (xy 424.179339 -395.972957) (xy 424.128758 -395.938049)
			(xy 424.082753 -395.897298) (xy 424.041996 -395.851299) (xy 424.00708 -395.800723) (xy 423.978516 -395.746307)
			(xy 423.956718 -395.688845) (xy 423.942006 -395.629174) (xy 423.934594 -395.568165) (xy 423.934128 -395.537436)
			(xy 423.934583 -395.506739) (xy 423.941989 -395.445793) (xy 423.956685 -395.386184) (xy 423.978457 -395.328781)
			(xy 424.006988 -395.274419) (xy 424.024044 -395.248892) (xy 424.029482 -395.240122) (xy 424.033617 -395.21993)
			(xy 424.029505 -395.199733) (xy 424.024044 -395.19098) (xy 424.014808 -395.177372) (xy 423.997905 -395.149155)
			(xy 423.990262 -395.134592) (xy 423.985161 -395.125598) (xy 423.969316 -395.112346) (xy 423.949522 -395.106442)
			(xy 423.939208 -395.10716) (xy 423.924969 -395.108685) (xy 423.896378 -395.110339) (xy 423.882058 -395.110462)
			(xy 423.851323 -395.110102) (xy 423.790302 -395.102687) (xy 423.73062 -395.087972) (xy 423.673147 -395.066169)
			(xy 423.618721 -395.037598) (xy 423.568135 -395.002675) (xy 423.522128 -394.96191) (xy 423.48137 -394.915895)
			(xy 423.446456 -394.865304) (xy 423.417894 -394.810873) (xy 423.396102 -394.753396) (xy 423.381397 -394.693711)
			(xy 423.373993 -394.632689) (xy 423.37355 -394.601954) (xy 423.373986 -394.571416) (xy 423.381297 -394.510779)
			(xy 423.395821 -394.451455) (xy 423.417349 -394.394298) (xy 423.44557 -394.340133) (xy 423.46245 -394.31468)
			(xy 423.468241 -394.305288) (xy 423.47199 -394.283571) (xy 423.466288 -394.262283) (xy 423.459656 -394.253466)
			(xy 423.439433 -394.228369) (xy 423.404793 -394.174015) (xy 423.377308 -394.115716) (xy 423.35742 -394.054407)
			(xy 423.350944 -394.022834) (xy 423.348583 -394.012827) (xy 423.337102 -393.995789) (xy 423.319842 -393.984644)
			(xy 423.309796 -393.982448) (xy 423.28116 -393.977081) (xy 423.225478 -393.959928) (xy 423.172421 -393.935851)
			(xy 423.122847 -393.905238) (xy 423.077557 -393.868584) (xy 423.037282 -393.826482) (xy 423.002673 -393.779611)
			(xy 422.974288 -393.728729) (xy 422.952587 -393.674657) (xy 422.93792 -393.618269) (xy 422.930524 -393.560476)
			(xy 422.930066 -393.531344) (xy 421.847071 -393.531344) (xy 421.853265 -393.546448) (xy 421.868501 -393.603828)
			(xy 421.876192 -393.662696) (xy 421.876728 -393.69238) (xy 421.876207 -393.723443) (xy 421.867793 -393.784997)
			(xy 421.859964 -393.815062) (xy 421.85717 -393.825222) (xy 421.85971 -393.845034) (xy 421.907208 -393.92733)
			(xy 421.92321 -393.939522) (xy 421.93337 -393.942062) (xy 421.962478 -393.950067) (xy 422.018445 -393.972696)
			(xy 422.070951 -394.002487) (xy 422.119084 -394.038923) (xy 422.162008 -394.081372) (xy 422.198979 -394.129095)
			(xy 422.229354 -394.181265) (xy 422.252606 -394.236977) (xy 422.268331 -394.295261) (xy 422.276257 -394.355108)
			(xy 422.276778 -394.385292) (xy 422.276676 -394.399042) (xy 422.275024 -394.426493) (xy 422.273476 -394.440156)
			(xy 422.27274 -394.448845) (xy 422.276517 -394.465856) (xy 422.280842 -394.47343) (xy 422.296844 -394.49883)
			(xy 422.301627 -394.505854) (xy 422.314864 -394.516495) (xy 422.322752 -394.519658) (xy 422.346505 -394.528635)
			(xy 422.39115 -394.552824) (xy 422.431573 -394.583553) (xy 422.466824 -394.620099) (xy 422.496075 -394.661604)
			(xy 422.518638 -394.707092) (xy 422.533983 -394.755494) (xy 422.54175 -394.805674) (xy 422.542208 -394.831062)
			(xy 422.541728 -394.857053) (xy 422.533601 -394.908396) (xy 422.517542 -394.957836) (xy 422.493947 -395.004154)
			(xy 422.463395 -395.046211) (xy 422.42664 -395.08297) (xy 422.384587 -395.113527) (xy 422.338271 -395.137128)
			(xy 422.288833 -395.153192) (xy 422.237491 -395.161325) (xy 422.2115 -395.16177) (xy 422.186591 -395.161319)
			(xy 422.137335 -395.153851) (xy 422.089756 -395.139082) (xy 422.044929 -395.117347) (xy 422.003868 -395.089137)
			(xy 421.967499 -395.05509) (xy 421.936646 -395.015975) (xy 421.912006 -394.972677) (xy 421.894135 -394.926174)
			(xy 421.888412 -394.901928) (xy 421.886325 -394.893677) (xy 421.877497 -394.879138) (xy 421.87114 -394.87348)
			(xy 421.847772 -394.85443) (xy 421.840864 -394.849261) (xy 421.824639 -394.843425) (xy 421.816022 -394.843)
			(xy 421.784055 -394.842253) (xy 421.720796 -394.832928) (xy 421.65945 -394.814888) (xy 421.601212 -394.788486)
			(xy 421.547216 -394.754235) (xy 421.498513 -394.712803) (xy 421.45605 -394.664994) (xy 421.420655 -394.611741)
			(xy 421.40632 -394.583158) (xy 421.39997 -394.56995) (xy 421.375332 -394.554456) (xy 421.3606 -394.554456)
			(xy 421.350589 -394.554943) (xy 421.33209 -394.562601) (xy 421.317926 -394.576753) (xy 421.310252 -394.595246)
			(xy 421.3098 -394.605256) (xy 421.3098 -394.69949) (xy 421.313356 -394.70838) (xy 421.322259 -394.731908)
			(xy 421.333644 -394.780907) (xy 421.337472 -394.831065) (xy 421.333655 -394.881223) (xy 421.32228 -394.930224)
			(xy 421.313356 -394.953744) (xy 421.3098 -394.962634) (xy 421.3098 -395.101318) (xy 421.310309 -395.111496)
			(xy 421.318307 -395.130221) (xy 421.325294 -395.13764) (xy 421.346827 -395.159283) (xy 421.384554 -395.207285)
			(xy 421.415566 -395.259875) (xy 421.439314 -395.316119) (xy 421.455377 -395.375021) (xy 421.46347 -395.435535)
			(xy 421.463978 -395.466062) (xy 421.463374 -395.499382) (xy 421.453704 -395.565317) (xy 421.434579 -395.629153)
			(xy 421.421052 -395.65961) (xy 421.416791 -395.670079) (xy 421.416866 -395.692653) (xy 421.426618 -395.713012)
			(xy 421.435022 -395.72057) (xy 421.457269 -395.739244) (xy 421.497334 -395.781299) (xy 421.531757 -395.828085)
			(xy 421.559984 -395.87885) (xy 421.581562 -395.932778) (xy 421.596145 -395.989002) (xy 421.603498 -396.04662)
			(xy 421.603932 -396.075662) (xy 421.603481 -396.104666) (xy 421.596151 -396.16221) (xy 421.581615 -396.218367)
			(xy 421.560106 -396.272241) (xy 421.531969 -396.322968) (xy 421.497652 -396.369738) (xy 421.457707 -396.411801)
			(xy 421.43553 -396.4305) (xy 421.428418 -396.436088) (xy 421.419274 -396.451328) (xy 421.404034 -396.534132)
			(xy 421.406828 -396.551404) (xy 421.4114 -396.559532) (xy 421.423994 -396.582711) (xy 421.44188 -396.632331)
			(xy 421.44869 -396.671292) (xy 422.996614 -396.671292) (xy 422.997054 -396.641322) (xy 423.004879 -396.581895)
			(xy 423.020394 -396.523997) (xy 423.043333 -396.46862) (xy 423.073305 -396.416711) (xy 423.109795 -396.369158)
			(xy 423.152181 -396.326776) (xy 423.199736 -396.290288) (xy 423.251647 -396.26032) (xy 423.307026 -396.237384)
			(xy 423.364924 -396.221873) (xy 423.424352 -396.214052) (xy 423.454322 -396.213584) (xy 423.484318 -396.214083)
			(xy 423.543793 -396.221934) (xy 423.601733 -396.237487) (xy 423.657145 -396.260475) (xy 423.70908 -396.290504)
			(xy 423.756648 -396.327058) (xy 423.799034 -396.369513) (xy 423.835511 -396.417141) (xy 423.865455 -396.469125)
			(xy 423.888352 -396.524574) (xy 423.896536 -396.553436) (xy 423.899508 -396.562745) (xy 423.911187 -396.578382)
			(xy 423.92787 -396.58851) (xy 423.93743 -396.59052) (xy 423.966232 -396.595759) (xy 424.022285 -396.612646)
			(xy 424.075729 -396.63654) (xy 424.125691 -396.667051) (xy 424.171358 -396.703681) (xy 424.211983 -396.745833)
			(xy 424.246904 -396.792818) (xy 424.275552 -396.843872) (xy 424.29746 -396.89816) (xy 424.31227 -396.954798)
			(xy 424.31974 -397.012861) (xy 424.320208 -397.042132) (xy 424.319687 -397.073248) (xy 424.311276 -397.134909)
			(xy 424.294585 -397.194862) (xy 424.269924 -397.251999) (xy 424.237746 -397.305267) (xy 424.198647 -397.353682)
			(xy 424.153346 -397.396352) (xy 424.102681 -397.432489) (xy 424.047586 -397.461426) (xy 423.989077 -397.482629)
			(xy 423.958766 -397.48968) (xy 423.94964 -397.491997) (xy 423.933935 -397.502367) (xy 423.923062 -397.517727)
			(xy 423.920412 -397.526764) (xy 423.912514 -397.555642) (xy 423.890196 -397.611196) (xy 423.860829 -397.663367)
			(xy 423.824912 -397.711267) (xy 423.804334 -397.733012) (xy 423.797792 -397.740341) (xy 423.790353 -397.758506)
			(xy 423.789856 -397.768318) (xy 423.789602 -397.82115) (xy 423.79138 -397.822928) (xy 423.799131 -397.829569)
			(xy 423.818257 -397.836646) (xy 423.828464 -397.836644) (xy 423.860214 -397.835374) (xy 423.870416 -397.834481)
			(xy 423.888898 -397.825707) (xy 423.896028 -397.818356) (xy 423.917816 -397.794698) (xy 423.966906 -397.753144)
			(xy 424.021332 -397.718874) (xy 424.080021 -397.692565) (xy 424.141816 -397.674735) (xy 424.2055 -397.665736)
			(xy 424.237658 -397.665194) (xy 424.267629 -397.665656) (xy 424.327059 -397.673475) (xy 424.384959 -397.688985)
			(xy 424.44034 -397.71192) (xy 424.492253 -397.741888) (xy 424.53981 -397.778375) (xy 424.582197 -397.820759)
			(xy 424.618689 -397.868312) (xy 424.648661 -397.920223) (xy 424.671601 -397.975601) (xy 424.687116 -398.0335)
			(xy 424.694941 -398.092929) (xy 424.694941 -398.152871) (xy 424.687116 -398.2123) (xy 424.671601 -398.270199)
			(xy 424.648661 -398.325577) (xy 424.639852 -398.340834) (xy 426.971458 -398.340834) (xy 426.975529 -398.285212)
			(xy 426.987655 -398.230775) (xy 427.007578 -398.178684) (xy 427.034874 -398.130049) (xy 427.06896 -398.085906)
			(xy 427.109109 -398.047197) (xy 427.154467 -398.014746) (xy 427.204067 -397.989245) (xy 427.256851 -397.971238)
			(xy 427.311694 -397.961108) (xy 427.367428 -397.959071) (xy 427.422865 -397.965171) (xy 427.476822 -397.979277)
			(xy 427.528151 -398.001089) (xy 427.575757 -398.030143) (xy 427.618625 -398.065818) (xy 427.655842 -398.107355)
			(xy 427.686615 -398.153868) (xy 427.710287 -398.204365) (xy 427.726355 -398.257772) (xy 427.734475 -398.312948)
			(xy 427.734984 -398.340834) (xy 427.734475 -398.36872) (xy 427.726355 -398.423896) (xy 427.710287 -398.477303)
			(xy 427.686615 -398.5278) (xy 427.655842 -398.574313) (xy 427.618625 -398.61585) (xy 427.575757 -398.651525)
			(xy 427.528151 -398.680579) (xy 427.476822 -398.702391) (xy 427.422865 -398.716497) (xy 427.367428 -398.722597)
			(xy 427.311694 -398.72056) (xy 427.256851 -398.71043) (xy 427.204067 -398.692423) (xy 427.154467 -398.666922)
			(xy 427.109109 -398.634471) (xy 427.06896 -398.595762) (xy 427.034874 -398.551619) (xy 427.007578 -398.502984)
			(xy 426.987655 -398.450893) (xy 426.975529 -398.396456) (xy 426.971458 -398.340834) (xy 424.639852 -398.340834)
			(xy 424.618689 -398.377488) (xy 424.582197 -398.425041) (xy 424.53981 -398.467425) (xy 424.492253 -398.503912)
			(xy 424.44034 -398.53388) (xy 424.384959 -398.556815) (xy 424.327059 -398.572325) (xy 424.267629 -398.580144)
			(xy 424.237658 -398.58061) (xy 424.20923 -398.580196) (xy 424.152806 -398.5732) (xy 424.09768 -398.559282)
			(xy 424.071034 -398.549368) (xy 424.058842 -398.544542) (xy 424.032934 -398.547844) (xy 423.942764 -398.6149)
			(xy 423.931842 -398.638776) (xy 423.932858 -398.651984) (xy 423.934382 -398.68856) (xy 423.933843 -398.720304)
			(xy 423.925067 -398.783184) (xy 423.907692 -398.844249) (xy 423.882051 -398.90233) (xy 423.865802 -398.929606)
			(xy 423.86147 -398.937166) (xy 423.857741 -398.954176) (xy 423.859915 -398.971454) (xy 423.863516 -398.97939)
			(xy 423.877486 -399.006568) (xy 423.881746 -399.014211) (xy 423.894439 -399.026238) (xy 423.910446 -399.033278)
			(xy 423.919142 -399.034254) (xy 423.925492 -399.034762) (xy 423.935838 -399.035195) (xy 423.955479 -399.028699)
			(xy 423.970951 -399.014965) (xy 423.975784 -399.005806) (xy 423.989881 -398.977165) (xy 424.024143 -398.923304)
			(xy 424.064879 -398.874156) (xy 424.111449 -398.830495) (xy 424.163118 -398.793008) (xy 424.219075 -398.762286)
			(xy 424.278438 -398.738812) (xy 424.340273 -398.722956) (xy 424.403606 -398.714966) (xy 424.435524 -398.714468)
			(xy 424.466255 -398.714933) (xy 424.527267 -398.722344) (xy 424.586942 -398.737055) (xy 424.644409 -398.758851)
			(xy 424.698829 -398.787414) (xy 424.749411 -398.822329) (xy 424.795415 -398.863085) (xy 424.836171 -398.909089)
			(xy 424.871086 -398.959671) (xy 424.899649 -399.014091) (xy 424.921445 -399.071558) (xy 424.926901 -399.09369)
			(xy 426.462696 -399.09369) (xy 426.466767 -399.038068) (xy 426.478893 -398.983631) (xy 426.498816 -398.93154)
			(xy 426.526112 -398.882905) (xy 426.560198 -398.838762) (xy 426.600347 -398.800053) (xy 426.645705 -398.767602)
			(xy 426.695305 -398.742101) (xy 426.748089 -398.724094) (xy 426.802932 -398.713964) (xy 426.858666 -398.711927)
			(xy 426.914103 -398.718027) (xy 426.96806 -398.732133) (xy 427.019389 -398.753945) (xy 427.066995 -398.782999)
			(xy 427.109863 -398.818674) (xy 427.14708 -398.860211) (xy 427.177853 -398.906724) (xy 427.201525 -398.957221)
			(xy 427.217593 -399.010628) (xy 427.225713 -399.065804) (xy 427.226222 -399.09369) (xy 427.225713 -399.121576)
			(xy 427.217593 -399.176752) (xy 427.201525 -399.230159) (xy 427.177853 -399.280656) (xy 427.161735 -399.305018)
			(xy 428.847502 -399.305018) (xy 428.851573 -399.249396) (xy 428.863699 -399.194959) (xy 428.883622 -399.142868)
			(xy 428.910918 -399.094233) (xy 428.945004 -399.05009) (xy 428.985153 -399.011381) (xy 429.030511 -398.97893)
			(xy 429.080111 -398.953429) (xy 429.132895 -398.935422) (xy 429.187738 -398.925292) (xy 429.243472 -398.923255)
			(xy 429.298909 -398.929355) (xy 429.352866 -398.943461) (xy 429.404195 -398.965273) (xy 429.451801 -398.994327)
			(xy 429.494669 -399.030002) (xy 429.531886 -399.071539) (xy 429.562659 -399.118052) (xy 429.586331 -399.168549)
			(xy 429.602399 -399.221956) (xy 429.610519 -399.277132) (xy 429.611028 -399.305018) (xy 429.610519 -399.332904)
			(xy 429.602399 -399.38808) (xy 429.586331 -399.441487) (xy 429.562659 -399.491984) (xy 429.531886 -399.538497)
			(xy 429.494669 -399.580034) (xy 429.451801 -399.615709) (xy 429.404195 -399.644763) (xy 429.352866 -399.666575)
			(xy 429.298909 -399.680681) (xy 429.243472 -399.686781) (xy 429.187738 -399.684744) (xy 429.132895 -399.674614)
			(xy 429.080111 -399.656607) (xy 429.030511 -399.631106) (xy 428.985153 -399.598655) (xy 428.945004 -399.559946)
			(xy 428.910918 -399.515803) (xy 428.883622 -399.467168) (xy 428.863699 -399.415077) (xy 428.851573 -399.36064)
			(xy 428.847502 -399.305018) (xy 427.161735 -399.305018) (xy 427.14708 -399.327169) (xy 427.109863 -399.368706)
			(xy 427.066995 -399.404381) (xy 427.019389 -399.433435) (xy 426.96806 -399.455247) (xy 426.914103 -399.469353)
			(xy 426.858666 -399.475453) (xy 426.802932 -399.473416) (xy 426.748089 -399.463286) (xy 426.695305 -399.445279)
			(xy 426.645705 -399.419778) (xy 426.600347 -399.387327) (xy 426.560198 -399.348618) (xy 426.526112 -399.304475)
			(xy 426.498816 -399.25584) (xy 426.478893 -399.203749) (xy 426.466767 -399.149312) (xy 426.462696 -399.09369)
			(xy 424.926901 -399.09369) (xy 424.936156 -399.131233) (xy 424.943567 -399.192245) (xy 424.944032 -399.222976)
			(xy 424.943573 -399.253673) (xy 424.936166 -399.314618) (xy 424.92147 -399.374227) (xy 424.8997 -399.43163)
			(xy 424.871171 -399.485993) (xy 424.854116 -399.51152) (xy 424.848663 -399.520282) (xy 424.844526 -399.54048)
			(xy 424.848647 -399.560681) (xy 424.854116 -399.569432) (xy 424.871153 -399.594969) (xy 424.899664 -399.649336)
			(xy 424.921428 -399.706739) (xy 424.936128 -399.766342) (xy 424.943552 -399.827281) (xy 424.944032 -399.857976)
			(xy 424.943573 -399.888673) (xy 424.936166 -399.949618) (xy 424.92147 -400.009227) (xy 424.8997 -400.06663)
			(xy 424.891765 -400.08175) (xy 426.971458 -400.08175) (xy 426.975529 -400.026128) (xy 426.987655 -399.971691)
			(xy 427.007578 -399.9196) (xy 427.034874 -399.870965) (xy 427.06896 -399.826822) (xy 427.109109 -399.788113)
			(xy 427.154467 -399.755662) (xy 427.204067 -399.730161) (xy 427.256851 -399.712154) (xy 427.311694 -399.702024)
			(xy 427.367428 -399.699987) (xy 427.422865 -399.706087) (xy 427.476822 -399.720193) (xy 427.528151 -399.742005)
			(xy 427.575757 -399.771059) (xy 427.618625 -399.806734) (xy 427.655842 -399.848271) (xy 427.686615 -399.894784)
			(xy 427.710287 -399.945281) (xy 427.726355 -399.998688) (xy 427.734475 -400.053864) (xy 427.734984 -400.08175)
			(xy 427.734475 -400.109636) (xy 427.726355 -400.164812) (xy 427.710287 -400.218219) (xy 427.686615 -400.268716)
			(xy 427.655842 -400.315229) (xy 427.618625 -400.356766) (xy 427.575757 -400.392441) (xy 427.528151 -400.421495)
			(xy 427.476822 -400.443307) (xy 427.422865 -400.457413) (xy 427.367428 -400.463513) (xy 427.311694 -400.461476)
			(xy 427.256851 -400.451346) (xy 427.204067 -400.433339) (xy 427.154467 -400.407838) (xy 427.109109 -400.375387)
			(xy 427.06896 -400.336678) (xy 427.034874 -400.292535) (xy 427.007578 -400.2439) (xy 426.987655 -400.191809)
			(xy 426.975529 -400.137372) (xy 426.971458 -400.08175) (xy 424.891765 -400.08175) (xy 424.871171 -400.120993)
			(xy 424.854116 -400.14652) (xy 424.848663 -400.155282) (xy 424.844526 -400.17548) (xy 424.848647 -400.195681)
			(xy 424.854116 -400.204432) (xy 424.871153 -400.229969) (xy 424.899664 -400.284336) (xy 424.921428 -400.341739)
			(xy 424.936128 -400.401342) (xy 424.943552 -400.462281) (xy 424.944032 -400.492976) (xy 424.943521 -400.523706)
			(xy 424.936116 -400.584717) (xy 424.921411 -400.644391) (xy 424.89962 -400.701857) (xy 424.871061 -400.756278)
			(xy 424.836151 -400.806859) (xy 424.811572 -400.834606) (xy 426.462696 -400.834606) (xy 426.466767 -400.778984)
			(xy 426.478893 -400.724547) (xy 426.498816 -400.672456) (xy 426.526112 -400.623821) (xy 426.560198 -400.579678)
			(xy 426.600347 -400.540969) (xy 426.645705 -400.508518) (xy 426.695305 -400.483017) (xy 426.748089 -400.46501)
			(xy 426.802932 -400.45488) (xy 426.858666 -400.452843) (xy 426.914103 -400.458943) (xy 426.96806 -400.473049)
			(xy 427.019389 -400.494861) (xy 427.066995 -400.523915) (xy 427.109863 -400.55959) (xy 427.14708 -400.601127)
			(xy 427.177853 -400.64764) (xy 427.201525 -400.698137) (xy 427.217593 -400.751544) (xy 427.225713 -400.80672)
			(xy 427.226222 -400.834606) (xy 427.225713 -400.862492) (xy 427.217593 -400.917668) (xy 427.201525 -400.971075)
			(xy 427.177853 -401.021572) (xy 427.14708 -401.068085) (xy 427.109863 -401.109622) (xy 427.066995 -401.145297)
			(xy 427.019389 -401.174351) (xy 426.96806 -401.196163) (xy 426.914103 -401.210269) (xy 426.858666 -401.216369)
			(xy 426.802932 -401.214332) (xy 426.748089 -401.204202) (xy 426.695305 -401.186195) (xy 426.645705 -401.160694)
			(xy 426.600347 -401.128243) (xy 426.560198 -401.089534) (xy 426.526112 -401.045391) (xy 426.498816 -400.996756)
			(xy 426.478893 -400.944665) (xy 426.466767 -400.890228) (xy 426.462696 -400.834606) (xy 424.811572 -400.834606)
			(xy 424.795398 -400.852864) (xy 424.749397 -400.893621) (xy 424.698819 -400.928536) (xy 424.644401 -400.9571)
			(xy 424.586937 -400.978897) (xy 424.527264 -400.993608) (xy 424.466254 -401.001019) (xy 424.435524 -401.001484)
			(xy 424.403711 -401.001003) (xy 424.340582 -400.993068) (xy 424.278935 -400.977319) (xy 424.219736 -400.954003)
			(xy 424.163907 -400.923483) (xy 424.112323 -400.886236) (xy 424.065788 -400.842844) (xy 424.025031 -400.793987)
			(xy 423.990687 -400.740426) (xy 423.976546 -400.711924) (xy 423.971672 -400.702799) (xy 423.956202 -400.689098)
			(xy 423.936591 -400.682584) (xy 423.926254 -400.682968) (xy 423.881804 -400.685) (xy 423.851072 -400.684559)
			(xy 423.790055 -400.67715) (xy 423.730376 -400.662441) (xy 423.672906 -400.640645) (xy 423.618482 -400.612081)
			(xy 423.567897 -400.577165) (xy 423.52189 -400.536407) (xy 423.481132 -400.4904) (xy 423.446216 -400.439815)
			(xy 423.417653 -400.38539) (xy 423.395858 -400.32792) (xy 423.381149 -400.268241) (xy 423.373741 -400.207224)
			(xy 423.373296 -400.176492) (xy 423.373785 -400.145796) (xy 423.381184 -400.084852) (xy 423.395872 -400.025243)
			(xy 423.417637 -399.967839) (xy 423.44616 -399.913476) (xy 423.463212 -399.887948) (xy 423.46869 -399.8792)
			(xy 423.472815 -399.858993) (xy 423.468685 -399.838788) (xy 423.463212 -399.830036) (xy 423.445762 -399.803924)
			(xy 423.41674 -399.748226) (xy 423.394794 -399.68938) (xy 423.380259 -399.628279) (xy 423.376344 -399.597118)
			(xy 423.374994 -399.588192) (xy 423.366928 -399.572056) (xy 423.360596 -399.565622) (xy 423.338498 -399.544794)
			(xy 423.331853 -399.539033) (xy 423.315746 -399.532011) (xy 423.307002 -399.531078) (xy 423.282163 -399.52904)
			(xy 423.233471 -399.518414) (xy 423.186927 -399.5006) (xy 423.143583 -399.476) (xy 423.104424 -399.445173)
			(xy 423.070336 -399.408817) (xy 423.042092 -399.367755) (xy 423.020332 -399.322919) (xy 423.005549 -399.275325)
			(xy 422.998078 -399.226051) (xy 422.99763 -399.201132) (xy 422.998025 -399.177394) (xy 423.004822 -399.130406)
			(xy 423.018267 -399.084873) (xy 423.038084 -399.04173) (xy 423.063865 -399.001863) (xy 423.079164 -398.983708)
			(xy 423.085729 -398.975286) (xy 423.091902 -398.954866) (xy 423.089268 -398.933697) (xy 423.084244 -398.924272)
			(xy 423.068742 -398.897465) (xy 423.044304 -398.840565) (xy 423.027776 -398.780887) (xy 423.019458 -398.719523)
			(xy 423.018966 -398.68856) (xy 423.019485 -398.656958) (xy 423.028187 -398.594357) (xy 423.045435 -398.533552)
			(xy 423.070897 -398.475704) (xy 423.087038 -398.44853) (xy 423.09162 -398.440328) (xy 423.095034 -398.421866)
			(xy 423.091595 -398.403408) (xy 423.087038 -398.39519) (xy 423.070917 -398.368008) (xy 423.045489 -398.310151)
			(xy 423.028248 -398.249351) (xy 423.01952 -398.186758) (xy 423.018966 -398.15516) (xy 423.01953 -398.121926)
			(xy 423.029139 -398.056155) (xy 423.048163 -397.992467) (xy 423.076202 -397.932202) (xy 423.112666 -397.876628)
			(xy 423.134282 -397.851376) (xy 423.140632 -397.844264) (xy 423.147236 -397.826992) (xy 423.147236 -397.740886)
			(xy 423.140632 -397.723614) (xy 423.134282 -397.716502) (xy 423.112721 -397.691252) (xy 423.076345 -397.635709)
			(xy 423.048375 -397.575493) (xy 423.029397 -397.511868) (xy 423.01981 -397.446169) (xy 423.01922 -397.412972)
			(xy 423.019747 -397.381146) (xy 423.028571 -397.31811) (xy 423.046044 -397.256903) (xy 423.071829 -397.198709)
			(xy 423.105429 -397.144648) (xy 423.125392 -397.119856) (xy 423.131234 -397.112744) (xy 423.13733 -397.095218)
			(xy 423.13479 -397.009112) (xy 423.127678 -396.992094) (xy 423.121328 -396.985236) (xy 423.101836 -396.96397)
			(xy 423.067845 -396.91736) (xy 423.039981 -396.866847) (xy 423.018687 -396.813233) (xy 423.004301 -396.757367)
			(xy 422.997052 -396.700136) (xy 422.996614 -396.671292) (xy 421.44869 -396.671292) (xy 421.450962 -396.684289)
			(xy 421.451532 -396.710662) (xy 421.45146 -396.72002) (xy 421.450314 -396.738702) (xy 421.449246 -396.748)
			(xy 421.44823 -396.75689) (xy 421.45204 -396.773654) (xy 421.495982 -396.843504) (xy 421.509698 -396.853918)
			(xy 421.51808 -396.856712) (xy 421.542117 -396.865164) (xy 421.587302 -396.888707) (xy 421.628119 -396.919202)
			(xy 421.663506 -396.955858) (xy 421.692547 -396.997722) (xy 421.714485 -397.043708) (xy 421.722042 -397.06804)
			(xy 421.723566 -397.073882) (xy 422.04386 -397.627602) (xy 422.047924 -397.63192) (xy 422.06414 -397.649619)
			(xy 422.091571 -397.689008) (xy 422.112716 -397.7321) (xy 422.127088 -397.777897) (xy 422.134354 -397.825344)
			(xy 422.134792 -397.849344) (xy 422.134327 -397.874147) (xy 422.126557 -397.92314) (xy 422.111216 -397.970314)
			(xy 422.088681 -398.014505) (xy 422.059509 -398.054626) (xy 422.024417 -398.089687) (xy 421.984271 -398.118825)
			(xy 421.94006 -398.141321) (xy 421.892873 -398.156621) (xy 421.843873 -398.164348) (xy 421.81907 -398.164812)
			(xy 421.793678 -398.164302) (xy 421.743548 -398.156168) (xy 421.695368 -398.140114) (xy 421.650379 -398.116554)
			(xy 421.609741 -398.086096) (xy 421.574503 -398.049526) (xy 421.545573 -398.007787) (xy 421.523698 -397.961955)
			(xy 421.516048 -397.937736) (xy 421.514524 -397.931894) (xy 421.404542 -397.741902) (xy 421.398479 -397.732546)
			(xy 421.380228 -397.719788) (xy 421.358294 -397.715945) (xy 421.347392 -397.71828) (xy 421.330628 -397.722598)
			(xy 421.3098 -397.749776) (xy 421.3098 -398.448784) (xy 421.311832 -398.455896) (xy 421.317648 -398.476945)
			(xy 421.323889 -398.520167) (xy 421.324278 -398.542002) (xy 421.32387 -398.563835) (xy 421.32327 -398.567989)
			(xy 422.042846 -398.567989) (xy 422.042846 -398.516015) (xy 422.050976 -398.46468) (xy 422.067037 -398.41525)
			(xy 422.090633 -398.36894) (xy 422.121183 -398.326892) (xy 422.157934 -398.290141) (xy 422.199982 -398.259591)
			(xy 422.246292 -398.235995) (xy 422.295722 -398.219934) (xy 422.347057 -398.211804) (xy 422.399031 -398.211804)
			(xy 422.450366 -398.219934) (xy 422.499796 -398.235995) (xy 422.546106 -398.259591) (xy 422.588154 -398.290141)
			(xy 422.624905 -398.326892) (xy 422.655455 -398.36894) (xy 422.679051 -398.41525) (xy 422.695112 -398.46468)
			(xy 422.703242 -398.516015) (xy 422.703752 -398.542002) (xy 422.703242 -398.567989) (xy 422.695112 -398.619324)
			(xy 422.679051 -398.668754) (xy 422.655455 -398.715064) (xy 422.624905 -398.757112) (xy 422.588154 -398.793863)
			(xy 422.546106 -398.824413) (xy 422.499796 -398.848009) (xy 422.450366 -398.86407) (xy 422.399031 -398.8722)
			(xy 422.347057 -398.8722) (xy 422.295722 -398.86407) (xy 422.246292 -398.848009) (xy 422.199982 -398.824413)
			(xy 422.157934 -398.793863) (xy 422.121183 -398.757112) (xy 422.090633 -398.715064) (xy 422.067037 -398.668754)
			(xy 422.050976 -398.619324) (xy 422.042846 -398.567989) (xy 421.32327 -398.567989) (xy 421.317627 -398.607054)
			(xy 421.311832 -398.628108) (xy 421.3098 -398.63522) (xy 421.3098 -399.807176) (xy 421.310322 -399.817689)
			(xy 421.318714 -399.836971) (xy 421.326056 -399.844514) (xy 421.389048 -399.902426) (xy 421.40886 -399.909284)
			(xy 421.419528 -399.908522) (xy 421.444166 -399.907506) (xy 421.46816 -399.90795) (xy 421.515559 -399.915452)
			(xy 421.561201 -399.930278) (xy 421.60396 -399.952062) (xy 421.642786 -399.980267) (xy 421.67672 -400.014199)
			(xy 421.704928 -400.053023) (xy 421.726714 -400.095781) (xy 421.741543 -400.141421) (xy 421.749049 -400.18882)
			(xy 421.749474 -400.212814) (xy 421.748976 -400.237184) (xy 421.741197 -400.2853) (xy 421.725885 -400.331574)
			(xy 421.70343 -400.374834) (xy 421.689276 -400.394678) (xy 421.683688 -400.402552) (xy 421.678608 -400.420332)
			(xy 421.68699 -400.506946) (xy 421.695118 -400.52371) (xy 421.70223 -400.53006) (xy 421.721354 -400.548202)
			(xy 421.754929 -400.588838) (xy 421.782591 -400.633709) (xy 421.803815 -400.68196) (xy 421.818195 -400.732672)
			(xy 421.825458 -400.784882) (xy 421.825928 -400.811238) (xy 421.825928 -401.461986) (xy 421.826268 -401.470976)
			(xy 421.832468 -401.487853) (xy 421.844138 -401.50153) (xy 421.851836 -401.506182) (xy 421.941244 -401.55622)
			(xy 421.96893 -401.555712) (xy 421.980614 -401.548346) (xy 422.003276 -401.534899) (xy 422.051516 -401.513696)
			(xy 422.10222 -401.499348) (xy 422.154418 -401.492131) (xy 422.180766 -401.491704) (xy 422.20802 -401.492165)
			(xy 422.261972 -401.499918) (xy 422.314273 -401.51527) (xy 422.363856 -401.53791) (xy 422.409712 -401.567376)
			(xy 422.450907 -401.603069) (xy 422.486603 -401.644261) (xy 422.516073 -401.690115) (xy 422.528353 -401.717002)
			(xy 423.860974 -401.717002) (xy 423.865045 -401.66138) (xy 423.877171 -401.606943) (xy 423.897094 -401.554852)
			(xy 423.92439 -401.506217) (xy 423.958476 -401.462074) (xy 423.998625 -401.423365) (xy 424.043983 -401.390914)
			(xy 424.093583 -401.365413) (xy 424.146367 -401.347406) (xy 424.20121 -401.337276) (xy 424.256944 -401.335239)
			(xy 424.312381 -401.341339) (xy 424.366338 -401.355445) (xy 424.417667 -401.377257) (xy 424.465273 -401.406311)
			(xy 424.508141 -401.441986) (xy 424.545358 -401.483523) (xy 424.576131 -401.530036) (xy 424.599803 -401.580533)
			(xy 424.615871 -401.63394) (xy 424.623991 -401.689116) (xy 424.6245 -401.717002) (xy 424.623991 -401.744888)
			(xy 424.615871 -401.800064) (xy 424.599803 -401.853471) (xy 424.576131 -401.903968) (xy 424.545358 -401.950481)
			(xy 424.508141 -401.992018) (xy 424.465273 -402.027693) (xy 424.417667 -402.056747) (xy 424.374379 -402.075142)
			(xy 424.921934 -402.075142) (xy 424.922416 -402.042998) (xy 424.930503 -401.979221) (xy 424.946567 -401.916972)
			(xy 424.970351 -401.857245) (xy 425.001475 -401.800994) (xy 425.039443 -401.749115) (xy 425.083648 -401.702437)
			(xy 425.133386 -401.661705) (xy 425.187862 -401.627569) (xy 425.216828 -401.613624) (xy 425.226539 -401.608563)
			(xy 425.240773 -401.591947) (xy 425.246854 -401.570929) (xy 425.245784 -401.56003) (xy 425.243166 -401.541408)
			(xy 425.240373 -401.503904) (xy 425.240196 -401.4851) (xy 425.240698 -401.453139) (xy 425.248709 -401.389721)
			(xy 425.264606 -401.327807) (xy 425.288138 -401.268374) (xy 425.318932 -401.212359) (xy 425.356505 -401.160644)
			(xy 425.400262 -401.114047) (xy 425.449515 -401.073302) (xy 425.503486 -401.039051) (xy 425.561325 -401.011834)
			(xy 425.622118 -400.992081) (xy 425.684908 -400.980103) (xy 425.748704 -400.97609) (xy 425.8125 -400.980103)
			(xy 425.87529 -400.992081) (xy 425.936083 -401.011834) (xy 425.993922 -401.039051) (xy 426.047893 -401.073302)
			(xy 426.097146 -401.114047) (xy 426.140903 -401.160644) (xy 426.178476 -401.212359) (xy 426.20927 -401.268374)
			(xy 426.232802 -401.327807) (xy 426.248699 -401.389721) (xy 426.25671 -401.453139) (xy 426.257212 -401.4851)
			(xy 426.256739 -401.517244) (xy 426.248647 -401.581021) (xy 426.23258 -401.643268) (xy 426.208794 -401.702994)
			(xy 426.177669 -401.759245) (xy 426.139701 -401.811123) (xy 426.095495 -401.857801) (xy 426.045758 -401.898534)
			(xy 425.991283 -401.932672) (xy 425.962318 -401.946618) (xy 425.952626 -401.951706) (xy 425.938397 -401.968313)
			(xy 425.932304 -401.989317) (xy 425.933362 -402.000212) (xy 425.935973 -402.018835) (xy 425.938771 -402.056338)
			(xy 425.93895 -402.075142) (xy 425.938448 -402.107103) (xy 425.930437 -402.170521) (xy 425.91454 -402.232435)
			(xy 425.891008 -402.291868) (xy 425.860214 -402.347883) (xy 425.822641 -402.399598) (xy 425.778884 -402.446195)
			(xy 425.729631 -402.48694) (xy 425.67566 -402.521191) (xy 425.617821 -402.548408) (xy 425.557028 -402.568161)
			(xy 425.494238 -402.580139) (xy 425.430442 -402.584153) (xy 425.366646 -402.580139) (xy 425.303856 -402.568161)
			(xy 425.243063 -402.548408) (xy 425.185224 -402.521191) (xy 425.131253 -402.48694) (xy 425.082 -402.446195)
			(xy 425.038243 -402.399598) (xy 425.00067 -402.347883) (xy 424.969876 -402.291868) (xy 424.946344 -402.232435)
			(xy 424.930447 -402.170521) (xy 424.922436 -402.107103) (xy 424.921934 -402.075142) (xy 424.374379 -402.075142)
			(xy 424.366338 -402.078559) (xy 424.312381 -402.092665) (xy 424.256944 -402.098765) (xy 424.20121 -402.096728)
			(xy 424.146367 -402.086598) (xy 424.093583 -402.068591) (xy 424.043983 -402.04309) (xy 423.998625 -402.010639)
			(xy 423.958476 -401.97193) (xy 423.92439 -401.927787) (xy 423.897094 -401.879152) (xy 423.877171 -401.827061)
			(xy 423.865045 -401.772624) (xy 423.860974 -401.717002) (xy 422.528353 -401.717002) (xy 422.538718 -401.739695)
			(xy 422.554075 -401.791994) (xy 422.561833 -401.845946) (xy 422.561833 -401.900454) (xy 422.554075 -401.954406)
			(xy 422.538718 -402.006705) (xy 422.516073 -402.056285) (xy 422.486603 -402.102139) (xy 422.450907 -402.143331)
			(xy 422.409712 -402.179024) (xy 422.363856 -402.20849) (xy 422.314273 -402.23113) (xy 422.261972 -402.246482)
			(xy 422.20802 -402.254235) (xy 422.180766 -402.25472) (xy 422.153806 -402.254259) (xy 422.100423 -402.246675)
			(xy 422.048641 -402.231648) (xy 421.99949 -402.209478) (xy 421.953952 -402.180608) (xy 421.912933 -402.145612)
			(xy 421.877252 -402.105188) (xy 421.847619 -402.060142) (xy 421.824625 -402.011371) (xy 421.816276 -401.985734)
			(xy 421.813438 -401.977657) (xy 421.803278 -401.963888) (xy 421.789145 -401.954244) (xy 421.78097 -401.951698)
			(xy 421.72255 -401.93595) (xy 421.712898 -401.945856) (xy 421.706294 -401.95246) (xy 421.698674 -401.969224)
			(xy 421.69334 -402.05533) (xy 421.698674 -402.07311) (xy 421.704516 -402.080476) (xy 421.721042 -402.102451)
			(xy 421.747324 -402.150744) (xy 421.76525 -402.202721) (xy 421.774327 -402.256947) (xy 421.774874 -402.284438)
			(xy 421.774362 -402.310422) (xy 421.766226 -402.36175) (xy 421.750161 -402.411173) (xy 421.726563 -402.457475)
			(xy 421.696012 -402.499515) (xy 421.659261 -402.536259) (xy 421.617214 -402.566801) (xy 421.570907 -402.590389)
			(xy 421.52148 -402.606443) (xy 421.47015 -402.614567) (xy 421.444166 -402.615146) (xy 421.41902 -402.61413)
			(xy 421.408352 -402.613368) (xy 421.38854 -402.620226) (xy 421.326056 -402.678138) (xy 421.318693 -402.685665)
			(xy 421.310315 -402.704957) (xy 421.3098 -402.715476) (xy 421.3098 -404.271437) (xy 428.841656 -404.271437)
			(xy 428.841656 -404.207515) (xy 428.849667 -404.144097) (xy 428.865564 -404.082183) (xy 428.889096 -404.02275)
			(xy 428.91989 -403.966735) (xy 428.957463 -403.91502) (xy 429.00122 -403.868423) (xy 429.050473 -403.827678)
			(xy 429.104444 -403.793427) (xy 429.162283 -403.76621) (xy 429.223076 -403.746457) (xy 429.285866 -403.734479)
			(xy 429.349662 -403.730466) (xy 429.413458 -403.734479) (xy 429.476248 -403.746457) (xy 429.537041 -403.76621)
			(xy 429.59488 -403.793427) (xy 429.648851 -403.827678) (xy 429.698104 -403.868423) (xy 429.741861 -403.91502)
			(xy 429.779434 -403.966735) (xy 429.810228 -404.02275) (xy 429.83376 -404.082183) (xy 429.849657 -404.144097)
			(xy 429.857668 -404.207515) (xy 429.85817 -404.239476) (xy 429.857668 -404.271437) (xy 429.849657 -404.334855)
			(xy 429.83376 -404.396769) (xy 429.810228 -404.456202) (xy 429.779434 -404.512217) (xy 429.741861 -404.563932)
			(xy 429.698104 -404.610529) (xy 429.648851 -404.651274) (xy 429.59488 -404.685525) (xy 429.537041 -404.712742)
			(xy 429.476248 -404.732495) (xy 429.413458 -404.744473) (xy 429.349662 -404.748487) (xy 429.285866 -404.744473)
			(xy 429.223076 -404.732495) (xy 429.162283 -404.712742) (xy 429.104444 -404.685525) (xy 429.050473 -404.651274)
			(xy 429.00122 -404.610529) (xy 428.957463 -404.563932) (xy 428.91989 -404.512217) (xy 428.889096 -404.456202)
			(xy 428.865564 -404.396769) (xy 428.849667 -404.334855) (xy 428.841656 -404.271437) (xy 421.3098 -404.271437)
			(xy 421.3098 -406.518618) (xy 421.310227 -406.528687) (xy 421.317946 -406.547286) (xy 421.324786 -406.554686)
			(xy 422.161462 -407.391362) (xy 422.168809 -407.398167) (xy 422.187272 -407.405883) (xy 422.197276 -407.406348)
			(xy 429.137064 -407.406348) (xy 429.147053 -407.405816) (xy 429.16549 -407.398106) (xy 429.172878 -407.391362)
			(xy 431.449734 -405.114506) (xy 431.456589 -405.107111) (xy 431.464336 -405.088512) (xy 431.46472 -405.078438)
			(xy 431.46472 -388.662418) (xy 431.464361 -388.653338) (xy 431.458022 -388.636323) (xy 431.44611 -388.622619)
			(xy 431.438304 -388.617968) (xy 431.358667 -388.573611) (xy 431.202823 -388.479007) (xy 431.051162 -388.377834)
			(xy 430.903959 -388.270277) (xy 430.761484 -388.156531) (xy 430.623997 -388.036805) (xy 430.491748 -387.911316)
			(xy 430.364978 -387.780294) (xy 430.24392 -387.643978) (xy 430.128793 -387.502617) (xy 430.019809 -387.356467)
			(xy 429.917165 -387.205797) (xy 429.821049 -387.050881) (xy 429.731637 -386.892002) (xy 429.649091 -386.729449)
			(xy 429.573563 -386.563519) (xy 429.50519 -386.394516) (xy 429.444096 -386.222746) (xy 429.390393 -386.048524)
			(xy 429.34418 -385.872168) (xy 429.30554 -385.693999) (xy 429.274545 -385.514343) (xy 429.25125 -385.333526)
			(xy 429.235698 -385.15188) (xy 429.227917 -384.969735) (xy 429.227488 -384.87858) (xy 429.227976 -384.78792)
			(xy 429.235702 -384.606764) (xy 429.251114 -384.4261) (xy 429.274183 -384.246254) (xy 429.304869 -384.067549)
			(xy 429.343115 -383.890308) (xy 429.388854 -383.714852) (xy 429.442001 -383.541496) (xy 429.502463 -383.370553)
			(xy 429.570128 -383.202332) (xy 429.644876 -383.037136) (xy 429.726571 -382.875263) (xy 429.815067 -382.717005)
			(xy 429.910203 -382.562647) (xy 430.011808 -382.412469) (xy 430.119698 -382.266741) (xy 430.233679 -382.125726)
			(xy 430.293272 -382.057402) (xy 430.30648 -382.042162) (xy 430.30521 -382.00203) (xy 429.584866 -381.281686)
			(xy 429.57747 -381.274835) (xy 429.558871 -381.2671) (xy 429.548798 -381.2667) (xy 421.462962 -381.2667)
			(xy 421.452895 -381.26713) (xy 421.434301 -381.274854) (xy 421.426894 -381.281686) (xy 418.802566 -383.906014)
			(xy 418.79517 -383.912865) (xy 418.776571 -383.9206) (xy 418.766498 -383.921) (xy 401.549362 -383.921)
			(xy 401.539295 -383.92143) (xy 401.520701 -383.929154) (xy 401.513294 -383.935986) (xy 401.122024 -384.327256)
			(xy 425.863923 -384.327256) (xy 425.863923 -384.272744) (xy 425.871681 -384.218787) (xy 425.887039 -384.166483)
			(xy 425.909685 -384.116897) (xy 425.939158 -384.071039) (xy 425.974857 -384.029842) (xy 426.016055 -383.994146)
			(xy 426.061915 -383.964676) (xy 426.111502 -383.942032) (xy 426.163806 -383.926677) (xy 426.217764 -383.918922)
			(xy 426.24502 -383.91846) (xy 426.265175 -383.918692) (xy 426.305264 -383.922896) (xy 426.32503 -383.926842)
			(xy 426.336206 -383.929382) (xy 426.35805 -383.924302) (xy 426.437298 -383.86258) (xy 426.447458 -383.842514)
			(xy 426.447966 -383.831084) (xy 426.44937 -383.804466) (xy 426.458601 -383.751972) (xy 426.47505 -383.701274)
			(xy 426.498398 -383.653359) (xy 426.52819 -383.609162) (xy 426.563844 -383.569543) (xy 426.604667 -383.535274)
			(xy 426.649864 -383.507023) (xy 426.698554 -383.485339) (xy 426.749789 -383.470644) (xy 426.80257 -383.463227)
			(xy 426.82922 -383.462784) (xy 426.855942 -383.463226) (xy 426.908861 -383.470699) (xy 426.96022 -383.485482)
			(xy 427.009014 -383.507287) (xy 427.054288 -383.535686) (xy 427.095158 -383.570124) (xy 427.130823 -383.609927)
			(xy 427.160586 -383.654317) (xy 427.172628 -383.678176) (xy 427.176692 -383.686558) (xy 427.190154 -383.699512)
			(xy 427.269656 -383.732532) (xy 427.288198 -383.73304) (xy 427.297088 -383.729992) (xy 427.327174 -383.720394)
			(xy 427.389467 -383.710053) (xy 427.42104 -383.709418) (xy 427.448293 -383.709841) (xy 427.502245 -383.717603)
			(xy 427.554542 -383.732965) (xy 427.604121 -383.755613) (xy 427.649973 -383.785085) (xy 427.691163 -383.820783)
			(xy 427.726854 -383.86198) (xy 427.756319 -383.907837) (xy 427.778958 -383.95742) (xy 427.794311 -384.00972)
			(xy 427.802064 -384.063673) (xy 427.802548 -384.090926) (xy 427.802101 -384.118224) (xy 427.794302 -384.17226)
			(xy 427.778881 -384.224633) (xy 427.756153 -384.274274) (xy 427.726582 -384.320168) (xy 427.690772 -384.361379)
			(xy 427.649454 -384.397066) (xy 427.603471 -384.4265) (xy 427.553763 -384.449079) (xy 427.501344 -384.464344)
			(xy 427.47438 -384.468624) (xy 427.46623 -384.470158) (xy 427.451455 -384.477665) (xy 427.445424 -384.483356)
			(xy 427.42485 -384.504184) (xy 427.419136 -384.510452) (xy 427.411869 -384.525766) (xy 427.410626 -384.534156)
			(xy 427.406845 -384.562958) (xy 427.393562 -384.619511) (xy 427.373929 -384.674185) (xy 427.348201 -384.72627)
			(xy 427.316713 -384.775088) (xy 427.298612 -384.797808) (xy 427.293304 -384.804799) (xy 427.287337 -384.821297)
			(xy 427.286928 -384.830066) (xy 427.286928 -384.98399) (xy 427.287308 -384.992765) (xy 427.293282 -385.009267)
			(xy 427.298612 -385.016248) (xy 427.316595 -385.038834) (xy 427.347914 -385.087337) (xy 427.361096 -385.113022)
			(xy 427.36548 -385.120973) (xy 427.378766 -385.133332) (xy 427.387004 -385.137152) (xy 427.415198 -385.14909)
			(xy 427.423579 -385.152134) (xy 427.44138 -385.152912) (xy 427.449996 -385.150614) (xy 427.478204 -385.142174)
			(xy 427.536381 -385.133122) (xy 427.56582 -385.13258) (xy 427.593069 -385.133092) (xy 427.647013 -385.14085)
			(xy 427.699304 -385.156207) (xy 427.748877 -385.178848) (xy 427.794723 -385.208314) (xy 427.83591 -385.244004)
			(xy 427.871598 -385.285193) (xy 427.901062 -385.331041) (xy 427.9237 -385.380615) (xy 427.939054 -385.432906)
			(xy 427.94681 -385.486851) (xy 427.94681 -385.541349) (xy 427.939054 -385.595294) (xy 427.9237 -385.647585)
			(xy 427.901062 -385.697159) (xy 427.871598 -385.743007) (xy 427.83591 -385.784196) (xy 427.794723 -385.819886)
			(xy 427.748877 -385.849352) (xy 427.699304 -385.871993) (xy 427.647013 -385.88735) (xy 427.593069 -385.895108)
			(xy 427.56582 -385.895596) (xy 427.541748 -385.895248) (xy 427.493985 -385.889204) (xy 427.44736 -385.87721)
			(xy 427.42485 -385.868672) (xy 427.412404 -385.863592) (xy 427.386496 -385.866894) (xy 427.295818 -385.933696)
			(xy 427.284896 -385.957318) (xy 427.285912 -385.970526) (xy 427.286928 -385.999228) (xy 427.286442 -386.026479)
			(xy 427.278686 -386.080427) (xy 427.263331 -386.132722) (xy 427.240689 -386.182299) (xy 427.211223 -386.228149)
			(xy 427.175532 -386.26934) (xy 427.134341 -386.305031) (xy 427.088491 -386.334497) (xy 427.038914 -386.357139)
			(xy 426.986619 -386.372494) (xy 426.932671 -386.38025) (xy 426.878169 -386.38025) (xy 426.824221 -386.372494)
			(xy 426.771926 -386.357139) (xy 426.722349 -386.334497) (xy 426.676499 -386.305031) (xy 426.635308 -386.26934)
			(xy 426.599617 -386.228149) (xy 426.570151 -386.182299) (xy 426.547509 -386.132722) (xy 426.532154 -386.080427)
			(xy 426.524398 -386.026479) (xy 426.523912 -385.999228) (xy 426.524928 -385.970526) (xy 426.525944 -385.957318)
			(xy 426.515022 -385.933696) (xy 426.424344 -385.866894) (xy 426.398436 -385.863592) (xy 426.38599 -385.868672)
			(xy 426.36348 -385.877211) (xy 426.316857 -385.889213) (xy 426.269092 -385.895245) (xy 426.24502 -385.895596)
			(xy 426.217765 -385.895158) (xy 426.16381 -385.887404) (xy 426.111509 -385.872049) (xy 426.061924 -385.849407)
			(xy 426.016067 -385.819938) (xy 425.974871 -385.784243) (xy 425.939174 -385.743049) (xy 425.909703 -385.697193)
			(xy 425.887058 -385.64761) (xy 425.871701 -385.595309) (xy 425.863943 -385.541355) (xy 425.863943 -385.486845)
			(xy 425.871701 -385.432891) (xy 425.887058 -385.38059) (xy 425.909703 -385.331007) (xy 425.939174 -385.285151)
			(xy 425.974871 -385.243957) (xy 426.016067 -385.208262) (xy 426.061924 -385.178793) (xy 426.111509 -385.156151)
			(xy 426.16381 -385.140796) (xy 426.217765 -385.133042) (xy 426.24502 -385.13258) (xy 426.274456 -385.133149)
			(xy 426.33263 -385.142201) (xy 426.360844 -385.150614) (xy 426.369454 -385.152972) (xy 426.387276 -385.152202)
			(xy 426.395642 -385.14909) (xy 426.423836 -385.137152) (xy 426.432067 -385.133324) (xy 426.445341 -385.12096)
			(xy 426.449744 -385.113022) (xy 426.46291 -385.087327) (xy 426.494228 -385.038822) (xy 426.512228 -385.016248)
			(xy 426.517507 -385.009237) (xy 426.523493 -384.992755) (xy 426.523912 -384.98399) (xy 426.523912 -384.830066)
			(xy 426.523565 -384.821287) (xy 426.51757 -384.804785) (xy 426.512228 -384.797808) (xy 426.494243 -384.775224)
			(xy 426.462926 -384.72672) (xy 426.449744 -384.701034) (xy 426.44533 -384.693102) (xy 426.432066 -384.680732)
			(xy 426.423836 -384.676904) (xy 426.395642 -384.664966) (xy 426.387255 -384.661941) (xy 426.369459 -384.66115)
			(xy 426.360844 -384.663442) (xy 426.332633 -384.671872) (xy 426.274458 -384.680931) (xy 426.24502 -384.681476)
			(xy 426.217764 -384.681078) (xy 426.163806 -384.673323) (xy 426.111502 -384.657968) (xy 426.061915 -384.635324)
			(xy 426.016055 -384.605854) (xy 425.974857 -384.570158) (xy 425.939158 -384.528961) (xy 425.909685 -384.483103)
			(xy 425.887039 -384.433517) (xy 425.871681 -384.381213) (xy 425.863923 -384.327256) (xy 401.122024 -384.327256)
			(xy 397.718424 -387.730856) (xy 425.863923 -387.730856) (xy 425.863923 -387.676344) (xy 425.871681 -387.622387)
			(xy 425.887039 -387.570083) (xy 425.909685 -387.520497) (xy 425.939158 -387.474639) (xy 425.974857 -387.433442)
			(xy 426.016055 -387.397746) (xy 426.061915 -387.368276) (xy 426.111502 -387.345632) (xy 426.163806 -387.330277)
			(xy 426.217764 -387.322522) (xy 426.24502 -387.32206) (xy 426.269091 -387.322423) (xy 426.316854 -387.32846)
			(xy 426.36348 -387.340448) (xy 426.38599 -387.348984) (xy 426.398436 -387.354064) (xy 426.424344 -387.350762)
			(xy 426.515022 -387.28396) (xy 426.525944 -387.260338) (xy 426.524928 -387.24713) (xy 426.523912 -387.218428)
			(xy 426.524398 -387.191177) (xy 426.532154 -387.137229) (xy 426.547509 -387.084934) (xy 426.570151 -387.035357)
			(xy 426.599617 -386.989507) (xy 426.635308 -386.948316) (xy 426.676499 -386.912625) (xy 426.722349 -386.883159)
			(xy 426.771926 -386.860517) (xy 426.824221 -386.845162) (xy 426.878169 -386.837406) (xy 426.932671 -386.837406)
			(xy 426.986619 -386.845162) (xy 427.038914 -386.860517) (xy 427.088491 -386.883159) (xy 427.134341 -386.912625)
			(xy 427.175532 -386.948316) (xy 427.211223 -386.989507) (xy 427.240689 -387.035357) (xy 427.263331 -387.084934)
			(xy 427.278686 -387.137229) (xy 427.286442 -387.191177) (xy 427.286928 -387.218428) (xy 427.285912 -387.24713)
			(xy 427.284896 -387.260338) (xy 427.295818 -387.28396) (xy 427.386496 -387.350762) (xy 427.412404 -387.354064)
			(xy 427.42485 -387.348984) (xy 427.447357 -387.340436) (xy 427.493982 -387.328436) (xy 427.541747 -387.322409)
			(xy 427.56582 -387.32206) (xy 427.593068 -387.322612) (xy 427.647009 -387.33037) (xy 427.699297 -387.345725)
			(xy 427.748867 -387.368366) (xy 427.794711 -387.39783) (xy 427.835896 -387.433518) (xy 427.871582 -387.474705)
			(xy 427.901044 -387.52055) (xy 427.923682 -387.570122) (xy 427.939035 -387.622411) (xy 427.94679 -387.676352)
			(xy 427.94679 -387.730848) (xy 427.939035 -387.784789) (xy 427.923682 -387.837078) (xy 427.901044 -387.88665)
			(xy 427.871582 -387.932495) (xy 427.835896 -387.973682) (xy 427.794711 -388.00937) (xy 427.748867 -388.038834)
			(xy 427.699297 -388.061475) (xy 427.647009 -388.07683) (xy 427.593068 -388.084588) (xy 427.56582 -388.085076)
			(xy 427.536383 -388.084522) (xy 427.478209 -388.07546) (xy 427.449996 -388.067042) (xy 427.441392 -388.064656)
			(xy 427.423564 -388.065445) (xy 427.415198 -388.068566) (xy 427.387004 -388.080504) (xy 427.378769 -388.084326)
			(xy 427.365496 -388.096693) (xy 427.361096 -388.104634) (xy 427.347933 -388.130331) (xy 427.316613 -388.178835)
			(xy 427.298612 -388.201408) (xy 427.293304 -388.208399) (xy 427.287337 -388.224897) (xy 427.286928 -388.233666)
			(xy 427.286928 -388.38759) (xy 427.287308 -388.396365) (xy 427.293282 -388.412867) (xy 427.298612 -388.419848)
			(xy 427.316595 -388.442434) (xy 427.347914 -388.490937) (xy 427.361096 -388.516622) (xy 427.36548 -388.524573)
			(xy 427.378766 -388.536932) (xy 427.387004 -388.540752) (xy 427.415198 -388.55269) (xy 427.423579 -388.555734)
			(xy 427.44138 -388.556512) (xy 427.449996 -388.554214) (xy 427.478204 -388.545774) (xy 427.536381 -388.536722)
			(xy 427.56582 -388.53618) (xy 427.593069 -388.536692) (xy 427.647013 -388.54445) (xy 427.699304 -388.559807)
			(xy 427.748877 -388.582448) (xy 427.794723 -388.611914) (xy 427.83591 -388.647604) (xy 427.871598 -388.688793)
			(xy 427.901062 -388.734641) (xy 427.9237 -388.784215) (xy 427.939054 -388.836506) (xy 427.94681 -388.890451)
			(xy 427.94681 -388.944949) (xy 427.939054 -388.998894) (xy 427.9237 -389.051185) (xy 427.901062 -389.100759)
			(xy 427.871598 -389.146607) (xy 427.83591 -389.187796) (xy 427.794723 -389.223486) (xy 427.748877 -389.252952)
			(xy 427.699304 -389.275593) (xy 427.647013 -389.29095) (xy 427.593069 -389.298708) (xy 427.56582 -389.299196)
			(xy 427.541748 -389.298848) (xy 427.493985 -389.292804) (xy 427.44736 -389.28081) (xy 427.42485 -389.272272)
			(xy 427.412404 -389.267192) (xy 427.386496 -389.270494) (xy 427.295818 -389.337296) (xy 427.284896 -389.360918)
			(xy 427.285912 -389.374126) (xy 427.286928 -389.402828) (xy 427.286442 -389.430079) (xy 427.278686 -389.484027)
			(xy 427.263331 -389.536322) (xy 427.240689 -389.585899) (xy 427.211223 -389.631749) (xy 427.175532 -389.67294)
			(xy 427.134341 -389.708631) (xy 427.088491 -389.738097) (xy 427.038914 -389.760739) (xy 426.986619 -389.776094)
			(xy 426.932671 -389.78385) (xy 426.878169 -389.78385) (xy 426.824221 -389.776094) (xy 426.771926 -389.760739)
			(xy 426.722349 -389.738097) (xy 426.676499 -389.708631) (xy 426.635308 -389.67294) (xy 426.599617 -389.631749)
			(xy 426.570151 -389.585899) (xy 426.547509 -389.536322) (xy 426.532154 -389.484027) (xy 426.524398 -389.430079)
			(xy 426.523912 -389.402828) (xy 426.524928 -389.374126) (xy 426.525944 -389.360918) (xy 426.515022 -389.337296)
			(xy 426.424344 -389.270494) (xy 426.398436 -389.267192) (xy 426.38599 -389.272272) (xy 426.36348 -389.280811)
			(xy 426.316857 -389.292813) (xy 426.269092 -389.298845) (xy 426.24502 -389.299196) (xy 426.217765 -389.298758)
			(xy 426.16381 -389.291004) (xy 426.111509 -389.275649) (xy 426.061924 -389.253007) (xy 426.016067 -389.223538)
			(xy 425.974871 -389.187843) (xy 425.939174 -389.146649) (xy 425.909703 -389.100793) (xy 425.887058 -389.05121)
			(xy 425.871701 -388.998909) (xy 425.863943 -388.944955) (xy 425.863943 -388.890445) (xy 425.871701 -388.836491)
			(xy 425.887058 -388.78419) (xy 425.909703 -388.734607) (xy 425.939174 -388.688751) (xy 425.974871 -388.647557)
			(xy 426.016067 -388.611862) (xy 426.061924 -388.582393) (xy 426.111509 -388.559751) (xy 426.16381 -388.544396)
			(xy 426.217765 -388.536642) (xy 426.24502 -388.53618) (xy 426.274456 -388.536749) (xy 426.33263 -388.545801)
			(xy 426.360844 -388.554214) (xy 426.369454 -388.556572) (xy 426.387276 -388.555802) (xy 426.395642 -388.55269)
			(xy 426.423836 -388.540752) (xy 426.432067 -388.536924) (xy 426.445341 -388.52456) (xy 426.449744 -388.516622)
			(xy 426.46291 -388.490927) (xy 426.494228 -388.442422) (xy 426.512228 -388.419848) (xy 426.517507 -388.412837)
			(xy 426.523493 -388.396355) (xy 426.523912 -388.38759) (xy 426.523912 -388.233666) (xy 426.523565 -388.224887)
			(xy 426.51757 -388.208385) (xy 426.512228 -388.201408) (xy 426.494243 -388.178824) (xy 426.462926 -388.13032)
			(xy 426.449744 -388.104634) (xy 426.44533 -388.096702) (xy 426.432066 -388.084332) (xy 426.423836 -388.080504)
			(xy 426.395642 -388.068566) (xy 426.387255 -388.065541) (xy 426.369459 -388.06475) (xy 426.360844 -388.067042)
			(xy 426.332633 -388.075472) (xy 426.274458 -388.084531) (xy 426.24502 -388.085076) (xy 426.217764 -388.084678)
			(xy 426.163806 -388.076923) (xy 426.111502 -388.061568) (xy 426.061915 -388.038924) (xy 426.016055 -388.009454)
			(xy 425.974857 -387.973758) (xy 425.939158 -387.932561) (xy 425.909685 -387.886703) (xy 425.887039 -387.837117)
			(xy 425.871681 -387.784813) (xy 425.863923 -387.730856) (xy 397.718424 -387.730856) (xy 396.2908 -389.15848)
			(xy 396.283803 -389.166119) (xy 396.276076 -389.185316) (xy 396.276553 -389.206005) (xy 396.280386 -389.21563)
			(xy 396.326868 -389.316722) (xy 396.354046 -389.332978) (xy 396.370048 -389.331708) (xy 396.397988 -389.330692)
			(xy 396.421923 -389.331069) (xy 396.469417 -389.337058) (xy 396.515792 -389.348931) (xy 396.538196 -389.357362)
			(xy 396.550134 -389.362188) (xy 396.575026 -389.35914) (xy 396.665958 -389.295894) (xy 396.677134 -389.273796)
			(xy 396.67688 -389.260588) (xy 396.67688 -389.25246) (xy 396.677366 -389.225209) (xy 396.685122 -389.171261)
			(xy 396.700477 -389.118966) (xy 396.723119 -389.069389) (xy 396.752585 -389.023539) (xy 396.788276 -388.982348)
			(xy 396.829467 -388.946657) (xy 396.875317 -388.917191) (xy 396.924894 -388.894549) (xy 396.977189 -388.879194)
			(xy 397.031137 -388.871438) (xy 397.085639 -388.871438) (xy 397.139587 -388.879194) (xy 397.191882 -388.894549)
			(xy 397.241459 -388.917191) (xy 397.287309 -388.946657) (xy 397.3285 -388.982348) (xy 397.364191 -389.023539)
			(xy 397.393657 -389.069389) (xy 397.416299 -389.118966) (xy 397.431654 -389.171261) (xy 397.43941 -389.225209)
			(xy 397.439896 -389.25246) (xy 397.439896 -389.260588) (xy 397.439642 -389.273796) (xy 397.450818 -389.295894)
			(xy 397.54175 -389.35914) (xy 397.566642 -389.362188) (xy 397.57858 -389.357362) (xy 397.600973 -389.348896)
			(xy 397.64735 -389.337012) (xy 397.69485 -389.331035) (xy 397.718788 -389.330692) (xy 397.746041 -389.331155)
			(xy 397.799994 -389.33891) (xy 397.852293 -389.354265) (xy 397.901875 -389.376907) (xy 397.9098 -389.382)
			(xy 398.964402 -389.382) (xy 398.968473 -389.326378) (xy 398.980599 -389.271941) (xy 399.000522 -389.21985)
			(xy 399.027818 -389.171215) (xy 399.061904 -389.127072) (xy 399.102053 -389.088363) (xy 399.147411 -389.055912)
			(xy 399.197011 -389.030411) (xy 399.249795 -389.012404) (xy 399.304638 -389.002274) (xy 399.360372 -389.000237)
			(xy 399.415809 -389.006337) (xy 399.469766 -389.020443) (xy 399.521095 -389.042255) (xy 399.568701 -389.071309)
			(xy 399.611569 -389.106984) (xy 399.648786 -389.148521) (xy 399.679559 -389.195034) (xy 399.703231 -389.245531)
			(xy 399.719299 -389.298938) (xy 399.727419 -389.354114) (xy 399.727928 -389.382) (xy 399.727501 -389.405368)
			(xy 424.720002 -389.405368) (xy 424.724073 -389.349746) (xy 424.736199 -389.295309) (xy 424.756122 -389.243218)
			(xy 424.783418 -389.194583) (xy 424.817504 -389.15044) (xy 424.857653 -389.111731) (xy 424.903011 -389.07928)
			(xy 424.952611 -389.053779) (xy 425.005395 -389.035772) (xy 425.060238 -389.025642) (xy 425.115972 -389.023605)
			(xy 425.171409 -389.029705) (xy 425.225366 -389.043811) (xy 425.276695 -389.065623) (xy 425.324301 -389.094677)
			(xy 425.367169 -389.130352) (xy 425.404386 -389.171889) (xy 425.435159 -389.218402) (xy 425.458831 -389.268899)
			(xy 425.474899 -389.322306) (xy 425.483019 -389.377482) (xy 425.483528 -389.405368) (xy 425.483019 -389.433254)
			(xy 425.474899 -389.48843) (xy 425.458831 -389.541837) (xy 425.435159 -389.592334) (xy 425.404386 -389.638847)
			(xy 425.367169 -389.680384) (xy 425.324301 -389.716059) (xy 425.276695 -389.745113) (xy 425.225366 -389.766925)
			(xy 425.171409 -389.781031) (xy 425.115972 -389.787131) (xy 425.060238 -389.785094) (xy 425.005395 -389.774964)
			(xy 424.952611 -389.756957) (xy 424.903011 -389.731456) (xy 424.857653 -389.699005) (xy 424.817504 -389.660296)
			(xy 424.783418 -389.616153) (xy 424.756122 -389.567518) (xy 424.736199 -389.515427) (xy 424.724073 -389.46099)
			(xy 424.720002 -389.405368) (xy 399.727501 -389.405368) (xy 399.727419 -389.409886) (xy 399.719299 -389.465062)
			(xy 399.703231 -389.518469) (xy 399.679559 -389.568966) (xy 399.648786 -389.615479) (xy 399.611569 -389.657016)
			(xy 399.568701 -389.692691) (xy 399.521095 -389.721745) (xy 399.469766 -389.743557) (xy 399.415809 -389.757663)
			(xy 399.360372 -389.763763) (xy 399.304638 -389.761726) (xy 399.249795 -389.751596) (xy 399.197011 -389.733589)
			(xy 399.147411 -389.708088) (xy 399.102053 -389.675637) (xy 399.061904 -389.636928) (xy 399.027818 -389.592785)
			(xy 399.000522 -389.54415) (xy 398.980599 -389.492059) (xy 398.968473 -389.437622) (xy 398.964402 -389.382)
			(xy 397.9098 -389.382) (xy 397.947729 -389.406375) (xy 397.988923 -389.442068) (xy 398.024618 -389.483261)
			(xy 398.054087 -389.529115) (xy 398.076731 -389.578696) (xy 398.092087 -389.630995) (xy 398.099845 -389.684947)
			(xy 398.099845 -389.739453) (xy 398.092087 -389.793405) (xy 398.076731 -389.845704) (xy 398.054087 -389.895285)
			(xy 398.024618 -389.941139) (xy 397.988923 -389.982332) (xy 397.947729 -390.018025) (xy 397.901875 -390.047493)
			(xy 397.852293 -390.070135) (xy 397.799994 -390.08549) (xy 397.746041 -390.093245) (xy 397.718788 -390.093708)
			(xy 397.68935 -390.093164) (xy 397.631174 -390.084106) (xy 397.602964 -390.075674) (xy 397.594349 -390.073382)
			(xy 397.576552 -390.07417) (xy 397.568166 -390.077198) (xy 397.539972 -390.089136) (xy 397.531737 -390.092959)
			(xy 397.518456 -390.10532) (xy 397.514064 -390.113266) (xy 397.500882 -390.138951) (xy 397.469562 -390.187454)
			(xy 397.45158 -390.21004) (xy 397.446243 -390.217018) (xy 397.440257 -390.233521) (xy 397.439896 -390.242298)
			(xy 397.439896 -390.396222) (xy 397.440305 -390.404991) (xy 397.446275 -390.421487) (xy 397.45158 -390.42848)
			(xy 397.469582 -390.451052) (xy 397.500905 -390.499555) (xy 397.514064 -390.525254) (xy 397.518461 -390.533199)
			(xy 397.53173 -390.545577) (xy 397.539972 -390.549384) (xy 397.568166 -390.561322) (xy 397.576532 -390.564431)
			(xy 397.594353 -390.565198) (xy 397.602964 -390.562846) (xy 397.631178 -390.554433) (xy 397.689352 -390.545382)
			(xy 397.718788 -390.544812) (xy 397.74604 -390.545274) (xy 397.799989 -390.55303) (xy 397.852286 -390.568384)
			(xy 397.901865 -390.591024) (xy 397.947717 -390.620491) (xy 397.978029 -390.646755) (xy 424.720943 -390.646755)
			(xy 424.720943 -390.592245) (xy 424.728701 -390.538291) (xy 424.744058 -390.48599) (xy 424.766703 -390.436407)
			(xy 424.796174 -390.390551) (xy 424.831871 -390.349357) (xy 424.873067 -390.313662) (xy 424.918924 -390.284193)
			(xy 424.968509 -390.261551) (xy 425.02081 -390.246196) (xy 425.074765 -390.238442) (xy 425.10202 -390.23798)
			(xy 425.127704 -390.23843) (xy 425.178604 -390.245342) (xy 425.228116 -390.259026) (xy 425.275343 -390.279233)
			(xy 425.319429 -390.305598) (xy 425.339764 -390.321292) (xy 425.347892 -390.327642) (xy 425.366942 -390.332976)
			(xy 425.458382 -390.32307) (xy 425.475654 -390.313418) (xy 425.482258 -390.305544) (xy 425.50298 -390.280621)
			(xy 425.549752 -390.235749) (xy 425.601849 -390.197186) (xy 425.658426 -390.16556) (xy 425.718565 -390.141383)
			(xy 425.781289 -390.125047) (xy 425.845582 -390.116818) (xy 425.87799 -390.116314) (xy 425.909954 -390.11675)
			(xy 425.973378 -390.124762) (xy 426.035299 -390.140659) (xy 426.094738 -390.164192) (xy 426.150759 -390.194988)
			(xy 426.202479 -390.232564) (xy 426.249081 -390.276325) (xy 426.289831 -390.325583) (xy 426.324085 -390.379559)
			(xy 426.351305 -390.437403) (xy 426.37106 -390.498202) (xy 426.383039 -390.560998) (xy 426.387054 -390.6248)
			(xy 426.383184 -390.68629) (xy 427.39767 -390.68629) (xy 427.401741 -390.630668) (xy 427.413867 -390.576231)
			(xy 427.43379 -390.52414) (xy 427.461086 -390.475505) (xy 427.495172 -390.431362) (xy 427.535321 -390.392653)
			(xy 427.580679 -390.360202) (xy 427.630279 -390.334701) (xy 427.683063 -390.316694) (xy 427.737906 -390.306564)
			(xy 427.79364 -390.304527) (xy 427.849077 -390.310627) (xy 427.903034 -390.324733) (xy 427.954363 -390.346545)
			(xy 428.001969 -390.375599) (xy 428.044837 -390.411274) (xy 428.082054 -390.452811) (xy 428.112827 -390.499324)
			(xy 428.136499 -390.549821) (xy 428.152567 -390.603228) (xy 428.160687 -390.658404) (xy 428.161196 -390.68629)
			(xy 428.160687 -390.714176) (xy 428.152567 -390.769352) (xy 428.136499 -390.822759) (xy 428.112827 -390.873256)
			(xy 428.082054 -390.919769) (xy 428.044837 -390.961306) (xy 428.001969 -390.996981) (xy 427.954363 -391.026035)
			(xy 427.903034 -391.047847) (xy 427.849077 -391.061953) (xy 427.79364 -391.068053) (xy 427.737906 -391.066016)
			(xy 427.683063 -391.055886) (xy 427.630279 -391.037879) (xy 427.580679 -391.012378) (xy 427.535321 -390.979927)
			(xy 427.495172 -390.941218) (xy 427.461086 -390.897075) (xy 427.43379 -390.84844) (xy 427.413867 -390.796349)
			(xy 427.401741 -390.741912) (xy 427.39767 -390.68629) (xy 426.383184 -390.68629) (xy 426.383039 -390.688602)
			(xy 426.37106 -390.751398) (xy 426.351305 -390.812197) (xy 426.324085 -390.870041) (xy 426.289831 -390.924017)
			(xy 426.249081 -390.973275) (xy 426.202479 -391.017036) (xy 426.150759 -391.054612) (xy 426.094738 -391.085408)
			(xy 426.035299 -391.108941) (xy 425.973378 -391.124838) (xy 425.909954 -391.13285) (xy 425.87799 -391.13333)
			(xy 425.845091 -391.132796) (xy 425.77984 -391.124319) (xy 425.716229 -391.107494) (xy 425.65532 -391.082604)
			(xy 425.598131 -391.050064) (xy 425.545618 -391.010417) (xy 425.498659 -390.964327) (xy 425.47794 -390.938766)
			(xy 425.47159 -390.930638) (xy 425.454318 -390.920732) (xy 425.362878 -390.909556) (xy 425.343828 -390.914636)
			(xy 425.3357 -390.920986) (xy 425.315568 -390.936087) (xy 425.27209 -390.961433) (xy 425.225656 -390.980839)
			(xy 425.177072 -390.993968) (xy 425.127183 -391.000591) (xy 425.10202 -391.000996) (xy 425.074765 -391.000558)
			(xy 425.02081 -390.992804) (xy 424.968509 -390.977449) (xy 424.918924 -390.954807) (xy 424.873067 -390.925338)
			(xy 424.831871 -390.889643) (xy 424.796174 -390.848449) (xy 424.766703 -390.802593) (xy 424.744058 -390.75301)
			(xy 424.728701 -390.700709) (xy 424.720943 -390.646755) (xy 397.978029 -390.646755) (xy 397.988909 -390.656182)
			(xy 398.024602 -390.697373) (xy 398.05407 -390.743224) (xy 398.076712 -390.792803) (xy 398.092068 -390.845099)
			(xy 398.099825 -390.899048) (xy 398.099825 -390.953552) (xy 398.092068 -391.007501) (xy 398.076712 -391.059797)
			(xy 398.05407 -391.109376) (xy 398.024602 -391.155227) (xy 397.988909 -391.196418) (xy 397.947717 -391.232109)
			(xy 397.901865 -391.261576) (xy 397.852286 -391.284216) (xy 397.799989 -391.29957) (xy 397.74604 -391.307326)
			(xy 397.718788 -391.307828) (xy 397.694716 -391.307477) (xy 397.646951 -391.301446) (xy 397.600328 -391.289442)
			(xy 397.577818 -391.280904) (xy 397.565372 -391.275824) (xy 397.539464 -391.279126) (xy 397.490373 -391.315291)
			(xy 400.656761 -391.315291) (xy 400.656761 -391.263309) (xy 400.664893 -391.211968) (xy 400.680956 -391.162531)
			(xy 400.704556 -391.116215) (xy 400.73511 -391.074162) (xy 400.771866 -391.037406) (xy 400.81392 -391.006852)
			(xy 400.860236 -390.983254) (xy 400.909674 -390.967192) (xy 400.961015 -390.959061) (xy 400.987006 -390.958578)
			(xy 401.010204 -390.958963) (xy 401.056144 -390.965454) (xy 401.100728 -390.978295) (xy 401.143084 -390.997234)
			(xy 401.18238 -391.021899) (xy 401.200366 -391.036556) (xy 401.207478 -391.042652) (xy 401.225004 -391.048748)
			(xy 401.310602 -391.04697) (xy 401.327874 -391.039858) (xy 401.334732 -391.033508) (xy 401.353151 -391.017162)
			(xy 401.393931 -390.989558) (xy 401.438354 -390.968305) (xy 401.485436 -390.953873) (xy 401.534138 -390.94658)
			(xy 401.55876 -390.946132) (xy 401.583597 -390.946581) (xy 401.632714 -390.954) (xy 401.680166 -390.968691)
			(xy 401.724882 -390.990322) (xy 401.765854 -391.018407) (xy 401.784312 -391.035032) (xy 401.79139 -391.041056)
			(xy 401.80857 -391.0481) (xy 401.81784 -391.048748) (xy 401.849082 -391.04951) (xy 401.858337 -391.049352)
			(xy 401.87579 -391.043228) (xy 401.883118 -391.037572) (xy 401.905652 -391.019367) (xy 401.955793 -390.990359)
			(xy 402.010216 -390.970517) (xy 402.06726 -390.960444) (xy 402.096224 -390.959848) (xy 402.122206 -390.960448)
			(xy 402.173531 -390.96858) (xy 402.222952 -390.984641) (xy 402.269252 -391.008235) (xy 402.311291 -391.038781)
			(xy 402.348034 -391.075527) (xy 402.378578 -391.117569) (xy 402.402168 -391.16387) (xy 402.418225 -391.213292)
			(xy 402.425768 -391.260917) (xy 403.114004 -391.260917) (xy 403.114004 -391.208943) (xy 403.122134 -391.157608)
			(xy 403.138195 -391.108178) (xy 403.161791 -391.061868) (xy 403.192341 -391.01982) (xy 403.229092 -390.983069)
			(xy 403.27114 -390.952519) (xy 403.31745 -390.928923) (xy 403.36688 -390.912862) (xy 403.418215 -390.904732)
			(xy 403.470189 -390.904732) (xy 403.521524 -390.912862) (xy 403.570954 -390.928923) (xy 403.617264 -390.952519)
			(xy 403.659312 -390.983069) (xy 403.696063 -391.01982) (xy 403.726613 -391.061868) (xy 403.750209 -391.108178)
			(xy 403.76627 -391.157608) (xy 403.7744 -391.208943) (xy 403.77491 -391.23493) (xy 403.7744 -391.260917)
			(xy 404.314154 -391.260917) (xy 404.314154 -391.208943) (xy 404.322284 -391.157608) (xy 404.338345 -391.108178)
			(xy 404.361941 -391.061868) (xy 404.392491 -391.01982) (xy 404.429242 -390.983069) (xy 404.47129 -390.952519)
			(xy 404.5176 -390.928923) (xy 404.56703 -390.912862) (xy 404.618365 -390.904732) (xy 404.670339 -390.904732)
			(xy 404.721674 -390.912862) (xy 404.771104 -390.928923) (xy 404.817414 -390.952519) (xy 404.859462 -390.983069)
			(xy 404.896213 -391.01982) (xy 404.926763 -391.061868) (xy 404.950359 -391.108178) (xy 404.96642 -391.157608)
			(xy 404.97455 -391.208943) (xy 404.97506 -391.23493) (xy 404.97455 -391.260917) (xy 405.51405 -391.260917)
			(xy 405.51405 -391.208943) (xy 405.52218 -391.157608) (xy 405.538241 -391.108178) (xy 405.561837 -391.061868)
			(xy 405.592387 -391.01982) (xy 405.629138 -390.983069) (xy 405.671186 -390.952519) (xy 405.717496 -390.928923)
			(xy 405.766926 -390.912862) (xy 405.818261 -390.904732) (xy 405.870235 -390.904732) (xy 405.92157 -390.912862)
			(xy 405.971 -390.928923) (xy 406.01731 -390.952519) (xy 406.059358 -390.983069) (xy 406.096109 -391.01982)
			(xy 406.126659 -391.061868) (xy 406.150255 -391.108178) (xy 406.166316 -391.157608) (xy 406.174446 -391.208943)
			(xy 406.174956 -391.23493) (xy 406.174446 -391.260917) (xy 406.713946 -391.260917) (xy 406.713946 -391.208943)
			(xy 406.722076 -391.157608) (xy 406.738137 -391.108178) (xy 406.761733 -391.061868) (xy 406.792283 -391.01982)
			(xy 406.829034 -390.983069) (xy 406.871082 -390.952519) (xy 406.917392 -390.928923) (xy 406.966822 -390.912862)
			(xy 407.018157 -390.904732) (xy 407.070131 -390.904732) (xy 407.121466 -390.912862) (xy 407.170896 -390.928923)
			(xy 407.217206 -390.952519) (xy 407.259254 -390.983069) (xy 407.296005 -391.01982) (xy 407.326555 -391.061868)
			(xy 407.350151 -391.108178) (xy 407.366212 -391.157608) (xy 407.374342 -391.208943) (xy 407.374852 -391.23493)
			(xy 407.374342 -391.260917) (xy 407.914096 -391.260917) (xy 407.914096 -391.208943) (xy 407.922226 -391.157608)
			(xy 407.938287 -391.108178) (xy 407.961883 -391.061868) (xy 407.992433 -391.01982) (xy 408.029184 -390.983069)
			(xy 408.071232 -390.952519) (xy 408.117542 -390.928923) (xy 408.166972 -390.912862) (xy 408.218307 -390.904732)
			(xy 408.270281 -390.904732) (xy 408.321616 -390.912862) (xy 408.371046 -390.928923) (xy 408.417356 -390.952519)
			(xy 408.459404 -390.983069) (xy 408.496155 -391.01982) (xy 408.526705 -391.061868) (xy 408.550301 -391.108178)
			(xy 408.566362 -391.157608) (xy 408.574492 -391.208943) (xy 408.575002 -391.23493) (xy 408.574492 -391.260917)
			(xy 409.113992 -391.260917) (xy 409.113992 -391.208943) (xy 409.122122 -391.157608) (xy 409.138183 -391.108178)
			(xy 409.161779 -391.061868) (xy 409.192329 -391.01982) (xy 409.22908 -390.983069) (xy 409.271128 -390.952519)
			(xy 409.317438 -390.928923) (xy 409.366868 -390.912862) (xy 409.418203 -390.904732) (xy 409.470177 -390.904732)
			(xy 409.521512 -390.912862) (xy 409.570942 -390.928923) (xy 409.617252 -390.952519) (xy 409.6593 -390.983069)
			(xy 409.696051 -391.01982) (xy 409.726601 -391.061868) (xy 409.750197 -391.108178) (xy 409.766258 -391.157608)
			(xy 409.774388 -391.208943) (xy 409.774898 -391.23493) (xy 409.774388 -391.260917) (xy 410.314142 -391.260917)
			(xy 410.314142 -391.208943) (xy 410.322272 -391.157608) (xy 410.338333 -391.108178) (xy 410.361929 -391.061868)
			(xy 410.392479 -391.01982) (xy 410.42923 -390.983069) (xy 410.471278 -390.952519) (xy 410.517588 -390.928923)
			(xy 410.567018 -390.912862) (xy 410.618353 -390.904732) (xy 410.670327 -390.904732) (xy 410.721662 -390.912862)
			(xy 410.771092 -390.928923) (xy 410.817402 -390.952519) (xy 410.85945 -390.983069) (xy 410.896201 -391.01982)
			(xy 410.926751 -391.061868) (xy 410.950347 -391.108178) (xy 410.966408 -391.157608) (xy 410.974538 -391.208943)
			(xy 410.975048 -391.23493) (xy 410.974538 -391.260917) (xy 411.514038 -391.260917) (xy 411.514038 -391.208943)
			(xy 411.522168 -391.157608) (xy 411.538229 -391.108178) (xy 411.561825 -391.061868) (xy 411.592375 -391.01982)
			(xy 411.629126 -390.983069) (xy 411.671174 -390.952519) (xy 411.717484 -390.928923) (xy 411.766914 -390.912862)
			(xy 411.818249 -390.904732) (xy 411.870223 -390.904732) (xy 411.921558 -390.912862) (xy 411.970988 -390.928923)
			(xy 412.017298 -390.952519) (xy 412.059346 -390.983069) (xy 412.096097 -391.01982) (xy 412.126647 -391.061868)
			(xy 412.150243 -391.108178) (xy 412.166304 -391.157608) (xy 412.174434 -391.208943) (xy 412.174944 -391.23493)
			(xy 412.174434 -391.260917) (xy 412.713934 -391.260917) (xy 412.713934 -391.208943) (xy 412.722064 -391.157608)
			(xy 412.738125 -391.108178) (xy 412.761721 -391.061868) (xy 412.792271 -391.01982) (xy 412.829022 -390.983069)
			(xy 412.87107 -390.952519) (xy 412.91738 -390.928923) (xy 412.96681 -390.912862) (xy 413.018145 -390.904732)
			(xy 413.070119 -390.904732) (xy 413.121454 -390.912862) (xy 413.170884 -390.928923) (xy 413.217194 -390.952519)
			(xy 413.259242 -390.983069) (xy 413.295993 -391.01982) (xy 413.326543 -391.061868) (xy 413.350139 -391.108178)
			(xy 413.3662 -391.157608) (xy 413.37433 -391.208943) (xy 413.37484 -391.23493) (xy 413.37433 -391.260917)
			(xy 413.914084 -391.260917) (xy 413.914084 -391.208943) (xy 413.922214 -391.157608) (xy 413.938275 -391.108178)
			(xy 413.961871 -391.061868) (xy 413.992421 -391.01982) (xy 414.029172 -390.983069) (xy 414.07122 -390.952519)
			(xy 414.11753 -390.928923) (xy 414.16696 -390.912862) (xy 414.218295 -390.904732) (xy 414.270269 -390.904732)
			(xy 414.321604 -390.912862) (xy 414.371034 -390.928923) (xy 414.417344 -390.952519) (xy 414.459392 -390.983069)
			(xy 414.496143 -391.01982) (xy 414.526693 -391.061868) (xy 414.550289 -391.108178) (xy 414.56635 -391.157608)
			(xy 414.57448 -391.208943) (xy 414.57499 -391.23493) (xy 414.57448 -391.260917) (xy 415.11398 -391.260917)
			(xy 415.11398 -391.208943) (xy 415.12211 -391.157608) (xy 415.138171 -391.108178) (xy 415.161767 -391.061868)
			(xy 415.192317 -391.01982) (xy 415.229068 -390.983069) (xy 415.271116 -390.952519) (xy 415.317426 -390.928923)
			(xy 415.366856 -390.912862) (xy 415.418191 -390.904732) (xy 415.470165 -390.904732) (xy 415.5215 -390.912862)
			(xy 415.57093 -390.928923) (xy 415.61724 -390.952519) (xy 415.659288 -390.983069) (xy 415.696039 -391.01982)
			(xy 415.726589 -391.061868) (xy 415.750185 -391.108178) (xy 415.766246 -391.157608) (xy 415.774376 -391.208943)
			(xy 415.774886 -391.23493) (xy 415.774376 -391.260917) (xy 416.31413 -391.260917) (xy 416.31413 -391.208943)
			(xy 416.32226 -391.157608) (xy 416.338321 -391.108178) (xy 416.361917 -391.061868) (xy 416.392467 -391.01982)
			(xy 416.429218 -390.983069) (xy 416.471266 -390.952519) (xy 416.517576 -390.928923) (xy 416.567006 -390.912862)
			(xy 416.618341 -390.904732) (xy 416.670315 -390.904732) (xy 416.72165 -390.912862) (xy 416.77108 -390.928923)
			(xy 416.81739 -390.952519) (xy 416.859438 -390.983069) (xy 416.896189 -391.01982) (xy 416.926739 -391.061868)
			(xy 416.950335 -391.108178) (xy 416.966396 -391.157608) (xy 416.974526 -391.208943) (xy 416.975036 -391.23493)
			(xy 416.974526 -391.260917) (xy 417.514026 -391.260917) (xy 417.514026 -391.208943) (xy 417.522156 -391.157608)
			(xy 417.538217 -391.108178) (xy 417.561813 -391.061868) (xy 417.592363 -391.01982) (xy 417.629114 -390.983069)
			(xy 417.671162 -390.952519) (xy 417.717472 -390.928923) (xy 417.766902 -390.912862) (xy 417.818237 -390.904732)
			(xy 417.870211 -390.904732) (xy 417.921546 -390.912862) (xy 417.970976 -390.928923) (xy 418.017286 -390.952519)
			(xy 418.059334 -390.983069) (xy 418.096085 -391.01982) (xy 418.126635 -391.061868) (xy 418.150231 -391.108178)
			(xy 418.166292 -391.157608) (xy 418.174422 -391.208943) (xy 418.174932 -391.23493) (xy 418.174422 -391.260917)
			(xy 418.713922 -391.260917) (xy 418.713922 -391.208943) (xy 418.722052 -391.157608) (xy 418.738113 -391.108178)
			(xy 418.761709 -391.061868) (xy 418.792259 -391.01982) (xy 418.82901 -390.983069) (xy 418.871058 -390.952519)
			(xy 418.917368 -390.928923) (xy 418.966798 -390.912862) (xy 419.018133 -390.904732) (xy 419.070107 -390.904732)
			(xy 419.121442 -390.912862) (xy 419.170872 -390.928923) (xy 419.217182 -390.952519) (xy 419.25923 -390.983069)
			(xy 419.295981 -391.01982) (xy 419.326531 -391.061868) (xy 419.350127 -391.108178) (xy 419.366188 -391.157608)
			(xy 419.374318 -391.208943) (xy 419.374828 -391.23493) (xy 419.374318 -391.260917) (xy 419.914072 -391.260917)
			(xy 419.914072 -391.208943) (xy 419.922202 -391.157608) (xy 419.938263 -391.108178) (xy 419.961859 -391.061868)
			(xy 419.992409 -391.01982) (xy 420.02916 -390.983069) (xy 420.071208 -390.952519) (xy 420.117518 -390.928923)
			(xy 420.166948 -390.912862) (xy 420.218283 -390.904732) (xy 420.270257 -390.904732) (xy 420.321592 -390.912862)
			(xy 420.371022 -390.928923) (xy 420.417332 -390.952519) (xy 420.45938 -390.983069) (xy 420.496131 -391.01982)
			(xy 420.526681 -391.061868) (xy 420.550277 -391.108178) (xy 420.566338 -391.157608) (xy 420.574468 -391.208943)
			(xy 420.574978 -391.23493) (xy 420.574468 -391.260917) (xy 421.113968 -391.260917) (xy 421.113968 -391.208943)
			(xy 421.122098 -391.157608) (xy 421.138159 -391.108178) (xy 421.161755 -391.061868) (xy 421.192305 -391.01982)
			(xy 421.229056 -390.983069) (xy 421.271104 -390.952519) (xy 421.317414 -390.928923) (xy 421.366844 -390.912862)
			(xy 421.418179 -390.904732) (xy 421.470153 -390.904732) (xy 421.521488 -390.912862) (xy 421.570918 -390.928923)
			(xy 421.617228 -390.952519) (xy 421.659276 -390.983069) (xy 421.696027 -391.01982) (xy 421.726577 -391.061868)
			(xy 421.750173 -391.108178) (xy 421.766234 -391.157608) (xy 421.774364 -391.208943) (xy 421.774874 -391.23493)
			(xy 421.774364 -391.260917) (xy 421.771945 -391.276193) (xy 422.180945 -391.276193) (xy 422.180945 -391.224207)
			(xy 422.189078 -391.172862) (xy 422.205143 -391.123422) (xy 422.228744 -391.077103) (xy 422.259302 -391.035047)
			(xy 422.296062 -390.998289) (xy 422.33812 -390.967734) (xy 422.38444 -390.944135) (xy 422.433882 -390.928073)
			(xy 422.485227 -390.919944) (xy 422.51122 -390.919462) (xy 422.534995 -390.919841) (xy 422.582056 -390.926649)
			(xy 422.627654 -390.940136) (xy 422.670846 -390.960022) (xy 422.71074 -390.985897) (xy 422.728898 -391.00125)
			(xy 422.736003 -391.006957) (xy 422.753065 -391.013328) (xy 422.762172 -391.013696) (xy 422.793668 -391.013696)
			(xy 422.802767 -391.013286) (xy 422.819817 -391.006923) (xy 422.826942 -391.00125) (xy 422.845126 -390.985933)
			(xy 422.885021 -390.960072) (xy 422.928208 -390.940191) (xy 422.973797 -390.926701) (xy 423.020848 -390.91988)
			(xy 423.04462 -390.919462) (xy 423.070604 -390.920033) (xy 423.121931 -390.928165) (xy 423.171355 -390.944227)
			(xy 423.217657 -390.967821) (xy 423.259699 -390.998369) (xy 423.296444 -391.035116) (xy 423.326989 -391.07716)
			(xy 423.350581 -391.123464) (xy 423.366639 -391.172888) (xy 423.374769 -391.224216) (xy 423.374769 -391.276184)
			(xy 423.366639 -391.327512) (xy 423.350581 -391.376936) (xy 423.326989 -391.42324) (xy 423.296444 -391.465284)
			(xy 423.259699 -391.502031) (xy 423.217657 -391.532579) (xy 423.171355 -391.556173) (xy 423.121931 -391.572235)
			(xy 423.070604 -391.580367) (xy 423.04462 -391.580878) (xy 423.020846 -391.580465) (xy 422.973787 -391.573664)
			(xy 422.92819 -391.560185) (xy 422.884998 -391.540306) (xy 422.845102 -391.514439) (xy 422.826942 -391.49909)
			(xy 422.81983 -391.493393) (xy 422.802773 -391.487018) (xy 422.793668 -391.486644) (xy 422.762172 -391.486644)
			(xy 422.753069 -391.487016) (xy 422.736018 -391.493405) (xy 422.728898 -391.49909) (xy 422.710742 -391.514442)
			(xy 422.670839 -391.540297) (xy 422.627645 -391.56017) (xy 422.58205 -391.573652) (xy 422.534993 -391.580465)
			(xy 422.51122 -391.580878) (xy 422.485227 -391.580456) (xy 422.433882 -391.572327) (xy 422.38444 -391.556265)
			(xy 422.33812 -391.532666) (xy 422.296062 -391.502111) (xy 422.259302 -391.465353) (xy 422.228744 -391.423297)
			(xy 422.205143 -391.376978) (xy 422.189078 -391.327538) (xy 422.180945 -391.276193) (xy 421.771945 -391.276193)
			(xy 421.766234 -391.312252) (xy 421.750173 -391.361682) (xy 421.726577 -391.407992) (xy 421.696027 -391.45004)
			(xy 421.659276 -391.486791) (xy 421.617228 -391.517341) (xy 421.570918 -391.540937) (xy 421.521488 -391.556998)
			(xy 421.470153 -391.565128) (xy 421.418179 -391.565128) (xy 421.366844 -391.556998) (xy 421.317414 -391.540937)
			(xy 421.271104 -391.517341) (xy 421.229056 -391.486791) (xy 421.192305 -391.45004) (xy 421.161755 -391.407992)
			(xy 421.138159 -391.361682) (xy 421.122098 -391.312252) (xy 421.113968 -391.260917) (xy 420.574468 -391.260917)
			(xy 420.566338 -391.312252) (xy 420.550277 -391.361682) (xy 420.526681 -391.407992) (xy 420.496131 -391.45004)
			(xy 420.45938 -391.486791) (xy 420.417332 -391.517341) (xy 420.371022 -391.540937) (xy 420.321592 -391.556998)
			(xy 420.270257 -391.565128) (xy 420.218283 -391.565128) (xy 420.166948 -391.556998) (xy 420.117518 -391.540937)
			(xy 420.071208 -391.517341) (xy 420.02916 -391.486791) (xy 419.992409 -391.45004) (xy 419.961859 -391.407992)
			(xy 419.938263 -391.361682) (xy 419.922202 -391.312252) (xy 419.914072 -391.260917) (xy 419.374318 -391.260917)
			(xy 419.366188 -391.312252) (xy 419.350127 -391.361682) (xy 419.326531 -391.407992) (xy 419.295981 -391.45004)
			(xy 419.25923 -391.486791) (xy 419.217182 -391.517341) (xy 419.170872 -391.540937) (xy 419.121442 -391.556998)
			(xy 419.070107 -391.565128) (xy 419.018133 -391.565128) (xy 418.966798 -391.556998) (xy 418.917368 -391.540937)
			(xy 418.871058 -391.517341) (xy 418.82901 -391.486791) (xy 418.792259 -391.45004) (xy 418.761709 -391.407992)
			(xy 418.738113 -391.361682) (xy 418.722052 -391.312252) (xy 418.713922 -391.260917) (xy 418.174422 -391.260917)
			(xy 418.166292 -391.312252) (xy 418.150231 -391.361682) (xy 418.126635 -391.407992) (xy 418.096085 -391.45004)
			(xy 418.059334 -391.486791) (xy 418.017286 -391.517341) (xy 417.970976 -391.540937) (xy 417.921546 -391.556998)
			(xy 417.870211 -391.565128) (xy 417.818237 -391.565128) (xy 417.766902 -391.556998) (xy 417.717472 -391.540937)
			(xy 417.671162 -391.517341) (xy 417.629114 -391.486791) (xy 417.592363 -391.45004) (xy 417.561813 -391.407992)
			(xy 417.538217 -391.361682) (xy 417.522156 -391.312252) (xy 417.514026 -391.260917) (xy 416.974526 -391.260917)
			(xy 416.966396 -391.312252) (xy 416.950335 -391.361682) (xy 416.926739 -391.407992) (xy 416.896189 -391.45004)
			(xy 416.859438 -391.486791) (xy 416.81739 -391.517341) (xy 416.77108 -391.540937) (xy 416.72165 -391.556998)
			(xy 416.670315 -391.565128) (xy 416.618341 -391.565128) (xy 416.567006 -391.556998) (xy 416.517576 -391.540937)
			(xy 416.471266 -391.517341) (xy 416.429218 -391.486791) (xy 416.392467 -391.45004) (xy 416.361917 -391.407992)
			(xy 416.338321 -391.361682) (xy 416.32226 -391.312252) (xy 416.31413 -391.260917) (xy 415.774376 -391.260917)
			(xy 415.766246 -391.312252) (xy 415.750185 -391.361682) (xy 415.726589 -391.407992) (xy 415.696039 -391.45004)
			(xy 415.659288 -391.486791) (xy 415.61724 -391.517341) (xy 415.57093 -391.540937) (xy 415.5215 -391.556998)
			(xy 415.470165 -391.565128) (xy 415.418191 -391.565128) (xy 415.366856 -391.556998) (xy 415.317426 -391.540937)
			(xy 415.271116 -391.517341) (xy 415.229068 -391.486791) (xy 415.192317 -391.45004) (xy 415.161767 -391.407992)
			(xy 415.138171 -391.361682) (xy 415.12211 -391.312252) (xy 415.11398 -391.260917) (xy 414.57448 -391.260917)
			(xy 414.56635 -391.312252) (xy 414.550289 -391.361682) (xy 414.526693 -391.407992) (xy 414.496143 -391.45004)
			(xy 414.459392 -391.486791) (xy 414.417344 -391.517341) (xy 414.371034 -391.540937) (xy 414.321604 -391.556998)
			(xy 414.270269 -391.565128) (xy 414.218295 -391.565128) (xy 414.16696 -391.556998) (xy 414.11753 -391.540937)
			(xy 414.07122 -391.517341) (xy 414.029172 -391.486791) (xy 413.992421 -391.45004) (xy 413.961871 -391.407992)
			(xy 413.938275 -391.361682) (xy 413.922214 -391.312252) (xy 413.914084 -391.260917) (xy 413.37433 -391.260917)
			(xy 413.3662 -391.312252) (xy 413.350139 -391.361682) (xy 413.326543 -391.407992) (xy 413.295993 -391.45004)
			(xy 413.259242 -391.486791) (xy 413.217194 -391.517341) (xy 413.170884 -391.540937) (xy 413.121454 -391.556998)
			(xy 413.070119 -391.565128) (xy 413.018145 -391.565128) (xy 412.96681 -391.556998) (xy 412.91738 -391.540937)
			(xy 412.87107 -391.517341) (xy 412.829022 -391.486791) (xy 412.792271 -391.45004) (xy 412.761721 -391.407992)
			(xy 412.738125 -391.361682) (xy 412.722064 -391.312252) (xy 412.713934 -391.260917) (xy 412.174434 -391.260917)
			(xy 412.166304 -391.312252) (xy 412.150243 -391.361682) (xy 412.126647 -391.407992) (xy 412.096097 -391.45004)
			(xy 412.059346 -391.486791) (xy 412.017298 -391.517341) (xy 411.970988 -391.540937) (xy 411.921558 -391.556998)
			(xy 411.870223 -391.565128) (xy 411.818249 -391.565128) (xy 411.766914 -391.556998) (xy 411.717484 -391.540937)
			(xy 411.671174 -391.517341) (xy 411.629126 -391.486791) (xy 411.592375 -391.45004) (xy 411.561825 -391.407992)
			(xy 411.538229 -391.361682) (xy 411.522168 -391.312252) (xy 411.514038 -391.260917) (xy 410.974538 -391.260917)
			(xy 410.966408 -391.312252) (xy 410.950347 -391.361682) (xy 410.926751 -391.407992) (xy 410.896201 -391.45004)
			(xy 410.85945 -391.486791) (xy 410.817402 -391.517341) (xy 410.771092 -391.540937) (xy 410.721662 -391.556998)
			(xy 410.670327 -391.565128) (xy 410.618353 -391.565128) (xy 410.567018 -391.556998) (xy 410.517588 -391.540937)
			(xy 410.471278 -391.517341) (xy 410.42923 -391.486791) (xy 410.392479 -391.45004) (xy 410.361929 -391.407992)
			(xy 410.338333 -391.361682) (xy 410.322272 -391.312252) (xy 410.314142 -391.260917) (xy 409.774388 -391.260917)
			(xy 409.766258 -391.312252) (xy 409.750197 -391.361682) (xy 409.726601 -391.407992) (xy 409.696051 -391.45004)
			(xy 409.6593 -391.486791) (xy 409.617252 -391.517341) (xy 409.570942 -391.540937) (xy 409.521512 -391.556998)
			(xy 409.470177 -391.565128) (xy 409.418203 -391.565128) (xy 409.366868 -391.556998) (xy 409.317438 -391.540937)
			(xy 409.271128 -391.517341) (xy 409.22908 -391.486791) (xy 409.192329 -391.45004) (xy 409.161779 -391.407992)
			(xy 409.138183 -391.361682) (xy 409.122122 -391.312252) (xy 409.113992 -391.260917) (xy 408.574492 -391.260917)
			(xy 408.566362 -391.312252) (xy 408.550301 -391.361682) (xy 408.526705 -391.407992) (xy 408.496155 -391.45004)
			(xy 408.459404 -391.486791) (xy 408.417356 -391.517341) (xy 408.371046 -391.540937) (xy 408.321616 -391.556998)
			(xy 408.270281 -391.565128) (xy 408.218307 -391.565128) (xy 408.166972 -391.556998) (xy 408.117542 -391.540937)
			(xy 408.071232 -391.517341) (xy 408.029184 -391.486791) (xy 407.992433 -391.45004) (xy 407.961883 -391.407992)
			(xy 407.938287 -391.361682) (xy 407.922226 -391.312252) (xy 407.914096 -391.260917) (xy 407.374342 -391.260917)
			(xy 407.366212 -391.312252) (xy 407.350151 -391.361682) (xy 407.326555 -391.407992) (xy 407.296005 -391.45004)
			(xy 407.259254 -391.486791) (xy 407.217206 -391.517341) (xy 407.170896 -391.540937) (xy 407.121466 -391.556998)
			(xy 407.070131 -391.565128) (xy 407.018157 -391.565128) (xy 406.966822 -391.556998) (xy 406.917392 -391.540937)
			(xy 406.871082 -391.517341) (xy 406.829034 -391.486791) (xy 406.792283 -391.45004) (xy 406.761733 -391.407992)
			(xy 406.738137 -391.361682) (xy 406.722076 -391.312252) (xy 406.713946 -391.260917) (xy 406.174446 -391.260917)
			(xy 406.166316 -391.312252) (xy 406.150255 -391.361682) (xy 406.126659 -391.407992) (xy 406.096109 -391.45004)
			(xy 406.059358 -391.486791) (xy 406.01731 -391.517341) (xy 405.971 -391.540937) (xy 405.92157 -391.556998)
			(xy 405.870235 -391.565128) (xy 405.818261 -391.565128) (xy 405.766926 -391.556998) (xy 405.717496 -391.540937)
			(xy 405.671186 -391.517341) (xy 405.629138 -391.486791) (xy 405.592387 -391.45004) (xy 405.561837 -391.407992)
			(xy 405.538241 -391.361682) (xy 405.52218 -391.312252) (xy 405.51405 -391.260917) (xy 404.97455 -391.260917)
			(xy 404.96642 -391.312252) (xy 404.950359 -391.361682) (xy 404.926763 -391.407992) (xy 404.896213 -391.45004)
			(xy 404.859462 -391.486791) (xy 404.817414 -391.517341) (xy 404.771104 -391.540937) (xy 404.721674 -391.556998)
			(xy 404.670339 -391.565128) (xy 404.618365 -391.565128) (xy 404.56703 -391.556998) (xy 404.5176 -391.540937)
			(xy 404.47129 -391.517341) (xy 404.429242 -391.486791) (xy 404.392491 -391.45004) (xy 404.361941 -391.407992)
			(xy 404.338345 -391.361682) (xy 404.322284 -391.312252) (xy 404.314154 -391.260917) (xy 403.7744 -391.260917)
			(xy 403.76627 -391.312252) (xy 403.750209 -391.361682) (xy 403.726613 -391.407992) (xy 403.696063 -391.45004)
			(xy 403.659312 -391.486791) (xy 403.617264 -391.517341) (xy 403.570954 -391.540937) (xy 403.521524 -391.556998)
			(xy 403.470189 -391.565128) (xy 403.418215 -391.565128) (xy 403.36688 -391.556998) (xy 403.31745 -391.540937)
			(xy 403.27114 -391.517341) (xy 403.229092 -391.486791) (xy 403.192341 -391.45004) (xy 403.161791 -391.407992)
			(xy 403.138195 -391.361682) (xy 403.122134 -391.312252) (xy 403.114004 -391.260917) (xy 402.425768 -391.260917)
			(xy 402.426354 -391.264618) (xy 402.426354 -391.316582) (xy 402.418225 -391.367908) (xy 402.402168 -391.41733)
			(xy 402.378578 -391.463631) (xy 402.348034 -391.505673) (xy 402.311291 -391.542419) (xy 402.269252 -391.572965)
			(xy 402.222952 -391.596559) (xy 402.173531 -391.61262) (xy 402.122206 -391.620752) (xy 402.096224 -391.621264)
			(xy 402.071386 -391.620825) (xy 402.022269 -391.613404) (xy 401.974817 -391.598711) (xy 401.930101 -391.577077)
			(xy 401.889129 -391.54899) (xy 401.870672 -391.532364) (xy 401.8636 -391.526333) (xy 401.846415 -391.519293)
			(xy 401.837144 -391.518648) (xy 401.805902 -391.517886) (xy 401.796646 -391.518037) (xy 401.779193 -391.524166)
			(xy 401.771866 -391.529824) (xy 401.749302 -391.54799) (xy 401.699172 -391.577006) (xy 401.644758 -391.596859)
			(xy 401.587721 -391.606945) (xy 401.55876 -391.607548) (xy 401.535564 -391.607119) (xy 401.489626 -391.600637)
			(xy 401.445042 -391.587807) (xy 401.402686 -391.568878) (xy 401.363387 -391.544222) (xy 401.3454 -391.52957)
			(xy 401.338288 -391.523474) (xy 401.320762 -391.517378) (xy 401.235164 -391.519156) (xy 401.217892 -391.526268)
			(xy 401.211034 -391.532618) (xy 401.192593 -391.548937) (xy 401.151818 -391.576545) (xy 401.107401 -391.597802)
			(xy 401.060324 -391.612241) (xy 401.011627 -391.619541) (xy 400.987006 -391.619994) (xy 400.961015 -391.619539)
			(xy 400.909674 -391.611408) (xy 400.860236 -391.595346) (xy 400.81392 -391.571748) (xy 400.771866 -391.541194)
			(xy 400.73511 -391.504438) (xy 400.704556 -391.462385) (xy 400.680956 -391.416069) (xy 400.664893 -391.366632)
			(xy 400.656761 -391.315291) (xy 397.490373 -391.315291) (xy 397.448786 -391.345928) (xy 397.437864 -391.36955)
			(xy 397.43888 -391.382758) (xy 397.439896 -391.41146) (xy 397.43941 -391.438711) (xy 397.431654 -391.492659)
			(xy 397.416299 -391.544954) (xy 397.393657 -391.594531) (xy 397.364191 -391.640381) (xy 397.3285 -391.681572)
			(xy 397.287309 -391.717263) (xy 397.241459 -391.746729) (xy 397.191882 -391.769371) (xy 397.139587 -391.784726)
			(xy 397.085639 -391.792482) (xy 397.031137 -391.792482) (xy 396.977189 -391.784726) (xy 396.924894 -391.769371)
			(xy 396.875317 -391.746729) (xy 396.829467 -391.717263) (xy 396.788276 -391.681572) (xy 396.752585 -391.640381)
			(xy 396.723119 -391.594531) (xy 396.700477 -391.544954) (xy 396.685122 -391.492659) (xy 396.677366 -391.438711)
			(xy 396.67688 -391.41146) (xy 396.677896 -391.382758) (xy 396.678912 -391.36955) (xy 396.66799 -391.345928)
			(xy 396.577312 -391.279126) (xy 396.551404 -391.275824) (xy 396.538958 -391.280904) (xy 396.516448 -391.289438)
			(xy 396.469821 -391.301423) (xy 396.422059 -391.307456) (xy 396.397988 -391.307828) (xy 396.370736 -391.307341)
			(xy 396.316787 -391.299583) (xy 396.264491 -391.284226) (xy 396.214912 -391.261583) (xy 396.169061 -391.232115)
			(xy 396.12787 -391.196422) (xy 396.092178 -391.155229) (xy 396.062711 -391.109377) (xy 396.04007 -391.059798)
			(xy 396.024714 -391.007502) (xy 396.016958 -390.953552) (xy 396.016958 -390.899048) (xy 396.024714 -390.845098)
			(xy 396.04007 -390.792802) (xy 396.062711 -390.743223) (xy 396.092178 -390.697371) (xy 396.12787 -390.656178)
			(xy 396.169061 -390.620485) (xy 396.214912 -390.591017) (xy 396.264491 -390.568374) (xy 396.316787 -390.553017)
			(xy 396.370736 -390.545259) (xy 396.397988 -390.544812) (xy 396.427427 -390.545354) (xy 396.485603 -390.554409)
			(xy 396.513812 -390.562846) (xy 396.522428 -390.565141) (xy 396.540228 -390.564361) (xy 396.54861 -390.561322)
			(xy 396.576804 -390.549384) (xy 396.585043 -390.545565) (xy 396.598334 -390.533208) (xy 396.602712 -390.525254)
			(xy 396.615893 -390.499568) (xy 396.64721 -390.451063) (xy 396.665196 -390.42848) (xy 396.670529 -390.4215)
			(xy 396.676513 -390.404998) (xy 396.67688 -390.396222) (xy 396.67688 -390.242298) (xy 396.676476 -390.233527)
			(xy 396.670518 -390.217022) (xy 396.665196 -390.21004) (xy 396.647198 -390.187465) (xy 396.615882 -390.138958)
			(xy 396.602712 -390.113266) (xy 396.598306 -390.105332) (xy 396.585027 -390.092978) (xy 396.576804 -390.089136)
			(xy 396.54861 -390.077198) (xy 396.540244 -390.074075) (xy 396.522415 -390.073282) (xy 396.513812 -390.075674)
			(xy 396.485599 -390.084092) (xy 396.427425 -390.093154) (xy 396.397988 -390.093708) (xy 396.370737 -390.093221)
			(xy 396.316791 -390.085463) (xy 396.264498 -390.070107) (xy 396.214922 -390.047465) (xy 396.169073 -390.017999)
			(xy 396.127884 -389.982307) (xy 396.092194 -389.941117) (xy 396.062729 -389.895268) (xy 396.040088 -389.845691)
			(xy 396.024734 -389.793397) (xy 396.016978 -389.739451) (xy 396.01648 -389.7122) (xy 396.016842 -389.687662)
			(xy 396.023107 -389.638988) (xy 396.03557 -389.591522) (xy 396.054027 -389.54605) (xy 396.065756 -389.524494)
			(xy 396.074392 -389.509508) (xy 396.06982 -389.475726) (xy 396.057628 -389.463534) (xy 396.050194 -389.456818)
			(xy 396.031694 -389.449182) (xy 396.01168 -389.449182) (xy 395.99318 -389.456818) (xy 395.985746 -389.463534)
			(xy 395.970506 -389.478774) (xy 395.963109 -389.485624) (xy 395.944511 -389.493365) (xy 395.934438 -389.49376)
			(xy 394.769848 -389.49376) (xy 394.743432 -389.512556) (xy 394.738098 -389.527796) (xy 394.729094 -389.552435)
			(xy 394.705281 -389.599177) (xy 394.675288 -389.642217) (xy 394.639683 -389.680741) (xy 394.599135 -389.714025)
			(xy 394.55441 -389.74144) (xy 394.506351 -389.762469) (xy 394.455864 -389.776716) (xy 394.403901 -389.783913)
			(xy 394.377672 -389.784336) (xy 394.350421 -389.783848) (xy 394.296475 -389.776089) (xy 394.244182 -389.760731)
			(xy 394.194607 -389.738089) (xy 394.148758 -389.708623) (xy 394.107569 -389.672931) (xy 394.071877 -389.631742)
			(xy 394.042411 -389.585893) (xy 394.019769 -389.536318) (xy 394.004411 -389.484025) (xy 393.996652 -389.430079)
			(xy 393.996164 -389.402828) (xy 393.996418 -389.383774) (xy 394.000239 -389.345859) (xy 394.003784 -389.327136)
			(xy 394.006324 -389.31469) (xy 393.998958 -389.290306) (xy 393.954254 -389.245602) (xy 393.920472 -389.24103)
			(xy 393.905486 -389.249666) (xy 393.883882 -389.261458) (xy 393.838291 -389.280003) (xy 393.790694 -389.292535)
			(xy 393.741882 -389.298845) (xy 393.717272 -389.299196) (xy 393.690022 -389.298708) (xy 393.636078 -389.290948)
			(xy 393.583788 -389.27559) (xy 393.534215 -389.252947) (xy 393.488369 -389.22348) (xy 393.447183 -389.187789)
			(xy 393.411496 -389.146599) (xy 393.382033 -389.10075) (xy 393.359396 -389.051175) (xy 393.344043 -388.998882)
			(xy 393.336289 -388.944938) (xy 393.335764 -388.917688) (xy 393.33613 -388.893078) (xy 393.342426 -388.844264)
			(xy 393.35495 -388.796665) (xy 393.373494 -388.751073) (xy 393.385294 -388.729474) (xy 393.39393 -388.714488)
			(xy 393.389358 -388.680706) (xy 392.917172 -388.20852) (xy 392.909773 -388.201676) (xy 392.891175 -388.193948)
			(xy 392.881104 -388.193534) (xy 368.323114 -388.193534) (xy 368.313051 -388.193974) (xy 368.294473 -388.201714)
			(xy 368.287046 -388.20852) (xy 367.196878 -389.298688) (xy 367.19002 -389.325358) (xy 367.19383 -389.338566)
			(xy 367.200615 -389.364129) (xy 367.20788 -389.416516) (xy 367.208308 -389.44296) (xy 367.207847 -389.470215)
			(xy 367.200095 -389.52417) (xy 367.184742 -389.576473) (xy 367.162102 -389.626058) (xy 367.132635 -389.671916)
			(xy 367.096942 -389.713113) (xy 367.055748 -389.748811) (xy 367.009893 -389.778283) (xy 366.96031 -389.800928)
			(xy 366.908009 -389.816287) (xy 366.854055 -389.824045) (xy 366.8268 -389.824468) (xy 366.800356 -389.824033)
			(xy 366.747971 -389.816766) (xy 366.722406 -389.80999) (xy 366.709198 -389.80618) (xy 366.682528 -389.813038)
			(xy 365.580168 -390.915398) (xy 365.572548 -390.93267) (xy 365.572294 -390.942322) (xy 365.571532 -390.953498)
			(xy 365.571327 -390.964767) (xy 365.579485 -390.985746) (xy 365.58728 -390.993884) (xy 365.610648 -391.016236)
			(xy 365.619309 -391.023765) (xy 365.641135 -391.030789) (xy 365.652558 -391.029698) (xy 365.669806 -391.027459)
			(xy 365.704508 -391.025047) (xy 365.7219 -391.024872) (xy 365.753862 -391.025374) (xy 365.817283 -391.033386)
			(xy 365.879199 -391.049283) (xy 365.938635 -391.072815) (xy 365.994652 -391.103611) (xy 366.046368 -391.141185)
			(xy 366.092967 -391.184945) (xy 366.133714 -391.234199) (xy 366.167967 -391.288173) (xy 366.180726 -391.315286)
			(xy 368.129087 -391.315286) (xy 368.129087 -391.263314) (xy 368.137217 -391.211981) (xy 368.153276 -391.162552)
			(xy 368.176869 -391.116244) (xy 368.207416 -391.074195) (xy 368.244163 -391.037443) (xy 368.286208 -391.006891)
			(xy 368.332513 -390.983292) (xy 368.38194 -390.967227) (xy 368.433272 -390.959091) (xy 368.459258 -390.958578)
			(xy 368.482492 -390.958965) (xy 368.528503 -390.965465) (xy 368.573151 -390.978344) (xy 368.615556 -390.997348)
			(xy 368.654881 -391.022102) (xy 368.672872 -391.03681) (xy 368.679984 -391.042906) (xy 368.696494 -391.049002)
			(xy 368.780822 -391.049002) (xy 368.797332 -391.042906) (xy 368.804444 -391.03681) (xy 368.822443 -391.022115)
			(xy 368.86177 -390.997366) (xy 368.904173 -390.978364) (xy 368.948817 -390.965482) (xy 368.994825 -390.958974)
			(xy 369.018058 -390.958578) (xy 369.046653 -390.959172) (xy 369.102987 -390.969026) (xy 369.156791 -390.988414)
			(xy 369.206462 -391.016759) (xy 369.228878 -391.034524) (xy 369.235736 -391.040112) (xy 369.2525 -391.046208)
			(xy 369.334796 -391.046208) (xy 369.35156 -391.040366) (xy 369.358418 -391.034778) (xy 369.380783 -391.017142)
			(xy 369.430299 -390.989007) (xy 369.483899 -390.969757) (xy 369.540001 -390.95996) (xy 369.568476 -390.95934)
			(xy 369.59447 -390.959725) (xy 369.645819 -390.967855) (xy 369.695264 -390.983917) (xy 369.741587 -391.007517)
			(xy 369.783648 -391.038073) (xy 369.820411 -391.074834) (xy 369.85097 -391.116892) (xy 369.874573 -391.163214)
			(xy 369.890639 -391.212657) (xy 369.898284 -391.260917) (xy 370.586256 -391.260917) (xy 370.586256 -391.208943)
			(xy 370.594386 -391.157608) (xy 370.610447 -391.108178) (xy 370.634043 -391.061868) (xy 370.664593 -391.01982)
			(xy 370.701344 -390.983069) (xy 370.743392 -390.952519) (xy 370.789702 -390.928923) (xy 370.839132 -390.912862)
			(xy 370.890467 -390.904732) (xy 370.942441 -390.904732) (xy 370.993776 -390.912862) (xy 371.043206 -390.928923)
			(xy 371.089516 -390.952519) (xy 371.131564 -390.983069) (xy 371.168315 -391.01982) (xy 371.198865 -391.061868)
			(xy 371.222461 -391.108178) (xy 371.238522 -391.157608) (xy 371.246652 -391.208943) (xy 371.247162 -391.23493)
			(xy 371.246652 -391.260917) (xy 371.786406 -391.260917) (xy 371.786406 -391.208943) (xy 371.794536 -391.157608)
			(xy 371.810597 -391.108178) (xy 371.834193 -391.061868) (xy 371.864743 -391.01982) (xy 371.901494 -390.983069)
			(xy 371.943542 -390.952519) (xy 371.989852 -390.928923) (xy 372.039282 -390.912862) (xy 372.090617 -390.904732)
			(xy 372.142591 -390.904732) (xy 372.193926 -390.912862) (xy 372.243356 -390.928923) (xy 372.289666 -390.952519)
			(xy 372.331714 -390.983069) (xy 372.368465 -391.01982) (xy 372.399015 -391.061868) (xy 372.422611 -391.108178)
			(xy 372.438672 -391.157608) (xy 372.446802 -391.208943) (xy 372.447312 -391.23493) (xy 372.446802 -391.260917)
			(xy 372.986302 -391.260917) (xy 372.986302 -391.208943) (xy 372.994432 -391.157608) (xy 373.010493 -391.108178)
			(xy 373.034089 -391.061868) (xy 373.064639 -391.01982) (xy 373.10139 -390.983069) (xy 373.143438 -390.952519)
			(xy 373.189748 -390.928923) (xy 373.239178 -390.912862) (xy 373.290513 -390.904732) (xy 373.342487 -390.904732)
			(xy 373.393822 -390.912862) (xy 373.443252 -390.928923) (xy 373.489562 -390.952519) (xy 373.53161 -390.983069)
			(xy 373.568361 -391.01982) (xy 373.598911 -391.061868) (xy 373.622507 -391.108178) (xy 373.638568 -391.157608)
			(xy 373.646698 -391.208943) (xy 373.647208 -391.23493) (xy 373.646698 -391.260917) (xy 374.186198 -391.260917)
			(xy 374.186198 -391.208943) (xy 374.194328 -391.157608) (xy 374.210389 -391.108178) (xy 374.233985 -391.061868)
			(xy 374.264535 -391.01982) (xy 374.301286 -390.983069) (xy 374.343334 -390.952519) (xy 374.389644 -390.928923)
			(xy 374.439074 -390.912862) (xy 374.490409 -390.904732) (xy 374.542383 -390.904732) (xy 374.593718 -390.912862)
			(xy 374.643148 -390.928923) (xy 374.689458 -390.952519) (xy 374.731506 -390.983069) (xy 374.768257 -391.01982)
			(xy 374.798807 -391.061868) (xy 374.822403 -391.108178) (xy 374.838464 -391.157608) (xy 374.846594 -391.208943)
			(xy 374.847104 -391.23493) (xy 374.846594 -391.260917) (xy 375.386348 -391.260917) (xy 375.386348 -391.208943)
			(xy 375.394478 -391.157608) (xy 375.410539 -391.108178) (xy 375.434135 -391.061868) (xy 375.464685 -391.01982)
			(xy 375.501436 -390.983069) (xy 375.543484 -390.952519) (xy 375.589794 -390.928923) (xy 375.639224 -390.912862)
			(xy 375.690559 -390.904732) (xy 375.742533 -390.904732) (xy 375.793868 -390.912862) (xy 375.843298 -390.928923)
			(xy 375.889608 -390.952519) (xy 375.931656 -390.983069) (xy 375.968407 -391.01982) (xy 375.998957 -391.061868)
			(xy 376.022553 -391.108178) (xy 376.038614 -391.157608) (xy 376.046744 -391.208943) (xy 376.047254 -391.23493)
			(xy 376.046744 -391.260917) (xy 376.586244 -391.260917) (xy 376.586244 -391.208943) (xy 376.594374 -391.157608)
			(xy 376.610435 -391.108178) (xy 376.634031 -391.061868) (xy 376.664581 -391.01982) (xy 376.701332 -390.983069)
			(xy 376.74338 -390.952519) (xy 376.78969 -390.928923) (xy 376.83912 -390.912862) (xy 376.890455 -390.904732)
			(xy 376.942429 -390.904732) (xy 376.993764 -390.912862) (xy 377.043194 -390.928923) (xy 377.089504 -390.952519)
			(xy 377.131552 -390.983069) (xy 377.168303 -391.01982) (xy 377.198853 -391.061868) (xy 377.222449 -391.108178)
			(xy 377.23851 -391.157608) (xy 377.24664 -391.208943) (xy 377.24715 -391.23493) (xy 377.24664 -391.260917)
			(xy 377.786394 -391.260917) (xy 377.786394 -391.208943) (xy 377.794524 -391.157608) (xy 377.810585 -391.108178)
			(xy 377.834181 -391.061868) (xy 377.864731 -391.01982) (xy 377.901482 -390.983069) (xy 377.94353 -390.952519)
			(xy 377.98984 -390.928923) (xy 378.03927 -390.912862) (xy 378.090605 -390.904732) (xy 378.142579 -390.904732)
			(xy 378.193914 -390.912862) (xy 378.243344 -390.928923) (xy 378.289654 -390.952519) (xy 378.331702 -390.983069)
			(xy 378.368453 -391.01982) (xy 378.399003 -391.061868) (xy 378.422599 -391.108178) (xy 378.43866 -391.157608)
			(xy 378.44679 -391.208943) (xy 378.4473 -391.23493) (xy 378.44679 -391.260917) (xy 378.98629 -391.260917)
			(xy 378.98629 -391.208943) (xy 378.99442 -391.157608) (xy 379.010481 -391.108178) (xy 379.034077 -391.061868)
			(xy 379.064627 -391.01982) (xy 379.101378 -390.983069) (xy 379.143426 -390.952519) (xy 379.189736 -390.928923)
			(xy 379.239166 -390.912862) (xy 379.290501 -390.904732) (xy 379.342475 -390.904732) (xy 379.39381 -390.912862)
			(xy 379.44324 -390.928923) (xy 379.48955 -390.952519) (xy 379.531598 -390.983069) (xy 379.568349 -391.01982)
			(xy 379.598899 -391.061868) (xy 379.622495 -391.108178) (xy 379.638556 -391.157608) (xy 379.646686 -391.208943)
			(xy 379.647196 -391.23493) (xy 379.646686 -391.260917) (xy 380.186186 -391.260917) (xy 380.186186 -391.208943)
			(xy 380.194316 -391.157608) (xy 380.210377 -391.108178) (xy 380.233973 -391.061868) (xy 380.264523 -391.01982)
			(xy 380.301274 -390.983069) (xy 380.343322 -390.952519) (xy 380.389632 -390.928923) (xy 380.439062 -390.912862)
			(xy 380.490397 -390.904732) (xy 380.542371 -390.904732) (xy 380.593706 -390.912862) (xy 380.643136 -390.928923)
			(xy 380.689446 -390.952519) (xy 380.731494 -390.983069) (xy 380.768245 -391.01982) (xy 380.798795 -391.061868)
			(xy 380.822391 -391.108178) (xy 380.838452 -391.157608) (xy 380.846582 -391.208943) (xy 380.847092 -391.23493)
			(xy 380.846582 -391.260917) (xy 381.386336 -391.260917) (xy 381.386336 -391.208943) (xy 381.394466 -391.157608)
			(xy 381.410527 -391.108178) (xy 381.434123 -391.061868) (xy 381.464673 -391.01982) (xy 381.501424 -390.983069)
			(xy 381.543472 -390.952519) (xy 381.589782 -390.928923) (xy 381.639212 -390.912862) (xy 381.690547 -390.904732)
			(xy 381.742521 -390.904732) (xy 381.793856 -390.912862) (xy 381.843286 -390.928923) (xy 381.889596 -390.952519)
			(xy 381.931644 -390.983069) (xy 381.968395 -391.01982) (xy 381.998945 -391.061868) (xy 382.022541 -391.108178)
			(xy 382.038602 -391.157608) (xy 382.046732 -391.208943) (xy 382.047242 -391.23493) (xy 382.046732 -391.260917)
			(xy 382.586232 -391.260917) (xy 382.586232 -391.208943) (xy 382.594362 -391.157608) (xy 382.610423 -391.108178)
			(xy 382.634019 -391.061868) (xy 382.664569 -391.01982) (xy 382.70132 -390.983069) (xy 382.743368 -390.952519)
			(xy 382.789678 -390.928923) (xy 382.839108 -390.912862) (xy 382.890443 -390.904732) (xy 382.942417 -390.904732)
			(xy 382.993752 -390.912862) (xy 383.043182 -390.928923) (xy 383.089492 -390.952519) (xy 383.13154 -390.983069)
			(xy 383.168291 -391.01982) (xy 383.198841 -391.061868) (xy 383.222437 -391.108178) (xy 383.238498 -391.157608)
			(xy 383.246628 -391.208943) (xy 383.247138 -391.23493) (xy 383.246628 -391.260917) (xy 383.786382 -391.260917)
			(xy 383.786382 -391.208943) (xy 383.794512 -391.157608) (xy 383.810573 -391.108178) (xy 383.834169 -391.061868)
			(xy 383.864719 -391.01982) (xy 383.90147 -390.983069) (xy 383.943518 -390.952519) (xy 383.989828 -390.928923)
			(xy 384.039258 -390.912862) (xy 384.090593 -390.904732) (xy 384.142567 -390.904732) (xy 384.193902 -390.912862)
			(xy 384.243332 -390.928923) (xy 384.289642 -390.952519) (xy 384.33169 -390.983069) (xy 384.368441 -391.01982)
			(xy 384.398991 -391.061868) (xy 384.422587 -391.108178) (xy 384.438648 -391.157608) (xy 384.446778 -391.208943)
			(xy 384.447288 -391.23493) (xy 384.446778 -391.260917) (xy 384.986278 -391.260917) (xy 384.986278 -391.208943)
			(xy 384.994408 -391.157608) (xy 385.010469 -391.108178) (xy 385.034065 -391.061868) (xy 385.064615 -391.01982)
			(xy 385.101366 -390.983069) (xy 385.143414 -390.952519) (xy 385.189724 -390.928923) (xy 385.239154 -390.912862)
			(xy 385.290489 -390.904732) (xy 385.342463 -390.904732) (xy 385.393798 -390.912862) (xy 385.443228 -390.928923)
			(xy 385.489538 -390.952519) (xy 385.531586 -390.983069) (xy 385.568337 -391.01982) (xy 385.598887 -391.061868)
			(xy 385.622483 -391.108178) (xy 385.638544 -391.157608) (xy 385.646674 -391.208943) (xy 385.647184 -391.23493)
			(xy 385.646674 -391.260917) (xy 386.186174 -391.260917) (xy 386.186174 -391.208943) (xy 386.194304 -391.157608)
			(xy 386.210365 -391.108178) (xy 386.233961 -391.061868) (xy 386.264511 -391.01982) (xy 386.301262 -390.983069)
			(xy 386.34331 -390.952519) (xy 386.38962 -390.928923) (xy 386.43905 -390.912862) (xy 386.490385 -390.904732)
			(xy 386.542359 -390.904732) (xy 386.593694 -390.912862) (xy 386.643124 -390.928923) (xy 386.689434 -390.952519)
			(xy 386.731482 -390.983069) (xy 386.768233 -391.01982) (xy 386.798783 -391.061868) (xy 386.822379 -391.108178)
			(xy 386.83844 -391.157608) (xy 386.84657 -391.208943) (xy 386.84708 -391.23493) (xy 386.84657 -391.260917)
			(xy 387.386324 -391.260917) (xy 387.386324 -391.208943) (xy 387.394454 -391.157608) (xy 387.410515 -391.108178)
			(xy 387.434111 -391.061868) (xy 387.464661 -391.01982) (xy 387.501412 -390.983069) (xy 387.54346 -390.952519)
			(xy 387.58977 -390.928923) (xy 387.6392 -390.912862) (xy 387.690535 -390.904732) (xy 387.742509 -390.904732)
			(xy 387.793844 -390.912862) (xy 387.843274 -390.928923) (xy 387.889584 -390.952519) (xy 387.931632 -390.983069)
			(xy 387.968383 -391.01982) (xy 387.998933 -391.061868) (xy 388.022529 -391.108178) (xy 388.03859 -391.157608)
			(xy 388.04672 -391.208943) (xy 388.04723 -391.23493) (xy 388.04672 -391.260917) (xy 388.58622 -391.260917)
			(xy 388.58622 -391.208943) (xy 388.59435 -391.157608) (xy 388.610411 -391.108178) (xy 388.634007 -391.061868)
			(xy 388.664557 -391.01982) (xy 388.701308 -390.983069) (xy 388.743356 -390.952519) (xy 388.789666 -390.928923)
			(xy 388.839096 -390.912862) (xy 388.890431 -390.904732) (xy 388.942405 -390.904732) (xy 388.99374 -390.912862)
			(xy 389.04317 -390.928923) (xy 389.08948 -390.952519) (xy 389.131528 -390.983069) (xy 389.168279 -391.01982)
			(xy 389.198829 -391.061868) (xy 389.222425 -391.108178) (xy 389.238486 -391.157608) (xy 389.246616 -391.208943)
			(xy 389.247126 -391.23493) (xy 389.246616 -391.260917) (xy 389.244198 -391.276188) (xy 389.653272 -391.276188)
			(xy 389.653272 -391.224212) (xy 389.661402 -391.172875) (xy 389.677463 -391.123443) (xy 389.701058 -391.077131)
			(xy 389.731608 -391.03508) (xy 389.768359 -390.998326) (xy 389.810407 -390.967773) (xy 389.856717 -390.944173)
			(xy 389.906148 -390.928109) (xy 389.957484 -390.919974) (xy 389.983472 -390.919462) (xy 390.007246 -390.91987)
			(xy 390.054306 -390.926671) (xy 390.099903 -390.940151) (xy 390.143096 -390.960031) (xy 390.182991 -390.9859)
			(xy 390.20115 -391.00125) (xy 390.208269 -391.006937) (xy 390.22532 -391.01332) (xy 390.234424 -391.013696)
			(xy 390.26592 -391.013696) (xy 390.275022 -391.013311) (xy 390.292072 -391.00693) (xy 390.299194 -391.00125)
			(xy 390.317359 -390.985908) (xy 390.357258 -390.960051) (xy 390.400451 -390.940175) (xy 390.446044 -390.926691)
			(xy 390.493099 -390.919877) (xy 390.516872 -390.919462) (xy 390.54286 -390.920003) (xy 390.594198 -390.92813)
			(xy 390.643631 -390.944188) (xy 390.689944 -390.967782) (xy 390.731996 -390.998331) (xy 390.76875 -391.035083)
			(xy 390.799303 -391.077132) (xy 390.822901 -391.123443) (xy 390.838963 -391.172875) (xy 390.847095 -391.224212)
			(xy 390.847095 -391.276188) (xy 390.838963 -391.327525) (xy 390.822901 -391.376957) (xy 390.799303 -391.423268)
			(xy 390.76875 -391.465317) (xy 390.731996 -391.502069) (xy 390.689944 -391.532618) (xy 390.643631 -391.556212)
			(xy 390.594198 -391.57227) (xy 390.54286 -391.580397) (xy 390.516872 -391.580878) (xy 390.493097 -391.580494)
			(xy 390.446037 -391.573686) (xy 390.40044 -391.5602) (xy 390.357247 -391.540315) (xy 390.317353 -391.514442)
			(xy 390.299194 -391.49909) (xy 390.292096 -391.493372) (xy 390.275028 -391.487009) (xy 390.26592 -391.486644)
			(xy 390.234424 -391.486644) (xy 390.225324 -391.487042) (xy 390.208273 -391.493413) (xy 390.20115 -391.49909)
			(xy 390.182974 -391.514418) (xy 390.143077 -391.540276) (xy 390.099888 -391.560154) (xy 390.054297 -391.573642)
			(xy 390.007244 -391.580461) (xy 389.983472 -391.580878) (xy 389.957484 -391.580426) (xy 389.906148 -391.572291)
			(xy 389.856717 -391.556227) (xy 389.810407 -391.532627) (xy 389.768359 -391.502074) (xy 389.731608 -391.46532)
			(xy 389.701058 -391.423269) (xy 389.677463 -391.376957) (xy 389.661402 -391.327525) (xy 389.653272 -391.276188)
			(xy 389.244198 -391.276188) (xy 389.238486 -391.312252) (xy 389.222425 -391.361682) (xy 389.198829 -391.407992)
			(xy 389.168279 -391.45004) (xy 389.131528 -391.486791) (xy 389.08948 -391.517341) (xy 389.04317 -391.540937)
			(xy 388.99374 -391.556998) (xy 388.942405 -391.565128) (xy 388.890431 -391.565128) (xy 388.839096 -391.556998)
			(xy 388.789666 -391.540937) (xy 388.743356 -391.517341) (xy 388.701308 -391.486791) (xy 388.664557 -391.45004)
			(xy 388.634007 -391.407992) (xy 388.610411 -391.361682) (xy 388.59435 -391.312252) (xy 388.58622 -391.260917)
			(xy 388.04672 -391.260917) (xy 388.03859 -391.312252) (xy 388.022529 -391.361682) (xy 387.998933 -391.407992)
			(xy 387.968383 -391.45004) (xy 387.931632 -391.486791) (xy 387.889584 -391.517341) (xy 387.843274 -391.540937)
			(xy 387.793844 -391.556998) (xy 387.742509 -391.565128) (xy 387.690535 -391.565128) (xy 387.6392 -391.556998)
			(xy 387.58977 -391.540937) (xy 387.54346 -391.517341) (xy 387.501412 -391.486791) (xy 387.464661 -391.45004)
			(xy 387.434111 -391.407992) (xy 387.410515 -391.361682) (xy 387.394454 -391.312252) (xy 387.386324 -391.260917)
			(xy 386.84657 -391.260917) (xy 386.83844 -391.312252) (xy 386.822379 -391.361682) (xy 386.798783 -391.407992)
			(xy 386.768233 -391.45004) (xy 386.731482 -391.486791) (xy 386.689434 -391.517341) (xy 386.643124 -391.540937)
			(xy 386.593694 -391.556998) (xy 386.542359 -391.565128) (xy 386.490385 -391.565128) (xy 386.43905 -391.556998)
			(xy 386.38962 -391.540937) (xy 386.34331 -391.517341) (xy 386.301262 -391.486791) (xy 386.264511 -391.45004)
			(xy 386.233961 -391.407992) (xy 386.210365 -391.361682) (xy 386.194304 -391.312252) (xy 386.186174 -391.260917)
			(xy 385.646674 -391.260917) (xy 385.638544 -391.312252) (xy 385.622483 -391.361682) (xy 385.598887 -391.407992)
			(xy 385.568337 -391.45004) (xy 385.531586 -391.486791) (xy 385.489538 -391.517341) (xy 385.443228 -391.540937)
			(xy 385.393798 -391.556998) (xy 385.342463 -391.565128) (xy 385.290489 -391.565128) (xy 385.239154 -391.556998)
			(xy 385.189724 -391.540937) (xy 385.143414 -391.517341) (xy 385.101366 -391.486791) (xy 385.064615 -391.45004)
			(xy 385.034065 -391.407992) (xy 385.010469 -391.361682) (xy 384.994408 -391.312252) (xy 384.986278 -391.260917)
			(xy 384.446778 -391.260917) (xy 384.438648 -391.312252) (xy 384.422587 -391.361682) (xy 384.398991 -391.407992)
			(xy 384.368441 -391.45004) (xy 384.33169 -391.486791) (xy 384.289642 -391.517341) (xy 384.243332 -391.540937)
			(xy 384.193902 -391.556998) (xy 384.142567 -391.565128) (xy 384.090593 -391.565128) (xy 384.039258 -391.556998)
			(xy 383.989828 -391.540937) (xy 383.943518 -391.517341) (xy 383.90147 -391.486791) (xy 383.864719 -391.45004)
			(xy 383.834169 -391.407992) (xy 383.810573 -391.361682) (xy 383.794512 -391.312252) (xy 383.786382 -391.260917)
			(xy 383.246628 -391.260917) (xy 383.238498 -391.312252) (xy 383.222437 -391.361682) (xy 383.198841 -391.407992)
			(xy 383.168291 -391.45004) (xy 383.13154 -391.486791) (xy 383.089492 -391.517341) (xy 383.043182 -391.540937)
			(xy 382.993752 -391.556998) (xy 382.942417 -391.565128) (xy 382.890443 -391.565128) (xy 382.839108 -391.556998)
			(xy 382.789678 -391.540937) (xy 382.743368 -391.517341) (xy 382.70132 -391.486791) (xy 382.664569 -391.45004)
			(xy 382.634019 -391.407992) (xy 382.610423 -391.361682) (xy 382.594362 -391.312252) (xy 382.586232 -391.260917)
			(xy 382.046732 -391.260917) (xy 382.038602 -391.312252) (xy 382.022541 -391.361682) (xy 381.998945 -391.407992)
			(xy 381.968395 -391.45004) (xy 381.931644 -391.486791) (xy 381.889596 -391.517341) (xy 381.843286 -391.540937)
			(xy 381.793856 -391.556998) (xy 381.742521 -391.565128) (xy 381.690547 -391.565128) (xy 381.639212 -391.556998)
			(xy 381.589782 -391.540937) (xy 381.543472 -391.517341) (xy 381.501424 -391.486791) (xy 381.464673 -391.45004)
			(xy 381.434123 -391.407992) (xy 381.410527 -391.361682) (xy 381.394466 -391.312252) (xy 381.386336 -391.260917)
			(xy 380.846582 -391.260917) (xy 380.838452 -391.312252) (xy 380.822391 -391.361682) (xy 380.798795 -391.407992)
			(xy 380.768245 -391.45004) (xy 380.731494 -391.486791) (xy 380.689446 -391.517341) (xy 380.643136 -391.540937)
			(xy 380.593706 -391.556998) (xy 380.542371 -391.565128) (xy 380.490397 -391.565128) (xy 380.439062 -391.556998)
			(xy 380.389632 -391.540937) (xy 380.343322 -391.517341) (xy 380.301274 -391.486791) (xy 380.264523 -391.45004)
			(xy 380.233973 -391.407992) (xy 380.210377 -391.361682) (xy 380.194316 -391.312252) (xy 380.186186 -391.260917)
			(xy 379.646686 -391.260917) (xy 379.638556 -391.312252) (xy 379.622495 -391.361682) (xy 379.598899 -391.407992)
			(xy 379.568349 -391.45004) (xy 379.531598 -391.486791) (xy 379.48955 -391.517341) (xy 379.44324 -391.540937)
			(xy 379.39381 -391.556998) (xy 379.342475 -391.565128) (xy 379.290501 -391.565128) (xy 379.239166 -391.556998)
			(xy 379.189736 -391.540937) (xy 379.143426 -391.517341) (xy 379.101378 -391.486791) (xy 379.064627 -391.45004)
			(xy 379.034077 -391.407992) (xy 379.010481 -391.361682) (xy 378.99442 -391.312252) (xy 378.98629 -391.260917)
			(xy 378.44679 -391.260917) (xy 378.43866 -391.312252) (xy 378.422599 -391.361682) (xy 378.399003 -391.407992)
			(xy 378.368453 -391.45004) (xy 378.331702 -391.486791) (xy 378.289654 -391.517341) (xy 378.243344 -391.540937)
			(xy 378.193914 -391.556998) (xy 378.142579 -391.565128) (xy 378.090605 -391.565128) (xy 378.03927 -391.556998)
			(xy 377.98984 -391.540937) (xy 377.94353 -391.517341) (xy 377.901482 -391.486791) (xy 377.864731 -391.45004)
			(xy 377.834181 -391.407992) (xy 377.810585 -391.361682) (xy 377.794524 -391.312252) (xy 377.786394 -391.260917)
			(xy 377.24664 -391.260917) (xy 377.23851 -391.312252) (xy 377.222449 -391.361682) (xy 377.198853 -391.407992)
			(xy 377.168303 -391.45004) (xy 377.131552 -391.486791) (xy 377.089504 -391.517341) (xy 377.043194 -391.540937)
			(xy 376.993764 -391.556998) (xy 376.942429 -391.565128) (xy 376.890455 -391.565128) (xy 376.83912 -391.556998)
			(xy 376.78969 -391.540937) (xy 376.74338 -391.517341) (xy 376.701332 -391.486791) (xy 376.664581 -391.45004)
			(xy 376.634031 -391.407992) (xy 376.610435 -391.361682) (xy 376.594374 -391.312252) (xy 376.586244 -391.260917)
			(xy 376.046744 -391.260917) (xy 376.038614 -391.312252) (xy 376.022553 -391.361682) (xy 375.998957 -391.407992)
			(xy 375.968407 -391.45004) (xy 375.931656 -391.486791) (xy 375.889608 -391.517341) (xy 375.843298 -391.540937)
			(xy 375.793868 -391.556998) (xy 375.742533 -391.565128) (xy 375.690559 -391.565128) (xy 375.639224 -391.556998)
			(xy 375.589794 -391.540937) (xy 375.543484 -391.517341) (xy 375.501436 -391.486791) (xy 375.464685 -391.45004)
			(xy 375.434135 -391.407992) (xy 375.410539 -391.361682) (xy 375.394478 -391.312252) (xy 375.386348 -391.260917)
			(xy 374.846594 -391.260917) (xy 374.838464 -391.312252) (xy 374.822403 -391.361682) (xy 374.798807 -391.407992)
			(xy 374.768257 -391.45004) (xy 374.731506 -391.486791) (xy 374.689458 -391.517341) (xy 374.643148 -391.540937)
			(xy 374.593718 -391.556998) (xy 374.542383 -391.565128) (xy 374.490409 -391.565128) (xy 374.439074 -391.556998)
			(xy 374.389644 -391.540937) (xy 374.343334 -391.517341) (xy 374.301286 -391.486791) (xy 374.264535 -391.45004)
			(xy 374.233985 -391.407992) (xy 374.210389 -391.361682) (xy 374.194328 -391.312252) (xy 374.186198 -391.260917)
			(xy 373.646698 -391.260917) (xy 373.638568 -391.312252) (xy 373.622507 -391.361682) (xy 373.598911 -391.407992)
			(xy 373.568361 -391.45004) (xy 373.53161 -391.486791) (xy 373.489562 -391.517341) (xy 373.443252 -391.540937)
			(xy 373.393822 -391.556998) (xy 373.342487 -391.565128) (xy 373.290513 -391.565128) (xy 373.239178 -391.556998)
			(xy 373.189748 -391.540937) (xy 373.143438 -391.517341) (xy 373.10139 -391.486791) (xy 373.064639 -391.45004)
			(xy 373.034089 -391.407992) (xy 373.010493 -391.361682) (xy 372.994432 -391.312252) (xy 372.986302 -391.260917)
			(xy 372.446802 -391.260917) (xy 372.438672 -391.312252) (xy 372.422611 -391.361682) (xy 372.399015 -391.407992)
			(xy 372.368465 -391.45004) (xy 372.331714 -391.486791) (xy 372.289666 -391.517341) (xy 372.243356 -391.540937)
			(xy 372.193926 -391.556998) (xy 372.142591 -391.565128) (xy 372.090617 -391.565128) (xy 372.039282 -391.556998)
			(xy 371.989852 -391.540937) (xy 371.943542 -391.517341) (xy 371.901494 -391.486791) (xy 371.864743 -391.45004)
			(xy 371.834193 -391.407992) (xy 371.810597 -391.361682) (xy 371.794536 -391.312252) (xy 371.786406 -391.260917)
			(xy 371.246652 -391.260917) (xy 371.238522 -391.312252) (xy 371.222461 -391.361682) (xy 371.198865 -391.407992)
			(xy 371.168315 -391.45004) (xy 371.131564 -391.486791) (xy 371.089516 -391.517341) (xy 371.043206 -391.540937)
			(xy 370.993776 -391.556998) (xy 370.942441 -391.565128) (xy 370.890467 -391.565128) (xy 370.839132 -391.556998)
			(xy 370.789702 -391.540937) (xy 370.743392 -391.517341) (xy 370.701344 -391.486791) (xy 370.664593 -391.45004)
			(xy 370.634043 -391.407992) (xy 370.610447 -391.361682) (xy 370.594386 -391.312252) (xy 370.586256 -391.260917)
			(xy 369.898284 -391.260917) (xy 369.898773 -391.264006) (xy 369.898773 -391.315994) (xy 369.890639 -391.367343)
			(xy 369.874573 -391.416786) (xy 369.85097 -391.463108) (xy 369.820411 -391.505166) (xy 369.783648 -391.541927)
			(xy 369.741587 -391.572483) (xy 369.695264 -391.596083) (xy 369.645819 -391.612145) (xy 369.59447 -391.620275)
			(xy 369.568476 -391.620756) (xy 369.539883 -391.620135) (xy 369.483549 -391.610288) (xy 369.429746 -391.590908)
			(xy 369.380073 -391.562571) (xy 369.357656 -391.54481) (xy 369.350798 -391.539222) (xy 369.334034 -391.533126)
			(xy 369.251738 -391.533126) (xy 369.234974 -391.538968) (xy 369.228116 -391.544556) (xy 369.205732 -391.562167)
			(xy 369.156223 -391.590309) (xy 369.10263 -391.609567) (xy 369.046532 -391.619371) (xy 369.018058 -391.619994)
			(xy 368.994824 -391.619604) (xy 368.948813 -391.613105) (xy 368.904165 -391.600227) (xy 368.86176 -391.581224)
			(xy 368.822435 -391.55647) (xy 368.804444 -391.541762) (xy 368.797332 -391.535666) (xy 368.780822 -391.52957)
			(xy 368.696494 -391.52957) (xy 368.679984 -391.535666) (xy 368.672872 -391.541762) (xy 368.654863 -391.556446)
			(xy 368.61554 -391.581197) (xy 368.573139 -391.600202) (xy 368.528497 -391.613086) (xy 368.48249 -391.619597)
			(xy 368.459258 -391.619994) (xy 368.433272 -391.619509) (xy 368.38194 -391.611373) (xy 368.332513 -391.595308)
			(xy 368.286208 -391.571709) (xy 368.244163 -391.541157) (xy 368.207416 -391.504405) (xy 368.176869 -391.462356)
			(xy 368.153276 -391.416048) (xy 368.137217 -391.366619) (xy 368.129087 -391.315286) (xy 366.180726 -391.315286)
			(xy 366.195185 -391.346013) (xy 366.214938 -391.406809) (xy 366.226917 -391.469602) (xy 366.230931 -391.5334)
			(xy 366.226917 -391.597198) (xy 366.214938 -391.659991) (xy 366.195185 -391.720787) (xy 366.167967 -391.778627)
			(xy 366.133714 -391.832601) (xy 366.092967 -391.881855) (xy 366.046368 -391.925615) (xy 365.994652 -391.963189)
			(xy 365.938635 -391.993985) (xy 365.879199 -392.017517) (xy 365.817283 -392.033414) (xy 365.753862 -392.041426)
			(xy 365.7219 -392.041888) (xy 365.689325 -392.041368) (xy 365.624708 -392.033048) (xy 365.561683 -392.016544)
			(xy 365.501282 -391.992127) (xy 365.444493 -391.960196) (xy 365.392247 -391.921274) (xy 365.3454 -391.875998)
			(xy 365.304718 -391.825111) (xy 365.270868 -391.769445) (xy 365.244404 -391.709912) (xy 365.225759 -391.647487)
			(xy 365.215239 -391.583192) (xy 365.213646 -391.550652) (xy 365.212884 -391.530078) (xy 365.183674 -391.50163)
			(xy 364.922816 -391.50163) (xy 364.896654 -391.520426) (xy 364.89132 -391.53592) (xy 364.881773 -391.562045)
			(xy 364.856188 -391.611431) (xy 364.823704 -391.65658) (xy 364.785009 -391.696533) (xy 364.740923 -391.730445)
			(xy 364.69238 -391.757596) (xy 364.640409 -391.777412) (xy 364.586113 -391.789472) (xy 364.53064 -391.79352)
			(xy 364.475167 -391.789472) (xy 364.420871 -391.777412) (xy 364.3689 -391.757596) (xy 364.320357 -391.730445)
			(xy 364.276271 -391.696533) (xy 364.237576 -391.65658) (xy 364.205092 -391.611431) (xy 364.179507 -391.562045)
			(xy 364.16996 -391.53592) (xy 364.164626 -391.520426) (xy 364.138464 -391.50163) (xy 359.077514 -391.50163)
			(xy 359.068722 -391.501997) (xy 359.052176 -391.507945) (xy 359.038621 -391.519144) (xy 359.033826 -391.526522)
			(xy 358.982264 -391.61339) (xy 358.981756 -391.639806) (xy 358.988106 -391.651744) (xy 359.002715 -391.6799)
			(xy 359.02342 -391.739854) (xy 359.033948 -391.802402) (xy 359.034588 -391.834116) (xy 359.033964 -391.865767)
			(xy 359.023488 -391.928196) (xy 359.01376 -391.958322) (xy 359.011313 -391.966614) (xy 359.011574 -391.983889)
			(xy 359.014268 -391.992104) (xy 359.024428 -392.020298) (xy 359.027798 -392.028497) (xy 359.039089 -392.042146)
			(xy 359.046526 -392.046968) (xy 359.074863 -392.064128) (xy 359.127251 -392.104676) (xy 359.147629 -392.1252)
			(xy 366.783872 -392.1252) (xy 366.787943 -392.069578) (xy 366.800069 -392.015141) (xy 366.819992 -391.96305)
			(xy 366.847288 -391.914415) (xy 366.881374 -391.870272) (xy 366.921523 -391.831563) (xy 366.966881 -391.799112)
			(xy 367.016481 -391.773611) (xy 367.069265 -391.755604) (xy 367.124108 -391.745474) (xy 367.179842 -391.743437)
			(xy 367.235279 -391.749537) (xy 367.289236 -391.763643) (xy 367.340565 -391.785455) (xy 367.388171 -391.814509)
			(xy 367.431039 -391.850184) (xy 367.468256 -391.891721) (xy 367.499029 -391.938234) (xy 367.522701 -391.988731)
			(xy 367.538769 -392.042138) (xy 367.546889 -392.097314) (xy 367.547398 -392.1252) (xy 367.546889 -392.153086)
			(xy 367.538769 -392.208262) (xy 367.522701 -392.261669) (xy 367.499029 -392.312166) (xy 367.468256 -392.358679)
			(xy 367.431039 -392.400216) (xy 367.388171 -392.435891) (xy 367.340565 -392.464945) (xy 367.289236 -392.486757)
			(xy 367.235279 -392.500863) (xy 367.179842 -392.506963) (xy 367.124108 -392.504926) (xy 367.069265 -392.494796)
			(xy 367.016481 -392.476789) (xy 366.966881 -392.451288) (xy 366.921523 -392.418837) (xy 366.881374 -392.380128)
			(xy 366.847288 -392.335985) (xy 366.819992 -392.28735) (xy 366.800069 -392.235259) (xy 366.787943 -392.180822)
			(xy 366.783872 -392.1252) (xy 359.147629 -392.1252) (xy 359.173927 -392.151687) (xy 359.214098 -392.204364)
			(xy 359.247086 -392.261813) (xy 359.272329 -392.323062) (xy 359.2894 -392.387072) (xy 359.29801 -392.452757)
			(xy 359.298494 -392.48588) (xy 359.29805 -392.515991) (xy 359.290937 -392.57579) (xy 359.276807 -392.63433)
			(xy 359.255858 -392.69079) (xy 359.228385 -392.744379) (xy 359.194771 -392.794347) (xy 359.155489 -392.839992)
			(xy 359.111089 -392.880676) (xy 359.086912 -392.89863) (xy 359.07749 -392.906292) (xy 359.066492 -392.927905)
			(xy 359.06583 -392.940032) (xy 359.06583 -393.022328) (xy 359.066462 -393.034459) (xy 359.071676 -393.04468)
			(xy 366.783872 -393.04468) (xy 366.787943 -392.989058) (xy 366.800069 -392.934621) (xy 366.819992 -392.88253)
			(xy 366.847288 -392.833895) (xy 366.881374 -392.789752) (xy 366.921523 -392.751043) (xy 366.966881 -392.718592)
			(xy 367.016481 -392.693091) (xy 367.069265 -392.675084) (xy 367.124108 -392.664954) (xy 367.179842 -392.662917)
			(xy 367.235279 -392.669017) (xy 367.289236 -392.683123) (xy 367.340565 -392.704935) (xy 367.388171 -392.733989)
			(xy 367.43065 -392.76934) (xy 368.04395 -392.76934) (xy 368.04395 -392.709404) (xy 368.051773 -392.649982)
			(xy 368.067286 -392.592089) (xy 368.090222 -392.536716) (xy 368.120189 -392.48481) (xy 368.156676 -392.43726)
			(xy 368.199056 -392.39488) (xy 368.246606 -392.358393) (xy 368.298512 -392.328426) (xy 368.353885 -392.30549)
			(xy 368.411778 -392.289977) (xy 368.4712 -392.282154) (xy 368.531136 -392.282154) (xy 368.590558 -392.289977)
			(xy 368.648451 -392.30549) (xy 368.703824 -392.328426) (xy 368.75573 -392.358393) (xy 368.80328 -392.39488)
			(xy 368.84566 -392.43726) (xy 368.882147 -392.48481) (xy 368.912114 -392.536716) (xy 368.93505 -392.592089)
			(xy 368.950563 -392.649982) (xy 368.958386 -392.709404) (xy 368.958876 -392.739372) (xy 368.958386 -392.76934)
			(xy 368.950563 -392.828762) (xy 368.93505 -392.886655) (xy 368.912114 -392.942028) (xy 368.882147 -392.993934)
			(xy 368.84566 -393.041484) (xy 368.80328 -393.083864) (xy 368.75573 -393.120351) (xy 368.703824 -393.150318)
			(xy 368.648451 -393.173254) (xy 368.590558 -393.188767) (xy 368.531136 -393.19659) (xy 368.4712 -393.19659)
			(xy 368.411778 -393.188767) (xy 368.353885 -393.173254) (xy 368.298512 -393.150318) (xy 368.246606 -393.120351)
			(xy 368.199056 -393.083864) (xy 368.156676 -393.041484) (xy 368.120189 -392.993934) (xy 368.090222 -392.942028)
			(xy 368.067286 -392.886655) (xy 368.051773 -392.828762) (xy 368.04395 -392.76934) (xy 367.43065 -392.76934)
			(xy 367.431039 -392.769664) (xy 367.468256 -392.811201) (xy 367.499029 -392.857714) (xy 367.522701 -392.908211)
			(xy 367.538769 -392.961618) (xy 367.546889 -393.016794) (xy 367.547398 -393.04468) (xy 367.546889 -393.072566)
			(xy 367.538769 -393.127742) (xy 367.522701 -393.181149) (xy 367.499029 -393.231646) (xy 367.468256 -393.278159)
			(xy 367.431039 -393.319696) (xy 367.388171 -393.355371) (xy 367.340565 -393.384425) (xy 367.289236 -393.406237)
			(xy 367.235279 -393.420343) (xy 367.179842 -393.426443) (xy 367.124108 -393.424406) (xy 367.069265 -393.414276)
			(xy 367.016481 -393.396269) (xy 366.966881 -393.370768) (xy 366.921523 -393.338317) (xy 366.881374 -393.299608)
			(xy 366.847288 -393.255465) (xy 366.819992 -393.20683) (xy 366.800069 -393.154739) (xy 366.787943 -393.100302)
			(xy 366.783872 -393.04468) (xy 359.071676 -393.04468) (xy 359.077484 -393.056066) (xy 359.086912 -393.06373)
			(xy 359.111091 -393.081677) (xy 359.155473 -393.122374) (xy 359.194739 -393.168028) (xy 359.228341 -393.217998)
			(xy 359.255807 -393.271587) (xy 359.276753 -393.328043) (xy 359.290887 -393.386578) (xy 359.298011 -393.446372)
			(xy 359.298494 -393.47648) (xy 359.29805 -393.507213) (xy 359.290643 -393.56823) (xy 359.275935 -393.627909)
			(xy 359.254141 -393.685381) (xy 359.225577 -393.739806) (xy 359.190662 -393.790391) (xy 359.149903 -393.836399)
			(xy 359.103896 -393.877158) (xy 359.053311 -393.912074) (xy 358.998886 -393.940638) (xy 358.941415 -393.962433)
			(xy 358.881736 -393.977142) (xy 358.820719 -393.984549) (xy 358.789986 -393.984988) (xy 358.75967 -393.984565)
			(xy 358.699464 -393.977386) (xy 358.64054 -393.963095) (xy 358.583734 -393.941896) (xy 358.529854 -393.914089)
			(xy 358.479665 -393.88007) (xy 358.456484 -393.860528) (xy 358.449626 -393.854178) (xy 358.432608 -393.848082)
			(xy 358.347264 -393.848082) (xy 358.330246 -393.854178) (xy 358.323388 -393.860528) (xy 358.295956 -393.882626)
			(xy 358.286608 -393.89053) (xy 358.276004 -393.912553) (xy 358.275636 -393.92479) (xy 358.276652 -393.956286)
			(xy 358.277795 -393.968526) (xy 358.289862 -393.9899) (xy 358.291976 -393.991454) (xy 366.784838 -393.991454)
			(xy 366.784838 -393.936946) (xy 366.792595 -393.882994) (xy 366.807951 -393.830694) (xy 366.830594 -393.781113)
			(xy 366.860062 -393.735258) (xy 366.895757 -393.694064) (xy 366.93695 -393.658368) (xy 366.982804 -393.628899)
			(xy 367.032385 -393.606255) (xy 367.084684 -393.590897) (xy 367.138636 -393.583139) (xy 367.16589 -393.582652)
			(xy 367.194525 -393.583129) (xy 367.251151 -393.591702) (xy 367.30586 -393.60864) (xy 367.357424 -393.633564)
			(xy 367.404683 -393.665913) (xy 367.446577 -393.704963) (xy 367.482166 -393.749834) (xy 367.496852 -393.774422)
			(xy 367.503964 -393.786614) (xy 367.52784 -393.80033) (xy 367.644934 -393.798044) (xy 367.668302 -393.78382)
			(xy 367.674906 -393.771374) (xy 367.689842 -393.744121) (xy 367.725972 -393.693556) (xy 367.768616 -393.648348)
			(xy 367.816987 -393.609329) (xy 367.870195 -393.577217) (xy 367.92726 -393.552604) (xy 367.987132 -393.535943)
			(xy 368.048708 -393.527541) (xy 368.079782 -393.527026) (xy 368.109752 -393.527478) (xy 368.169179 -393.5353)
			(xy 368.227077 -393.550812) (xy 368.282455 -393.57375) (xy 368.334365 -393.60372) (xy 368.381918 -393.640209)
			(xy 368.424301 -393.682594) (xy 368.460789 -393.730149) (xy 368.490757 -393.782059) (xy 368.513693 -393.837438)
			(xy 368.529203 -393.895336) (xy 368.537023 -393.954764) (xy 368.53749 -393.984734) (xy 368.536981 -394.015614)
			(xy 368.528666 -394.076811) (xy 368.512191 -394.136333) (xy 368.487858 -394.193096) (xy 368.456107 -394.246069)
			(xy 368.446935 -394.25753) (xy 369.933982 -394.25753) (xy 369.934503 -394.231542) (xy 369.942629 -394.180205)
			(xy 369.958687 -394.130772) (xy 369.98228 -394.08446) (xy 370.012828 -394.042408) (xy 370.049578 -394.005654)
			(xy 370.091626 -393.975101) (xy 370.137935 -393.951502) (xy 370.187366 -393.935439) (xy 370.238702 -393.927306)
			(xy 370.26469 -393.926822) (xy 370.281123 -393.92704) (xy 370.313823 -393.930353) (xy 370.329968 -393.933426)
			(xy 370.342922 -393.935966) (xy 370.368068 -393.928092) (xy 370.445284 -393.846304) (xy 370.451888 -393.820904)
			(xy 370.448586 -393.808204) (xy 370.441579 -393.779762) (xy 370.434062 -393.721669) (xy 370.4336 -393.69238)
			(xy 370.434126 -393.661492) (xy 370.442431 -393.600277) (xy 370.458888 -393.540733) (xy 370.483198 -393.483941)
			(xy 370.498624 -393.457176) (xy 370.504466 -393.44727) (xy 370.506752 -393.424918) (xy 370.473478 -393.329668)
			(xy 370.45773 -393.313666) (xy 370.447062 -393.309602) (xy 370.423673 -393.300436) (xy 370.379777 -393.276013)
			(xy 370.340082 -393.245229) (xy 370.305502 -393.208793) (xy 370.276834 -393.167544) (xy 370.254737 -393.122432)
			(xy 370.239721 -393.074495) (xy 370.232132 -393.024839) (xy 370.23167 -392.999722) (xy 370.23218 -392.973735)
			(xy 370.24031 -392.9224) (xy 370.256371 -392.87297) (xy 370.279967 -392.82666) (xy 370.310517 -392.784612)
			(xy 370.347268 -392.747861) (xy 370.389316 -392.717311) (xy 370.435626 -392.693715) (xy 370.485056 -392.677654)
			(xy 370.536391 -392.669524) (xy 370.588365 -392.669524) (xy 370.6397 -392.677654) (xy 370.68913 -392.693715)
			(xy 370.73544 -392.717311) (xy 370.777488 -392.747861) (xy 370.814239 -392.784612) (xy 370.844789 -392.82666)
			(xy 370.868385 -392.87297) (xy 370.884446 -392.9224) (xy 370.892576 -392.973735) (xy 370.893086 -392.999722)
			(xy 371.431566 -392.999722) (xy 371.432076 -392.973735) (xy 371.440206 -392.9224) (xy 371.456267 -392.87297)
			(xy 371.479863 -392.82666) (xy 371.510413 -392.784612) (xy 371.547164 -392.747861) (xy 371.589212 -392.717311)
			(xy 371.635522 -392.693715) (xy 371.684952 -392.677654) (xy 371.736287 -392.669524) (xy 371.788261 -392.669524)
			(xy 371.839596 -392.677654) (xy 371.889026 -392.693715) (xy 371.935336 -392.717311) (xy 371.977384 -392.747861)
			(xy 372.014135 -392.784612) (xy 372.044685 -392.82666) (xy 372.068281 -392.87297) (xy 372.084342 -392.9224)
			(xy 372.092472 -392.973735) (xy 372.092982 -392.999722) (xy 372.631716 -392.999722) (xy 372.632226 -392.973735)
			(xy 372.640356 -392.9224) (xy 372.656417 -392.87297) (xy 372.680013 -392.82666) (xy 372.710563 -392.784612)
			(xy 372.747314 -392.747861) (xy 372.789362 -392.717311) (xy 372.835672 -392.693715) (xy 372.885102 -392.677654)
			(xy 372.936437 -392.669524) (xy 372.988411 -392.669524) (xy 373.039746 -392.677654) (xy 373.089176 -392.693715)
			(xy 373.135486 -392.717311) (xy 373.177534 -392.747861) (xy 373.214285 -392.784612) (xy 373.244835 -392.82666)
			(xy 373.268431 -392.87297) (xy 373.284492 -392.9224) (xy 373.292622 -392.973735) (xy 373.293132 -392.999722)
			(xy 373.831612 -392.999722) (xy 373.832122 -392.973735) (xy 373.840252 -392.9224) (xy 373.856313 -392.87297)
			(xy 373.879909 -392.82666) (xy 373.910459 -392.784612) (xy 373.94721 -392.747861) (xy 373.989258 -392.717311)
			(xy 374.035568 -392.693715) (xy 374.084998 -392.677654) (xy 374.136333 -392.669524) (xy 374.188307 -392.669524)
			(xy 374.239642 -392.677654) (xy 374.289072 -392.693715) (xy 374.335382 -392.717311) (xy 374.37743 -392.747861)
			(xy 374.414181 -392.784612) (xy 374.444731 -392.82666) (xy 374.468327 -392.87297) (xy 374.484388 -392.9224)
			(xy 374.492518 -392.973735) (xy 374.493028 -392.999722) (xy 375.031762 -392.999722) (xy 375.032272 -392.973735)
			(xy 375.040402 -392.9224) (xy 375.056463 -392.87297) (xy 375.080059 -392.82666) (xy 375.110609 -392.784612)
			(xy 375.14736 -392.747861) (xy 375.189408 -392.717311) (xy 375.235718 -392.693715) (xy 375.285148 -392.677654)
			(xy 375.336483 -392.669524) (xy 375.388457 -392.669524) (xy 375.439792 -392.677654) (xy 375.489222 -392.693715)
			(xy 375.535532 -392.717311) (xy 375.57758 -392.747861) (xy 375.614331 -392.784612) (xy 375.644881 -392.82666)
			(xy 375.668477 -392.87297) (xy 375.684538 -392.9224) (xy 375.692668 -392.973735) (xy 375.693178 -392.999722)
			(xy 376.231658 -392.999722) (xy 376.232168 -392.973735) (xy 376.240298 -392.9224) (xy 376.256359 -392.87297)
			(xy 376.279955 -392.82666) (xy 376.310505 -392.784612) (xy 376.347256 -392.747861) (xy 376.389304 -392.717311)
			(xy 376.435614 -392.693715) (xy 376.485044 -392.677654) (xy 376.536379 -392.669524) (xy 376.588353 -392.669524)
			(xy 376.639688 -392.677654) (xy 376.689118 -392.693715) (xy 376.735428 -392.717311) (xy 376.777476 -392.747861)
			(xy 376.814227 -392.784612) (xy 376.844777 -392.82666) (xy 376.868373 -392.87297) (xy 376.884434 -392.9224)
			(xy 376.892564 -392.973735) (xy 376.893074 -392.999722) (xy 377.431554 -392.999722) (xy 377.432064 -392.973735)
			(xy 377.440194 -392.9224) (xy 377.456255 -392.87297) (xy 377.479851 -392.82666) (xy 377.510401 -392.784612)
			(xy 377.547152 -392.747861) (xy 377.5892 -392.717311) (xy 377.63551 -392.693715) (xy 377.68494 -392.677654)
			(xy 377.736275 -392.669524) (xy 377.788249 -392.669524) (xy 377.839584 -392.677654) (xy 377.889014 -392.693715)
			(xy 377.935324 -392.717311) (xy 377.977372 -392.747861) (xy 378.014123 -392.784612) (xy 378.044673 -392.82666)
			(xy 378.068269 -392.87297) (xy 378.08433 -392.9224) (xy 378.09246 -392.973735) (xy 378.09297 -392.999722)
			(xy 378.631704 -392.999722) (xy 378.632214 -392.973735) (xy 378.640344 -392.9224) (xy 378.656405 -392.87297)
			(xy 378.680001 -392.82666) (xy 378.710551 -392.784612) (xy 378.747302 -392.747861) (xy 378.78935 -392.717311)
			(xy 378.83566 -392.693715) (xy 378.88509 -392.677654) (xy 378.936425 -392.669524) (xy 378.988399 -392.669524)
			(xy 379.039734 -392.677654) (xy 379.089164 -392.693715) (xy 379.135474 -392.717311) (xy 379.177522 -392.747861)
			(xy 379.214273 -392.784612) (xy 379.244823 -392.82666) (xy 379.268419 -392.87297) (xy 379.28448 -392.9224)
			(xy 379.29261 -392.973735) (xy 379.29312 -392.999722) (xy 379.8316 -392.999722) (xy 379.83211 -392.973735)
			(xy 379.84024 -392.9224) (xy 379.856301 -392.87297) (xy 379.879897 -392.82666) (xy 379.910447 -392.784612)
			(xy 379.947198 -392.747861) (xy 379.989246 -392.717311) (xy 380.035556 -392.693715) (xy 380.084986 -392.677654)
			(xy 380.136321 -392.669524) (xy 380.188295 -392.669524) (xy 380.23963 -392.677654) (xy 380.28906 -392.693715)
			(xy 380.33537 -392.717311) (xy 380.377418 -392.747861) (xy 380.414169 -392.784612) (xy 380.444719 -392.82666)
			(xy 380.468315 -392.87297) (xy 380.484376 -392.9224) (xy 380.492506 -392.973735) (xy 380.493016 -392.999722)
			(xy 381.03175 -392.999722) (xy 381.03226 -392.973735) (xy 381.04039 -392.9224) (xy 381.056451 -392.87297)
			(xy 381.080047 -392.82666) (xy 381.110597 -392.784612) (xy 381.147348 -392.747861) (xy 381.189396 -392.717311)
			(xy 381.235706 -392.693715) (xy 381.285136 -392.677654) (xy 381.336471 -392.669524) (xy 381.388445 -392.669524)
			(xy 381.43978 -392.677654) (xy 381.48921 -392.693715) (xy 381.53552 -392.717311) (xy 381.577568 -392.747861)
			(xy 381.614319 -392.784612) (xy 381.644869 -392.82666) (xy 381.668465 -392.87297) (xy 381.684526 -392.9224)
			(xy 381.692656 -392.973735) (xy 381.693166 -392.999722) (xy 382.231646 -392.999722) (xy 382.232156 -392.973735)
			(xy 382.240286 -392.9224) (xy 382.256347 -392.87297) (xy 382.279943 -392.82666) (xy 382.310493 -392.784612)
			(xy 382.347244 -392.747861) (xy 382.389292 -392.717311) (xy 382.435602 -392.693715) (xy 382.485032 -392.677654)
			(xy 382.536367 -392.669524) (xy 382.588341 -392.669524) (xy 382.639676 -392.677654) (xy 382.689106 -392.693715)
			(xy 382.735416 -392.717311) (xy 382.777464 -392.747861) (xy 382.814215 -392.784612) (xy 382.844765 -392.82666)
			(xy 382.868361 -392.87297) (xy 382.884422 -392.9224) (xy 382.892552 -392.973735) (xy 382.893062 -392.999722)
			(xy 383.431542 -392.999722) (xy 383.432052 -392.973735) (xy 383.440182 -392.9224) (xy 383.456243 -392.87297)
			(xy 383.479839 -392.82666) (xy 383.510389 -392.784612) (xy 383.54714 -392.747861) (xy 383.589188 -392.717311)
			(xy 383.635498 -392.693715) (xy 383.684928 -392.677654) (xy 383.736263 -392.669524) (xy 383.788237 -392.669524)
			(xy 383.839572 -392.677654) (xy 383.889002 -392.693715) (xy 383.935312 -392.717311) (xy 383.97736 -392.747861)
			(xy 384.014111 -392.784612) (xy 384.044661 -392.82666) (xy 384.068257 -392.87297) (xy 384.084318 -392.9224)
			(xy 384.092448 -392.973735) (xy 384.092958 -392.999722) (xy 384.631692 -392.999722) (xy 384.632202 -392.973735)
			(xy 384.640332 -392.9224) (xy 384.656393 -392.87297) (xy 384.679989 -392.82666) (xy 384.710539 -392.784612)
			(xy 384.74729 -392.747861) (xy 384.789338 -392.717311) (xy 384.835648 -392.693715) (xy 384.885078 -392.677654)
			(xy 384.936413 -392.669524) (xy 384.988387 -392.669524) (xy 385.039722 -392.677654) (xy 385.089152 -392.693715)
			(xy 385.135462 -392.717311) (xy 385.17751 -392.747861) (xy 385.214261 -392.784612) (xy 385.244811 -392.82666)
			(xy 385.268407 -392.87297) (xy 385.284468 -392.9224) (xy 385.292598 -392.973735) (xy 385.293108 -392.999722)
			(xy 385.831588 -392.999722) (xy 385.832098 -392.973735) (xy 385.840228 -392.9224) (xy 385.856289 -392.87297)
			(xy 385.879885 -392.82666) (xy 385.910435 -392.784612) (xy 385.947186 -392.747861) (xy 385.989234 -392.717311)
			(xy 386.035544 -392.693715) (xy 386.084974 -392.677654) (xy 386.136309 -392.669524) (xy 386.188283 -392.669524)
			(xy 386.239618 -392.677654) (xy 386.289048 -392.693715) (xy 386.335358 -392.717311) (xy 386.377406 -392.747861)
			(xy 386.414157 -392.784612) (xy 386.444707 -392.82666) (xy 386.468303 -392.87297) (xy 386.484364 -392.9224)
			(xy 386.492494 -392.973735) (xy 386.493004 -392.999722) (xy 387.031738 -392.999722) (xy 387.032248 -392.973735)
			(xy 387.040378 -392.9224) (xy 387.056439 -392.87297) (xy 387.080035 -392.82666) (xy 387.110585 -392.784612)
			(xy 387.147336 -392.747861) (xy 387.189384 -392.717311) (xy 387.235694 -392.693715) (xy 387.285124 -392.677654)
			(xy 387.336459 -392.669524) (xy 387.388433 -392.669524) (xy 387.439768 -392.677654) (xy 387.489198 -392.693715)
			(xy 387.535508 -392.717311) (xy 387.577556 -392.747861) (xy 387.614307 -392.784612) (xy 387.644857 -392.82666)
			(xy 387.668453 -392.87297) (xy 387.684514 -392.9224) (xy 387.692644 -392.973735) (xy 387.693154 -392.999722)
			(xy 388.231634 -392.999722) (xy 388.232144 -392.973735) (xy 388.240274 -392.9224) (xy 388.256335 -392.87297)
			(xy 388.279931 -392.82666) (xy 388.310481 -392.784612) (xy 388.347232 -392.747861) (xy 388.38928 -392.717311)
			(xy 388.43559 -392.693715) (xy 388.48502 -392.677654) (xy 388.536355 -392.669524) (xy 388.588329 -392.669524)
			(xy 388.639664 -392.677654) (xy 388.689094 -392.693715) (xy 388.735404 -392.717311) (xy 388.777452 -392.747861)
			(xy 388.814203 -392.784612) (xy 388.844753 -392.82666) (xy 388.868349 -392.87297) (xy 388.88441 -392.9224)
			(xy 388.89254 -392.973735) (xy 388.89305 -392.999722) (xy 388.89252 -393.026824) (xy 388.883711 -393.080307)
			(xy 388.875524 -393.106148) (xy 388.871714 -393.11707) (xy 388.874254 -393.139422) (xy 388.926832 -393.225274)
			(xy 388.945882 -393.23772) (xy 388.957058 -393.239498) (xy 388.98638 -393.244184) (xy 389.04355 -393.260236)
			(xy 389.098164 -393.283549) (xy 389.149303 -393.313731) (xy 389.196109 -393.350274) (xy 389.237793 -393.392565)
			(xy 389.273657 -393.439894) (xy 389.303096 -393.491464) (xy 389.319442 -393.531344) (xy 390.402318 -393.531344)
			(xy 390.402744 -393.502708) (xy 390.409901 -393.445886) (xy 390.424083 -393.390398) (xy 390.44507 -393.33711)
			(xy 390.472534 -393.286854) (xy 390.488932 -393.263374) (xy 390.494609 -393.254857) (xy 390.499219 -393.23493)
			(xy 390.495651 -393.214791) (xy 390.490456 -393.20597) (xy 390.472968 -393.177993) (xy 390.445339 -393.11808)
			(xy 390.426594 -393.054823) (xy 390.417121 -392.98953) (xy 390.416542 -392.956542) (xy 390.417008 -392.927301)
			(xy 390.424441 -392.869294) (xy 390.439202 -392.812707) (xy 390.461052 -392.758461) (xy 390.489635 -392.70744)
			(xy 390.524485 -392.660477) (xy 390.565034 -392.618336) (xy 390.61062 -392.581704) (xy 390.660503 -392.551179)
			(xy 390.713867 -392.527256) (xy 390.769844 -392.510327) (xy 390.827522 -392.500667) (xy 390.856724 -392.499088)
			(xy 390.866376 -392.498834) (xy 390.883902 -392.491214) (xy 390.946386 -392.428222) (xy 390.954006 -392.41095)
			(xy 390.95426 -392.401044) (xy 390.955853 -392.368494) (xy 390.966342 -392.304173) (xy 390.984963 -392.241719)
			(xy 391.01141 -392.182156) (xy 391.04525 -392.12646) (xy 391.085928 -392.075543) (xy 391.132777 -392.030241)
			(xy 391.18503 -391.991295) (xy 391.241831 -391.959344) (xy 391.302248 -391.934911) (xy 391.365292 -391.918398)
			(xy 391.429929 -391.910074) (xy 391.462514 -391.909554) (xy 391.496097 -391.910127) (xy 391.56268 -391.918952)
			(xy 391.62752 -391.936472) (xy 391.689486 -391.962382) (xy 391.747498 -391.996231) (xy 391.800545 -392.037428)
			(xy 391.847702 -392.085255) (xy 391.888146 -392.138879) (xy 391.921173 -392.197363) (xy 391.934192 -392.228324)
			(xy 391.93978 -392.24204) (xy 391.963402 -392.259058) (xy 392.08456 -392.266678) (xy 392.110214 -392.252454)
			(xy 392.117326 -392.2395) (xy 392.134272 -392.210171) (xy 392.174678 -392.15581) (xy 392.22194 -392.10729)
			(xy 392.275222 -392.065469) (xy 392.333581 -392.031087) (xy 392.395986 -392.004752) (xy 392.461333 -391.986929)
			(xy 392.528467 -391.977934) (xy 392.562334 -391.977372) (xy 392.601586 -391.978139) (xy 392.679151 -391.990257)
			(xy 392.716766 -392.001502) (xy 392.729212 -392.005312) (xy 392.75512 -392.000232) (xy 392.840718 -391.927334)
			(xy 392.850116 -391.902696) (xy 392.848084 -391.889742) (xy 392.846185 -391.875914) (xy 392.84415 -391.848073)
			(xy 392.84402 -391.834116) (xy 392.844506 -391.806865) (xy 392.852262 -391.752917) (xy 392.867617 -391.700622)
			(xy 392.890259 -391.651045) (xy 392.919725 -391.605195) (xy 392.955416 -391.564004) (xy 392.996607 -391.528313)
			(xy 393.042457 -391.498847) (xy 393.092034 -391.476205) (xy 393.144329 -391.46085) (xy 393.198277 -391.453094)
			(xy 393.252779 -391.453094) (xy 393.306727 -391.46085) (xy 393.359022 -391.476205) (xy 393.408599 -391.498847)
			(xy 393.454449 -391.528313) (xy 393.49564 -391.564004) (xy 393.531331 -391.605195) (xy 393.560797 -391.651045)
			(xy 393.583439 -391.700622) (xy 393.598794 -391.752917) (xy 393.60655 -391.806865) (xy 393.607036 -391.834116)
			(xy 393.606362 -391.865763) (xy 393.595889 -391.928185) (xy 393.586208 -391.958322) (xy 393.583801 -391.96662)
			(xy 393.584057 -391.983884) (xy 393.586716 -391.992104) (xy 393.596876 -392.020298) (xy 393.60017 -392.028542)
			(xy 393.61148 -392.042209) (xy 393.618974 -392.046968) (xy 393.647294 -392.064152) (xy 393.699674 -392.1047)
			(xy 393.720025 -392.1252) (xy 399.31162 -392.1252) (xy 399.315691 -392.069578) (xy 399.327817 -392.015141)
			(xy 399.34774 -391.96305) (xy 399.375036 -391.914415) (xy 399.409122 -391.870272) (xy 399.449271 -391.831563)
			(xy 399.494629 -391.799112) (xy 399.544229 -391.773611) (xy 399.597013 -391.755604) (xy 399.651856 -391.745474)
			(xy 399.70759 -391.743437) (xy 399.763027 -391.749537) (xy 399.816984 -391.763643) (xy 399.868313 -391.785455)
			(xy 399.915919 -391.814509) (xy 399.958787 -391.850184) (xy 399.996004 -391.891721) (xy 400.026777 -391.938234)
			(xy 400.050449 -391.988731) (xy 400.066517 -392.042138) (xy 400.074637 -392.097314) (xy 400.075146 -392.1252)
			(xy 400.074637 -392.153086) (xy 400.066517 -392.208262) (xy 400.050449 -392.261669) (xy 400.026777 -392.312166)
			(xy 399.996004 -392.358679) (xy 399.958787 -392.400216) (xy 399.915919 -392.435891) (xy 399.868313 -392.464945)
			(xy 399.816984 -392.486757) (xy 399.763027 -392.500863) (xy 399.70759 -392.506963) (xy 399.651856 -392.504926)
			(xy 399.597013 -392.494796) (xy 399.544229 -392.476789) (xy 399.494629 -392.451288) (xy 399.449271 -392.418837)
			(xy 399.409122 -392.380128) (xy 399.375036 -392.335985) (xy 399.34774 -392.28735) (xy 399.327817 -392.235259)
			(xy 399.315691 -392.180822) (xy 399.31162 -392.1252) (xy 393.720025 -392.1252) (xy 393.746343 -392.15171)
			(xy 393.786509 -392.204385) (xy 393.819491 -392.261831) (xy 393.84473 -392.323076) (xy 393.861799 -392.38708)
			(xy 393.870407 -392.452759) (xy 393.870942 -392.48588) (xy 393.870485 -392.515989) (xy 393.863354 -392.575783)
			(xy 393.849215 -392.634318) (xy 393.828264 -392.690774) (xy 393.800794 -392.744361) (xy 393.767191 -392.794331)
			(xy 393.727923 -392.839985) (xy 393.68354 -392.880683) (xy 393.65936 -392.89863) (xy 393.649895 -392.906255)
			(xy 393.638895 -392.927892) (xy 393.638278 -392.940032) (xy 393.638278 -393.022328) (xy 393.638886 -393.034463)
			(xy 393.644102 -393.04468) (xy 399.31162 -393.04468) (xy 399.315691 -392.989058) (xy 399.327817 -392.934621)
			(xy 399.34774 -392.88253) (xy 399.375036 -392.833895) (xy 399.409122 -392.789752) (xy 399.449271 -392.751043)
			(xy 399.494629 -392.718592) (xy 399.544229 -392.693091) (xy 399.597013 -392.675084) (xy 399.651856 -392.664954)
			(xy 399.70759 -392.662917) (xy 399.763027 -392.669017) (xy 399.816984 -392.683123) (xy 399.868313 -392.704935)
			(xy 399.915919 -392.733989) (xy 399.958787 -392.769664) (xy 399.996004 -392.811201) (xy 400.026777 -392.857714)
			(xy 400.050449 -392.908211) (xy 400.066517 -392.961618) (xy 400.074637 -393.016794) (xy 400.075146 -393.04468)
			(xy 400.074637 -393.072566) (xy 400.066517 -393.127742) (xy 400.050449 -393.181149) (xy 400.026777 -393.231646)
			(xy 399.996004 -393.278159) (xy 399.958787 -393.319696) (xy 399.915919 -393.355371) (xy 399.868313 -393.384425)
			(xy 399.816984 -393.406237) (xy 399.763027 -393.420343) (xy 399.70759 -393.426443) (xy 399.651856 -393.424406)
			(xy 399.597013 -393.414276) (xy 399.544229 -393.396269) (xy 399.494629 -393.370768) (xy 399.449271 -393.338317)
			(xy 399.409122 -393.299608) (xy 399.375036 -393.255465) (xy 399.34774 -393.20683) (xy 399.327817 -393.154739)
			(xy 399.315691 -393.100302) (xy 399.31162 -393.04468) (xy 393.644102 -393.04468) (xy 393.64992 -393.056076)
			(xy 393.65936 -393.06373) (xy 393.683553 -393.081663) (xy 393.727956 -393.122348) (xy 393.767238 -393.167996)
			(xy 393.800851 -393.217966) (xy 393.828323 -393.271559) (xy 393.849268 -393.328022) (xy 393.863394 -393.386566)
			(xy 393.870502 -393.446368) (xy 393.870942 -393.47648) (xy 393.870425 -393.507209) (xy 393.86302 -393.56822)
			(xy 393.848314 -393.627893) (xy 393.826523 -393.685359) (xy 393.797965 -393.739779) (xy 393.763055 -393.79036)
			(xy 393.722303 -393.836365) (xy 393.676303 -393.877122) (xy 393.625725 -393.912037) (xy 393.571308 -393.940601)
			(xy 393.513845 -393.962398) (xy 393.454173 -393.97711) (xy 393.393163 -393.984522) (xy 393.362434 -393.984988)
			(xy 393.330309 -393.984519) (xy 393.266573 -393.976408) (xy 393.204365 -393.960336) (xy 393.144676 -393.936559)
			(xy 393.088457 -393.905456) (xy 393.036601 -393.867521) (xy 393.01293 -393.845796) (xy 393.005585 -393.83945)
			(xy 392.987574 -393.83226) (xy 392.977878 -393.831826) (xy 392.94689 -393.831826) (xy 392.937188 -393.83225)
			(xy 392.919162 -393.839421) (xy 392.911838 -393.845796) (xy 392.89609 -393.860274) (xy 392.8872 -393.867894)
			(xy 392.87831 -393.888468) (xy 392.881612 -393.990576) (xy 392.891772 -394.010642) (xy 392.90117 -394.017754)
			(xy 392.92749 -394.038435) (xy 392.975028 -394.085559) (xy 393.015969 -394.138515) (xy 393.049606 -394.196386)
			(xy 393.075355 -394.258172) (xy 393.092771 -394.322804) (xy 393.101553 -394.389162) (xy 393.102084 -394.42263)
			(xy 393.101672 -394.453363) (xy 393.09426 -394.514379) (xy 393.079547 -394.574057) (xy 393.057748 -394.631527)
			(xy 393.02918 -394.68595) (xy 392.994261 -394.736533) (xy 392.9535 -394.782538) (xy 392.907491 -394.823295)
			(xy 392.856904 -394.858208) (xy 392.802478 -394.88677) (xy 392.745006 -394.908563) (xy 392.685326 -394.923269)
			(xy 392.624309 -394.930675) (xy 392.593576 -394.931138) (xy 392.562074 -394.930654) (xy 392.499553 -394.922865)
			(xy 392.438473 -394.907408) (xy 392.379773 -394.884522) (xy 392.32435 -394.854557) (xy 392.298428 -394.83665)
			(xy 392.287506 -394.82903) (xy 392.261598 -394.826236) (xy 392.157204 -394.870178) (xy 392.141202 -394.890752)
			(xy 392.13917 -394.90396) (xy 392.133738 -394.93631) (xy 392.115508 -394.999324) (xy 392.089327 -395.059472)
			(xy 392.055631 -395.115756) (xy 392.014979 -395.16724) (xy 391.968046 -395.21307) (xy 391.91561 -395.252487)
			(xy 391.858542 -395.284835) (xy 391.797788 -395.309579) (xy 391.734358 -395.326306) (xy 391.669303 -395.33474)
			(xy 391.636504 -395.335252) (xy 391.6051 -395.334723) (xy 391.542771 -395.326988) (xy 391.481869 -395.311636)
			(xy 391.423322 -395.288899) (xy 391.36802 -395.259125) (xy 391.316806 -395.222767) (xy 391.27046 -395.180378)
			(xy 391.229688 -395.132604) (xy 391.19511 -395.080172) (xy 391.167253 -395.023881) (xy 391.14654 -394.964587)
			(xy 391.133288 -394.903193) (xy 391.130028 -394.871956) (xy 391.129012 -394.861796) (xy 391.120376 -394.844778)
			(xy 391.052304 -394.785342) (xy 391.034016 -394.778992) (xy 391.023856 -394.7795) (xy 390.999726 -394.780008)
			(xy 390.968994 -394.779538) (xy 390.907979 -394.772132) (xy 390.848301 -394.757426) (xy 390.790832 -394.735633)
			(xy 390.736408 -394.707072) (xy 390.685823 -394.672158) (xy 390.639817 -394.631402) (xy 390.599058 -394.585397)
			(xy 390.564142 -394.534815) (xy 390.535578 -394.480392) (xy 390.513782 -394.422923) (xy 390.499072 -394.363246)
			(xy 390.491664 -394.302232) (xy 390.491218 -394.2715) (xy 390.491625 -394.240718) (xy 390.499043 -394.179603)
			(xy 390.513782 -394.11983) (xy 390.535626 -394.062273) (xy 390.564257 -394.007772) (xy 390.581388 -393.982194)
			(xy 390.586465 -393.974199) (xy 390.590915 -393.955807) (xy 390.590024 -393.94638) (xy 390.585706 -393.915646)
			(xy 390.584045 -393.906382) (xy 390.57492 -393.889938) (xy 390.567926 -393.883642) (xy 390.5461 -393.864954)
			(xy 390.506795 -393.82304) (xy 390.473047 -393.776535) (xy 390.445387 -393.72617) (xy 390.42425 -393.672739)
			(xy 390.40997 -393.617081) (xy 390.40277 -393.560074) (xy 390.402318 -393.531344) (xy 389.319442 -393.531344)
			(xy 389.325617 -393.546409) (xy 389.340842 -393.603805) (xy 389.348513 -393.662689) (xy 389.34898 -393.69238)
			(xy 389.348453 -393.723443) (xy 389.340041 -393.784996) (xy 389.332216 -393.815062) (xy 389.329422 -393.825222)
			(xy 389.331962 -393.845034) (xy 389.37946 -393.92733) (xy 389.395462 -393.939522) (xy 389.405622 -393.942062)
			(xy 389.434726 -393.950082) (xy 389.490692 -393.972713) (xy 389.543198 -394.002504) (xy 389.591332 -394.038939)
			(xy 389.634259 -394.081385) (xy 389.671234 -394.129105) (xy 389.701615 -394.181272) (xy 389.724875 -394.236981)
			(xy 389.740609 -394.295263) (xy 389.748546 -394.355108) (xy 389.74903 -394.385292) (xy 389.748928 -394.399042)
			(xy 389.747276 -394.426493) (xy 389.745728 -394.440156) (xy 389.74501 -394.448844) (xy 389.748783 -394.465853)
			(xy 389.753094 -394.47343) (xy 389.769096 -394.49883) (xy 389.773866 -394.505866) (xy 389.787108 -394.516508)
			(xy 389.795004 -394.519658) (xy 389.818778 -394.528584) (xy 389.863427 -394.552776) (xy 389.903853 -394.58351)
			(xy 389.939104 -394.620064) (xy 389.968352 -394.661577) (xy 389.99091 -394.707074) (xy 390.006246 -394.755485)
			(xy 390.014001 -394.805671) (xy 390.01446 -394.831062) (xy 390.01399 -394.857053) (xy 390.005863 -394.908395)
			(xy 389.989803 -394.957833) (xy 389.966205 -395.004149) (xy 389.935652 -395.046203) (xy 389.898895 -395.082959)
			(xy 389.85684 -395.113511) (xy 389.810523 -395.137106) (xy 389.761085 -395.153165) (xy 389.709743 -395.16129)
			(xy 389.683752 -395.16177) (xy 389.658845 -395.161272) (xy 389.60959 -395.153821) (xy 389.562012 -395.139065)
			(xy 389.517185 -395.117338) (xy 389.476125 -395.089132) (xy 389.439762 -395.055085) (xy 389.408918 -395.015968)
			(xy 389.384292 -394.972666) (xy 389.366441 -394.92616) (xy 389.360664 -394.901928) (xy 389.358501 -394.893708)
			(xy 389.34969 -394.879187) (xy 389.343392 -394.87348) (xy 389.320024 -394.85443) (xy 389.313135 -394.849225)
			(xy 389.2969 -394.843381) (xy 389.288274 -394.843) (xy 389.258437 -394.842297) (xy 389.199315 -394.834148)
			(xy 389.141753 -394.818384) (xy 389.086729 -394.795272) (xy 389.035176 -394.765204) (xy 388.987969 -394.728689)
			(xy 388.945908 -394.686349) (xy 388.909707 -394.6389) (xy 388.879981 -394.587149) (xy 388.857234 -394.531972)
			(xy 388.841852 -394.474308) (xy 388.834095 -394.415133) (xy 388.833614 -394.385292) (xy 388.834136 -394.354229)
			(xy 388.842551 -394.292675) (xy 388.850378 -394.26261) (xy 388.853172 -394.25245) (xy 388.850632 -394.232638)
			(xy 388.803134 -394.150342) (xy 388.787132 -394.13815) (xy 388.776972 -394.13561) (xy 388.747859 -394.12762)
			(xy 388.691891 -394.104986) (xy 388.639385 -394.075192) (xy 388.59125 -394.038754) (xy 388.548323 -393.996305)
			(xy 388.511349 -393.94858) (xy 388.480969 -393.89641) (xy 388.457712 -393.840699) (xy 388.44198 -393.782413)
			(xy 388.434046 -393.722566) (xy 388.433564 -393.69238) (xy 388.434081 -393.661492) (xy 388.442387 -393.600276)
			(xy 388.458846 -393.540731) (xy 388.48316 -393.48394) (xy 388.498588 -393.457176) (xy 388.50443 -393.44727)
			(xy 388.506716 -393.424918) (xy 388.473442 -393.329668) (xy 388.457694 -393.313666) (xy 388.447026 -393.309602)
			(xy 388.423629 -393.300456) (xy 388.379734 -393.276028) (xy 388.340041 -393.24524) (xy 388.305462 -393.208801)
			(xy 388.276795 -393.167549) (xy 388.2547 -393.122435) (xy 388.239685 -393.074497) (xy 388.232096 -393.024839)
			(xy 388.231634 -392.999722) (xy 387.693154 -392.999722) (xy 387.692624 -393.026824) (xy 387.683814 -393.080307)
			(xy 387.675628 -393.106148) (xy 387.671818 -393.11707) (xy 387.674358 -393.139422) (xy 387.726936 -393.225274)
			(xy 387.745986 -393.23772) (xy 387.757162 -393.239498) (xy 387.786484 -393.244181) (xy 387.843655 -393.260233)
			(xy 387.898269 -393.283547) (xy 387.949408 -393.313729) (xy 387.996213 -393.350273) (xy 388.037897 -393.392564)
			(xy 388.073761 -393.439893) (xy 388.1032 -393.491463) (xy 388.125722 -393.546408) (xy 388.140946 -393.603805)
			(xy 388.148617 -393.662689) (xy 388.149084 -393.69238) (xy 388.14856 -393.723506) (xy 388.140155 -393.785188)
			(xy 388.13232 -393.815316) (xy 388.129526 -393.825476) (xy 388.132066 -393.845542) (xy 388.17931 -393.92733)
			(xy 388.195312 -393.939522) (xy 388.205472 -393.942062) (xy 388.234585 -393.950048) (xy 388.290551 -393.972685)
			(xy 388.343056 -394.002482) (xy 388.391189 -394.038921) (xy 388.434115 -394.081371) (xy 388.471088 -394.129095)
			(xy 388.501468 -394.181265) (xy 388.524726 -394.236976) (xy 388.54046 -394.29526) (xy 388.548397 -394.355107)
			(xy 388.54888 -394.385292) (xy 388.548755 -394.399427) (xy 388.546973 -394.427641) (xy 388.545324 -394.44168)
			(xy 388.544568 -394.450287) (xy 388.548205 -394.467166) (xy 388.552436 -394.4747) (xy 388.568184 -394.5001)
			(xy 388.572896 -394.507158) (xy 388.586 -394.517928) (xy 388.593838 -394.521182) (xy 388.617221 -394.530361)
			(xy 388.661117 -394.554783) (xy 388.700812 -394.585565) (xy 388.735392 -394.621999) (xy 388.764061 -394.663246)
			(xy 388.786158 -394.708357) (xy 388.801176 -394.756291) (xy 388.808767 -394.805946) (xy 388.80923 -394.831062)
			(xy 388.808816 -394.855265) (xy 388.801741 -394.90315) (xy 388.787752 -394.94949) (xy 388.767148 -394.993291)
			(xy 388.754112 -395.013688) (xy 388.74932 -395.021642) (xy 388.74529 -395.039755) (xy 388.746238 -395.048994)
			(xy 388.750556 -395.079982) (xy 388.752251 -395.089275) (xy 388.761524 -395.105717) (xy 388.76859 -395.111986)
			(xy 388.790684 -395.130661) (xy 388.830454 -395.172675) (xy 388.864615 -395.219365) (xy 388.892621 -395.269985)
			(xy 388.914028 -395.323731) (xy 388.928492 -395.379746) (xy 388.935785 -395.437136) (xy 388.93623 -395.466062)
			(xy 392.983718 -395.466062) (xy 392.987789 -395.41044) (xy 392.999915 -395.356003) (xy 393.019838 -395.303912)
			(xy 393.047134 -395.255277) (xy 393.08122 -395.211134) (xy 393.121369 -395.172425) (xy 393.166727 -395.139974)
			(xy 393.216327 -395.114473) (xy 393.269111 -395.096466) (xy 393.323954 -395.086336) (xy 393.379688 -395.084299)
			(xy 393.435125 -395.090399) (xy 393.489082 -395.104505) (xy 393.540411 -395.126317) (xy 393.588017 -395.155371)
			(xy 393.630885 -395.191046) (xy 393.668102 -395.232583) (xy 393.698875 -395.279096) (xy 393.722547 -395.329593)
			(xy 393.738615 -395.383) (xy 393.746735 -395.438176) (xy 393.747244 -395.466062) (xy 393.746735 -395.493948)
			(xy 393.738615 -395.549124) (xy 393.722547 -395.602531) (xy 393.698875 -395.653028) (xy 393.668102 -395.699541)
			(xy 393.630885 -395.741078) (xy 393.588017 -395.776753) (xy 393.540411 -395.805807) (xy 393.489082 -395.827619)
			(xy 393.435125 -395.841725) (xy 393.379688 -395.847825) (xy 393.323954 -395.845788) (xy 393.269111 -395.835658)
			(xy 393.216327 -395.817651) (xy 393.166727 -395.79215) (xy 393.121369 -395.759699) (xy 393.08122 -395.72099)
			(xy 393.047134 -395.676847) (xy 393.019838 -395.628212) (xy 392.999915 -395.576121) (xy 392.987789 -395.521684)
			(xy 392.983718 -395.466062) (xy 388.93623 -395.466062) (xy 388.935641 -395.499383) (xy 388.925978 -395.565322)
			(xy 388.906852 -395.629161) (xy 388.893304 -395.65961) (xy 388.889047 -395.670072) (xy 388.889161 -395.692635)
			(xy 388.8989 -395.712987) (xy 388.907274 -395.72057) (xy 388.929499 -395.739269) (xy 388.969564 -395.78132)
			(xy 389.003988 -395.828101) (xy 389.032216 -395.878862) (xy 389.053795 -395.932786) (xy 389.068378 -395.989007)
			(xy 389.075731 -396.046621) (xy 389.076184 -396.075662) (xy 389.075695 -396.104666) (xy 389.068385 -396.162213)
			(xy 389.064691 -396.1765) (xy 395.05712 -396.1765) (xy 395.061191 -396.120878) (xy 395.073317 -396.066441)
			(xy 395.09324 -396.01435) (xy 395.120536 -395.965715) (xy 395.154622 -395.921572) (xy 395.194771 -395.882863)
			(xy 395.240129 -395.850412) (xy 395.289729 -395.824911) (xy 395.342513 -395.806904) (xy 395.397356 -395.796774)
			(xy 395.45309 -395.794737) (xy 395.508527 -395.800837) (xy 395.562484 -395.814943) (xy 395.613813 -395.836755)
			(xy 395.661419 -395.865809) (xy 395.704287 -395.901484) (xy 395.741504 -395.943021) (xy 395.772277 -395.989534)
			(xy 395.795949 -396.040031) (xy 395.812017 -396.093438) (xy 395.820137 -396.148614) (xy 395.820558 -396.171674)
			(xy 396.402052 -396.171674) (xy 396.40263 -396.136719) (xy 396.412194 -396.067466) (xy 396.431153 -396.000175)
			(xy 396.459148 -395.936115) (xy 396.495653 -395.876492) (xy 396.517368 -395.849094) (xy 396.522673 -395.842101)
			(xy 396.528642 -395.825605) (xy 396.529052 -395.816836) (xy 396.529052 -395.662912) (xy 396.528675 -395.654137)
			(xy 396.522699 -395.637634) (xy 396.517368 -395.630654) (xy 396.495675 -395.60324) (xy 396.459175 -395.543618)
			(xy 396.431179 -395.479561) (xy 396.412214 -395.412276) (xy 396.402636 -395.343028) (xy 396.402052 -395.308074)
			(xy 396.402532 -395.277344) (xy 396.409942 -395.216332) (xy 396.424652 -395.156659) (xy 396.446448 -395.099193)
			(xy 396.47501 -395.044773) (xy 396.509924 -394.994193) (xy 396.550679 -394.948189) (xy 396.596682 -394.907432)
			(xy 396.647261 -394.872517) (xy 396.70168 -394.843953) (xy 396.759145 -394.822157) (xy 396.818819 -394.807445)
			(xy 396.87983 -394.800032) (xy 396.91056 -394.799566) (xy 396.931485 -394.799774) (xy 396.973195 -394.803206)
			(xy 396.993872 -394.806424) (xy 397.003016 -394.807948) (xy 397.020796 -394.804646) (xy 397.092932 -394.760958)
			(xy 397.104108 -394.746988) (xy 397.107156 -394.738352) (xy 397.115916 -394.713329) (xy 397.139404 -394.6658)
			(xy 397.16925 -394.621983) (xy 397.204879 -394.582723) (xy 397.245602 -394.548777) (xy 397.290636 -394.5208)
			(xy 397.339111 -394.499331) (xy 397.390093 -394.484785) (xy 397.442598 -394.477441) (xy 397.469106 -394.476986)
			(xy 397.496357 -394.477472) (xy 397.550305 -394.485229) (xy 397.602599 -394.500585) (xy 397.652176 -394.523226)
			(xy 397.698026 -394.552693) (xy 397.739216 -394.588384) (xy 397.774907 -394.629574) (xy 397.804374 -394.675424)
			(xy 397.827015 -394.725001) (xy 397.842371 -394.777295) (xy 397.850128 -394.831243) (xy 397.850614 -394.858494)
			(xy 397.850101 -394.886466) (xy 397.841958 -394.941815) (xy 397.825817 -394.99538) (xy 397.802023 -395.046012)
			(xy 397.771087 -395.092625) (xy 397.733674 -395.134218) (xy 397.690586 -395.1699) (xy 397.642747 -395.198903)
			(xy 397.591184 -395.220607) (xy 397.537004 -395.234545) (xy 397.509238 -395.23797) (xy 397.500094 -395.238732)
			(xy 397.483838 -395.24686) (xy 397.425926 -395.308074) (xy 397.418814 -395.324584) (xy 397.418306 -395.333728)
			(xy 397.416208 -395.366046) (xy 397.404797 -395.429798) (xy 397.385377 -395.491583) (xy 397.358262 -395.550399)
			(xy 397.323892 -395.605291) (xy 397.303752 -395.630654) (xy 397.29847 -395.637663) (xy 397.292487 -395.654147)
			(xy 397.292068 -395.662912) (xy 397.292068 -395.816836) (xy 397.292418 -395.825614) (xy 397.298412 -395.842116)
			(xy 397.303752 -395.849094) (xy 397.325455 -395.876501) (xy 397.361956 -395.936124) (xy 397.389951 -396.000182)
			(xy 397.408914 -396.06747) (xy 397.418487 -396.13672) (xy 397.419068 -396.171674) (xy 397.418367 -396.210189)
			(xy 397.406762 -396.286338) (xy 397.395954 -396.323312) (xy 397.392652 -396.333726) (xy 397.395192 -396.355062)
			(xy 397.445738 -396.439136) (xy 397.463264 -396.451328) (xy 397.474186 -396.45336) (xy 397.50006 -396.458733)
			(xy 397.550145 -396.475583) (xy 397.597424 -396.499185) (xy 397.640993 -396.529087) (xy 397.680019 -396.564715)
			(xy 397.713753 -396.605389) (xy 397.741551 -396.65033) (xy 397.76288 -396.698677) (xy 397.777332 -396.749506)
			(xy 397.784631 -396.801843) (xy 397.785082 -396.828264) (xy 397.784611 -396.855517) (xy 397.776858 -396.909469)
			(xy 397.761506 -396.961768) (xy 397.738865 -397.01135) (xy 397.709399 -397.057205) (xy 397.673706 -397.098399)
			(xy 397.632513 -397.134093) (xy 397.586659 -397.163561) (xy 397.537078 -397.186202) (xy 397.484779 -397.201556)
			(xy 397.430827 -397.20931) (xy 397.403574 -397.209772) (xy 397.370554 -397.208248) (xy 397.3576 -397.207232)
			(xy 397.334232 -397.217392) (xy 397.265652 -397.304514) (xy 397.261334 -397.32966) (xy 397.265398 -397.341852)
			(xy 397.274661 -397.371345) (xy 397.284613 -397.432356) (xy 397.28521 -397.463264) (xy 397.284784 -397.49052)
			(xy 397.277031 -397.544478) (xy 397.261677 -397.596783) (xy 397.239037 -397.646371) (xy 397.209569 -397.692232)
			(xy 397.173874 -397.733432) (xy 397.13268 -397.769133) (xy 397.086823 -397.798608) (xy 397.037239 -397.821257)
			(xy 396.984936 -397.836618) (xy 396.930979 -397.844379) (xy 396.876467 -397.844383) (xy 396.82251 -397.836628)
			(xy 396.770205 -397.821273) (xy 396.720618 -397.79863) (xy 396.674758 -397.769161) (xy 396.633559 -397.733465)
			(xy 396.597859 -397.692269) (xy 396.568386 -397.646412) (xy 396.545739 -397.596827) (xy 396.530379 -397.544524)
			(xy 396.52262 -397.490567) (xy 396.522618 -397.436055) (xy 396.530375 -397.382097) (xy 396.545731 -397.329793)
			(xy 396.568376 -397.280207) (xy 396.597846 -397.234348) (xy 396.633544 -397.19315) (xy 396.674741 -397.157452)
			(xy 396.720599 -397.12798) (xy 396.770185 -397.105334) (xy 396.822489 -397.089977) (xy 396.876446 -397.082219)
			(xy 396.903702 -397.081756) (xy 396.936722 -397.08328) (xy 396.949676 -397.084296) (xy 396.973044 -397.074136)
			(xy 397.041624 -396.987014) (xy 397.045942 -396.961868) (xy 397.041878 -396.949676) (xy 397.03262 -396.920181)
			(xy 397.022665 -396.859172) (xy 397.022066 -396.828264) (xy 397.023844 -396.791434) (xy 397.02486 -396.780512)
			(xy 397.018002 -396.760192) (xy 396.951454 -396.68831) (xy 396.931896 -396.679928) (xy 396.92072 -396.680182)
			(xy 396.91056 -396.680182) (xy 396.879827 -396.679782) (xy 396.81881 -396.672368) (xy 396.759131 -396.657654)
			(xy 396.701661 -396.635854) (xy 396.647238 -396.607286) (xy 396.596655 -396.572366) (xy 396.55065 -396.531603)
			(xy 396.509894 -396.485593) (xy 396.47498 -396.435005) (xy 396.446419 -396.380578) (xy 396.424626 -396.323106)
			(xy 396.40992 -396.263425) (xy 396.402514 -396.202407) (xy 396.402052 -396.171674) (xy 395.820558 -396.171674)
			(xy 395.820646 -396.1765) (xy 395.820137 -396.204386) (xy 395.812017 -396.259562) (xy 395.795949 -396.312969)
			(xy 395.772277 -396.363466) (xy 395.741504 -396.409979) (xy 395.704287 -396.451516) (xy 395.661419 -396.487191)
			(xy 395.613813 -396.516245) (xy 395.562484 -396.538057) (xy 395.508527 -396.552163) (xy 395.45309 -396.558263)
			(xy 395.397356 -396.556226) (xy 395.342513 -396.546096) (xy 395.289729 -396.528089) (xy 395.240129 -396.502588)
			(xy 395.194771 -396.470137) (xy 395.154622 -396.431428) (xy 395.120536 -396.387285) (xy 395.09324 -396.33865)
			(xy 395.073317 -396.286559) (xy 395.061191 -396.232122) (xy 395.05712 -396.1765) (xy 389.064691 -396.1765)
			(xy 389.053864 -396.218375) (xy 389.032366 -396.272252) (xy 389.004233 -396.322983) (xy 388.969918 -396.369753)
			(xy 388.92997 -396.411814) (xy 388.907782 -396.4305) (xy 388.90067 -396.436088) (xy 388.891526 -396.451328)
			(xy 388.876286 -396.534132) (xy 388.87908 -396.551404) (xy 388.883652 -396.559532) (xy 388.896228 -396.582718)
			(xy 388.914102 -396.63234) (xy 388.920925 -396.671292) (xy 390.46912 -396.671292) (xy 390.46961 -396.641324)
			(xy 390.477433 -396.581902) (xy 390.492946 -396.524009) (xy 390.515882 -396.468636) (xy 390.545849 -396.41673)
			(xy 390.582336 -396.36918) (xy 390.624716 -396.3268) (xy 390.672266 -396.290313) (xy 390.724172 -396.260346)
			(xy 390.779545 -396.23741) (xy 390.837438 -396.221897) (xy 390.89686 -396.214074) (xy 390.956796 -396.214074)
			(xy 391.016218 -396.221897) (xy 391.074111 -396.23741) (xy 391.129484 -396.260346) (xy 391.18139 -396.290313)
			(xy 391.22894 -396.3268) (xy 391.27132 -396.36918) (xy 391.307807 -396.41673) (xy 391.337774 -396.468636)
			(xy 391.36071 -396.524009) (xy 391.376223 -396.581902) (xy 391.384046 -396.641324) (xy 391.384536 -396.671292)
			(xy 391.383975 -396.703116) (xy 391.375158 -396.766151) (xy 391.357692 -396.827357) (xy 391.331915 -396.885552)
			(xy 391.298323 -396.939614) (xy 391.278364 -396.964408) (xy 391.272522 -396.97152) (xy 391.266426 -396.989046)
			(xy 391.268966 -397.075152) (xy 391.276078 -397.09217) (xy 391.282428 -397.099028) (xy 391.294914 -397.112556)
			(xy 391.317929 -397.141292) (xy 391.328402 -397.156432) (xy 391.33653 -397.168116) (xy 391.362184 -397.180054)
			(xy 391.479786 -397.166846) (xy 391.502138 -397.149574) (xy 391.507218 -397.136366) (xy 391.518068 -397.109864)
			(xy 391.546551 -397.060184) (xy 391.582139 -397.01532) (xy 391.624034 -396.976279) (xy 391.671293 -396.94394)
			(xy 391.722856 -396.919028) (xy 391.777563 -396.902103) (xy 391.834185 -396.893546) (xy 391.862818 -396.893034)
			(xy 391.890189 -396.893481) (xy 391.944369 -396.901302) (xy 391.996873 -396.916795) (xy 392.046619 -396.939641)
			(xy 392.092585 -396.969371) (xy 392.113516 -396.987014) (xy 392.120628 -396.99311) (xy 392.137646 -396.99946)
			(xy 392.22299 -396.99946) (xy 392.240008 -396.99311) (xy 392.24712 -396.987014) (xy 392.268053 -396.969373)
			(xy 392.314021 -396.939649) (xy 392.363767 -396.916803) (xy 392.416269 -396.901307) (xy 392.470447 -396.893478)
			(xy 392.525189 -396.893478) (xy 392.579367 -396.901307) (xy 392.631869 -396.916803) (xy 392.681615 -396.939649)
			(xy 392.727583 -396.969373) (xy 392.748516 -396.987014) (xy 392.755628 -396.99311) (xy 392.772646 -396.99946)
			(xy 392.85799 -396.99946) (xy 392.875008 -396.99311) (xy 392.88212 -396.987014) (xy 392.903073 -396.969401)
			(xy 392.94904 -396.939685) (xy 392.998782 -396.916844) (xy 393.051278 -396.901346) (xy 393.10545 -396.893512)
			(xy 393.132818 -396.893034) (xy 393.160071 -396.893437) (xy 393.214023 -396.901197) (xy 393.266321 -396.916555)
			(xy 393.315902 -396.9392) (xy 393.361755 -396.96867) (xy 393.402948 -397.004365) (xy 393.438641 -397.045559)
			(xy 393.468109 -397.091414) (xy 393.490751 -397.140995) (xy 393.502307 -397.180352) (xy 394.841185 -397.180352)
			(xy 394.841185 -397.125848) (xy 394.848942 -397.0719) (xy 394.864298 -397.019604) (xy 394.886941 -396.970026)
			(xy 394.916408 -396.924176) (xy 394.952101 -396.882986) (xy 394.993294 -396.847295) (xy 395.039146 -396.81783)
			(xy 395.088725 -396.79519) (xy 395.141021 -396.779838) (xy 395.19497 -396.772084) (xy 395.222222 -396.771622)
			(xy 395.249593 -396.77207) (xy 395.303773 -396.779891) (xy 395.356277 -396.795384) (xy 395.406023 -396.81823)
			(xy 395.451989 -396.847959) (xy 395.47292 -396.865602) (xy 395.480032 -396.871698) (xy 395.49705 -396.878048)
			(xy 395.582394 -396.878048) (xy 395.599412 -396.871698) (xy 395.606524 -396.865602) (xy 395.627474 -396.847985)
			(xy 395.673442 -396.81827) (xy 395.723185 -396.79543) (xy 395.775682 -396.779933) (xy 395.829854 -396.772099)
			(xy 395.857222 -396.771622) (xy 395.884474 -396.772049) (xy 395.938424 -396.779809) (xy 395.99072 -396.795167)
			(xy 396.040299 -396.817811) (xy 396.08615 -396.847281) (xy 396.127341 -396.882975) (xy 396.163033 -396.924168)
			(xy 396.192499 -396.970021) (xy 396.21514 -397.0196) (xy 396.230496 -397.071898) (xy 396.238252 -397.125848)
			(xy 396.238252 -397.180352) (xy 396.230496 -397.234302) (xy 396.21514 -397.2866) (xy 396.192499 -397.336179)
			(xy 396.163033 -397.382032) (xy 396.127341 -397.423225) (xy 396.08615 -397.458919) (xy 396.040299 -397.488389)
			(xy 395.99072 -397.511033) (xy 395.938424 -397.526391) (xy 395.884474 -397.534151) (xy 395.857222 -397.534638)
			(xy 395.829852 -397.534174) (xy 395.775672 -397.526358) (xy 395.723168 -397.510869) (xy 395.673421 -397.488027)
			(xy 395.627455 -397.4583) (xy 395.606524 -397.440658) (xy 395.599412 -397.434562) (xy 395.582394 -397.428212)
			(xy 395.49705 -397.428212) (xy 395.480032 -397.434562) (xy 395.47292 -397.440658) (xy 395.451986 -397.458295)
			(xy 395.406014 -397.488008) (xy 395.356267 -397.510845) (xy 395.303767 -397.526337) (xy 395.249591 -397.534165)
			(xy 395.222222 -397.534638) (xy 395.19497 -397.534116) (xy 395.141021 -397.526362) (xy 395.088725 -397.511009)
			(xy 395.039146 -397.48837) (xy 394.993294 -397.458905) (xy 394.952101 -397.423214) (xy 394.916408 -397.382024)
			(xy 394.886941 -397.336174) (xy 394.864298 -397.286596) (xy 394.848942 -397.2343) (xy 394.841185 -397.180352)
			(xy 393.502307 -397.180352) (xy 393.506107 -397.193294) (xy 393.513864 -397.247247) (xy 393.513864 -397.301753)
			(xy 393.506107 -397.355706) (xy 393.490751 -397.408005) (xy 393.468109 -397.457586) (xy 393.438641 -397.503441)
			(xy 393.402948 -397.544635) (xy 393.361755 -397.58033) (xy 393.315902 -397.6098) (xy 393.266321 -397.632445)
			(xy 393.214023 -397.647803) (xy 393.160071 -397.655563) (xy 393.132818 -397.65605) (xy 393.105448 -397.655586)
			(xy 393.051268 -397.647769) (xy 392.998764 -397.63228) (xy 392.949017 -397.609438) (xy 392.903051 -397.579712)
			(xy 392.88212 -397.56207) (xy 392.875008 -397.555974) (xy 392.85799 -397.549624) (xy 392.772646 -397.549624)
			(xy 392.755628 -397.555974) (xy 392.748516 -397.56207) (xy 392.727583 -397.579711) (xy 392.681615 -397.609435)
			(xy 392.631869 -397.632281) (xy 392.579367 -397.647777) (xy 392.525189 -397.655606) (xy 392.470447 -397.655606)
			(xy 392.416269 -397.647777) (xy 392.363767 -397.632281) (xy 392.314021 -397.609435) (xy 392.268053 -397.579711)
			(xy 392.24712 -397.56207) (xy 392.240008 -397.555974) (xy 392.22299 -397.549624) (xy 392.137646 -397.549624)
			(xy 392.120628 -397.555974) (xy 392.113516 -397.56207) (xy 392.092585 -397.57971) (xy 392.046612 -397.609423)
			(xy 391.996865 -397.632259) (xy 391.944364 -397.64775) (xy 391.890187 -397.655577) (xy 391.862818 -397.65605)
			(xy 391.834217 -397.655537) (xy 391.777654 -397.647005) (xy 391.722997 -397.630129) (xy 391.67147 -397.605286)
			(xy 391.624227 -397.573033) (xy 391.582324 -397.534093) (xy 391.564114 -397.512032) (xy 391.555478 -397.500856)
			(xy 391.528808 -397.49095) (xy 391.412476 -397.513302) (xy 391.391648 -397.532098) (xy 391.387584 -397.545814)
			(xy 391.377488 -397.577161) (xy 391.349516 -397.63678) (xy 391.313275 -397.691766) (xy 391.291826 -397.716756)
			(xy 391.285476 -397.723868) (xy 391.278872 -397.74114) (xy 391.278872 -397.827246) (xy 391.285476 -397.844518)
			(xy 391.291826 -397.85163) (xy 391.313403 -397.876866) (xy 391.349777 -397.932414) (xy 391.377744 -397.992633)
			(xy 391.396718 -398.05626) (xy 391.406301 -398.121962) (xy 391.406888 -398.15516) (xy 391.40637 -398.186762)
			(xy 391.397666 -398.249363) (xy 391.380418 -398.310168) (xy 391.354956 -398.368016) (xy 391.338816 -398.39519)
			(xy 391.334294 -398.403422) (xy 391.330854 -398.421866) (xy 391.334269 -398.440314) (xy 391.338816 -398.44853)
			(xy 391.354941 -398.47571) (xy 391.380369 -398.533567) (xy 391.397609 -398.594368) (xy 391.406336 -398.656961)
			(xy 391.406888 -398.68856) (xy 391.40635 -398.720174) (xy 391.402609 -398.74705) (xy 393.22198 -398.74705)
			(xy 393.22198 -398.69255) (xy 393.229735 -398.638605) (xy 393.245089 -398.586313) (xy 393.267728 -398.536738)
			(xy 393.297192 -398.490889) (xy 393.33288 -398.4497) (xy 393.374067 -398.414008) (xy 393.419913 -398.384541)
			(xy 393.469487 -398.361899) (xy 393.521778 -398.346541) (xy 393.575722 -398.338782) (xy 393.602972 -398.338294)
			(xy 393.630342 -398.338778) (xy 393.68452 -398.346592) (xy 393.737023 -398.362077) (xy 393.78677 -398.384914)
			(xy 393.832738 -398.414635) (xy 393.85367 -398.432274) (xy 393.860782 -398.43837) (xy 393.8778 -398.44472)
			(xy 393.963144 -398.44472) (xy 393.980162 -398.43837) (xy 393.987274 -398.432274) (xy 394.008202 -398.41463)
			(xy 394.054176 -398.384919) (xy 394.103925 -398.362085) (xy 394.156426 -398.346595) (xy 394.210603 -398.338768)
			(xy 394.237972 -398.338294) (xy 394.265226 -398.338751) (xy 394.319181 -398.346505) (xy 394.371482 -398.361859)
			(xy 394.421066 -398.3845) (xy 394.466923 -398.413967) (xy 394.508119 -398.449661) (xy 394.543816 -398.490855)
			(xy 394.573287 -398.536709) (xy 394.595931 -398.586292) (xy 394.611289 -398.638592) (xy 394.619047 -398.692546)
			(xy 394.619047 -398.747054) (xy 394.611289 -398.801008) (xy 394.595931 -398.853308) (xy 394.573287 -398.902891)
			(xy 394.543816 -398.948745) (xy 394.508119 -398.989939) (xy 394.466923 -399.025633) (xy 394.421066 -399.0551)
			(xy 394.371482 -399.077741) (xy 394.319181 -399.093095) (xy 394.265226 -399.100849) (xy 394.237972 -399.10131)
			(xy 394.210601 -399.100858) (xy 394.156422 -399.093036) (xy 394.103919 -399.077544) (xy 394.054172 -399.054699)
			(xy 394.008206 -399.024972) (xy 393.987274 -399.00733) (xy 393.980162 -399.001234) (xy 393.963144 -398.994884)
			(xy 393.8778 -398.994884) (xy 393.860782 -399.001234) (xy 393.85367 -399.00733) (xy 393.832726 -399.024954)
			(xy 393.786756 -399.054667) (xy 393.737012 -399.077506) (xy 393.684514 -399.093) (xy 393.63034 -399.100833)
			(xy 393.602972 -399.10131) (xy 393.575722 -399.100818) (xy 393.521778 -399.093059) (xy 393.469487 -399.077701)
			(xy 393.419913 -399.055059) (xy 393.374067 -399.025592) (xy 393.33288 -398.9899) (xy 393.297192 -398.948711)
			(xy 393.267728 -398.902862) (xy 393.245089 -398.853287) (xy 393.229735 -398.800995) (xy 393.22198 -398.74705)
			(xy 391.402609 -398.74705) (xy 391.397632 -398.782799) (xy 391.380384 -398.843629) (xy 391.354935 -398.90151)
			(xy 391.321767 -398.95534) (xy 391.28151 -399.004098) (xy 391.234931 -399.046855) (xy 391.182914 -399.082801)
			(xy 391.15492 -399.0975) (xy 391.14561 -399.102769) (xy 391.132096 -399.119326) (xy 391.126442 -399.139937)
			(xy 391.127488 -399.150586) (xy 391.129293 -399.163144) (xy 391.131199 -399.188445) (xy 391.131298 -399.201132)
			(xy 391.130788 -399.227119) (xy 391.122658 -399.278454) (xy 391.106597 -399.327884) (xy 391.083001 -399.374194)
			(xy 391.052451 -399.416242) (xy 391.0157 -399.452993) (xy 390.973652 -399.483543) (xy 390.927342 -399.507139)
			(xy 390.877912 -399.5232) (xy 390.826577 -399.53133) (xy 390.774603 -399.53133) (xy 390.723268 -399.5232)
			(xy 390.673838 -399.507139) (xy 390.627528 -399.483543) (xy 390.58548 -399.452993) (xy 390.548729 -399.416242)
			(xy 390.518179 -399.374194) (xy 390.494583 -399.327884) (xy 390.478522 -399.278454) (xy 390.470392 -399.227119)
			(xy 390.469882 -399.201132) (xy 390.470289 -399.177394) (xy 390.477085 -399.130408) (xy 390.490528 -399.084875)
			(xy 390.510341 -399.041732) (xy 390.536119 -399.001864) (xy 390.551416 -398.983708) (xy 390.558127 -398.97531)
			(xy 390.564463 -398.954789) (xy 390.561872 -398.933468) (xy 390.55675 -398.924018) (xy 390.541241 -398.897251)
			(xy 390.516826 -398.840409) (xy 390.500303 -398.780792) (xy 390.491975 -398.719492) (xy 390.491472 -398.68856)
			(xy 390.49199 -398.656958) (xy 390.500693 -398.594356) (xy 390.51794 -398.533552) (xy 390.543403 -398.475704)
			(xy 390.559544 -398.44853) (xy 390.564126 -398.440328) (xy 390.56754 -398.421866) (xy 390.564101 -398.403408)
			(xy 390.559544 -398.39519) (xy 390.543423 -398.368007) (xy 390.517995 -398.310151) (xy 390.500754 -398.249351)
			(xy 390.492026 -398.186758) (xy 390.491472 -398.15516) (xy 390.492035 -398.121925) (xy 390.501644 -398.056155)
			(xy 390.520668 -397.992467) (xy 390.548708 -397.932201) (xy 390.585172 -397.876627) (xy 390.606788 -397.851376)
			(xy 390.613138 -397.844264) (xy 390.619742 -397.826992) (xy 390.619742 -397.740886) (xy 390.613138 -397.723614)
			(xy 390.606788 -397.716502) (xy 390.585228 -397.691251) (xy 390.548852 -397.635708) (xy 390.520881 -397.575493)
			(xy 390.501903 -397.511868) (xy 390.492316 -397.446169) (xy 390.491726 -397.412972) (xy 390.492252 -397.381146)
			(xy 390.501076 -397.318109) (xy 390.518549 -397.256903) (xy 390.544334 -397.198708) (xy 390.577935 -397.144648)
			(xy 390.597898 -397.119856) (xy 390.60374 -397.112744) (xy 390.609836 -397.095218) (xy 390.607296 -397.009112)
			(xy 390.600184 -396.992094) (xy 390.593834 -396.985236) (xy 390.574343 -396.96397) (xy 390.540351 -396.91736)
			(xy 390.512487 -396.866847) (xy 390.491194 -396.813233) (xy 390.476808 -396.757367) (xy 390.469558 -396.700136)
			(xy 390.46912 -396.671292) (xy 388.920925 -396.671292) (xy 388.923202 -396.684291) (xy 388.923784 -396.710662)
			(xy 388.923716 -396.720021) (xy 388.922572 -396.738703) (xy 388.921498 -396.748) (xy 388.920482 -396.75689)
			(xy 388.924292 -396.773654) (xy 388.968234 -396.843504) (xy 388.98195 -396.853918) (xy 388.990332 -396.856712)
			(xy 389.014359 -396.865184) (xy 389.059531 -396.888736) (xy 389.100337 -396.919234) (xy 389.135716 -396.955888)
			(xy 389.164752 -396.997747) (xy 389.186691 -397.043725) (xy 389.194294 -397.06804) (xy 389.195818 -397.073882)
			(xy 389.516112 -397.627602) (xy 389.520176 -397.63192) (xy 389.536364 -397.649642) (xy 389.563791 -397.689029)
			(xy 389.584937 -397.732115) (xy 389.599315 -397.777906) (xy 389.606592 -397.825346) (xy 389.607044 -397.849344)
			(xy 389.606647 -397.874151) (xy 389.598875 -397.923152) (xy 389.58353 -397.970332) (xy 389.56099 -398.01453)
			(xy 389.53181 -398.054656) (xy 389.49671 -398.08972) (xy 389.456555 -398.118858) (xy 389.412334 -398.141353)
			(xy 389.365138 -398.15665) (xy 389.316129 -398.164372) (xy 389.291322 -398.164812) (xy 389.265928 -398.164292)
			(xy 389.215796 -398.156165) (xy 389.16761 -398.140117) (xy 389.122616 -398.116561) (xy 389.081973 -398.086107)
			(xy 389.04673 -398.049538) (xy 389.017796 -398.007799) (xy 388.995917 -397.961966) (xy 388.9883 -397.937736)
			(xy 388.986776 -397.931894) (xy 388.666482 -397.378174) (xy 388.662418 -397.373856) (xy 388.646253 -397.356127)
			(xy 388.618887 -397.316723) (xy 388.597798 -397.273632) (xy 388.583472 -397.227846) (xy 388.576238 -397.18042)
			(xy 388.575804 -397.156432) (xy 388.575885 -397.144384) (xy 388.577668 -397.120355) (xy 388.57936 -397.108426)
			(xy 388.58063 -397.099536) (xy 388.577582 -397.082518) (xy 388.535418 -397.011652) (xy 388.52221 -397.000476)
			(xy 388.513828 -396.997428) (xy 388.492071 -396.989056) (xy 388.451214 -396.966609) (xy 388.414245 -396.938212)
			(xy 388.382024 -396.904523) (xy 388.3553 -396.866326) (xy 388.334695 -396.824509) (xy 388.320689 -396.780046)
			(xy 388.313606 -396.733971) (xy 388.313168 -396.710662) (xy 388.313738 -396.684289) (xy 388.32282 -396.632331)
			(xy 388.340706 -396.582711) (xy 388.3533 -396.559532) (xy 388.357872 -396.551404) (xy 388.360666 -396.534132)
			(xy 388.345426 -396.451328) (xy 388.336282 -396.436088) (xy 388.32917 -396.4305) (xy 388.306993 -396.411801)
			(xy 388.267048 -396.369738) (xy 388.232731 -396.322968) (xy 388.204594 -396.272241) (xy 388.183085 -396.218367)
			(xy 388.168549 -396.16221) (xy 388.161219 -396.104666) (xy 388.160768 -396.075662) (xy 388.161365 -396.042341)
			(xy 388.171025 -395.976403) (xy 388.190148 -395.912563) (xy 388.203694 -395.882114) (xy 388.207928 -395.871644)
			(xy 388.207823 -395.849088) (xy 388.198093 -395.828738) (xy 388.189724 -395.821154) (xy 388.167462 -395.802497)
			(xy 388.127399 -395.760439) (xy 388.092979 -395.71365) (xy 388.064755 -395.662882) (xy 388.043183 -395.608951)
			(xy 388.028607 -395.552724) (xy 388.021262 -395.495105) (xy 388.020814 -395.466062) (xy 388.021279 -395.437136)
			(xy 388.028562 -395.379745) (xy 388.04302 -395.323729) (xy 388.064422 -395.269982) (xy 388.092426 -395.21936)
			(xy 388.126587 -395.172672) (xy 388.16636 -395.130661) (xy 388.188454 -395.111986) (xy 388.195425 -395.105637)
			(xy 388.204683 -395.089235) (xy 388.206488 -395.079982) (xy 388.210806 -395.048994) (xy 388.211717 -395.039758)
			(xy 388.207689 -395.021657) (xy 388.202932 -395.013688) (xy 388.186627 -394.987841) (xy 388.162722 -394.931607)
			(xy 388.155434 -394.901928) (xy 388.153366 -394.893769) (xy 388.144671 -394.879367) (xy 388.138416 -394.873734)
			(xy 388.115302 -394.854684) (xy 388.108416 -394.849447) (xy 388.09219 -394.843476) (xy 388.083552 -394.843)
			(xy 388.053915 -394.842) (xy 387.99525 -394.83335) (xy 387.938193 -394.817197) (xy 387.883698 -394.793814)
			(xy 387.832679 -394.76359) (xy 387.78599 -394.727032) (xy 387.744411 -394.684752) (xy 387.708638 -394.637457)
			(xy 387.679272 -394.58594) (xy 387.656803 -394.531062) (xy 387.641607 -394.473743) (xy 387.633939 -394.414942)
			(xy 387.633464 -394.385292) (xy 387.633985 -394.354229) (xy 387.642401 -394.292675) (xy 387.650228 -394.26261)
			(xy 387.653022 -394.25245) (xy 387.650482 -394.232638) (xy 387.602984 -394.150342) (xy 387.586982 -394.13815)
			(xy 387.576822 -394.13561) (xy 387.547732 -394.127585) (xy 387.491805 -394.104918) (xy 387.43934 -394.0751)
			(xy 387.391246 -394.03865) (xy 387.348356 -393.996199) (xy 387.311413 -393.948482) (xy 387.281058 -393.896327)
			(xy 387.257817 -393.840636) (xy 387.242091 -393.782375) (xy 387.234155 -393.722553) (xy 387.233668 -393.69238)
			(xy 387.234198 -393.661492) (xy 387.242503 -393.600277) (xy 387.258958 -393.540733) (xy 387.283267 -393.483941)
			(xy 387.298692 -393.457176) (xy 387.304534 -393.44727) (xy 387.30682 -393.424918) (xy 387.273546 -393.329668)
			(xy 387.257798 -393.313666) (xy 387.24713 -393.309602) (xy 387.223734 -393.300454) (xy 387.179839 -393.276027)
			(xy 387.140145 -393.245239) (xy 387.105566 -393.2088) (xy 387.076899 -393.167549) (xy 387.054804 -393.122435)
			(xy 387.039789 -393.074497) (xy 387.0322 -393.024839) (xy 387.031738 -392.999722) (xy 386.493004 -392.999722)
			(xy 386.492471 -393.026824) (xy 386.483663 -393.080306) (xy 386.475478 -393.106148) (xy 386.471668 -393.11707)
			(xy 386.474208 -393.139422) (xy 386.526786 -393.225274) (xy 386.545836 -393.23772) (xy 386.557012 -393.239498)
			(xy 386.586328 -393.24422) (xy 386.643498 -393.260266) (xy 386.698112 -393.283574) (xy 386.749252 -393.313751)
			(xy 386.796058 -393.350291) (xy 386.837743 -393.392578) (xy 386.873608 -393.439904) (xy 386.903049 -393.491471)
			(xy 386.925571 -393.546414) (xy 386.940795 -393.603808) (xy 386.948467 -393.66269) (xy 386.948934 -393.69238)
			(xy 386.948408 -393.723443) (xy 386.939995 -393.784996) (xy 386.93217 -393.815062) (xy 386.929376 -393.825222)
			(xy 386.931916 -393.845034) (xy 386.979414 -393.92733) (xy 386.995416 -393.939522) (xy 387.005576 -393.942062)
			(xy 387.03469 -393.950046) (xy 387.090656 -393.972683) (xy 387.143161 -394.00248) (xy 387.191294 -394.03892)
			(xy 387.234219 -394.08137) (xy 387.271193 -394.129094) (xy 387.301572 -394.181265) (xy 387.324831 -394.236975)
			(xy 387.340564 -394.29526) (xy 387.348501 -394.355107) (xy 387.348984 -394.385292) (xy 387.348859 -394.399427)
			(xy 387.347077 -394.427641) (xy 387.345428 -394.44168) (xy 387.344672 -394.450287) (xy 387.348309 -394.467166)
			(xy 387.35254 -394.4747) (xy 387.368288 -394.5001) (xy 387.372999 -394.507159) (xy 387.386104 -394.517929)
			(xy 387.393942 -394.521182) (xy 387.417326 -394.530359) (xy 387.461221 -394.554781) (xy 387.500916 -394.585564)
			(xy 387.535496 -394.621998) (xy 387.564165 -394.663246) (xy 387.586262 -394.708356) (xy 387.60128 -394.756291)
			(xy 387.608871 -394.805946) (xy 387.609334 -394.831062) (xy 387.60892 -394.855265) (xy 387.601845 -394.90315)
			(xy 387.587855 -394.94949) (xy 387.567251 -394.993291) (xy 387.554216 -395.013688) (xy 387.549424 -395.021642)
			(xy 387.545394 -395.039755) (xy 387.546342 -395.048994) (xy 387.55066 -395.079982) (xy 387.552354 -395.089275)
			(xy 387.561628 -395.105717) (xy 387.568694 -395.111986) (xy 387.590768 -395.130685) (xy 387.630543 -395.172692)
			(xy 387.664708 -395.219376) (xy 387.692718 -395.269993) (xy 387.714128 -395.323736) (xy 387.728595 -395.379748)
			(xy 387.735889 -395.437137) (xy 387.736334 -395.466062) (xy 387.735745 -395.499383) (xy 387.726082 -395.565322)
			(xy 387.706956 -395.629161) (xy 387.693408 -395.65961) (xy 387.68915 -395.670072) (xy 387.689264 -395.692635)
			(xy 387.699004 -395.712987) (xy 387.707378 -395.72057) (xy 387.729604 -395.739268) (xy 387.769669 -395.781319)
			(xy 387.804092 -395.828101) (xy 387.83232 -395.878861) (xy 387.853899 -395.932786) (xy 387.868482 -395.989007)
			(xy 387.875835 -396.046621) (xy 387.876288 -396.075662) (xy 387.875798 -396.104666) (xy 387.868488 -396.162213)
			(xy 387.853967 -396.218374) (xy 387.832469 -396.272252) (xy 387.804337 -396.322982) (xy 387.770022 -396.369753)
			(xy 387.730074 -396.411814) (xy 387.707886 -396.4305) (xy 387.700774 -396.436088) (xy 387.69163 -396.451328)
			(xy 387.67639 -396.534132) (xy 387.679184 -396.551404) (xy 387.683756 -396.559532) (xy 387.696332 -396.582718)
			(xy 387.714206 -396.63234) (xy 387.723306 -396.684291) (xy 387.723888 -396.710662) (xy 387.72382 -396.720021)
			(xy 387.722676 -396.738703) (xy 387.721602 -396.748) (xy 387.720586 -396.75689) (xy 387.724396 -396.773654)
			(xy 387.768338 -396.843504) (xy 387.782054 -396.853918) (xy 387.790436 -396.856712) (xy 387.814541 -396.865173)
			(xy 387.859831 -396.888803) (xy 387.900725 -396.919418) (xy 387.936155 -396.956219) (xy 387.965196 -396.998246)
			(xy 387.987091 -397.0444) (xy 387.994652 -397.068802) (xy 387.996176 -397.074644) (xy 388.315962 -397.627602)
			(xy 388.320026 -397.63192) (xy 388.336218 -397.649625) (xy 388.363583 -397.689035) (xy 388.384667 -397.732132)
			(xy 388.398987 -397.777923) (xy 388.406211 -397.825355) (xy 388.40664 -397.849344) (xy 388.406222 -397.874136)
			(xy 388.398459 -397.923109) (xy 388.383131 -397.970265) (xy 388.360614 -398.014442) (xy 388.331464 -398.054554)
			(xy 388.296399 -398.089611) (xy 388.256281 -398.118752) (xy 388.212098 -398.141258) (xy 388.164939 -398.156576)
			(xy 388.115964 -398.164328) (xy 388.091172 -398.164812) (xy 388.065777 -398.164336) (xy 388.015642 -398.156201)
			(xy 387.967456 -398.140146) (xy 387.922461 -398.116584) (xy 387.881819 -398.086123) (xy 387.846577 -398.049549)
			(xy 387.817644 -398.007805) (xy 387.795766 -397.961968) (xy 387.78815 -397.937736) (xy 387.786626 -397.931894)
			(xy 387.466078 -397.377412) (xy 387.462014 -397.373094) (xy 387.445909 -397.355439) (xy 387.418723 -397.316138)
			(xy 387.397773 -397.273187) (xy 387.383537 -397.227569) (xy 387.376343 -397.180326) (xy 387.375908 -397.156432)
			(xy 387.375989 -397.144384) (xy 387.377772 -397.120355) (xy 387.379464 -397.108426) (xy 387.380734 -397.099536)
			(xy 387.377686 -397.082518) (xy 387.335522 -397.011652) (xy 387.322314 -397.000476) (xy 387.313932 -396.997428)
			(xy 387.292176 -396.989054) (xy 387.251319 -396.966608) (xy 387.214349 -396.93821) (xy 387.182128 -396.904522)
			(xy 387.155404 -396.866325) (xy 387.1348 -396.824509) (xy 387.120793 -396.780046) (xy 387.11371 -396.733971)
			(xy 387.113272 -396.710662) (xy 387.113841 -396.684289) (xy 387.122923 -396.632331) (xy 387.14081 -396.582711)
			(xy 387.153404 -396.559532) (xy 387.157976 -396.551404) (xy 387.16077 -396.534132) (xy 387.14553 -396.451328)
			(xy 387.136386 -396.436088) (xy 387.129274 -396.4305) (xy 387.107098 -396.4118) (xy 387.067152 -396.369737)
			(xy 387.032836 -396.322968) (xy 387.004698 -396.272241) (xy 386.983189 -396.218367) (xy 386.968653 -396.16221)
			(xy 386.961323 -396.104666) (xy 386.960872 -396.075662) (xy 386.961469 -396.042341) (xy 386.971128 -395.976403)
			(xy 386.990252 -395.912563) (xy 387.003798 -395.882114) (xy 387.008031 -395.871644) (xy 387.007926 -395.849088)
			(xy 386.998197 -395.828738) (xy 386.989828 -395.821154) (xy 386.967567 -395.802496) (xy 386.927503 -395.760439)
			(xy 386.893083 -395.71365) (xy 386.86486 -395.662882) (xy 386.843287 -395.608951) (xy 386.828711 -395.552724)
			(xy 386.821366 -395.495105) (xy 386.820918 -395.466062) (xy 386.821382 -395.437136) (xy 386.828665 -395.379745)
			(xy 386.843123 -395.323729) (xy 386.864525 -395.269982) (xy 386.89253 -395.21936) (xy 386.926691 -395.172672)
			(xy 386.966464 -395.130661) (xy 386.988558 -395.111986) (xy 386.99553 -395.105638) (xy 387.004788 -395.089235)
			(xy 387.006592 -395.079982) (xy 387.01091 -395.048994) (xy 387.01182 -395.039758) (xy 387.007793 -395.021657)
			(xy 387.003036 -395.013688) (xy 386.986731 -394.987841) (xy 386.962826 -394.931606) (xy 386.955538 -394.901928)
			(xy 386.953469 -394.893769) (xy 386.944774 -394.879367) (xy 386.93852 -394.873734) (xy 386.915406 -394.854684)
			(xy 386.908519 -394.849448) (xy 386.892294 -394.843476) (xy 386.883656 -394.843) (xy 386.854019 -394.841996)
			(xy 386.795354 -394.833346) (xy 386.738297 -394.817195) (xy 386.683803 -394.793811) (xy 386.632784 -394.763588)
			(xy 386.586094 -394.727031) (xy 386.544515 -394.684751) (xy 386.508743 -394.637456) (xy 386.479376 -394.585939)
			(xy 386.456907 -394.531062) (xy 386.441711 -394.473743) (xy 386.434043 -394.414942) (xy 386.433568 -394.385292)
			(xy 386.434089 -394.354229) (xy 386.442505 -394.292675) (xy 386.450332 -394.26261) (xy 386.453126 -394.25245)
			(xy 386.450586 -394.232638) (xy 386.403088 -394.150342) (xy 386.387086 -394.13815) (xy 386.376926 -394.13561)
			(xy 386.347805 -394.12765) (xy 386.291837 -394.105012) (xy 386.239331 -394.075213) (xy 386.191198 -394.03877)
			(xy 386.148272 -393.996317) (xy 386.111299 -393.94859) (xy 386.080921 -393.896417) (xy 386.057664 -393.840703)
			(xy 386.041933 -393.782416) (xy 386.033999 -393.722566) (xy 386.033518 -393.69238) (xy 386.034041 -393.661492)
			(xy 386.042347 -393.600276) (xy 386.058804 -393.540732) (xy 386.083115 -393.483941) (xy 386.098542 -393.457176)
			(xy 386.104384 -393.44727) (xy 386.10667 -393.424918) (xy 386.073396 -393.329668) (xy 386.057648 -393.313666)
			(xy 386.04698 -393.309602) (xy 386.023595 -393.300427) (xy 385.979698 -393.276006) (xy 385.940003 -393.245224)
			(xy 385.905422 -393.208789) (xy 385.876753 -393.167541) (xy 385.854656 -393.12243) (xy 385.839639 -393.074494)
			(xy 385.83205 -393.024838) (xy 385.831588 -392.999722) (xy 385.293108 -392.999722) (xy 385.292575 -393.026824)
			(xy 385.283767 -393.080306) (xy 385.275582 -393.106148) (xy 385.271772 -393.11707) (xy 385.274312 -393.139422)
			(xy 385.32689 -393.225274) (xy 385.34594 -393.23772) (xy 385.357116 -393.239498) (xy 385.386432 -393.244217)
			(xy 385.443603 -393.260264) (xy 385.498217 -393.283572) (xy 385.549356 -393.313749) (xy 385.596162 -393.350289)
			(xy 385.637848 -393.392577) (xy 385.673712 -393.439903) (xy 385.703153 -393.49147) (xy 385.725675 -393.546413)
			(xy 385.740899 -393.603808) (xy 385.748571 -393.66269) (xy 385.749038 -393.69238) (xy 385.748515 -393.723506)
			(xy 385.740109 -393.785188) (xy 385.732274 -393.815316) (xy 385.72948 -393.825476) (xy 385.73202 -393.845542)
			(xy 385.779264 -393.92733) (xy 385.795266 -393.939522) (xy 385.805426 -393.942062) (xy 385.83453 -393.950079)
			(xy 385.890497 -393.97271) (xy 385.943003 -394.002502) (xy 385.991137 -394.038937) (xy 386.034064 -394.081384)
			(xy 386.071039 -394.129105) (xy 386.101419 -394.181272) (xy 386.124679 -394.23698) (xy 386.140414 -394.295263)
			(xy 386.14835 -394.355108) (xy 386.148834 -394.385292) (xy 386.148709 -394.399427) (xy 386.146927 -394.427641)
			(xy 386.145278 -394.44168) (xy 386.144514 -394.450287) (xy 386.148156 -394.467167) (xy 386.15239 -394.4747)
			(xy 386.168138 -394.5001) (xy 386.172832 -394.507172) (xy 386.185949 -394.517934) (xy 386.193792 -394.521182)
			(xy 386.217165 -394.530386) (xy 386.261062 -394.554802) (xy 386.300759 -394.585579) (xy 386.335341 -394.622009)
			(xy 386.364011 -394.663253) (xy 386.38611 -394.708361) (xy 386.401129 -394.756294) (xy 386.408721 -394.805947)
			(xy 386.409184 -394.831062) (xy 386.408761 -394.855264) (xy 386.401688 -394.903149) (xy 386.3877 -394.949489)
			(xy 386.3671 -394.993291) (xy 386.354066 -395.013688) (xy 386.349277 -395.021644) (xy 386.345244 -395.039756)
			(xy 386.346192 -395.048994) (xy 386.35051 -395.079982) (xy 386.352189 -395.089279) (xy 386.361472 -395.10572)
			(xy 386.368544 -395.111986) (xy 386.390628 -395.130672) (xy 386.430401 -395.172683) (xy 386.464564 -395.21937)
			(xy 386.492572 -395.269989) (xy 386.51398 -395.323733) (xy 386.528446 -395.379747) (xy 386.535739 -395.437136)
			(xy 386.536184 -395.466062) (xy 386.53559 -395.499383) (xy 386.525929 -395.565321) (xy 386.506804 -395.629161)
			(xy 386.493258 -395.65961) (xy 386.488984 -395.670068) (xy 386.489097 -395.692636) (xy 386.498847 -395.71299)
			(xy 386.507228 -395.72057) (xy 386.529464 -395.739256) (xy 386.569527 -395.78131) (xy 386.603948 -395.828095)
			(xy 386.632174 -395.878858) (xy 386.653751 -395.932783) (xy 386.668333 -395.989006) (xy 386.675685 -396.046621)
			(xy 386.676138 -396.075662) (xy 386.675666 -396.104667) (xy 386.668355 -396.162215) (xy 386.653833 -396.218378)
			(xy 386.632332 -396.272256) (xy 386.604196 -396.322986) (xy 386.569878 -396.369756) (xy 386.529926 -396.411816)
			(xy 386.507736 -396.4305) (xy 386.500624 -396.436088) (xy 386.49148 -396.451328) (xy 386.47624 -396.534132)
			(xy 386.479034 -396.551404) (xy 386.483606 -396.559532) (xy 386.496178 -396.58272) (xy 386.514054 -396.632341)
			(xy 386.523156 -396.684292) (xy 386.523738 -396.710662) (xy 386.523669 -396.720021) (xy 386.522526 -396.738703)
			(xy 386.521452 -396.748) (xy 386.520436 -396.75689) (xy 386.524246 -396.773654) (xy 386.568188 -396.843504)
			(xy 386.581904 -396.853918) (xy 386.590286 -396.856712) (xy 386.614304 -396.865209) (xy 386.659477 -396.888754)
			(xy 386.700284 -396.919247) (xy 386.735666 -396.955897) (xy 386.764703 -396.997752) (xy 386.786644 -397.043726)
			(xy 386.794248 -397.06804) (xy 386.795772 -397.073882) (xy 387.116066 -397.627602) (xy 387.12013 -397.63192)
			(xy 387.136323 -397.649625) (xy 387.163687 -397.689034) (xy 387.184772 -397.732132) (xy 387.199091 -397.777923)
			(xy 387.206315 -397.825354) (xy 387.206744 -397.849344) (xy 387.206322 -397.874136) (xy 387.198559 -397.923109)
			(xy 387.183231 -397.970264) (xy 387.160715 -398.014441) (xy 387.131566 -398.054552) (xy 387.0965 -398.08961)
			(xy 387.056383 -398.118751) (xy 387.012201 -398.141257) (xy 386.965042 -398.156575) (xy 386.916068 -398.164328)
			(xy 386.891276 -398.164812) (xy 386.865881 -398.164333) (xy 386.815746 -398.156198) (xy 386.76756 -398.140143)
			(xy 386.722566 -398.116582) (xy 386.681923 -398.086121) (xy 386.646681 -398.049548) (xy 386.617748 -398.007804)
			(xy 386.59587 -397.961967) (xy 386.588254 -397.937736) (xy 386.58673 -397.931894) (xy 386.266436 -397.378174)
			(xy 386.262372 -397.373856) (xy 386.246164 -397.356152) (xy 386.218742 -397.316759) (xy 386.1976 -397.273669)
			(xy 386.183227 -397.227874) (xy 386.175954 -397.180431) (xy 386.175504 -397.156432) (xy 386.175646 -397.14438)
			(xy 386.177552 -397.12035) (xy 386.179314 -397.108426) (xy 386.180584 -397.099536) (xy 386.177536 -397.082518)
			(xy 386.135372 -397.011652) (xy 386.122164 -397.000476) (xy 386.113782 -396.997428) (xy 386.092037 -396.989026)
			(xy 386.051178 -396.966587) (xy 386.014207 -396.938195) (xy 385.981984 -396.90451) (xy 385.955258 -396.866317)
			(xy 385.934651 -396.824504) (xy 385.920644 -396.780043) (xy 385.91356 -396.73397) (xy 385.913122 -396.710662)
			(xy 385.913685 -396.684289) (xy 385.922769 -396.63233) (xy 385.940658 -396.58271) (xy 385.953254 -396.559532)
			(xy 385.957826 -396.551404) (xy 385.96062 -396.534132) (xy 385.94538 -396.451328) (xy 385.936236 -396.436088)
			(xy 385.929124 -396.4305) (xy 385.906958 -396.411788) (xy 385.86701 -396.369728) (xy 385.832691 -396.322962)
			(xy 385.804552 -396.272237) (xy 385.783041 -396.218365) (xy 385.768504 -396.162208) (xy 385.761173 -396.104666)
			(xy 385.760722 -396.075662) (xy 385.761324 -396.042341) (xy 385.770982 -395.976403) (xy 385.790103 -395.912563)
			(xy 385.803648 -395.882114) (xy 385.807897 -395.871648) (xy 385.807793 -395.849086) (xy 385.798053 -395.828735)
			(xy 385.789678 -395.821154) (xy 385.767406 -395.802509) (xy 385.727345 -395.760447) (xy 385.692928 -395.713656)
			(xy 385.664706 -395.662886) (xy 385.643135 -395.608954) (xy 385.62856 -395.552725) (xy 385.621216 -395.495105)
			(xy 385.620768 -395.466062) (xy 385.621214 -395.437135) (xy 385.628498 -395.379743) (xy 385.642957 -395.323726)
			(xy 385.664362 -395.269978) (xy 385.69237 -395.219356) (xy 385.726535 -395.172669) (xy 385.766312 -395.130659)
			(xy 385.788408 -395.111986) (xy 385.795387 -395.105646) (xy 385.80464 -395.089237) (xy 385.806442 -395.079982)
			(xy 385.81076 -395.048994) (xy 385.811662 -395.039757) (xy 385.807638 -395.021658) (xy 385.802886 -395.013688)
			(xy 385.786577 -394.987843) (xy 385.762674 -394.931607) (xy 385.755388 -394.901928) (xy 385.753332 -394.893765)
			(xy 385.744629 -394.879364) (xy 385.73837 -394.873734) (xy 385.715256 -394.854684) (xy 385.708356 -394.849468)
			(xy 385.692141 -394.843484) (xy 385.683506 -394.843) (xy 385.653871 -394.84195) (xy 385.595207 -394.833307)
			(xy 385.538151 -394.817161) (xy 385.483657 -394.793783) (xy 385.432638 -394.763564) (xy 385.385947 -394.727011)
			(xy 385.344368 -394.684735) (xy 385.308595 -394.637445) (xy 385.279227 -394.585931) (xy 385.256758 -394.531056)
			(xy 385.241561 -394.473739) (xy 385.233893 -394.41494) (xy 385.233418 -394.385292) (xy 385.23394 -394.354229)
			(xy 385.242355 -394.292675) (xy 385.250182 -394.26261) (xy 385.252976 -394.25245) (xy 385.250436 -394.232638)
			(xy 385.202938 -394.150342) (xy 385.186936 -394.13815) (xy 385.176776 -394.13561) (xy 385.147696 -394.12755)
			(xy 385.091768 -394.104888) (xy 385.039302 -394.075077) (xy 384.991207 -394.038632) (xy 384.948315 -393.996185)
			(xy 384.911371 -393.948472) (xy 384.881015 -393.896319) (xy 384.857772 -393.840631) (xy 384.842046 -393.782372)
			(xy 384.834109 -393.722552) (xy 384.833622 -393.69238) (xy 384.834145 -393.661492) (xy 384.84245 -393.600276)
			(xy 384.858908 -393.540732) (xy 384.883219 -393.483941) (xy 384.898646 -393.457176) (xy 384.904488 -393.44727)
			(xy 384.906774 -393.424918) (xy 384.8735 -393.329668) (xy 384.857752 -393.313666) (xy 384.847084 -393.309602)
			(xy 384.8237 -393.300425) (xy 384.779803 -393.276004) (xy 384.740107 -393.245222) (xy 384.705526 -393.208788)
			(xy 384.676857 -393.16754) (xy 384.65476 -393.122429) (xy 384.639744 -393.074494) (xy 384.632154 -393.024838)
			(xy 384.631692 -392.999722) (xy 384.092958 -392.999722) (xy 384.092428 -393.026824) (xy 384.083618 -393.080307)
			(xy 384.075432 -393.106148) (xy 384.071622 -393.11707) (xy 384.074162 -393.139422) (xy 384.12674 -393.225274)
			(xy 384.14579 -393.23772) (xy 384.156966 -393.239498) (xy 384.186289 -393.244178) (xy 384.24346 -393.260231)
			(xy 384.298073 -393.283544) (xy 384.349212 -393.313727) (xy 384.396017 -393.350271) (xy 384.437702 -393.392563)
			(xy 384.473565 -393.439892) (xy 384.503005 -393.491462) (xy 384.525526 -393.546408) (xy 384.54075 -393.603805)
			(xy 384.548421 -393.662689) (xy 384.548888 -393.69238) (xy 384.54836 -393.723443) (xy 384.539949 -393.784996)
			(xy 384.532124 -393.815062) (xy 384.52933 -393.825222) (xy 384.53187 -393.845034) (xy 384.579368 -393.92733)
			(xy 384.59537 -393.939522) (xy 384.60553 -393.942062) (xy 384.634635 -393.950077) (xy 384.690602 -393.972708)
			(xy 384.743108 -394.0025) (xy 384.791242 -394.038936) (xy 384.834168 -394.081383) (xy 384.871143 -394.129104)
			(xy 384.901523 -394.181271) (xy 384.924783 -394.23698) (xy 384.940518 -394.295262) (xy 384.948454 -394.355107)
			(xy 384.948938 -394.385292) (xy 384.948813 -394.399427) (xy 384.947031 -394.427641) (xy 384.945382 -394.44168)
			(xy 384.944618 -394.450287) (xy 384.948259 -394.467168) (xy 384.952494 -394.4747) (xy 384.968242 -394.5001)
			(xy 384.972935 -394.507173) (xy 384.986052 -394.517935) (xy 384.993896 -394.521182) (xy 385.01727 -394.530384)
			(xy 385.061167 -394.5548) (xy 385.100863 -394.585578) (xy 385.135445 -394.622009) (xy 385.164116 -394.663253)
			(xy 385.186215 -394.708361) (xy 385.201233 -394.756293) (xy 385.208825 -394.805947) (xy 385.209288 -394.831062)
			(xy 385.208865 -394.855264) (xy 385.201791 -394.903149) (xy 385.187804 -394.949489) (xy 385.167204 -394.993291)
			(xy 385.15417 -395.013688) (xy 385.149382 -395.021645) (xy 385.145348 -395.039756) (xy 385.146296 -395.048994)
			(xy 385.150614 -395.079982) (xy 385.152292 -395.089279) (xy 385.161575 -395.105721) (xy 385.168648 -395.111986)
			(xy 385.190733 -395.130672) (xy 385.230506 -395.172682) (xy 385.264668 -395.21937) (xy 385.292676 -395.269989)
			(xy 385.314084 -395.323733) (xy 385.32855 -395.379747) (xy 385.335843 -395.437136) (xy 385.336288 -395.466062)
			(xy 385.335694 -395.499383) (xy 385.326032 -395.565321) (xy 385.306908 -395.629161) (xy 385.293362 -395.65961)
			(xy 385.289086 -395.670068) (xy 385.289199 -395.692637) (xy 385.29895 -395.712991) (xy 385.307332 -395.72057)
			(xy 385.329569 -395.739255) (xy 385.369632 -395.781309) (xy 385.404052 -395.828094) (xy 385.432278 -395.878857)
			(xy 385.453855 -395.932783) (xy 385.468437 -395.989005) (xy 385.475789 -396.046621) (xy 385.476242 -396.075662)
			(xy 385.475769 -396.104667) (xy 385.468458 -396.162215) (xy 385.453936 -396.218377) (xy 385.432435 -396.272256)
			(xy 385.4043 -396.322986) (xy 385.369981 -396.369756) (xy 385.33003 -396.411816) (xy 385.30784 -396.4305)
			(xy 385.300728 -396.436088) (xy 385.291584 -396.451328) (xy 385.276344 -396.534132) (xy 385.279138 -396.551404)
			(xy 385.28371 -396.559532) (xy 385.296283 -396.58272) (xy 385.314158 -396.632341) (xy 385.32326 -396.684292)
			(xy 385.323842 -396.710662) (xy 385.323773 -396.720021) (xy 385.32263 -396.738703) (xy 385.321556 -396.748)
			(xy 385.32054 -396.75689) (xy 385.32435 -396.773654) (xy 385.368292 -396.843504) (xy 385.382008 -396.853918)
			(xy 385.39039 -396.856712) (xy 385.414486 -396.865197) (xy 385.459777 -396.888821) (xy 385.500672 -396.919431)
			(xy 385.536104 -396.956228) (xy 385.565147 -396.99825) (xy 385.587044 -397.044401) (xy 385.594606 -397.068802)
			(xy 385.59613 -397.074644) (xy 385.915916 -397.627602) (xy 385.91998 -397.63192) (xy 385.936168 -397.649642)
			(xy 385.963596 -397.689028) (xy 385.984742 -397.732114) (xy 385.999119 -397.777906) (xy 386.006396 -397.825346)
			(xy 386.006848 -397.849344) (xy 386.006447 -397.87415) (xy 385.998675 -397.923151) (xy 385.98333 -397.970332)
			(xy 385.960791 -398.014529) (xy 385.931611 -398.054654) (xy 385.896512 -398.089718) (xy 385.856357 -398.118857)
			(xy 385.812137 -398.141352) (xy 385.764941 -398.156649) (xy 385.715933 -398.164371) (xy 385.691126 -398.164812)
			(xy 385.665732 -398.164289) (xy 385.6156 -398.156162) (xy 385.567415 -398.140114) (xy 385.52242 -398.11656)
			(xy 385.481777 -398.086105) (xy 385.446534 -398.049537) (xy 385.4176 -398.007798) (xy 385.395721 -397.961966)
			(xy 385.388104 -397.937736) (xy 385.38658 -397.931894) (xy 385.066032 -397.377412) (xy 385.061968 -397.373094)
			(xy 385.045868 -397.355422) (xy 385.018618 -397.316144) (xy 384.997607 -397.273204) (xy 384.983314 -397.227586)
			(xy 384.976067 -397.180334) (xy 384.975608 -397.156432) (xy 384.97575 -397.14438) (xy 384.977656 -397.12035)
			(xy 384.979418 -397.108426) (xy 384.980688 -397.099536) (xy 384.97764 -397.082518) (xy 384.935476 -397.011652)
			(xy 384.922268 -397.000476) (xy 384.913886 -396.997428) (xy 384.892142 -396.989024) (xy 384.851283 -396.966585)
			(xy 384.814311 -396.938194) (xy 384.782088 -396.904509) (xy 384.755362 -396.866317) (xy 384.734756 -396.824504)
			(xy 384.720748 -396.780043) (xy 384.713664 -396.73397) (xy 384.713226 -396.710662) (xy 384.713788 -396.684289)
			(xy 384.722872 -396.63233) (xy 384.740762 -396.58271) (xy 384.753358 -396.559532) (xy 384.75793 -396.551404)
			(xy 384.760724 -396.534132) (xy 384.745484 -396.451328) (xy 384.73634 -396.436088) (xy 384.729228 -396.4305)
			(xy 384.707063 -396.411787) (xy 384.667115 -396.369728) (xy 384.632796 -396.322961) (xy 384.604656 -396.272236)
			(xy 384.583145 -396.218365) (xy 384.568608 -396.162208) (xy 384.561277 -396.104666) (xy 384.560826 -396.075662)
			(xy 384.561427 -396.042341) (xy 384.571086 -395.976403) (xy 384.590207 -395.912563) (xy 384.603752 -395.882114)
			(xy 384.608 -395.871648) (xy 384.607896 -395.849086) (xy 384.598157 -395.828735) (xy 384.589782 -395.821154)
			(xy 384.567511 -395.802508) (xy 384.52745 -395.760447) (xy 384.493032 -395.713655) (xy 384.464811 -395.662886)
			(xy 384.443239 -395.608953) (xy 384.428664 -395.552725) (xy 384.42132 -395.495105) (xy 384.420872 -395.466062)
			(xy 384.421316 -395.437135) (xy 384.4286 -395.379742) (xy 384.44306 -395.323725) (xy 384.464465 -395.269977)
			(xy 384.492473 -395.219356) (xy 384.526638 -395.172668) (xy 384.566415 -395.130659) (xy 384.588512 -395.111986)
			(xy 384.595476 -395.105631) (xy 384.60474 -395.089233) (xy 384.606546 -395.079982) (xy 384.610864 -395.048994)
			(xy 384.611765 -395.039757) (xy 384.607742 -395.021658) (xy 384.60299 -395.013688) (xy 384.586681 -394.987843)
			(xy 384.562778 -394.931607) (xy 384.555492 -394.901928) (xy 384.553435 -394.893765) (xy 384.544733 -394.879364)
			(xy 384.538474 -394.873734) (xy 384.51536 -394.854684) (xy 384.508485 -394.84943) (xy 384.492251 -394.843469)
			(xy 384.48361 -394.843) (xy 384.453975 -394.841946) (xy 384.395312 -394.833303) (xy 384.338255 -394.817158)
			(xy 384.283761 -394.793781) (xy 384.232742 -394.763563) (xy 384.186052 -394.72701) (xy 384.144472 -394.684734)
			(xy 384.108699 -394.637444) (xy 384.079332 -394.58593) (xy 384.056862 -394.531055) (xy 384.041665 -394.473739)
			(xy 384.033997 -394.41494) (xy 384.033522 -394.385292) (xy 384.034044 -394.354229) (xy 384.042459 -394.292675)
			(xy 384.050286 -394.26261) (xy 384.05308 -394.25245) (xy 384.05054 -394.232638) (xy 384.003042 -394.150342)
			(xy 383.98704 -394.13815) (xy 383.97688 -394.13561) (xy 383.947769 -394.127614) (xy 383.891801 -394.104982)
			(xy 383.839294 -394.075189) (xy 383.791159 -394.038751) (xy 383.748232 -393.996302) (xy 383.711257 -393.948579)
			(xy 383.680878 -393.896409) (xy 383.65762 -393.840698) (xy 383.641888 -393.782413) (xy 383.633954 -393.722565)
			(xy 383.633472 -393.69238) (xy 383.634002 -393.661492) (xy 383.642306 -393.600277) (xy 383.658762 -393.540733)
			(xy 383.68307 -393.483941) (xy 383.698496 -393.457176) (xy 383.704338 -393.44727) (xy 383.706624 -393.424918)
			(xy 383.67335 -393.329668) (xy 383.657602 -393.313666) (xy 383.646934 -393.309602) (xy 383.623539 -393.300452)
			(xy 383.579644 -393.276025) (xy 383.53995 -393.245238) (xy 383.505371 -393.208799) (xy 383.476704 -393.167548)
			(xy 383.454608 -393.122434) (xy 383.439593 -393.074497) (xy 383.432004 -393.024839) (xy 383.431542 -392.999722)
			(xy 382.893062 -392.999722) (xy 382.892531 -393.026824) (xy 382.883722 -393.080307) (xy 382.875536 -393.106148)
			(xy 382.871726 -393.11707) (xy 382.874266 -393.139422) (xy 382.926844 -393.225274) (xy 382.945894 -393.23772)
			(xy 382.95707 -393.239498) (xy 382.986393 -393.244175) (xy 383.043564 -393.260228) (xy 383.098178 -393.283542)
			(xy 383.149317 -393.313725) (xy 383.196122 -393.35027) (xy 383.237806 -393.392562) (xy 383.273669 -393.439891)
			(xy 383.303109 -393.491462) (xy 383.32563 -393.546407) (xy 383.340854 -393.603805) (xy 383.348525 -393.662689)
			(xy 383.348992 -393.69238) (xy 383.348464 -393.723443) (xy 383.340053 -393.784996) (xy 383.332228 -393.815062)
			(xy 383.329434 -393.825222) (xy 383.331974 -393.845034) (xy 383.379472 -393.92733) (xy 383.395474 -393.939522)
			(xy 383.405634 -393.942062) (xy 383.43474 -393.950074) (xy 383.490706 -393.972706) (xy 383.543212 -394.002499)
			(xy 383.591346 -394.038934) (xy 383.634273 -394.081382) (xy 383.671247 -394.129103) (xy 383.701628 -394.181271)
			(xy 383.724887 -394.236979) (xy 383.740622 -394.295262) (xy 383.748558 -394.355107) (xy 383.749042 -394.385292)
			(xy 383.748917 -394.399427) (xy 383.747135 -394.427641) (xy 383.745486 -394.44168) (xy 383.744721 -394.450287)
			(xy 383.748363 -394.467168) (xy 383.752598 -394.4747) (xy 383.768346 -394.5001) (xy 383.773058 -394.507161)
			(xy 383.786155 -394.517941) (xy 383.794 -394.521182) (xy 383.817342 -394.530426) (xy 383.861186 -394.554877)
			(xy 383.900831 -394.585674) (xy 383.935367 -394.622108) (xy 383.964 -394.663343) (xy 383.986072 -394.708431)
			(xy 384.001077 -394.756338) (xy 384.008669 -394.805961) (xy 384.009138 -394.831062) (xy 384.008723 -394.855265)
			(xy 384.001648 -394.90315) (xy 383.987659 -394.94949) (xy 383.967055 -394.993291) (xy 383.95402 -395.013688)
			(xy 383.949229 -395.021643) (xy 383.945198 -395.039755) (xy 383.946146 -395.048994) (xy 383.950464 -395.079982)
			(xy 383.952157 -395.089275) (xy 383.961431 -395.105717) (xy 383.968498 -395.111986) (xy 383.990572 -395.130684)
			(xy 384.030347 -395.172691) (xy 384.064512 -395.219376) (xy 384.092523 -395.269993) (xy 384.113932 -395.323736)
			(xy 384.128399 -395.379748) (xy 384.135693 -395.437137) (xy 384.136138 -395.466062) (xy 384.135548 -395.499383)
			(xy 384.125886 -395.565322) (xy 384.10676 -395.629161) (xy 384.093212 -395.65961) (xy 384.088953 -395.670072)
			(xy 384.089066 -395.692635) (xy 384.098807 -395.712988) (xy 384.107182 -395.72057) (xy 384.129409 -395.739267)
			(xy 384.169474 -395.781318) (xy 384.203897 -395.8281) (xy 384.232124 -395.878861) (xy 384.253703 -395.932786)
			(xy 384.268286 -395.989007) (xy 384.275639 -396.046621) (xy 384.276092 -396.075662) (xy 384.275601 -396.104666)
			(xy 384.26829 -396.162212) (xy 384.25377 -396.218374) (xy 384.232272 -396.272252) (xy 384.20414 -396.322982)
			(xy 384.169825 -396.369753) (xy 384.129878 -396.411814) (xy 384.10769 -396.4305) (xy 384.100578 -396.436088)
			(xy 384.091434 -396.451328) (xy 384.076194 -396.534132) (xy 384.078988 -396.551404) (xy 384.08356 -396.559532)
			(xy 384.096137 -396.582718) (xy 384.11401 -396.63234) (xy 384.12311 -396.684291) (xy 384.123692 -396.710662)
			(xy 384.123624 -396.720021) (xy 384.12248 -396.738703) (xy 384.121406 -396.748) (xy 384.12039 -396.75689)
			(xy 384.1242 -396.773654) (xy 384.168142 -396.843504) (xy 384.181858 -396.853918) (xy 384.19024 -396.856712)
			(xy 384.214268 -396.86518) (xy 384.259441 -396.888733) (xy 384.300246 -396.919232) (xy 384.335625 -396.955887)
			(xy 384.36466 -396.997746) (xy 384.386599 -397.043724) (xy 384.394202 -397.06804) (xy 384.395726 -397.073882)
			(xy 384.71602 -397.627602) (xy 384.720084 -397.63192) (xy 384.736273 -397.649641) (xy 384.7637 -397.689028)
			(xy 384.784846 -397.732114) (xy 384.799223 -397.777906) (xy 384.8065 -397.825346) (xy 384.806952 -397.849344)
			(xy 384.806547 -397.87415) (xy 384.798775 -397.92315) (xy 384.783431 -397.970331) (xy 384.760891 -398.014528)
			(xy 384.731713 -398.054653) (xy 384.696614 -398.089717) (xy 384.65646 -398.118856) (xy 384.61224 -398.141351)
			(xy 384.565045 -398.156648) (xy 384.516037 -398.164371) (xy 384.49123 -398.164812) (xy 384.465837 -398.164285)
			(xy 384.415704 -398.156159) (xy 384.367519 -398.140112) (xy 384.322525 -398.116558) (xy 384.281882 -398.086104)
			(xy 384.246638 -398.049536) (xy 384.217704 -398.007798) (xy 384.195825 -397.961965) (xy 384.188208 -397.937736)
			(xy 384.186684 -397.931894) (xy 383.86639 -397.378174) (xy 383.862326 -397.373856) (xy 383.846162 -397.356126)
			(xy 383.818796 -397.316723) (xy 383.797706 -397.273632) (xy 383.78338 -397.227846) (xy 383.776146 -397.18042)
			(xy 383.775712 -397.156432) (xy 383.775793 -397.144384) (xy 383.777576 -397.120355) (xy 383.779268 -397.108426)
			(xy 383.780538 -397.099536) (xy 383.77749 -397.082518) (xy 383.735326 -397.011652) (xy 383.722118 -397.000476)
			(xy 383.713736 -396.997428) (xy 383.691981 -396.989051) (xy 383.651123 -396.966606) (xy 383.614154 -396.938209)
			(xy 383.581933 -396.904521) (xy 383.555209 -396.866324) (xy 383.534604 -396.824509) (xy 383.520597 -396.780046)
			(xy 383.513514 -396.73397) (xy 383.513076 -396.710662) (xy 383.513645 -396.684289) (xy 383.522727 -396.632331)
			(xy 383.540614 -396.58271) (xy 383.553208 -396.559532) (xy 383.55778 -396.551404) (xy 383.560574 -396.534132)
			(xy 383.545334 -396.451328) (xy 383.53619 -396.436088) (xy 383.529078 -396.4305) (xy 383.506903 -396.411799)
			(xy 383.466957 -396.369736) (xy 383.43264 -396.322967) (xy 383.404502 -396.27224) (xy 383.382993 -396.218367)
			(xy 383.368457 -396.162209) (xy 383.361127 -396.104666) (xy 383.360676 -396.075662) (xy 383.361273 -396.042341)
			(xy 383.370932 -395.976402) (xy 383.390056 -395.912563) (xy 383.403602 -395.882114) (xy 383.407834 -395.871643)
			(xy 383.407728 -395.849088) (xy 383.398 -395.828738) (xy 383.389632 -395.821154) (xy 383.367372 -395.802495)
			(xy 383.327308 -395.760438) (xy 383.292888 -395.713649) (xy 383.264664 -395.662882) (xy 383.243091 -395.608951)
			(xy 383.228515 -395.552724) (xy 383.22117 -395.495105) (xy 383.220722 -395.466062) (xy 383.221184 -395.437136)
			(xy 383.228467 -395.379745) (xy 383.242925 -395.323729) (xy 383.264328 -395.269981) (xy 383.292333 -395.21936)
			(xy 383.326494 -395.172671) (xy 383.366268 -395.13066) (xy 383.388362 -395.111986) (xy 383.395334 -395.105639)
			(xy 383.404592 -395.089235) (xy 383.406396 -395.079982) (xy 383.410714 -395.048994) (xy 383.411623 -395.039758)
			(xy 383.407596 -395.021657) (xy 383.40284 -395.013688) (xy 383.386535 -394.98784) (xy 383.36263 -394.931606)
			(xy 383.355342 -394.901928) (xy 383.353272 -394.89377) (xy 383.344578 -394.879367) (xy 383.338324 -394.873734)
			(xy 383.31521 -394.854684) (xy 383.30838 -394.849477) (xy 383.292287 -394.843507) (xy 383.283714 -394.843)
			(xy 383.254079 -394.841943) (xy 383.195416 -394.8333) (xy 383.13836 -394.817155) (xy 383.083866 -394.793778)
			(xy 383.032846 -394.763561) (xy 382.986156 -394.727008) (xy 382.944576 -394.684733) (xy 382.908803 -394.637443)
			(xy 382.879436 -394.585929) (xy 382.856966 -394.531055) (xy 382.841769 -394.473739) (xy 382.834101 -394.41494)
			(xy 382.833626 -394.385292) (xy 382.834148 -394.354229) (xy 382.842563 -394.292675) (xy 382.85039 -394.26261)
			(xy 382.853184 -394.25245) (xy 382.850644 -394.232638) (xy 382.803146 -394.150342) (xy 382.787144 -394.13815)
			(xy 382.776984 -394.13561) (xy 382.747874 -394.127612) (xy 382.691906 -394.10498) (xy 382.639398 -394.075187)
			(xy 382.591263 -394.03875) (xy 382.548336 -393.996301) (xy 382.511362 -393.948578) (xy 382.480982 -393.896408)
			(xy 382.457724 -393.840697) (xy 382.441992 -393.782413) (xy 382.434058 -393.722565) (xy 382.433576 -393.69238)
			(xy 382.434105 -393.661492) (xy 382.44241 -393.600277) (xy 382.458866 -393.540733) (xy 382.483174 -393.483941)
			(xy 382.4986 -393.457176) (xy 382.504442 -393.44727) (xy 382.506728 -393.424918) (xy 382.473454 -393.329668)
			(xy 382.457706 -393.313666) (xy 382.447038 -393.309602) (xy 382.423644 -393.300449) (xy 382.379749 -393.276023)
			(xy 382.340054 -393.245237) (xy 382.305475 -393.208798) (xy 382.276808 -393.167547) (xy 382.254712 -393.122434)
			(xy 382.239697 -393.074497) (xy 382.232108 -393.024839) (xy 382.231646 -392.999722) (xy 381.693166 -392.999722)
			(xy 381.692635 -393.026824) (xy 381.683826 -393.080307) (xy 381.67564 -393.106148) (xy 381.67183 -393.11707)
			(xy 381.67437 -393.139422) (xy 381.726948 -393.225528) (xy 381.745744 -393.23772) (xy 381.757174 -393.239498)
			(xy 381.786467 -393.244282) (xy 381.843601 -393.260359) (xy 381.898178 -393.283687) (xy 381.94928 -393.313876)
			(xy 381.996051 -393.350418) (xy 382.037705 -393.3927) (xy 382.073543 -393.440012) (xy 382.102964 -393.491561)
			(xy 382.125473 -393.54648) (xy 382.140694 -393.603849) (xy 382.14837 -393.662703) (xy 382.148842 -393.69238)
			(xy 382.148315 -393.723443) (xy 382.139903 -393.784996) (xy 382.132078 -393.815062) (xy 382.129284 -393.825222)
			(xy 382.131824 -393.845034) (xy 382.179322 -393.92733) (xy 382.195324 -393.939522) (xy 382.205484 -393.942062)
			(xy 382.2346 -393.95004) (xy 382.290565 -393.972678) (xy 382.34307 -394.002476) (xy 382.391203 -394.038917)
			(xy 382.434128 -394.081368) (xy 382.471101 -394.129093) (xy 382.50148 -394.181263) (xy 382.524739 -394.236975)
			(xy 382.540473 -394.295259) (xy 382.548409 -394.355106) (xy 382.548892 -394.385292) (xy 382.548767 -394.399427)
			(xy 382.546985 -394.427641) (xy 382.545336 -394.44168) (xy 382.544578 -394.450287) (xy 382.548217 -394.467167)
			(xy 382.552448 -394.4747) (xy 382.568196 -394.5001) (xy 382.572904 -394.507161) (xy 382.586011 -394.51793)
			(xy 382.59385 -394.521182) (xy 382.617236 -394.530354) (xy 382.661131 -394.554778) (xy 382.700825 -394.585561)
			(xy 382.735405 -394.621997) (xy 382.764073 -394.663245) (xy 382.786171 -394.708355) (xy 382.801188 -394.75629)
			(xy 382.808779 -394.805946) (xy 382.809242 -394.831062) (xy 382.808826 -394.855265) (xy 382.801752 -394.90315)
			(xy 382.787763 -394.94949) (xy 382.767159 -394.993291) (xy 382.754124 -395.013688) (xy 382.749333 -395.021643)
			(xy 382.745302 -395.039755) (xy 382.74625 -395.048994) (xy 382.750568 -395.079982) (xy 382.75226 -395.089275)
			(xy 382.761535 -395.105717) (xy 382.768602 -395.111986) (xy 382.790677 -395.130683) (xy 382.830452 -395.172691)
			(xy 382.864617 -395.219375) (xy 382.892627 -395.269993) (xy 382.914036 -395.323736) (xy 382.928503 -395.379748)
			(xy 382.935797 -395.437137) (xy 382.936242 -395.466062) (xy 382.935652 -395.499383) (xy 382.92599 -395.565322)
			(xy 382.906864 -395.629161) (xy 382.893316 -395.65961) (xy 382.889055 -395.670071) (xy 382.889169 -395.692635)
			(xy 382.898911 -395.712988) (xy 382.907286 -395.72057) (xy 382.929513 -395.739266) (xy 382.969578 -395.781317)
			(xy 383.004001 -395.8281) (xy 383.032229 -395.878861) (xy 383.053807 -395.932785) (xy 383.06839 -395.989007)
			(xy 383.075743 -396.046621) (xy 383.076196 -396.075662) (xy 383.075703 -396.104666) (xy 383.068393 -396.162212)
			(xy 383.053873 -396.218374) (xy 383.032374 -396.272251) (xy 383.004243 -396.322982) (xy 382.969929 -396.369753)
			(xy 382.929981 -396.411814) (xy 382.907794 -396.4305) (xy 382.900682 -396.436088) (xy 382.891538 -396.451328)
			(xy 382.876298 -396.534132) (xy 382.879092 -396.551404) (xy 382.883664 -396.559532) (xy 382.896241 -396.582718)
			(xy 382.914114 -396.63234) (xy 382.923214 -396.684291) (xy 382.923796 -396.710662) (xy 382.923728 -396.720021)
			(xy 382.922584 -396.738703) (xy 382.92151 -396.748) (xy 382.920494 -396.75689) (xy 382.924304 -396.773654)
			(xy 382.968246 -396.843504) (xy 382.981962 -396.853918) (xy 382.990344 -396.856712) (xy 383.014373 -396.865178)
			(xy 383.059545 -396.888731) (xy 383.10035 -396.919231) (xy 383.135729 -396.955886) (xy 383.164765 -396.997746)
			(xy 383.186703 -397.043724) (xy 383.194306 -397.06804) (xy 383.19583 -397.073882) (xy 383.516124 -397.627602)
			(xy 383.520188 -397.63192) (xy 383.536378 -397.64964) (xy 383.563804 -397.689028) (xy 383.58495 -397.732114)
			(xy 383.599327 -397.777906) (xy 383.606604 -397.825346) (xy 383.607056 -397.849344) (xy 383.606647 -397.87415)
			(xy 383.598875 -397.92315) (xy 383.583531 -397.97033) (xy 383.560992 -398.014527) (xy 383.531814 -398.054651)
			(xy 383.496715 -398.089715) (xy 383.456562 -398.118854) (xy 383.412343 -398.14135) (xy 383.365148 -398.156648)
			(xy 383.316141 -398.164371) (xy 383.291334 -398.164812) (xy 383.265941 -398.164282) (xy 383.215808 -398.156156)
			(xy 383.167624 -398.14011) (xy 383.122629 -398.116556) (xy 383.081986 -398.086103) (xy 383.046743 -398.049535)
			(xy 383.017808 -398.007797) (xy 382.995929 -397.961965) (xy 382.988312 -397.937736) (xy 382.986788 -397.931894)
			(xy 382.666494 -397.378174) (xy 382.66243 -397.373856) (xy 382.646267 -397.356126) (xy 382.6189 -397.316722)
			(xy 382.59781 -397.273631) (xy 382.583484 -397.227846) (xy 382.57625 -397.18042) (xy 382.575816 -397.156432)
			(xy 382.575897 -397.144384) (xy 382.577679 -397.120355) (xy 382.579372 -397.108426) (xy 382.580642 -397.099536)
			(xy 382.577594 -397.082518) (xy 382.53543 -397.011652) (xy 382.522222 -397.000476) (xy 382.51384 -396.997428)
			(xy 382.492086 -396.989049) (xy 382.451228 -396.966604) (xy 382.414259 -396.938208) (xy 382.382037 -396.90452)
			(xy 382.355313 -396.866324) (xy 382.334708 -396.824508) (xy 382.320701 -396.780046) (xy 382.313618 -396.73397)
			(xy 382.31318 -396.710662) (xy 382.313748 -396.684289) (xy 382.322831 -396.632331) (xy 382.340718 -396.58271)
			(xy 382.353312 -396.559532) (xy 382.357884 -396.551404) (xy 382.360678 -396.534132) (xy 382.345438 -396.451328)
			(xy 382.336294 -396.436088) (xy 382.329182 -396.4305) (xy 382.307008 -396.411798) (xy 382.267061 -396.369736)
			(xy 382.232745 -396.322967) (xy 382.204607 -396.27224) (xy 382.183098 -396.218367) (xy 382.168561 -396.162209)
			(xy 382.161231 -396.104666) (xy 382.16078 -396.075662) (xy 382.161376 -396.042341) (xy 382.171036 -395.976402)
			(xy 382.190159 -395.912563) (xy 382.203706 -395.882114) (xy 382.207936 -395.871643) (xy 382.207831 -395.849088)
			(xy 382.198103 -395.828738) (xy 382.189736 -395.821154) (xy 382.167476 -395.802494) (xy 382.127413 -395.760437)
			(xy 382.092992 -395.713649) (xy 382.064768 -395.662881) (xy 382.043195 -395.608951) (xy 382.028619 -395.552724)
			(xy 382.021274 -395.495105) (xy 382.020826 -395.466062) (xy 382.021287 -395.437136) (xy 382.02857 -395.379744)
			(xy 382.043028 -395.323728) (xy 382.064431 -395.269981) (xy 382.092436 -395.21936) (xy 382.126598 -395.172671)
			(xy 382.166371 -395.13066) (xy 382.188466 -395.111986) (xy 382.195439 -395.10564) (xy 382.204696 -395.089235)
			(xy 382.2065 -395.079982) (xy 382.210818 -395.048994) (xy 382.211727 -395.039757) (xy 382.2077 -395.021657)
			(xy 382.202944 -395.013688) (xy 382.18664 -394.98784) (xy 382.162734 -394.931606) (xy 382.155446 -394.901928)
			(xy 382.153375 -394.89377) (xy 382.144682 -394.879367) (xy 382.138428 -394.873734) (xy 382.115314 -394.854684)
			(xy 382.108425 -394.849451) (xy 382.092201 -394.843478) (xy 382.083564 -394.843) (xy 382.053927 -394.841989)
			(xy 381.995263 -394.83334) (xy 381.938206 -394.817189) (xy 381.883711 -394.793807) (xy 381.832692 -394.763584)
			(xy 381.786002 -394.727027) (xy 381.744423 -394.684748) (xy 381.708651 -394.637455) (xy 381.679284 -394.585938)
			(xy 381.656815 -394.531061) (xy 381.641619 -394.473742) (xy 381.633951 -394.414941) (xy 381.633476 -394.385292)
			(xy 381.633996 -394.354229) (xy 381.642413 -394.292675) (xy 381.65024 -394.26261) (xy 381.653034 -394.25245)
			(xy 381.650494 -394.232638) (xy 381.602996 -394.150342) (xy 381.586994 -394.13815) (xy 381.576834 -394.13561)
			(xy 381.547714 -394.127645) (xy 381.491747 -394.105007) (xy 381.43924 -394.075209) (xy 381.391107 -394.038767)
			(xy 381.348181 -393.996315) (xy 381.311208 -393.948588) (xy 381.280829 -393.896415) (xy 381.257572 -393.840702)
			(xy 381.241841 -393.782415) (xy 381.233907 -393.722566) (xy 381.233426 -393.69238) (xy 381.233901 -393.661458)
			(xy 381.242183 -393.600171) (xy 381.258648 -393.540559) (xy 381.282995 -393.48371) (xy 381.29845 -393.456922)
			(xy 381.304546 -393.44727) (xy 381.306832 -393.424918) (xy 381.273304 -393.329668) (xy 381.257556 -393.313666)
			(xy 381.246888 -393.309602) (xy 381.223538 -393.300378) (xy 381.179694 -393.275924) (xy 381.140049 -393.245124)
			(xy 381.105513 -393.208687) (xy 381.076882 -393.167449) (xy 381.054811 -393.122358) (xy 381.039808 -393.074449)
			(xy 381.032218 -393.024823) (xy 381.03175 -392.999722) (xy 380.493016 -392.999722) (xy 380.492483 -393.026824)
			(xy 380.483675 -393.080306) (xy 380.47549 -393.106148) (xy 380.47168 -393.11707) (xy 380.47422 -393.139422)
			(xy 380.526798 -393.225274) (xy 380.545848 -393.23772) (xy 380.557024 -393.239498) (xy 380.586341 -393.244211)
			(xy 380.643512 -393.260258) (xy 380.698126 -393.283567) (xy 380.749265 -393.313746) (xy 380.796071 -393.350286)
			(xy 380.837756 -393.392575) (xy 380.873621 -393.439901) (xy 380.903061 -393.491469) (xy 380.925583 -393.546412)
			(xy 380.940807 -393.603807) (xy 380.948479 -393.66269) (xy 380.948946 -393.69238) (xy 380.948419 -393.723443)
			(xy 380.940007 -393.784996) (xy 380.932182 -393.815062) (xy 380.929388 -393.825222) (xy 380.931928 -393.845034)
			(xy 380.979426 -393.92733) (xy 380.995428 -393.939522) (xy 381.005588 -393.942062) (xy 381.034704 -393.950038)
			(xy 381.09067 -393.972676) (xy 381.143175 -394.002475) (xy 381.191307 -394.038916) (xy 381.234233 -394.081367)
			(xy 381.271206 -394.129092) (xy 381.301585 -394.181263) (xy 381.324843 -394.236974) (xy 381.340577 -394.295259)
			(xy 381.348513 -394.355106) (xy 381.348996 -394.385292) (xy 381.348871 -394.399427) (xy 381.347089 -394.427641)
			(xy 381.34544 -394.44168) (xy 381.344682 -394.450287) (xy 381.34832 -394.467167) (xy 381.352552 -394.4747)
			(xy 381.3683 -394.5001) (xy 381.372994 -394.507175) (xy 381.386104 -394.517948) (xy 381.393954 -394.521182)
			(xy 381.417308 -394.530397) (xy 381.46115 -394.554855) (xy 381.500793 -394.585657) (xy 381.535327 -394.622096)
			(xy 381.563957 -394.663335) (xy 381.586028 -394.708426) (xy 381.601031 -394.756335) (xy 381.608623 -394.805961)
			(xy 381.609092 -394.831062) (xy 381.608668 -394.855264) (xy 381.601594 -394.903149) (xy 381.587608 -394.949489)
			(xy 381.567007 -394.993291) (xy 381.553974 -395.013688) (xy 381.549186 -395.021645) (xy 381.545152 -395.039756)
			(xy 381.5461 -395.048994) (xy 381.550418 -395.079982) (xy 381.552094 -395.08928) (xy 381.561379 -395.105721)
			(xy 381.568452 -395.111986) (xy 381.590538 -395.130671) (xy 381.63031 -395.172682) (xy 381.664473 -395.219369)
			(xy 381.692481 -395.269988) (xy 381.713888 -395.323733) (xy 381.728354 -395.379747) (xy 381.735647 -395.437136)
			(xy 381.736092 -395.466062) (xy 381.735497 -395.499383) (xy 381.725836 -395.565321) (xy 381.706712 -395.629161)
			(xy 381.693166 -395.65961) (xy 381.688922 -395.670076) (xy 381.689036 -395.692633) (xy 381.698768 -395.712984)
			(xy 381.707136 -395.72057) (xy 381.729374 -395.739254) (xy 381.769436 -395.781309) (xy 381.803857 -395.828094)
			(xy 381.832082 -395.878857) (xy 381.853659 -395.932783) (xy 381.868241 -395.989005) (xy 381.875593 -396.046621)
			(xy 381.876046 -396.075662) (xy 381.875571 -396.104667) (xy 381.86826 -396.162214) (xy 381.853738 -396.218377)
			(xy 381.832238 -396.272255) (xy 381.804103 -396.322986) (xy 381.769785 -396.369756) (xy 381.729834 -396.411815)
			(xy 381.707644 -396.4305) (xy 381.700532 -396.436088) (xy 381.691388 -396.451328) (xy 381.676148 -396.534132)
			(xy 381.678942 -396.551404) (xy 381.683514 -396.559532) (xy 381.696087 -396.58272) (xy 381.713962 -396.63234)
			(xy 381.723064 -396.684291) (xy 381.723646 -396.710662) (xy 381.723577 -396.720021) (xy 381.722434 -396.738703)
			(xy 381.72136 -396.748) (xy 381.720344 -396.75689) (xy 381.724154 -396.773654) (xy 381.768096 -396.843504)
			(xy 381.781812 -396.853918) (xy 381.790194 -396.856712) (xy 381.814213 -396.865204) (xy 381.859387 -396.888751)
			(xy 381.900193 -396.919245) (xy 381.935574 -396.955895) (xy 381.964612 -396.997751) (xy 381.986552 -397.043726)
			(xy 381.994156 -397.06804) (xy 381.99568 -397.073882) (xy 382.315974 -397.627602) (xy 382.320038 -397.63192)
			(xy 382.336232 -397.649624) (xy 382.363596 -397.689034) (xy 382.38468 -397.732131) (xy 382.398999 -397.777923)
			(xy 382.406223 -397.825354) (xy 382.406652 -397.849344) (xy 382.406223 -397.874136) (xy 382.39846 -397.923108)
			(xy 382.383132 -397.970262) (xy 382.360616 -398.014439) (xy 382.331468 -398.054549) (xy 382.296404 -398.089607)
			(xy 382.256288 -398.118748) (xy 382.212107 -398.141255) (xy 382.164949 -398.156574) (xy 382.115976 -398.164327)
			(xy 382.091184 -398.164812) (xy 382.065789 -398.164326) (xy 382.015655 -398.156193) (xy 381.967469 -398.140139)
			(xy 381.922475 -398.116578) (xy 381.881832 -398.086119) (xy 381.84659 -398.049546) (xy 381.817656 -398.007803)
			(xy 381.795778 -397.961967) (xy 381.788162 -397.937736) (xy 381.786638 -397.931894) (xy 381.466344 -397.378174)
			(xy 381.46228 -397.373856) (xy 381.446073 -397.35615) (xy 381.41865 -397.316759) (xy 381.397508 -397.273668)
			(xy 381.383135 -397.227874) (xy 381.375862 -397.180431) (xy 381.375412 -397.156432) (xy 381.375554 -397.14438)
			(xy 381.37746 -397.12035) (xy 381.379222 -397.108426) (xy 381.380492 -397.099536) (xy 381.377444 -397.082518)
			(xy 381.33528 -397.011652) (xy 381.322072 -397.000476) (xy 381.31369 -396.997428) (xy 381.291947 -396.989022)
			(xy 381.251087 -396.966584) (xy 381.214116 -396.938192) (xy 381.181893 -396.904509) (xy 381.155167 -396.866316)
			(xy 381.13456 -396.824503) (xy 381.120552 -396.780043) (xy 381.113468 -396.733969) (xy 381.11303 -396.710662)
			(xy 381.113592 -396.684289) (xy 381.122676 -396.63233) (xy 381.140566 -396.58271) (xy 381.153162 -396.559532)
			(xy 381.157734 -396.551404) (xy 381.160528 -396.534132) (xy 381.145288 -396.451328) (xy 381.136144 -396.436088)
			(xy 381.129032 -396.4305) (xy 381.106868 -396.411786) (xy 381.066919 -396.369727) (xy 381.0326 -396.322961)
			(xy 381.00446 -396.272236) (xy 380.982949 -396.218364) (xy 380.968412 -396.162208) (xy 380.961081 -396.104666)
			(xy 380.96063 -396.075662) (xy 380.961231 -396.042341) (xy 380.970889 -395.976403) (xy 380.990011 -395.912563)
			(xy 381.003556 -395.882114) (xy 381.007803 -395.871647) (xy 381.007698 -395.849086) (xy 380.997961 -395.828735)
			(xy 380.989586 -395.821154) (xy 380.967316 -395.802507) (xy 380.927255 -395.760446) (xy 380.892837 -395.713655)
			(xy 380.864615 -395.662885) (xy 380.843043 -395.608953) (xy 380.828468 -395.552725) (xy 380.821124 -395.495105)
			(xy 380.820676 -395.466062) (xy 380.821119 -395.437135) (xy 380.828403 -395.379742) (xy 380.842863 -395.323725)
			(xy 380.864267 -395.269977) (xy 380.892276 -395.219356) (xy 380.926442 -395.172668) (xy 380.966219 -395.130659)
			(xy 380.988316 -395.111986) (xy 380.995281 -395.105631) (xy 381.004544 -395.089233) (xy 381.00635 -395.079982)
			(xy 381.010668 -395.048994) (xy 381.011569 -395.039757) (xy 381.007546 -395.021658) (xy 381.002794 -395.013688)
			(xy 380.986485 -394.987843) (xy 380.962582 -394.931607) (xy 380.955296 -394.901928) (xy 380.953238 -394.893766)
			(xy 380.944536 -394.879365) (xy 380.938278 -394.873734) (xy 380.915164 -394.854684) (xy 380.908346 -394.849459)
			(xy 380.892244 -394.8435) (xy 380.883668 -394.843) (xy 380.854032 -394.841985) (xy 380.795367 -394.833337)
			(xy 380.73831 -394.817187) (xy 380.683816 -394.793805) (xy 380.632797 -394.763582) (xy 380.586107 -394.727026)
			(xy 380.544527 -394.684747) (xy 380.508755 -394.637454) (xy 380.479388 -394.585937) (xy 380.456919 -394.531061)
			(xy 380.441723 -394.473742) (xy 380.434055 -394.414941) (xy 380.43358 -394.385292) (xy 380.4341 -394.354229)
			(xy 380.442517 -394.292675) (xy 380.450344 -394.26261) (xy 380.453138 -394.25245) (xy 380.450598 -394.232638)
			(xy 380.4031 -394.150342) (xy 380.387098 -394.13815) (xy 380.376938 -394.13561) (xy 380.347819 -394.127643)
			(xy 380.291851 -394.105005) (xy 380.239345 -394.075207) (xy 380.191211 -394.038766) (xy 380.148285 -393.996314)
			(xy 380.111312 -393.948587) (xy 380.080933 -393.896415) (xy 380.057676 -393.840702) (xy 380.041945 -393.782415)
			(xy 380.034011 -393.722566) (xy 380.03353 -393.69238) (xy 380.034052 -393.661492) (xy 380.042357 -393.600276)
			(xy 380.058815 -393.540732) (xy 380.083127 -393.48394) (xy 380.098554 -393.457176) (xy 380.104396 -393.44727)
			(xy 380.106682 -393.424918) (xy 380.073408 -393.329668) (xy 380.05766 -393.313666) (xy 380.046992 -393.309602)
			(xy 380.02361 -393.30042) (xy 379.979713 -393.276001) (xy 379.940016 -393.24522) (xy 379.905435 -393.208786)
			(xy 379.876766 -393.167539) (xy 379.854668 -393.122429) (xy 379.839652 -393.074494) (xy 379.832062 -393.024838)
			(xy 379.8316 -392.999722) (xy 379.29312 -392.999722) (xy 379.292587 -393.026824) (xy 379.283779 -393.080306)
			(xy 379.275594 -393.106148) (xy 379.271784 -393.11707) (xy 379.274324 -393.139422) (xy 379.326902 -393.225274)
			(xy 379.345952 -393.23772) (xy 379.357128 -393.239498) (xy 379.386446 -393.244208) (xy 379.443616 -393.260256)
			(xy 379.49823 -393.283565) (xy 379.54937 -393.313744) (xy 379.596176 -393.350285) (xy 379.637861 -393.392574)
			(xy 379.673725 -393.4399) (xy 379.703165 -393.491468) (xy 379.725687 -393.546412) (xy 379.740911 -393.603807)
			(xy 379.748583 -393.66269) (xy 379.74905 -393.69238) (xy 379.748527 -393.723506) (xy 379.740121 -393.785188)
			(xy 379.732286 -393.815316) (xy 379.729492 -393.825476) (xy 379.732032 -393.845542) (xy 379.779276 -393.92733)
			(xy 379.795278 -393.939522) (xy 379.805438 -393.942062) (xy 379.834545 -393.950071) (xy 379.890511 -393.972704)
			(xy 379.943017 -394.002497) (xy 379.991151 -394.038933) (xy 380.034077 -394.08138) (xy 380.071051 -394.129102)
			(xy 380.101432 -394.18127) (xy 380.124691 -394.236979) (xy 380.140426 -394.295262) (xy 380.148362 -394.355107)
			(xy 380.148846 -394.385292) (xy 380.148721 -394.399427) (xy 380.146939 -394.427641) (xy 380.14529 -394.44168)
			(xy 380.144524 -394.450287) (xy 380.148167 -394.467168) (xy 380.152402 -394.4747) (xy 380.16815 -394.5001)
			(xy 380.172872 -394.50715) (xy 380.185969 -394.517925) (xy 380.193804 -394.521182) (xy 380.21718 -394.530379)
			(xy 380.261076 -394.554797) (xy 380.300772 -394.585575) (xy 380.335354 -394.622007) (xy 380.364024 -394.663252)
			(xy 380.386123 -394.70836) (xy 380.401141 -394.756293) (xy 380.408733 -394.805947) (xy 380.409196 -394.831062)
			(xy 380.408771 -394.855264) (xy 380.401698 -394.903149) (xy 380.387711 -394.949488) (xy 380.367111 -394.99329)
			(xy 380.354078 -395.013688) (xy 380.349291 -395.021645) (xy 380.345256 -395.039756) (xy 380.346204 -395.048994)
			(xy 380.350522 -395.079982) (xy 380.352197 -395.08928) (xy 380.361482 -395.105721) (xy 380.368556 -395.111986)
			(xy 380.390643 -395.13067) (xy 380.430415 -395.172681) (xy 380.464577 -395.219369) (xy 380.492585 -395.269988)
			(xy 380.513992 -395.323733) (xy 380.528458 -395.379747) (xy 380.535751 -395.437136) (xy 380.536196 -395.466062)
			(xy 380.535601 -395.499383) (xy 380.52594 -395.565321) (xy 380.506816 -395.629161) (xy 380.49327 -395.65961)
			(xy 380.489025 -395.670075) (xy 380.489139 -395.692634) (xy 380.498871 -395.712985) (xy 380.50724 -395.72057)
			(xy 380.529458 -395.739278) (xy 380.569525 -395.781326) (xy 380.60395 -395.828105) (xy 380.632179 -395.878864)
			(xy 380.65376 -395.932788) (xy 380.668344 -395.989008) (xy 380.675697 -396.046622) (xy 380.67615 -396.075662)
			(xy 380.675674 -396.104667) (xy 380.668363 -396.162214) (xy 380.653841 -396.218377) (xy 380.632341 -396.272255)
			(xy 380.604206 -396.322985) (xy 380.569888 -396.369755) (xy 380.529937 -396.411815) (xy 380.507748 -396.4305)
			(xy 380.500636 -396.436088) (xy 380.491492 -396.451328) (xy 380.476252 -396.534132) (xy 380.479046 -396.551404)
			(xy 380.483618 -396.559532) (xy 380.496191 -396.58272) (xy 380.514066 -396.63234) (xy 380.523168 -396.684291)
			(xy 380.52375 -396.710662) (xy 380.523681 -396.720021) (xy 380.522538 -396.738703) (xy 380.521464 -396.748)
			(xy 380.520448 -396.75689) (xy 380.524258 -396.773654) (xy 380.5682 -396.843504) (xy 380.581916 -396.853918)
			(xy 380.590298 -396.856712) (xy 380.614318 -396.865202) (xy 380.659491 -396.888749) (xy 380.700298 -396.919244)
			(xy 380.735679 -396.955894) (xy 380.764716 -396.99775) (xy 380.786656 -397.043726) (xy 380.79426 -397.06804)
			(xy 380.795784 -397.073882) (xy 381.116078 -397.627602) (xy 381.120142 -397.63192) (xy 381.136337 -397.649623)
			(xy 381.1637 -397.689033) (xy 381.184784 -397.732131) (xy 381.199103 -397.777923) (xy 381.206328 -397.825354)
			(xy 381.206756 -397.849344) (xy 381.206323 -397.874135) (xy 381.19856 -397.923107) (xy 381.183232 -397.970261)
			(xy 381.160717 -398.014438) (xy 381.131569 -398.054548) (xy 381.096505 -398.089605) (xy 381.05639 -398.118746)
			(xy 381.012209 -398.141254) (xy 380.965052 -398.156573) (xy 380.916079 -398.164327) (xy 380.891288 -398.164812)
			(xy 380.865893 -398.164322) (xy 380.815759 -398.15619) (xy 380.767573 -398.140136) (xy 380.722579 -398.116576)
			(xy 380.681936 -398.086118) (xy 380.646694 -398.049545) (xy 380.61776 -398.007803) (xy 380.595882 -397.961967)
			(xy 380.588266 -397.937736) (xy 380.586742 -397.931894) (xy 380.266448 -397.378174) (xy 380.262384 -397.373856)
			(xy 380.246178 -397.35615) (xy 380.218755 -397.316758) (xy 380.197613 -397.273668) (xy 380.183239 -397.227874)
			(xy 380.175966 -397.180431) (xy 380.175516 -397.156432) (xy 380.175658 -397.14438) (xy 380.177564 -397.12035)
			(xy 380.179326 -397.108426) (xy 380.180596 -397.099536) (xy 380.177548 -397.082518) (xy 380.135384 -397.011652)
			(xy 380.122176 -397.000476) (xy 380.113794 -396.997428) (xy 380.092051 -396.98902) (xy 380.051192 -396.966582)
			(xy 380.014221 -396.938191) (xy 379.981997 -396.904508) (xy 379.955271 -396.866315) (xy 379.934664 -396.824503)
			(xy 379.920656 -396.780043) (xy 379.913572 -396.733969) (xy 379.913134 -396.710662) (xy 379.913695 -396.684289)
			(xy 379.922779 -396.63233) (xy 379.94067 -396.58271) (xy 379.953266 -396.559532) (xy 379.957838 -396.551404)
			(xy 379.960632 -396.534132) (xy 379.945392 -396.451328) (xy 379.936248 -396.436088) (xy 379.929136 -396.4305)
			(xy 379.906973 -396.411785) (xy 379.867024 -396.369726) (xy 379.832705 -396.32296) (xy 379.804564 -396.272236)
			(xy 379.783053 -396.218364) (xy 379.768516 -396.162208) (xy 379.761185 -396.104666) (xy 379.760734 -396.075662)
			(xy 379.761335 -396.042341) (xy 379.770993 -395.976403) (xy 379.790115 -395.912563) (xy 379.80366 -395.882114)
			(xy 379.807906 -395.871647) (xy 379.807801 -395.849087) (xy 379.798064 -395.828735) (xy 379.78969 -395.821154)
			(xy 379.767421 -395.802506) (xy 379.727359 -395.760445) (xy 379.692941 -395.713654) (xy 379.664719 -395.662885)
			(xy 379.643147 -395.608953) (xy 379.628572 -395.552725) (xy 379.621228 -395.495105) (xy 379.62078 -395.466062)
			(xy 379.621221 -395.437135) (xy 379.628505 -395.379742) (xy 379.642965 -395.323725) (xy 379.66437 -395.269977)
			(xy 379.692379 -395.219355) (xy 379.726545 -395.172668) (xy 379.766323 -395.130659) (xy 379.78842 -395.111986)
			(xy 379.795385 -395.105632) (xy 379.804648 -395.089234) (xy 379.806454 -395.079982) (xy 379.810772 -395.048994)
			(xy 379.811672 -395.039757) (xy 379.80765 -395.021658) (xy 379.802898 -395.013688) (xy 379.786589 -394.987843)
			(xy 379.762686 -394.931607) (xy 379.7554 -394.901928) (xy 379.753341 -394.893766) (xy 379.74464 -394.879365)
			(xy 379.738382 -394.873734) (xy 379.715268 -394.854684) (xy 379.708391 -394.849433) (xy 379.692158 -394.84347)
			(xy 379.683518 -394.843) (xy 379.653883 -394.841939) (xy 379.59522 -394.833297) (xy 379.538164 -394.817153)
			(xy 379.48367 -394.793776) (xy 379.432651 -394.763559) (xy 379.38596 -394.727007) (xy 379.34438 -394.684732)
			(xy 379.308607 -394.637442) (xy 379.27924 -394.585929) (xy 379.25677 -394.531055) (xy 379.241573 -394.473739)
			(xy 379.233905 -394.41494) (xy 379.23343 -394.385292) (xy 379.233951 -394.354229) (xy 379.242367 -394.292675)
			(xy 379.250194 -394.26261) (xy 379.252988 -394.25245) (xy 379.250448 -394.232638) (xy 379.20295 -394.150342)
			(xy 379.186948 -394.13815) (xy 379.176788 -394.13561) (xy 379.14771 -394.127542) (xy 379.091783 -394.104882)
			(xy 379.039316 -394.075072) (xy 378.99122 -394.038628) (xy 378.948329 -393.996182) (xy 378.911384 -393.948469)
			(xy 378.881027 -393.896317) (xy 378.857784 -393.84063) (xy 378.842058 -393.782371) (xy 378.834121 -393.722552)
			(xy 378.833634 -393.69238) (xy 378.834155 -393.661492) (xy 378.842461 -393.600276) (xy 378.858919 -393.540732)
			(xy 378.88323 -393.48394) (xy 378.898658 -393.457176) (xy 378.9045 -393.44727) (xy 378.906786 -393.424918)
			(xy 378.873512 -393.329668) (xy 378.857764 -393.313666) (xy 378.847096 -393.309602) (xy 378.823715 -393.300418)
			(xy 378.779817 -393.275999) (xy 378.740121 -393.245219) (xy 378.70554 -393.208785) (xy 378.67687 -393.167539)
			(xy 378.654772 -393.122428) (xy 378.639756 -393.074493) (xy 378.632166 -393.024838) (xy 378.631704 -392.999722)
			(xy 378.09297 -392.999722) (xy 378.092439 -393.026824) (xy 378.08363 -393.080307) (xy 378.075444 -393.106148)
			(xy 378.071634 -393.11707) (xy 378.074174 -393.139422) (xy 378.126752 -393.225274) (xy 378.145802 -393.23772)
			(xy 378.156978 -393.239498) (xy 378.186302 -393.244168) (xy 378.243473 -393.260223) (xy 378.298087 -393.283538)
			(xy 378.349226 -393.313722) (xy 378.396031 -393.350267) (xy 378.437715 -393.39256) (xy 378.473578 -393.439889)
			(xy 378.503017 -393.491461) (xy 378.525538 -393.546407) (xy 378.540762 -393.603804) (xy 378.548433 -393.662689)
			(xy 378.5489 -393.69238) (xy 378.548375 -393.723443) (xy 378.539962 -393.784997) (xy 378.532136 -393.815062)
			(xy 378.529342 -393.825222) (xy 378.531882 -393.845034) (xy 378.57938 -393.92733) (xy 378.595382 -393.939522)
			(xy 378.605542 -393.942062) (xy 378.634649 -393.950069) (xy 378.690616 -393.972702) (xy 378.743121 -394.002495)
			(xy 378.791255 -394.038932) (xy 378.834182 -394.081379) (xy 378.871156 -394.129101) (xy 378.901536 -394.18127)
			(xy 378.924795 -394.236979) (xy 378.94053 -394.295262) (xy 378.948466 -394.355107) (xy 378.94895 -394.385292)
			(xy 378.948825 -394.399427) (xy 378.947043 -394.427641) (xy 378.945394 -394.44168) (xy 378.944628 -394.450287)
			(xy 378.94827 -394.467168) (xy 378.952506 -394.4747) (xy 378.968254 -394.5001) (xy 378.972975 -394.507151)
			(xy 378.986073 -394.517925) (xy 378.993908 -394.521182) (xy 379.017285 -394.530377) (xy 379.061181 -394.554795)
			(xy 379.100877 -394.585574) (xy 379.135458 -394.622006) (xy 379.164128 -394.663251) (xy 379.186227 -394.70836)
			(xy 379.201245 -394.756293) (xy 379.208837 -394.805947) (xy 379.2093 -394.831062) (xy 379.208875 -394.855264)
			(xy 379.201801 -394.903149) (xy 379.187815 -394.949488) (xy 379.167215 -394.99329) (xy 379.154182 -395.013688)
			(xy 379.149395 -395.021645) (xy 379.14536 -395.039756) (xy 379.146308 -395.048994) (xy 379.150626 -395.079982)
			(xy 379.1523 -395.08928) (xy 379.161586 -395.105721) (xy 379.16866 -395.111986) (xy 379.190748 -395.130669)
			(xy 379.230519 -395.17268) (xy 379.264681 -395.219368) (xy 379.292689 -395.269988) (xy 379.314097 -395.323733)
			(xy 379.328562 -395.379746) (xy 379.335855 -395.437136) (xy 379.3363 -395.466062) (xy 379.335714 -395.499384)
			(xy 379.326051 -395.565322) (xy 379.306923 -395.629161) (xy 379.293374 -395.65961) (xy 379.289127 -395.670075)
			(xy 379.289241 -395.692634) (xy 379.298975 -395.712985) (xy 379.307344 -395.72057) (xy 379.329563 -395.739277)
			(xy 379.36963 -395.781325) (xy 379.404054 -395.828105) (xy 379.432284 -395.878864) (xy 379.453864 -395.932787)
			(xy 379.468448 -395.989008) (xy 379.475801 -396.046621) (xy 379.476254 -396.075662) (xy 379.475776 -396.104667)
			(xy 379.468466 -396.162214) (xy 379.453944 -396.218377) (xy 379.432444 -396.272255) (xy 379.404309 -396.322985)
			(xy 379.369992 -396.369755) (xy 379.330041 -396.411815) (xy 379.307852 -396.4305) (xy 379.30074 -396.436088)
			(xy 379.291596 -396.451328) (xy 379.276356 -396.534132) (xy 379.27915 -396.551404) (xy 379.283722 -396.559532)
			(xy 379.296296 -396.582719) (xy 379.314171 -396.63234) (xy 379.323272 -396.684291) (xy 379.323854 -396.710662)
			(xy 379.323785 -396.720021) (xy 379.322642 -396.738703) (xy 379.321568 -396.748) (xy 379.320552 -396.75689)
			(xy 379.324362 -396.773654) (xy 379.368304 -396.843504) (xy 379.38202 -396.853918) (xy 379.390402 -396.856712)
			(xy 379.4145 -396.865191) (xy 379.459791 -396.888817) (xy 379.500686 -396.919428) (xy 379.536117 -396.956225)
			(xy 379.56516 -396.998249) (xy 379.587056 -397.044401) (xy 379.594618 -397.068802) (xy 379.596142 -397.074644)
			(xy 379.915928 -397.627602) (xy 379.919992 -397.63192) (xy 379.936182 -397.64964) (xy 379.963609 -397.689027)
			(xy 379.984754 -397.732114) (xy 379.999131 -397.777906) (xy 380.006408 -397.825346) (xy 380.00686 -397.849344)
			(xy 380.006447 -397.87415) (xy 379.998675 -397.923149) (xy 379.983331 -397.970329) (xy 379.960793 -398.014525)
			(xy 379.931615 -398.05465) (xy 379.896517 -398.089714) (xy 379.856364 -398.118853) (xy 379.812146 -398.141349)
			(xy 379.764951 -398.156647) (xy 379.715944 -398.164371) (xy 379.691138 -398.164812) (xy 379.665745 -398.164278)
			(xy 379.615613 -398.156153) (xy 379.567428 -398.140107) (xy 379.522434 -398.116554) (xy 379.48179 -398.086101)
			(xy 379.446547 -398.049534) (xy 379.417612 -398.007797) (xy 379.395733 -397.961965) (xy 379.388116 -397.937736)
			(xy 379.386592 -397.931894) (xy 379.066044 -397.377412) (xy 379.06198 -397.373094) (xy 379.045882 -397.35542)
			(xy 379.018632 -397.316143) (xy 378.997619 -397.273204) (xy 378.983326 -397.227586) (xy 378.976079 -397.180334)
			(xy 378.97562 -397.156432) (xy 378.975762 -397.14438) (xy 378.977668 -397.12035) (xy 378.97943 -397.108426)
			(xy 378.9807 -397.099536) (xy 378.977652 -397.082518) (xy 378.935488 -397.011652) (xy 378.92228 -397.000476)
			(xy 378.913898 -396.997428) (xy 378.892156 -396.989017) (xy 378.851297 -396.96658) (xy 378.814325 -396.93819)
			(xy 378.782101 -396.904507) (xy 378.755375 -396.866315) (xy 378.734768 -396.824503) (xy 378.72076 -396.780043)
			(xy 378.713676 -396.733969) (xy 378.713238 -396.710662) (xy 378.713799 -396.684289) (xy 378.722883 -396.63233)
			(xy 378.740774 -396.58271) (xy 378.75337 -396.559532) (xy 378.757942 -396.551404) (xy 378.760736 -396.534132)
			(xy 378.745496 -396.451328) (xy 378.736352 -396.436088) (xy 378.72924 -396.4305) (xy 378.707078 -396.411784)
			(xy 378.667129 -396.369726) (xy 378.632809 -396.32296) (xy 378.604669 -396.272235) (xy 378.583158 -396.218364)
			(xy 378.56862 -396.162208) (xy 378.561289 -396.104666) (xy 378.560838 -396.075662) (xy 378.561438 -396.042341)
			(xy 378.571097 -395.976403) (xy 378.590219 -395.912563) (xy 378.603764 -395.882114) (xy 378.608008 -395.871647)
			(xy 378.607904 -395.849087) (xy 378.598167 -395.828736) (xy 378.589794 -395.821154) (xy 378.567526 -395.802505)
			(xy 378.527464 -395.760445) (xy 378.493045 -395.713654) (xy 378.464823 -395.662885) (xy 378.443251 -395.608953)
			(xy 378.428676 -395.552725) (xy 378.421332 -395.495105) (xy 378.420884 -395.466062) (xy 378.421324 -395.437135)
			(xy 378.428608 -395.379742) (xy 378.443068 -395.323725) (xy 378.464473 -395.269976) (xy 378.492482 -395.219355)
			(xy 378.526649 -395.172668) (xy 378.566427 -395.130659) (xy 378.588524 -395.111986) (xy 378.59549 -395.105633)
			(xy 378.604752 -395.089234) (xy 378.606558 -395.079982) (xy 378.610876 -395.048994) (xy 378.611776 -395.039757)
			(xy 378.607754 -395.021658) (xy 378.603002 -395.013688) (xy 378.586694 -394.987843) (xy 378.56279 -394.931607)
			(xy 378.555504 -394.901928) (xy 378.553444 -394.893766) (xy 378.544744 -394.879365) (xy 378.538486 -394.873734)
			(xy 378.515372 -394.854684) (xy 378.508494 -394.849435) (xy 378.492262 -394.843471) (xy 378.483622 -394.843)
			(xy 378.453984 -394.842027) (xy 378.395318 -394.833373) (xy 378.33826 -394.817218) (xy 378.283766 -394.793831)
			(xy 378.232747 -394.763604) (xy 378.186057 -394.727044) (xy 378.144479 -394.684761) (xy 378.108707 -394.637465)
			(xy 378.079341 -394.585945) (xy 378.056872 -394.531066) (xy 378.041677 -394.473745) (xy 378.034009 -394.414942)
			(xy 378.033534 -394.385292) (xy 378.034055 -394.354229) (xy 378.042471 -394.292675) (xy 378.050298 -394.26261)
			(xy 378.053092 -394.25245) (xy 378.050552 -394.232638) (xy 378.003054 -394.150342) (xy 377.987052 -394.13815)
			(xy 377.976892 -394.13561) (xy 377.947783 -394.127606) (xy 377.891815 -394.104975) (xy 377.839308 -394.075183)
			(xy 377.791172 -394.038747) (xy 377.748245 -393.996299) (xy 377.71127 -393.948576) (xy 377.68089 -393.896407)
			(xy 377.657632 -393.840697) (xy 377.6419 -393.782412) (xy 377.633966 -393.722565) (xy 377.633484 -393.69238)
			(xy 377.634012 -393.661492) (xy 377.642317 -393.600277) (xy 377.658773 -393.540733) (xy 377.683082 -393.483941)
			(xy 377.698508 -393.457176) (xy 377.70435 -393.44727) (xy 377.706636 -393.424918) (xy 377.673362 -393.329668)
			(xy 377.657614 -393.313666) (xy 377.646946 -393.309602) (xy 377.623554 -393.300445) (xy 377.579658 -393.27602)
			(xy 377.539964 -393.245234) (xy 377.505384 -393.208797) (xy 377.476717 -393.167546) (xy 377.454621 -393.122433)
			(xy 377.439605 -393.074496) (xy 377.432016 -393.024839) (xy 377.431554 -392.999722) (xy 376.893074 -392.999722)
			(xy 376.892543 -393.026824) (xy 376.883734 -393.080307) (xy 376.875548 -393.106148) (xy 376.871738 -393.11707)
			(xy 376.874278 -393.139422) (xy 376.926856 -393.225274) (xy 376.945906 -393.23772) (xy 376.957082 -393.239498)
			(xy 376.986407 -393.244165) (xy 377.043578 -393.26022) (xy 377.098192 -393.283536) (xy 377.14933 -393.31372)
			(xy 377.196135 -393.350266) (xy 377.237819 -393.392559) (xy 377.273682 -393.439889) (xy 377.303121 -393.49146)
			(xy 377.325642 -393.546406) (xy 377.340866 -393.603804) (xy 377.348537 -393.662689) (xy 377.349004 -393.69238)
			(xy 377.348479 -393.723443) (xy 377.340066 -393.784997) (xy 377.33224 -393.815062) (xy 377.329446 -393.825222)
			(xy 377.331986 -393.845034) (xy 377.379484 -393.92733) (xy 377.395486 -393.939522) (xy 377.405646 -393.942062)
			(xy 377.434754 -393.950066) (xy 377.490721 -393.972699) (xy 377.543226 -394.002493) (xy 377.59136 -394.03893)
			(xy 377.634286 -394.081378) (xy 377.67126 -394.1291) (xy 377.701641 -394.181269) (xy 377.7249 -394.236978)
			(xy 377.740634 -394.295261) (xy 377.748571 -394.355107) (xy 377.749054 -394.385292) (xy 377.748929 -394.399427)
			(xy 377.747147 -394.427641) (xy 377.745498 -394.44168) (xy 377.744732 -394.450287) (xy 377.748374 -394.467168)
			(xy 377.75261 -394.4747) (xy 377.768358 -394.5001) (xy 377.773066 -394.507164) (xy 377.786166 -394.517943)
			(xy 377.794012 -394.521182) (xy 377.817356 -394.53042) (xy 377.8612 -394.554872) (xy 377.900845 -394.58567)
			(xy 377.93538 -394.622105) (xy 377.964013 -394.663341) (xy 377.986084 -394.70843) (xy 378.001089 -394.756337)
			(xy 378.008681 -394.805961) (xy 378.00915 -394.831062) (xy 378.008733 -394.855264) (xy 378.001658 -394.90315)
			(xy 377.98767 -394.94949) (xy 377.967067 -394.993291) (xy 377.954032 -395.013688) (xy 377.949241 -395.021643)
			(xy 377.94521 -395.039756) (xy 377.946158 -395.048994) (xy 377.950476 -395.079982) (xy 377.952165 -395.089276)
			(xy 377.961442 -395.105718) (xy 377.96851 -395.111986) (xy 377.990587 -395.130681) (xy 378.030361 -395.172689)
			(xy 378.064526 -395.219374) (xy 378.092535 -395.269992) (xy 378.113944 -395.323735) (xy 378.128411 -395.379748)
			(xy 378.135705 -395.437137) (xy 378.13615 -395.466062) (xy 378.135559 -395.499383) (xy 378.125897 -395.565322)
			(xy 378.106771 -395.629161) (xy 378.093224 -395.65961) (xy 378.088961 -395.670071) (xy 378.089075 -395.692635)
			(xy 378.098818 -395.712988) (xy 378.107194 -395.72057) (xy 378.129423 -395.739264) (xy 378.169487 -395.781316)
			(xy 378.20391 -395.828099) (xy 378.232137 -395.87886) (xy 378.253716 -395.932785) (xy 378.268298 -395.989006)
			(xy 378.275651 -396.046621) (xy 378.276104 -396.075662) (xy 378.275645 -396.104668) (xy 378.268333 -396.162216)
			(xy 378.253809 -396.21838) (xy 378.232307 -396.272259) (xy 378.204169 -396.322989) (xy 378.169848 -396.369758)
			(xy 378.129893 -396.411817) (xy 378.107702 -396.4305) (xy 378.10059 -396.436088) (xy 378.091446 -396.451328)
			(xy 378.076206 -396.534132) (xy 378.079 -396.551404) (xy 378.083572 -396.559532) (xy 378.096142 -396.582722)
			(xy 378.114019 -396.632341) (xy 378.123122 -396.684292) (xy 378.123704 -396.710662) (xy 378.123635 -396.720021)
			(xy 378.122492 -396.738703) (xy 378.121418 -396.748) (xy 378.120402 -396.75689) (xy 378.124212 -396.773654)
			(xy 378.168154 -396.843504) (xy 378.18187 -396.853918) (xy 378.190252 -396.856712) (xy 378.214283 -396.865173)
			(xy 378.259455 -396.888728) (xy 378.300259 -396.919229) (xy 378.335638 -396.955885) (xy 378.364673 -396.997745)
			(xy 378.386611 -397.043724) (xy 378.394214 -397.06804) (xy 378.395738 -397.073882) (xy 378.716032 -397.627602)
			(xy 378.720096 -397.63192) (xy 378.736287 -397.649639) (xy 378.763713 -397.689027) (xy 378.784859 -397.732114)
			(xy 378.799235 -397.777905) (xy 378.806512 -397.825346) (xy 378.806964 -397.849344) (xy 378.806547 -397.87415)
			(xy 378.798776 -397.923149) (xy 378.783432 -397.970328) (xy 378.760893 -398.014524) (xy 378.731716 -398.054649)
			(xy 378.696619 -398.089713) (xy 378.656466 -398.118851) (xy 378.612248 -398.141347) (xy 378.565055 -398.156646)
			(xy 378.516048 -398.16437) (xy 378.491242 -398.164812) (xy 378.465849 -398.164275) (xy 378.415717 -398.15615)
			(xy 378.367532 -398.140105) (xy 378.322538 -398.116552) (xy 378.281895 -398.0861) (xy 378.246651 -398.049534)
			(xy 378.217717 -398.007796) (xy 378.195837 -397.961965) (xy 378.18822 -397.937736) (xy 378.186696 -397.931894)
			(xy 377.866402 -397.378174) (xy 377.862338 -397.373856) (xy 377.846176 -397.356124) (xy 377.818809 -397.316721)
			(xy 377.797719 -397.273631) (xy 377.783392 -397.227846) (xy 377.776158 -397.18042) (xy 377.775724 -397.156432)
			(xy 377.775805 -397.144384) (xy 377.777587 -397.120355) (xy 377.77928 -397.108426) (xy 377.78055 -397.099536)
			(xy 377.777502 -397.082518) (xy 377.735338 -397.011652) (xy 377.72213 -397.000476) (xy 377.713748 -396.997428)
			(xy 377.691995 -396.989045) (xy 377.651138 -396.966601) (xy 377.614168 -396.938205) (xy 377.581946 -396.904518)
			(xy 377.555222 -396.866323) (xy 377.534616 -396.824508) (xy 377.520609 -396.780045) (xy 377.513526 -396.73397)
			(xy 377.513088 -396.710662) (xy 377.513655 -396.684289) (xy 377.522738 -396.632331) (xy 377.540626 -396.58271)
			(xy 377.55322 -396.559532) (xy 377.557792 -396.551404) (xy 377.560586 -396.534132) (xy 377.545346 -396.451328)
			(xy 377.536202 -396.436088) (xy 377.52909 -396.4305) (xy 377.506917 -396.411796) (xy 377.466971 -396.369734)
			(xy 377.432654 -396.322966) (xy 377.404515 -396.272239) (xy 377.383006 -396.218366) (xy 377.368469 -396.162209)
			(xy 377.361139 -396.104666) (xy 377.360688 -396.075662) (xy 377.361284 -396.042341) (xy 377.370943 -395.976402)
			(xy 377.390067 -395.912563) (xy 377.403614 -395.882114) (xy 377.407842 -395.871642) (xy 377.407737 -395.849088)
			(xy 377.398011 -395.828739) (xy 377.389644 -395.821154) (xy 377.367386 -395.802492) (xy 377.327322 -395.760436)
			(xy 377.292901 -395.713648) (xy 377.264677 -395.662881) (xy 377.243103 -395.60895) (xy 377.228527 -395.552724)
			(xy 377.221182 -395.495105) (xy 377.220734 -395.466062) (xy 377.221192 -395.437136) (xy 377.228475 -395.379744)
			(xy 377.242934 -395.323728) (xy 377.264336 -395.26998) (xy 377.292342 -395.219359) (xy 377.326505 -395.172671)
			(xy 377.366279 -395.13066) (xy 377.388374 -395.111986) (xy 377.395348 -395.105641) (xy 377.404604 -395.089235)
			(xy 377.406408 -395.079982) (xy 377.410726 -395.048994) (xy 377.411633 -395.039757) (xy 377.407607 -395.021657)
			(xy 377.402852 -395.013688) (xy 377.38654 -394.987845) (xy 377.362639 -394.931608) (xy 377.355354 -394.901928)
			(xy 377.353281 -394.893771) (xy 377.344589 -394.879368) (xy 377.338336 -394.873734) (xy 377.315222 -394.854684)
			(xy 377.308389 -394.849482) (xy 377.292299 -394.843509) (xy 377.283726 -394.843) (xy 377.254088 -394.842024)
			(xy 377.195422 -394.83337) (xy 377.138365 -394.817215) (xy 377.08387 -394.793829) (xy 377.032851 -394.763602)
			(xy 376.986162 -394.727042) (xy 376.944583 -394.68476) (xy 376.908811 -394.637464) (xy 376.879445 -394.585945)
			(xy 376.856976 -394.531066) (xy 376.841781 -394.473745) (xy 376.834113 -394.414942) (xy 376.833638 -394.385292)
			(xy 376.834159 -394.354229) (xy 376.842575 -394.292675) (xy 376.850402 -394.26261) (xy 376.853196 -394.25245)
			(xy 376.850656 -394.232638) (xy 376.803158 -394.150342) (xy 376.787156 -394.13815) (xy 376.776996 -394.13561)
			(xy 376.747888 -394.127604) (xy 376.69192 -394.104973) (xy 376.639412 -394.075182) (xy 376.591277 -394.038746)
			(xy 376.548349 -393.996298) (xy 376.511375 -393.948576) (xy 376.480995 -393.896406) (xy 376.457736 -393.840696)
			(xy 376.442004 -393.782412) (xy 376.43407 -393.722565) (xy 376.433588 -393.69238) (xy 376.434115 -393.661492)
			(xy 376.44242 -393.600277) (xy 376.458877 -393.540733) (xy 376.483186 -393.483941) (xy 376.498612 -393.457176)
			(xy 376.504454 -393.44727) (xy 376.50674 -393.424918) (xy 376.473466 -393.329668) (xy 376.457718 -393.313666)
			(xy 376.44705 -393.309602) (xy 376.423659 -393.300443) (xy 376.379763 -393.276018) (xy 376.340068 -393.245233)
			(xy 376.305489 -393.208796) (xy 376.276821 -393.167546) (xy 376.254725 -393.122433) (xy 376.239709 -393.074496)
			(xy 376.23212 -393.024839) (xy 376.231658 -392.999722) (xy 375.693178 -392.999722) (xy 375.692647 -393.026824)
			(xy 375.683838 -393.080307) (xy 375.675652 -393.106148) (xy 375.671842 -393.11707) (xy 375.674382 -393.139422)
			(xy 375.72696 -393.225528) (xy 375.745756 -393.23772) (xy 375.757186 -393.239498) (xy 375.786481 -393.244272)
			(xy 375.843615 -393.260351) (xy 375.898192 -393.283681) (xy 375.949294 -393.313871) (xy 375.996064 -393.350414)
			(xy 376.037718 -393.392697) (xy 376.073556 -393.44001) (xy 376.102976 -393.491559) (xy 376.125485 -393.546479)
			(xy 376.140706 -393.603848) (xy 376.148382 -393.662703) (xy 376.148854 -393.69238) (xy 376.148327 -393.723443)
			(xy 376.139915 -393.784996) (xy 376.13209 -393.815062) (xy 376.129296 -393.825222) (xy 376.131836 -393.845034)
			(xy 376.179334 -393.92733) (xy 376.195336 -393.939522) (xy 376.205496 -393.942062) (xy 376.234614 -393.950032)
			(xy 376.29058 -393.972672) (xy 376.343084 -394.002471) (xy 376.391217 -394.038913) (xy 376.434141 -394.081365)
			(xy 376.471114 -394.129091) (xy 376.501493 -394.181262) (xy 376.524751 -394.236973) (xy 376.540485 -394.295259)
			(xy 376.548421 -394.355106) (xy 376.548904 -394.385292) (xy 376.548779 -394.399427) (xy 376.546997 -394.427641)
			(xy 376.545348 -394.44168) (xy 376.544589 -394.450287) (xy 376.548228 -394.467167) (xy 376.55246 -394.4747)
			(xy 376.568208 -394.5001) (xy 376.572912 -394.507164) (xy 376.586022 -394.517931) (xy 376.593862 -394.521182)
			(xy 376.61725 -394.530348) (xy 376.661145 -394.554773) (xy 376.700839 -394.585557) (xy 376.735418 -394.621994)
			(xy 376.764086 -394.663243) (xy 376.786183 -394.708354) (xy 376.8012 -394.75629) (xy 376.808791 -394.805946)
			(xy 376.809254 -394.831062) (xy 376.808836 -394.855264) (xy 376.801762 -394.90315) (xy 376.787773 -394.949489)
			(xy 376.767171 -394.993291) (xy 376.754136 -395.013688) (xy 376.749346 -395.021643) (xy 376.745314 -395.039756)
			(xy 376.746262 -395.048994) (xy 376.75058 -395.079982) (xy 376.752268 -395.089276) (xy 376.761545 -395.105718)
			(xy 376.768614 -395.111986) (xy 376.790692 -395.13068) (xy 376.830466 -395.172689) (xy 376.86463 -395.219374)
			(xy 376.89264 -395.269992) (xy 376.914048 -395.323735) (xy 376.928515 -395.379748) (xy 376.935809 -395.437137)
			(xy 376.936254 -395.466062) (xy 376.935663 -395.499383) (xy 376.926001 -395.565322) (xy 376.906875 -395.629161)
			(xy 376.893328 -395.65961) (xy 376.889064 -395.670071) (xy 376.889177 -395.692635) (xy 376.898921 -395.712988)
			(xy 376.907298 -395.72057) (xy 376.929528 -395.739263) (xy 376.969592 -395.781315) (xy 377.004014 -395.828098)
			(xy 377.032241 -395.87886) (xy 377.05382 -395.932785) (xy 377.068402 -395.989006) (xy 377.075755 -396.046621)
			(xy 377.076208 -396.075662) (xy 377.075747 -396.104668) (xy 377.068436 -396.162216) (xy 377.053912 -396.21838)
			(xy 377.03241 -396.272258) (xy 377.004272 -396.322989) (xy 376.969952 -396.369758) (xy 376.929997 -396.411816)
			(xy 376.907806 -396.4305) (xy 376.900694 -396.436088) (xy 376.89155 -396.451328) (xy 376.87631 -396.534132)
			(xy 376.879104 -396.551404) (xy 376.883676 -396.559532) (xy 376.896246 -396.582721) (xy 376.914123 -396.632341)
			(xy 376.923226 -396.684292) (xy 376.923808 -396.710662) (xy 376.923739 -396.720021) (xy 376.922596 -396.738703)
			(xy 376.921522 -396.748) (xy 376.920506 -396.75689) (xy 376.924316 -396.773654) (xy 376.968258 -396.843504)
			(xy 376.981974 -396.853918) (xy 376.990356 -396.856712) (xy 377.014387 -396.865171) (xy 377.059559 -396.888726)
			(xy 377.100364 -396.919228) (xy 377.135742 -396.955884) (xy 377.164777 -396.997745) (xy 377.186715 -397.043724)
			(xy 377.194318 -397.06804) (xy 377.195842 -397.073882) (xy 377.516136 -397.627602) (xy 377.5202 -397.63192)
			(xy 377.536392 -397.649639) (xy 377.563818 -397.689027) (xy 377.584963 -397.732113) (xy 377.599339 -397.777905)
			(xy 377.606616 -397.825346) (xy 377.607068 -397.849344) (xy 377.606647 -397.874149) (xy 377.598876 -397.923148)
			(xy 377.583532 -397.970327) (xy 377.560994 -398.014523) (xy 377.531817 -398.054647) (xy 377.49672 -398.089711)
			(xy 377.456568 -398.11885) (xy 377.412351 -398.141346) (xy 377.365158 -398.156645) (xy 377.316152 -398.16437)
			(xy 377.291346 -398.164812) (xy 377.265953 -398.164271) (xy 377.215821 -398.156148) (xy 377.167637 -398.140103)
			(xy 377.122642 -398.116551) (xy 377.081999 -398.086099) (xy 377.046756 -398.049533) (xy 377.017821 -398.007796)
			(xy 376.995941 -397.961965) (xy 376.988324 -397.937736) (xy 376.9868 -397.931894) (xy 376.666506 -397.378174)
			(xy 376.662442 -397.373856) (xy 376.646281 -397.356124) (xy 376.618913 -397.316721) (xy 376.597823 -397.273631)
			(xy 376.583496 -397.227846) (xy 376.576262 -397.18042) (xy 376.575828 -397.156432) (xy 376.575909 -397.144384)
			(xy 376.577691 -397.120355) (xy 376.579384 -397.108426) (xy 376.580654 -397.099536) (xy 376.577606 -397.082518)
			(xy 376.535442 -397.011652) (xy 376.522234 -397.000476) (xy 376.513852 -396.997428) (xy 376.4921 -396.989043)
			(xy 376.451242 -396.966599) (xy 376.414272 -396.938204) (xy 376.38205 -396.904517) (xy 376.355326 -396.866322)
			(xy 376.33472 -396.824507) (xy 376.320713 -396.780045) (xy 376.31363 -396.73397) (xy 376.313192 -396.710662)
			(xy 376.313759 -396.684289) (xy 376.322842 -396.632331) (xy 376.34073 -396.58271) (xy 376.353324 -396.559532)
			(xy 376.357896 -396.551404) (xy 376.36069 -396.534132) (xy 376.34545 -396.451328) (xy 376.336306 -396.436088)
			(xy 376.329194 -396.4305) (xy 376.307022 -396.411795) (xy 376.267075 -396.369734) (xy 376.232758 -396.322965)
			(xy 376.20462 -396.272239) (xy 376.18311 -396.218366) (xy 376.168573 -396.162209) (xy 376.161243 -396.104666)
			(xy 376.160792 -396.075662) (xy 376.161387 -396.042341) (xy 376.171047 -395.976402) (xy 376.190171 -395.912563)
			(xy 376.203718 -395.882114) (xy 376.207945 -395.871642) (xy 376.207839 -395.849088) (xy 376.198114 -395.828739)
			(xy 376.189748 -395.821154) (xy 376.167491 -395.802491) (xy 376.127426 -395.760435) (xy 376.093005 -395.713647)
			(xy 376.064781 -395.66288) (xy 376.043207 -395.60895) (xy 376.028631 -395.552724) (xy 376.021286 -395.495105)
			(xy 376.020838 -395.466062) (xy 376.021295 -395.437136) (xy 376.028578 -395.379744) (xy 376.043036 -395.323728)
			(xy 376.064439 -395.26998) (xy 376.092446 -395.219359) (xy 376.126608 -395.17267) (xy 376.166383 -395.13066)
			(xy 376.188478 -395.111986) (xy 376.195453 -395.105641) (xy 376.204708 -395.089236) (xy 376.206512 -395.079982)
			(xy 376.21083 -395.048994) (xy 376.211737 -395.039757) (xy 376.207711 -395.021657) (xy 376.202956 -395.013688)
			(xy 376.186644 -394.987845) (xy 376.162743 -394.931607) (xy 376.155458 -394.901928) (xy 376.15341 -394.893762)
			(xy 376.144702 -394.879362) (xy 376.13844 -394.873734) (xy 376.115326 -394.854684) (xy 376.108434 -394.849456)
			(xy 376.092213 -394.84348) (xy 376.083576 -394.843) (xy 376.05394 -394.841978) (xy 375.995275 -394.83333)
			(xy 375.938219 -394.817181) (xy 375.883724 -394.7938) (xy 375.832705 -394.763579) (xy 375.786015 -394.727023)
			(xy 375.744436 -394.684745) (xy 375.708663 -394.637452) (xy 375.679297 -394.585936) (xy 375.656827 -394.53106)
			(xy 375.641631 -394.473741) (xy 375.633963 -394.414941) (xy 375.633488 -394.385292) (xy 375.634008 -394.354229)
			(xy 375.642424 -394.292675) (xy 375.650252 -394.26261) (xy 375.653046 -394.25245) (xy 375.650506 -394.232638)
			(xy 375.603008 -394.150342) (xy 375.587006 -394.13815) (xy 375.576846 -394.13561) (xy 375.547728 -394.127637)
			(xy 375.491761 -394.105001) (xy 375.439254 -394.075204) (xy 375.39112 -394.038763) (xy 375.348194 -393.996312)
			(xy 375.311221 -393.948586) (xy 375.280842 -393.896414) (xy 375.257585 -393.840701) (xy 375.241853 -393.782415)
			(xy 375.233919 -393.722566) (xy 375.233438 -393.69238) (xy 375.233911 -393.661458) (xy 375.242194 -393.600171)
			(xy 375.258659 -393.540559) (xy 375.283007 -393.48371) (xy 375.298462 -393.456922) (xy 375.304558 -393.44727)
			(xy 375.306844 -393.424918) (xy 375.273316 -393.329668) (xy 375.257568 -393.313666) (xy 375.2469 -393.309602)
			(xy 375.223552 -393.300371) (xy 375.179708 -393.275919) (xy 375.140062 -393.24512) (xy 375.105527 -393.208684)
			(xy 375.076895 -393.167447) (xy 375.054823 -393.122357) (xy 375.03982 -393.074449) (xy 375.03223 -393.024823)
			(xy 375.031762 -392.999722) (xy 374.493028 -392.999722) (xy 374.492499 -393.026824) (xy 374.483689 -393.080307)
			(xy 374.475502 -393.106148) (xy 374.471692 -393.11707) (xy 374.474232 -393.139422) (xy 374.52681 -393.225274)
			(xy 374.54586 -393.23772) (xy 374.557036 -393.239498) (xy 374.586355 -393.244201) (xy 374.643525 -393.260251)
			(xy 374.698139 -393.283561) (xy 374.749279 -393.31374) (xy 374.796084 -393.350282) (xy 374.837769 -393.392572)
			(xy 374.873633 -393.439898) (xy 374.903073 -393.491467) (xy 374.925595 -393.546411) (xy 374.940819 -393.603807)
			(xy 374.948491 -393.66269) (xy 374.948958 -393.69238) (xy 374.948431 -393.723443) (xy 374.940019 -393.784996)
			(xy 374.932194 -393.815062) (xy 374.9294 -393.825222) (xy 374.93194 -393.845034) (xy 374.979438 -393.92733)
			(xy 374.99544 -393.939522) (xy 375.0056 -393.942062) (xy 375.034719 -393.95003) (xy 375.090684 -393.97267)
			(xy 375.143189 -394.002469) (xy 375.191321 -394.038911) (xy 375.234246 -394.081364) (xy 375.271218 -394.12909)
			(xy 375.301597 -394.181261) (xy 375.324855 -394.236973) (xy 375.340589 -394.295258) (xy 375.348525 -394.355106)
			(xy 375.349008 -394.385292) (xy 375.348883 -394.399427) (xy 375.347101 -394.427641) (xy 375.345452 -394.44168)
			(xy 375.344692 -394.450287) (xy 375.348331 -394.467167) (xy 375.352564 -394.4747) (xy 375.368312 -394.5001)
			(xy 375.373035 -394.507153) (xy 375.386125 -394.517937) (xy 375.393966 -394.521182) (xy 375.417322 -394.53039)
			(xy 375.461165 -394.55485) (xy 375.500807 -394.585653) (xy 375.53534 -394.622093) (xy 375.563971 -394.663332)
			(xy 375.586041 -394.708425) (xy 375.601044 -394.756334) (xy 375.608636 -394.80596) (xy 375.609104 -394.831062)
			(xy 375.608678 -394.855264) (xy 375.601605 -394.903149) (xy 375.587618 -394.949488) (xy 375.567019 -394.99329)
			(xy 375.553986 -395.013688) (xy 375.549199 -395.021645) (xy 375.545164 -395.039756) (xy 375.546112 -395.048994)
			(xy 375.55043 -395.079982) (xy 375.552103 -395.089281) (xy 375.561389 -395.105722) (xy 375.568464 -395.111986)
			(xy 375.590552 -395.130668) (xy 375.630324 -395.17268) (xy 375.664486 -395.219368) (xy 375.692494 -395.269987)
			(xy 375.713901 -395.323733) (xy 375.728366 -395.379746) (xy 375.735659 -395.437136) (xy 375.736104 -395.466062)
			(xy 375.735518 -395.499384) (xy 375.725854 -395.565322) (xy 375.706727 -395.629161) (xy 375.693178 -395.65961)
			(xy 375.68893 -395.670075) (xy 375.689044 -395.692634) (xy 375.698778 -395.712985) (xy 375.707148 -395.72057)
			(xy 375.729367 -395.739276) (xy 375.769434 -395.781324) (xy 375.803859 -395.828104) (xy 375.832088 -395.878864)
			(xy 375.853668 -395.932787) (xy 375.868252 -395.989008) (xy 375.875605 -396.046621) (xy 375.876058 -396.075662)
			(xy 375.875579 -396.104667) (xy 375.868268 -396.162214) (xy 375.853747 -396.218376) (xy 375.832246 -396.272254)
			(xy 375.804113 -396.322985) (xy 375.769795 -396.369755) (xy 375.729845 -396.411815) (xy 375.707656 -396.4305)
			(xy 375.700544 -396.436088) (xy 375.6914 -396.451328) (xy 375.67616 -396.534132) (xy 375.678954 -396.551404)
			(xy 375.683526 -396.559532) (xy 375.6961 -396.582719) (xy 375.713975 -396.63234) (xy 375.723076 -396.684291)
			(xy 375.723658 -396.710662) (xy 375.723589 -396.720021) (xy 375.722446 -396.738703) (xy 375.721372 -396.748)
			(xy 375.720356 -396.75689) (xy 375.724166 -396.773654) (xy 375.768108 -396.843504) (xy 375.781824 -396.853918)
			(xy 375.790206 -396.856712) (xy 375.814228 -396.865198) (xy 375.859401 -396.888746) (xy 375.900207 -396.919242)
			(xy 375.935587 -396.955893) (xy 375.964624 -396.99775) (xy 375.986564 -397.043725) (xy 375.994168 -397.06804)
			(xy 375.995692 -397.073882) (xy 376.315986 -397.627602) (xy 376.32005 -397.63192) (xy 376.336246 -397.649622)
			(xy 376.363609 -397.689033) (xy 376.384693 -397.732131) (xy 376.399011 -397.777923) (xy 376.406236 -397.825354)
			(xy 376.406664 -397.849344) (xy 376.406223 -397.874135) (xy 376.39846 -397.923106) (xy 376.383133 -397.970259)
			(xy 376.360619 -398.014435) (xy 376.331471 -398.054545) (xy 376.296409 -398.089603) (xy 376.256294 -398.118744)
			(xy 376.212115 -398.141251) (xy 376.164959 -398.156571) (xy 376.115987 -398.164326) (xy 376.091196 -398.164812)
			(xy 376.065802 -398.164315) (xy 376.015668 -398.156184) (xy 375.967482 -398.140132) (xy 375.922488 -398.116573)
			(xy 375.881845 -398.086115) (xy 375.846602 -398.049543) (xy 375.817669 -398.007802) (xy 375.795791 -397.961967)
			(xy 375.788174 -397.937736) (xy 375.78665 -397.931894) (xy 375.466356 -397.378174) (xy 375.462292 -397.373856)
			(xy 375.446088 -397.356149) (xy 375.418664 -397.316757) (xy 375.397521 -397.273668) (xy 375.383148 -397.227873)
			(xy 375.375874 -397.180431) (xy 375.375424 -397.156432) (xy 375.375566 -397.14438) (xy 375.377472 -397.12035)
			(xy 375.379234 -397.108426) (xy 375.380504 -397.099536) (xy 375.377456 -397.082518) (xy 375.335292 -397.011652)
			(xy 375.322084 -397.000476) (xy 375.313702 -396.997428) (xy 375.291961 -396.989015) (xy 375.251102 -396.966578)
			(xy 375.21413 -396.938189) (xy 375.181906 -396.904506) (xy 375.155179 -396.866314) (xy 375.134572 -396.824502)
			(xy 375.120564 -396.780042) (xy 375.11348 -396.733969) (xy 375.113042 -396.710662) (xy 375.113602 -396.684289)
			(xy 375.122687 -396.63233) (xy 375.140578 -396.58271) (xy 375.153174 -396.559532) (xy 375.157746 -396.551404)
			(xy 375.16054 -396.534132) (xy 375.1453 -396.451328) (xy 375.136156 -396.436088) (xy 375.129044 -396.4305)
			(xy 375.106883 -396.411783) (xy 375.066933 -396.369725) (xy 375.032614 -396.322959) (xy 375.004473 -396.272235)
			(xy 374.982962 -396.218364) (xy 374.968424 -396.162208) (xy 374.961093 -396.104666) (xy 374.960642 -396.075662)
			(xy 374.961242 -396.042341) (xy 374.9709 -395.976403) (xy 374.990022 -395.912563) (xy 375.003568 -395.882114)
			(xy 375.007811 -395.871646) (xy 375.007706 -395.849087) (xy 374.997971 -395.828736) (xy 374.989598 -395.821154)
			(xy 374.967331 -395.802504) (xy 374.927269 -395.760444) (xy 374.89285 -395.713654) (xy 374.864628 -395.662884)
			(xy 374.843056 -395.608953) (xy 374.82848 -395.552725) (xy 374.821136 -395.495105) (xy 374.820688 -395.466062)
			(xy 374.821126 -395.437135) (xy 374.828411 -395.379742) (xy 374.842871 -395.323724) (xy 374.864276 -395.269976)
			(xy 374.892286 -395.219355) (xy 374.926452 -395.172667) (xy 374.966231 -395.130659) (xy 374.988328 -395.111986)
			(xy 374.995294 -395.105633) (xy 375.004556 -395.089234) (xy 375.006362 -395.079982) (xy 375.01068 -395.048994)
			(xy 375.011579 -395.039757) (xy 375.007557 -395.021658) (xy 375.002806 -395.013688) (xy 374.986498 -394.987842)
			(xy 374.962595 -394.931607) (xy 374.955308 -394.901928) (xy 374.953247 -394.893767) (xy 374.944547 -394.879365)
			(xy 374.93829 -394.873734) (xy 374.915176 -394.854684) (xy 374.908355 -394.849463) (xy 374.892255 -394.843502)
			(xy 374.88368 -394.843) (xy 374.854044 -394.841974) (xy 374.79538 -394.833327) (xy 374.738323 -394.817178)
			(xy 374.683829 -394.793798) (xy 374.63281 -394.763577) (xy 374.58612 -394.727021) (xy 374.54454 -394.684743)
			(xy 374.508768 -394.637451) (xy 374.479401 -394.585935) (xy 374.456931 -394.531059) (xy 374.441735 -394.473741)
			(xy 374.434067 -394.414941) (xy 374.433592 -394.385292) (xy 374.434112 -394.354229) (xy 374.442528 -394.292675)
			(xy 374.450356 -394.26261) (xy 374.45315 -394.25245) (xy 374.45061 -394.232638) (xy 374.403112 -394.150342)
			(xy 374.38711 -394.13815) (xy 374.37695 -394.13561) (xy 374.347833 -394.127635) (xy 374.291865 -394.104999)
			(xy 374.239359 -394.075202) (xy 374.191225 -394.038762) (xy 374.148298 -393.996311) (xy 374.111325 -393.948585)
			(xy 374.080946 -393.896413) (xy 374.057689 -393.840701) (xy 374.041957 -393.782414) (xy 374.034023 -393.722566)
			(xy 374.033542 -393.69238) (xy 374.034062 -393.661492) (xy 374.042368 -393.600276) (xy 374.058826 -393.540732)
			(xy 374.083138 -393.48394) (xy 374.098566 -393.457176) (xy 374.104408 -393.44727) (xy 374.106694 -393.424918)
			(xy 374.07342 -393.329668) (xy 374.057672 -393.313666) (xy 374.047004 -393.309602) (xy 374.023624 -393.300414)
			(xy 373.979727 -393.275996) (xy 373.94003 -393.245216) (xy 373.905449 -393.208784) (xy 373.876779 -393.167537)
			(xy 373.854681 -393.122427) (xy 373.839664 -393.074493) (xy 373.832074 -393.024838) (xy 373.831612 -392.999722)
			(xy 373.293132 -392.999722) (xy 373.292603 -393.026824) (xy 373.283793 -393.080307) (xy 373.275606 -393.106148)
			(xy 373.271796 -393.11707) (xy 373.274336 -393.139422) (xy 373.326914 -393.225274) (xy 373.345964 -393.23772)
			(xy 373.35714 -393.239498) (xy 373.386459 -393.244198) (xy 373.44363 -393.260248) (xy 373.498244 -393.283559)
			(xy 373.549383 -393.313739) (xy 373.596189 -393.350281) (xy 373.637874 -393.39257) (xy 373.673738 -393.439898)
			(xy 373.703178 -393.491466) (xy 373.725699 -393.546411) (xy 373.740923 -393.603806) (xy 373.748595 -393.66269)
			(xy 373.749062 -393.69238) (xy 373.748538 -393.723506) (xy 373.740133 -393.785188) (xy 373.732298 -393.815316)
			(xy 373.729504 -393.825476) (xy 373.732044 -393.845542) (xy 373.779288 -393.92733) (xy 373.79529 -393.939522)
			(xy 373.80545 -393.942062) (xy 373.834559 -393.950063) (xy 373.890525 -393.972697) (xy 373.943031 -394.002491)
			(xy 373.991164 -394.038929) (xy 374.034091 -394.081377) (xy 374.071065 -394.1291) (xy 374.101445 -394.181268)
			(xy 374.124704 -394.236978) (xy 374.140438 -394.295261) (xy 374.148375 -394.355107) (xy 374.148858 -394.385292)
			(xy 374.148733 -394.399427) (xy 374.146951 -394.427641) (xy 374.145302 -394.44168) (xy 374.144535 -394.450287)
			(xy 374.148178 -394.467168) (xy 374.152414 -394.4747) (xy 374.168162 -394.5001) (xy 374.172881 -394.507153)
			(xy 374.18598 -394.517926) (xy 374.193816 -394.521182) (xy 374.217194 -394.530373) (xy 374.261091 -394.554792)
			(xy 374.300786 -394.585572) (xy 374.335367 -394.622004) (xy 374.364037 -394.66325) (xy 374.386135 -394.708359)
			(xy 374.401153 -394.756292) (xy 374.408745 -394.805946) (xy 374.409208 -394.831062) (xy 374.408781 -394.855264)
			(xy 374.401708 -394.903149) (xy 374.387722 -394.949488) (xy 374.367123 -394.99329) (xy 374.35409 -395.013688)
			(xy 374.349303 -395.021646) (xy 374.345268 -395.039756) (xy 374.346216 -395.048994) (xy 374.350534 -395.079982)
			(xy 374.352206 -395.089281) (xy 374.361493 -395.105722) (xy 374.368568 -395.111986) (xy 374.390657 -395.130667)
			(xy 374.430429 -395.172679) (xy 374.46459 -395.219367) (xy 374.492598 -395.269987) (xy 374.514005 -395.323732)
			(xy 374.52847 -395.379746) (xy 374.535763 -395.437136) (xy 374.536208 -395.466062) (xy 374.535621 -395.499384)
			(xy 374.525958 -395.565322) (xy 374.506831 -395.629161) (xy 374.493282 -395.65961) (xy 374.489033 -395.670074)
			(xy 374.489147 -395.692634) (xy 374.498881 -395.712985) (xy 374.507252 -395.72057) (xy 374.529472 -395.739275)
			(xy 374.569539 -395.781323) (xy 374.603963 -395.828104) (xy 374.632192 -395.878863) (xy 374.653772 -395.932787)
			(xy 374.668356 -395.989008) (xy 374.675709 -396.046621) (xy 374.676162 -396.075662) (xy 374.675681 -396.104667)
			(xy 374.668371 -396.162214) (xy 374.653849 -396.218376) (xy 374.632349 -396.272254) (xy 374.604216 -396.322985)
			(xy 374.569899 -396.369755) (xy 374.529949 -396.411815) (xy 374.50776 -396.4305) (xy 374.500648 -396.436088)
			(xy 374.491504 -396.451328) (xy 374.476264 -396.534132) (xy 374.479058 -396.551404) (xy 374.48363 -396.559532)
			(xy 374.496204 -396.582719) (xy 374.514079 -396.63234) (xy 374.52318 -396.684291) (xy 374.523762 -396.710662)
			(xy 374.523693 -396.720021) (xy 374.52255 -396.738703) (xy 374.521476 -396.748) (xy 374.52046 -396.75689)
			(xy 374.52427 -396.773654) (xy 374.568212 -396.843504) (xy 374.581928 -396.853918) (xy 374.59031 -396.856712)
			(xy 374.614332 -396.865196) (xy 374.659505 -396.888744) (xy 374.700311 -396.91924) (xy 374.735692 -396.955892)
			(xy 374.764729 -396.997749) (xy 374.786668 -397.043725) (xy 374.794272 -397.06804) (xy 374.795796 -397.073882)
			(xy 375.11609 -397.627602) (xy 375.120154 -397.63192) (xy 375.136351 -397.649621) (xy 375.163714 -397.689032)
			(xy 375.184797 -397.73213) (xy 375.199116 -397.777923) (xy 375.20634 -397.825354) (xy 375.206768 -397.849344)
			(xy 375.206323 -397.874135) (xy 375.19856 -397.923105) (xy 375.183233 -397.970259) (xy 375.160719 -398.014434)
			(xy 375.131573 -398.054544) (xy 375.096511 -398.089601) (xy 375.056396 -398.118742) (xy 375.012218 -398.14125)
			(xy 374.965062 -398.15657) (xy 374.916091 -398.164326) (xy 374.8913 -398.164812) (xy 374.865906 -398.164312)
			(xy 374.815772 -398.156181) (xy 374.767586 -398.140129) (xy 374.722592 -398.116571) (xy 374.681949 -398.086114)
			(xy 374.646707 -398.049543) (xy 374.617773 -398.007801) (xy 374.595895 -397.961967) (xy 374.588278 -397.937736)
			(xy 374.586754 -397.931894) (xy 374.26646 -397.378174) (xy 374.262396 -397.373856) (xy 374.246192 -397.356148)
			(xy 374.218768 -397.316757) (xy 374.197625 -397.273668) (xy 374.183252 -397.227873) (xy 374.175978 -397.18043)
			(xy 374.175528 -397.156432) (xy 374.17567 -397.14438) (xy 374.177576 -397.12035) (xy 374.179338 -397.108426)
			(xy 374.180608 -397.099536) (xy 374.17756 -397.082518) (xy 374.135396 -397.011652) (xy 374.122188 -397.000476)
			(xy 374.113806 -396.997428) (xy 374.092066 -396.989013) (xy 374.051206 -396.966577) (xy 374.014234 -396.938187)
			(xy 373.98201 -396.904505) (xy 373.955284 -396.866314) (xy 373.934676 -396.824502) (xy 373.920668 -396.780042)
			(xy 373.913584 -396.733969) (xy 373.913146 -396.710662) (xy 373.913706 -396.684289) (xy 373.92279 -396.63233)
			(xy 373.940681 -396.58271) (xy 373.953278 -396.559532) (xy 373.95785 -396.551404) (xy 373.960644 -396.534132)
			(xy 373.945404 -396.451328) (xy 373.93626 -396.436088) (xy 373.929148 -396.4305) (xy 373.906967 -396.411807)
			(xy 373.867022 -396.369742) (xy 373.832707 -396.322971) (xy 373.80457 -396.272243) (xy 373.783062 -396.218368)
			(xy 373.768527 -396.16221) (xy 373.761196 -396.104666) (xy 373.760746 -396.075662) (xy 373.761345 -396.042341)
			(xy 373.771004 -395.976403) (xy 373.790126 -395.912563) (xy 373.803672 -395.882114) (xy 373.807914 -395.871646)
			(xy 373.807809 -395.849087) (xy 373.798074 -395.828736) (xy 373.789702 -395.821154) (xy 373.767435 -395.802503)
			(xy 373.727373 -395.760443) (xy 373.692954 -395.713653) (xy 373.664732 -395.662884) (xy 373.64316 -395.608952)
			(xy 373.628584 -395.552725) (xy 373.62124 -395.495105) (xy 373.620792 -395.466062) (xy 373.621229 -395.437135)
			(xy 373.628513 -395.379742) (xy 373.642974 -395.323724) (xy 373.664379 -395.269976) (xy 373.692389 -395.219354)
			(xy 373.726556 -395.172667) (xy 373.766335 -395.130659) (xy 373.788432 -395.111986) (xy 373.795399 -395.105634)
			(xy 373.80466 -395.089234) (xy 373.806466 -395.079982) (xy 373.810784 -395.048994) (xy 373.811682 -395.039757)
			(xy 373.807661 -395.021658) (xy 373.80291 -395.013688) (xy 373.786602 -394.987842) (xy 373.762699 -394.931607)
			(xy 373.755412 -394.901928) (xy 373.75335 -394.893767) (xy 373.744651 -394.879366) (xy 373.738394 -394.873734)
			(xy 373.71528 -394.854684) (xy 373.7084 -394.849438) (xy 373.69217 -394.843472) (xy 373.68353 -394.843)
			(xy 373.653892 -394.84202) (xy 373.595226 -394.833367) (xy 373.538169 -394.817212) (xy 373.483675 -394.793826)
			(xy 373.432656 -394.7636) (xy 373.385966 -394.727041) (xy 373.344387 -394.684759) (xy 373.308616 -394.637463)
			(xy 373.279249 -394.585944) (xy 373.256781 -394.531065) (xy 373.241585 -394.473745) (xy 373.233917 -394.414942)
			(xy 373.233442 -394.385292) (xy 373.233963 -394.354229) (xy 373.242379 -394.292675) (xy 373.250206 -394.26261)
			(xy 373.253 -394.25245) (xy 373.25046 -394.232638) (xy 373.202962 -394.150342) (xy 373.18696 -394.13815)
			(xy 373.1768 -394.13561) (xy 373.147706 -394.1276) (xy 373.091779 -394.104929) (xy 373.039314 -394.07511)
			(xy 372.991221 -394.038658) (xy 372.948332 -393.996205) (xy 372.91139 -393.948487) (xy 372.881035 -393.89633)
			(xy 372.857794 -393.840638) (xy 372.842069 -393.782376) (xy 372.834133 -393.722553) (xy 372.833646 -393.69238)
			(xy 372.834165 -393.661492) (xy 372.842471 -393.600276) (xy 372.85893 -393.540732) (xy 372.883242 -393.48394)
			(xy 372.89867 -393.457176) (xy 372.904512 -393.44727) (xy 372.906798 -393.424918) (xy 372.873524 -393.329668)
			(xy 372.857776 -393.313666) (xy 372.847108 -393.309602) (xy 372.823729 -393.300412) (xy 372.779832 -393.275994)
			(xy 372.740135 -393.245215) (xy 372.705553 -393.208783) (xy 372.676883 -393.167537) (xy 372.654785 -393.122427)
			(xy 372.639768 -393.074493) (xy 372.632178 -393.024838) (xy 372.631716 -392.999722) (xy 372.092982 -392.999722)
			(xy 372.09245 -393.026824) (xy 372.083642 -393.080307) (xy 372.075456 -393.106148) (xy 372.071646 -393.11707)
			(xy 372.074186 -393.139422) (xy 372.126764 -393.225274) (xy 372.145814 -393.23772) (xy 372.15699 -393.239498)
			(xy 372.186303 -393.244237) (xy 372.243473 -393.260281) (xy 372.298087 -393.283586) (xy 372.349227 -393.313761)
			(xy 372.396034 -393.350298) (xy 372.43772 -393.392584) (xy 372.473585 -393.439908) (xy 372.503026 -393.491474)
			(xy 372.525548 -393.546416) (xy 372.540773 -393.60381) (xy 372.548445 -393.662691) (xy 372.548912 -393.69238)
			(xy 372.548386 -393.723443) (xy 372.539974 -393.784997) (xy 372.532148 -393.815062) (xy 372.529354 -393.825222)
			(xy 372.531894 -393.845034) (xy 372.579392 -393.92733) (xy 372.595394 -393.939522) (xy 372.605554 -393.942062)
			(xy 372.634664 -393.95006) (xy 372.69063 -393.972695) (xy 372.743136 -394.002489) (xy 372.791269 -394.038927)
			(xy 372.834195 -394.081376) (xy 372.871169 -394.129099) (xy 372.901549 -394.181268) (xy 372.924808 -394.236977)
			(xy 372.940542 -394.295261) (xy 372.948479 -394.355107) (xy 372.948962 -394.385292) (xy 372.948837 -394.399427)
			(xy 372.947055 -394.427641) (xy 372.945406 -394.44168) (xy 372.944639 -394.450287) (xy 372.948282 -394.467168)
			(xy 372.952518 -394.4747) (xy 372.968266 -394.5001) (xy 372.972984 -394.507154) (xy 372.986084 -394.517926)
			(xy 372.99392 -394.521182) (xy 373.017299 -394.530371) (xy 373.061195 -394.55479) (xy 373.100891 -394.58557)
			(xy 373.135472 -394.622003) (xy 373.164141 -394.663249) (xy 373.186239 -394.708358) (xy 373.201257 -394.756292)
			(xy 373.208849 -394.805946) (xy 373.209312 -394.831062) (xy 373.208885 -394.855264) (xy 373.201812 -394.903148)
			(xy 373.187826 -394.949488) (xy 373.167227 -394.99329) (xy 373.154194 -395.013688) (xy 373.149408 -395.021646)
			(xy 373.145372 -395.039756) (xy 373.14632 -395.048994) (xy 373.150638 -395.079982) (xy 373.152309 -395.089281)
			(xy 373.161597 -395.105722) (xy 373.168672 -395.111986) (xy 373.190762 -395.130666) (xy 373.230533 -395.172678)
			(xy 373.264695 -395.219367) (xy 373.292702 -395.269987) (xy 373.314109 -395.323732) (xy 373.328574 -395.379746)
			(xy 373.335867 -395.437136) (xy 373.336312 -395.466062) (xy 373.335725 -395.499384) (xy 373.326062 -395.565322)
			(xy 373.306934 -395.629161) (xy 373.293386 -395.65961) (xy 373.289135 -395.670074) (xy 373.289249 -395.692634)
			(xy 373.298985 -395.712986) (xy 373.307356 -395.72057) (xy 373.329577 -395.739274) (xy 373.369643 -395.781323)
			(xy 373.404068 -395.828103) (xy 373.432296 -395.878863) (xy 373.453876 -395.932787) (xy 373.46846 -395.989007)
			(xy 373.475813 -396.046621) (xy 373.476266 -396.075662) (xy 373.475784 -396.104667) (xy 373.468473 -396.162214)
			(xy 373.453952 -396.218376) (xy 373.432452 -396.272254) (xy 373.404319 -396.322984) (xy 373.370002 -396.369754)
			(xy 373.330053 -396.411815) (xy 373.307864 -396.4305) (xy 373.300752 -396.436088) (xy 373.291608 -396.451328)
			(xy 373.276368 -396.534132) (xy 373.279162 -396.551404) (xy 373.283734 -396.559532) (xy 373.296309 -396.582719)
			(xy 373.314183 -396.63234) (xy 373.323284 -396.684291) (xy 373.323866 -396.710662) (xy 373.323797 -396.720021)
			(xy 373.322654 -396.738703) (xy 373.32158 -396.748) (xy 373.320564 -396.75689) (xy 373.324374 -396.773654)
			(xy 373.368316 -396.843504) (xy 373.382032 -396.853918) (xy 373.390414 -396.856712) (xy 373.414514 -396.865184)
			(xy 373.459805 -396.888812) (xy 373.500699 -396.919425) (xy 373.53613 -396.956223) (xy 373.565173 -396.998248)
			(xy 373.587068 -397.0444) (xy 373.59463 -397.068802) (xy 373.596154 -397.074644) (xy 373.91594 -397.627602)
			(xy 373.920004 -397.63192) (xy 373.936196 -397.649638) (xy 373.963622 -397.689026) (xy 373.984767 -397.732113)
			(xy 373.999143 -397.777905) (xy 374.00642 -397.825346) (xy 374.006872 -397.849344) (xy 374.006447 -397.874149)
			(xy 373.998676 -397.923148) (xy 373.983333 -397.970326) (xy 373.960795 -398.014522) (xy 373.931618 -398.054646)
			(xy 373.896522 -398.08971) (xy 373.856371 -398.118849) (xy 373.812154 -398.141345) (xy 373.764961 -398.156644)
			(xy 373.715956 -398.16437) (xy 373.69115 -398.164812) (xy 373.665757 -398.164268) (xy 373.615626 -398.156145)
			(xy 373.567441 -398.1401) (xy 373.522447 -398.116549) (xy 373.481803 -398.086097) (xy 373.44656 -398.049532)
			(xy 373.417625 -398.007795) (xy 373.395745 -397.961965) (xy 373.388128 -397.937736) (xy 373.386604 -397.931894)
			(xy 373.066056 -397.377412) (xy 373.061992 -397.373094) (xy 373.045896 -397.355418) (xy 373.018645 -397.316142)
			(xy 372.997632 -397.273203) (xy 372.983338 -397.227586) (xy 372.976091 -397.180334) (xy 372.975632 -397.156432)
			(xy 372.975774 -397.14438) (xy 372.97768 -397.12035) (xy 372.979442 -397.108426) (xy 372.980712 -397.099536)
			(xy 372.977664 -397.082518) (xy 372.9355 -397.011652) (xy 372.922292 -397.000476) (xy 372.91391 -396.997428)
			(xy 372.892171 -396.989011) (xy 372.851311 -396.966575) (xy 372.814339 -396.938186) (xy 372.782115 -396.904504)
			(xy 372.755388 -396.866313) (xy 372.734781 -396.824501) (xy 372.720772 -396.780042) (xy 372.713688 -396.733969)
			(xy 372.71325 -396.710662) (xy 372.713822 -396.684289) (xy 372.722904 -396.632331) (xy 372.740789 -396.582711)
			(xy 372.753382 -396.559532) (xy 372.757954 -396.551404) (xy 372.760748 -396.534132) (xy 372.745508 -396.451328)
			(xy 372.736364 -396.436088) (xy 372.729252 -396.4305) (xy 372.707071 -396.411806) (xy 372.667127 -396.369741)
			(xy 372.632811 -396.32297) (xy 372.604675 -396.272242) (xy 372.583166 -396.218368) (xy 372.568631 -396.16221)
			(xy 372.5613 -396.104666) (xy 372.56085 -396.075662) (xy 372.561449 -396.042341) (xy 372.571108 -395.976403)
			(xy 372.59023 -395.912563) (xy 372.603776 -395.882114) (xy 372.608016 -395.871646) (xy 372.607911 -395.849087)
			(xy 372.598178 -395.828736) (xy 372.589806 -395.821154) (xy 372.56754 -395.802502) (xy 372.527478 -395.760443)
			(xy 372.493059 -395.713653) (xy 372.464836 -395.662884) (xy 372.443264 -395.608952) (xy 372.428688 -395.552725)
			(xy 372.421344 -395.495105) (xy 372.420896 -395.466062) (xy 372.421331 -395.437135) (xy 372.428616 -395.379741)
			(xy 372.443076 -395.323724) (xy 372.464482 -395.269975) (xy 372.492492 -395.219354) (xy 372.526659 -395.172667)
			(xy 372.566438 -395.130659) (xy 372.588536 -395.111986) (xy 372.595504 -395.105634) (xy 372.604765 -395.089234)
			(xy 372.60657 -395.079982) (xy 372.610888 -395.048994) (xy 372.611786 -395.039757) (xy 372.607765 -395.021658)
			(xy 372.603014 -395.013688) (xy 372.586707 -394.987842) (xy 372.562803 -394.931607) (xy 372.555516 -394.901928)
			(xy 372.553453 -394.893767) (xy 372.544755 -394.879366) (xy 372.538498 -394.873734) (xy 372.515384 -394.854684)
			(xy 372.508503 -394.849439) (xy 372.492273 -394.843473) (xy 372.483634 -394.843) (xy 372.453996 -394.842016)
			(xy 372.395331 -394.833364) (xy 372.338273 -394.81721) (xy 372.283779 -394.793824) (xy 372.23276 -394.763599)
			(xy 372.18607 -394.727039) (xy 372.144492 -394.684757) (xy 372.10872 -394.637462) (xy 372.079354 -394.585943)
			(xy 372.056885 -394.531065) (xy 372.041689 -394.473744) (xy 372.034021 -394.414942) (xy 372.033546 -394.385292)
			(xy 372.034067 -394.354229) (xy 372.042483 -394.292675) (xy 372.05031 -394.26261) (xy 372.053104 -394.25245)
			(xy 372.050564 -394.232638) (xy 372.003066 -394.150342) (xy 371.987064 -394.13815) (xy 371.976904 -394.13561)
			(xy 371.947779 -394.127665) (xy 371.891811 -394.105024) (xy 371.839306 -394.075222) (xy 371.791173 -394.038778)
			(xy 371.748248 -393.996323) (xy 371.711276 -393.948594) (xy 371.680898 -393.89642) (xy 371.657642 -393.840705)
			(xy 371.64191 -393.782417) (xy 371.633977 -393.722567) (xy 371.633496 -393.69238) (xy 371.634022 -393.661492)
			(xy 371.642327 -393.600277) (xy 371.658784 -393.540733) (xy 371.683094 -393.483941) (xy 371.69852 -393.457176)
			(xy 371.704362 -393.44727) (xy 371.706648 -393.424918) (xy 371.673374 -393.329668) (xy 371.657626 -393.313666)
			(xy 371.646958 -393.309602) (xy 371.623568 -393.300439) (xy 371.579672 -393.276015) (xy 371.539977 -393.24523)
			(xy 371.505398 -393.208794) (xy 371.476729 -393.167544) (xy 371.454633 -393.122432) (xy 371.439617 -393.074495)
			(xy 371.432028 -393.024839) (xy 371.431566 -392.999722) (xy 370.893086 -392.999722) (xy 370.892554 -393.026824)
			(xy 370.883746 -393.080307) (xy 370.87556 -393.106148) (xy 370.87175 -393.11707) (xy 370.87429 -393.139422)
			(xy 370.926868 -393.225274) (xy 370.945918 -393.23772) (xy 370.957094 -393.239498) (xy 370.986407 -393.244234)
			(xy 371.043578 -393.260278) (xy 371.098192 -393.283584) (xy 371.149332 -393.313759) (xy 371.196138 -393.350297)
			(xy 371.237824 -393.392583) (xy 371.273689 -393.439907) (xy 371.30313 -393.491474) (xy 371.325652 -393.546415)
			(xy 371.340877 -393.603809) (xy 371.348549 -393.66269) (xy 371.349016 -393.69238) (xy 371.34849 -393.723443)
			(xy 371.340078 -393.784996) (xy 371.332252 -393.815062) (xy 371.329458 -393.825222) (xy 371.331998 -393.845034)
			(xy 371.379496 -393.92733) (xy 371.395498 -393.939522) (xy 371.405658 -393.942062) (xy 371.434769 -393.950058)
			(xy 371.490735 -393.972693) (xy 371.54324 -394.002488) (xy 371.591374 -394.038926) (xy 371.6343 -394.081375)
			(xy 371.671273 -394.129098) (xy 371.701653 -394.181267) (xy 371.724912 -394.236977) (xy 371.740646 -394.295261)
			(xy 371.748583 -394.355107) (xy 371.749066 -394.385292) (xy 371.748941 -394.399427) (xy 371.747159 -394.427641)
			(xy 371.74551 -394.44168) (xy 371.744756 -394.450287) (xy 371.748392 -394.467166) (xy 371.752622 -394.4747)
			(xy 371.76837 -394.5001) (xy 371.773074 -394.507167) (xy 371.786177 -394.517944) (xy 371.794024 -394.521182)
			(xy 371.817371 -394.530413) (xy 371.861214 -394.554867) (xy 371.900859 -394.585666) (xy 371.935393 -394.622103)
			(xy 371.964025 -394.663339) (xy 371.986097 -394.708429) (xy 372.001101 -394.756336) (xy 372.008693 -394.805961)
			(xy 372.009162 -394.831062) (xy 372.008743 -394.855264) (xy 372.001669 -394.90315) (xy 371.987681 -394.949489)
			(xy 371.967078 -394.993291) (xy 371.954044 -395.013688) (xy 371.949254 -395.021644) (xy 371.945222 -395.039756)
			(xy 371.94617 -395.048994) (xy 371.950488 -395.079982) (xy 371.952174 -395.089277) (xy 371.961452 -395.105719)
			(xy 371.968522 -395.111986) (xy 371.990601 -395.130678) (xy 372.030375 -395.172687) (xy 372.064539 -395.219373)
			(xy 372.092548 -395.269991) (xy 372.113957 -395.323735) (xy 372.128423 -395.379748) (xy 372.135717 -395.437137)
			(xy 372.136162 -395.466062) (xy 372.13557 -395.499383) (xy 372.125908 -395.565322) (xy 372.106783 -395.629161)
			(xy 372.093236 -395.65961) (xy 372.088969 -395.67007) (xy 372.089082 -395.692636) (xy 372.098828 -395.712989)
			(xy 372.107206 -395.72057) (xy 372.129438 -395.739261) (xy 372.169501 -395.781314) (xy 372.203923 -395.828097)
			(xy 372.23215 -395.878859) (xy 372.253728 -395.932784) (xy 372.268311 -395.989006) (xy 372.275663 -396.046621)
			(xy 372.276116 -396.075662) (xy 372.275652 -396.104668) (xy 372.268341 -396.162216) (xy 372.253818 -396.218379)
			(xy 372.232316 -396.272258) (xy 372.204179 -396.322988) (xy 372.169859 -396.369757) (xy 372.129905 -396.411816)
			(xy 372.107714 -396.4305) (xy 372.100602 -396.436088) (xy 372.091458 -396.451328) (xy 372.076218 -396.534132)
			(xy 372.079012 -396.551404) (xy 372.083584 -396.559532) (xy 372.096155 -396.582721) (xy 372.114031 -396.632341)
			(xy 372.123134 -396.684292) (xy 372.123716 -396.710662) (xy 372.123647 -396.720021) (xy 372.122504 -396.738703)
			(xy 372.12143 -396.748) (xy 372.120414 -396.75689) (xy 372.124224 -396.773654) (xy 372.168166 -396.843504)
			(xy 372.181882 -396.853918) (xy 372.190264 -396.856712) (xy 372.214297 -396.865167) (xy 372.259469 -396.888723)
			(xy 372.300273 -396.919226) (xy 372.335651 -396.955883) (xy 372.364686 -396.997744) (xy 372.386623 -397.043724)
			(xy 372.394226 -397.06804) (xy 372.39575 -397.073882) (xy 372.716044 -397.627602) (xy 372.720108 -397.63192)
			(xy 372.736301 -397.649637) (xy 372.763727 -397.689026) (xy 372.784871 -397.732113) (xy 372.799247 -397.777905)
			(xy 372.806524 -397.825346) (xy 372.806976 -397.849344) (xy 372.806547 -397.874149) (xy 372.798776 -397.923147)
			(xy 372.783433 -397.970325) (xy 372.760896 -398.014521) (xy 372.73172 -398.054645) (xy 372.696624 -398.089708)
			(xy 372.656473 -398.118847) (xy 372.612257 -398.141344) (xy 372.565064 -398.156644) (xy 372.516059 -398.164369)
			(xy 372.491254 -398.164812) (xy 372.465858 -398.164352) (xy 372.415723 -398.156214) (xy 372.367536 -398.140156)
			(xy 372.322542 -398.116592) (xy 372.2819 -398.086129) (xy 372.246658 -398.049553) (xy 372.217725 -398.007807)
			(xy 372.195848 -397.961968) (xy 372.188232 -397.937736) (xy 372.186708 -397.931894) (xy 371.866414 -397.378174)
			(xy 371.86235 -397.373856) (xy 371.84619 -397.356123) (xy 371.818822 -397.31672) (xy 371.797732 -397.27363)
			(xy 371.783404 -397.227845) (xy 371.77617 -397.180419) (xy 371.775736 -397.156432) (xy 371.775817 -397.144384)
			(xy 371.777599 -397.120355) (xy 371.779292 -397.108426) (xy 371.780562 -397.099536) (xy 371.777514 -397.082518)
			(xy 371.73535 -397.011652) (xy 371.722142 -397.000476) (xy 371.71376 -396.997428) (xy 371.69201 -396.989038)
			(xy 371.651152 -396.966596) (xy 371.614182 -396.938202) (xy 371.581959 -396.904515) (xy 371.555234 -396.866321)
			(xy 371.534629 -396.824506) (xy 371.520621 -396.780045) (xy 371.513538 -396.73397) (xy 371.5131 -396.710662)
			(xy 371.513666 -396.684289) (xy 371.522749 -396.632331) (xy 371.540637 -396.58271) (xy 371.553232 -396.559532)
			(xy 371.557804 -396.551404) (xy 371.560598 -396.534132) (xy 371.545358 -396.451328) (xy 371.536214 -396.436088)
			(xy 371.529102 -396.4305) (xy 371.506932 -396.411793) (xy 371.466985 -396.369732) (xy 371.432667 -396.322964)
			(xy 371.404528 -396.272238) (xy 371.383018 -396.218366) (xy 371.368482 -396.162209) (xy 371.361151 -396.104666)
			(xy 371.3607 -396.075662) (xy 371.361295 -396.042341) (xy 371.370954 -395.976402) (xy 371.390079 -395.912563)
			(xy 371.403626 -395.882114) (xy 371.40785 -395.871641) (xy 371.407745 -395.849089) (xy 371.398021 -395.828739)
			(xy 371.389656 -395.821154) (xy 371.367401 -395.80249) (xy 371.327336 -395.760434) (xy 371.292914 -395.713647)
			(xy 371.26469 -395.66288) (xy 371.243116 -395.60895) (xy 371.228539 -395.552723) (xy 371.221194 -395.495105)
			(xy 371.220746 -395.466062) (xy 371.2212 -395.437136) (xy 371.228483 -395.379744) (xy 371.242942 -395.323727)
			(xy 371.264345 -395.269979) (xy 371.292352 -395.219358) (xy 371.326515 -395.17267) (xy 371.366291 -395.13066)
			(xy 371.388386 -395.111986) (xy 371.395362 -395.105643) (xy 371.404617 -395.089236) (xy 371.40642 -395.079982)
			(xy 371.410738 -395.048994) (xy 371.411643 -395.039757) (xy 371.407618 -395.021657) (xy 371.402864 -395.013688)
			(xy 371.386553 -394.987844) (xy 371.362652 -394.931607) (xy 371.355366 -394.901928) (xy 371.353316 -394.893763)
			(xy 371.344609 -394.879363) (xy 371.338348 -394.873734) (xy 371.315234 -394.854684) (xy 371.308398 -394.849487)
			(xy 371.29231 -394.843511) (xy 371.283738 -394.843) (xy 371.2541 -394.842013) (xy 371.195435 -394.833361)
			(xy 371.138378 -394.817207) (xy 371.083883 -394.793822) (xy 371.032864 -394.763597) (xy 370.986175 -394.727037)
			(xy 370.944596 -394.684756) (xy 370.908824 -394.637461) (xy 370.879458 -394.585943) (xy 370.856989 -394.531064)
			(xy 370.841793 -394.473744) (xy 370.834125 -394.414942) (xy 370.83365 -394.385292) (xy 370.834171 -394.354229)
			(xy 370.842587 -394.292675) (xy 370.850414 -394.26261) (xy 370.853208 -394.25245) (xy 370.850668 -394.232638)
			(xy 370.80317 -394.150342) (xy 370.787168 -394.13815) (xy 370.777008 -394.13561) (xy 370.765287 -394.132463)
			(xy 370.742161 -394.125093) (xy 370.73078 -394.120878) (xy 370.718334 -394.116306) (xy 370.692426 -394.120116)
			(xy 370.603018 -394.188696) (xy 370.592604 -394.212826) (xy 370.593874 -394.22578) (xy 370.595398 -394.25753)
			(xy 370.59501 -394.281206) (xy 370.588279 -394.328077) (xy 370.574915 -394.373503) (xy 370.565426 -394.395198)
			(xy 370.561108 -394.404596) (xy 370.560346 -394.424662) (xy 370.592604 -394.511022) (xy 370.60632 -394.525754)
			(xy 370.615718 -394.530072) (xy 370.640079 -394.541777) (xy 370.684951 -394.5719) (xy 370.72433 -394.608915)
			(xy 370.75717 -394.651838) (xy 370.782598 -394.699527) (xy 370.799937 -394.750715) (xy 370.808726 -394.80404)
			(xy 370.809266 -394.831062) (xy 370.808846 -394.855264) (xy 370.801772 -394.903149) (xy 370.787784 -394.949489)
			(xy 370.767182 -394.993291) (xy 370.754148 -395.013688) (xy 370.749358 -395.021644) (xy 370.745326 -395.039756)
			(xy 370.746274 -395.048994) (xy 370.750592 -395.079982) (xy 370.752276 -395.089277) (xy 370.761556 -395.105719)
			(xy 370.768626 -395.111986) (xy 370.790706 -395.130677) (xy 370.83048 -395.172687) (xy 370.864643 -395.219372)
			(xy 370.892652 -395.269991) (xy 370.914061 -395.323735) (xy 370.928527 -395.379747) (xy 370.935821 -395.437137)
			(xy 370.936266 -395.466062) (xy 370.935674 -395.499383) (xy 370.926012 -395.565322) (xy 370.906887 -395.629161)
			(xy 370.89334 -395.65961) (xy 370.889072 -395.67007) (xy 370.889185 -395.692636) (xy 370.898932 -395.712989)
			(xy 370.90731 -395.72057) (xy 370.929542 -395.73926) (xy 370.969606 -395.781313) (xy 371.004028 -395.828097)
			(xy 371.032254 -395.878859) (xy 371.053832 -395.932784) (xy 371.068415 -395.989006) (xy 371.075767 -396.046621)
			(xy 371.07622 -396.075662) (xy 371.075755 -396.104667) (xy 371.068443 -396.162216) (xy 371.05392 -396.218379)
			(xy 371.032418 -396.272257) (xy 371.004282 -396.322988) (xy 370.969962 -396.369757) (xy 370.930009 -396.411816)
			(xy 370.907818 -396.4305) (xy 370.900706 -396.436088) (xy 370.891562 -396.451328) (xy 370.876322 -396.534132)
			(xy 370.879116 -396.551404) (xy 370.883688 -396.559532) (xy 370.896259 -396.582721) (xy 370.914136 -396.632341)
			(xy 370.923238 -396.684292) (xy 370.92382 -396.710662) (xy 370.923751 -396.720021) (xy 370.922608 -396.738703)
			(xy 370.921534 -396.748) (xy 370.920518 -396.75689) (xy 370.924328 -396.773654) (xy 370.96827 -396.843504)
			(xy 370.981986 -396.853918) (xy 370.990368 -396.856712) (xy 371.014382 -396.865218) (xy 371.059556 -396.888761)
			(xy 371.100364 -396.919252) (xy 371.135746 -396.9559) (xy 371.164784 -396.997753) (xy 371.186726 -397.043726)
			(xy 371.19433 -397.06804) (xy 371.195854 -397.073882) (xy 371.516148 -397.627602) (xy 371.520212 -397.63192)
			(xy 371.536406 -397.649637) (xy 371.563831 -397.689025) (xy 371.584975 -397.732113) (xy 371.599352 -397.777905)
			(xy 371.606628 -397.825346) (xy 371.60708 -397.849344) (xy 371.606647 -397.874149) (xy 371.598876 -397.923146)
			(xy 371.583533 -397.970324) (xy 371.560996 -398.014519) (xy 371.531821 -398.054643) (xy 371.496725 -398.089707)
			(xy 371.456575 -398.118846) (xy 371.412359 -398.141343) (xy 371.365168 -398.156643) (xy 371.316163 -398.164369)
			(xy 371.291358 -398.164812) (xy 371.265962 -398.164348) (xy 371.215827 -398.156211) (xy 371.167641 -398.140154)
			(xy 371.122646 -398.11659) (xy 371.082004 -398.086127) (xy 371.046762 -398.049552) (xy 371.017829 -398.007806)
			(xy 370.995952 -397.961968) (xy 370.988336 -397.937736) (xy 370.986812 -397.931894) (xy 370.666518 -397.378174)
			(xy 370.662454 -397.373856) (xy 370.646295 -397.356122) (xy 370.618926 -397.31672) (xy 370.597836 -397.27363)
			(xy 370.583508 -397.227845) (xy 370.576274 -397.180419) (xy 370.57584 -397.156432) (xy 370.575921 -397.144384)
			(xy 370.577703 -397.120355) (xy 370.579396 -397.108426) (xy 370.580666 -397.099536) (xy 370.577618 -397.082518)
			(xy 370.535454 -397.011652) (xy 370.522246 -397.000476) (xy 370.513864 -396.997428) (xy 370.492115 -396.989036)
			(xy 370.451257 -396.966594) (xy 370.414286 -396.9382) (xy 370.382064 -396.904514) (xy 370.355339 -396.86632)
			(xy 370.334733 -396.824506) (xy 370.320725 -396.780044) (xy 370.313642 -396.73397) (xy 370.313204 -396.710662)
			(xy 370.313769 -396.684289) (xy 370.322852 -396.63233) (xy 370.340741 -396.58271) (xy 370.353336 -396.559532)
			(xy 370.357908 -396.551404) (xy 370.360702 -396.534132) (xy 370.345462 -396.451328) (xy 370.336318 -396.436088)
			(xy 370.329206 -396.4305) (xy 370.307037 -396.411792) (xy 370.267089 -396.369731) (xy 370.232771 -396.322964)
			(xy 370.204632 -396.272238) (xy 370.183122 -396.218366) (xy 370.168586 -396.162209) (xy 370.161255 -396.104666)
			(xy 370.160804 -396.075662) (xy 370.161407 -396.042341) (xy 370.171065 -395.976403) (xy 370.190186 -395.912564)
			(xy 370.20373 -395.882114) (xy 370.207953 -395.871641) (xy 370.207847 -395.849089) (xy 370.198124 -395.82874)
			(xy 370.18976 -395.821154) (xy 370.167505 -395.802489) (xy 370.12744 -395.760433) (xy 370.093019 -395.713646)
			(xy 370.064794 -395.66288) (xy 370.04322 -395.60895) (xy 370.028643 -395.552723) (xy 370.021298 -395.495105)
			(xy 370.02085 -395.466062) (xy 370.021302 -395.437136) (xy 370.028586 -395.379743) (xy 370.043045 -395.323727)
			(xy 370.064448 -395.269979) (xy 370.092455 -395.219358) (xy 370.126619 -395.17267) (xy 370.166394 -395.13066)
			(xy 370.18849 -395.111986) (xy 370.195467 -395.105643) (xy 370.204721 -395.089236) (xy 370.206524 -395.079982)
			(xy 370.210842 -395.048994) (xy 370.211747 -395.039757) (xy 370.207722 -395.021657) (xy 370.202968 -395.013688)
			(xy 370.189988 -394.993261) (xy 370.169404 -394.949461) (xy 370.155414 -394.903132) (xy 370.148318 -394.855259)
			(xy 370.14785 -394.831062) (xy 370.148231 -394.807386) (xy 370.154964 -394.760515) (xy 370.168331 -394.715088)
			(xy 370.177822 -394.693394) (xy 370.18214 -394.683996) (xy 370.182902 -394.66393) (xy 370.150644 -394.57757)
			(xy 370.136928 -394.562838) (xy 370.12753 -394.55852) (xy 370.103154 -394.546845) (xy 370.058284 -394.516715)
			(xy 370.018907 -394.479694) (xy 369.98607 -394.436766) (xy 369.960645 -394.389072) (xy 369.943308 -394.337881)
			(xy 369.934521 -394.284553) (xy 369.933982 -394.25753) (xy 368.446935 -394.25753) (xy 368.417517 -394.294288)
			(xy 368.395504 -394.31595) (xy 368.386868 -394.324332) (xy 368.37874 -394.346684) (xy 368.390678 -394.451078)
			(xy 368.403632 -394.47089) (xy 368.414046 -394.47724) (xy 368.439381 -394.492755) (xy 368.486235 -394.529279)
			(xy 368.527968 -394.57156) (xy 368.563877 -394.618887) (xy 368.593358 -394.670463) (xy 368.615916 -394.725421)
			(xy 368.631172 -394.782837) (xy 368.638867 -394.841744) (xy 368.639344 -394.871448) (xy 368.638873 -394.902107)
			(xy 368.630681 -394.962875) (xy 368.61445 -395.022006) (xy 368.590471 -395.078441) (xy 368.559173 -395.13117)
			(xy 368.521116 -395.179248) (xy 368.49939 -395.200886) (xy 368.491653 -395.209199) (xy 368.483656 -395.23042)
			(xy 368.485563 -395.253017) (xy 368.490754 -395.263116) (xy 368.504888 -395.288587) (xy 368.52496 -395.343265)
			(xy 368.535123 -395.400617) (xy 368.535712 -395.42974) (xy 368.535202 -395.455727) (xy 368.527072 -395.507062)
			(xy 368.511011 -395.556492) (xy 368.487415 -395.602802) (xy 368.456865 -395.64485) (xy 368.420114 -395.681601)
			(xy 368.378066 -395.712151) (xy 368.331756 -395.735747) (xy 368.282326 -395.751808) (xy 368.230991 -395.759938)
			(xy 368.179017 -395.759938) (xy 368.127682 -395.751808) (xy 368.078252 -395.735747) (xy 368.031942 -395.712151)
			(xy 367.989894 -395.681601) (xy 367.953143 -395.64485) (xy 367.922593 -395.602802) (xy 367.898997 -395.556492)
			(xy 367.882936 -395.507062) (xy 367.874806 -395.455727) (xy 367.874296 -395.42974) (xy 367.874717 -395.405227)
			(xy 367.881901 -395.35673) (xy 367.896177 -395.309829) (xy 367.9063 -395.2875) (xy 367.910678 -395.277033)
			(xy 367.910724 -395.25437) (xy 367.900996 -395.233902) (xy 367.892584 -395.226286) (xy 367.87037 -395.207613)
			(xy 367.83036 -395.165579) (xy 367.795987 -395.118822) (xy 367.767803 -395.068094) (xy 367.746261 -395.014208)
			(xy 367.731707 -394.958031) (xy 367.724374 -394.900464) (xy 367.723928 -394.871448) (xy 367.72442 -394.840568)
			(xy 367.732738 -394.779369) (xy 367.749215 -394.719847) (xy 367.773552 -394.663083) (xy 367.805306 -394.610111)
			(xy 367.843899 -394.561893) (xy 367.865914 -394.540232) (xy 367.87455 -394.53185) (xy 367.882678 -394.509498)
			(xy 367.87074 -394.405104) (xy 367.857786 -394.385292) (xy 367.847372 -394.378942) (xy 367.823982 -394.364729)
			(xy 367.780472 -394.331521) (xy 367.74124 -394.293355) (xy 367.706846 -394.250776) (xy 367.677783 -394.204395)
			(xy 367.665762 -394.179806) (xy 367.659666 -394.167106) (xy 367.636806 -394.151612) (xy 367.519966 -394.144246)
			(xy 367.495582 -394.156692) (xy 367.487962 -394.16863) (xy 367.472878 -394.191514) (xy 367.437187 -394.233106)
			(xy 367.395911 -394.269163) (xy 367.349899 -394.298941) (xy 367.300099 -394.321828) (xy 367.247537 -394.337352)
			(xy 367.193294 -394.345194) (xy 367.16589 -394.345668) (xy 367.138636 -394.345261) (xy 367.084684 -394.337503)
			(xy 367.032385 -394.322145) (xy 366.982804 -394.299501) (xy 366.93695 -394.270032) (xy 366.895757 -394.234336)
			(xy 366.860062 -394.193142) (xy 366.830594 -394.147287) (xy 366.807951 -394.097706) (xy 366.792595 -394.045406)
			(xy 366.784838 -393.991454) (xy 358.291976 -393.991454) (xy 358.299766 -393.99718) (xy 358.325855 -394.01485)
			(xy 358.373881 -394.055641) (xy 358.416505 -394.102049) (xy 358.453073 -394.153364) (xy 358.483028 -394.208801)
			(xy 358.505909 -394.267511) (xy 358.521368 -394.328597) (xy 358.529167 -394.391124) (xy 358.529636 -394.42263)
			(xy 358.52917 -394.45336) (xy 358.521759 -394.514373) (xy 358.507048 -394.574047) (xy 358.486736 -394.6276)
			(xy 362.130076 -394.6276) (xy 362.13409 -394.563802) (xy 362.146068 -394.501011) (xy 362.165822 -394.440216)
			(xy 362.19304 -394.382375) (xy 362.227292 -394.328403) (xy 362.268038 -394.279149) (xy 362.314637 -394.23539)
			(xy 362.366353 -394.197817) (xy 362.42237 -394.167021) (xy 362.481805 -394.143489) (xy 362.54372 -394.127592)
			(xy 362.60714 -394.119581) (xy 362.639102 -394.1191) (xy 362.669798 -394.119591) (xy 362.730742 -394.126989)
			(xy 362.79035 -394.141677) (xy 362.847755 -394.163441) (xy 362.902118 -394.191964) (xy 362.927646 -394.209016)
			(xy 362.936398 -394.214487) (xy 362.956602 -394.218615) (xy 362.976806 -394.214487) (xy 362.985558 -394.209016)
			(xy 363.011082 -394.19196) (xy 363.065454 -394.163454) (xy 363.12286 -394.141695) (xy 363.182466 -394.126998)
			(xy 363.243407 -394.119579) (xy 363.274102 -394.1191) (xy 363.306063 -394.119586) (xy 363.369482 -394.127598)
			(xy 363.431397 -394.143495) (xy 363.490831 -394.167027) (xy 363.546847 -394.197822) (xy 363.598561 -394.235395)
			(xy 363.645159 -394.279154) (xy 363.685905 -394.328407) (xy 363.720157 -394.382379) (xy 363.747374 -394.440218)
			(xy 363.767127 -394.501013) (xy 363.779105 -394.563803) (xy 363.783119 -394.6276) (xy 363.779105 -394.691397)
			(xy 363.767127 -394.754187) (xy 363.747374 -394.814982) (xy 363.720157 -394.872821) (xy 363.685905 -394.926793)
			(xy 363.645159 -394.976046) (xy 363.598561 -395.019805) (xy 363.546847 -395.057378) (xy 363.490831 -395.088173)
			(xy 363.431397 -395.111705) (xy 363.369482 -395.127602) (xy 363.306063 -395.135614) (xy 363.274102 -395.136116)
			(xy 363.243405 -395.135671) (xy 363.182459 -395.128261) (xy 363.12285 -395.113562) (xy 363.065447 -395.091788)
			(xy 363.011085 -395.063256) (xy 362.985558 -395.0462) (xy 362.976806 -395.040729) (xy 362.956602 -395.036601)
			(xy 362.936398 -395.040729) (xy 362.927646 -395.0462) (xy 362.902122 -395.063257) (xy 362.84775 -395.091762)
			(xy 362.790344 -395.113521) (xy 362.730738 -395.128217) (xy 362.669797 -395.135637) (xy 362.639102 -395.136116)
			(xy 362.60714 -395.135619) (xy 362.54372 -395.127608) (xy 362.481805 -395.111711) (xy 362.42237 -395.088179)
			(xy 362.366353 -395.057383) (xy 362.314637 -395.01981) (xy 362.268038 -394.976051) (xy 362.227292 -394.926797)
			(xy 362.19304 -394.872825) (xy 362.165822 -394.814984) (xy 362.146068 -394.754189) (xy 362.13409 -394.691398)
			(xy 362.130076 -394.6276) (xy 358.486736 -394.6276) (xy 358.485252 -394.631513) (xy 358.456688 -394.685934)
			(xy 358.421773 -394.736515) (xy 358.381017 -394.782518) (xy 358.335013 -394.823275) (xy 358.284432 -394.858189)
			(xy 358.230012 -394.886752) (xy 358.172545 -394.908548) (xy 358.112871 -394.923259) (xy 358.051858 -394.93067)
			(xy 358.021128 -394.931138) (xy 357.989625 -394.930666) (xy 357.927102 -394.92288) (xy 357.866021 -394.907423)
			(xy 357.80732 -394.884534) (xy 357.751899 -394.854562) (xy 357.72598 -394.83665) (xy 357.715058 -394.82903)
			(xy 357.68915 -394.826236) (xy 357.584756 -394.870178) (xy 357.568754 -394.890752) (xy 357.566722 -394.90396)
			(xy 357.561238 -394.936301) (xy 357.543026 -394.999319) (xy 357.51686 -395.059472) (xy 357.483174 -395.115759)
			(xy 357.442529 -395.167247) (xy 357.395599 -395.213079) (xy 357.343165 -395.252494) (xy 357.286096 -395.284838)
			(xy 357.225341 -395.309574) (xy 357.161909 -395.32629) (xy 357.096855 -395.334708) (xy 357.064056 -395.335252)
			(xy 357.032649 -395.334788) (xy 356.970311 -395.327057) (xy 356.909401 -395.311706) (xy 356.850846 -395.288969)
			(xy 356.795537 -395.259192) (xy 356.744318 -395.222828) (xy 356.697968 -395.180432) (xy 356.657194 -395.132649)
			(xy 356.622617 -395.080208) (xy 356.594763 -395.023907) (xy 356.574056 -394.964603) (xy 356.560812 -394.9032)
			(xy 356.55758 -394.871956) (xy 356.556564 -394.861796) (xy 356.547928 -394.844778) (xy 356.479856 -394.785342)
			(xy 356.461568 -394.778992) (xy 356.451408 -394.7795) (xy 356.427278 -394.780008) (xy 356.395231 -394.779527)
			(xy 356.331643 -394.771482) (xy 356.26957 -394.75551) (xy 356.209996 -394.731865) (xy 356.153866 -394.70092)
			(xy 356.10207 -394.663168) (xy 356.055428 -394.619205) (xy 356.014681 -394.56973) (xy 355.980474 -394.515527)
			(xy 355.95335 -394.457454) (xy 355.933738 -394.396434) (xy 355.92195 -394.333432) (xy 355.919532 -394.301472)
			(xy 355.918516 -394.281406) (xy 355.889052 -394.25372) (xy 355.542088 -394.25372) (xy 355.531487 -394.254266)
			(xy 355.512074 -394.262796) (xy 355.504496 -394.27023) (xy 355.484162 -394.291997) (xy 355.439725 -394.331668)
			(xy 355.39144 -394.366555) (xy 355.365812 -394.381736) (xy 355.32949 -394.402818) (xy 355.321105 -394.408236)
			(xy 355.308968 -394.42406) (xy 355.305868 -394.433552) (xy 355.281738 -394.52423) (xy 355.292152 -394.553694)
			(xy 355.305106 -394.563092) (xy 355.325929 -394.578752) (xy 355.362839 -394.615523) (xy 355.393527 -394.657626)
			(xy 355.417234 -394.70402) (xy 355.433375 -394.753557) (xy 355.441549 -394.805012) (xy 355.442012 -394.831062)
			(xy 355.441532 -394.857053) (xy 355.433405 -394.908397) (xy 355.417346 -394.957837) (xy 355.393751 -395.004155)
			(xy 355.363199 -395.046212) (xy 355.326444 -395.082972) (xy 355.284391 -395.113529) (xy 355.238075 -395.13713)
			(xy 355.188638 -395.153195) (xy 355.137295 -395.161328) (xy 355.111304 -395.16177) (xy 355.085936 -395.161301)
			(xy 355.035798 -395.153536) (xy 354.987435 -395.138205) (xy 354.94198 -395.115666) (xy 354.900502 -395.086449)
			(xy 354.863974 -395.051239) (xy 354.833252 -395.010862) (xy 354.820728 -394.988796) (xy 354.815619 -394.980293)
			(xy 354.800304 -394.967716) (xy 354.781359 -394.9619) (xy 354.771452 -394.96238) (xy 354.758338 -394.963534)
			(xy 354.732039 -394.964806) (xy 354.718874 -394.96492) (xy 354.683047 -394.964384) (xy 354.611939 -394.955547)
			(xy 354.542464 -394.93801) (xy 354.47568 -394.912042) (xy 354.412608 -394.878039) (xy 354.383086 -394.857732)
			(xy 354.372926 -394.850366) (xy 354.348288 -394.847064) (xy 354.245926 -394.884148) (xy 354.229162 -394.902436)
			(xy 354.226114 -394.914628) (xy 354.218638 -394.940873) (xy 354.196303 -394.990659) (xy 354.181664 -395.013688)
			(xy 354.176907 -395.021657) (xy 354.17288 -395.039758) (xy 354.17379 -395.048994) (xy 354.178108 -395.079982)
			(xy 354.179912 -395.089235) (xy 354.18917 -395.105638) (xy 354.196142 -395.111986) (xy 354.218236 -395.130661)
			(xy 354.258009 -395.172672) (xy 354.29217 -395.21936) (xy 354.320175 -395.269982) (xy 354.341577 -395.323729)
			(xy 354.356035 -395.379745) (xy 354.363318 -395.437136) (xy 354.363782 -395.466062) (xy 358.41127 -395.466062)
			(xy 358.415341 -395.41044) (xy 358.427467 -395.356003) (xy 358.44739 -395.303912) (xy 358.474686 -395.255277)
			(xy 358.508772 -395.211134) (xy 358.548921 -395.172425) (xy 358.594279 -395.139974) (xy 358.643879 -395.114473)
			(xy 358.696663 -395.096466) (xy 358.751506 -395.086336) (xy 358.80724 -395.084299) (xy 358.862677 -395.090399)
			(xy 358.916634 -395.104505) (xy 358.967963 -395.126317) (xy 359.015569 -395.155371) (xy 359.058437 -395.191046)
			(xy 359.095654 -395.232583) (xy 359.126427 -395.279096) (xy 359.150099 -395.329593) (xy 359.166167 -395.383)
			(xy 359.174287 -395.438176) (xy 359.174796 -395.466062) (xy 359.174287 -395.493948) (xy 359.166167 -395.549124)
			(xy 359.150099 -395.602531) (xy 359.126427 -395.653028) (xy 359.095654 -395.699541) (xy 359.058437 -395.741078)
			(xy 359.015569 -395.776753) (xy 358.967963 -395.805807) (xy 358.916634 -395.827619) (xy 358.862677 -395.841725)
			(xy 358.80724 -395.847825) (xy 358.751506 -395.845788) (xy 358.696663 -395.835658) (xy 358.643879 -395.817651)
			(xy 358.594279 -395.79215) (xy 358.548921 -395.759699) (xy 358.508772 -395.72099) (xy 358.474686 -395.676847)
			(xy 358.44739 -395.628212) (xy 358.427467 -395.576121) (xy 358.415341 -395.521684) (xy 358.41127 -395.466062)
			(xy 354.363782 -395.466062) (xy 354.363178 -395.499382) (xy 354.353509 -395.565317) (xy 354.334384 -395.629153)
			(xy 354.320856 -395.65961) (xy 354.316594 -395.670079) (xy 354.316669 -395.692653) (xy 354.326423 -395.713012)
			(xy 354.334826 -395.72057) (xy 354.357073 -395.739244) (xy 354.397138 -395.7813) (xy 354.43156 -395.828086)
			(xy 354.459787 -395.87885) (xy 354.481365 -395.932778) (xy 354.495947 -395.989002) (xy 354.5033 -396.04662)
			(xy 354.503736 -396.075662) (xy 354.503285 -396.104666) (xy 354.495955 -396.16221) (xy 354.492256 -396.1765)
			(xy 360.484672 -396.1765) (xy 360.488743 -396.120878) (xy 360.500869 -396.066441) (xy 360.520792 -396.01435)
			(xy 360.548088 -395.965715) (xy 360.582174 -395.921572) (xy 360.622323 -395.882863) (xy 360.667681 -395.850412)
			(xy 360.717281 -395.824911) (xy 360.770065 -395.806904) (xy 360.824908 -395.796774) (xy 360.880642 -395.794737)
			(xy 360.936079 -395.800837) (xy 360.990036 -395.814943) (xy 361.041365 -395.836755) (xy 361.088971 -395.865809)
			(xy 361.131839 -395.901484) (xy 361.169056 -395.943021) (xy 361.199829 -395.989534) (xy 361.223501 -396.040031)
			(xy 361.239569 -396.093438) (xy 361.247689 -396.148614) (xy 361.24811 -396.171674) (xy 363.874304 -396.171674)
			(xy 363.87487 -396.136718) (xy 363.884435 -396.067464) (xy 363.903396 -396.000173) (xy 363.931395 -395.936113)
			(xy 363.967903 -395.876491) (xy 363.98962 -395.849094) (xy 363.994919 -395.842097) (xy 364.000893 -395.825604)
			(xy 364.001304 -395.816836) (xy 364.001304 -395.662912) (xy 364.000937 -395.654135) (xy 363.994955 -395.637633)
			(xy 363.98962 -395.630654) (xy 363.967935 -395.603234) (xy 363.931432 -395.543614) (xy 363.903434 -395.479559)
			(xy 363.884467 -395.412275) (xy 363.874888 -395.343027) (xy 363.874304 -395.308074) (xy 363.874732 -395.277342)
			(xy 363.882143 -395.216326) (xy 363.896855 -395.156649) (xy 363.918653 -395.09918) (xy 363.94722 -395.044758)
			(xy 363.982137 -394.994175) (xy 364.022897 -394.94817) (xy 364.068905 -394.907414) (xy 364.11949 -394.8725)
			(xy 364.173915 -394.843938) (xy 364.231385 -394.822144) (xy 364.291064 -394.807436) (xy 364.35208 -394.800029)
			(xy 364.382812 -394.799566) (xy 364.408585 -394.799879) (xy 364.459866 -394.805098) (xy 364.485174 -394.80998)
			(xy 364.495588 -394.812012) (xy 364.515654 -394.807948) (xy 364.593378 -394.754354) (xy 364.6043 -394.736828)
			(xy 364.606078 -394.726414) (xy 364.610754 -394.699854) (xy 364.626628 -394.648315) (xy 364.649605 -394.599526)
			(xy 364.679226 -394.554461) (xy 364.714901 -394.514018) (xy 364.755917 -394.479004) (xy 364.801458 -394.450119)
			(xy 364.850613 -394.427937) (xy 364.902404 -394.412901) (xy 364.955796 -394.405312) (xy 364.98276 -394.40485)
			(xy 365.010008 -394.405415) (xy 365.063951 -394.413165) (xy 365.116242 -394.428513) (xy 365.165816 -394.451147)
			(xy 365.211664 -394.480605) (xy 365.252854 -394.516288) (xy 365.288546 -394.55747) (xy 365.318014 -394.603312)
			(xy 365.340658 -394.652881) (xy 365.356017 -394.705169) (xy 365.363779 -394.75911) (xy 365.364268 -394.786358)
			(xy 365.363778 -394.813289) (xy 365.35622 -394.866619) (xy 365.341236 -394.918355) (xy 365.319122 -394.967468)
			(xy 365.290319 -395.012982) (xy 365.255399 -395.053991) (xy 365.215057 -395.08968) (xy 365.170096 -395.119339)
			(xy 365.12141 -395.142378) (xy 365.069967 -395.158338) (xy 365.01679 -395.166903) (xy 364.989872 -395.167866)
			(xy 364.979204 -395.16812) (xy 364.960408 -395.176502) (xy 364.8964 -395.245844) (xy 364.889542 -395.265402)
			(xy 364.890304 -395.275816) (xy 364.89132 -395.308074) (xy 364.890719 -395.343029) (xy 364.881161 -395.412281)
			(xy 364.862209 -395.479571) (xy 364.834218 -395.543632) (xy 364.797717 -395.603255) (xy 364.776004 -395.630654)
			(xy 364.770717 -395.637659) (xy 364.764738 -395.654146) (xy 364.76432 -395.662912) (xy 364.76432 -395.816836)
			(xy 364.76468 -395.825613) (xy 364.770668 -395.842115) (xy 364.776004 -395.849094) (xy 364.797715 -395.876495)
			(xy 364.834213 -395.93612) (xy 364.862206 -396.00018) (xy 364.881167 -396.067469) (xy 364.890739 -396.136719)
			(xy 364.89132 -396.171674) (xy 364.890871 -396.202891) (xy 364.883254 -396.26486) (xy 364.868109 -396.32543)
			(xy 364.845662 -396.383689) (xy 364.831376 -396.41145) (xy 364.826804 -396.419578) (xy 364.824518 -396.437612)
			(xy 364.843568 -396.520924) (xy 364.853474 -396.53591) (xy 364.861094 -396.541498) (xy 364.88164 -396.556926)
			(xy 364.918772 -396.592439) (xy 364.950802 -396.632614) (xy 364.977151 -396.676724) (xy 364.978412 -396.679674)
			(xy 366.90884 -396.679674) (xy 366.912911 -396.624052) (xy 366.925037 -396.569615) (xy 366.94496 -396.517524)
			(xy 366.972256 -396.468889) (xy 367.006342 -396.424746) (xy 367.046491 -396.386037) (xy 367.091849 -396.353586)
			(xy 367.141449 -396.328085) (xy 367.194233 -396.310078) (xy 367.249076 -396.299948) (xy 367.30481 -396.297911)
			(xy 367.360247 -396.304011) (xy 367.414204 -396.318117) (xy 367.465533 -396.339929) (xy 367.513139 -396.368983)
			(xy 367.556007 -396.404658) (xy 367.593224 -396.446195) (xy 367.623997 -396.492708) (xy 367.647669 -396.543205)
			(xy 367.663737 -396.596612) (xy 367.671857 -396.651788) (xy 367.672366 -396.679674) (xy 367.671919 -396.704137)
			(xy 367.874806 -396.704137) (xy 367.874806 -396.652163) (xy 367.882936 -396.600828) (xy 367.898997 -396.551398)
			(xy 367.922593 -396.505088) (xy 367.953143 -396.46304) (xy 367.989894 -396.426289) (xy 368.031942 -396.395739)
			(xy 368.078252 -396.372143) (xy 368.127682 -396.356082) (xy 368.179017 -396.347952) (xy 368.230991 -396.347952)
			(xy 368.282326 -396.356082) (xy 368.331756 -396.372143) (xy 368.378066 -396.395739) (xy 368.420114 -396.426289)
			(xy 368.456865 -396.46304) (xy 368.487415 -396.505088) (xy 368.511011 -396.551398) (xy 368.527072 -396.600828)
			(xy 368.535202 -396.652163) (xy 368.535712 -396.67815) (xy 368.535202 -396.704137) (xy 368.527072 -396.755472)
			(xy 368.511011 -396.804902) (xy 368.487415 -396.851212) (xy 368.456865 -396.89326) (xy 368.420114 -396.930011)
			(xy 368.378066 -396.960561) (xy 368.331756 -396.984157) (xy 368.282326 -397.000218) (xy 368.230991 -397.008348)
			(xy 368.179017 -397.008348) (xy 368.127682 -397.000218) (xy 368.078252 -396.984157) (xy 368.031942 -396.960561)
			(xy 367.989894 -396.930011) (xy 367.953143 -396.89326) (xy 367.922593 -396.851212) (xy 367.898997 -396.804902)
			(xy 367.882936 -396.755472) (xy 367.874806 -396.704137) (xy 367.671919 -396.704137) (xy 367.671857 -396.70756)
			(xy 367.663737 -396.762736) (xy 367.647669 -396.816143) (xy 367.623997 -396.86664) (xy 367.593224 -396.913153)
			(xy 367.556007 -396.95469) (xy 367.513139 -396.990365) (xy 367.465533 -397.019419) (xy 367.414204 -397.041231)
			(xy 367.360247 -397.055337) (xy 367.30481 -397.061437) (xy 367.249076 -397.0594) (xy 367.194233 -397.04927)
			(xy 367.141449 -397.031263) (xy 367.091849 -397.005762) (xy 367.046491 -396.973311) (xy 367.006342 -396.934602)
			(xy 366.972256 -396.890459) (xy 366.94496 -396.841824) (xy 366.925037 -396.789733) (xy 366.912911 -396.735296)
			(xy 366.90884 -396.679674) (xy 364.978412 -396.679674) (xy 364.99734 -396.723972) (xy 365.011006 -396.773502)
			(xy 365.017901 -396.824418) (xy 365.01832 -396.850108) (xy 365.017878 -396.877479) (xy 365.010057 -396.93166)
			(xy 364.994564 -396.984164) (xy 364.971716 -397.033911) (xy 364.941985 -397.079876) (xy 364.92434 -397.100806)
			(xy 364.918244 -397.107918) (xy 364.911894 -397.124936) (xy 364.911894 -397.21028) (xy 364.918244 -397.227298)
			(xy 364.92434 -397.23441) (xy 364.942004 -397.255322) (xy 364.971711 -397.301301) (xy 364.994541 -397.351054)
			(xy 365.010027 -397.403558) (xy 365.017849 -397.457738) (xy 365.01832 -397.485108) (xy 365.017834 -397.512359)
			(xy 365.010078 -397.566307) (xy 364.994723 -397.618602) (xy 364.972081 -397.668179) (xy 364.942615 -397.714029)
			(xy 364.906924 -397.75522) (xy 364.865733 -397.790911) (xy 364.819883 -397.820377) (xy 364.770306 -397.843019)
			(xy 364.718011 -397.858374) (xy 364.664063 -397.86613) (xy 364.609561 -397.86613) (xy 364.555613 -397.858374)
			(xy 364.503318 -397.843019) (xy 364.453741 -397.820377) (xy 364.407891 -397.790911) (xy 364.3667 -397.75522)
			(xy 364.331009 -397.714029) (xy 364.301543 -397.668179) (xy 364.278901 -397.618602) (xy 364.263546 -397.566307)
			(xy 364.25579 -397.512359) (xy 364.255304 -397.485108) (xy 364.255774 -397.457738) (xy 364.263591 -397.403559)
			(xy 364.279079 -397.351056) (xy 364.30192 -397.301309) (xy 364.331643 -397.255342) (xy 364.349284 -397.23441)
			(xy 364.35538 -397.227298) (xy 364.36173 -397.21028) (xy 364.36173 -397.124936) (xy 364.35538 -397.107918)
			(xy 364.349284 -397.100806) (xy 364.331632 -397.079885) (xy 364.301922 -397.033909) (xy 364.279089 -396.984158)
			(xy 364.263601 -396.931655) (xy 364.255776 -396.877478) (xy 364.255304 -396.850108) (xy 364.255591 -396.828584)
			(xy 364.260428 -396.785809) (xy 364.264956 -396.764764) (xy 364.266988 -396.75562) (xy 364.264702 -396.737586)
			(xy 364.224316 -396.662148) (xy 364.210854 -396.65021) (xy 364.201964 -396.646908) (xy 364.17344 -396.635542)
			(xy 364.119094 -396.60696) (xy 364.068587 -396.57204) (xy 364.022654 -396.531291) (xy 363.981963 -396.485307)
			(xy 363.947108 -396.434755) (xy 363.918594 -396.380374) (xy 363.896839 -396.322954) (xy 363.882158 -396.263332)
			(xy 363.874765 -396.202376) (xy 363.874304 -396.171674) (xy 361.24811 -396.171674) (xy 361.248198 -396.1765)
			(xy 361.247689 -396.204386) (xy 361.239569 -396.259562) (xy 361.223501 -396.312969) (xy 361.199829 -396.363466)
			(xy 361.169056 -396.409979) (xy 361.131839 -396.451516) (xy 361.088971 -396.487191) (xy 361.041365 -396.516245)
			(xy 360.990036 -396.538057) (xy 360.936079 -396.552163) (xy 360.880642 -396.558263) (xy 360.824908 -396.556226)
			(xy 360.770065 -396.546096) (xy 360.717281 -396.528089) (xy 360.667681 -396.502588) (xy 360.622323 -396.470137)
			(xy 360.582174 -396.431428) (xy 360.548088 -396.387285) (xy 360.520792 -396.33865) (xy 360.500869 -396.286559)
			(xy 360.488743 -396.232122) (xy 360.484672 -396.1765) (xy 354.492256 -396.1765) (xy 354.481419 -396.218368)
			(xy 354.45991 -396.272241) (xy 354.431773 -396.322969) (xy 354.397457 -396.369738) (xy 354.357512 -396.411802)
			(xy 354.335334 -396.4305) (xy 354.328222 -396.436088) (xy 354.319078 -396.451328) (xy 354.303838 -396.534132)
			(xy 354.306632 -396.551404) (xy 354.311204 -396.559532) (xy 354.323797 -396.582711) (xy 354.341684 -396.632331)
			(xy 354.348494 -396.671292) (xy 355.896672 -396.671292) (xy 355.897162 -396.641324) (xy 355.904985 -396.581902)
			(xy 355.920498 -396.524009) (xy 355.943434 -396.468636) (xy 355.973401 -396.41673) (xy 356.009888 -396.36918)
			(xy 356.052268 -396.3268) (xy 356.099818 -396.290313) (xy 356.151724 -396.260346) (xy 356.207097 -396.23741)
			(xy 356.26499 -396.221897) (xy 356.324412 -396.214074) (xy 356.384348 -396.214074) (xy 356.44377 -396.221897)
			(xy 356.501663 -396.23741) (xy 356.557036 -396.260346) (xy 356.608942 -396.290313) (xy 356.656492 -396.3268)
			(xy 356.698872 -396.36918) (xy 356.735359 -396.41673) (xy 356.765326 -396.468636) (xy 356.788262 -396.524009)
			(xy 356.803775 -396.581902) (xy 356.811598 -396.641324) (xy 356.812088 -396.671292) (xy 356.811538 -396.703117)
			(xy 356.80272 -396.766153) (xy 356.785252 -396.827359) (xy 356.759472 -396.885554) (xy 356.725877 -396.939615)
			(xy 356.705916 -396.964408) (xy 356.700074 -396.97152) (xy 356.693978 -396.989046) (xy 356.696518 -397.075152)
			(xy 356.70363 -397.09217) (xy 356.70998 -397.099028) (xy 356.722463 -397.112558) (xy 356.74548 -397.141293)
			(xy 356.755954 -397.156432) (xy 356.764082 -397.168116) (xy 356.789736 -397.180054) (xy 356.907338 -397.166846)
			(xy 356.92969 -397.149574) (xy 356.93477 -397.136366) (xy 356.94566 -397.109881) (xy 356.974138 -397.060203)
			(xy 357.009721 -397.01534) (xy 357.051609 -396.976299) (xy 357.098863 -396.943957) (xy 357.15042 -396.919042)
			(xy 357.205122 -396.902112) (xy 357.261739 -396.893549) (xy 357.29037 -396.893034) (xy 357.31774 -396.893509)
			(xy 357.371919 -396.901324) (xy 357.424422 -396.91681) (xy 357.474169 -396.93965) (xy 357.520136 -396.969373)
			(xy 357.541068 -396.987014) (xy 357.54818 -396.99311) (xy 357.565198 -396.99946) (xy 357.650542 -396.99946)
			(xy 357.66756 -396.99311) (xy 357.674672 -396.987014) (xy 357.695605 -396.969373) (xy 357.741573 -396.939649)
			(xy 357.791319 -396.916803) (xy 357.843821 -396.901307) (xy 357.897999 -396.893478) (xy 357.952741 -396.893478)
			(xy 358.006919 -396.901307) (xy 358.059421 -396.916803) (xy 358.109167 -396.939649) (xy 358.155135 -396.969373)
			(xy 358.176068 -396.987014) (xy 358.18318 -396.99311) (xy 358.200198 -396.99946) (xy 358.285542 -396.99946)
			(xy 358.30256 -396.99311) (xy 358.309672 -396.987014) (xy 358.330606 -396.969377) (xy 358.376578 -396.939664)
			(xy 358.426325 -396.916828) (xy 358.478825 -396.901336) (xy 358.533001 -396.893508) (xy 358.56037 -396.893034)
			(xy 358.587627 -396.893411) (xy 358.641587 -396.901165) (xy 358.693895 -396.91652) (xy 358.743484 -396.939164)
			(xy 358.789346 -396.968634) (xy 358.830547 -397.004332) (xy 358.866248 -397.04553) (xy 358.895722 -397.091389)
			(xy 358.918369 -397.140977) (xy 358.933728 -397.193283) (xy 358.941487 -397.247243) (xy 358.941487 -397.301757)
			(xy 358.933728 -397.355717) (xy 358.918369 -397.408023) (xy 358.895722 -397.45761) (xy 358.866248 -397.50347)
			(xy 358.830547 -397.544668) (xy 358.789346 -397.580366) (xy 358.743484 -397.609836) (xy 358.693895 -397.63248)
			(xy 358.641587 -397.647835) (xy 358.587627 -397.655589) (xy 358.56037 -397.65605) (xy 358.532999 -397.655614)
			(xy 358.478818 -397.647791) (xy 358.426314 -397.632295) (xy 358.376567 -397.609447) (xy 358.330602 -397.579715)
			(xy 358.309672 -397.56207) (xy 358.30256 -397.555974) (xy 358.285542 -397.549624) (xy 358.200198 -397.549624)
			(xy 358.18318 -397.555974) (xy 358.176068 -397.56207) (xy 358.155135 -397.579711) (xy 358.109167 -397.609435)
			(xy 358.059421 -397.632281) (xy 358.006919 -397.647777) (xy 357.952741 -397.655606) (xy 357.897999 -397.655606)
			(xy 357.843821 -397.647777) (xy 357.791319 -397.632281) (xy 357.741573 -397.609435) (xy 357.695605 -397.579711)
			(xy 357.674672 -397.56207) (xy 357.66756 -397.555974) (xy 357.650542 -397.549624) (xy 357.565198 -397.549624)
			(xy 357.54818 -397.555974) (xy 357.541068 -397.56207) (xy 357.520117 -397.579686) (xy 357.47415 -397.609402)
			(xy 357.424407 -397.632243) (xy 357.371911 -397.64774) (xy 357.317738 -397.655573) (xy 357.29037 -397.65605)
			(xy 357.261767 -397.655572) (xy 357.205203 -397.647032) (xy 357.150545 -397.630149) (xy 357.099019 -397.6053)
			(xy 357.051776 -397.573042) (xy 357.009875 -397.534096) (xy 356.991666 -397.512032) (xy 356.98303 -397.500856)
			(xy 356.95636 -397.49095) (xy 356.840028 -397.513302) (xy 356.8192 -397.532098) (xy 356.815136 -397.545814)
			(xy 356.805032 -397.577158) (xy 356.777062 -397.636777) (xy 356.740825 -397.691765) (xy 356.719378 -397.716756)
			(xy 356.713028 -397.723868) (xy 356.706424 -397.74114) (xy 356.706424 -397.827246) (xy 356.713028 -397.844518)
			(xy 356.719378 -397.85163) (xy 356.740964 -397.876859) (xy 356.777334 -397.932409) (xy 356.805298 -397.99263)
			(xy 356.824271 -398.056259) (xy 356.833853 -398.121961) (xy 356.83444 -398.15516) (xy 356.83395 -398.185128)
			(xy 356.826127 -398.24455) (xy 356.810614 -398.302443) (xy 356.787678 -398.357816) (xy 356.757711 -398.409722)
			(xy 356.721224 -398.457272) (xy 356.678844 -398.499652) (xy 356.631294 -398.536139) (xy 356.579388 -398.566106)
			(xy 356.524015 -398.589042) (xy 356.466122 -398.604555) (xy 356.4067 -398.612378) (xy 356.346764 -398.612378)
			(xy 356.287342 -398.604555) (xy 356.229449 -398.589042) (xy 356.174076 -398.566106) (xy 356.12217 -398.536139)
			(xy 356.07462 -398.499652) (xy 356.03224 -398.457272) (xy 355.995753 -398.409722) (xy 355.965786 -398.357816)
			(xy 355.94285 -398.302443) (xy 355.927337 -398.24455) (xy 355.919514 -398.185128) (xy 355.919024 -398.15516)
			(xy 355.919599 -398.121926) (xy 355.929207 -398.056156) (xy 355.948229 -397.992469) (xy 355.976265 -397.932203)
			(xy 356.012726 -397.876628) (xy 356.03434 -397.851376) (xy 356.04069 -397.844264) (xy 356.047294 -397.826992)
			(xy 356.047294 -397.740886) (xy 356.04069 -397.723614) (xy 356.03434 -397.716502) (xy 356.012772 -397.691258)
			(xy 355.976399 -397.635712) (xy 355.94843 -397.575495) (xy 355.929454 -397.511869) (xy 355.919867 -397.44617)
			(xy 355.919278 -397.412972) (xy 355.919815 -397.381147) (xy 355.928638 -397.318111) (xy 355.946109 -397.256905)
			(xy 355.971892 -397.19871) (xy 356.005489 -397.144649) (xy 356.02545 -397.119856) (xy 356.031292 -397.112744)
			(xy 356.037388 -397.095218) (xy 356.034848 -397.009112) (xy 356.027736 -396.992094) (xy 356.021386 -396.985236)
			(xy 356.001904 -396.963961) (xy 355.96791 -396.917354) (xy 355.940043 -396.866844) (xy 355.918748 -396.813231)
			(xy 355.90436 -396.757366) (xy 355.89711 -396.700136) (xy 355.896672 -396.671292) (xy 354.348494 -396.671292)
			(xy 354.350766 -396.684289) (xy 354.351336 -396.710662) (xy 354.351264 -396.72002) (xy 354.350118 -396.738702)
			(xy 354.34905 -396.748) (xy 354.348034 -396.75689) (xy 354.351844 -396.773654) (xy 354.395786 -396.843504)
			(xy 354.409502 -396.853918) (xy 354.417884 -396.856712) (xy 354.441921 -396.865164) (xy 354.487106 -396.888707)
			(xy 354.527922 -396.919203) (xy 354.563309 -396.955859) (xy 354.592349 -396.997723) (xy 354.614286 -397.043708)
			(xy 354.621846 -397.06804) (xy 354.62337 -397.073882) (xy 354.943664 -397.627602) (xy 354.947728 -397.63192)
			(xy 354.963944 -397.649619) (xy 354.991374 -397.689009) (xy 355.012519 -397.7321) (xy 355.026891 -397.777898)
			(xy 355.034157 -397.825344) (xy 355.034596 -397.849344) (xy 355.034131 -397.874147) (xy 355.026361 -397.92314)
			(xy 355.01102 -397.970314) (xy 354.988486 -398.014506) (xy 354.959313 -398.054627) (xy 354.924222 -398.089689)
			(xy 354.884076 -398.118827) (xy 354.839864 -398.141323) (xy 354.792677 -398.156624) (xy 354.743677 -398.164352)
			(xy 354.718874 -398.164812) (xy 354.693481 -398.164302) (xy 354.643352 -398.156168) (xy 354.595171 -398.140115)
			(xy 354.550181 -398.116555) (xy 354.509543 -398.086098) (xy 354.474304 -398.049528) (xy 354.445374 -398.007788)
			(xy 354.423498 -397.961956) (xy 354.415852 -397.937736) (xy 354.414328 -397.931894) (xy 354.094034 -397.378174)
			(xy 354.08997 -397.373856) (xy 354.073782 -397.356146) (xy 354.04641 -397.316743) (xy 354.025323 -397.273647)
			(xy 354.011007 -397.227854) (xy 354.003794 -397.180422) (xy 354.003356 -397.156432) (xy 354.003442 -397.144384)
			(xy 354.005225 -397.120355) (xy 354.006912 -397.108426) (xy 354.008182 -397.099536) (xy 354.005134 -397.082518)
			(xy 353.96297 -397.011652) (xy 353.949762 -397.000476) (xy 353.94138 -396.997428) (xy 353.91964 -396.989022)
			(xy 353.878795 -396.96657) (xy 353.841838 -396.93817) (xy 353.809625 -396.904484) (xy 353.782906 -396.866293)
			(xy 353.762302 -396.824486) (xy 353.748291 -396.780033) (xy 353.741198 -396.733966) (xy 353.74072 -396.710662)
			(xy 353.741302 -396.684291) (xy 353.750403 -396.63234) (xy 353.768276 -396.582718) (xy 353.780852 -396.559532)
			(xy 353.785424 -396.551404) (xy 353.788218 -396.534132) (xy 353.772978 -396.451328) (xy 353.763834 -396.436088)
			(xy 353.756722 -396.4305) (xy 353.734534 -396.411815) (xy 353.694585 -396.369754) (xy 353.66027 -396.322983)
			(xy 353.632137 -396.272253) (xy 353.610638 -396.218375) (xy 353.596117 -396.162213) (xy 353.588807 -396.104667)
			(xy 353.58832 -396.075662) (xy 353.588923 -396.042342) (xy 353.598589 -395.976406) (xy 353.617711 -395.912567)
			(xy 353.631246 -395.882114) (xy 353.635513 -395.871643) (xy 353.635447 -395.849063) (xy 353.625698 -395.828695)
			(xy 353.617276 -395.821154) (xy 353.595032 -395.802479) (xy 353.554975 -395.760421) (xy 353.52056 -395.713634)
			(xy 353.492341 -395.662868) (xy 353.470772 -395.608941) (xy 353.456198 -395.552718) (xy 353.448855 -395.495103)
			(xy 353.448366 -395.466062) (xy 353.448811 -395.437137) (xy 353.456105 -395.379748) (xy 353.470572 -395.323736)
			(xy 353.491982 -395.269993) (xy 353.519992 -395.219376) (xy 353.554157 -395.172692) (xy 353.593932 -395.130685)
			(xy 353.616006 -395.111986) (xy 353.623072 -395.105717) (xy 353.632346 -395.089275) (xy 353.63404 -395.079982)
			(xy 353.638358 -395.048994) (xy 353.639306 -395.039755) (xy 353.635276 -395.021642) (xy 353.630484 -395.013688)
			(xy 353.615498 -394.98905) (xy 353.610394 -394.980686) (xy 353.595224 -394.968313) (xy 353.576522 -394.962528)
			(xy 353.56673 -394.962888) (xy 353.518724 -394.96492) (xy 353.482922 -394.96437) (xy 353.411868 -394.955515)
			(xy 353.342446 -394.937973) (xy 353.275714 -394.912012) (xy 353.212689 -394.878027) (xy 353.18319 -394.857732)
			(xy 353.172776 -394.850366) (xy 353.148392 -394.847064) (xy 353.04603 -394.884402) (xy 353.029266 -394.90269)
			(xy 353.026218 -394.914882) (xy 353.01874 -394.941066) (xy 352.996396 -394.99072) (xy 352.981768 -395.013688)
			(xy 352.977011 -395.021657) (xy 352.972983 -395.039758) (xy 352.973894 -395.048994) (xy 352.978212 -395.079982)
			(xy 352.980017 -395.089235) (xy 352.989275 -395.105637) (xy 352.996246 -395.111986) (xy 353.01834 -395.130661)
			(xy 353.058113 -395.172672) (xy 353.092274 -395.21936) (xy 353.120278 -395.269982) (xy 353.14168 -395.323729)
			(xy 353.156138 -395.379745) (xy 353.163421 -395.437136) (xy 353.163886 -395.466062) (xy 353.163282 -395.499382)
			(xy 353.153613 -395.565317) (xy 353.134488 -395.629153) (xy 353.12096 -395.65961) (xy 353.116698 -395.670079)
			(xy 353.116773 -395.692653) (xy 353.126527 -395.713011) (xy 353.13493 -395.72057) (xy 353.157177 -395.739244)
			(xy 353.197241 -395.7813) (xy 353.231663 -395.828086) (xy 353.25989 -395.878851) (xy 353.281468 -395.932778)
			(xy 353.29605 -395.989003) (xy 353.303403 -396.04662) (xy 353.30384 -396.075662) (xy 353.303389 -396.104666)
			(xy 353.296059 -396.16221) (xy 353.281523 -396.218368) (xy 353.260015 -396.272241) (xy 353.231877 -396.322969)
			(xy 353.197562 -396.369739) (xy 353.157617 -396.411803) (xy 353.135438 -396.4305) (xy 353.128326 -396.436088)
			(xy 353.119182 -396.451328) (xy 353.103942 -396.534132) (xy 353.106736 -396.551404) (xy 353.111308 -396.559532)
			(xy 353.123901 -396.582711) (xy 353.141787 -396.632331) (xy 353.150869 -396.684289) (xy 353.15144 -396.710662)
			(xy 353.151368 -396.72002) (xy 353.150222 -396.738702) (xy 353.149154 -396.748) (xy 353.148138 -396.75689)
			(xy 353.151948 -396.773654) (xy 353.19589 -396.843504) (xy 353.209606 -396.853918) (xy 353.217988 -396.856712)
			(xy 353.242084 -396.865195) (xy 353.287372 -396.888824) (xy 353.328266 -396.919436) (xy 353.363698 -396.956232)
			(xy 353.392744 -396.998252) (xy 353.414648 -397.0444) (xy 353.422204 -397.068802) (xy 353.423728 -397.074644)
			(xy 353.743514 -397.627602) (xy 353.747578 -397.63192) (xy 353.763769 -397.649628) (xy 353.791149 -397.68903)
			(xy 353.812243 -397.732125) (xy 353.826565 -397.777918) (xy 353.833783 -397.825353) (xy 353.834192 -397.849344)
			(xy 353.833703 -397.874132) (xy 353.825942 -397.923097) (xy 353.810617 -397.970245) (xy 353.788107 -398.014416)
			(xy 353.758964 -398.054523) (xy 353.723908 -398.089577) (xy 353.683799 -398.118717) (xy 353.639627 -398.141225)
			(xy 353.592478 -398.156546) (xy 353.543512 -398.164304) (xy 353.518724 -398.164812) (xy 353.493329 -398.164306)
			(xy 353.443194 -398.156179) (xy 353.395006 -398.14013) (xy 353.35001 -398.116574) (xy 353.309365 -398.086118)
			(xy 353.27412 -398.049547) (xy 353.245184 -398.007806) (xy 353.223304 -397.961971) (xy 353.215702 -397.937736)
			(xy 353.214178 -397.931894) (xy 352.89363 -397.377412) (xy 352.889566 -397.373094) (xy 352.873487 -397.355416)
			(xy 352.846299 -397.316118) (xy 352.825341 -397.273174) (xy 352.811091 -397.227562) (xy 352.803873 -397.180325)
			(xy 352.80346 -397.156432) (xy 352.803546 -397.144384) (xy 352.805329 -397.120355) (xy 352.807016 -397.108426)
			(xy 352.808286 -397.099536) (xy 352.805238 -397.082518) (xy 352.763074 -397.011652) (xy 352.749866 -397.000476)
			(xy 352.741484 -396.997428) (xy 352.719743 -396.989023) (xy 352.678899 -396.96657) (xy 352.64194 -396.938171)
			(xy 352.609728 -396.904485) (xy 352.583008 -396.866294) (xy 352.562404 -396.824486) (xy 352.548392 -396.780033)
			(xy 352.541299 -396.733967) (xy 352.540824 -396.710662) (xy 352.541406 -396.684291) (xy 352.550507 -396.63234)
			(xy 352.568381 -396.582718) (xy 352.580956 -396.559532) (xy 352.585528 -396.551404) (xy 352.588322 -396.534132)
			(xy 352.573082 -396.451328) (xy 352.563938 -396.436088) (xy 352.556826 -396.4305) (xy 352.534638 -396.411815)
			(xy 352.494689 -396.369754) (xy 352.460373 -396.322983) (xy 352.43224 -396.272253) (xy 352.410741 -396.218375)
			(xy 352.39622 -396.162213) (xy 352.38891 -396.104667) (xy 352.388424 -396.075662) (xy 352.389027 -396.042342)
			(xy 352.398693 -395.976406) (xy 352.417815 -395.912568) (xy 352.43135 -395.882114) (xy 352.435617 -395.871643)
			(xy 352.435551 -395.849062) (xy 352.425802 -395.828694) (xy 352.41738 -395.821154) (xy 352.395136 -395.802479)
			(xy 352.355078 -395.760422) (xy 352.320663 -395.713634) (xy 352.292444 -395.662869) (xy 352.270875 -395.608941)
			(xy 352.256301 -395.552718) (xy 352.248958 -395.495103) (xy 352.24847 -395.466062) (xy 352.248915 -395.437136)
			(xy 352.256208 -395.379746) (xy 352.270672 -395.323731) (xy 352.292079 -395.269985) (xy 352.320085 -395.219365)
			(xy 352.354246 -395.172675) (xy 352.394016 -395.130661) (xy 352.41611 -395.111986) (xy 352.423176 -395.105717)
			(xy 352.432449 -395.089275) (xy 352.434144 -395.079982) (xy 352.438462 -395.048994) (xy 352.43941 -395.039755)
			(xy 352.43538 -395.021642) (xy 352.430588 -395.013688) (xy 352.415602 -394.98905) (xy 352.410498 -394.980686)
			(xy 352.395328 -394.968312) (xy 352.376626 -394.962525) (xy 352.366834 -394.962888) (xy 352.318828 -394.96492)
			(xy 352.283 -394.964387) (xy 352.211889 -394.955556) (xy 352.14241 -394.938025) (xy 352.075623 -394.912062)
			(xy 352.012546 -394.878063) (xy 351.98304 -394.857732) (xy 351.97288 -394.850366) (xy 351.948242 -394.847064)
			(xy 351.84588 -394.884148) (xy 351.829116 -394.902436) (xy 351.826068 -394.914628) (xy 351.818593 -394.940873)
			(xy 351.796262 -394.990661) (xy 351.781618 -395.013688) (xy 351.776865 -395.021658) (xy 351.772841 -395.039757)
			(xy 351.773744 -395.048994) (xy 351.778062 -395.079982) (xy 351.779865 -395.089236) (xy 351.789117 -395.105646)
			(xy 351.796096 -395.111986) (xy 351.818192 -395.130659) (xy 351.857969 -395.172669) (xy 351.892134 -395.219357)
			(xy 351.920141 -395.269978) (xy 351.941546 -395.323726) (xy 351.956005 -395.379743) (xy 351.963289 -395.437135)
			(xy 351.963736 -395.466062) (xy 351.963132 -395.499382) (xy 351.953462 -395.565316) (xy 351.934335 -395.629152)
			(xy 351.92081 -395.65961) (xy 351.916551 -395.67008) (xy 351.916626 -395.692655) (xy 351.926373 -395.713017)
			(xy 351.93478 -395.72057) (xy 351.957029 -395.739243) (xy 351.997097 -395.781297) (xy 352.031523 -395.828082)
			(xy 352.059753 -395.878847) (xy 352.081333 -395.932775) (xy 352.095918 -395.989) (xy 352.103271 -396.046619)
			(xy 352.10369 -396.075662) (xy 352.103239 -396.104666) (xy 352.095908 -396.162209) (xy 352.081371 -396.218365)
			(xy 352.059861 -396.272238) (xy 352.031722 -396.322963) (xy 351.997404 -396.36973) (xy 351.957456 -396.411791)
			(xy 351.935288 -396.4305) (xy 351.928176 -396.436088) (xy 351.919032 -396.451328) (xy 351.903792 -396.534132)
			(xy 351.906586 -396.551404) (xy 351.911158 -396.559532) (xy 351.923753 -396.58271) (xy 351.941642 -396.63233)
			(xy 351.950726 -396.684289) (xy 351.95129 -396.710662) (xy 351.951218 -396.72002) (xy 351.950072 -396.738702)
			(xy 351.949004 -396.748) (xy 351.947988 -396.75689) (xy 351.951798 -396.773654) (xy 351.99574 -396.843504)
			(xy 352.009456 -396.853918) (xy 352.017838 -396.856712) (xy 352.041872 -396.865167) (xy 352.08705 -396.888715)
			(xy 352.12786 -396.919214) (xy 352.163241 -396.955871) (xy 352.192275 -396.997735) (xy 352.214209 -397.043719)
			(xy 352.2218 -397.06804) (xy 352.223324 -397.073882) (xy 352.543618 -397.627602) (xy 352.547682 -397.63192)
			(xy 352.563873 -397.649628) (xy 352.591253 -397.68903) (xy 352.612347 -397.732125) (xy 352.626668 -397.777919)
			(xy 352.633885 -397.825353) (xy 352.634296 -397.849344) (xy 352.633807 -397.874132) (xy 352.626046 -397.923097)
			(xy 352.610721 -397.970246) (xy 352.588211 -398.014417) (xy 352.559069 -398.054524) (xy 352.524012 -398.089579)
			(xy 352.483904 -398.118719) (xy 352.439731 -398.141227) (xy 352.392582 -398.156549) (xy 352.343616 -398.164308)
			(xy 352.318828 -398.164812) (xy 352.293433 -398.164306) (xy 352.243297 -398.15618) (xy 352.195109 -398.140131)
			(xy 352.150112 -398.116575) (xy 352.109467 -398.086119) (xy 352.074221 -398.049549) (xy 352.045285 -398.007808)
			(xy 352.023405 -397.961972) (xy 352.015806 -397.937736) (xy 352.014282 -397.931894) (xy 351.693988 -397.378174)
			(xy 351.689924 -397.373856) (xy 351.673707 -397.356158) (xy 351.646276 -397.316769) (xy 351.62513 -397.273677)
			(xy 351.610759 -397.227879) (xy 351.603495 -397.180432) (xy 351.603056 -397.156432) (xy 351.603214 -397.14438)
			(xy 351.605123 -397.120352) (xy 351.606866 -397.108426) (xy 351.608136 -397.099536) (xy 351.605088 -397.082518)
			(xy 351.562924 -397.011652) (xy 351.549716 -397.000476) (xy 351.541334 -396.997428) (xy 351.519596 -396.98902)
			(xy 351.478757 -396.966564) (xy 351.441805 -396.938162) (xy 351.409597 -396.904475) (xy 351.382883 -396.866285)
			(xy 351.362282 -396.824479) (xy 351.348273 -396.780028) (xy 351.341182 -396.733965) (xy 351.340674 -396.710662)
			(xy 351.341256 -396.684292) (xy 351.350358 -396.632341) (xy 351.368235 -396.582721) (xy 351.380806 -396.559532)
			(xy 351.385378 -396.551404) (xy 351.388172 -396.534132) (xy 351.372932 -396.451328) (xy 351.363788 -396.436088)
			(xy 351.356676 -396.4305) (xy 351.334486 -396.411816) (xy 351.294533 -396.369757) (xy 351.260213 -396.322987)
			(xy 351.232077 -396.272257) (xy 351.210575 -396.218378) (xy 351.196053 -396.162215) (xy 351.188741 -396.104667)
			(xy 351.188274 -396.075662) (xy 351.188877 -396.042342) (xy 351.198542 -395.976405) (xy 351.217662 -395.912566)
			(xy 351.2312 -395.882114) (xy 351.23547 -395.871645) (xy 351.235404 -395.849064) (xy 351.225648 -395.8287)
			(xy 351.21723 -395.821154) (xy 351.194984 -395.80248) (xy 351.154922 -395.760425) (xy 351.120503 -395.713638)
			(xy 351.092281 -395.662873) (xy 351.070709 -395.608944) (xy 351.056134 -395.55272) (xy 351.048789 -395.495103)
			(xy 351.04832 -395.466062) (xy 351.048765 -395.437137) (xy 351.056059 -395.379747) (xy 351.070525 -395.323734)
			(xy 351.091933 -395.26999) (xy 351.119941 -395.219371) (xy 351.154104 -395.172684) (xy 351.193877 -395.130674)
			(xy 351.21596 -395.111986) (xy 351.223032 -395.10572) (xy 351.232314 -395.089279) (xy 351.233994 -395.079982)
			(xy 351.238312 -395.048994) (xy 351.23926 -395.039756) (xy 351.235227 -395.021644) (xy 351.230438 -395.013688)
			(xy 351.215452 -394.98905) (xy 351.210351 -394.980679) (xy 351.195182 -394.96829) (xy 351.176477 -394.962486)
			(xy 351.166684 -394.962888) (xy 351.118678 -394.96492) (xy 351.082875 -394.964373) (xy 351.011818 -394.955524)
			(xy 350.942393 -394.937988) (xy 350.875657 -394.912031) (xy 350.812627 -394.878051) (xy 350.783144 -394.857732)
			(xy 350.77273 -394.850366) (xy 350.748346 -394.847064) (xy 350.645984 -394.884402) (xy 350.62922 -394.90269)
			(xy 350.626172 -394.914882) (xy 350.618695 -394.941066) (xy 350.596355 -394.990722) (xy 350.581722 -395.013688)
			(xy 350.576969 -395.021658) (xy 350.572945 -395.039757) (xy 350.573848 -395.048994) (xy 350.578166 -395.079982)
			(xy 350.579969 -395.089236) (xy 350.589222 -395.105645) (xy 350.5962 -395.111986) (xy 350.618296 -395.130659)
			(xy 350.658072 -395.172669) (xy 350.692237 -395.219357) (xy 350.720244 -395.269978) (xy 350.741648 -395.323726)
			(xy 350.756108 -395.379743) (xy 350.763391 -395.437135) (xy 350.76384 -395.466062) (xy 350.763236 -395.499382)
			(xy 350.753566 -395.565316) (xy 350.734439 -395.629152) (xy 350.720914 -395.65961) (xy 350.716655 -395.67008)
			(xy 350.71673 -395.692655) (xy 350.726477 -395.713016) (xy 350.734884 -395.72057) (xy 350.757133 -395.739243)
			(xy 350.797201 -395.781297) (xy 350.831626 -395.828082) (xy 350.859856 -395.878847) (xy 350.881436 -395.932775)
			(xy 350.89602 -395.989001) (xy 350.903374 -396.046619) (xy 350.903794 -396.075662) (xy 350.903343 -396.104666)
			(xy 350.896012 -396.162209) (xy 350.881476 -396.218366) (xy 350.859965 -396.272238) (xy 350.831826 -396.322964)
			(xy 350.797508 -396.369731) (xy 350.757561 -396.411792) (xy 350.735392 -396.4305) (xy 350.72828 -396.436088)
			(xy 350.719136 -396.451328) (xy 350.703896 -396.534132) (xy 350.70669 -396.551404) (xy 350.711262 -396.559532)
			(xy 350.723857 -396.58271) (xy 350.741746 -396.63233) (xy 350.750829 -396.684289) (xy 350.751394 -396.710662)
			(xy 350.751322 -396.72002) (xy 350.750176 -396.738702) (xy 350.749108 -396.748) (xy 350.748092 -396.75689)
			(xy 350.751902 -396.773654) (xy 350.795844 -396.843504) (xy 350.80956 -396.853918) (xy 350.817942 -396.856712)
			(xy 350.842035 -396.865198) (xy 350.887317 -396.888832) (xy 350.928204 -396.919448) (xy 350.96363 -396.956245)
			(xy 350.992671 -396.998264) (xy 351.01457 -397.044411) (xy 351.022158 -397.068802) (xy 351.023682 -397.074644)
			(xy 351.343468 -397.627602) (xy 351.347532 -397.63192) (xy 351.363747 -397.649619) (xy 351.391177 -397.689009)
			(xy 351.412322 -397.7321) (xy 351.426694 -397.777898) (xy 351.43396 -397.825344) (xy 351.4344 -397.849344)
			(xy 351.433935 -397.874147) (xy 351.426165 -397.923141) (xy 351.410824 -397.970315) (xy 351.38829 -398.014507)
			(xy 351.359117 -398.054629) (xy 351.324026 -398.08969) (xy 351.28388 -398.118829) (xy 351.239669 -398.141326)
			(xy 351.192482 -398.156627) (xy 351.143481 -398.164356) (xy 351.118678 -398.164812) (xy 351.093285 -398.164303)
			(xy 351.043155 -398.156169) (xy 350.994974 -398.140116) (xy 350.949983 -398.116557) (xy 350.909344 -398.0861)
			(xy 350.874105 -398.049529) (xy 350.845175 -398.00779) (xy 350.823299 -397.961957) (xy 350.815656 -397.937736)
			(xy 350.814132 -397.931894) (xy 350.493584 -397.377412) (xy 350.48952 -397.373094) (xy 350.473416 -397.355425)
			(xy 350.446178 -397.316139) (xy 350.425169 -397.273199) (xy 350.410868 -397.227583) (xy 350.403602 -397.180334)
			(xy 350.40316 -397.156432) (xy 350.403318 -397.14438) (xy 350.405227 -397.120352) (xy 350.40697 -397.108426)
			(xy 350.40824 -397.099536) (xy 350.405192 -397.082518) (xy 350.363028 -397.011652) (xy 350.34982 -397.000476)
			(xy 350.341438 -396.997428) (xy 350.3197 -396.98902) (xy 350.27886 -396.966564) (xy 350.241908 -396.938163)
			(xy 350.2097 -396.904476) (xy 350.182985 -396.866286) (xy 350.162384 -396.82448) (xy 350.148375 -396.780029)
			(xy 350.141283 -396.733965) (xy 350.140778 -396.710662) (xy 350.14136 -396.684292) (xy 350.150462 -396.632341)
			(xy 350.168339 -396.582721) (xy 350.18091 -396.559532) (xy 350.185482 -396.551404) (xy 350.188276 -396.534132)
			(xy 350.173036 -396.451328) (xy 350.163892 -396.436088) (xy 350.15678 -396.4305) (xy 350.134589 -396.411816)
			(xy 350.094636 -396.369757) (xy 350.060316 -396.322988) (xy 350.03218 -396.272257) (xy 350.010678 -396.218379)
			(xy 349.996155 -396.162215) (xy 349.988844 -396.104667) (xy 349.988378 -396.075662) (xy 349.988981 -396.042342)
			(xy 349.998646 -395.976405) (xy 350.017766 -395.912566) (xy 350.031304 -395.882114) (xy 350.035573 -395.871644)
			(xy 350.035508 -395.849064) (xy 350.025752 -395.828699) (xy 350.017334 -395.821154) (xy 349.995088 -395.80248)
			(xy 349.955025 -395.760425) (xy 349.920607 -395.713638) (xy 349.892384 -395.662873) (xy 349.870812 -395.608945)
			(xy 349.856236 -395.55272) (xy 349.848892 -395.495104) (xy 349.848424 -395.466062) (xy 349.848869 -395.437137)
			(xy 349.856163 -395.379747) (xy 349.870629 -395.323734) (xy 349.892037 -395.26999) (xy 349.920046 -395.219371)
			(xy 349.954209 -395.172685) (xy 349.993982 -395.130675) (xy 350.016064 -395.111986) (xy 350.023135 -395.10572)
			(xy 350.032417 -395.089278) (xy 350.034098 -395.079982) (xy 350.038416 -395.048994) (xy 350.039364 -395.039756)
			(xy 350.035331 -395.021644) (xy 350.030542 -395.013688) (xy 350.015556 -394.98905) (xy 350.010455 -394.980679)
			(xy 349.995286 -394.968289) (xy 349.976581 -394.962483) (xy 349.966788 -394.962888) (xy 349.918782 -394.96492)
			(xy 349.882955 -394.964384) (xy 349.811847 -394.955548) (xy 349.742371 -394.938013) (xy 349.675587 -394.912045)
			(xy 349.612513 -394.878042) (xy 349.582994 -394.857732) (xy 349.572834 -394.850366) (xy 349.548196 -394.847064)
			(xy 349.445834 -394.884148) (xy 349.42907 -394.902436) (xy 349.426022 -394.914628) (xy 349.418546 -394.940873)
			(xy 349.396212 -394.990659) (xy 349.381572 -395.013688) (xy 349.376815 -395.021656) (xy 349.372787 -395.039758)
			(xy 349.373698 -395.048994) (xy 349.378016 -395.079982) (xy 349.379821 -395.089234) (xy 349.38908 -395.105637)
			(xy 349.39605 -395.111986) (xy 349.418144 -395.130661) (xy 349.457916 -395.172672) (xy 349.492077 -395.219361)
			(xy 349.520081 -395.269982) (xy 349.541483 -395.323729) (xy 349.55594 -395.379745) (xy 349.563223 -395.437136)
			(xy 349.56369 -395.466062) (xy 349.563086 -395.499382) (xy 349.553417 -395.565317) (xy 349.534292 -395.629154)
			(xy 349.520764 -395.65961) (xy 349.516502 -395.670079) (xy 349.516577 -395.692653) (xy 349.526331 -395.713011)
			(xy 349.534734 -395.72057) (xy 349.556981 -395.739244) (xy 349.597045 -395.7813) (xy 349.631466 -395.828086)
			(xy 349.659693 -395.878851) (xy 349.68127 -395.932779) (xy 349.695853 -395.989003) (xy 349.703205 -396.04662)
			(xy 349.703644 -396.075662) (xy 349.703193 -396.104666) (xy 349.695863 -396.16221) (xy 349.681327 -396.218368)
			(xy 349.659819 -396.272242) (xy 349.631682 -396.32297) (xy 349.597366 -396.36974) (xy 349.557421 -396.411804)
			(xy 349.535242 -396.4305) (xy 349.52813 -396.436088) (xy 349.518986 -396.451328) (xy 349.503746 -396.534132)
			(xy 349.50654 -396.551404) (xy 349.511112 -396.559532) (xy 349.523705 -396.582711) (xy 349.541591 -396.632331)
			(xy 349.550673 -396.684289) (xy 349.551244 -396.710662) (xy 349.551172 -396.72002) (xy 349.550026 -396.738702)
			(xy 349.548958 -396.748) (xy 349.547942 -396.75689) (xy 349.551752 -396.773654) (xy 349.595694 -396.843504)
			(xy 349.60941 -396.853918) (xy 349.617792 -396.856712) (xy 349.641829 -396.865165) (xy 349.687012 -396.888708)
			(xy 349.727827 -396.919204) (xy 349.763214 -396.955861) (xy 349.792253 -396.997725) (xy 349.81419 -397.04371)
			(xy 349.821754 -397.06804) (xy 349.823278 -397.073882) (xy 350.143572 -397.627602) (xy 350.147636 -397.63192)
			(xy 350.163851 -397.649619) (xy 350.191281 -397.689009) (xy 350.212426 -397.7321) (xy 350.226797 -397.777898)
			(xy 350.234063 -397.825344) (xy 350.234504 -397.849344) (xy 350.234039 -397.874147) (xy 350.226269 -397.923141)
			(xy 350.210928 -397.970315) (xy 350.188394 -398.014508) (xy 350.159222 -398.05463) (xy 350.12413 -398.089692)
			(xy 350.083984 -398.118831) (xy 350.039773 -398.141328) (xy 349.992586 -398.15663) (xy 349.943585 -398.164359)
			(xy 349.918782 -398.164812) (xy 349.893389 -398.164303) (xy 349.843259 -398.15617) (xy 349.795076 -398.140117)
			(xy 349.750086 -398.116558) (xy 349.709446 -398.086101) (xy 349.674206 -398.049531) (xy 349.645275 -398.007791)
			(xy 349.623399 -397.961958) (xy 349.61576 -397.937736) (xy 349.614236 -397.931894) (xy 349.293942 -397.378174)
			(xy 349.289878 -397.373856) (xy 349.27369 -397.356146) (xy 349.246317 -397.316743) (xy 349.225229 -397.273647)
			(xy 349.210913 -397.227855) (xy 349.2037 -397.180422) (xy 349.203264 -397.156432) (xy 349.20335 -397.144384)
			(xy 349.205133 -397.120355) (xy 349.20682 -397.108426) (xy 349.20809 -397.099536) (xy 349.205042 -397.082518)
			(xy 349.162878 -397.011652) (xy 349.14967 -397.000476) (xy 349.141288 -396.997428) (xy 349.119547 -396.989023)
			(xy 349.078702 -396.966571) (xy 349.041743 -396.938171) (xy 349.00953 -396.904485) (xy 348.98281 -396.866295)
			(xy 348.962205 -396.824487) (xy 348.948194 -396.780033) (xy 348.941101 -396.733967) (xy 348.940628 -396.710662)
			(xy 348.94121 -396.684291) (xy 348.950311 -396.63234) (xy 348.968185 -396.582719) (xy 348.98076 -396.559532)
			(xy 348.985332 -396.551404) (xy 348.988126 -396.534132) (xy 348.972886 -396.451328) (xy 348.963742 -396.436088)
			(xy 348.95663 -396.4305) (xy 348.934442 -396.411815) (xy 348.894492 -396.369754) (xy 348.860176 -396.322984)
			(xy 348.832043 -396.272253) (xy 348.810544 -396.218375) (xy 348.796023 -396.162213) (xy 348.788712 -396.104667)
			(xy 348.788228 -396.075662) (xy 348.788831 -396.042342) (xy 348.798497 -395.976406) (xy 348.817619 -395.912568)
			(xy 348.831154 -395.882114) (xy 348.835421 -395.871643) (xy 348.835355 -395.849062) (xy 348.825607 -395.828693)
			(xy 348.817184 -395.821154) (xy 348.79494 -395.802479) (xy 348.754882 -395.760422) (xy 348.720467 -395.713634)
			(xy 348.692247 -395.662869) (xy 348.670677 -395.608941) (xy 348.656104 -395.552718) (xy 348.64876 -395.495103)
			(xy 348.648274 -395.466062) (xy 348.648719 -395.437136) (xy 348.656012 -395.379746) (xy 348.670477 -395.323731)
			(xy 348.691883 -395.269986) (xy 348.71989 -395.219365) (xy 348.75405 -395.172676) (xy 348.793821 -395.130662)
			(xy 348.815914 -395.111986) (xy 348.82298 -395.105717) (xy 348.832252 -395.089274) (xy 348.833948 -395.079982)
			(xy 348.838266 -395.048994) (xy 348.839214 -395.039755) (xy 348.835184 -395.021642) (xy 348.830392 -395.013688)
			(xy 348.815406 -394.98905) (xy 348.810302 -394.980685) (xy 348.795133 -394.96831) (xy 348.77643 -394.962522)
			(xy 348.766638 -394.962888) (xy 348.718886 -394.96492) (xy 348.683059 -394.964385) (xy 348.61195 -394.955549)
			(xy 348.542474 -394.938014) (xy 348.47569 -394.912047) (xy 348.412616 -394.878044) (xy 348.383098 -394.857732)
			(xy 348.372938 -394.850366) (xy 348.3483 -394.847064) (xy 348.245938 -394.884148) (xy 348.229174 -394.902436)
			(xy 348.226126 -394.914628) (xy 348.21865 -394.940873) (xy 348.196316 -394.990659) (xy 348.181676 -395.013688)
			(xy 348.176926 -395.021659) (xy 348.172906 -395.039757) (xy 348.173802 -395.048994) (xy 348.17812 -395.079982)
			(xy 348.179925 -395.089234) (xy 348.189185 -395.105636) (xy 348.196154 -395.111986) (xy 348.218248 -395.130661)
			(xy 348.25802 -395.172672) (xy 348.29218 -395.219361) (xy 348.320184 -395.269983) (xy 348.341586 -395.32373)
			(xy 348.356043 -395.379745) (xy 348.363326 -395.437136) (xy 348.363794 -395.466062) (xy 348.36319 -395.499382)
			(xy 348.353521 -395.565317) (xy 348.334396 -395.629154) (xy 348.320868 -395.65961) (xy 348.316606 -395.670079)
			(xy 348.31668 -395.692653) (xy 348.326436 -395.713011) (xy 348.334838 -395.72057) (xy 348.357085 -395.739244)
			(xy 348.397148 -395.7813) (xy 348.431569 -395.828087) (xy 348.459796 -395.878851) (xy 348.481373 -395.932779)
			(xy 348.495955 -395.989003) (xy 348.503308 -396.04662) (xy 348.503748 -396.075662) (xy 348.503297 -396.104666)
			(xy 348.495967 -396.16221) (xy 348.481432 -396.218368) (xy 348.459923 -396.272242) (xy 348.431786 -396.32297)
			(xy 348.397471 -396.369741) (xy 348.357526 -396.411805) (xy 348.335346 -396.4305) (xy 348.328234 -396.436088)
			(xy 348.31909 -396.451328) (xy 348.30385 -396.534132) (xy 348.306644 -396.551404) (xy 348.311216 -396.559532)
			(xy 348.323809 -396.582711) (xy 348.341695 -396.632331) (xy 348.350776 -396.684289) (xy 348.351348 -396.710662)
			(xy 348.351276 -396.72002) (xy 348.35013 -396.738702) (xy 348.349062 -396.748) (xy 348.348046 -396.75689)
			(xy 348.351856 -396.773654) (xy 348.395798 -396.843504) (xy 348.409514 -396.853918) (xy 348.417896 -396.856712)
			(xy 348.441932 -396.865165) (xy 348.487116 -396.888709) (xy 348.52793 -396.919205) (xy 348.563316 -396.955862)
			(xy 348.592355 -396.997726) (xy 348.614291 -397.043711) (xy 348.621858 -397.06804) (xy 348.623382 -397.073882)
			(xy 348.943676 -397.627602) (xy 348.94774 -397.63192) (xy 348.963955 -397.649619) (xy 348.991384 -397.689009)
			(xy 349.012529 -397.7321) (xy 349.0269 -397.777898) (xy 349.034166 -397.825344) (xy 349.034608 -397.849344)
			(xy 349.034143 -397.874147) (xy 349.026373 -397.923141) (xy 349.011032 -397.970316) (xy 348.988498 -398.014509)
			(xy 348.959326 -398.054631) (xy 348.924234 -398.089694) (xy 348.884089 -398.118833) (xy 348.839877 -398.141331)
			(xy 348.79269 -398.156633) (xy 348.74369 -398.164363) (xy 348.718886 -398.164812) (xy 348.693493 -398.164303)
			(xy 348.643362 -398.156171) (xy 348.595179 -398.140118) (xy 348.550188 -398.11656) (xy 348.509548 -398.086103)
			(xy 348.474308 -398.049533) (xy 348.445376 -398.007793) (xy 348.4235 -397.96196) (xy 348.415864 -397.937736)
			(xy 348.41434 -397.931894) (xy 348.094046 -397.378174) (xy 348.089982 -397.373856) (xy 348.073794 -397.356146)
			(xy 348.04642 -397.316743) (xy 348.025332 -397.273648) (xy 348.011016 -397.227855) (xy 348.003803 -397.180422)
			(xy 348.003368 -397.156432) (xy 348.003454 -397.144384) (xy 348.005237 -397.120355) (xy 348.006924 -397.108426)
			(xy 348.008194 -397.099536) (xy 348.005146 -397.082518) (xy 347.962982 -397.011652) (xy 347.949774 -397.000476)
			(xy 347.941392 -396.997428) (xy 347.919651 -396.989023) (xy 347.878805 -396.966571) (xy 347.841846 -396.938172)
			(xy 347.809632 -396.904486) (xy 347.782912 -396.866295) (xy 347.762307 -396.824488) (xy 347.748295 -396.780034)
			(xy 347.741202 -396.733967) (xy 347.740732 -396.710662) (xy 347.741314 -396.684291) (xy 347.750415 -396.63234)
			(xy 347.768289 -396.582719) (xy 347.780864 -396.559532) (xy 347.785436 -396.551404) (xy 347.78823 -396.534132)
			(xy 347.77299 -396.451328) (xy 347.763846 -396.436088) (xy 347.756734 -396.4305) (xy 347.734545 -396.411815)
			(xy 347.694596 -396.369754) (xy 347.660279 -396.322984) (xy 347.632146 -396.272254) (xy 347.610647 -396.218376)
			(xy 347.596125 -396.162213) (xy 347.588815 -396.104667) (xy 347.588332 -396.075662) (xy 347.588935 -396.042342)
			(xy 347.598601 -395.976406) (xy 347.617723 -395.912568) (xy 347.631258 -395.882114) (xy 347.635525 -395.871643)
			(xy 347.635458 -395.849062) (xy 347.625711 -395.828693) (xy 347.617288 -395.821154) (xy 347.595043 -395.802479)
			(xy 347.554985 -395.760422) (xy 347.52057 -395.713635) (xy 347.49235 -395.662869) (xy 347.47078 -395.608942)
			(xy 347.456206 -395.552718) (xy 347.448863 -395.495103) (xy 347.448378 -395.466062) (xy 347.448823 -395.437136)
			(xy 347.456116 -395.379746) (xy 347.470581 -395.323732) (xy 347.491987 -395.269986) (xy 347.519994 -395.219365)
			(xy 347.554155 -395.172677) (xy 347.593926 -395.130663) (xy 347.616018 -395.111986) (xy 347.623083 -395.105716)
			(xy 347.632355 -395.089274) (xy 347.634052 -395.079982) (xy 347.63837 -395.048994) (xy 347.639318 -395.039756)
			(xy 347.635282 -395.021646) (xy 347.630496 -395.013688) (xy 347.61551 -394.98905) (xy 347.610407 -394.980685)
			(xy 347.595237 -394.968308) (xy 347.576535 -394.962519) (xy 347.566742 -394.962888) (xy 347.518736 -394.96492)
			(xy 347.482908 -394.964388) (xy 347.411797 -394.955558) (xy 347.342317 -394.938027) (xy 347.275529 -394.912065)
			(xy 347.212452 -394.878066) (xy 347.182948 -394.857732) (xy 347.172788 -394.850366) (xy 347.14815 -394.847064)
			(xy 347.045788 -394.884148) (xy 347.029024 -394.902436) (xy 347.025976 -394.914628) (xy 347.018501 -394.940873)
			(xy 346.99617 -394.990662) (xy 346.981526 -395.013688) (xy 346.976773 -395.021658) (xy 346.972748 -395.039757)
			(xy 346.973652 -395.048994) (xy 346.97797 -395.079982) (xy 346.979773 -395.089236) (xy 346.989027 -395.105644)
			(xy 346.996004 -395.111986) (xy 347.0181 -395.13066) (xy 347.057876 -395.172669) (xy 347.09204 -395.219357)
			(xy 347.120047 -395.269979) (xy 347.141451 -395.323726) (xy 347.15591 -395.379743) (xy 347.163194 -395.437136)
			(xy 347.163644 -395.466062) (xy 347.16304 -395.499382) (xy 347.15337 -395.565316) (xy 347.134243 -395.629152)
			(xy 347.120718 -395.65961) (xy 347.116458 -395.67008) (xy 347.116534 -395.692654) (xy 347.126282 -395.713016)
			(xy 347.134688 -395.72057) (xy 347.156937 -395.739243) (xy 347.197004 -395.781297) (xy 347.231429 -395.828083)
			(xy 347.259659 -395.878847) (xy 347.281239 -395.932776) (xy 347.295823 -395.989001) (xy 347.303176 -396.046619)
			(xy 347.303598 -396.075662) (xy 347.303147 -396.104666) (xy 347.295816 -396.162209) (xy 347.28128 -396.218366)
			(xy 347.25977 -396.272238) (xy 347.231631 -396.322964) (xy 347.197313 -396.369732) (xy 347.157366 -396.411793)
			(xy 347.135196 -396.4305) (xy 347.128084 -396.436088) (xy 347.11894 -396.451328) (xy 347.1037 -396.534132)
			(xy 347.106494 -396.551404) (xy 347.111066 -396.559532) (xy 347.123661 -396.58271) (xy 347.141549 -396.63233)
			(xy 347.150633 -396.684289) (xy 347.151198 -396.710662) (xy 347.151126 -396.72002) (xy 347.14998 -396.738702)
			(xy 347.148912 -396.748) (xy 347.147896 -396.75689) (xy 347.151706 -396.773654) (xy 347.195648 -396.843504)
			(xy 347.209364 -396.853918) (xy 347.217746 -396.856712) (xy 347.24178 -396.865168) (xy 347.286957 -396.888717)
			(xy 347.327766 -396.919216) (xy 347.363146 -396.955873) (xy 347.392179 -396.997737) (xy 347.414112 -397.043721)
			(xy 347.421708 -397.06804) (xy 347.423232 -397.073882) (xy 347.743526 -397.627602) (xy 347.74759 -397.63192)
			(xy 347.763781 -397.649628) (xy 347.79116 -397.68903) (xy 347.812253 -397.732125) (xy 347.826574 -397.777919)
			(xy 347.833791 -397.825353) (xy 347.834204 -397.849344) (xy 347.833715 -397.874132) (xy 347.825954 -397.923098)
			(xy 347.810629 -397.970247) (xy 347.788119 -398.014419) (xy 347.758977 -398.054526) (xy 347.72392 -398.089582)
			(xy 347.683812 -398.118723) (xy 347.63964 -398.141232) (xy 347.59249 -398.156556) (xy 347.543524 -398.164315)
			(xy 347.518736 -398.164812) (xy 347.493341 -398.164307) (xy 347.443204 -398.156181) (xy 347.395015 -398.140134)
			(xy 347.350017 -398.116578) (xy 347.30937 -398.086122) (xy 347.274124 -398.049552) (xy 347.245187 -398.007811)
			(xy 347.223306 -397.961975) (xy 347.215714 -397.937736) (xy 347.21419 -397.931894) (xy 346.893896 -397.378174)
			(xy 346.889832 -397.373856) (xy 346.873615 -397.356158) (xy 346.846183 -397.316769) (xy 346.825037 -397.273678)
			(xy 346.810665 -397.22788) (xy 346.803401 -397.180432) (xy 346.802964 -397.156432) (xy 346.803122 -397.14438)
			(xy 346.805031 -397.120352) (xy 346.806774 -397.108426) (xy 346.808044 -397.099536) (xy 346.804996 -397.082518)
			(xy 346.762832 -397.011652) (xy 346.749624 -397.000476) (xy 346.741242 -396.997428) (xy 346.719504 -396.98902)
			(xy 346.678664 -396.966565) (xy 346.641711 -396.938163) (xy 346.609502 -396.904476) (xy 346.582787 -396.866286)
			(xy 346.562186 -396.82448) (xy 346.548176 -396.780029) (xy 346.541085 -396.733965) (xy 346.540582 -396.710662)
			(xy 346.541164 -396.684292) (xy 346.550266 -396.632341) (xy 346.568143 -396.582721) (xy 346.580714 -396.559532)
			(xy 346.585286 -396.551404) (xy 346.58808 -396.534132) (xy 346.57284 -396.451328) (xy 346.563696 -396.436088)
			(xy 346.556584 -396.4305) (xy 346.534393 -396.411816) (xy 346.49444 -396.369757) (xy 346.46012 -396.322988)
			(xy 346.431983 -396.272258) (xy 346.410481 -396.218379) (xy 346.395958 -396.162216) (xy 346.388646 -396.104667)
			(xy 346.388182 -396.075662) (xy 346.388785 -396.042342) (xy 346.39845 -395.976405) (xy 346.41757 -395.912566)
			(xy 346.431108 -395.882114) (xy 346.435378 -395.871644) (xy 346.435312 -395.849064) (xy 346.425557 -395.828698)
			(xy 346.417138 -395.821154) (xy 346.394891 -395.80248) (xy 346.354829 -395.760425) (xy 346.32041 -395.713639)
			(xy 346.292187 -395.662873) (xy 346.270614 -395.608945) (xy 346.256039 -395.55272) (xy 346.248694 -395.495104)
			(xy 346.248228 -395.466062) (xy 346.248673 -395.437137) (xy 346.255967 -395.379747) (xy 346.270433 -395.323734)
			(xy 346.291841 -395.26999) (xy 346.31985 -395.219372) (xy 346.354013 -395.172686) (xy 346.393787 -395.130676)
			(xy 346.415868 -395.111986) (xy 346.422939 -395.10572) (xy 346.432219 -395.089278) (xy 346.433902 -395.079982)
			(xy 346.43822 -395.048994) (xy 346.439168 -395.039756) (xy 346.435135 -395.021644) (xy 346.430346 -395.013688)
			(xy 346.41536 -394.98905) (xy 346.410259 -394.980678) (xy 346.395091 -394.968287) (xy 346.376385 -394.96248)
			(xy 346.366592 -394.962888) (xy 346.31884 -394.96492) (xy 346.283011 -394.964388) (xy 346.211901 -394.955558)
			(xy 346.142421 -394.938029) (xy 346.075632 -394.912066) (xy 346.012555 -394.878068) (xy 345.983052 -394.857732)
			(xy 345.972892 -394.850366) (xy 345.948254 -394.847064) (xy 345.845892 -394.884148) (xy 345.829128 -394.902436)
			(xy 345.82608 -394.914628) (xy 345.818605 -394.940873) (xy 345.796275 -394.990662) (xy 345.78163 -395.013688)
			(xy 345.776876 -395.021657) (xy 345.772852 -395.039757) (xy 345.773756 -395.048994) (xy 345.778074 -395.079982)
			(xy 345.779877 -395.089236) (xy 345.789131 -395.105644) (xy 345.796108 -395.111986) (xy 345.818204 -395.13066)
			(xy 345.857979 -395.17267) (xy 345.892143 -395.219357) (xy 345.92015 -395.269979) (xy 345.941554 -395.323727)
			(xy 345.956013 -395.379743) (xy 345.963297 -395.437136) (xy 345.963748 -395.466062) (xy 345.963144 -395.499382)
			(xy 345.953474 -395.565316) (xy 345.934348 -395.629152) (xy 345.920822 -395.65961) (xy 345.916562 -395.67008)
			(xy 345.916637 -395.692654) (xy 345.926386 -395.713016) (xy 345.934792 -395.72057) (xy 345.957041 -395.739243)
			(xy 345.997108 -395.781297) (xy 346.031533 -395.828083) (xy 346.059762 -395.878848) (xy 346.081342 -395.932776)
			(xy 346.095925 -395.989001) (xy 346.103279 -396.046619) (xy 346.103702 -396.075662) (xy 346.103251 -396.104666)
			(xy 346.095921 -396.162209) (xy 346.081384 -396.218366) (xy 346.059874 -396.272239) (xy 346.031735 -396.322965)
			(xy 345.997418 -396.369733) (xy 345.957471 -396.411794) (xy 345.9353 -396.4305) (xy 345.928188 -396.436088)
			(xy 345.919044 -396.451328) (xy 345.903804 -396.534132) (xy 345.906598 -396.551404) (xy 345.91117 -396.559532)
			(xy 345.923765 -396.58271) (xy 345.941653 -396.632331) (xy 345.950736 -396.684289) (xy 345.951302 -396.710662)
			(xy 345.95123 -396.72002) (xy 345.950084 -396.738702) (xy 345.949016 -396.748) (xy 345.948 -396.75689)
			(xy 345.95181 -396.773654) (xy 345.995752 -396.843504) (xy 346.009468 -396.853918) (xy 346.01785 -396.856712)
			(xy 346.041884 -396.865168) (xy 346.08706 -396.888717) (xy 346.127868 -396.919217) (xy 346.163248 -396.955874)
			(xy 346.192281 -396.997738) (xy 346.214214 -397.043722) (xy 346.221812 -397.06804) (xy 346.223336 -397.073882)
			(xy 346.54363 -397.627602) (xy 346.547694 -397.63192) (xy 346.563885 -397.649628) (xy 346.591263 -397.689031)
			(xy 346.612356 -397.732126) (xy 346.626677 -397.777919) (xy 346.633894 -397.825353) (xy 346.634308 -397.849344)
			(xy 346.633819 -397.874132) (xy 346.626058 -397.923098) (xy 346.610733 -397.970248) (xy 346.588223 -398.01442)
			(xy 346.559081 -398.054528) (xy 346.524025 -398.089584) (xy 346.483917 -398.118725) (xy 346.439744 -398.141235)
			(xy 346.392594 -398.156559) (xy 346.343629 -398.164319) (xy 346.31884 -398.164812) (xy 346.293444 -398.164307)
			(xy 346.243307 -398.156182) (xy 346.195118 -398.140135) (xy 346.150119 -398.11658) (xy 346.109472 -398.086124)
			(xy 346.074225 -398.049554) (xy 346.045288 -398.007812) (xy 346.023406 -397.961976) (xy 346.015818 -397.937736)
			(xy 346.014294 -397.931894) (xy 345.694 -397.378174) (xy 345.689936 -397.373856) (xy 345.673719 -397.356158)
			(xy 345.646286 -397.316769) (xy 345.62514 -397.273678) (xy 345.610768 -397.22788) (xy 345.603504 -397.180432)
			(xy 345.603068 -397.156432) (xy 345.603226 -397.14438) (xy 345.605135 -397.120352) (xy 345.606878 -397.108426)
			(xy 345.608148 -397.099536) (xy 345.6051 -397.082518) (xy 345.562936 -397.011652) (xy 345.549728 -397.000476)
			(xy 345.541346 -396.997428) (xy 345.519608 -396.989021) (xy 345.478767 -396.966565) (xy 345.441813 -396.938164)
			(xy 345.409605 -396.904477) (xy 345.382889 -396.866287) (xy 345.362287 -396.824481) (xy 345.348278 -396.780029)
			(xy 345.341186 -396.733965) (xy 345.340686 -396.710662) (xy 345.341268 -396.684292) (xy 345.350371 -396.632341)
			(xy 345.368248 -396.582721) (xy 345.380818 -396.559532) (xy 345.38539 -396.551404) (xy 345.388184 -396.534132)
			(xy 345.372944 -396.451328) (xy 345.3638 -396.436088) (xy 345.356688 -396.4305) (xy 345.334497 -396.411816)
			(xy 345.294543 -396.369758) (xy 345.260223 -396.322988) (xy 345.232086 -396.272258) (xy 345.210584 -396.218379)
			(xy 345.19606 -396.162216) (xy 345.188749 -396.104668) (xy 345.188286 -396.075662) (xy 345.188889 -396.042342)
			(xy 345.198554 -395.976405) (xy 345.217675 -395.912567) (xy 345.231212 -395.882114) (xy 345.235481 -395.871644)
			(xy 345.235415 -395.849064) (xy 345.225661 -395.828698) (xy 345.217242 -395.821154) (xy 345.194999 -395.802478)
			(xy 345.154945 -395.760419) (xy 345.120533 -395.713631) (xy 345.092316 -395.662866) (xy 345.070749 -395.608939)
			(xy 345.056176 -395.552716) (xy 345.048834 -395.495102) (xy 345.048332 -395.466062) (xy 345.048777 -395.437137)
			(xy 345.056071 -395.379747) (xy 345.070537 -395.323734) (xy 345.091945 -395.26999) (xy 345.119954 -395.219372)
			(xy 345.154118 -395.172686) (xy 345.193891 -395.130677) (xy 345.215972 -395.111986) (xy 345.223042 -395.105719)
			(xy 345.232322 -395.089278) (xy 345.234006 -395.079982) (xy 345.238324 -395.048994) (xy 345.239272 -395.039756)
			(xy 345.235239 -395.021644) (xy 345.23045 -395.013688) (xy 345.215464 -394.98905) (xy 345.210363 -394.980678)
			(xy 345.195195 -394.968285) (xy 345.176489 -394.962477) (xy 345.166696 -394.962888) (xy 345.11869 -394.96492)
			(xy 345.082887 -394.964374) (xy 345.011829 -394.955526) (xy 344.942403 -394.937991) (xy 344.875666 -394.912036)
			(xy 344.812636 -394.878056) (xy 344.783156 -394.857732) (xy 344.772742 -394.850366) (xy 344.748358 -394.847064)
			(xy 344.645996 -394.884402) (xy 344.629232 -394.90269) (xy 344.626184 -394.914882) (xy 344.618705 -394.941065)
			(xy 344.596359 -394.990718) (xy 344.581734 -395.013688) (xy 344.57698 -395.021657) (xy 344.572955 -395.039757)
			(xy 344.57386 -395.048994) (xy 344.578178 -395.079982) (xy 344.579981 -395.089236) (xy 344.589236 -395.105643)
			(xy 344.596212 -395.111986) (xy 344.618308 -395.13066) (xy 344.658083 -395.17267) (xy 344.692246 -395.219358)
			(xy 344.720253 -395.269979) (xy 344.741657 -395.323727) (xy 344.756116 -395.379743) (xy 344.763399 -395.437136)
			(xy 344.763852 -395.466062) (xy 344.763248 -395.499382) (xy 344.753578 -395.565316) (xy 344.734452 -395.629153)
			(xy 344.720926 -395.65961) (xy 344.716666 -395.67008) (xy 344.716741 -395.692654) (xy 344.72649 -395.713015)
			(xy 344.734896 -395.72057) (xy 344.757145 -395.739243) (xy 344.797211 -395.781298) (xy 344.831636 -395.828083)
			(xy 344.859865 -395.878848) (xy 344.881444 -395.932776) (xy 344.896028 -395.989001) (xy 344.903381 -396.046619)
			(xy 344.903806 -396.075662) (xy 344.903355 -396.104666) (xy 344.896025 -396.162209) (xy 344.881488 -396.218366)
			(xy 344.859978 -396.272239) (xy 344.83184 -396.322965) (xy 344.797522 -396.369733) (xy 344.757575 -396.411795)
			(xy 344.735404 -396.4305) (xy 344.728292 -396.436088) (xy 344.719148 -396.451328) (xy 344.703908 -396.534132)
			(xy 344.706702 -396.551404) (xy 344.711274 -396.559532) (xy 344.723869 -396.58271) (xy 344.741757 -396.632331)
			(xy 344.75084 -396.684289) (xy 344.751406 -396.710662) (xy 344.751334 -396.72002) (xy 344.750188 -396.738702)
			(xy 344.74912 -396.748) (xy 344.748104 -396.75689) (xy 344.751914 -396.773654) (xy 344.795856 -396.843504)
			(xy 344.809572 -396.853918) (xy 344.817954 -396.856712) (xy 344.842052 -396.865193) (xy 344.887344 -396.888819)
			(xy 344.928242 -396.919429) (xy 344.963678 -396.956224) (xy 344.992728 -396.998244) (xy 345.014634 -397.044393)
			(xy 345.02217 -397.068802) (xy 345.023694 -397.074644) (xy 345.34348 -397.627602) (xy 345.347544 -397.63192)
			(xy 345.363763 -397.649617) (xy 345.391201 -397.689004) (xy 345.412352 -397.732095) (xy 345.426728 -397.777894)
			(xy 345.433996 -397.825343) (xy 345.434412 -397.849344) (xy 345.433947 -397.874147) (xy 345.426177 -397.923142)
			(xy 345.410836 -397.970317) (xy 345.388302 -398.01451) (xy 345.35913 -398.054632) (xy 345.324039 -398.089695)
			(xy 345.283893 -398.118835) (xy 345.239682 -398.141334) (xy 345.192494 -398.156636) (xy 345.143494 -398.164367)
			(xy 345.11869 -398.164812) (xy 345.093297 -398.164303) (xy 345.043165 -398.156172) (xy 344.994982 -398.14012)
			(xy 344.94999 -398.116561) (xy 344.90935 -398.086104) (xy 344.874109 -398.049534) (xy 344.845177 -398.007794)
			(xy 344.8233 -397.961961) (xy 344.815668 -397.937736) (xy 344.814144 -397.931894) (xy 344.493596 -397.377412)
			(xy 344.489532 -397.373094) (xy 344.473428 -397.355425) (xy 344.446189 -397.31614) (xy 344.425179 -397.273199)
			(xy 344.410877 -397.227584) (xy 344.403611 -397.180334) (xy 344.403172 -397.156432) (xy 344.40333 -397.14438)
			(xy 344.405239 -397.120352) (xy 344.406982 -397.108426) (xy 344.408252 -397.099536) (xy 344.405204 -397.082518)
			(xy 344.36304 -397.011652) (xy 344.349832 -397.000476) (xy 344.34145 -396.997428) (xy 344.319711 -396.989021)
			(xy 344.27887 -396.966566) (xy 344.241916 -396.938165) (xy 344.209707 -396.904478) (xy 344.182991 -396.866288)
			(xy 344.162389 -396.824481) (xy 344.148379 -396.78003) (xy 344.141287 -396.733965) (xy 344.14079 -396.710662)
			(xy 344.141372 -396.684292) (xy 344.150475 -396.632341) (xy 344.168352 -396.582721) (xy 344.180922 -396.559532)
			(xy 344.185494 -396.551404) (xy 344.188288 -396.534132) (xy 344.173048 -396.451328) (xy 344.163904 -396.436088)
			(xy 344.156792 -396.4305) (xy 344.134601 -396.411816) (xy 344.094647 -396.369758) (xy 344.060326 -396.322989)
			(xy 344.032189 -396.272258) (xy 344.010686 -396.218379) (xy 343.996163 -396.162216) (xy 343.988851 -396.104668)
			(xy 343.98839 -396.075662) (xy 343.988993 -396.042342) (xy 343.998658 -395.976405) (xy 344.017779 -395.912567)
			(xy 344.031316 -395.882114) (xy 344.035585 -395.871644) (xy 344.035519 -395.849063) (xy 344.025766 -395.828698)
			(xy 344.017346 -395.821154) (xy 343.995103 -395.802478) (xy 343.955048 -395.760419) (xy 343.920636 -395.713631)
			(xy 343.892419 -395.662866) (xy 343.870851 -395.608939) (xy 343.856279 -395.552716) (xy 343.848936 -395.495102)
			(xy 343.848436 -395.466062) (xy 343.848881 -395.437137) (xy 343.856175 -395.379747) (xy 343.870641 -395.323735)
			(xy 343.89205 -395.269991) (xy 343.920059 -395.219373) (xy 343.954223 -395.172687) (xy 343.993996 -395.130678)
			(xy 344.016076 -395.111986) (xy 344.023146 -395.105719) (xy 344.032425 -395.089277) (xy 344.03411 -395.079982)
			(xy 344.038428 -395.048994) (xy 344.039376 -395.039756) (xy 344.035344 -395.021644) (xy 344.030554 -395.013688)
			(xy 344.015568 -394.98905) (xy 344.010467 -394.980677) (xy 343.995299 -394.968283) (xy 343.976593 -394.962473)
			(xy 343.9668 -394.962888) (xy 343.918794 -394.96492) (xy 343.882966 -394.964385) (xy 343.811858 -394.95555)
			(xy 343.742381 -394.938016) (xy 343.675596 -394.91205) (xy 343.612522 -394.878048) (xy 343.583006 -394.857732)
			(xy 343.572846 -394.850366) (xy 343.548208 -394.847064) (xy 343.445846 -394.884148) (xy 343.429082 -394.902436)
			(xy 343.426034 -394.914628) (xy 343.418558 -394.940873) (xy 343.396225 -394.99066) (xy 343.381584 -395.013688)
			(xy 343.376834 -395.021658) (xy 343.372813 -395.039757) (xy 343.37371 -395.048994) (xy 343.378028 -395.079982)
			(xy 343.379833 -395.089234) (xy 343.389094 -395.105635) (xy 343.396062 -395.111986) (xy 343.41816 -395.130658)
			(xy 343.457939 -395.172667) (xy 343.492106 -395.219354) (xy 343.520116 -395.269975) (xy 343.541522 -395.323724)
			(xy 343.555983 -395.379741) (xy 343.563267 -395.437135) (xy 343.563702 -395.466062) (xy 343.563098 -395.499382)
			(xy 343.553429 -395.565317) (xy 343.534305 -395.629154) (xy 343.520776 -395.65961) (xy 343.516513 -395.670079)
			(xy 343.516588 -395.692653) (xy 343.526344 -395.71301) (xy 343.534746 -395.72057) (xy 343.556992 -395.739245)
			(xy 343.597055 -395.781301) (xy 343.631476 -395.828087) (xy 343.659701 -395.878852) (xy 343.681279 -395.932779)
			(xy 343.69586 -395.989003) (xy 343.703213 -396.04662) (xy 343.703656 -396.075662) (xy 343.703206 -396.104666)
			(xy 343.695875 -396.16221) (xy 343.68134 -396.218369) (xy 343.659832 -396.272243) (xy 343.631695 -396.322971)
			(xy 343.59738 -396.369742) (xy 343.557436 -396.411807) (xy 343.535254 -396.4305) (xy 343.528142 -396.436088)
			(xy 343.518998 -396.451328) (xy 343.503758 -396.534132) (xy 343.506552 -396.551404) (xy 343.511124 -396.559532)
			(xy 343.52372 -396.58271) (xy 343.541612 -396.63233) (xy 343.550696 -396.684289) (xy 343.551256 -396.710662)
			(xy 343.551184 -396.72002) (xy 343.550038 -396.738702) (xy 343.54897 -396.748) (xy 343.547954 -396.75689)
			(xy 343.551764 -396.773654) (xy 343.595706 -396.843504) (xy 343.609422 -396.853918) (xy 343.617804 -396.856712)
			(xy 343.64184 -396.865165) (xy 343.687022 -396.88871) (xy 343.727836 -396.919207) (xy 343.763221 -396.955863)
			(xy 343.792258 -396.997728) (xy 343.814195 -397.043712) (xy 343.821766 -397.06804) (xy 343.82329 -397.073882)
			(xy 344.143584 -397.627602) (xy 344.147648 -397.63192) (xy 344.163867 -397.649617) (xy 344.191304 -397.689005)
			(xy 344.212455 -397.732096) (xy 344.226831 -397.777894) (xy 344.234099 -397.825343) (xy 344.234516 -397.849344)
			(xy 344.234051 -397.874147) (xy 344.226281 -397.923142) (xy 344.21094 -397.970317) (xy 344.188406 -398.014511)
			(xy 344.159234 -398.054633) (xy 344.124143 -398.089697) (xy 344.083997 -398.118837) (xy 344.039786 -398.141336)
			(xy 343.992599 -398.15664) (xy 343.943598 -398.16437) (xy 343.918794 -398.164812) (xy 343.893401 -398.164304)
			(xy 343.843269 -398.156173) (xy 343.795085 -398.140121) (xy 343.750092 -398.116563) (xy 343.709451 -398.086106)
			(xy 343.67421 -398.049536) (xy 343.645278 -398.007796) (xy 343.623401 -397.961962) (xy 343.615772 -397.937736)
			(xy 343.614248 -397.931894) (xy 343.293954 -397.378174) (xy 343.28989 -397.373856) (xy 343.273701 -397.356147)
			(xy 343.246327 -397.316744) (xy 343.225239 -397.273648) (xy 343.210922 -397.227855) (xy 343.203709 -397.180422)
			(xy 343.203276 -397.156432) (xy 343.203362 -397.144384) (xy 343.205145 -397.120355) (xy 343.206832 -397.108426)
			(xy 343.208102 -397.099536) (xy 343.205054 -397.082518) (xy 343.16289 -397.011652) (xy 343.149682 -397.000476)
			(xy 343.1413 -396.997428) (xy 343.119559 -396.989024) (xy 343.078712 -396.966572) (xy 343.041752 -396.938174)
			(xy 343.009537 -396.904488) (xy 342.982816 -396.866297) (xy 342.962211 -396.824489) (xy 342.948198 -396.780035)
			(xy 342.941105 -396.733967) (xy 342.94064 -396.710662) (xy 342.941222 -396.684291) (xy 342.950323 -396.63234)
			(xy 342.968198 -396.582719) (xy 342.980772 -396.559532) (xy 342.985344 -396.551404) (xy 342.988138 -396.534132)
			(xy 342.972898 -396.451328) (xy 342.963754 -396.436088) (xy 342.956642 -396.4305) (xy 342.934453 -396.411815)
			(xy 342.894503 -396.369755) (xy 342.860186 -396.322985) (xy 342.832052 -396.272254) (xy 342.810552 -396.218376)
			(xy 342.79603 -396.162214) (xy 342.78872 -396.104667) (xy 342.78824 -396.075662) (xy 342.788843 -396.042342)
			(xy 342.798509 -395.976406) (xy 342.817632 -395.912568) (xy 342.831166 -395.882114) (xy 342.835432 -395.871643)
			(xy 342.835366 -395.849062) (xy 342.82562 -395.828692) (xy 342.817196 -395.821154) (xy 342.794951 -395.802479)
			(xy 342.754892 -395.760423) (xy 342.720476 -395.713635) (xy 342.692256 -395.66287) (xy 342.670686 -395.608942)
			(xy 342.656111 -395.552719) (xy 342.648768 -395.495103) (xy 342.648286 -395.466062) (xy 342.648731 -395.437136)
			(xy 342.656024 -395.379746) (xy 342.670489 -395.323732) (xy 342.691896 -395.269987) (xy 342.719903 -395.219366)
			(xy 342.754064 -395.172678) (xy 342.793836 -395.130665) (xy 342.815926 -395.111986) (xy 342.823001 -395.105722)
			(xy 342.83229 -395.089281) (xy 342.83396 -395.079982) (xy 342.838278 -395.048994) (xy 342.839226 -395.039756)
			(xy 342.83519 -395.021646) (xy 342.830404 -395.013688) (xy 342.815418 -394.98905) (xy 342.810315 -394.980684)
			(xy 342.795145 -394.968305) (xy 342.776443 -394.962513) (xy 342.76665 -394.962888) (xy 342.718898 -394.96492)
			(xy 342.68307 -394.964385) (xy 342.611962 -394.955551) (xy 342.542485 -394.938017) (xy 342.475699 -394.912051)
			(xy 342.412625 -394.878049) (xy 342.38311 -394.857732) (xy 342.37295 -394.850366) (xy 342.348312 -394.847064)
			(xy 342.24595 -394.884148) (xy 342.229186 -394.902436) (xy 342.226138 -394.914628) (xy 342.218662 -394.940873)
			(xy 342.196329 -394.99066) (xy 342.181688 -395.013688) (xy 342.176937 -395.021658) (xy 342.172916 -395.039757)
			(xy 342.173814 -395.048994) (xy 342.178132 -395.079982) (xy 342.179938 -395.089234) (xy 342.189199 -395.105634)
			(xy 342.196166 -395.111986) (xy 342.218264 -395.130659) (xy 342.258043 -395.172667) (xy 342.29221 -395.219354)
			(xy 342.320219 -395.269976) (xy 342.341625 -395.323724) (xy 342.356085 -395.379741) (xy 342.36337 -395.437135)
			(xy 342.363806 -395.466062) (xy 342.363202 -395.499382) (xy 342.353533 -395.565317) (xy 342.334409 -395.629154)
			(xy 342.32088 -395.65961) (xy 342.316617 -395.670079) (xy 342.316691 -395.692653) (xy 342.326448 -395.713009)
			(xy 342.33485 -395.72057) (xy 342.357096 -395.739245) (xy 342.397159 -395.781301) (xy 342.431579 -395.828088)
			(xy 342.459804 -395.878852) (xy 342.481381 -395.93278) (xy 342.495963 -395.989003) (xy 342.503315 -396.04662)
			(xy 342.50376 -396.075662) (xy 342.503309 -396.104666) (xy 342.495978 -396.162208) (xy 342.48144 -396.218364)
			(xy 342.459929 -396.272235) (xy 342.431789 -396.32296) (xy 342.397469 -396.369725) (xy 342.35752 -396.411784)
			(xy 342.335358 -396.4305) (xy 342.328246 -396.436088) (xy 342.319102 -396.451328) (xy 342.303862 -396.534132)
			(xy 342.306656 -396.551404) (xy 342.311228 -396.559532) (xy 342.323824 -396.58271) (xy 342.341715 -396.63233)
			(xy 342.350799 -396.684289) (xy 342.35136 -396.710662) (xy 342.351288 -396.72002) (xy 342.350142 -396.738702)
			(xy 342.349074 -396.748) (xy 342.348058 -396.75689) (xy 342.351868 -396.773654) (xy 342.39581 -396.843504)
			(xy 342.409526 -396.853918) (xy 342.417908 -396.856712) (xy 342.441944 -396.865166) (xy 342.487125 -396.888711)
			(xy 342.527939 -396.919208) (xy 342.563323 -396.955864) (xy 342.59236 -396.997729) (xy 342.614296 -397.043713)
			(xy 342.62187 -397.06804) (xy 342.623394 -397.073882) (xy 342.943688 -397.627602) (xy 342.947752 -397.63192)
			(xy 342.963971 -397.649617) (xy 342.991408 -397.689005) (xy 343.012558 -397.732096) (xy 343.026934 -397.777895)
			(xy 343.034202 -397.825343) (xy 343.03462 -397.849344) (xy 343.034155 -397.874145) (xy 343.026384 -397.923134)
			(xy 343.011042 -397.970303) (xy 342.988507 -398.014489) (xy 342.959333 -398.054604) (xy 342.92424 -398.089658)
			(xy 342.884094 -398.118788) (xy 342.839883 -398.141275) (xy 342.792697 -398.156565) (xy 342.743699 -398.164282)
			(xy 342.718898 -398.164812) (xy 342.693504 -398.164304) (xy 342.643372 -398.156173) (xy 342.595188 -398.140122)
			(xy 342.550195 -398.116564) (xy 342.509553 -398.086107) (xy 342.474312 -398.049537) (xy 342.445379 -398.007797)
			(xy 342.423501 -397.961963) (xy 342.415876 -397.937736) (xy 342.414352 -397.931894) (xy 342.094058 -397.378174)
			(xy 342.089994 -397.373856) (xy 342.073805 -397.356147) (xy 342.046431 -397.316744) (xy 342.025342 -397.273648)
			(xy 342.011025 -397.227855) (xy 342.003812 -397.180422) (xy 342.00338 -397.156432) (xy 342.003466 -397.144384)
			(xy 342.005249 -397.120355) (xy 342.006936 -397.108426) (xy 342.008206 -397.099536) (xy 342.005158 -397.082518)
			(xy 341.962994 -397.011652) (xy 341.949786 -397.000476) (xy 341.941404 -396.997428) (xy 341.919662 -396.989024)
			(xy 341.878815 -396.966573) (xy 341.841855 -396.938174) (xy 341.80964 -396.904488) (xy 341.782918 -396.866298)
			(xy 341.762312 -396.824489) (xy 341.7483 -396.780035) (xy 341.741206 -396.733967) (xy 341.740744 -396.710662)
			(xy 341.741326 -396.684291) (xy 341.750427 -396.63234) (xy 341.768302 -396.582719) (xy 341.780876 -396.559532)
			(xy 341.785448 -396.551404) (xy 341.788242 -396.534132) (xy 341.773002 -396.451328) (xy 341.763858 -396.436088)
			(xy 341.756746 -396.4305) (xy 341.734557 -396.411815) (xy 341.694606 -396.369755) (xy 341.660289 -396.322985)
			(xy 341.632155 -396.272255) (xy 341.610655 -396.218376) (xy 341.596133 -396.162214) (xy 341.588822 -396.104667)
			(xy 341.588344 -396.075662) (xy 341.588947 -396.042342) (xy 341.598613 -395.976406) (xy 341.617736 -395.912568)
			(xy 341.63127 -395.882114) (xy 341.635536 -395.871643) (xy 341.635469 -395.849062) (xy 341.625724 -395.828692)
			(xy 341.6173 -395.821154) (xy 341.595055 -395.802479) (xy 341.554996 -395.760423) (xy 341.520579 -395.713636)
			(xy 341.492359 -395.66287) (xy 341.470788 -395.608942) (xy 341.456214 -395.552719) (xy 341.44887 -395.495103)
			(xy 341.44839 -395.466062) (xy 341.448835 -395.437136) (xy 341.456128 -395.379746) (xy 341.470593 -395.323732)
			(xy 341.492 -395.269987) (xy 341.520007 -395.219367) (xy 341.554169 -395.172679) (xy 341.59394 -395.130666)
			(xy 341.61603 -395.111986) (xy 341.623105 -395.105722) (xy 341.632393 -395.089281) (xy 341.634064 -395.079982)
			(xy 341.638382 -395.048994) (xy 341.63933 -395.039756) (xy 341.635295 -395.021646) (xy 341.630508 -395.013688)
			(xy 341.615522 -394.98905) (xy 341.610419 -394.980683) (xy 341.59525 -394.968303) (xy 341.576547 -394.962509)
			(xy 341.566754 -394.962888) (xy 341.518748 -394.96492) (xy 341.482919 -394.964388) (xy 341.411808 -394.95556)
			(xy 341.342328 -394.938031) (xy 341.275539 -394.912069) (xy 341.21246 -394.878071) (xy 341.18296 -394.857732)
			(xy 341.1728 -394.850366) (xy 341.148162 -394.847064) (xy 341.0458 -394.884148) (xy 341.029036 -394.902436)
			(xy 341.025988 -394.914628) (xy 341.018511 -394.940872) (xy 340.996175 -394.990657) (xy 340.981538 -395.013688)
			(xy 340.976784 -395.021657) (xy 340.972758 -395.039757) (xy 340.973664 -395.048994) (xy 340.977982 -395.079982)
			(xy 340.979785 -395.089236) (xy 340.98904 -395.105642) (xy 340.996016 -395.111986) (xy 341.018111 -395.13066)
			(xy 341.057886 -395.17267) (xy 341.09205 -395.219358) (xy 341.120056 -395.26998) (xy 341.141459 -395.323727)
			(xy 341.155918 -395.379744) (xy 341.163202 -395.437136) (xy 341.163656 -395.466062) (xy 341.163052 -395.499382)
			(xy 341.153382 -395.565316) (xy 341.134256 -395.629153) (xy 341.12073 -395.65961) (xy 341.11647 -395.67008)
			(xy 341.116545 -395.692654) (xy 341.126294 -395.713015) (xy 341.1347 -395.72057) (xy 341.156948 -395.739243)
			(xy 341.197015 -395.781298) (xy 341.231439 -395.828084) (xy 341.259668 -395.878848) (xy 341.281247 -395.932776)
			(xy 341.295831 -395.989001) (xy 341.303184 -396.046619) (xy 341.30361 -396.075662) (xy 341.303159 -396.104666)
			(xy 341.295829 -396.162209) (xy 341.281292 -396.218366) (xy 341.259783 -396.272239) (xy 341.231644 -396.322966)
			(xy 341.197327 -396.369734) (xy 341.15738 -396.411796) (xy 341.135208 -396.4305) (xy 341.128096 -396.436088)
			(xy 341.118952 -396.451328) (xy 341.103712 -396.534132) (xy 341.106506 -396.551404) (xy 341.111078 -396.559532)
			(xy 341.123672 -396.58271) (xy 341.14156 -396.632331) (xy 341.150643 -396.684289) (xy 341.15121 -396.710662)
			(xy 341.151138 -396.72002) (xy 341.149992 -396.738702) (xy 341.148924 -396.748) (xy 341.147908 -396.75689)
			(xy 341.151718 -396.773654) (xy 341.19566 -396.843504) (xy 341.209376 -396.853918) (xy 341.217758 -396.856712)
			(xy 341.241791 -396.865169) (xy 341.286967 -396.888718) (xy 341.327774 -396.919218) (xy 341.363153 -396.955876)
			(xy 341.392185 -396.99774) (xy 341.414117 -397.043723) (xy 341.42172 -397.06804) (xy 341.423244 -397.073882)
			(xy 341.743538 -397.627602) (xy 341.747602 -397.63192) (xy 341.763792 -397.649629) (xy 341.79117 -397.689031)
			(xy 341.812263 -397.732126) (xy 341.826583 -397.777919) (xy 341.8338 -397.825353) (xy 341.834216 -397.849344)
			(xy 341.833727 -397.874133) (xy 341.825966 -397.923099) (xy 341.810642 -397.970249) (xy 341.788132 -398.014422)
			(xy 341.75899 -398.05453) (xy 341.723933 -398.089587) (xy 341.683825 -398.118729) (xy 341.639653 -398.14124)
			(xy 341.592503 -398.156565) (xy 341.543537 -398.164326) (xy 341.518748 -398.164812) (xy 341.493352 -398.164308)
			(xy 341.443214 -398.156184) (xy 341.395024 -398.140137) (xy 341.350024 -398.116583) (xy 341.309376 -398.086127)
			(xy 341.274128 -398.049557) (xy 341.245189 -398.007815) (xy 341.223307 -397.961979) (xy 341.215726 -397.937736)
			(xy 341.214202 -397.931894) (xy 340.893908 -397.378174) (xy 340.889844 -397.373856) (xy 340.873626 -397.356158)
			(xy 340.846193 -397.31677) (xy 340.825046 -397.273679) (xy 340.810674 -397.22788) (xy 340.80341 -397.180432)
			(xy 340.802976 -397.156432) (xy 340.803134 -397.14438) (xy 340.805043 -397.120352) (xy 340.806786 -397.108426)
			(xy 340.808056 -397.099536) (xy 340.805008 -397.082518) (xy 340.762844 -397.011652) (xy 340.749636 -397.000476)
			(xy 340.741254 -396.997428) (xy 340.719515 -396.989021) (xy 340.678674 -396.966566) (xy 340.641719 -396.938165)
			(xy 340.609509 -396.904479) (xy 340.582793 -396.866289) (xy 340.562191 -396.824482) (xy 340.548181 -396.78003)
			(xy 340.541089 -396.733966) (xy 340.540594 -396.710662) (xy 340.541176 -396.684292) (xy 340.550279 -396.632341)
			(xy 340.568156 -396.582721) (xy 340.580726 -396.559532) (xy 340.585298 -396.551404) (xy 340.588092 -396.534132)
			(xy 340.572852 -396.451328) (xy 340.563708 -396.436088) (xy 340.556596 -396.4305) (xy 340.534405 -396.411817)
			(xy 340.49445 -396.369758) (xy 340.460129 -396.322989) (xy 340.431992 -396.272259) (xy 340.410489 -396.21838)
			(xy 340.395966 -396.162216) (xy 340.388654 -396.104668) (xy 340.388194 -396.075662) (xy 340.388797 -396.042342)
			(xy 340.398462 -395.976405) (xy 340.417583 -395.912567) (xy 340.43112 -395.882114) (xy 340.435389 -395.871644)
			(xy 340.435323 -395.849063) (xy 340.42557 -395.828697) (xy 340.41715 -395.821154) (xy 340.394907 -395.802478)
			(xy 340.354852 -395.76042) (xy 340.320439 -395.713632) (xy 340.292222 -395.662866) (xy 340.270654 -395.608939)
			(xy 340.256082 -395.552717) (xy 340.248739 -395.495102) (xy 340.24824 -395.466062) (xy 340.248685 -395.437137)
			(xy 340.255979 -395.379748) (xy 340.270445 -395.323735) (xy 340.291854 -395.269991) (xy 340.319863 -395.219373)
			(xy 340.354027 -395.172688) (xy 340.393801 -395.130679) (xy 340.41588 -395.111986) (xy 340.422949 -395.105719)
			(xy 340.432228 -395.089277) (xy 340.433914 -395.079982) (xy 340.438232 -395.048994) (xy 340.43918 -395.039756)
			(xy 340.435148 -395.021644) (xy 340.430358 -395.013688) (xy 340.415372 -394.98905) (xy 340.410267 -394.98069)
			(xy 340.395096 -394.968325) (xy 340.376396 -394.962549) (xy 340.366604 -394.962888) (xy 340.318852 -394.96492)
			(xy 340.283023 -394.964389) (xy 340.211912 -394.95556) (xy 340.142431 -394.938032) (xy 340.075642 -394.912071)
			(xy 340.012563 -394.878073) (xy 339.983064 -394.857732) (xy 339.972904 -394.850366) (xy 339.948266 -394.847064)
			(xy 339.845904 -394.884148) (xy 339.82914 -394.902436) (xy 339.826092 -394.914628) (xy 339.818615 -394.940872)
			(xy 339.79628 -394.990658) (xy 339.781642 -395.013688) (xy 339.776887 -395.021657) (xy 339.772862 -395.039757)
			(xy 339.773768 -395.048994) (xy 339.778086 -395.079982) (xy 339.779889 -395.089236) (xy 339.789145 -395.105642)
			(xy 339.79612 -395.111986) (xy 339.818215 -395.13066) (xy 339.85799 -395.17267) (xy 339.892153 -395.219358)
			(xy 339.920159 -395.26998) (xy 339.941562 -395.323727) (xy 339.956021 -395.379744) (xy 339.963304 -395.437136)
			(xy 339.96376 -395.466062) (xy 339.963156 -395.499382) (xy 339.953486 -395.565316) (xy 339.93436 -395.629153)
			(xy 339.920834 -395.65961) (xy 339.916573 -395.67008) (xy 339.916648 -395.692654) (xy 339.926399 -395.713014)
			(xy 339.934804 -395.72057) (xy 339.957052 -395.739243) (xy 339.997118 -395.781298) (xy 340.031542 -395.828084)
			(xy 340.05977 -395.878849) (xy 340.08135 -395.932777) (xy 340.095933 -395.989001) (xy 340.103286 -396.046619)
			(xy 340.103714 -396.075662) (xy 340.103263 -396.104666) (xy 340.095933 -396.162209) (xy 340.081396 -396.218366)
			(xy 340.059887 -396.272239) (xy 340.031749 -396.322966) (xy 339.997432 -396.369735) (xy 339.957485 -396.411797)
			(xy 339.935312 -396.4305) (xy 339.9282 -396.436088) (xy 339.919056 -396.451328) (xy 339.903816 -396.534132)
			(xy 339.90661 -396.551404) (xy 339.911182 -396.559532) (xy 339.923776 -396.58271) (xy 339.941664 -396.632331)
			(xy 339.950746 -396.684289) (xy 339.951314 -396.710662) (xy 339.951242 -396.72002) (xy 339.950096 -396.738702)
			(xy 339.949028 -396.748) (xy 339.948012 -396.75689) (xy 339.951822 -396.773654) (xy 339.995764 -396.843504)
			(xy 340.00948 -396.853918) (xy 340.017862 -396.856712) (xy 340.041895 -396.865169) (xy 340.08707 -396.888719)
			(xy 340.127877 -396.919219) (xy 340.163256 -396.955877) (xy 340.192287 -396.997741) (xy 340.214219 -397.043724)
			(xy 340.221824 -397.06804) (xy 340.223348 -397.073882) (xy 340.543642 -397.627602) (xy 340.547706 -397.63192)
			(xy 340.563896 -397.649629) (xy 340.591274 -397.689031) (xy 340.612366 -397.732126) (xy 340.626686 -397.777919)
			(xy 340.633903 -397.825354) (xy 340.63432 -397.849344) (xy 340.633856 -397.874132) (xy 340.626093 -397.923097)
			(xy 340.610767 -397.970244) (xy 340.588253 -398.014413) (xy 340.559108 -398.054517) (xy 340.524047 -398.089567)
			(xy 340.483935 -398.118702) (xy 340.439759 -398.141202) (xy 340.392607 -398.156515) (xy 340.34364 -398.164263)
			(xy 340.318852 -398.164812) (xy 340.29346 -398.164301) (xy 340.243333 -398.156164) (xy 340.195155 -398.140108)
			(xy 340.150168 -398.116547) (xy 340.109533 -398.086089) (xy 340.074297 -398.049519) (xy 340.045369 -398.00778)
			(xy 340.023496 -397.961949) (xy 340.01583 -397.937736) (xy 340.014306 -397.931894) (xy 339.694012 -397.378174)
			(xy 339.689948 -397.373856) (xy 339.67373 -397.356158) (xy 339.646297 -397.31677) (xy 339.625149 -397.273679)
			(xy 339.610777 -397.22788) (xy 339.603513 -397.180432) (xy 339.60308 -397.156432) (xy 339.603238 -397.14438)
			(xy 339.605147 -397.120352) (xy 339.60689 -397.108426) (xy 339.60816 -397.099536) (xy 339.605112 -397.082518)
			(xy 339.562948 -397.011652) (xy 339.54974 -397.000476) (xy 339.541358 -396.997428) (xy 339.519619 -396.989021)
			(xy 339.478777 -396.966567) (xy 339.441822 -396.938166) (xy 339.409612 -396.90448) (xy 339.382895 -396.866289)
			(xy 339.362293 -396.824483) (xy 339.348282 -396.780031) (xy 339.34119 -396.733966) (xy 339.340698 -396.710662)
			(xy 339.34128 -396.684292) (xy 339.350383 -396.632341) (xy 339.368261 -396.582722) (xy 339.38083 -396.559532)
			(xy 339.385402 -396.551404) (xy 339.388196 -396.534132) (xy 339.372956 -396.451328) (xy 339.363812 -396.436088)
			(xy 339.3567 -396.4305) (xy 339.334509 -396.411816) (xy 339.294554 -396.369758) (xy 339.260233 -396.322989)
			(xy 339.232095 -396.272259) (xy 339.210592 -396.21838) (xy 339.196069 -396.162216) (xy 339.188757 -396.104668)
			(xy 339.188298 -396.075662) (xy 339.188901 -396.042342) (xy 339.198566 -395.976406) (xy 339.217687 -395.912567)
			(xy 339.231224 -395.882114) (xy 339.235492 -395.871644) (xy 339.235426 -395.849063) (xy 339.225674 -395.828697)
			(xy 339.217254 -395.821154) (xy 339.195011 -395.802478) (xy 339.154955 -395.76042) (xy 339.120542 -395.713632)
			(xy 339.092325 -395.662867) (xy 339.070757 -395.608939) (xy 339.056184 -395.552717) (xy 339.048841 -395.495102)
			(xy 339.048344 -395.466062) (xy 339.048789 -395.437137) (xy 339.056083 -395.379748) (xy 339.07055 -395.323735)
			(xy 339.091958 -395.269991) (xy 339.119968 -395.219374) (xy 339.154132 -395.172688) (xy 339.193906 -395.13068)
			(xy 339.215984 -395.111986) (xy 339.223053 -395.105718) (xy 339.232331 -395.089277) (xy 339.234018 -395.079982)
			(xy 339.238336 -395.048994) (xy 339.239284 -395.039756) (xy 339.235252 -395.021643) (xy 339.230462 -395.013688)
			(xy 339.215476 -394.98905) (xy 339.210371 -394.980689) (xy 339.1952 -394.968323) (xy 339.1765 -394.962545)
			(xy 339.166708 -394.962888) (xy 339.118702 -394.96492) (xy 339.082899 -394.964375) (xy 339.011841 -394.955528)
			(xy 338.942414 -394.937994) (xy 338.875676 -394.91204) (xy 338.812644 -394.878062) (xy 338.783168 -394.857732)
			(xy 338.772754 -394.850366) (xy 338.74837 -394.847064) (xy 338.646008 -394.884402) (xy 338.629244 -394.90269)
			(xy 338.626196 -394.914882) (xy 338.618717 -394.941065) (xy 338.596372 -394.990719) (xy 338.581746 -395.013688)
			(xy 338.576991 -395.021657) (xy 338.572965 -395.039757) (xy 338.573872 -395.048994) (xy 338.57819 -395.079982)
			(xy 338.579994 -395.089235) (xy 338.58925 -395.105641) (xy 338.596224 -395.111986) (xy 338.618319 -395.13066)
			(xy 338.658093 -395.172671) (xy 338.692256 -395.219359) (xy 338.720262 -395.26998) (xy 338.741665 -395.323728)
			(xy 338.756123 -395.379744) (xy 338.763407 -395.437136) (xy 338.763864 -395.466062) (xy 338.76326 -395.499382)
			(xy 338.75359 -395.565316) (xy 338.734465 -395.629153) (xy 338.720938 -395.65961) (xy 338.716677 -395.67008)
			(xy 338.716752 -395.692654) (xy 338.726503 -395.713014) (xy 338.734908 -395.72057) (xy 338.757156 -395.739244)
			(xy 338.797222 -395.781298) (xy 338.831645 -395.828084) (xy 338.859873 -395.878849) (xy 338.881452 -395.932777)
			(xy 338.896036 -395.989002) (xy 338.903389 -396.046619) (xy 338.903818 -396.075662) (xy 338.903367 -396.104666)
			(xy 338.896037 -396.162209) (xy 338.8815 -396.218367) (xy 338.859991 -396.27224) (xy 338.831853 -396.322967)
			(xy 338.797536 -396.369735) (xy 338.75759 -396.411798) (xy 338.735416 -396.4305) (xy 338.728304 -396.436088)
			(xy 338.71916 -396.451328) (xy 338.70392 -396.534132) (xy 338.706714 -396.551404) (xy 338.711286 -396.559532)
			(xy 338.72388 -396.58271) (xy 338.741768 -396.632331) (xy 338.75085 -396.684289) (xy 338.751418 -396.710662)
			(xy 338.751346 -396.72002) (xy 338.7502 -396.738702) (xy 338.749132 -396.748) (xy 338.748116 -396.75689)
			(xy 338.751926 -396.773654) (xy 338.795868 -396.843504) (xy 338.809584 -396.853918) (xy 338.817966 -396.856712)
			(xy 338.842063 -396.865193) (xy 338.887354 -396.888821) (xy 338.92825 -396.919432) (xy 338.963685 -396.956227)
			(xy 338.992733 -396.998247) (xy 339.014639 -397.044395) (xy 339.022182 -397.068802) (xy 339.023706 -397.074644)
			(xy 339.343492 -397.627602) (xy 339.347556 -397.63192) (xy 339.363775 -397.649617) (xy 339.391211 -397.689005)
			(xy 339.412362 -397.732096) (xy 339.426737 -397.777895) (xy 339.434005 -397.825343) (xy 339.434424 -397.849344)
			(xy 339.433959 -397.874145) (xy 339.426188 -397.923134) (xy 339.410847 -397.970303) (xy 339.388311 -398.01449)
			(xy 339.359137 -398.054605) (xy 339.324045 -398.08966) (xy 339.283898 -398.11879) (xy 339.239687 -398.141278)
			(xy 339.192501 -398.156568) (xy 339.143503 -398.164285) (xy 339.118702 -398.164812) (xy 339.093308 -398.164304)
			(xy 339.043175 -398.156174) (xy 338.994991 -398.140123) (xy 338.949997 -398.116566) (xy 338.909355 -398.086109)
			(xy 338.874113 -398.049539) (xy 338.84518 -398.007798) (xy 338.823302 -397.961965) (xy 338.81568 -397.937736)
			(xy 338.814156 -397.931894) (xy 338.493608 -397.377412) (xy 338.489544 -397.373094) (xy 338.473439 -397.355426)
			(xy 338.446199 -397.31614) (xy 338.425188 -397.2732) (xy 338.410887 -397.227584) (xy 338.40362 -397.180334)
			(xy 338.403184 -397.156432) (xy 338.403342 -397.14438) (xy 338.405251 -397.120352) (xy 338.406994 -397.108426)
			(xy 338.408264 -397.099536) (xy 338.405216 -397.082518) (xy 338.363052 -397.011652) (xy 338.349844 -397.000476)
			(xy 338.341462 -396.997428) (xy 338.319723 -396.989022) (xy 338.27888 -396.966567) (xy 338.241925 -396.938167)
			(xy 338.209714 -396.90448) (xy 338.182997 -396.86629) (xy 338.162394 -396.824483) (xy 338.148384 -396.780031)
			(xy 338.141292 -396.733966) (xy 338.140802 -396.710662) (xy 338.141384 -396.684291) (xy 338.150484 -396.63234)
			(xy 338.168357 -396.582718) (xy 338.180934 -396.559532) (xy 338.185506 -396.551404) (xy 338.1883 -396.534132)
			(xy 338.17306 -396.451328) (xy 338.163916 -396.436088) (xy 338.156804 -396.4305) (xy 338.134613 -396.411816)
			(xy 338.094658 -396.369758) (xy 338.060336 -396.322989) (xy 338.032198 -396.272259) (xy 338.010695 -396.21838)
			(xy 337.996171 -396.162216) (xy 337.98886 -396.104668) (xy 337.988402 -396.075662) (xy 337.989005 -396.042342)
			(xy 337.99867 -395.976406) (xy 338.017792 -395.912567) (xy 338.031328 -395.882114) (xy 338.035596 -395.871644)
			(xy 338.03553 -395.849063) (xy 338.025778 -395.828696) (xy 338.017358 -395.821154) (xy 337.995115 -395.802478)
			(xy 337.955059 -395.76042) (xy 337.920646 -395.713632) (xy 337.892428 -395.662867) (xy 337.87086 -395.60894)
			(xy 337.856287 -395.552717) (xy 337.848944 -395.495102) (xy 337.848448 -395.466062) (xy 337.848893 -395.437137)
			(xy 337.856187 -395.379748) (xy 337.870654 -395.323735) (xy 337.892063 -395.269992) (xy 337.920072 -395.219374)
			(xy 337.954237 -395.172689) (xy 337.994011 -395.130681) (xy 338.016088 -395.111986) (xy 338.023157 -395.105718)
			(xy 338.032433 -395.089276) (xy 338.034122 -395.079982) (xy 338.03844 -395.048994) (xy 338.039388 -395.039756)
			(xy 338.035356 -395.021643) (xy 338.030566 -395.013688) (xy 338.01558 -394.98905) (xy 338.010475 -394.980689)
			(xy 337.995304 -394.968321) (xy 337.976604 -394.962542) (xy 337.966812 -394.962888) (xy 337.918806 -394.96492)
			(xy 337.882978 -394.964386) (xy 337.811869 -394.955552) (xy 337.742391 -394.938019) (xy 337.675606 -394.912054)
			(xy 337.61253 -394.878053) (xy 337.583018 -394.857732) (xy 337.572858 -394.850366) (xy 337.54822 -394.847064)
			(xy 337.445858 -394.884148) (xy 337.429094 -394.902436) (xy 337.426046 -394.914628) (xy 337.41857 -394.940873)
			(xy 337.396238 -394.99066) (xy 337.381596 -395.013688) (xy 337.376845 -395.021658) (xy 337.372823 -395.039757)
			(xy 337.373722 -395.048994) (xy 337.37804 -395.079982) (xy 337.379846 -395.089234) (xy 337.389108 -395.105633)
			(xy 337.396074 -395.111986) (xy 337.418171 -395.130659) (xy 337.45795 -395.172667) (xy 337.492116 -395.219355)
			(xy 337.520125 -395.269976) (xy 337.541531 -395.323724) (xy 337.555991 -395.379742) (xy 337.563275 -395.437135)
			(xy 337.563714 -395.466062) (xy 337.56311 -395.499382) (xy 337.553441 -395.565317) (xy 337.534318 -395.629154)
			(xy 337.520788 -395.65961) (xy 337.516525 -395.670078) (xy 337.516599 -395.692652) (xy 337.526357 -395.713008)
			(xy 337.534758 -395.72057) (xy 337.557004 -395.739245) (xy 337.597066 -395.781302) (xy 337.631485 -395.828088)
			(xy 337.65971 -395.878853) (xy 337.681287 -395.93278) (xy 337.695868 -395.989004) (xy 337.703221 -396.04662)
			(xy 337.703668 -396.075662) (xy 337.703217 -396.104666) (xy 337.695886 -396.162208) (xy 337.681349 -396.218364)
			(xy 337.659838 -396.272236) (xy 337.631697 -396.322961) (xy 337.597378 -396.369727) (xy 337.55743 -396.411786)
			(xy 337.535266 -396.4305) (xy 337.528154 -396.436088) (xy 337.51901 -396.451328) (xy 337.50377 -396.534132)
			(xy 337.506564 -396.551404) (xy 337.511136 -396.559532) (xy 337.523732 -396.58271) (xy 337.541622 -396.63233)
			(xy 337.550706 -396.684289) (xy 337.551268 -396.710662) (xy 337.551196 -396.72002) (xy 337.55005 -396.738702)
			(xy 337.548982 -396.748) (xy 337.547966 -396.75689) (xy 337.551776 -396.773654) (xy 337.595718 -396.843504)
			(xy 337.609434 -396.853918) (xy 337.617816 -396.856712) (xy 337.641851 -396.865166) (xy 337.687032 -396.888712)
			(xy 337.727844 -396.919209) (xy 337.763228 -396.955866) (xy 337.792264 -396.99773) (xy 337.8142 -397.043715)
			(xy 337.821778 -397.06804) (xy 337.823302 -397.073882) (xy 338.143596 -397.627602) (xy 338.14766 -397.63192)
			(xy 338.163879 -397.649617) (xy 338.191315 -397.689005) (xy 338.212465 -397.732096) (xy 338.22684 -397.777895)
			(xy 338.234108 -397.825343) (xy 338.234528 -397.849344) (xy 338.234063 -397.874145) (xy 338.226292 -397.923134)
			(xy 338.210951 -397.970304) (xy 338.188415 -398.014491) (xy 338.159242 -398.054606) (xy 338.124149 -398.089661)
			(xy 338.084002 -398.118792) (xy 338.039791 -398.14128) (xy 337.992605 -398.156571) (xy 337.943607 -398.164289)
			(xy 337.918806 -398.164812) (xy 337.893412 -398.164305) (xy 337.843279 -398.156175) (xy 337.795094 -398.140125)
			(xy 337.750099 -398.116567) (xy 337.709457 -398.086111) (xy 337.674214 -398.04954) (xy 337.64528 -398.0078)
			(xy 337.623402 -397.961966) (xy 337.615784 -397.937736) (xy 337.61426 -397.931894) (xy 337.293966 -397.378174)
			(xy 337.289902 -397.373856) (xy 337.273713 -397.356147) (xy 337.246338 -397.316744) (xy 337.225248 -397.273649)
			(xy 337.210931 -397.227856) (xy 337.203718 -397.180422) (xy 337.203288 -397.156432) (xy 337.203374 -397.144384)
			(xy 337.205156 -397.120355) (xy 337.206844 -397.108426) (xy 337.208114 -397.099536) (xy 337.205066 -397.082518)
			(xy 337.162902 -397.011652) (xy 337.149694 -397.000476) (xy 337.141312 -396.997428) (xy 337.11957 -396.989024)
			(xy 337.078722 -396.966574) (xy 337.04176 -396.938176) (xy 337.009544 -396.90449) (xy 336.982823 -396.866299)
			(xy 336.962216 -396.82449) (xy 336.948203 -396.780036) (xy 336.941109 -396.733967) (xy 336.940652 -396.710662)
			(xy 336.941234 -396.684291) (xy 336.950336 -396.63234) (xy 336.968211 -396.58272) (xy 336.980784 -396.559532)
			(xy 336.985356 -396.551404) (xy 336.98815 -396.534132) (xy 336.97291 -396.451328) (xy 336.963766 -396.436088)
			(xy 336.956654 -396.4305) (xy 336.934465 -396.411815) (xy 336.894513 -396.369756) (xy 336.860196 -396.322986)
			(xy 336.832061 -396.272255) (xy 336.81056 -396.218377) (xy 336.796038 -396.162214) (xy 336.788727 -396.104667)
			(xy 336.788252 -396.075662) (xy 336.788855 -396.042342) (xy 336.798521 -395.976406) (xy 336.817645 -395.912568)
			(xy 336.831178 -395.882114) (xy 336.835443 -395.871643) (xy 336.835377 -395.849062) (xy 336.825632 -395.828691)
			(xy 336.817208 -395.821154) (xy 336.794963 -395.80248) (xy 336.754903 -395.760423) (xy 336.720486 -395.713636)
			(xy 336.692265 -395.662871) (xy 336.670694 -395.608943) (xy 336.656119 -395.552719) (xy 336.648775 -395.495103)
			(xy 336.648298 -395.466062) (xy 336.648743 -395.437136) (xy 336.656036 -395.379746) (xy 336.670501 -395.323733)
			(xy 336.691909 -395.269988) (xy 336.719916 -395.219368) (xy 336.754078 -395.17268) (xy 336.79385 -395.130668)
			(xy 336.815938 -395.111986) (xy 336.823012 -395.105722) (xy 336.832299 -395.08928) (xy 336.833972 -395.079982)
			(xy 336.83829 -395.048994) (xy 336.839238 -395.039756) (xy 336.835203 -395.021645) (xy 336.830416 -395.013688)
			(xy 336.81543 -394.98905) (xy 336.810327 -394.980682) (xy 336.795158 -394.9683) (xy 336.776455 -394.962503)
			(xy 336.766662 -394.962888) (xy 336.71891 -394.96492) (xy 336.683082 -394.964386) (xy 336.611973 -394.955553)
			(xy 336.542495 -394.93802) (xy 336.475709 -394.912055) (xy 336.412633 -394.878055) (xy 336.383122 -394.857732)
			(xy 336.372962 -394.850366) (xy 336.348324 -394.847064) (xy 336.245962 -394.884148) (xy 336.229198 -394.902436)
			(xy 336.22615 -394.914628) (xy 336.218674 -394.940873) (xy 336.196342 -394.99066) (xy 336.1817 -395.013688)
			(xy 336.176948 -395.021658) (xy 336.172926 -395.039757) (xy 336.173826 -395.048994) (xy 336.178144 -395.079982)
			(xy 336.17995 -395.089234) (xy 336.189212 -395.105632) (xy 336.196178 -395.111986) (xy 336.218275 -395.130659)
			(xy 336.258053 -395.172668) (xy 336.292219 -395.219355) (xy 336.320228 -395.269977) (xy 336.341633 -395.323725)
			(xy 336.356093 -395.379742) (xy 336.363378 -395.437135) (xy 336.363818 -395.466062) (xy 336.363214 -395.499382)
			(xy 336.353545 -395.565317) (xy 336.334422 -395.629154) (xy 336.320892 -395.65961) (xy 336.316628 -395.670078)
			(xy 336.316703 -395.692652) (xy 336.326462 -395.713008) (xy 336.334862 -395.72057) (xy 336.357112 -395.739242)
			(xy 336.397182 -395.781296) (xy 336.431609 -395.828081) (xy 336.45984 -395.878845) (xy 336.481421 -395.932774)
			(xy 336.496006 -395.989) (xy 336.50336 -396.046619) (xy 336.503772 -396.075662) (xy 336.503321 -396.104666)
			(xy 336.49599 -396.162208) (xy 336.481453 -396.218364) (xy 336.459942 -396.272236) (xy 336.431802 -396.322961)
			(xy 336.397483 -396.369727) (xy 336.357534 -396.411787) (xy 336.33537 -396.4305) (xy 336.328258 -396.436088)
			(xy 336.319114 -396.451328) (xy 336.303874 -396.534132) (xy 336.306668 -396.551404) (xy 336.31124 -396.559532)
			(xy 336.323836 -396.58271) (xy 336.341726 -396.63233) (xy 336.35081 -396.684289) (xy 336.351372 -396.710662)
			(xy 336.3513 -396.72002) (xy 336.350154 -396.738702) (xy 336.349086 -396.748) (xy 336.34807 -396.75689)
			(xy 336.35188 -396.773654) (xy 336.395822 -396.843504) (xy 336.409538 -396.853918) (xy 336.41792 -396.856712)
			(xy 336.441955 -396.865166) (xy 336.487135 -396.888713) (xy 336.527947 -396.91921) (xy 336.56333 -396.955867)
			(xy 336.592366 -396.997731) (xy 336.614301 -397.043716) (xy 336.621882 -397.06804) (xy 336.623406 -397.073882)
			(xy 336.9437 -397.627602) (xy 336.947764 -397.63192) (xy 336.963983 -397.649617) (xy 336.991418 -397.689005)
			(xy 337.012568 -397.732097) (xy 337.026943 -397.777895) (xy 337.034211 -397.825343) (xy 337.034632 -397.849344)
			(xy 337.034167 -397.874145) (xy 337.026396 -397.923135) (xy 337.011055 -397.970305) (xy 336.988519 -398.014492)
			(xy 336.959346 -398.054608) (xy 336.924253 -398.089663) (xy 336.884107 -398.118794) (xy 336.839895 -398.141283)
			(xy 336.792709 -398.156574) (xy 336.743712 -398.164293) (xy 336.71891 -398.164812) (xy 336.693516 -398.164305)
			(xy 336.643382 -398.156176) (xy 336.595196 -398.140126) (xy 336.550202 -398.116569) (xy 336.509559 -398.086112)
			(xy 336.474315 -398.049542) (xy 336.445381 -398.007801) (xy 336.423503 -397.961967) (xy 336.415888 -397.937736)
			(xy 336.414364 -397.931894) (xy 336.09407 -397.378174) (xy 336.090006 -397.373856) (xy 336.073817 -397.356147)
			(xy 336.046441 -397.316744) (xy 336.025351 -397.273649) (xy 336.011034 -397.227856) (xy 336.003821 -397.180422)
			(xy 336.003392 -397.156432) (xy 336.003478 -397.144384) (xy 336.00526 -397.120355) (xy 336.006948 -397.108426)
			(xy 336.008218 -397.099536) (xy 336.00517 -397.082518) (xy 335.963006 -397.011652) (xy 335.949798 -397.000476)
			(xy 335.941416 -396.997428) (xy 335.919674 -396.989024) (xy 335.878825 -396.966574) (xy 335.841863 -396.938176)
			(xy 335.809647 -396.904491) (xy 335.782925 -396.8663) (xy 335.762317 -396.824491) (xy 335.748304 -396.780036)
			(xy 335.74121 -396.733968) (xy 335.740756 -396.710662) (xy 335.741338 -396.684291) (xy 335.75044 -396.632341)
			(xy 335.768315 -396.58272) (xy 335.780888 -396.559532) (xy 335.78546 -396.551404) (xy 335.788254 -396.534132)
			(xy 335.773014 -396.451328) (xy 335.76387 -396.436088) (xy 335.756758 -396.4305) (xy 335.734568 -396.411816)
			(xy 335.694617 -396.369756) (xy 335.660299 -396.322986) (xy 335.632164 -396.272255) (xy 335.610663 -396.218377)
			(xy 335.596141 -396.162214) (xy 335.58883 -396.104667) (xy 335.588356 -396.075662) (xy 335.588959 -396.042342)
			(xy 335.598625 -395.976406) (xy 335.617749 -395.912568) (xy 335.631282 -395.882114) (xy 335.635547 -395.871643)
			(xy 335.63548 -395.849061) (xy 335.625737 -395.828691) (xy 335.617312 -395.821154) (xy 335.595066 -395.80248)
			(xy 335.555006 -395.760424) (xy 335.520589 -395.713637) (xy 335.492368 -395.662871) (xy 335.470797 -395.608943)
			(xy 335.456222 -395.552719) (xy 335.448878 -395.495103) (xy 335.448402 -395.466062) (xy 335.448847 -395.437136)
			(xy 335.45614 -395.379747) (xy 335.470606 -395.323733) (xy 335.492013 -395.269988) (xy 335.520021 -395.219368)
			(xy 335.554183 -395.172681) (xy 335.593955 -395.130669) (xy 335.616042 -395.111986) (xy 335.623116 -395.105721)
			(xy 335.632401 -395.08928) (xy 335.634076 -395.079982) (xy 335.638394 -395.048994) (xy 335.639342 -395.039756)
			(xy 335.635307 -395.021645) (xy 335.63052 -395.013688) (xy 335.617487 -394.99329) (xy 335.596887 -394.949488)
			(xy 335.5829 -394.903149) (xy 335.575827 -394.855264) (xy 335.575402 -394.831062) (xy 335.575833 -394.80739)
			(xy 335.582587 -394.76053) (xy 335.595936 -394.715108) (xy 335.605374 -394.693394) (xy 335.609692 -394.683996)
			(xy 335.610454 -394.66393) (xy 335.578196 -394.57757) (xy 335.56448 -394.562838) (xy 335.555082 -394.55852)
			(xy 335.530711 -394.546828) (xy 335.485823 -394.51672) (xy 335.446432 -394.47971) (xy 335.413586 -394.436785)
			(xy 335.388161 -394.389088) (xy 335.370835 -394.33789) (xy 335.362069 -394.284555) (xy 335.361534 -394.25753)
			(xy 335.362079 -394.230392) (xy 335.370937 -394.176845) (xy 335.388422 -394.125463) (xy 335.414063 -394.077626)
			(xy 335.447171 -394.034619) (xy 335.486859 -393.997596) (xy 335.53206 -393.967552) (xy 335.58156 -393.945292)
			(xy 335.634032 -393.931415) (xy 335.661 -393.928346) (xy 335.671668 -393.92733) (xy 335.690464 -393.916662)
			(xy 335.748376 -393.838684) (xy 335.752948 -393.817856) (xy 335.750916 -393.807188) (xy 335.745479 -393.778797)
			(xy 335.739621 -393.721284) (xy 335.739232 -393.69238) (xy 335.739657 -393.661522) (xy 335.74624 -393.600157)
			(xy 335.759298 -393.539837) (xy 335.778683 -393.481243) (xy 335.804176 -393.425038) (xy 335.819496 -393.398248)
			(xy 335.824322 -393.39012) (xy 335.82737 -393.371832) (xy 335.810352 -393.286488) (xy 335.800192 -393.27074)
			(xy 335.792572 -393.265152) (xy 335.772266 -393.249421) (xy 335.736308 -393.212744) (xy 335.706445 -393.170955)
			(xy 335.683392 -393.125056) (xy 335.667703 -393.076148) (xy 335.659753 -393.025403) (xy 335.659222 -392.999722)
			(xy 335.659672 -392.974917) (xy 335.667097 -392.925866) (xy 335.681768 -392.878475) (xy 335.703355 -392.833808)
			(xy 335.731375 -392.792869) (xy 335.765198 -392.756576) (xy 335.804065 -392.725745) (xy 335.847101 -392.701068)
			(xy 335.870042 -392.69162) (xy 335.884774 -392.685778) (xy 335.9023 -392.660124) (xy 335.902808 -392.612118)
			(xy 335.90349 -392.579919) (xy 335.911115 -392.515965) (xy 335.925785 -392.453251) (xy 335.947318 -392.39255)
			(xy 335.975449 -392.334612) (xy 336.00983 -392.280149) (xy 336.050039 -392.229835) (xy 336.07248 -392.206734)
			(xy 336.19186 -392.087608) (xy 336.19855 -392.080201) (xy 336.206141 -392.061764) (xy 336.206592 -392.051794)
			(xy 336.206592 -391.552938) (xy 336.19313 -391.52957) (xy 336.180938 -391.522712) (xy 336.159455 -391.510025)
			(xy 336.120229 -391.479195) (xy 336.086082 -391.442821) (xy 336.05779 -391.401728) (xy 336.035995 -391.356849)
			(xy 336.021193 -391.309204) (xy 336.01372 -391.259876) (xy 336.013298 -391.23493) (xy 336.013744 -391.210379)
			(xy 336.021002 -391.161817) (xy 336.035363 -391.114862) (xy 336.05651 -391.070548) (xy 336.08398 -391.029849)
			(xy 336.117166 -390.993661) (xy 336.13598 -390.977882) (xy 336.143346 -390.97204) (xy 336.152744 -390.95553)
			(xy 336.164428 -390.878314) (xy 336.165355 -390.868934) (xy 336.161171 -390.850572) (xy 336.1563 -390.8425)
			(xy 335.94167 -390.521444) (xy 335.928462 -390.511284) (xy 335.919826 -390.50849) (xy 335.889028 -390.498168)
			(xy 335.829757 -390.471591) (xy 335.773834 -390.438546) (xy 335.721961 -390.39945) (xy 335.674789 -390.354793)
			(xy 335.632912 -390.305137) (xy 335.614518 -390.278366) (xy 335.377282 -389.923274) (xy 335.358748 -389.894641)
			(xy 335.327784 -389.833866) (xy 335.304178 -389.769873) (xy 335.288255 -389.70355) (xy 335.280238 -389.635814)
			(xy 335.279746 -389.60171) (xy 335.279746 -389.585708) (xy 335.262474 -389.560054) (xy 335.24825 -389.554212)
			(xy 335.216857 -389.540685) (xy 335.157204 -389.507301) (xy 335.101894 -389.467128) (xy 335.051697 -389.420725)
			(xy 335.00731 -389.368736) (xy 334.9879 -389.340598) (xy 334.750664 -388.985506) (xy 334.732131 -388.956873)
			(xy 334.70117 -388.896098) (xy 334.677568 -388.832105) (xy 334.661651 -388.765781) (xy 334.65364 -388.698046)
			(xy 334.653128 -388.663942) (xy 334.653128 -388.64794) (xy 334.635856 -388.622286) (xy 334.621632 -388.616444)
			(xy 334.590239 -388.602917) (xy 334.530586 -388.569533) (xy 334.475276 -388.52936) (xy 334.425078 -388.482958)
			(xy 334.38069 -388.43097) (xy 334.361282 -388.40283) (xy 334.124046 -388.047738) (xy 334.105494 -388.019081)
			(xy 334.074491 -387.958258) (xy 334.050841 -387.894217) (xy 334.034869 -387.827843) (xy 334.026797 -387.760054)
			(xy 334.026256 -387.72592) (xy 334.026324 -387.71384) (xy 334.027341 -387.689703) (xy 334.028288 -387.67766)
			(xy 334.02905 -387.66877) (xy 334.024986 -387.652514) (xy 333.34452 -386.634228) (xy 333.33817 -386.626354)
			(xy 331.088492 -384.37693) (xy 331.080177 -384.369368) (xy 331.059079 -384.361702) (xy 331.047852 -384.362198)
			(xy 330.958952 -384.370326) (xy 330.939394 -384.381756) (xy 330.933044 -384.391154) (xy 330.917703 -384.41265)
			(xy 330.882048 -384.451606) (xy 330.841365 -384.485278) (xy 330.796431 -384.513024) (xy 330.748102 -384.534313)
			(xy 330.697301 -384.54874) (xy 330.644997 -384.556029) (xy 330.618592 -384.556508) (xy 330.589154 -384.555964)
			(xy 330.530978 -384.546907) (xy 330.502768 -384.538474) (xy 330.494152 -384.536182) (xy 330.476355 -384.536968)
			(xy 330.46797 -384.539998) (xy 330.439776 -384.551936) (xy 330.43154 -384.555758) (xy 330.418259 -384.56812)
			(xy 330.413868 -384.576066) (xy 330.400686 -384.601751) (xy 330.369367 -384.650254) (xy 330.351384 -384.67284)
			(xy 330.346046 -384.679818) (xy 330.34006 -384.696321) (xy 330.3397 -384.705098) (xy 330.3397 -384.859022)
			(xy 330.340109 -384.867791) (xy 330.346079 -384.884286) (xy 330.351384 -384.89128) (xy 330.369386 -384.913852)
			(xy 330.400709 -384.962355) (xy 330.413868 -384.988054) (xy 330.418265 -384.995998) (xy 330.431534 -385.008375)
			(xy 330.439776 -385.012184) (xy 330.46797 -385.024122) (xy 330.476336 -385.02723) (xy 330.494157 -385.027996)
			(xy 330.502768 -385.025646) (xy 330.530982 -385.017234) (xy 330.589156 -385.008183) (xy 330.618592 -385.007612)
			(xy 330.645844 -385.008075) (xy 330.699793 -385.01583) (xy 330.752089 -385.031185) (xy 330.801667 -385.053826)
			(xy 330.847519 -385.083292) (xy 330.888711 -385.118984) (xy 330.924403 -385.160175) (xy 330.95387 -385.206026)
			(xy 330.976512 -385.255604) (xy 330.991868 -385.307899) (xy 330.999625 -385.361848) (xy 330.999625 -385.416352)
			(xy 330.991868 -385.470301) (xy 330.976512 -385.522596) (xy 330.95387 -385.572174) (xy 330.924403 -385.618025)
			(xy 330.888711 -385.659216) (xy 330.847519 -385.694908) (xy 330.801667 -385.724374) (xy 330.752089 -385.747015)
			(xy 330.699793 -385.76237) (xy 330.645844 -385.770125) (xy 330.618592 -385.770628) (xy 330.59452 -385.770278)
			(xy 330.546755 -385.764246) (xy 330.500132 -385.752243) (xy 330.477622 -385.743704) (xy 330.465176 -385.738624)
			(xy 330.439268 -385.741926) (xy 330.34859 -385.808728) (xy 330.337668 -385.83235) (xy 330.338684 -385.845558)
			(xy 330.3397 -385.87426) (xy 330.339214 -385.901511) (xy 330.331458 -385.955459) (xy 330.316103 -386.007754)
			(xy 330.293461 -386.057331) (xy 330.263995 -386.103181) (xy 330.228304 -386.144372) (xy 330.187113 -386.180063)
			(xy 330.141263 -386.209529) (xy 330.091686 -386.232171) (xy 330.039391 -386.247526) (xy 329.985443 -386.255282)
			(xy 329.930941 -386.255282) (xy 329.876993 -386.247526) (xy 329.824698 -386.232171) (xy 329.775121 -386.209529)
			(xy 329.729271 -386.180063) (xy 329.68808 -386.144372) (xy 329.652389 -386.103181) (xy 329.622923 -386.057331)
			(xy 329.600281 -386.007754) (xy 329.584926 -385.955459) (xy 329.57717 -385.901511) (xy 329.576684 -385.87426)
			(xy 329.5777 -385.845558) (xy 329.578716 -385.83235) (xy 329.567794 -385.808728) (xy 329.477116 -385.741926)
			(xy 329.451208 -385.738624) (xy 329.438762 -385.743704) (xy 329.416252 -385.752239) (xy 329.369626 -385.764224)
			(xy 329.321863 -385.770257) (xy 329.297792 -385.770628) (xy 329.27054 -385.770142) (xy 329.21659 -385.762384)
			(xy 329.164293 -385.747027) (xy 329.114715 -385.724384) (xy 329.068863 -385.694916) (xy 329.027671 -385.659223)
			(xy 328.991979 -385.618031) (xy 328.962512 -385.572178) (xy 328.93987 -385.522599) (xy 328.924515 -385.470302)
			(xy 328.916758 -385.416352) (xy 328.916758 -385.361848) (xy 328.924515 -385.307898) (xy 328.93987 -385.255601)
			(xy 328.962512 -385.206022) (xy 328.991979 -385.160169) (xy 329.027671 -385.118977) (xy 329.068863 -385.083284)
			(xy 329.114715 -385.053816) (xy 329.164293 -385.031173) (xy 329.21659 -385.015816) (xy 329.27054 -385.008058)
			(xy 329.297792 -385.007612) (xy 329.327231 -385.008155) (xy 329.385407 -385.01721) (xy 329.413616 -385.025646)
			(xy 329.422232 -385.02794) (xy 329.440031 -385.027159) (xy 329.448414 -385.024122) (xy 329.476608 -385.012184)
			(xy 329.484847 -385.008365) (xy 329.498136 -384.996008) (xy 329.502516 -384.988054) (xy 329.515697 -384.962368)
			(xy 329.547014 -384.913864) (xy 329.565 -384.89128) (xy 329.570333 -384.8843) (xy 329.576316 -384.867798)
			(xy 329.576684 -384.859022) (xy 329.576684 -384.705098) (xy 329.57628 -384.696327) (xy 329.570323 -384.679822)
			(xy 329.565 -384.67284) (xy 329.547002 -384.650265) (xy 329.515686 -384.601759) (xy 329.502516 -384.576066)
			(xy 329.49811 -384.568132) (xy 329.484832 -384.555777) (xy 329.476608 -384.551936) (xy 329.448414 -384.539998)
			(xy 329.440048 -384.536874) (xy 329.422218 -384.53608) (xy 329.413616 -384.538474) (xy 329.385403 -384.546892)
			(xy 329.327229 -384.555955) (xy 329.297792 -384.556508) (xy 329.270541 -384.556022) (xy 329.216594 -384.548264)
			(xy 329.1643 -384.532908) (xy 329.114724 -384.510267) (xy 329.068875 -384.4808) (xy 329.027686 -384.445109)
			(xy 328.991995 -384.403919) (xy 328.962529 -384.358069) (xy 328.939889 -384.308492) (xy 328.924534 -384.256198)
			(xy 328.916778 -384.202251) (xy 328.916778 -384.147749) (xy 328.924534 -384.093802) (xy 328.939889 -384.041508)
			(xy 328.962529 -383.991931) (xy 328.991995 -383.946081) (xy 329.027686 -383.904891) (xy 329.068875 -383.8692)
			(xy 329.114724 -383.839733) (xy 329.1643 -383.817092) (xy 329.216594 -383.801736) (xy 329.270541 -383.793978)
			(xy 329.297792 -383.793492) (xy 329.321864 -383.793841) (xy 329.369629 -383.799871) (xy 329.416254 -383.811873)
			(xy 329.438762 -383.820416) (xy 329.451208 -383.825496) (xy 329.477116 -383.822194) (xy 329.567794 -383.755392)
			(xy 329.578716 -383.73177) (xy 329.5777 -383.718562) (xy 329.576684 -383.68986) (xy 329.577119 -383.663584)
			(xy 329.584326 -383.611529) (xy 329.59861 -383.560957) (xy 329.619702 -383.512824) (xy 329.647203 -383.468043)
			(xy 329.68059 -383.427461) (xy 329.719233 -383.391847) (xy 329.7624 -383.361875) (xy 329.809272 -383.338113)
			(xy 329.833986 -383.32918) (xy 329.846432 -383.324862) (xy 329.864212 -383.305304) (xy 329.886564 -383.20853)
			(xy 329.888117 -383.200087) (xy 329.886141 -383.183044) (xy 329.878665 -383.167601) (xy 329.872848 -383.161286)
			(xy 328.728832 -382.017016) (xy 328.69762 -381.985144) (xy 328.640244 -381.916829) (xy 328.58904 -381.843773)
			(xy 328.544398 -381.766532) (xy 328.506658 -381.685695) (xy 328.476106 -381.601876) (xy 328.452976 -381.515713)
			(xy 328.437443 -381.427863) (xy 328.429625 -381.338992) (xy 328.429112 -381.294386) (xy 328.429112 -376.748802)
			(xy 328.429624 -376.704183) (xy 328.437448 -376.615289) (xy 328.452986 -376.527414) (xy 328.476118 -376.441226)
			(xy 328.506669 -376.357381) (xy 328.544408 -376.276515) (xy 328.589046 -376.199244) (xy 328.640244 -376.126154)
			(xy 328.697615 -376.057802) (xy 328.728832 -376.025918) (xy 328.881994 -375.872502) (xy 328.888806 -375.865157)
			(xy 328.89654 -375.846695) (xy 328.89698 -375.836688) (xy 328.89698 -375.400062) (xy 328.896549 -375.389995)
			(xy 328.888823 -375.371403) (xy 328.881994 -375.363994) (xy 327.619614 -374.101614) (xy 327.612211 -374.09478)
			(xy 327.593613 -374.087074) (xy 327.583546 -374.086628) (xy 295.950132 -374.086628) (xy 295.94008 -374.086125)
			(xy 295.921516 -374.078406) (xy 295.914064 -374.071642) (xy 295.303194 -373.460772) (xy 295.296353 -373.453372)
			(xy 295.288629 -373.434774) (xy 295.288208 -373.424704) (xy 295.288208 -372.1608) (xy 295.28779 -372.151477)
			(xy 295.281107 -372.13407) (xy 295.268628 -372.120216) (xy 295.260522 -372.115588) (xy 295.167304 -372.067836)
			(xy 295.13911 -372.069868) (xy 295.127426 -372.078504) (xy 295.101387 -372.096611) (xy 295.045673 -372.126922)
			(xy 294.986622 -372.150066) (xy 294.92515 -372.165686) (xy 294.862213 -372.173538) (xy 294.8305 -372.174008)
			(xy 294.798539 -372.173506) (xy 294.735121 -372.165495) (xy 294.673207 -372.149598) (xy 294.613774 -372.126066)
			(xy 294.557759 -372.095272) (xy 294.506044 -372.057699) (xy 294.459447 -372.013942) (xy 294.418702 -371.964689)
			(xy 294.384451 -371.910718) (xy 294.357234 -371.852879) (xy 294.337481 -371.792086) (xy 294.325503 -371.729296)
			(xy 294.32149 -371.6655) (xy 294.325503 -371.601704) (xy 294.337481 -371.538914) (xy 294.357234 -371.478121)
			(xy 294.384451 -371.420282) (xy 294.418702 -371.366311) (xy 294.459447 -371.317058) (xy 294.506044 -371.273301)
			(xy 294.557759 -371.235728) (xy 294.613774 -371.204934) (xy 294.673207 -371.181402) (xy 294.735121 -371.165505)
			(xy 294.798539 -371.157494) (xy 294.8305 -371.156992) (xy 294.86987 -371.158516) (xy 294.881046 -371.159278)
			(xy 294.901874 -371.151658) (xy 295.273222 -370.78031) (xy 295.280043 -370.772969) (xy 295.287791 -370.754506)
			(xy 295.288208 -370.744496) (xy 295.288208 -367.51895) (xy 295.287837 -367.509906) (xy 295.281549 -367.492947)
			(xy 295.26977 -367.47922) (xy 295.262046 -367.4745) (xy 295.233598 -367.457482) (xy 295.225216 -367.451894)
			(xy 295.20642 -367.448338) (xy 295.117774 -367.465356) (xy 295.101518 -367.47577) (xy 295.09593 -367.483898)
			(xy 295.078012 -367.508329) (xy 295.037275 -367.553177) (xy 294.9915 -367.59287) (xy 294.941335 -367.626846)
			(xy 294.887491 -367.654626) (xy 294.83073 -367.675815) (xy 294.771853 -367.690114) (xy 294.711696 -367.697321)
			(xy 294.681402 -367.697766) (xy 294.649442 -367.697285) (xy 294.586027 -367.689274) (xy 294.524115 -367.673378)
			(xy 294.464684 -367.649848) (xy 294.408671 -367.619055) (xy 294.356959 -367.581484) (xy 294.310363 -367.537728)
			(xy 294.269619 -367.488477) (xy 294.235369 -367.434508) (xy 294.208154 -367.376672) (xy 294.188401 -367.315881)
			(xy 294.176424 -367.253093) (xy 294.17241 -367.1893) (xy 294.176424 -367.125507) (xy 294.188401 -367.062719)
			(xy 294.208154 -367.001928) (xy 294.235369 -366.944092) (xy 294.269619 -366.890123) (xy 294.310363 -366.840872)
			(xy 294.356959 -366.797116) (xy 294.408671 -366.759545) (xy 294.464684 -366.728752) (xy 294.524115 -366.705222)
			(xy 294.586027 -366.689326) (xy 294.649442 -366.681315) (xy 294.681402 -366.68075) (xy 294.712997 -366.681229)
			(xy 294.7757 -366.68906) (xy 294.83695 -366.7046) (xy 294.895801 -366.727611) (xy 294.951348 -366.757737)
			(xy 294.977312 -366.775746) (xy 294.98604 -366.781439) (xy 295.006372 -366.785897) (xy 295.016682 -366.784382)
			(xy 295.04767 -366.778286) (xy 295.057754 -366.775909) (xy 295.074939 -366.764375) (xy 295.080944 -366.755934)
			(xy 295.091104 -366.74044) (xy 295.101772 -366.7252) (xy 295.09847 -366.688878) (xy 294.440102 -366.03051)
			(xy 294.432704 -366.023662) (xy 294.414106 -366.015925) (xy 294.404034 -366.015524) (xy 283.114242 -366.015524)
			(xy 283.104176 -366.015091) (xy 283.085584 -366.007364) (xy 283.078174 -366.000538) (xy 282.518358 -365.440722)
			(xy 282.511517 -365.433322) (xy 282.503802 -365.414723) (xy 282.503372 -365.404654) (xy 282.503372 -362.013754)
			(xy 282.50294 -362.003688) (xy 282.495211 -361.985098) (xy 282.488386 -361.977686) (xy 281.417014 -360.906314)
			(xy 281.409611 -360.89948) (xy 281.391013 -360.891774) (xy 281.380946 -360.891328) (xy 276.40153 -360.891328)
			(xy 276.391479 -360.890824) (xy 276.372915 -360.883106) (xy 276.365462 -360.876342) (xy 274.74672 -359.2576)
			(xy 274.739317 -359.250766) (xy 274.720719 -359.243061) (xy 274.710652 -359.242614) (xy 270.950436 -359.242614)
			(xy 270.940371 -359.24218) (xy 270.921782 -359.234451) (xy 270.914368 -359.227628) (xy 261.847838 -350.161098)
			(xy 261.840988 -350.153701) (xy 261.833248 -350.135103) (xy 261.832852 -350.12503) (xy 261.832852 -330.793344)
			(xy 261.832417 -330.783279) (xy 261.824683 -330.764694) (xy 261.817866 -330.757276) (xy 258.895088 -327.834498)
			(xy 258.879086 -327.827132) (xy 258.870196 -327.826116) (xy 258.855826 -327.824657) (xy 258.827347 -327.819827)
			(xy 258.8133 -327.816464) (xy 258.804156 -327.814178) (xy 258.785868 -327.816464) (xy 258.708906 -327.857104)
			(xy 258.696714 -327.871074) (xy 258.693412 -327.879964) (xy 258.682845 -327.907013) (xy 258.654706 -327.957811)
			(xy 258.619195 -328.003757) (xy 258.577132 -328.043792) (xy 258.529487 -328.07699) (xy 258.477362 -328.102585)
			(xy 258.42196 -328.119985) (xy 258.364561 -328.128789) (xy 258.335526 -328.129392) (xy 258.308272 -328.12893)
			(xy 258.254319 -328.121176) (xy 258.202019 -328.105822) (xy 258.152437 -328.083181) (xy 258.106582 -328.053714)
			(xy 258.065387 -328.01802) (xy 258.029692 -327.976826) (xy 258.000224 -327.930972) (xy 257.977581 -327.88139)
			(xy 257.962226 -327.82909) (xy 257.95447 -327.775138) (xy 257.954018 -327.747884) (xy 257.95448 -327.720572)
			(xy 257.962263 -327.666506) (xy 257.977682 -327.614104) (xy 258.000421 -327.564438) (xy 258.030015 -327.518526)
			(xy 258.065858 -327.477307) (xy 258.107216 -327.441625) (xy 258.153243 -327.41221) (xy 258.202997 -327.389664)
			(xy 258.2291 -327.381616) (xy 258.242054 -327.377806) (xy 258.26085 -327.358502) (xy 258.285996 -327.260712)
			(xy 258.287841 -327.252106) (xy 258.286216 -327.234594) (xy 258.278752 -327.21867) (xy 258.272788 -327.212198)
			(xy 258.243832 -327.183242) (xy 258.236991 -327.175842) (xy 258.229273 -327.157243) (xy 258.228846 -327.147174)
			(xy 258.228846 -306.765706) (xy 258.228422 -306.755636) (xy 258.220704 -306.737036) (xy 258.21386 -306.729638)
			(xy 257.900424 -306.416202) (xy 257.893021 -306.409367) (xy 257.874423 -306.40166) (xy 257.864356 -306.401216)
			(xy 238.092742 -306.401216) (xy 238.082677 -306.40165) (xy 238.064089 -306.409381) (xy 238.056674 -306.416202)
			(xy 237.400338 -307.072538) (xy 237.393494 -307.079937) (xy 237.385767 -307.098535) (xy 237.385352 -307.108606)
			(xy 237.385352 -316.901576) (xy 237.385806 -316.91206) (xy 237.394097 -316.931312) (xy 237.409418 -316.945618)
			(xy 237.419134 -316.949582) (xy 237.524798 -316.987174) (xy 237.555532 -316.978538) (xy 237.565692 -316.965838)
			(xy 237.583908 -316.944212) (xy 237.625633 -316.906055) (xy 237.672534 -316.874477) (xy 237.723584 -316.850169)
			(xy 237.777662 -316.833665) (xy 237.833585 -316.825325) (xy 237.861856 -316.824868) (xy 237.889113 -316.825328)
			(xy 237.943072 -316.83308) (xy 237.995378 -316.848433) (xy 238.044967 -316.871075) (xy 238.090829 -316.900544)
			(xy 238.132029 -316.93624) (xy 238.16773 -316.977436) (xy 238.197204 -317.023294) (xy 238.219851 -317.07288)
			(xy 238.23521 -317.125185) (xy 238.242969 -317.179143) (xy 238.242969 -317.22568) (xy 238.579406 -317.22568)
			(xy 238.579979 -317.196765) (xy 238.588697 -317.139596) (xy 238.605943 -317.084398) (xy 238.631325 -317.032436)
			(xy 238.664259 -316.984901) (xy 238.703991 -316.942882) (xy 238.726472 -316.92469) (xy 238.735246 -316.91714)
			(xy 238.74542 -316.896372) (xy 238.74603 -316.884812) (xy 238.74603 -316.804548) (xy 238.745456 -316.79298)
			(xy 238.735266 -316.772207) (xy 238.726472 -316.76467) (xy 238.703968 -316.746503) (xy 238.664236 -316.704477)
			(xy 238.6313 -316.656937) (xy 238.605915 -316.604971) (xy 238.588663 -316.54977) (xy 238.579939 -316.492597)
			(xy 238.579406 -316.46368) (xy 238.579892 -316.436429) (xy 238.587648 -316.382481) (xy 238.603003 -316.330186)
			(xy 238.625645 -316.280609) (xy 238.655111 -316.234759) (xy 238.690802 -316.193568) (xy 238.731993 -316.157877)
			(xy 238.777843 -316.128411) (xy 238.82742 -316.105769) (xy 238.879715 -316.090414) (xy 238.933663 -316.082658)
			(xy 238.988165 -316.082658) (xy 239.042113 -316.090414) (xy 239.094408 -316.105769) (xy 239.143985 -316.128411)
			(xy 239.189835 -316.157877) (xy 239.231026 -316.193568) (xy 239.266717 -316.234759) (xy 239.296183 -316.280609)
			(xy 239.318825 -316.330186) (xy 239.33418 -316.382481) (xy 239.341936 -316.436429) (xy 239.342422 -316.46368)
			(xy 239.341919 -316.492598) (xy 239.333191 -316.549771) (xy 239.315932 -316.604972) (xy 239.290538 -316.656934)
			(xy 239.25759 -316.704467) (xy 239.217844 -316.746482) (xy 239.195356 -316.76467) (xy 239.186605 -316.772242)
			(xy 239.176417 -316.792993) (xy 239.175798 -316.804548) (xy 239.175798 -316.884812) (xy 239.176362 -316.896381)
			(xy 239.186561 -316.917151) (xy 239.195356 -316.92469) (xy 239.217826 -316.942898) (xy 239.257564 -316.984913)
			(xy 239.290506 -317.032444) (xy 239.315897 -317.084402) (xy 239.333155 -317.139597) (xy 239.341886 -317.196765)
			(xy 239.342422 -317.22568) (xy 239.342021 -317.252375) (xy 239.334597 -317.305247) (xy 239.319876 -317.356567)
			(xy 239.298146 -317.405336) (xy 239.269832 -317.450599) (xy 239.235486 -317.491475) (xy 239.21593 -317.509652)
			(xy 239.207294 -317.517272) (xy 239.198404 -317.5381) (xy 239.202976 -317.6397) (xy 239.21339 -317.659512)
			(xy 239.222788 -317.66637) (xy 239.246075 -317.684499) (xy 239.287267 -317.726759) (xy 239.321465 -317.774855)
			(xy 239.347854 -317.827641) (xy 239.365805 -317.88386) (xy 239.37489 -317.942171) (xy 239.375442 -317.971678)
			(xy 239.374956 -317.998929) (xy 239.3672 -318.052877) (xy 239.351845 -318.105172) (xy 239.329203 -318.154749)
			(xy 239.299737 -318.200599) (xy 239.264046 -318.24179) (xy 239.222855 -318.277481) (xy 239.177005 -318.306947)
			(xy 239.127428 -318.329589) (xy 239.075133 -318.344944) (xy 239.021185 -318.3527) (xy 238.966683 -318.3527)
			(xy 238.912735 -318.344944) (xy 238.86044 -318.329589) (xy 238.810863 -318.306947) (xy 238.765013 -318.277481)
			(xy 238.723822 -318.24179) (xy 238.688131 -318.200599) (xy 238.658665 -318.154749) (xy 238.636023 -318.105172)
			(xy 238.620668 -318.052877) (xy 238.612912 -317.998929) (xy 238.612426 -317.971678) (xy 238.612883 -317.944985)
			(xy 238.620299 -317.892117) (xy 238.635009 -317.840798) (xy 238.656728 -317.79203) (xy 238.685032 -317.746764)
			(xy 238.719367 -317.705885) (xy 238.738918 -317.687706) (xy 238.747554 -317.680086) (xy 238.756444 -317.659258)
			(xy 238.751872 -317.557658) (xy 238.741458 -317.537846) (xy 238.73206 -317.530988) (xy 238.708805 -317.512817)
			(xy 238.6676 -317.470574) (xy 238.633391 -317.422489) (xy 238.606994 -317.369709) (xy 238.589039 -317.313495)
			(xy 238.579955 -317.255186) (xy 238.579406 -317.22568) (xy 238.242969 -317.22568) (xy 238.242969 -317.233657)
			(xy 238.23521 -317.287615) (xy 238.219851 -317.33992) (xy 238.197204 -317.389506) (xy 238.16773 -317.435364)
			(xy 238.132029 -317.47656) (xy 238.090829 -317.512256) (xy 238.044967 -317.541725) (xy 237.995378 -317.564367)
			(xy 237.943072 -317.57972) (xy 237.889113 -317.587472) (xy 237.861856 -317.587884) (xy 237.833589 -317.587369)
			(xy 237.777674 -317.579024) (xy 237.723602 -317.562522) (xy 237.672556 -317.538224) (xy 237.625651 -317.506663)
			(xy 237.583916 -317.468528) (xy 237.565692 -317.446914) (xy 237.555532 -317.434214) (xy 237.524798 -317.425578)
			(xy 237.419134 -317.46317) (xy 237.409441 -317.467171) (xy 237.394145 -317.481485) (xy 237.385805 -317.500702)
			(xy 237.385352 -317.511176) (xy 237.385352 -318.70448) (xy 239.823475 -318.70448) (xy 239.827208 -318.651225)
			(xy 239.838329 -318.59901) (xy 239.856619 -318.548855) (xy 239.881723 -318.50174) (xy 239.91315 -318.458584)
			(xy 239.950286 -318.420231) (xy 239.971072 -318.403478) (xy 239.979851 -318.395934) (xy 239.990022 -318.375161)
			(xy 239.99063 -318.3636) (xy 239.99063 -318.283336) (xy 239.990063 -318.271767) (xy 239.979869 -318.250994)
			(xy 239.971072 -318.243458) (xy 239.948563 -318.225298) (xy 239.90883 -318.183271) (xy 239.875895 -318.135729)
			(xy 239.850511 -318.083762) (xy 239.833261 -318.028559) (xy 239.824538 -317.971386) (xy 239.824006 -317.942468)
			(xy 239.824492 -317.915217) (xy 239.832248 -317.861269) (xy 239.847603 -317.808974) (xy 239.870245 -317.759397)
			(xy 239.899711 -317.713547) (xy 239.935402 -317.672356) (xy 239.976593 -317.636665) (xy 240.022443 -317.607199)
			(xy 240.07202 -317.584557) (xy 240.124315 -317.569202) (xy 240.178263 -317.561446) (xy 240.232765 -317.561446)
			(xy 240.286713 -317.569202) (xy 240.339008 -317.584557) (xy 240.388585 -317.607199) (xy 240.434435 -317.636665)
			(xy 240.475626 -317.672356) (xy 240.511317 -317.713547) (xy 240.540783 -317.759397) (xy 240.563425 -317.808974)
			(xy 240.57878 -317.861269) (xy 240.586536 -317.915217) (xy 240.587022 -317.942468) (xy 240.58651 -317.971386)
			(xy 240.577784 -318.028558) (xy 240.560527 -318.083759) (xy 240.535134 -318.135721) (xy 240.502188 -318.183255)
			(xy 240.462443 -318.225269) (xy 240.439956 -318.243458) (xy 240.43121 -318.251035) (xy 240.42102 -318.271783)
			(xy 240.420398 -318.283336) (xy 240.420398 -318.3636) (xy 240.420969 -318.375168) (xy 240.431163 -318.395939)
			(xy 240.439956 -318.403478) (xy 240.460707 -318.420269) (xy 240.497835 -318.458619) (xy 240.529256 -318.501769)
			(xy 240.554354 -318.548878) (xy 240.572641 -318.599026) (xy 240.583759 -318.651233) (xy 240.587492 -318.70448)
			(xy 242.211075 -318.70448) (xy 242.214808 -318.651225) (xy 242.225929 -318.59901) (xy 242.244219 -318.548855)
			(xy 242.269323 -318.50174) (xy 242.30075 -318.458584) (xy 242.337886 -318.420231) (xy 242.358672 -318.403478)
			(xy 242.367451 -318.395934) (xy 242.377622 -318.375161) (xy 242.37823 -318.3636) (xy 242.37823 -318.283336)
			(xy 242.377663 -318.271767) (xy 242.367469 -318.250994) (xy 242.358672 -318.243458) (xy 242.336163 -318.225298)
			(xy 242.29643 -318.183271) (xy 242.263495 -318.135729) (xy 242.238111 -318.083762) (xy 242.220861 -318.028559)
			(xy 242.212138 -317.971386) (xy 242.211606 -317.942468) (xy 242.212081 -317.914872) (xy 242.220051 -317.860258)
			(xy 242.235805 -317.807362) (xy 242.259015 -317.757287) (xy 242.289197 -317.711078) (xy 242.32572 -317.669699)
			(xy 242.367824 -317.634013) (xy 242.414629 -317.604764) (xy 242.439698 -317.593218) (xy 242.450112 -317.588646)
			(xy 242.464844 -317.571628) (xy 242.49253 -317.474092) (xy 242.488974 -317.451994) (xy 242.48237 -317.442342)
			(xy 242.466424 -317.418329) (xy 242.441172 -317.366513) (xy 242.424011 -317.311485) (xy 242.415334 -317.254501)
			(xy 242.414806 -317.22568) (xy 242.415379 -317.196765) (xy 242.424097 -317.139596) (xy 242.441343 -317.084398)
			(xy 242.466725 -317.032436) (xy 242.499659 -316.984901) (xy 242.539391 -316.942882) (xy 242.561872 -316.92469)
			(xy 242.570646 -316.91714) (xy 242.58082 -316.896372) (xy 242.58143 -316.884812) (xy 242.58143 -316.804548)
			(xy 242.580856 -316.79298) (xy 242.570666 -316.772207) (xy 242.561872 -316.76467) (xy 242.539368 -316.746503)
			(xy 242.499636 -316.704477) (xy 242.4667 -316.656937) (xy 242.441315 -316.604971) (xy 242.424063 -316.54977)
			(xy 242.415339 -316.492597) (xy 242.414806 -316.46368) (xy 242.415292 -316.436429) (xy 242.423048 -316.382481)
			(xy 242.438403 -316.330186) (xy 242.461045 -316.280609) (xy 242.490511 -316.234759) (xy 242.526202 -316.193568)
			(xy 242.567393 -316.157877) (xy 242.613243 -316.128411) (xy 242.66282 -316.105769) (xy 242.715115 -316.090414)
			(xy 242.769063 -316.082658) (xy 242.823565 -316.082658) (xy 242.877513 -316.090414) (xy 242.929808 -316.105769)
			(xy 242.979385 -316.128411) (xy 243.025235 -316.157877) (xy 243.066426 -316.193568) (xy 243.102117 -316.234759)
			(xy 243.131583 -316.280609) (xy 243.154225 -316.330186) (xy 243.16958 -316.382481) (xy 243.177336 -316.436429)
			(xy 243.177822 -316.46368) (xy 243.177319 -316.492598) (xy 243.168591 -316.549771) (xy 243.151332 -316.604972)
			(xy 243.125938 -316.656934) (xy 243.09299 -316.704467) (xy 243.053244 -316.746482) (xy 243.030756 -316.76467)
			(xy 243.022005 -316.772242) (xy 243.011817 -316.792993) (xy 243.011198 -316.804548) (xy 243.011198 -316.884812)
			(xy 243.011762 -316.896381) (xy 243.021961 -316.917151) (xy 243.030756 -316.92469) (xy 243.053226 -316.942898)
			(xy 243.092964 -316.984913) (xy 243.125906 -317.032444) (xy 243.151297 -317.084402) (xy 243.168555 -317.139597)
			(xy 243.177286 -317.196765) (xy 243.177822 -317.22568) (xy 244.472206 -317.22568) (xy 244.472779 -317.196765)
			(xy 244.481497 -317.139596) (xy 244.498743 -317.084398) (xy 244.524125 -317.032436) (xy 244.557059 -316.984901)
			(xy 244.596791 -316.942882) (xy 244.619272 -316.92469) (xy 244.628046 -316.91714) (xy 244.63822 -316.896372)
			(xy 244.63883 -316.884812) (xy 244.63883 -316.804548) (xy 244.638256 -316.79298) (xy 244.628066 -316.772207)
			(xy 244.619272 -316.76467) (xy 244.596768 -316.746503) (xy 244.557036 -316.704477) (xy 244.5241 -316.656937)
			(xy 244.498715 -316.604971) (xy 244.481463 -316.54977) (xy 244.472739 -316.492597) (xy 244.472206 -316.46368)
			(xy 244.472692 -316.436429) (xy 244.480448 -316.382481) (xy 244.495803 -316.330186) (xy 244.518445 -316.280609)
			(xy 244.547911 -316.234759) (xy 244.583602 -316.193568) (xy 244.624793 -316.157877) (xy 244.670643 -316.128411)
			(xy 244.72022 -316.105769) (xy 244.772515 -316.090414) (xy 244.826463 -316.082658) (xy 244.880965 -316.082658)
			(xy 244.934913 -316.090414) (xy 244.987208 -316.105769) (xy 245.036785 -316.128411) (xy 245.082635 -316.157877)
			(xy 245.123826 -316.193568) (xy 245.159517 -316.234759) (xy 245.188983 -316.280609) (xy 245.211625 -316.330186)
			(xy 245.22698 -316.382481) (xy 245.234736 -316.436429) (xy 245.235222 -316.46368) (xy 245.234719 -316.492598)
			(xy 245.225991 -316.549771) (xy 245.208732 -316.604972) (xy 245.183338 -316.656934) (xy 245.15039 -316.704467)
			(xy 245.110644 -316.746482) (xy 245.088156 -316.76467) (xy 245.079405 -316.772242) (xy 245.069217 -316.792993)
			(xy 245.068598 -316.804548) (xy 245.068598 -316.884812) (xy 245.069162 -316.896381) (xy 245.079361 -316.917151)
			(xy 245.088156 -316.92469) (xy 245.110626 -316.942898) (xy 245.150364 -316.984913) (xy 245.183306 -317.032444)
			(xy 245.208697 -317.084402) (xy 245.225955 -317.139597) (xy 245.234686 -317.196765) (xy 245.235222 -317.22568)
			(xy 245.23473 -317.253149) (xy 245.226852 -317.307519) (xy 245.211258 -317.360196) (xy 245.188269 -317.410093)
			(xy 245.158361 -317.456175) (xy 245.122152 -317.497492) (xy 245.080391 -317.533187) (xy 245.057422 -317.54826)
			(xy 245.045992 -317.555372) (xy 245.033546 -317.57874) (xy 245.035832 -317.692786) (xy 245.049294 -317.715646)
			(xy 245.060978 -317.72225) (xy 245.08549 -317.736983) (xy 245.130248 -317.772578) (xy 245.169193 -317.814455)
			(xy 245.201451 -317.861676) (xy 245.226301 -317.913181) (xy 245.243186 -317.967819) (xy 245.251727 -318.024365)
			(xy 245.25224 -318.052958) (xy 245.251754 -318.080209) (xy 245.243998 -318.134157) (xy 245.228643 -318.186452)
			(xy 245.206001 -318.236029) (xy 245.176535 -318.281879) (xy 245.140844 -318.32307) (xy 245.099653 -318.358761)
			(xy 245.053803 -318.388227) (xy 245.004226 -318.410869) (xy 244.951931 -318.426224) (xy 244.897983 -318.43398)
			(xy 244.843481 -318.43398) (xy 244.789533 -318.426224) (xy 244.737238 -318.410869) (xy 244.687661 -318.388227)
			(xy 244.641811 -318.358761) (xy 244.60062 -318.32307) (xy 244.564929 -318.281879) (xy 244.535463 -318.236029)
			(xy 244.512821 -318.186452) (xy 244.497466 -318.134157) (xy 244.48971 -318.080209) (xy 244.489224 -318.052958)
			(xy 244.489724 -318.025489) (xy 244.497597 -317.971119) (xy 244.513189 -317.91844) (xy 244.536176 -317.868543)
			(xy 244.566084 -317.82246) (xy 244.602293 -317.781144) (xy 244.644055 -317.74545) (xy 244.667024 -317.730378)
			(xy 244.678454 -317.723266) (xy 244.6909 -317.699898) (xy 244.688614 -317.585852) (xy 244.675152 -317.562992)
			(xy 244.663468 -317.556388) (xy 244.638916 -317.541719) (xy 244.59416 -317.506111) (xy 244.55522 -317.464222)
			(xy 244.522967 -317.416991) (xy 244.498124 -317.365475) (xy 244.481247 -317.310829) (xy 244.472714 -317.254276)
			(xy 244.472206 -317.22568) (xy 243.177822 -317.22568) (xy 243.177287 -317.253274) (xy 243.169325 -317.307884)
			(xy 243.153579 -317.360778) (xy 243.130377 -317.410852) (xy 243.100204 -317.457061) (xy 243.063689 -317.498441)
			(xy 243.021593 -317.53413) (xy 242.974796 -317.563381) (xy 242.94973 -317.57493) (xy 242.939316 -317.579502)
			(xy 242.924584 -317.59652) (xy 242.896898 -317.694056) (xy 242.900454 -317.716154) (xy 242.907058 -317.725806)
			(xy 242.923028 -317.749804) (xy 242.948274 -317.801626) (xy 242.965428 -317.856658) (xy 242.974098 -317.913646)
			(xy 242.974622 -317.942468) (xy 242.97411 -317.971386) (xy 242.965384 -318.028558) (xy 242.948127 -318.083759)
			(xy 242.922734 -318.135721) (xy 242.889788 -318.183255) (xy 242.850043 -318.225269) (xy 242.827556 -318.243458)
			(xy 242.81881 -318.251035) (xy 242.80862 -318.271783) (xy 242.807998 -318.283336) (xy 242.807998 -318.3636)
			(xy 242.808569 -318.375168) (xy 242.818763 -318.395939) (xy 242.827556 -318.403478) (xy 242.848307 -318.420269)
			(xy 242.885435 -318.458619) (xy 242.916856 -318.501769) (xy 242.941954 -318.548878) (xy 242.960241 -318.599026)
			(xy 242.971359 -318.651233) (xy 242.975092 -318.70448) (xy 245.919475 -318.70448) (xy 245.923208 -318.651225)
			(xy 245.934329 -318.59901) (xy 245.952619 -318.548855) (xy 245.977723 -318.50174) (xy 246.00915 -318.458584)
			(xy 246.046286 -318.420231) (xy 246.067072 -318.403478) (xy 246.075851 -318.395934) (xy 246.086022 -318.375161)
			(xy 246.08663 -318.3636) (xy 246.08663 -318.283336) (xy 246.086063 -318.271767) (xy 246.075869 -318.250994)
			(xy 246.067072 -318.243458) (xy 246.044563 -318.225298) (xy 246.00483 -318.183271) (xy 245.971895 -318.135729)
			(xy 245.946511 -318.083762) (xy 245.929261 -318.028559) (xy 245.920538 -317.971386) (xy 245.920006 -317.942468)
			(xy 245.920492 -317.915217) (xy 245.928248 -317.861269) (xy 245.943603 -317.808974) (xy 245.966245 -317.759397)
			(xy 245.995711 -317.713547) (xy 246.031402 -317.672356) (xy 246.072593 -317.636665) (xy 246.118443 -317.607199)
			(xy 246.16802 -317.584557) (xy 246.220315 -317.569202) (xy 246.274263 -317.561446) (xy 246.328765 -317.561446)
			(xy 246.382713 -317.569202) (xy 246.435008 -317.584557) (xy 246.484585 -317.607199) (xy 246.530435 -317.636665)
			(xy 246.571626 -317.672356) (xy 246.607317 -317.713547) (xy 246.636783 -317.759397) (xy 246.659425 -317.808974)
			(xy 246.67478 -317.861269) (xy 246.682536 -317.915217) (xy 246.683022 -317.942468) (xy 246.68251 -317.971386)
			(xy 246.673784 -318.028558) (xy 246.656527 -318.083759) (xy 246.631134 -318.135721) (xy 246.598188 -318.183255)
			(xy 246.558443 -318.225269) (xy 246.535956 -318.243458) (xy 246.52721 -318.251035) (xy 246.51702 -318.271783)
			(xy 246.516398 -318.283336) (xy 246.516398 -318.3636) (xy 246.516969 -318.375168) (xy 246.527163 -318.395939)
			(xy 246.535956 -318.403478) (xy 246.556707 -318.420269) (xy 246.593835 -318.458619) (xy 246.625256 -318.501769)
			(xy 246.650354 -318.548878) (xy 246.668641 -318.599026) (xy 246.679759 -318.651233) (xy 246.683492 -318.70448)
			(xy 248.307075 -318.70448) (xy 248.310808 -318.651225) (xy 248.321929 -318.59901) (xy 248.340219 -318.548855)
			(xy 248.365323 -318.50174) (xy 248.39675 -318.458584) (xy 248.433886 -318.420231) (xy 248.454672 -318.403478)
			(xy 248.463451 -318.395934) (xy 248.473622 -318.375161) (xy 248.47423 -318.3636) (xy 248.47423 -318.283336)
			(xy 248.473663 -318.271767) (xy 248.463469 -318.250994) (xy 248.454672 -318.243458) (xy 248.432163 -318.225298)
			(xy 248.39243 -318.183271) (xy 248.359495 -318.135729) (xy 248.334111 -318.083762) (xy 248.316861 -318.028559)
			(xy 248.308138 -317.971386) (xy 248.307606 -317.942468) (xy 248.308023 -317.915885) (xy 248.315415 -317.863236)
			(xy 248.33005 -317.812124) (xy 248.351646 -317.763541) (xy 248.379782 -317.718431) (xy 248.413913 -317.677667)
			(xy 248.433336 -317.659512) (xy 248.440859 -317.651897) (xy 248.449528 -317.632354) (xy 248.4501 -317.621666)
			(xy 248.4501 -317.546482) (xy 248.449667 -317.535759) (xy 248.440993 -317.516154) (xy 248.433336 -317.508636)
			(xy 248.413902 -317.490495) (xy 248.379783 -317.449724) (xy 248.351658 -317.404608) (xy 248.330074 -317.356023)
			(xy 248.315449 -317.304911) (xy 248.308066 -317.252262) (xy 248.307606 -317.22568) (xy 248.308179 -317.196765)
			(xy 248.316897 -317.139596) (xy 248.334143 -317.084398) (xy 248.359525 -317.032436) (xy 248.392459 -316.984901)
			(xy 248.432191 -316.942882) (xy 248.454672 -316.92469) (xy 248.463446 -316.91714) (xy 248.47362 -316.896372)
			(xy 248.47423 -316.884812) (xy 248.47423 -316.804548) (xy 248.473656 -316.79298) (xy 248.463466 -316.772207)
			(xy 248.454672 -316.76467) (xy 248.432168 -316.746503) (xy 248.392436 -316.704477) (xy 248.3595 -316.656937)
			(xy 248.334115 -316.604971) (xy 248.316863 -316.54977) (xy 248.308139 -316.492597) (xy 248.307606 -316.46368)
			(xy 248.308092 -316.436429) (xy 248.315848 -316.382481) (xy 248.331203 -316.330186) (xy 248.353845 -316.280609)
			(xy 248.383311 -316.234759) (xy 248.419002 -316.193568) (xy 248.460193 -316.157877) (xy 248.506043 -316.128411)
			(xy 248.55562 -316.105769) (xy 248.607915 -316.090414) (xy 248.661863 -316.082658) (xy 248.716365 -316.082658)
			(xy 248.770313 -316.090414) (xy 248.822608 -316.105769) (xy 248.872185 -316.128411) (xy 248.918035 -316.157877)
			(xy 248.959226 -316.193568) (xy 248.994917 -316.234759) (xy 249.024383 -316.280609) (xy 249.047025 -316.330186)
			(xy 249.06238 -316.382481) (xy 249.070136 -316.436429) (xy 249.070622 -316.46368) (xy 249.070119 -316.492598)
			(xy 249.061391 -316.549771) (xy 249.044132 -316.604972) (xy 249.018738 -316.656934) (xy 248.98579 -316.704467)
			(xy 248.946044 -316.746482) (xy 248.923556 -316.76467) (xy 248.914805 -316.772242) (xy 248.904617 -316.792993)
			(xy 248.903998 -316.804548) (xy 248.903998 -316.884812) (xy 248.904562 -316.896381) (xy 248.914761 -316.917151)
			(xy 248.923556 -316.92469) (xy 248.946026 -316.942898) (xy 248.985764 -316.984913) (xy 249.018706 -317.032444)
			(xy 249.044097 -317.084402) (xy 249.061355 -317.139597) (xy 249.070086 -317.196765) (xy 249.070622 -317.22568)
			(xy 249.070161 -317.252261) (xy 249.062777 -317.304908) (xy 249.048149 -317.356019) (xy 249.026562 -317.404601)
			(xy 248.998434 -317.449713) (xy 248.964311 -317.490479) (xy 248.944892 -317.508636) (xy 248.937352 -317.516237)
			(xy 248.928691 -317.53579) (xy 248.928128 -317.546482) (xy 248.928128 -317.621666) (xy 248.928556 -317.632389)
			(xy 248.937236 -317.651993) (xy 248.944892 -317.659512) (xy 248.964287 -317.677694) (xy 248.998413 -317.718454)
			(xy 249.026544 -317.763561) (xy 249.048135 -317.812138) (xy 249.062768 -317.863244) (xy 249.070159 -317.915888)
			(xy 249.070622 -317.942468) (xy 249.07011 -317.971386) (xy 249.061384 -318.028558) (xy 249.044127 -318.083759)
			(xy 249.018734 -318.135721) (xy 248.985788 -318.183255) (xy 248.946043 -318.225269) (xy 248.923556 -318.243458)
			(xy 248.91481 -318.251035) (xy 248.90462 -318.271783) (xy 248.903998 -318.283336) (xy 248.903998 -318.3636)
			(xy 248.904569 -318.375168) (xy 248.914763 -318.395939) (xy 248.923556 -318.403478) (xy 248.944307 -318.420269)
			(xy 248.981435 -318.458619) (xy 249.012856 -318.501769) (xy 249.037954 -318.548878) (xy 249.056241 -318.599026)
			(xy 249.067359 -318.651233) (xy 249.071092 -318.70448) (xy 249.067365 -318.757728) (xy 249.056252 -318.809936)
			(xy 249.03797 -318.860086) (xy 249.012877 -318.907197) (xy 248.981461 -318.950351) (xy 248.944336 -318.988704)
			(xy 248.923556 -319.005458) (xy 248.91481 -319.013035) (xy 248.90462 -319.033783) (xy 248.903998 -319.045336)
			(xy 248.903998 -319.1256) (xy 248.904569 -319.137168) (xy 248.914763 -319.157939) (xy 248.923556 -319.165478)
			(xy 248.94602 -319.183693) (xy 248.985758 -319.225706) (xy 249.018701 -319.273236) (xy 249.044093 -319.325193)
			(xy 249.061353 -319.380387) (xy 249.070085 -319.437553) (xy 249.070622 -319.466468) (xy 249.070136 -319.493719)
			(xy 249.06238 -319.547667) (xy 249.047025 -319.599962) (xy 249.024383 -319.649539) (xy 248.994917 -319.695389)
			(xy 248.959226 -319.73658) (xy 248.918035 -319.772271) (xy 248.872185 -319.801737) (xy 248.822608 -319.824379)
			(xy 248.770313 -319.839734) (xy 248.716365 -319.84749) (xy 248.661863 -319.84749) (xy 248.607915 -319.839734)
			(xy 248.55562 -319.824379) (xy 248.506043 -319.801737) (xy 248.460193 -319.772271) (xy 248.419002 -319.73658)
			(xy 248.383311 -319.695389) (xy 248.353845 -319.649539) (xy 248.331203 -319.599962) (xy 248.315848 -319.547667)
			(xy 248.308092 -319.493719) (xy 248.307606 -319.466468) (xy 248.308171 -319.437553) (xy 248.31689 -319.380384)
			(xy 248.334138 -319.325186) (xy 248.359521 -319.273224) (xy 248.392457 -319.225689) (xy 248.43219 -319.18367)
			(xy 248.454672 -319.165478) (xy 248.463451 -319.157934) (xy 248.473622 -319.137161) (xy 248.47423 -319.1256)
			(xy 248.47423 -319.045336) (xy 248.473663 -319.033767) (xy 248.463469 -319.012994) (xy 248.454672 -319.005458)
			(xy 248.433857 -318.988743) (xy 248.396725 -318.950386) (xy 248.365302 -318.907227) (xy 248.340203 -318.860109)
			(xy 248.321918 -318.809952) (xy 248.310803 -318.757736) (xy 248.307075 -318.70448) (xy 246.683492 -318.70448)
			(xy 246.679765 -318.757728) (xy 246.668652 -318.809936) (xy 246.65037 -318.860086) (xy 246.625277 -318.907197)
			(xy 246.593861 -318.950351) (xy 246.556736 -318.988704) (xy 246.535956 -319.005458) (xy 246.52721 -319.013035)
			(xy 246.51702 -319.033783) (xy 246.516398 -319.045336) (xy 246.516398 -319.1256) (xy 246.516969 -319.137168)
			(xy 246.527163 -319.157939) (xy 246.535956 -319.165478) (xy 246.55842 -319.183693) (xy 246.598158 -319.225706)
			(xy 246.631101 -319.273236) (xy 246.656493 -319.325193) (xy 246.673753 -319.380387) (xy 246.682485 -319.437553)
			(xy 246.683022 -319.466468) (xy 246.682536 -319.493719) (xy 246.67478 -319.547667) (xy 246.659425 -319.599962)
			(xy 246.636783 -319.649539) (xy 246.607317 -319.695389) (xy 246.571626 -319.73658) (xy 246.530435 -319.772271)
			(xy 246.484585 -319.801737) (xy 246.435008 -319.824379) (xy 246.382713 -319.839734) (xy 246.328765 -319.84749)
			(xy 246.274263 -319.84749) (xy 246.220315 -319.839734) (xy 246.16802 -319.824379) (xy 246.118443 -319.801737)
			(xy 246.072593 -319.772271) (xy 246.031402 -319.73658) (xy 245.995711 -319.695389) (xy 245.966245 -319.649539)
			(xy 245.943603 -319.599962) (xy 245.928248 -319.547667) (xy 245.920492 -319.493719) (xy 245.920006 -319.466468)
			(xy 245.920571 -319.437553) (xy 245.92929 -319.380384) (xy 245.946538 -319.325186) (xy 245.971921 -319.273224)
			(xy 246.004857 -319.225689) (xy 246.04459 -319.18367) (xy 246.067072 -319.165478) (xy 246.075851 -319.157934)
			(xy 246.086022 -319.137161) (xy 246.08663 -319.1256) (xy 246.08663 -319.045336) (xy 246.086063 -319.033767)
			(xy 246.075869 -319.012994) (xy 246.067072 -319.005458) (xy 246.046257 -318.988743) (xy 246.009125 -318.950386)
			(xy 245.977702 -318.907227) (xy 245.952603 -318.860109) (xy 245.934318 -318.809952) (xy 245.923203 -318.757736)
			(xy 245.919475 -318.70448) (xy 242.975092 -318.70448) (xy 242.971365 -318.757728) (xy 242.960252 -318.809936)
			(xy 242.94197 -318.860086) (xy 242.916877 -318.907197) (xy 242.885461 -318.950351) (xy 242.848336 -318.988704)
			(xy 242.827556 -319.005458) (xy 242.81881 -319.013035) (xy 242.80862 -319.033783) (xy 242.807998 -319.045336)
			(xy 242.807998 -319.1256) (xy 242.808569 -319.137168) (xy 242.818763 -319.157939) (xy 242.827556 -319.165478)
			(xy 242.85002 -319.183693) (xy 242.889758 -319.225706) (xy 242.922701 -319.273236) (xy 242.948093 -319.325193)
			(xy 242.965353 -319.380387) (xy 242.974085 -319.437553) (xy 242.974622 -319.466468) (xy 242.974136 -319.493719)
			(xy 242.96638 -319.547667) (xy 242.951025 -319.599962) (xy 242.928383 -319.649539) (xy 242.898917 -319.695389)
			(xy 242.863226 -319.73658) (xy 242.822035 -319.772271) (xy 242.776185 -319.801737) (xy 242.726608 -319.824379)
			(xy 242.674313 -319.839734) (xy 242.620365 -319.84749) (xy 242.565863 -319.84749) (xy 242.511915 -319.839734)
			(xy 242.45962 -319.824379) (xy 242.410043 -319.801737) (xy 242.364193 -319.772271) (xy 242.323002 -319.73658)
			(xy 242.287311 -319.695389) (xy 242.257845 -319.649539) (xy 242.235203 -319.599962) (xy 242.219848 -319.547667)
			(xy 242.212092 -319.493719) (xy 242.211606 -319.466468) (xy 242.212171 -319.437553) (xy 242.22089 -319.380384)
			(xy 242.238138 -319.325186) (xy 242.263521 -319.273224) (xy 242.296457 -319.225689) (xy 242.33619 -319.18367)
			(xy 242.358672 -319.165478) (xy 242.367451 -319.157934) (xy 242.377622 -319.137161) (xy 242.37823 -319.1256)
			(xy 242.37823 -319.045336) (xy 242.377663 -319.033767) (xy 242.367469 -319.012994) (xy 242.358672 -319.005458)
			(xy 242.337857 -318.988743) (xy 242.300725 -318.950386) (xy 242.269302 -318.907227) (xy 242.244203 -318.860109)
			(xy 242.225918 -318.809952) (xy 242.214803 -318.757736) (xy 242.211075 -318.70448) (xy 240.587492 -318.70448)
			(xy 240.583765 -318.757728) (xy 240.572652 -318.809936) (xy 240.55437 -318.860086) (xy 240.529277 -318.907197)
			(xy 240.497861 -318.950351) (xy 240.460736 -318.988704) (xy 240.439956 -319.005458) (xy 240.43121 -319.013035)
			(xy 240.42102 -319.033783) (xy 240.420398 -319.045336) (xy 240.420398 -319.1256) (xy 240.420969 -319.137168)
			(xy 240.431163 -319.157939) (xy 240.439956 -319.165478) (xy 240.46242 -319.183693) (xy 240.502158 -319.225706)
			(xy 240.535101 -319.273236) (xy 240.560493 -319.325193) (xy 240.577753 -319.380387) (xy 240.586485 -319.437553)
			(xy 240.587022 -319.466468) (xy 240.586536 -319.493719) (xy 240.57878 -319.547667) (xy 240.563425 -319.599962)
			(xy 240.540783 -319.649539) (xy 240.511317 -319.695389) (xy 240.475626 -319.73658) (xy 240.434435 -319.772271)
			(xy 240.388585 -319.801737) (xy 240.339008 -319.824379) (xy 240.286713 -319.839734) (xy 240.232765 -319.84749)
			(xy 240.178263 -319.84749) (xy 240.124315 -319.839734) (xy 240.07202 -319.824379) (xy 240.022443 -319.801737)
			(xy 239.976593 -319.772271) (xy 239.935402 -319.73658) (xy 239.899711 -319.695389) (xy 239.870245 -319.649539)
			(xy 239.847603 -319.599962) (xy 239.832248 -319.547667) (xy 239.824492 -319.493719) (xy 239.824006 -319.466468)
			(xy 239.824571 -319.437553) (xy 239.83329 -319.380384) (xy 239.850538 -319.325186) (xy 239.875921 -319.273224)
			(xy 239.908857 -319.225689) (xy 239.94859 -319.18367) (xy 239.971072 -319.165478) (xy 239.979851 -319.157934)
			(xy 239.990022 -319.137161) (xy 239.99063 -319.1256) (xy 239.99063 -319.045336) (xy 239.990063 -319.033767)
			(xy 239.979869 -319.012994) (xy 239.971072 -319.005458) (xy 239.950257 -318.988743) (xy 239.913125 -318.950386)
			(xy 239.881702 -318.907227) (xy 239.856603 -318.860109) (xy 239.838318 -318.809952) (xy 239.827203 -318.757736)
			(xy 239.823475 -318.70448) (xy 237.385352 -318.70448) (xy 237.385352 -320.866473) (xy 247.984766 -320.866473)
			(xy 247.984766 -320.802551) (xy 247.992777 -320.739133) (xy 248.008674 -320.677219) (xy 248.032206 -320.617786)
			(xy 248.063 -320.561771) (xy 248.100573 -320.510056) (xy 248.14433 -320.463459) (xy 248.193583 -320.422714)
			(xy 248.247554 -320.388463) (xy 248.305393 -320.361246) (xy 248.366186 -320.341493) (xy 248.428976 -320.329515)
			(xy 248.492772 -320.325502) (xy 248.556568 -320.329515) (xy 248.619358 -320.341493) (xy 248.680151 -320.361246)
			(xy 248.73799 -320.388463) (xy 248.791961 -320.422714) (xy 248.841214 -320.463459) (xy 248.884971 -320.510056)
			(xy 248.922544 -320.561771) (xy 248.953338 -320.617786) (xy 248.97687 -320.677219) (xy 248.992767 -320.739133)
			(xy 249.000778 -320.802551) (xy 249.00128 -320.834512) (xy 249.000778 -320.866473) (xy 248.992767 -320.929891)
			(xy 248.97687 -320.991805) (xy 248.953338 -321.051238) (xy 248.922544 -321.107253) (xy 248.884971 -321.158968)
			(xy 248.841214 -321.205565) (xy 248.791961 -321.24631) (xy 248.73799 -321.280561) (xy 248.680151 -321.307778)
			(xy 248.619358 -321.327531) (xy 248.556568 -321.339509) (xy 248.492772 -321.343523) (xy 248.428976 -321.339509)
			(xy 248.366186 -321.327531) (xy 248.305393 -321.307778) (xy 248.247554 -321.280561) (xy 248.193583 -321.24631)
			(xy 248.14433 -321.205565) (xy 248.100573 -321.158968) (xy 248.063 -321.107253) (xy 248.032206 -321.051238)
			(xy 248.008674 -320.991805) (xy 247.992777 -320.929891) (xy 247.984766 -320.866473) (xy 237.385352 -320.866473)
			(xy 237.385352 -321.471544) (xy 238.503968 -321.471544) (xy 238.50447 -321.439583) (xy 238.512481 -321.376165)
			(xy 238.528378 -321.314251) (xy 238.55191 -321.254818) (xy 238.582704 -321.198803) (xy 238.620277 -321.147088)
			(xy 238.664034 -321.100491) (xy 238.713287 -321.059746) (xy 238.767258 -321.025495) (xy 238.825097 -320.998278)
			(xy 238.88589 -320.978525) (xy 238.94868 -320.966547) (xy 239.012476 -320.962534) (xy 239.076272 -320.966547)
			(xy 239.139062 -320.978525) (xy 239.199855 -320.998278) (xy 239.257694 -321.025495) (xy 239.311665 -321.059746)
			(xy 239.360918 -321.100491) (xy 239.404675 -321.147088) (xy 239.442248 -321.198803) (xy 239.473042 -321.254818)
			(xy 239.496574 -321.314251) (xy 239.512471 -321.376165) (xy 239.520482 -321.439583) (xy 239.520984 -321.471544)
			(xy 239.520399 -321.505335) (xy 239.511436 -321.572319) (xy 239.493687 -321.637529) (xy 239.467464 -321.699815)
			(xy 239.433228 -321.758084) (xy 239.391583 -321.811309) (xy 239.384739 -321.818) (xy 242.187982 -321.818)
			(xy 242.192053 -321.762378) (xy 242.204179 -321.707941) (xy 242.224102 -321.65585) (xy 242.251398 -321.607215)
			(xy 242.285484 -321.563072) (xy 242.325633 -321.524363) (xy 242.370991 -321.491912) (xy 242.420591 -321.466411)
			(xy 242.473375 -321.448404) (xy 242.528218 -321.438274) (xy 242.583952 -321.436237) (xy 242.639389 -321.442337)
			(xy 242.693346 -321.456443) (xy 242.744675 -321.478255) (xy 242.792281 -321.507309) (xy 242.835149 -321.542984)
			(xy 242.872366 -321.584521) (xy 242.903139 -321.631034) (xy 242.926811 -321.681531) (xy 242.942879 -321.734938)
			(xy 242.950999 -321.790114) (xy 242.951508 -321.818) (xy 242.950999 -321.845886) (xy 242.942879 -321.901062)
			(xy 242.926811 -321.954469) (xy 242.903139 -322.004966) (xy 242.872366 -322.051479) (xy 242.835149 -322.093016)
			(xy 242.792281 -322.128691) (xy 242.744675 -322.157745) (xy 242.693346 -322.179557) (xy 242.639389 -322.193663)
			(xy 242.583952 -322.199763) (xy 242.528218 -322.197726) (xy 242.473375 -322.187596) (xy 242.420591 -322.169589)
			(xy 242.370991 -322.144088) (xy 242.325633 -322.111637) (xy 242.285484 -322.072928) (xy 242.251398 -322.028785)
			(xy 242.224102 -321.98015) (xy 242.204179 -321.928059) (xy 242.192053 -321.873622) (xy 242.187982 -321.818)
			(xy 239.384739 -321.818) (xy 239.343259 -321.858554) (xy 239.316514 -321.879214) (xy 239.306862 -321.886326)
			(xy 239.296194 -321.907916) (xy 239.296448 -322.013834) (xy 239.30737 -322.035424) (xy 239.317276 -322.042536)
			(xy 239.344475 -322.063121) (xy 239.393624 -322.11042) (xy 239.436008 -322.163865) (xy 239.470865 -322.222498)
			(xy 239.497569 -322.285266) (xy 239.515641 -322.35104) (xy 239.524755 -322.41864) (xy 239.525302 -322.452746)
			(xy 239.5248 -322.484707) (xy 239.516789 -322.548125) (xy 239.500892 -322.610039) (xy 239.47736 -322.669472)
			(xy 239.446566 -322.725487) (xy 239.408993 -322.777202) (xy 239.365236 -322.823799) (xy 239.352905 -322.834)
			(xy 242.187982 -322.834) (xy 242.192053 -322.778378) (xy 242.204179 -322.723941) (xy 242.224102 -322.67185)
			(xy 242.251398 -322.623215) (xy 242.285484 -322.579072) (xy 242.325633 -322.540363) (xy 242.370991 -322.507912)
			(xy 242.420591 -322.482411) (xy 242.473375 -322.464404) (xy 242.528218 -322.454274) (xy 242.583952 -322.452237)
			(xy 242.639389 -322.458337) (xy 242.693346 -322.472443) (xy 242.744675 -322.494255) (xy 242.792281 -322.523309)
			(xy 242.835149 -322.558984) (xy 242.872366 -322.600521) (xy 242.903139 -322.647034) (xy 242.926811 -322.697531)
			(xy 242.942879 -322.750938) (xy 242.950999 -322.806114) (xy 242.951508 -322.834) (xy 242.950999 -322.861886)
			(xy 242.942879 -322.917062) (xy 242.926811 -322.970469) (xy 242.903139 -323.020966) (xy 242.872366 -323.067479)
			(xy 242.835149 -323.109016) (xy 242.792281 -323.144691) (xy 242.744675 -323.173745) (xy 242.693346 -323.195557)
			(xy 242.639389 -323.209663) (xy 242.583952 -323.215763) (xy 242.528218 -323.213726) (xy 242.473375 -323.203596)
			(xy 242.420591 -323.185589) (xy 242.370991 -323.160088) (xy 242.325633 -323.127637) (xy 242.285484 -323.088928)
			(xy 242.251398 -323.044785) (xy 242.224102 -322.99615) (xy 242.204179 -322.944059) (xy 242.192053 -322.889622)
			(xy 242.187982 -322.834) (xy 239.352905 -322.834) (xy 239.315983 -322.864544) (xy 239.262012 -322.898795)
			(xy 239.204173 -322.926012) (xy 239.14338 -322.945765) (xy 239.08059 -322.957743) (xy 239.016794 -322.961757)
			(xy 238.952998 -322.957743) (xy 238.890208 -322.945765) (xy 238.829415 -322.926012) (xy 238.771576 -322.898795)
			(xy 238.717605 -322.864544) (xy 238.668352 -322.823799) (xy 238.624595 -322.777202) (xy 238.587022 -322.725487)
			(xy 238.556228 -322.669472) (xy 238.532696 -322.610039) (xy 238.516799 -322.548125) (xy 238.508788 -322.484707)
			(xy 238.508286 -322.452746) (xy 238.508836 -322.418954) (xy 238.517801 -322.351967) (xy 238.535554 -322.286755)
			(xy 238.561782 -322.224467) (xy 238.596024 -322.166199) (xy 238.637677 -322.112976) (xy 238.686007 -322.065733)
			(xy 238.712756 -322.045076) (xy 238.722408 -322.037964) (xy 238.733076 -322.016374) (xy 238.732822 -321.910456)
			(xy 238.7219 -321.888866) (xy 238.711994 -321.881754) (xy 238.684784 -321.861184) (xy 238.635636 -321.813881)
			(xy 238.593254 -321.760433) (xy 238.558399 -321.701797) (xy 238.531697 -321.639028) (xy 238.513627 -321.573252)
			(xy 238.504514 -321.505651) (xy 238.503968 -321.471544) (xy 237.385352 -321.471544) (xy 237.385352 -323.85)
			(xy 242.187982 -323.85) (xy 242.192053 -323.794378) (xy 242.204179 -323.739941) (xy 242.224102 -323.68785)
			(xy 242.251398 -323.639215) (xy 242.285484 -323.595072) (xy 242.325633 -323.556363) (xy 242.370991 -323.523912)
			(xy 242.420591 -323.498411) (xy 242.473375 -323.480404) (xy 242.528218 -323.470274) (xy 242.583952 -323.468237)
			(xy 242.639389 -323.474337) (xy 242.693346 -323.488443) (xy 242.744675 -323.510255) (xy 242.792281 -323.539309)
			(xy 242.835149 -323.574984) (xy 242.872366 -323.616521) (xy 242.903139 -323.663034) (xy 242.926811 -323.713531)
			(xy 242.942879 -323.766938) (xy 242.950999 -323.822114) (xy 242.951508 -323.85) (xy 244.220492 -323.85)
			(xy 244.221001 -323.819154) (xy 244.228477 -323.757915) (xy 244.243305 -323.698031) (xy 244.265269 -323.64038)
			(xy 244.294045 -323.58581) (xy 244.329212 -323.535121) (xy 244.370252 -323.48906) (xy 244.416563 -323.448301)
			(xy 244.467465 -323.413443) (xy 244.52221 -323.385) (xy 244.579993 -323.363387) (xy 244.609874 -323.355716)
			(xy 244.623336 -323.352414) (xy 244.642894 -323.333618) (xy 244.675406 -323.222874) (xy 244.668802 -323.196204)
			(xy 244.659404 -323.186552) (xy 244.637288 -323.162772) (xy 244.598598 -323.110615) (xy 244.566862 -323.053956)
			(xy 244.542597 -322.993719) (xy 244.526198 -322.930883) (xy 244.517931 -322.86647) (xy 244.517418 -322.834)
			(xy 244.517845 -322.8035) (xy 244.525153 -322.742938) (xy 244.539653 -322.683685) (xy 244.561136 -322.626592)
			(xy 244.589294 -322.572479) (xy 244.623722 -322.522122) (xy 244.663927 -322.476244) (xy 244.686328 -322.45554)
			(xy 244.69598 -322.44665) (xy 244.704616 -322.422266) (xy 244.686074 -322.311776) (xy 244.670072 -322.291456)
			(xy 244.65788 -322.286376) (xy 244.627613 -322.273007) (xy 244.570536 -322.239533) (xy 244.518281 -322.198941)
			(xy 244.471732 -322.151915) (xy 244.431675 -322.099249) (xy 244.398786 -322.041833) (xy 244.37362 -321.980637)
			(xy 244.356603 -321.916694) (xy 244.348023 -321.851084) (xy 244.347492 -321.818) (xy 244.347994 -321.786039)
			(xy 244.356005 -321.722621) (xy 244.371902 -321.660707) (xy 244.395434 -321.601274) (xy 244.426228 -321.545259)
			(xy 244.463801 -321.493544) (xy 244.507558 -321.446947) (xy 244.556811 -321.406202) (xy 244.610782 -321.371951)
			(xy 244.668621 -321.344734) (xy 244.729414 -321.324981) (xy 244.792204 -321.313003) (xy 244.856 -321.30899)
			(xy 244.919796 -321.313003) (xy 244.982586 -321.324981) (xy 245.043379 -321.344734) (xy 245.101218 -321.371951)
			(xy 245.155189 -321.406202) (xy 245.197166 -321.440928) (xy 249.087988 -321.440928) (xy 249.090594 -321.377898)
			(xy 249.100977 -321.315675) (xy 249.118976 -321.255214) (xy 249.144315 -321.197443) (xy 249.176606 -321.143251)
			(xy 249.215352 -321.093468) (xy 249.259958 -321.048861) (xy 249.309739 -321.010114) (xy 249.363931 -320.977822)
			(xy 249.421701 -320.95248) (xy 249.482161 -320.93448) (xy 249.544384 -320.924096) (xy 249.607414 -320.921488)
			(xy 249.670282 -320.926697) (xy 249.732023 -320.939642) (xy 249.791689 -320.960124) (xy 249.848363 -320.98783)
			(xy 249.901174 -321.022333) (xy 249.949313 -321.063103) (xy 249.992038 -321.109514) (xy 250.028695 -321.160855)
			(xy 250.05872 -321.216335) (xy 250.081652 -321.275102) (xy 250.097139 -321.336255) (xy 250.104942 -321.398854)
			(xy 250.105418 -321.430396) (xy 250.105302 -321.446506) (xy 250.103268 -321.478662) (xy 250.101354 -321.494658)
			(xy 250.09983 -321.506596) (xy 250.107704 -321.528948) (xy 250.18238 -321.602354) (xy 250.204986 -321.60972)
			(xy 250.216924 -321.607942) (xy 250.235236 -321.605437) (xy 250.272102 -321.602766) (xy 250.290584 -321.602608)
			(xy 250.322126 -321.603051) (xy 250.384726 -321.610852) (xy 250.44588 -321.626336) (xy 250.504649 -321.649266)
			(xy 250.560131 -321.679289) (xy 250.611473 -321.715944) (xy 250.657887 -321.758668) (xy 250.69866 -321.806805)
			(xy 250.726885 -321.850004) (xy 253.591058 -321.850004) (xy 253.595129 -321.794382) (xy 253.607255 -321.739945)
			(xy 253.627178 -321.687854) (xy 253.654474 -321.639219) (xy 253.68856 -321.595076) (xy 253.728709 -321.556367)
			(xy 253.774067 -321.523916) (xy 253.823667 -321.498415) (xy 253.876451 -321.480408) (xy 253.931294 -321.470278)
			(xy 253.987028 -321.468241) (xy 254.042465 -321.474341) (xy 254.096422 -321.488447) (xy 254.147751 -321.510259)
			(xy 254.195357 -321.539313) (xy 254.238225 -321.574988) (xy 254.275442 -321.616525) (xy 254.306215 -321.663038)
			(xy 254.329887 -321.713535) (xy 254.345955 -321.766942) (xy 254.354075 -321.822118) (xy 254.354584 -321.850004)
			(xy 254.354075 -321.87789) (xy 254.345955 -321.933066) (xy 254.329887 -321.986473) (xy 254.306215 -322.03697)
			(xy 254.275442 -322.083483) (xy 254.238225 -322.12502) (xy 254.195357 -322.160695) (xy 254.147751 -322.189749)
			(xy 254.096422 -322.211561) (xy 254.042465 -322.225667) (xy 253.987028 -322.231767) (xy 253.931294 -322.22973)
			(xy 253.876451 -322.2196) (xy 253.823667 -322.201593) (xy 253.774067 -322.176092) (xy 253.728709 -322.143641)
			(xy 253.68856 -322.104932) (xy 253.654474 -322.060789) (xy 253.627178 -322.012154) (xy 253.607255 -321.960063)
			(xy 253.595129 -321.905626) (xy 253.591058 -321.850004) (xy 250.726885 -321.850004) (xy 250.733165 -321.859616)
			(xy 250.760873 -321.916289) (xy 250.781358 -321.975955) (xy 250.794306 -322.037696) (xy 250.799517 -322.100564)
			(xy 250.796912 -322.163594) (xy 250.786531 -322.225818) (xy 250.768533 -322.28628) (xy 250.743194 -322.344052)
			(xy 250.710904 -322.398245) (xy 250.672159 -322.448029) (xy 250.627553 -322.492637) (xy 250.577772 -322.531386)
			(xy 250.52358 -322.563679) (xy 250.46581 -322.589022) (xy 250.405349 -322.607024) (xy 250.343126 -322.617409)
			(xy 250.280096 -322.620018) (xy 250.217227 -322.614811) (xy 250.155485 -322.601867) (xy 250.095819 -322.581385)
			(xy 250.039144 -322.553681) (xy 249.986331 -322.519179) (xy 249.938191 -322.478409) (xy 249.895464 -322.431998)
			(xy 249.858806 -322.380658) (xy 249.828779 -322.325178) (xy 249.805846 -322.266411) (xy 249.790358 -322.205257)
			(xy 249.782553 -322.142658) (xy 249.782076 -322.111116) (xy 249.782193 -322.095006) (xy 249.784226 -322.06285)
			(xy 249.78614 -322.046854) (xy 249.787664 -322.034916) (xy 249.77979 -322.012564) (xy 249.705114 -321.939158)
			(xy 249.682508 -321.931792) (xy 249.67057 -321.93357) (xy 249.652258 -321.936076) (xy 249.615392 -321.938747)
			(xy 249.59691 -321.938904) (xy 249.565368 -321.938443) (xy 249.502769 -321.930641) (xy 249.441616 -321.915156)
			(xy 249.382847 -321.892226) (xy 249.327366 -321.862203) (xy 249.276025 -321.825547) (xy 249.229613 -321.782823)
			(xy 249.188841 -321.734685) (xy 249.154337 -321.681875) (xy 249.12663 -321.625202) (xy 249.106145 -321.565536)
			(xy 249.093199 -321.503796) (xy 249.087988 -321.440928) (xy 245.197166 -321.440928) (xy 245.204442 -321.446947)
			(xy 245.248199 -321.493544) (xy 245.285772 -321.545259) (xy 245.316566 -321.601274) (xy 245.340098 -321.660707)
			(xy 245.355995 -321.722621) (xy 245.364006 -321.786039) (xy 245.364508 -321.818) (xy 245.364072 -321.8485)
			(xy 245.356765 -321.909061) (xy 245.342266 -321.968313) (xy 245.320784 -322.025406) (xy 245.292627 -322.07952)
			(xy 245.258201 -322.129877) (xy 245.217998 -322.175755) (xy 245.195598 -322.19646) (xy 245.185946 -322.20535)
			(xy 245.17731 -322.229734) (xy 245.195852 -322.340224) (xy 245.211854 -322.360544) (xy 245.224046 -322.365624)
			(xy 245.254319 -322.37898) (xy 245.311395 -322.412456) (xy 245.363649 -322.453051) (xy 245.410197 -322.500079)
			(xy 245.450253 -322.552747) (xy 245.483141 -322.610164) (xy 245.508306 -322.671361) (xy 245.525323 -322.735305)
			(xy 245.533904 -322.800915) (xy 245.534434 -322.834) (xy 245.533905 -322.864846) (xy 245.52643 -322.926082)
			(xy 245.511603 -322.985965) (xy 245.48964 -323.043615) (xy 245.460865 -323.098184) (xy 245.425701 -323.148872)
			(xy 245.384663 -323.194934) (xy 245.338354 -323.235694) (xy 245.287455 -323.270552) (xy 245.232713 -323.298997)
			(xy 245.174932 -323.320611) (xy 245.145052 -323.328284) (xy 245.13159 -323.331586) (xy 245.112032 -323.350382)
			(xy 245.090718 -323.422983) (xy 250.505462 -323.422983) (xy 250.505462 -323.359061) (xy 250.513473 -323.295643)
			(xy 250.52937 -323.233729) (xy 250.552902 -323.174296) (xy 250.583696 -323.118281) (xy 250.621269 -323.066566)
			(xy 250.665026 -323.019969) (xy 250.714279 -322.979224) (xy 250.76825 -322.944973) (xy 250.826089 -322.917756)
			(xy 250.886882 -322.898003) (xy 250.949672 -322.886025) (xy 251.013468 -322.882012) (xy 251.077264 -322.886025)
			(xy 251.140054 -322.898003) (xy 251.200847 -322.917756) (xy 251.258686 -322.944973) (xy 251.312657 -322.979224)
			(xy 251.36191 -323.019969) (xy 251.364495 -323.022722) (xy 256.385058 -323.022722) (xy 256.389129 -322.9671)
			(xy 256.401255 -322.912663) (xy 256.421178 -322.860572) (xy 256.448474 -322.811937) (xy 256.48256 -322.767794)
			(xy 256.522709 -322.729085) (xy 256.568067 -322.696634) (xy 256.617667 -322.671133) (xy 256.670451 -322.653126)
			(xy 256.725294 -322.642996) (xy 256.781028 -322.640959) (xy 256.836465 -322.647059) (xy 256.890422 -322.661165)
			(xy 256.941751 -322.682977) (xy 256.989357 -322.712031) (xy 257.032225 -322.747706) (xy 257.069442 -322.789243)
			(xy 257.100215 -322.835756) (xy 257.123887 -322.886253) (xy 257.139955 -322.93966) (xy 257.148075 -322.994836)
			(xy 257.148584 -323.022722) (xy 257.148075 -323.050608) (xy 257.139955 -323.105784) (xy 257.123887 -323.159191)
			(xy 257.100215 -323.209688) (xy 257.069442 -323.256201) (xy 257.032225 -323.297738) (xy 256.989357 -323.333413)
			(xy 256.941751 -323.362467) (xy 256.890422 -323.384279) (xy 256.836465 -323.398385) (xy 256.781028 -323.404485)
			(xy 256.725294 -323.402448) (xy 256.670451 -323.392318) (xy 256.617667 -323.374311) (xy 256.568067 -323.34881)
			(xy 256.522709 -323.316359) (xy 256.48256 -323.27765) (xy 256.448474 -323.233507) (xy 256.421178 -323.184872)
			(xy 256.401255 -323.132781) (xy 256.389129 -323.078344) (xy 256.385058 -323.022722) (xy 251.364495 -323.022722)
			(xy 251.405667 -323.066566) (xy 251.44324 -323.118281) (xy 251.474034 -323.174296) (xy 251.497566 -323.233729)
			(xy 251.513463 -323.295643) (xy 251.521474 -323.359061) (xy 251.521976 -323.391022) (xy 251.521474 -323.422983)
			(xy 251.513463 -323.486401) (xy 251.497566 -323.548315) (xy 251.474034 -323.607748) (xy 251.44324 -323.663763)
			(xy 251.405667 -323.715478) (xy 251.36191 -323.762075) (xy 251.312657 -323.80282) (xy 251.258686 -323.837071)
			(xy 251.200847 -323.864288) (xy 251.140054 -323.884041) (xy 251.077264 -323.896019) (xy 251.013468 -323.900033)
			(xy 250.949672 -323.896019) (xy 250.886882 -323.884041) (xy 250.826089 -323.864288) (xy 250.76825 -323.837071)
			(xy 250.714279 -323.80282) (xy 250.665026 -323.762075) (xy 250.621269 -323.715478) (xy 250.583696 -323.663763)
			(xy 250.552902 -323.607748) (xy 250.52937 -323.548315) (xy 250.513473 -323.486401) (xy 250.505462 -323.422983)
			(xy 245.090718 -323.422983) (xy 245.07952 -323.461126) (xy 245.086124 -323.487796) (xy 245.095522 -323.497448)
			(xy 245.117643 -323.521224) (xy 245.156332 -323.573383) (xy 245.188066 -323.630042) (xy 245.21233 -323.69028)
			(xy 245.228728 -323.753117) (xy 245.236995 -323.817529) (xy 245.237508 -323.85) (xy 245.237054 -323.880464)
			(xy 245.229752 -323.940953) (xy 245.215289 -324.00014) (xy 245.204996 -324.028816) (xy 245.199916 -324.042532)
			(xy 245.200415 -324.045072) (xy 256.377692 -324.045072) (xy 256.381763 -323.98945) (xy 256.393889 -323.935013)
			(xy 256.413812 -323.882922) (xy 256.441108 -323.834287) (xy 256.475194 -323.790144) (xy 256.515343 -323.751435)
			(xy 256.560701 -323.718984) (xy 256.610301 -323.693483) (xy 256.663085 -323.675476) (xy 256.717928 -323.665346)
			(xy 256.773662 -323.663309) (xy 256.829099 -323.669409) (xy 256.883056 -323.683515) (xy 256.934385 -323.705327)
			(xy 256.981991 -323.734381) (xy 257.024859 -323.770056) (xy 257.062076 -323.811593) (xy 257.092849 -323.858106)
			(xy 257.116521 -323.908603) (xy 257.132589 -323.96201) (xy 257.140709 -324.017186) (xy 257.141218 -324.045072)
			(xy 257.140709 -324.072958) (xy 257.132589 -324.128134) (xy 257.116521 -324.181541) (xy 257.092849 -324.232038)
			(xy 257.062076 -324.278551) (xy 257.024859 -324.320088) (xy 256.981991 -324.355763) (xy 256.934385 -324.384817)
			(xy 256.883056 -324.406629) (xy 256.829099 -324.420735) (xy 256.773662 -324.426835) (xy 256.717928 -324.424798)
			(xy 256.663085 -324.414668) (xy 256.610301 -324.396661) (xy 256.560701 -324.37116) (xy 256.515343 -324.338709)
			(xy 256.475194 -324.3) (xy 256.441108 -324.255857) (xy 256.413812 -324.207222) (xy 256.393889 -324.155131)
			(xy 256.381763 -324.100694) (xy 256.377692 -324.045072) (xy 245.200415 -324.045072) (xy 245.205504 -324.07098)
			(xy 245.287546 -324.15861) (xy 245.315486 -324.16623) (xy 245.329456 -324.161912) (xy 245.365249 -324.151807)
			(xy 245.438828 -324.140969) (xy 245.476014 -324.140322) (xy 245.507554 -324.140782) (xy 245.570148 -324.148586)
			(xy 245.631297 -324.164073) (xy 245.69006 -324.187004) (xy 245.745536 -324.217027) (xy 245.796873 -324.253682)
			(xy 245.843281 -324.296405) (xy 245.884048 -324.34454) (xy 245.918549 -324.397348) (xy 245.946253 -324.454018)
			(xy 245.966734 -324.51368) (xy 245.979679 -324.575416) (xy 245.984888 -324.63828) (xy 245.982281 -324.701305)
			(xy 245.971899 -324.763524) (xy 245.953901 -324.823981) (xy 245.928562 -324.881748) (xy 245.896274 -324.935937)
			(xy 245.85753 -324.985715) (xy 245.812927 -325.03032) (xy 245.778966 -325.056754) (xy 256.397758 -325.056754)
			(xy 256.401829 -325.001132) (xy 256.413955 -324.946695) (xy 256.433878 -324.894604) (xy 256.461174 -324.845969)
			(xy 256.49526 -324.801826) (xy 256.535409 -324.763117) (xy 256.580767 -324.730666) (xy 256.630367 -324.705165)
			(xy 256.683151 -324.687158) (xy 256.737994 -324.677028) (xy 256.793728 -324.674991) (xy 256.849165 -324.681091)
			(xy 256.903122 -324.695197) (xy 256.954451 -324.717009) (xy 257.002057 -324.746063) (xy 257.044925 -324.781738)
			(xy 257.082142 -324.823275) (xy 257.112915 -324.869788) (xy 257.136587 -324.920285) (xy 257.152655 -324.973692)
			(xy 257.160775 -325.028868) (xy 257.161284 -325.056754) (xy 257.160775 -325.08464) (xy 257.152655 -325.139816)
			(xy 257.136587 -325.193223) (xy 257.112915 -325.24372) (xy 257.082142 -325.290233) (xy 257.044925 -325.33177)
			(xy 257.002057 -325.367445) (xy 256.954451 -325.396499) (xy 256.903122 -325.418311) (xy 256.849165 -325.432417)
			(xy 256.793728 -325.438517) (xy 256.737994 -325.43648) (xy 256.683151 -325.42635) (xy 256.630367 -325.408343)
			(xy 256.580767 -325.382842) (xy 256.535409 -325.350391) (xy 256.49526 -325.311682) (xy 256.461174 -325.267539)
			(xy 256.433878 -325.218904) (xy 256.413955 -325.166813) (xy 256.401829 -325.112376) (xy 256.397758 -325.056754)
			(xy 245.778966 -325.056754) (xy 245.76315 -325.069065) (xy 245.708962 -325.101355) (xy 245.651196 -325.126695)
			(xy 245.59074 -325.144695) (xy 245.528521 -325.15508) (xy 245.465496 -325.157688) (xy 245.402632 -325.152481)
			(xy 245.340895 -325.139538) (xy 245.281233 -325.119059) (xy 245.224562 -325.091357) (xy 245.171753 -325.056858)
			(xy 245.123617 -325.016092) (xy 245.080892 -324.969685) (xy 245.044236 -324.91835) (xy 245.014211 -324.862875)
			(xy 244.991278 -324.804112) (xy 244.975789 -324.742964) (xy 244.967983 -324.68037) (xy 244.967506 -324.64883)
			(xy 244.967968 -324.618366) (xy 244.975266 -324.557877) (xy 244.989727 -324.49869) (xy 245.000018 -324.470014)
			(xy 245.005098 -324.456298) (xy 244.99951 -324.42785) (xy 244.917468 -324.34022) (xy 244.889528 -324.3326)
			(xy 244.875558 -324.336918) (xy 244.839765 -324.347021) (xy 244.766186 -324.35786) (xy 244.729 -324.358508)
			(xy 244.698269 -324.358044) (xy 244.637255 -324.350635) (xy 244.577579 -324.335927) (xy 244.520111 -324.314132)
			(xy 244.465689 -324.285569) (xy 244.415107 -324.250655) (xy 244.369102 -324.209898) (xy 244.328345 -324.163893)
			(xy 244.293431 -324.113311) (xy 244.264868 -324.058889) (xy 244.243073 -324.001421) (xy 244.228365 -323.941745)
			(xy 244.220956 -323.880731) (xy 244.220492 -323.85) (xy 242.951508 -323.85) (xy 242.950999 -323.877886)
			(xy 242.942879 -323.933062) (xy 242.926811 -323.986469) (xy 242.903139 -324.036966) (xy 242.872366 -324.083479)
			(xy 242.835149 -324.125016) (xy 242.792281 -324.160691) (xy 242.744675 -324.189745) (xy 242.693346 -324.211557)
			(xy 242.639389 -324.225663) (xy 242.583952 -324.231763) (xy 242.528218 -324.229726) (xy 242.473375 -324.219596)
			(xy 242.420591 -324.201589) (xy 242.370991 -324.176088) (xy 242.325633 -324.143637) (xy 242.285484 -324.104928)
			(xy 242.251398 -324.060785) (xy 242.224102 -324.01215) (xy 242.204179 -323.960059) (xy 242.192053 -323.905622)
			(xy 242.187982 -323.85) (xy 237.385352 -323.85) (xy 237.385352 -324.866) (xy 242.187982 -324.866)
			(xy 242.192053 -324.810378) (xy 242.204179 -324.755941) (xy 242.224102 -324.70385) (xy 242.251398 -324.655215)
			(xy 242.285484 -324.611072) (xy 242.325633 -324.572363) (xy 242.370991 -324.539912) (xy 242.420591 -324.514411)
			(xy 242.473375 -324.496404) (xy 242.528218 -324.486274) (xy 242.583952 -324.484237) (xy 242.639389 -324.490337)
			(xy 242.693346 -324.504443) (xy 242.744675 -324.526255) (xy 242.792281 -324.555309) (xy 242.835149 -324.590984)
			(xy 242.872366 -324.632521) (xy 242.903139 -324.679034) (xy 242.926811 -324.729531) (xy 242.942879 -324.782938)
			(xy 242.950999 -324.838114) (xy 242.951508 -324.866) (xy 242.950999 -324.893886) (xy 242.942879 -324.949062)
			(xy 242.926811 -325.002469) (xy 242.903139 -325.052966) (xy 242.872366 -325.099479) (xy 242.835149 -325.141016)
			(xy 242.792281 -325.176691) (xy 242.744675 -325.205745) (xy 242.693346 -325.227557) (xy 242.639389 -325.241663)
			(xy 242.583952 -325.247763) (xy 242.528218 -325.245726) (xy 242.473375 -325.235596) (xy 242.420591 -325.217589)
			(xy 242.370991 -325.192088) (xy 242.325633 -325.159637) (xy 242.285484 -325.120928) (xy 242.251398 -325.076785)
			(xy 242.224102 -325.02815) (xy 242.204179 -324.976059) (xy 242.192053 -324.921622) (xy 242.187982 -324.866)
			(xy 237.385352 -324.866) (xy 237.385352 -327.698608) (xy 238.484918 -327.698608) (xy 238.485394 -327.66603)
			(xy 238.493734 -327.601411) (xy 238.510253 -327.538384) (xy 238.534682 -327.477981) (xy 238.566619 -327.42119)
			(xy 238.605544 -327.368939) (xy 238.650819 -327.322084) (xy 238.701704 -327.28139) (xy 238.729266 -327.264014)
			(xy 238.740442 -327.25741) (xy 238.753142 -327.23582) (xy 238.757714 -327.12533) (xy 238.746792 -327.102724)
			(xy 238.736124 -327.095104) (xy 238.712145 -327.07713) (xy 238.668154 -327.036432) (xy 238.629249 -326.990847)
			(xy 238.595968 -326.941009) (xy 238.568772 -326.887605) (xy 238.548038 -326.831377) (xy 238.534053 -326.773103)
			(xy 238.52701 -326.713589) (xy 238.526574 -326.683624) (xy 238.527001 -326.652229) (xy 238.534719 -326.589915)
			(xy 238.550053 -326.529026) (xy 238.572769 -326.470489) (xy 238.602521 -326.415196) (xy 238.638856 -326.363987)
			(xy 238.681222 -326.317644) (xy 238.728973 -326.276871) (xy 238.75492 -326.25919) (xy 238.765842 -326.252078)
			(xy 238.77778 -326.229218) (xy 238.77651 -326.117712) (xy 238.76381 -326.09536) (xy 238.752888 -326.088248)
			(xy 238.725877 -326.070764) (xy 238.676036 -326.030071) (xy 238.63173 -325.983411) (xy 238.59367 -325.931531)
			(xy 238.562464 -325.875261) (xy 238.538612 -325.815502) (xy 238.522494 -325.75321) (xy 238.51437 -325.689382)
			(xy 238.513874 -325.65721) (xy 238.514376 -325.625249) (xy 238.522387 -325.561831) (xy 238.538284 -325.499917)
			(xy 238.561816 -325.440484) (xy 238.59261 -325.384469) (xy 238.630183 -325.332754) (xy 238.67394 -325.286157)
			(xy 238.723193 -325.245412) (xy 238.777164 -325.211161) (xy 238.835003 -325.183944) (xy 238.895796 -325.164191)
			(xy 238.958586 -325.152213) (xy 239.022382 -325.1482) (xy 239.086178 -325.152213) (xy 239.148968 -325.164191)
			(xy 239.209761 -325.183944) (xy 239.2676 -325.211161) (xy 239.321571 -325.245412) (xy 239.370824 -325.286157)
			(xy 239.414581 -325.332754) (xy 239.452154 -325.384469) (xy 239.482948 -325.440484) (xy 239.50648 -325.499917)
			(xy 239.522377 -325.561831) (xy 239.530388 -325.625249) (xy 239.53089 -325.65721) (xy 239.530428 -325.688604)
			(xy 239.522717 -325.750917) (xy 239.50739 -325.811806) (xy 239.48468 -325.870343) (xy 239.454933 -325.925637)
			(xy 239.418601 -325.976846) (xy 239.376238 -326.02319) (xy 239.32849 -326.063963) (xy 239.302544 -326.081644)
			(xy 239.291622 -326.088756) (xy 239.279684 -326.111616) (xy 239.280954 -326.223122) (xy 239.293654 -326.245474)
			(xy 239.304576 -326.252586) (xy 239.331594 -326.27006) (xy 239.381437 -326.310753) (xy 239.425743 -326.357414)
			(xy 239.463804 -326.409295) (xy 239.495009 -326.465566) (xy 239.51886 -326.525327) (xy 239.534975 -326.587621)
			(xy 239.543096 -326.651452) (xy 239.54359 -326.683624) (xy 239.543057 -326.7162) (xy 239.534725 -326.780817)
			(xy 239.518214 -326.843842) (xy 239.493794 -326.904244) (xy 239.461865 -326.961036) (xy 239.422947 -327.013287)
			(xy 239.377679 -327.060144) (xy 239.326801 -327.10084) (xy 239.299242 -327.118218) (xy 239.288066 -327.124822)
			(xy 239.275366 -327.146412) (xy 239.270794 -327.256902) (xy 239.281716 -327.279508) (xy 239.292384 -327.287128)
			(xy 239.31638 -327.30508) (xy 239.36037 -327.345782) (xy 239.399274 -327.39137) (xy 239.432553 -327.441212)
			(xy 239.459747 -327.494618) (xy 239.480478 -327.550849) (xy 239.49446 -327.609126) (xy 239.5015 -327.668642)
			(xy 239.501934 -327.698608) (xy 239.50141 -327.730215) (xy 239.49357 -327.79294) (xy 239.478013 -327.854209)
			(xy 239.454979 -327.913076) (xy 239.424822 -327.968633) (xy 239.388009 -328.020021) (xy 239.345109 -328.066448)
			(xy 239.296782 -328.107197) (xy 239.27054 -328.12482) (xy 239.259872 -328.131932) (xy 239.247426 -328.154792)
			(xy 239.247934 -328.266044) (xy 239.26038 -328.28865) (xy 239.271302 -328.295762) (xy 239.297922 -328.31334)
			(xy 239.347014 -328.354075) (xy 239.390623 -328.400632) (xy 239.428063 -328.45228) (xy 239.441969 -328.477626)
			(xy 239.960912 -328.477626) (xy 239.961365 -328.446929) (xy 239.968772 -328.385983) (xy 239.983468 -328.326374)
			(xy 240.005241 -328.268971) (xy 240.033772 -328.214609) (xy 240.050828 -328.189082) (xy 240.056276 -328.180318)
			(xy 240.060409 -328.160122) (xy 240.056293 -328.139922) (xy 240.050828 -328.13117) (xy 240.033785 -328.105637)
			(xy 240.005277 -328.051268) (xy 239.983515 -327.993864) (xy 239.968815 -327.93426) (xy 239.961392 -327.873321)
			(xy 239.960912 -327.842626) (xy 239.961397 -327.810271) (xy 239.969619 -327.746086) (xy 239.98592 -327.683464)
			(xy 240.010037 -327.623417) (xy 240.04158 -327.566916) (xy 240.080039 -327.514875) (xy 240.124791 -327.468136)
			(xy 240.149634 -327.447402) (xy 240.157508 -327.441052) (xy 240.166906 -327.424034) (xy 240.177828 -327.333864)
			(xy 240.172748 -327.315068) (xy 240.166652 -327.30694) (xy 240.147187 -327.280383) (xy 240.114591 -327.223172)
			(xy 240.089655 -327.162231) (xy 240.072798 -327.09858) (xy 240.0643 -327.033285) (xy 240.063782 -327.000362)
			(xy 240.064284 -326.968401) (xy 240.072295 -326.904983) (xy 240.088192 -326.843069) (xy 240.111724 -326.783636)
			(xy 240.142518 -326.727621) (xy 240.180091 -326.675906) (xy 240.223848 -326.629309) (xy 240.273101 -326.588564)
			(xy 240.327072 -326.554313) (xy 240.384911 -326.527096) (xy 240.445704 -326.507343) (xy 240.508494 -326.495365)
			(xy 240.57229 -326.491352) (xy 240.636086 -326.495365) (xy 240.698876 -326.507343) (xy 240.759669 -326.527096)
			(xy 240.817508 -326.554313) (xy 240.871479 -326.588564) (xy 240.920732 -326.629309) (xy 240.964489 -326.675906)
			(xy 241.002062 -326.727621) (xy 241.032856 -326.783636) (xy 241.056388 -326.843069) (xy 241.070492 -326.898)
			(xy 242.061492 -326.898) (xy 242.061911 -326.86672) (xy 242.069575 -326.804631) (xy 242.084801 -326.743953)
			(xy 242.107358 -326.685601) (xy 242.136904 -326.630458) (xy 242.172995 -326.579358) (xy 242.215083 -326.533072)
			(xy 242.262532 -326.492301) (xy 242.288314 -326.474582) (xy 242.298474 -326.46713) (xy 242.31046 -326.444999)
			(xy 242.311174 -326.432418) (xy 242.311174 -326.347582) (xy 242.310494 -326.334999) (xy 242.298472 -326.31288)
			(xy 242.288314 -326.305418) (xy 242.262567 -326.287656) (xy 242.215139 -326.246876) (xy 242.173068 -326.200589)
			(xy 242.13699 -326.149492) (xy 242.10745 -326.094358) (xy 242.084892 -326.036017) (xy 242.069657 -325.975351)
			(xy 242.061976 -325.913275) (xy 242.061492 -325.882) (xy 242.061994 -325.850039) (xy 242.070005 -325.786621)
			(xy 242.085902 -325.724707) (xy 242.109434 -325.665274) (xy 242.140228 -325.609259) (xy 242.177801 -325.557544)
			(xy 242.221558 -325.510947) (xy 242.270811 -325.470202) (xy 242.324782 -325.435951) (xy 242.382621 -325.408734)
			(xy 242.443414 -325.388981) (xy 242.506204 -325.377003) (xy 242.57 -325.37299) (xy 242.633796 -325.377003)
			(xy 242.696586 -325.388981) (xy 242.757379 -325.408734) (xy 242.815218 -325.435951) (xy 242.869189 -325.470202)
			(xy 242.918442 -325.510947) (xy 242.962199 -325.557544) (xy 242.999772 -325.609259) (xy 243.030566 -325.665274)
			(xy 243.054098 -325.724707) (xy 243.069995 -325.786621) (xy 243.078006 -325.850039) (xy 243.078508 -325.882)
			(xy 243.078089 -325.91328) (xy 243.070425 -325.975369) (xy 243.055199 -326.036047) (xy 243.032642 -326.094399)
			(xy 243.003096 -326.149542) (xy 242.967005 -326.200642) (xy 242.924917 -326.246928) (xy 242.877468 -326.287699)
			(xy 242.851686 -326.305418) (xy 242.841526 -326.31287) (xy 242.82954 -326.335001) (xy 242.828826 -326.347582)
			(xy 242.828826 -326.432418) (xy 242.829506 -326.445001) (xy 242.841528 -326.46712) (xy 242.851686 -326.474582)
			(xy 242.877433 -326.492344) (xy 242.924861 -326.533124) (xy 242.954763 -326.566022) (xy 253.441454 -326.566022)
			(xy 253.441872 -326.539798) (xy 253.449066 -326.487846) (xy 253.463308 -326.437369) (xy 253.484329 -326.389318)
			(xy 253.511732 -326.344599) (xy 253.545003 -326.304054) (xy 253.583513 -326.268449) (xy 253.604776 -326.253094)
			(xy 253.616005 -326.244752) (xy 253.633731 -326.22312) (xy 253.644926 -326.197493) (xy 253.648751 -326.16979)
			(xy 253.64492 -326.142087) (xy 253.63372 -326.116462) (xy 253.61599 -326.094834) (xy 253.604776 -326.08647)
			(xy 253.583521 -326.07115) (xy 253.545072 -326.035555) (xy 253.511857 -325.995031) (xy 253.484503 -325.950342)
			(xy 253.463523 -325.90233) (xy 253.449314 -325.851897) (xy 253.442142 -325.799994) (xy 253.441708 -325.773796)
			(xy 253.442194 -325.746545) (xy 253.44995 -325.692597) (xy 253.465305 -325.640302) (xy 253.487947 -325.590725)
			(xy 253.517413 -325.544875) (xy 253.553104 -325.503684) (xy 253.594295 -325.467993) (xy 253.640145 -325.438527)
			(xy 253.689722 -325.415885) (xy 253.742017 -325.40053) (xy 253.795965 -325.392774) (xy 253.850467 -325.392774)
			(xy 253.904415 -325.40053) (xy 253.95671 -325.415885) (xy 254.006287 -325.438527) (xy 254.052137 -325.467993)
			(xy 254.093328 -325.503684) (xy 254.129019 -325.544875) (xy 254.158485 -325.590725) (xy 254.181127 -325.640302)
			(xy 254.196482 -325.692597) (xy 254.204238 -325.746545) (xy 254.204724 -325.773796) (xy 254.204286 -325.800019)
			(xy 254.197092 -325.851969) (xy 254.182851 -325.902444) (xy 254.161832 -325.950494) (xy 254.134432 -325.995213)
			(xy 254.101167 -326.035759) (xy 254.062662 -326.071367) (xy 254.041402 -326.086724) (xy 254.030157 -326.095046)
			(xy 254.012435 -326.116683) (xy 254.001244 -326.142315) (xy 253.997422 -326.170021) (xy 254.001255 -326.197725)
			(xy 254.012457 -326.223352) (xy 254.030188 -326.244982) (xy 254.041402 -326.253348) (xy 254.062661 -326.268664)
			(xy 254.101111 -326.304259) (xy 254.134326 -326.344783) (xy 254.16168 -326.389473) (xy 254.182659 -326.437486)
			(xy 254.196867 -326.48792) (xy 254.204037 -326.539824) (xy 254.20447 -326.566022) (xy 254.203984 -326.593273)
			(xy 254.196228 -326.647221) (xy 254.180873 -326.699516) (xy 254.158231 -326.749093) (xy 254.128765 -326.794943)
			(xy 254.093074 -326.836134) (xy 254.051883 -326.871825) (xy 254.006033 -326.901291) (xy 253.956456 -326.923933)
			(xy 253.904161 -326.939288) (xy 253.850213 -326.947044) (xy 253.795711 -326.947044) (xy 253.741763 -326.939288)
			(xy 253.689468 -326.923933) (xy 253.639891 -326.901291) (xy 253.594041 -326.871825) (xy 253.55285 -326.836134)
			(xy 253.517159 -326.794943) (xy 253.487693 -326.749093) (xy 253.465051 -326.699516) (xy 253.449696 -326.647221)
			(xy 253.44194 -326.593273) (xy 253.441454 -326.566022) (xy 242.954763 -326.566022) (xy 242.966932 -326.579411)
			(xy 243.00301 -326.630508) (xy 243.03255 -326.685642) (xy 243.055108 -326.743983) (xy 243.070343 -326.804649)
			(xy 243.078024 -326.866725) (xy 243.078508 -326.898) (xy 243.078006 -326.929961) (xy 243.069995 -326.993379)
			(xy 243.054098 -327.055293) (xy 243.030566 -327.114726) (xy 242.999772 -327.170741) (xy 242.977772 -327.201022)
			(xy 245.640858 -327.201022) (xy 245.644929 -327.1454) (xy 245.657055 -327.090963) (xy 245.676978 -327.038872)
			(xy 245.704274 -326.990237) (xy 245.73836 -326.946094) (xy 245.778509 -326.907385) (xy 245.823867 -326.874934)
			(xy 245.873467 -326.849433) (xy 245.926251 -326.831426) (xy 245.981094 -326.821296) (xy 246.036828 -326.819259)
			(xy 246.092265 -326.825359) (xy 246.146222 -326.839465) (xy 246.197551 -326.861277) (xy 246.245157 -326.890331)
			(xy 246.288025 -326.926006) (xy 246.325242 -326.967543) (xy 246.356015 -327.014056) (xy 246.379687 -327.064553)
			(xy 246.395755 -327.11796) (xy 246.403875 -327.173136) (xy 246.404384 -327.201022) (xy 246.403875 -327.228908)
			(xy 246.395755 -327.284084) (xy 246.379687 -327.337491) (xy 246.356015 -327.387988) (xy 246.325242 -327.434501)
			(xy 246.301848 -327.46061) (xy 253.441198 -327.46061) (xy 253.445269 -327.404988) (xy 253.457395 -327.350551)
			(xy 253.477318 -327.29846) (xy 253.504614 -327.249825) (xy 253.5387 -327.205682) (xy 253.578849 -327.166973)
			(xy 253.624207 -327.134522) (xy 253.673807 -327.109021) (xy 253.726591 -327.091014) (xy 253.781434 -327.080884)
			(xy 253.837168 -327.078847) (xy 253.892605 -327.084947) (xy 253.946562 -327.099053) (xy 253.997891 -327.120865)
			(xy 254.045497 -327.149919) (xy 254.088365 -327.185594) (xy 254.125582 -327.227131) (xy 254.156355 -327.273644)
			(xy 254.180027 -327.324141) (xy 254.196095 -327.377548) (xy 254.204215 -327.432724) (xy 254.204724 -327.46061)
			(xy 254.204215 -327.488496) (xy 254.196095 -327.543672) (xy 254.180027 -327.597079) (xy 254.156355 -327.647576)
			(xy 254.125582 -327.694089) (xy 254.088365 -327.735626) (xy 254.045497 -327.771301) (xy 253.997891 -327.800355)
			(xy 253.946562 -327.822167) (xy 253.892605 -327.836273) (xy 253.837168 -327.842373) (xy 253.781434 -327.840336)
			(xy 253.726591 -327.830206) (xy 253.673807 -327.812199) (xy 253.624207 -327.786698) (xy 253.578849 -327.754247)
			(xy 253.5387 -327.715538) (xy 253.504614 -327.671395) (xy 253.477318 -327.62276) (xy 253.457395 -327.570669)
			(xy 253.445269 -327.516232) (xy 253.441198 -327.46061) (xy 246.301848 -327.46061) (xy 246.288025 -327.476038)
			(xy 246.245157 -327.511713) (xy 246.197551 -327.540767) (xy 246.146222 -327.562579) (xy 246.092265 -327.576685)
			(xy 246.036828 -327.582785) (xy 245.981094 -327.580748) (xy 245.926251 -327.570618) (xy 245.873467 -327.552611)
			(xy 245.823867 -327.52711) (xy 245.778509 -327.494659) (xy 245.73836 -327.45595) (xy 245.704274 -327.411807)
			(xy 245.676978 -327.363172) (xy 245.657055 -327.311081) (xy 245.644929 -327.256644) (xy 245.640858 -327.201022)
			(xy 242.977772 -327.201022) (xy 242.962199 -327.222456) (xy 242.918442 -327.269053) (xy 242.869189 -327.309798)
			(xy 242.815218 -327.344049) (xy 242.757379 -327.371266) (xy 242.696586 -327.391019) (xy 242.633796 -327.402997)
			(xy 242.57 -327.407011) (xy 242.506204 -327.402997) (xy 242.443414 -327.391019) (xy 242.382621 -327.371266)
			(xy 242.324782 -327.344049) (xy 242.270811 -327.309798) (xy 242.221558 -327.269053) (xy 242.177801 -327.222456)
			(xy 242.140228 -327.170741) (xy 242.109434 -327.114726) (xy 242.085902 -327.055293) (xy 242.070005 -326.993379)
			(xy 242.061994 -326.929961) (xy 242.061492 -326.898) (xy 241.070492 -326.898) (xy 241.072285 -326.904983)
			(xy 241.080296 -326.968401) (xy 241.080798 -327.000362) (xy 241.080301 -327.032716) (xy 241.07208 -327.0969)
			(xy 241.055781 -327.159522) (xy 241.031666 -327.219569) (xy 241.000125 -327.27607) (xy 240.961668 -327.328112)
			(xy 240.916918 -327.374851) (xy 240.892076 -327.395586) (xy 240.884202 -327.401936) (xy 240.874804 -327.418954)
			(xy 240.863882 -327.509124) (xy 240.868962 -327.52792) (xy 240.875058 -327.536048) (xy 240.894519 -327.562607)
			(xy 240.927116 -327.619818) (xy 240.952052 -327.680759) (xy 240.96891 -327.744409) (xy 240.977409 -327.809703)
			(xy 240.977928 -327.842626) (xy 240.977444 -327.873322) (xy 240.970043 -327.934266) (xy 240.955353 -327.993875)
			(xy 240.933588 -328.051279) (xy 240.905064 -328.105642) (xy 240.888012 -328.13117) (xy 240.882517 -328.139909)
			(xy 240.878394 -328.160122) (xy 240.882533 -328.18033) (xy 240.888012 -328.189082) (xy 240.905027 -328.214633)
			(xy 240.933542 -328.268997) (xy 240.95531 -328.326395) (xy 240.970016 -328.385996) (xy 240.977445 -328.446932)
			(xy 240.977928 -328.477626) (xy 240.977426 -328.509587) (xy 240.969415 -328.573005) (xy 240.953518 -328.634919)
			(xy 240.929986 -328.694352) (xy 240.899192 -328.750367) (xy 240.861619 -328.802082) (xy 240.817862 -328.848679)
			(xy 240.768609 -328.889424) (xy 240.714638 -328.923675) (xy 240.656799 -328.950892) (xy 240.596006 -328.970645)
			(xy 240.533216 -328.982623) (xy 240.46942 -328.986637) (xy 240.405624 -328.982623) (xy 240.342834 -328.970645)
			(xy 240.282041 -328.950892) (xy 240.224202 -328.923675) (xy 240.170231 -328.889424) (xy 240.120978 -328.848679)
			(xy 240.077221 -328.802082) (xy 240.039648 -328.750367) (xy 240.008854 -328.694352) (xy 239.985322 -328.634919)
			(xy 239.969425 -328.573005) (xy 239.961414 -328.509587) (xy 239.960912 -328.477626) (xy 239.441969 -328.477626)
			(xy 239.458747 -328.508207) (xy 239.482192 -328.567534) (xy 239.498028 -328.629328) (xy 239.506009 -328.692618)
			(xy 239.506506 -328.724514) (xy 239.506004 -328.756475) (xy 239.497993 -328.819893) (xy 239.482096 -328.881807)
			(xy 239.458564 -328.94124) (xy 239.42777 -328.997255) (xy 239.390197 -329.04897) (xy 239.34644 -329.095567)
			(xy 239.297187 -329.136312) (xy 239.243216 -329.170563) (xy 239.185377 -329.19778) (xy 239.124584 -329.217533)
			(xy 239.061794 -329.229511) (xy 238.997998 -329.233525) (xy 238.934202 -329.229511) (xy 238.871412 -329.217533)
			(xy 238.810619 -329.19778) (xy 238.75278 -329.170563) (xy 238.698809 -329.136312) (xy 238.649556 -329.095567)
			(xy 238.605799 -329.04897) (xy 238.568226 -328.997255) (xy 238.537432 -328.94124) (xy 238.5139 -328.881807)
			(xy 238.498003 -328.819893) (xy 238.489992 -328.756475) (xy 238.48949 -328.724514) (xy 238.489943 -328.692905)
			(xy 238.497792 -328.630176) (xy 238.513359 -328.568905) (xy 238.536404 -328.510037) (xy 238.56657 -328.454481)
			(xy 238.603393 -328.403093) (xy 238.646303 -328.356669) (xy 238.694638 -328.315923) (xy 238.720884 -328.298302)
			(xy 238.731552 -328.29119) (xy 238.743998 -328.26833) (xy 238.74349 -328.157078) (xy 238.731044 -328.134472)
			(xy 238.720122 -328.12736) (xy 238.693472 -328.109826) (xy 238.644379 -328.069086) (xy 238.600771 -328.022522)
			(xy 238.563332 -327.970868) (xy 238.532652 -327.914934) (xy 238.509213 -327.855601) (xy 238.493383 -327.793801)
			(xy 238.485411 -327.730506) (xy 238.484918 -327.698608) (xy 237.385352 -327.698608) (xy 237.385352 -329.703133)
			(xy 248.215906 -329.703133) (xy 248.215906 -329.639211) (xy 248.223917 -329.575793) (xy 248.239814 -329.513879)
			(xy 248.263346 -329.454446) (xy 248.29414 -329.398431) (xy 248.331713 -329.346716) (xy 248.37547 -329.300119)
			(xy 248.424723 -329.259374) (xy 248.478694 -329.225123) (xy 248.536533 -329.197906) (xy 248.597326 -329.178153)
			(xy 248.660116 -329.166175) (xy 248.723912 -329.162162) (xy 248.787708 -329.166175) (xy 248.850498 -329.178153)
			(xy 248.911291 -329.197906) (xy 248.96913 -329.225123) (xy 249.023101 -329.259374) (xy 249.072354 -329.300119)
			(xy 249.116111 -329.346716) (xy 249.153684 -329.398431) (xy 249.184478 -329.454446) (xy 249.20801 -329.513879)
			(xy 249.223907 -329.575793) (xy 249.231918 -329.639211) (xy 249.23242 -329.671172) (xy 249.231918 -329.703133)
			(xy 249.223907 -329.766551) (xy 249.20801 -329.828465) (xy 249.184478 -329.887898) (xy 249.153684 -329.943913)
			(xy 249.116111 -329.995628) (xy 249.072354 -330.042225) (xy 249.023101 -330.08297) (xy 248.96913 -330.117221)
			(xy 248.911291 -330.144438) (xy 248.850498 -330.164191) (xy 248.787708 -330.176169) (xy 248.723912 -330.180183)
			(xy 248.660116 -330.176169) (xy 248.597326 -330.164191) (xy 248.536533 -330.144438) (xy 248.478694 -330.117221)
			(xy 248.424723 -330.08297) (xy 248.37547 -330.042225) (xy 248.331713 -329.995628) (xy 248.29414 -329.943913)
			(xy 248.263346 -329.887898) (xy 248.239814 -329.828465) (xy 248.223917 -329.766551) (xy 248.215906 -329.703133)
			(xy 237.385352 -329.703133) (xy 237.385352 -331.343) (xy 237.870492 -331.343) (xy 237.870975 -331.314081)
			(xy 237.879707 -331.256907) (xy 237.896969 -331.201706) (xy 237.922367 -331.149744) (xy 237.955319 -331.102211)
			(xy 237.995068 -331.060197) (xy 238.017558 -331.04201) (xy 238.026321 -331.034449) (xy 238.036501 -331.013689)
			(xy 238.037116 -331.002132) (xy 238.037116 -330.921868) (xy 238.036501 -330.910306) (xy 238.026337 -330.889535)
			(xy 238.017558 -330.88199) (xy 237.995061 -330.863815) (xy 237.955329 -330.821791) (xy 237.922392 -330.774252)
			(xy 237.897007 -330.722288) (xy 237.879753 -330.667088) (xy 237.871026 -330.609917) (xy 237.870492 -330.581)
			(xy 237.870978 -330.553749) (xy 237.878734 -330.499801) (xy 237.894089 -330.447506) (xy 237.916731 -330.397929)
			(xy 237.946197 -330.352079) (xy 237.981888 -330.310888) (xy 238.023079 -330.275197) (xy 238.068929 -330.245731)
			(xy 238.118506 -330.223089) (xy 238.170801 -330.207734) (xy 238.224749 -330.199978) (xy 238.279251 -330.199978)
			(xy 238.333199 -330.207734) (xy 238.385494 -330.223089) (xy 238.435071 -330.245731) (xy 238.480921 -330.275197)
			(xy 238.522112 -330.310888) (xy 238.557803 -330.352079) (xy 238.587269 -330.397929) (xy 238.609911 -330.447506)
			(xy 238.625266 -330.499801) (xy 238.633022 -330.553749) (xy 238.633508 -330.581) (xy 238.633025 -330.609919)
			(xy 238.624293 -330.667093) (xy 238.607031 -330.722294) (xy 238.581633 -330.774256) (xy 238.548681 -330.821789)
			(xy 238.508932 -330.863803) (xy 238.486442 -330.88199) (xy 238.477679 -330.889551) (xy 238.467499 -330.910311)
			(xy 238.466884 -330.921868) (xy 238.466884 -331.002132) (xy 238.467499 -331.013694) (xy 238.477663 -331.034465)
			(xy 238.486442 -331.04201) (xy 238.508939 -331.060185) (xy 238.548671 -331.102209) (xy 238.581608 -331.149748)
			(xy 238.606993 -331.201712) (xy 238.624247 -331.256912) (xy 238.632974 -331.314083) (xy 238.633508 -331.343)
			(xy 238.633322 -331.353414) (xy 239.74298 -331.353414) (xy 239.743453 -331.32267) (xy 239.750875 -331.261631)
			(xy 239.765601 -331.201932) (xy 239.787415 -331.144444) (xy 239.816 -331.090004) (xy 239.850938 -331.039406)
			(xy 239.870996 -331.016102) (xy 239.876774 -331.008943) (xy 239.8833 -330.991763) (xy 239.883696 -330.982574)
			(xy 239.883696 -330.95184) (xy 239.883268 -330.942655) (xy 239.876767 -330.92547) (xy 239.870996 -330.918312)
			(xy 239.850945 -330.895) (xy 239.81599 -330.844412) (xy 239.787393 -330.789975) (xy 239.765572 -330.732487)
			(xy 239.750844 -330.672787) (xy 239.743427 -330.611745) (xy 239.74298 -330.581) (xy 239.743482 -330.549039)
			(xy 239.751493 -330.485621) (xy 239.76739 -330.423707) (xy 239.790922 -330.364274) (xy 239.821716 -330.308259)
			(xy 239.859289 -330.256544) (xy 239.903046 -330.209947) (xy 239.952299 -330.169202) (xy 240.00627 -330.134951)
			(xy 240.064109 -330.107734) (xy 240.124902 -330.087981) (xy 240.187692 -330.076003) (xy 240.251488 -330.07199)
			(xy 240.315284 -330.076003) (xy 240.378074 -330.087981) (xy 240.438867 -330.107734) (xy 240.496706 -330.134951)
			(xy 240.550677 -330.169202) (xy 240.59993 -330.209947) (xy 240.616179 -330.227251) (xy 244.982978 -330.227251)
			(xy 244.982978 -330.172749) (xy 244.990734 -330.118801) (xy 245.006089 -330.066506) (xy 245.028731 -330.016929)
			(xy 245.058197 -329.971079) (xy 245.093888 -329.929888) (xy 245.135079 -329.894197) (xy 245.180929 -329.864731)
			(xy 245.230506 -329.842089) (xy 245.282801 -329.826734) (xy 245.336749 -329.818978) (xy 245.364 -329.818492)
			(xy 245.39137 -329.81896) (xy 245.445549 -329.826778) (xy 245.498052 -329.842266) (xy 245.547799 -329.865108)
			(xy 245.593766 -329.894831) (xy 245.614698 -329.912472) (xy 245.62181 -329.918568) (xy 245.638828 -329.924918)
			(xy 245.724172 -329.924918) (xy 245.74119 -329.918568) (xy 245.748302 -329.912472) (xy 245.769235 -329.894831)
			(xy 245.815203 -329.865107) (xy 245.864949 -329.842261) (xy 245.917451 -329.826765) (xy 245.971629 -329.818936)
			(xy 246.026371 -329.818936) (xy 246.080549 -329.826765) (xy 246.133051 -329.842261) (xy 246.182797 -329.865107)
			(xy 246.228765 -329.894831) (xy 246.249698 -329.912472) (xy 246.25681 -329.918568) (xy 246.273828 -329.924918)
			(xy 246.359172 -329.924918) (xy 246.37619 -329.918568) (xy 246.383302 -329.912472) (xy 246.404219 -329.894814)
			(xy 246.450196 -329.865106) (xy 246.499948 -329.842274) (xy 246.552452 -329.826787) (xy 246.60663 -329.818964)
			(xy 246.634 -329.818492) (xy 246.661251 -329.818978) (xy 246.715199 -329.826734) (xy 246.767494 -329.842089)
			(xy 246.817071 -329.864731) (xy 246.862921 -329.894197) (xy 246.904112 -329.929888) (xy 246.939803 -329.971079)
			(xy 246.969269 -330.016929) (xy 246.991911 -330.066506) (xy 247.007266 -330.118801) (xy 247.015022 -330.172749)
			(xy 247.015022 -330.227251) (xy 247.007266 -330.281199) (xy 246.991911 -330.333494) (xy 246.969269 -330.383071)
			(xy 246.939803 -330.428921) (xy 246.904112 -330.470112) (xy 246.862921 -330.505803) (xy 246.817071 -330.535269)
			(xy 246.767494 -330.557911) (xy 246.715199 -330.573266) (xy 246.661404 -330.581) (xy 256.005076 -330.581)
			(xy 256.005578 -330.549039) (xy 256.013589 -330.485621) (xy 256.029486 -330.423707) (xy 256.053018 -330.364274)
			(xy 256.083812 -330.308259) (xy 256.121385 -330.256544) (xy 256.165142 -330.209947) (xy 256.214395 -330.169202)
			(xy 256.268366 -330.134951) (xy 256.326205 -330.107734) (xy 256.386998 -330.087981) (xy 256.449788 -330.076003)
			(xy 256.513584 -330.07199) (xy 256.57738 -330.076003) (xy 256.64017 -330.087981) (xy 256.700963 -330.107734)
			(xy 256.758802 -330.134951) (xy 256.812773 -330.169202) (xy 256.862026 -330.209947) (xy 256.905783 -330.256544)
			(xy 256.943356 -330.308259) (xy 256.97415 -330.364274) (xy 256.997682 -330.423707) (xy 257.013579 -330.485621)
			(xy 257.02159 -330.549039) (xy 257.022092 -330.581) (xy 257.021583 -330.612204) (xy 257.013931 -330.674141)
			(xy 256.998755 -330.734676) (xy 256.976282 -330.792898) (xy 256.946851 -330.847931) (xy 256.910905 -330.898947)
			(xy 256.868983 -330.945179) (xy 256.821718 -330.985931) (xy 256.810081 -330.993961) (xy 257.555994 -330.993961)
			(xy 257.555994 -330.930039) (xy 257.564005 -330.866621) (xy 257.579902 -330.804707) (xy 257.603434 -330.745274)
			(xy 257.634228 -330.689259) (xy 257.671801 -330.637544) (xy 257.715558 -330.590947) (xy 257.764811 -330.550202)
			(xy 257.818782 -330.515951) (xy 257.876621 -330.488734) (xy 257.937414 -330.468981) (xy 258.000204 -330.457003)
			(xy 258.064 -330.45299) (xy 258.127796 -330.457003) (xy 258.190586 -330.468981) (xy 258.251379 -330.488734)
			(xy 258.309218 -330.515951) (xy 258.363189 -330.550202) (xy 258.412442 -330.590947) (xy 258.456199 -330.637544)
			(xy 258.493772 -330.689259) (xy 258.524566 -330.745274) (xy 258.548098 -330.804707) (xy 258.563995 -330.866621)
			(xy 258.572006 -330.930039) (xy 258.572508 -330.962) (xy 258.572006 -330.993961) (xy 258.563995 -331.057379)
			(xy 258.548098 -331.119293) (xy 258.524566 -331.178726) (xy 258.493772 -331.234741) (xy 258.456199 -331.286456)
			(xy 258.412442 -331.333053) (xy 258.363189 -331.373798) (xy 258.309218 -331.408049) (xy 258.251379 -331.435266)
			(xy 258.190586 -331.455019) (xy 258.127796 -331.466997) (xy 258.064 -331.471011) (xy 258.000204 -331.466997)
			(xy 257.937414 -331.455019) (xy 257.876621 -331.435266) (xy 257.818782 -331.408049) (xy 257.764811 -331.373798)
			(xy 257.715558 -331.333053) (xy 257.671801 -331.286456) (xy 257.634228 -331.234741) (xy 257.603434 -331.178726)
			(xy 257.579902 -331.119293) (xy 257.564005 -331.057379) (xy 257.555994 -330.993961) (xy 256.810081 -330.993961)
			(xy 256.796032 -331.003656) (xy 256.785364 -331.011022) (xy 256.773426 -331.03312) (xy 256.77368 -331.14361)
			(xy 256.785618 -331.165708) (xy 256.79654 -331.173074) (xy 256.825068 -331.192646) (xy 256.877067 -331.23828)
			(xy 256.92239 -331.290551) (xy 256.960196 -331.348491) (xy 256.989786 -331.411027) (xy 257.000756 -331.443838)
			(xy 257.004058 -331.454506) (xy 257.018536 -331.470508) (xy 257.10896 -331.510132) (xy 257.13055 -331.509878)
			(xy 257.14071 -331.505306) (xy 257.166079 -331.493999) (xy 257.219277 -331.478044) (xy 257.27423 -331.469989)
			(xy 257.302 -331.469492) (xy 257.329251 -331.469978) (xy 257.383199 -331.477734) (xy 257.435494 -331.493089)
			(xy 257.485071 -331.515731) (xy 257.530921 -331.545197) (xy 257.572112 -331.580888) (xy 257.607803 -331.622079)
			(xy 257.637269 -331.667929) (xy 257.659911 -331.717506) (xy 257.675266 -331.769801) (xy 257.683022 -331.823749)
			(xy 257.683022 -331.878251) (xy 257.675266 -331.932199) (xy 257.659911 -331.984494) (xy 257.637269 -332.034071)
			(xy 257.607803 -332.079921) (xy 257.572112 -332.121112) (xy 257.530921 -332.156803) (xy 257.485071 -332.186269)
			(xy 257.435494 -332.208911) (xy 257.383199 -332.224266) (xy 257.329251 -332.232022) (xy 257.302 -332.232508)
			(xy 257.273045 -332.231997) (xy 257.215802 -332.223237) (xy 257.160538 -332.205934) (xy 257.108521 -332.180485)
			(xy 257.060942 -332.147473) (xy 257.018894 -332.107655) (xy 256.983341 -332.061944) (xy 256.968752 -332.036928)
			(xy 256.963418 -332.027276) (xy 256.945892 -332.014322) (xy 256.849626 -331.993748) (xy 256.82829 -331.99832)
			(xy 256.8194 -332.004924) (xy 256.793003 -332.023959) (xy 256.736265 -332.055838) (xy 256.675921 -332.080214)
			(xy 256.61296 -332.096689) (xy 256.548411 -332.104992) (xy 256.51587 -332.105508) (xy 256.485138 -332.105072)
			(xy 256.424124 -332.09766) (xy 256.364447 -332.082948) (xy 256.306979 -332.06115) (xy 256.252557 -332.032585)
			(xy 256.201975 -331.997668) (xy 256.15597 -331.956909) (xy 256.115214 -331.910901) (xy 256.0803 -331.860317)
			(xy 256.051737 -331.805894) (xy 256.029943 -331.748424) (xy 256.015234 -331.688747) (xy 256.007826 -331.627732)
			(xy 256.007362 -331.597) (xy 256.007847 -331.565795) (xy 256.0155 -331.503856) (xy 256.030678 -331.443319)
			(xy 256.053153 -331.385097) (xy 256.082588 -331.330063) (xy 256.118538 -331.279048) (xy 256.160464 -331.232817)
			(xy 256.207734 -331.192067) (xy 256.233422 -331.174344) (xy 256.24409 -331.166978) (xy 256.256028 -331.14488)
			(xy 256.255774 -331.03439) (xy 256.243836 -331.012292) (xy 256.232914 -331.004926) (xy 256.207024 -330.987249)
			(xy 256.159392 -330.94649) (xy 256.117133 -330.900182) (xy 256.08089 -330.849029) (xy 256.051213 -330.793808)
			(xy 256.028551 -330.735356) (xy 256.013249 -330.674561) (xy 256.00554 -330.612346) (xy 256.005076 -330.581)
			(xy 246.661404 -330.581) (xy 246.661251 -330.581022) (xy 246.634 -330.581508) (xy 246.60663 -330.58104)
			(xy 246.552451 -330.573222) (xy 246.499948 -330.557734) (xy 246.450201 -330.534892) (xy 246.404234 -330.505169)
			(xy 246.383302 -330.487528) (xy 246.37619 -330.481432) (xy 246.359172 -330.475082) (xy 246.273828 -330.475082)
			(xy 246.25681 -330.481432) (xy 246.249698 -330.487528) (xy 246.228765 -330.505169) (xy 246.182797 -330.534893)
			(xy 246.133051 -330.557739) (xy 246.080549 -330.573235) (xy 246.026371 -330.581064) (xy 245.971629 -330.581064)
			(xy 245.917451 -330.573235) (xy 245.864949 -330.557739) (xy 245.815203 -330.534893) (xy 245.769235 -330.505169)
			(xy 245.748302 -330.487528) (xy 245.74119 -330.481432) (xy 245.724172 -330.475082) (xy 245.638828 -330.475082)
			(xy 245.62181 -330.481432) (xy 245.614698 -330.487528) (xy 245.593781 -330.505186) (xy 245.547804 -330.534894)
			(xy 245.498052 -330.557726) (xy 245.445548 -330.573213) (xy 245.39137 -330.581036) (xy 245.364 -330.581508)
			(xy 245.336749 -330.581022) (xy 245.282801 -330.573266) (xy 245.230506 -330.557911) (xy 245.180929 -330.535269)
			(xy 245.135079 -330.505803) (xy 245.093888 -330.470112) (xy 245.058197 -330.428921) (xy 245.028731 -330.383071)
			(xy 245.006089 -330.333494) (xy 244.990734 -330.281199) (xy 244.982978 -330.227251) (xy 240.616179 -330.227251)
			(xy 240.643687 -330.256544) (xy 240.68126 -330.308259) (xy 240.712054 -330.364274) (xy 240.735586 -330.423707)
			(xy 240.751483 -330.485621) (xy 240.759494 -330.549039) (xy 240.759996 -330.581) (xy 240.759537 -330.611745)
			(xy 240.752113 -330.672784) (xy 240.737385 -330.732483) (xy 240.715568 -330.789972) (xy 240.686981 -330.844412)
			(xy 240.652039 -330.895009) (xy 240.63198 -330.918312) (xy 240.626194 -330.925464) (xy 240.619673 -330.942649)
			(xy 240.61928 -330.95184) (xy 240.61928 -330.982574) (xy 240.619707 -330.991759) (xy 240.62621 -331.008944)
			(xy 240.63198 -331.016102) (xy 240.652034 -331.039411) (xy 240.686989 -331.09) (xy 240.715586 -331.144437)
			(xy 240.737407 -331.201925) (xy 240.752134 -331.261627) (xy 240.75955 -331.322669) (xy 240.759996 -331.353414)
			(xy 240.759494 -331.385375) (xy 240.751483 -331.448793) (xy 240.735586 -331.510707) (xy 240.712054 -331.57014)
			(xy 240.68126 -331.626155) (xy 240.643687 -331.67787) (xy 240.59993 -331.724467) (xy 240.550677 -331.765212)
			(xy 240.496706 -331.799463) (xy 240.438867 -331.82668) (xy 240.378074 -331.846433) (xy 240.315284 -331.858411)
			(xy 240.251488 -331.862425) (xy 240.187692 -331.858411) (xy 240.124902 -331.846433) (xy 240.064109 -331.82668)
			(xy 240.00627 -331.799463) (xy 239.952299 -331.765212) (xy 239.903046 -331.724467) (xy 239.859289 -331.67787)
			(xy 239.821716 -331.626155) (xy 239.790922 -331.57014) (xy 239.76739 -331.510707) (xy 239.751493 -331.448793)
			(xy 239.743482 -331.385375) (xy 239.74298 -331.353414) (xy 238.633322 -331.353414) (xy 238.633022 -331.370251)
			(xy 238.625266 -331.424199) (xy 238.609911 -331.476494) (xy 238.587269 -331.526071) (xy 238.557803 -331.571921)
			(xy 238.522112 -331.613112) (xy 238.480921 -331.648803) (xy 238.435071 -331.678269) (xy 238.385494 -331.700911)
			(xy 238.333199 -331.716266) (xy 238.279251 -331.724022) (xy 238.224749 -331.724022) (xy 238.170801 -331.716266)
			(xy 238.118506 -331.700911) (xy 238.068929 -331.678269) (xy 238.023079 -331.648803) (xy 237.981888 -331.613112)
			(xy 237.946197 -331.571921) (xy 237.916731 -331.526071) (xy 237.894089 -331.476494) (xy 237.878734 -331.424199)
			(xy 237.870978 -331.370251) (xy 237.870492 -331.343) (xy 237.385352 -331.343) (xy 237.385352 -332.613)
			(xy 237.869982 -332.613) (xy 237.874053 -332.557378) (xy 237.886179 -332.502941) (xy 237.906102 -332.45085)
			(xy 237.933398 -332.402215) (xy 237.967484 -332.358072) (xy 238.007633 -332.319363) (xy 238.052991 -332.286912)
			(xy 238.102591 -332.261411) (xy 238.155375 -332.243404) (xy 238.210218 -332.233274) (xy 238.265952 -332.231237)
			(xy 238.321389 -332.237337) (xy 238.375346 -332.251443) (xy 238.426675 -332.273255) (xy 238.474281 -332.302309)
			(xy 238.517149 -332.337984) (xy 238.554366 -332.379521) (xy 238.585139 -332.426034) (xy 238.608811 -332.476531)
			(xy 238.624879 -332.529938) (xy 238.632999 -332.585114) (xy 238.633508 -332.613) (xy 238.632999 -332.640886)
			(xy 238.632399 -332.644961) (xy 239.678712 -332.644961) (xy 239.678712 -332.581039) (xy 239.686723 -332.517621)
			(xy 239.70262 -332.455707) (xy 239.726152 -332.396274) (xy 239.756946 -332.340259) (xy 239.794519 -332.288544)
			(xy 239.838276 -332.241947) (xy 239.887529 -332.201202) (xy 239.9415 -332.166951) (xy 239.999339 -332.139734)
			(xy 240.060132 -332.119981) (xy 240.122922 -332.108003) (xy 240.186718 -332.10399) (xy 240.202774 -332.105)
			(xy 247.267982 -332.105) (xy 247.272053 -332.049378) (xy 247.284179 -331.994941) (xy 247.304102 -331.94285)
			(xy 247.331398 -331.894215) (xy 247.365484 -331.850072) (xy 247.405633 -331.811363) (xy 247.450991 -331.778912)
			(xy 247.500591 -331.753411) (xy 247.553375 -331.735404) (xy 247.608218 -331.725274) (xy 247.663952 -331.723237)
			(xy 247.719389 -331.729337) (xy 247.773346 -331.743443) (xy 247.824675 -331.765255) (xy 247.872281 -331.794309)
			(xy 247.915149 -331.829984) (xy 247.952366 -331.871521) (xy 247.983139 -331.918034) (xy 248.006811 -331.968531)
			(xy 248.022879 -332.021938) (xy 248.030999 -332.077114) (xy 248.031508 -332.105) (xy 248.030999 -332.132886)
			(xy 248.030399 -332.136961) (xy 248.919994 -332.136961) (xy 248.919994 -332.073039) (xy 248.928005 -332.009621)
			(xy 248.943902 -331.947707) (xy 248.967434 -331.888274) (xy 248.998228 -331.832259) (xy 249.035801 -331.780544)
			(xy 249.079558 -331.733947) (xy 249.128811 -331.693202) (xy 249.182782 -331.658951) (xy 249.240621 -331.631734)
			(xy 249.301414 -331.611981) (xy 249.364204 -331.600003) (xy 249.428 -331.59599) (xy 249.491796 -331.600003)
			(xy 249.554586 -331.611981) (xy 249.615379 -331.631734) (xy 249.673218 -331.658951) (xy 249.727189 -331.693202)
			(xy 249.776442 -331.733947) (xy 249.820199 -331.780544) (xy 249.857772 -331.832259) (xy 249.888566 -331.888274)
			(xy 249.912098 -331.947707) (xy 249.927995 -332.009621) (xy 249.936006 -332.073039) (xy 249.936508 -332.105)
			(xy 249.936006 -332.136961) (xy 249.927995 -332.200379) (xy 249.912098 -332.262293) (xy 249.888566 -332.321726)
			(xy 249.857772 -332.377741) (xy 249.820199 -332.429456) (xy 249.776442 -332.476053) (xy 249.727189 -332.516798)
			(xy 249.673218 -332.551049) (xy 249.615379 -332.578266) (xy 249.554586 -332.598019) (xy 249.491796 -332.609997)
			(xy 249.428 -332.614011) (xy 249.364204 -332.609997) (xy 249.301414 -332.598019) (xy 249.240621 -332.578266)
			(xy 249.182782 -332.551049) (xy 249.128811 -332.516798) (xy 249.079558 -332.476053) (xy 249.035801 -332.429456)
			(xy 248.998228 -332.377741) (xy 248.967434 -332.321726) (xy 248.943902 -332.262293) (xy 248.928005 -332.200379)
			(xy 248.919994 -332.136961) (xy 248.030399 -332.136961) (xy 248.022879 -332.188062) (xy 248.006811 -332.241469)
			(xy 247.983139 -332.291966) (xy 247.952366 -332.338479) (xy 247.915149 -332.380016) (xy 247.872281 -332.415691)
			(xy 247.824675 -332.444745) (xy 247.773346 -332.466557) (xy 247.719389 -332.480663) (xy 247.663952 -332.486763)
			(xy 247.608218 -332.484726) (xy 247.553375 -332.474596) (xy 247.500591 -332.456589) (xy 247.450991 -332.431088)
			(xy 247.405633 -332.398637) (xy 247.365484 -332.359928) (xy 247.331398 -332.315785) (xy 247.304102 -332.26715)
			(xy 247.284179 -332.215059) (xy 247.272053 -332.160622) (xy 247.267982 -332.105) (xy 240.202774 -332.105)
			(xy 240.250514 -332.108003) (xy 240.313304 -332.119981) (xy 240.374097 -332.139734) (xy 240.431936 -332.166951)
			(xy 240.485907 -332.201202) (xy 240.53516 -332.241947) (xy 240.578917 -332.288544) (xy 240.61649 -332.340259)
			(xy 240.647284 -332.396274) (xy 240.670816 -332.455707) (xy 240.686713 -332.517621) (xy 240.694724 -332.581039)
			(xy 240.695226 -332.613) (xy 240.694724 -332.644961) (xy 240.686713 -332.708379) (xy 240.670816 -332.770293)
			(xy 240.647284 -332.829726) (xy 240.61649 -332.885741) (xy 240.578917 -332.937456) (xy 240.53516 -332.984053)
			(xy 240.485907 -333.024798) (xy 240.431936 -333.059049) (xy 240.374097 -333.086266) (xy 240.313304 -333.106019)
			(xy 240.250514 -333.117997) (xy 240.186718 -333.122011) (xy 240.122922 -333.117997) (xy 240.060132 -333.106019)
			(xy 239.999339 -333.086266) (xy 239.9415 -333.059049) (xy 239.887529 -333.024798) (xy 239.838276 -332.984053)
			(xy 239.794519 -332.937456) (xy 239.756946 -332.885741) (xy 239.726152 -332.829726) (xy 239.70262 -332.770293)
			(xy 239.686723 -332.708379) (xy 239.678712 -332.644961) (xy 238.632399 -332.644961) (xy 238.624879 -332.696062)
			(xy 238.608811 -332.749469) (xy 238.585139 -332.799966) (xy 238.554366 -332.846479) (xy 238.517149 -332.888016)
			(xy 238.474281 -332.923691) (xy 238.426675 -332.952745) (xy 238.375346 -332.974557) (xy 238.321389 -332.988663)
			(xy 238.265952 -332.994763) (xy 238.210218 -332.992726) (xy 238.155375 -332.982596) (xy 238.102591 -332.964589)
			(xy 238.052991 -332.939088) (xy 238.007633 -332.906637) (xy 237.967484 -332.867928) (xy 237.933398 -332.823785)
			(xy 237.906102 -332.77515) (xy 237.886179 -332.723059) (xy 237.874053 -332.668622) (xy 237.869982 -332.613)
			(xy 237.385352 -332.613) (xy 237.385352 -333.087218) (xy 237.385795 -333.097377) (xy 237.393643 -333.116118)
			(xy 237.400592 -333.12354) (xy 237.45952 -333.181706) (xy 237.478316 -333.189072) (xy 237.48873 -333.188818)
			(xy 237.497112 -333.188818) (xy 237.527843 -333.189264) (xy 237.588857 -333.196674) (xy 237.648533 -333.211385)
			(xy 237.706 -333.233181) (xy 237.760421 -333.261746) (xy 237.811002 -333.296662) (xy 237.857006 -333.337421)
			(xy 237.897761 -333.383427) (xy 237.932674 -333.434011) (xy 237.961234 -333.488435) (xy 237.983026 -333.545904)
			(xy 237.997733 -333.605581) (xy 238.005138 -333.666595) (xy 238.00562 -333.697326) (xy 238.005175 -333.727441)
			(xy 237.998059 -333.78725) (xy 237.983931 -333.845799) (xy 237.962988 -333.902271) (xy 237.956486 -333.914961)
			(xy 240.195094 -333.914961) (xy 240.195094 -333.851039) (xy 240.203105 -333.787621) (xy 240.219002 -333.725707)
			(xy 240.242534 -333.666274) (xy 240.273328 -333.610259) (xy 240.310901 -333.558544) (xy 240.354658 -333.511947)
			(xy 240.403911 -333.471202) (xy 240.457882 -333.436951) (xy 240.515721 -333.409734) (xy 240.576514 -333.389981)
			(xy 240.639304 -333.378003) (xy 240.7031 -333.37399) (xy 240.766896 -333.378003) (xy 240.829686 -333.389981)
			(xy 240.890479 -333.409734) (xy 240.915353 -333.421439) (xy 246.483626 -333.421439) (xy 246.483626 -333.357517)
			(xy 246.491637 -333.294099) (xy 246.507534 -333.232185) (xy 246.531066 -333.172752) (xy 246.56186 -333.116737)
			(xy 246.599433 -333.065022) (xy 246.64319 -333.018425) (xy 246.692443 -332.97768) (xy 246.746414 -332.943429)
			(xy 246.804253 -332.916212) (xy 246.865046 -332.896459) (xy 246.927836 -332.884481) (xy 246.991632 -332.880468)
			(xy 247.055428 -332.884481) (xy 247.118218 -332.896459) (xy 247.125918 -332.898961) (xy 253.326894 -332.898961)
			(xy 253.326894 -332.835039) (xy 253.334905 -332.771621) (xy 253.350802 -332.709707) (xy 253.374334 -332.650274)
			(xy 253.405128 -332.594259) (xy 253.442701 -332.542544) (xy 253.486458 -332.495947) (xy 253.535711 -332.455202)
			(xy 253.589682 -332.420951) (xy 253.647521 -332.393734) (xy 253.708314 -332.373981) (xy 253.771104 -332.362003)
			(xy 253.8349 -332.35799) (xy 253.898696 -332.362003) (xy 253.961486 -332.373981) (xy 254.022279 -332.393734)
			(xy 254.080118 -332.420951) (xy 254.134089 -332.455202) (xy 254.183342 -332.495947) (xy 254.227099 -332.542544)
			(xy 254.264672 -332.594259) (xy 254.295466 -332.650274) (xy 254.318998 -332.709707) (xy 254.334895 -332.771621)
			(xy 254.342906 -332.835039) (xy 254.343408 -332.867) (xy 256.323082 -332.867) (xy 256.327153 -332.811378)
			(xy 256.339279 -332.756941) (xy 256.359202 -332.70485) (xy 256.386498 -332.656215) (xy 256.420584 -332.612072)
			(xy 256.460733 -332.573363) (xy 256.506091 -332.540912) (xy 256.555691 -332.515411) (xy 256.608475 -332.497404)
			(xy 256.663318 -332.487274) (xy 256.719052 -332.485237) (xy 256.774489 -332.491337) (xy 256.828446 -332.505443)
			(xy 256.879775 -332.527255) (xy 256.927381 -332.556309) (xy 256.970249 -332.591984) (xy 257.007466 -332.633521)
			(xy 257.038239 -332.680034) (xy 257.061911 -332.730531) (xy 257.077979 -332.783938) (xy 257.086099 -332.839114)
			(xy 257.086608 -332.867) (xy 257.086099 -332.894886) (xy 257.077979 -332.950062) (xy 257.061911 -333.003469)
			(xy 257.038239 -333.053966) (xy 257.007466 -333.100479) (xy 256.970249 -333.142016) (xy 256.927381 -333.177691)
			(xy 256.879775 -333.206745) (xy 256.828446 -333.228557) (xy 256.774489 -333.242663) (xy 256.719052 -333.248763)
			(xy 256.663318 -333.246726) (xy 256.608475 -333.236596) (xy 256.555691 -333.218589) (xy 256.506091 -333.193088)
			(xy 256.460733 -333.160637) (xy 256.420584 -333.121928) (xy 256.386498 -333.077785) (xy 256.359202 -333.02915)
			(xy 256.339279 -332.977059) (xy 256.327153 -332.922622) (xy 256.323082 -332.867) (xy 254.343408 -332.867)
			(xy 254.342906 -332.898961) (xy 254.334895 -332.962379) (xy 254.318998 -333.024293) (xy 254.295466 -333.083726)
			(xy 254.264672 -333.139741) (xy 254.227099 -333.191456) (xy 254.183342 -333.238053) (xy 254.134089 -333.278798)
			(xy 254.080118 -333.313049) (xy 254.022279 -333.340266) (xy 253.961486 -333.360019) (xy 253.898696 -333.371997)
			(xy 253.8349 -333.376011) (xy 253.771104 -333.371997) (xy 253.708314 -333.360019) (xy 253.647521 -333.340266)
			(xy 253.589682 -333.313049) (xy 253.535711 -333.278798) (xy 253.486458 -333.238053) (xy 253.442701 -333.191456)
			(xy 253.405128 -333.139741) (xy 253.374334 -333.083726) (xy 253.350802 -333.024293) (xy 253.334905 -332.962379)
			(xy 253.326894 -332.898961) (xy 247.125918 -332.898961) (xy 247.179011 -332.916212) (xy 247.23685 -332.943429)
			(xy 247.290821 -332.97768) (xy 247.340074 -333.018425) (xy 247.383831 -333.065022) (xy 247.421404 -333.116737)
			(xy 247.452198 -333.172752) (xy 247.47573 -333.232185) (xy 247.491627 -333.294099) (xy 247.499638 -333.357517)
			(xy 247.50014 -333.389478) (xy 247.499638 -333.421439) (xy 247.491627 -333.484857) (xy 247.47573 -333.546771)
			(xy 247.452198 -333.606204) (xy 247.421404 -333.662219) (xy 247.383831 -333.713934) (xy 247.340074 -333.760531)
			(xy 247.290821 -333.801276) (xy 247.23685 -333.835527) (xy 247.179011 -333.862744) (xy 247.118218 -333.882497)
			(xy 247.055428 -333.894475) (xy 246.991632 -333.898489) (xy 246.927836 -333.894475) (xy 246.865046 -333.882497)
			(xy 246.804253 -333.862744) (xy 246.746414 -333.835527) (xy 246.692443 -333.801276) (xy 246.64319 -333.760531)
			(xy 246.599433 -333.713934) (xy 246.56186 -333.662219) (xy 246.531066 -333.606204) (xy 246.507534 -333.546771)
			(xy 246.491637 -333.484857) (xy 246.483626 -333.421439) (xy 240.915353 -333.421439) (xy 240.948318 -333.436951)
			(xy 241.002289 -333.471202) (xy 241.051542 -333.511947) (xy 241.095299 -333.558544) (xy 241.132872 -333.610259)
			(xy 241.163666 -333.666274) (xy 241.187198 -333.725707) (xy 241.203095 -333.787621) (xy 241.211106 -333.851039)
			(xy 241.211608 -333.883) (xy 241.211106 -333.914961) (xy 241.203095 -333.978379) (xy 241.187198 -334.040293)
			(xy 241.163666 -334.099726) (xy 241.132872 -334.155741) (xy 241.095299 -334.207456) (xy 241.051542 -334.254053)
			(xy 241.002289 -334.294798) (xy 240.948318 -334.329049) (xy 240.890479 -334.356266) (xy 240.829686 -334.376019)
			(xy 240.766896 -334.387997) (xy 240.7031 -334.392011) (xy 240.639304 -334.387997) (xy 240.576514 -334.376019)
			(xy 240.515721 -334.356266) (xy 240.457882 -334.329049) (xy 240.403911 -334.294798) (xy 240.354658 -334.254053)
			(xy 240.310901 -334.207456) (xy 240.273328 -334.155741) (xy 240.242534 -334.099726) (xy 240.219002 -334.040293)
			(xy 240.203105 -333.978379) (xy 240.195094 -333.914961) (xy 237.956486 -333.914961) (xy 237.935523 -333.955875)
			(xy 237.901921 -334.005861) (xy 237.862651 -334.051529) (xy 237.840774 -334.07223) (xy 237.832138 -334.080104)
			(xy 237.823502 -334.10144) (xy 237.831122 -334.204564) (xy 237.842552 -334.224376) (xy 237.852204 -334.23098)
			(xy 237.877539 -334.248755) (xy 237.924121 -334.289504) (xy 237.965408 -334.335609) (xy 238.00079 -334.386389)
			(xy 238.029741 -334.44109) (xy 238.051833 -334.498903) (xy 238.066739 -334.558971) (xy 238.074239 -334.620405)
			(xy 238.074708 -334.65135) (xy 238.074241 -334.682079) (xy 238.066828 -334.743088) (xy 238.052115 -334.802759)
			(xy 238.030317 -334.860222) (xy 238.001752 -334.914639) (xy 237.966837 -334.965216) (xy 237.92608 -335.011216)
			(xy 237.880076 -335.051968) (xy 237.871393 -335.057961) (xy 240.195094 -335.057961) (xy 240.195094 -334.994039)
			(xy 240.203105 -334.930621) (xy 240.219002 -334.868707) (xy 240.242534 -334.809274) (xy 240.273328 -334.753259)
			(xy 240.310901 -334.701544) (xy 240.354658 -334.654947) (xy 240.403911 -334.614202) (xy 240.457882 -334.579951)
			(xy 240.515721 -334.552734) (xy 240.576514 -334.532981) (xy 240.639304 -334.521003) (xy 240.7031 -334.51699)
			(xy 240.766896 -334.521003) (xy 240.829686 -334.532981) (xy 240.890479 -334.552734) (xy 240.948318 -334.579951)
			(xy 241.002289 -334.614202) (xy 241.051542 -334.654947) (xy 241.095299 -334.701544) (xy 241.132872 -334.753259)
			(xy 241.163666 -334.809274) (xy 241.187198 -334.868707) (xy 241.203095 -334.930621) (xy 241.211106 -334.994039)
			(xy 241.211608 -335.026) (xy 241.211106 -335.057961) (xy 241.203095 -335.121379) (xy 241.187198 -335.183293)
			(xy 241.163666 -335.242726) (xy 241.132872 -335.298741) (xy 241.095299 -335.350456) (xy 241.051542 -335.397053)
			(xy 241.002289 -335.437798) (xy 240.948318 -335.472049) (xy 240.890479 -335.499266) (xy 240.829686 -335.519019)
			(xy 240.766896 -335.530997) (xy 240.7031 -335.535011) (xy 240.639304 -335.530997) (xy 240.576514 -335.519019)
			(xy 240.515721 -335.499266) (xy 240.457882 -335.472049) (xy 240.403911 -335.437798) (xy 240.354658 -335.397053)
			(xy 240.310901 -335.350456) (xy 240.273328 -335.298741) (xy 240.242534 -335.242726) (xy 240.219002 -335.183293)
			(xy 240.203105 -335.121379) (xy 240.195094 -335.057961) (xy 237.871393 -335.057961) (xy 237.829496 -335.086878)
			(xy 237.775077 -335.115437) (xy 237.717612 -335.13723) (xy 237.657939 -335.151937) (xy 237.596929 -335.159344)
			(xy 237.5662 -335.159858) (xy 237.549641 -335.159726) (xy 237.516595 -335.157566) (xy 237.50016 -335.15554)
			(xy 237.489238 -335.154016) (xy 237.46841 -335.160366) (xy 237.402624 -335.218024) (xy 237.394788 -335.225612)
			(xy 237.38584 -335.245481) (xy 237.385352 -335.256378) (xy 237.385352 -336.200961) (xy 240.195094 -336.200961)
			(xy 240.195094 -336.137039) (xy 240.203105 -336.073621) (xy 240.219002 -336.011707) (xy 240.242534 -335.952274)
			(xy 240.273328 -335.896259) (xy 240.310901 -335.844544) (xy 240.354658 -335.797947) (xy 240.403911 -335.757202)
			(xy 240.457882 -335.722951) (xy 240.515721 -335.695734) (xy 240.576514 -335.675981) (xy 240.639304 -335.664003)
			(xy 240.7031 -335.65999) (xy 240.766896 -335.664003) (xy 240.829686 -335.675981) (xy 240.890479 -335.695734)
			(xy 240.948318 -335.722951) (xy 241.002289 -335.757202) (xy 241.051542 -335.797947) (xy 241.095299 -335.844544)
			(xy 241.132872 -335.896259) (xy 241.163666 -335.952274) (xy 241.187198 -336.011707) (xy 241.203095 -336.073621)
			(xy 241.211106 -336.137039) (xy 241.211608 -336.169) (xy 241.211106 -336.200961) (xy 241.203095 -336.264379)
			(xy 241.187198 -336.326293) (xy 241.163666 -336.385726) (xy 241.132872 -336.441741) (xy 241.095299 -336.493456)
			(xy 241.051542 -336.540053) (xy 241.002289 -336.580798) (xy 240.948318 -336.615049) (xy 240.890479 -336.642266)
			(xy 240.829686 -336.662019) (xy 240.766896 -336.673997) (xy 240.7031 -336.678011) (xy 240.639304 -336.673997)
			(xy 240.576514 -336.662019) (xy 240.515721 -336.642266) (xy 240.457882 -336.615049) (xy 240.403911 -336.580798)
			(xy 240.354658 -336.540053) (xy 240.310901 -336.493456) (xy 240.273328 -336.441741) (xy 240.242534 -336.385726)
			(xy 240.219002 -336.326293) (xy 240.203105 -336.264379) (xy 240.195094 -336.200961) (xy 237.385352 -336.200961)
			(xy 237.385352 -336.371184) (xy 237.385792 -336.381246) (xy 237.393534 -336.399824) (xy 237.400338 -336.407252)
			(xy 237.419321 -336.426857) (xy 237.452059 -336.470517) (xy 237.478242 -336.518396) (xy 237.497337 -336.569517)
			(xy 237.508954 -336.622836) (xy 237.512856 -336.677267) (xy 237.508963 -336.731699) (xy 237.497355 -336.785021)
			(xy 237.478269 -336.836145) (xy 237.452094 -336.884028) (xy 237.419364 -336.927694) (xy 237.400338 -336.947256)
			(xy 237.393496 -336.954656) (xy 237.385776 -336.973254) (xy 237.385352 -336.983324) (xy 237.385352 -337.343961)
			(xy 240.195094 -337.343961) (xy 240.195094 -337.280039) (xy 240.203105 -337.216621) (xy 240.219002 -337.154707)
			(xy 240.242534 -337.095274) (xy 240.273328 -337.039259) (xy 240.310901 -336.987544) (xy 240.354658 -336.940947)
			(xy 240.403911 -336.900202) (xy 240.457882 -336.865951) (xy 240.515721 -336.838734) (xy 240.576514 -336.818981)
			(xy 240.639304 -336.807003) (xy 240.7031 -336.80299) (xy 240.766896 -336.807003) (xy 240.829686 -336.818981)
			(xy 240.890479 -336.838734) (xy 240.948318 -336.865951) (xy 241.002289 -336.900202) (xy 241.051542 -336.940947)
			(xy 241.095299 -336.987544) (xy 241.132872 -337.039259) (xy 241.163666 -337.095274) (xy 241.187198 -337.154707)
			(xy 241.203095 -337.216621) (xy 241.211106 -337.280039) (xy 241.211608 -337.312) (xy 241.211106 -337.343961)
			(xy 241.203095 -337.407379) (xy 241.187198 -337.469293) (xy 241.163666 -337.528726) (xy 241.132872 -337.584741)
			(xy 241.095299 -337.636456) (xy 241.051542 -337.683053) (xy 241.002289 -337.723798) (xy 240.948318 -337.758049)
			(xy 240.890479 -337.785266) (xy 240.829686 -337.805019) (xy 240.766896 -337.816997) (xy 240.7031 -337.821011)
			(xy 240.639304 -337.816997) (xy 240.576514 -337.805019) (xy 240.515721 -337.785266) (xy 240.457882 -337.758049)
			(xy 240.403911 -337.723798) (xy 240.354658 -337.683053) (xy 240.310901 -337.636456) (xy 240.273328 -337.584741)
			(xy 240.242534 -337.528726) (xy 240.219002 -337.469293) (xy 240.203105 -337.407379) (xy 240.195094 -337.343961)
			(xy 237.385352 -337.343961) (xy 237.385352 -338.486961) (xy 240.195094 -338.486961) (xy 240.195094 -338.423039)
			(xy 240.203105 -338.359621) (xy 240.219002 -338.297707) (xy 240.242534 -338.238274) (xy 240.273328 -338.182259)
			(xy 240.310901 -338.130544) (xy 240.354658 -338.083947) (xy 240.403911 -338.043202) (xy 240.457882 -338.008951)
			(xy 240.515721 -337.981734) (xy 240.576514 -337.961981) (xy 240.639304 -337.950003) (xy 240.7031 -337.94599)
			(xy 240.766896 -337.950003) (xy 240.829686 -337.961981) (xy 240.890479 -337.981734) (xy 240.948318 -338.008951)
			(xy 241.002289 -338.043202) (xy 241.051542 -338.083947) (xy 241.095299 -338.130544) (xy 241.132872 -338.182259)
			(xy 241.163666 -338.238274) (xy 241.187198 -338.297707) (xy 241.203095 -338.359621) (xy 241.211106 -338.423039)
			(xy 241.211608 -338.455) (xy 241.211106 -338.486961) (xy 241.203095 -338.550379) (xy 241.187198 -338.612293)
			(xy 241.163666 -338.671726) (xy 241.132872 -338.727741) (xy 241.095299 -338.779456) (xy 241.051542 -338.826053)
			(xy 241.002289 -338.866798) (xy 240.948318 -338.901049) (xy 240.890479 -338.928266) (xy 240.829686 -338.948019)
			(xy 240.766896 -338.959997) (xy 240.7031 -338.964011) (xy 240.639304 -338.959997) (xy 240.576514 -338.948019)
			(xy 240.515721 -338.928266) (xy 240.457882 -338.901049) (xy 240.403911 -338.866798) (xy 240.354658 -338.826053)
			(xy 240.310901 -338.779456) (xy 240.273328 -338.727741) (xy 240.242534 -338.671726) (xy 240.219002 -338.612293)
			(xy 240.203105 -338.550379) (xy 240.195094 -338.486961) (xy 237.385352 -338.486961) (xy 237.385352 -339.629961)
			(xy 240.195094 -339.629961) (xy 240.195094 -339.566039) (xy 240.203105 -339.502621) (xy 240.219002 -339.440707)
			(xy 240.242534 -339.381274) (xy 240.273328 -339.325259) (xy 240.310901 -339.273544) (xy 240.354658 -339.226947)
			(xy 240.403911 -339.186202) (xy 240.457882 -339.151951) (xy 240.515721 -339.124734) (xy 240.576514 -339.104981)
			(xy 240.639304 -339.093003) (xy 240.7031 -339.08899) (xy 240.719156 -339.09) (xy 256.539492 -339.09)
			(xy 256.540029 -339.060845) (xy 256.54893 -339.003218) (xy 256.566493 -338.947616) (xy 256.59231 -338.895332)
			(xy 256.625779 -338.847584) (xy 256.666123 -338.805484) (xy 256.712402 -338.77001) (xy 256.763538 -338.741989)
			(xy 256.818342 -338.722073) (xy 256.846832 -338.715858) (xy 256.856738 -338.713826) (xy 256.873248 -338.702904)
			(xy 256.92481 -338.628482) (xy 256.929128 -338.609178) (xy 256.92735 -338.599526) (xy 256.924136 -338.578784)
			(xy 256.9207 -338.536948) (xy 256.920492 -338.51596) (xy 256.920965 -338.483111) (xy 256.929424 -338.417961)
			(xy 256.94621 -338.354443) (xy 256.971041 -338.293619) (xy 257.003505 -338.236503) (xy 257.043059 -338.184047)
			(xy 257.089043 -338.137126) (xy 257.114548 -338.116418) (xy 257.126232 -338.107274) (xy 257.135884 -338.079334)
			(xy 257.107944 -337.960716) (xy 257.086862 -337.940142) (xy 257.07213 -337.937094) (xy 257.041279 -337.930185)
			(xy 256.981433 -337.909804) (xy 256.924574 -337.882163) (xy 256.871578 -337.84769) (xy 256.823263 -337.806916)
			(xy 256.780372 -337.760469) (xy 256.743567 -337.709065) (xy 256.713416 -337.653496) (xy 256.690383 -337.59462)
			(xy 256.674824 -337.533343) (xy 256.666977 -337.470611) (xy 256.666492 -337.439) (xy 256.666943 -337.407234)
			(xy 256.674879 -337.3442) (xy 256.690604 -337.282644) (xy 256.713873 -337.223526) (xy 256.744322 -337.167767)
			(xy 256.781479 -337.116233) (xy 256.824764 -337.069727) (xy 256.873503 -337.028975) (xy 256.926938 -336.994609)
			(xy 256.984237 -336.967165) (xy 257.014218 -336.956654) (xy 257.024124 -336.953352) (xy 257.039872 -336.939128)
			(xy 257.079496 -336.852514) (xy 257.080004 -336.831432) (xy 257.07594 -336.82178) (xy 257.066915 -336.798723)
			(xy 257.05424 -336.750859) (xy 257.047867 -336.701757) (xy 257.047492 -336.677) (xy 257.047886 -336.652244)
			(xy 257.054261 -336.603144) (xy 257.066929 -336.555281) (xy 257.07594 -336.53222) (xy 257.080004 -336.522568)
			(xy 257.079496 -336.501486) (xy 257.039872 -336.414872) (xy 257.024124 -336.400648) (xy 257.014218 -336.397346)
			(xy 256.984222 -336.386871) (xy 256.926911 -336.359441) (xy 256.873465 -336.325082) (xy 256.824719 -336.28433)
			(xy 256.781431 -336.237821) (xy 256.744277 -336.186279) (xy 256.713836 -336.130508) (xy 256.690584 -336.071379)
			(xy 256.674882 -336.009812) (xy 256.666976 -335.946769) (xy 256.666492 -335.915) (xy 256.666974 -335.882215)
			(xy 256.675407 -335.817191) (xy 256.692132 -335.753791) (xy 256.716872 -335.693068) (xy 256.749216 -335.636032)
			(xy 256.788626 -335.583628) (xy 256.834449 -335.536729) (xy 256.885923 -335.496111) (xy 256.942192 -335.462451)
			(xy 256.972054 -335.44891) (xy 256.982468 -335.444338) (xy 256.9972 -335.42732) (xy 257.025394 -335.330292)
			(xy 257.021838 -335.308194) (xy 257.015488 -335.298542) (xy 256.998848 -335.27322) (xy 256.971024 -335.219394)
			(xy 256.949805 -335.162638) (xy 256.935493 -335.10376) (xy 256.928292 -335.043596) (xy 256.927858 -335.0133)
			(xy 256.928318 -334.983182) (xy 256.935418 -334.923366) (xy 256.949531 -334.864808) (xy 256.97046 -334.808325)
			(xy 256.997911 -334.754708) (xy 257.031501 -334.704708) (xy 257.050794 -334.681576) (xy 257.056271 -334.674779)
			(xy 257.062629 -334.658534) (xy 257.06324 -334.649826) (xy 257.064002 -334.620108) (xy 257.063896 -334.61135)
			(xy 257.058431 -334.59472) (xy 257.053334 -334.587596) (xy 257.033276 -334.560801) (xy 256.999643 -334.502932)
			(xy 256.973895 -334.441149) (xy 256.956479 -334.376521) (xy 256.947695 -334.310167) (xy 256.947162 -334.2767)
			(xy 256.947619 -334.244387) (xy 256.955818 -334.180284) (xy 256.972072 -334.117735) (xy 256.996119 -334.05775)
			(xy 257.027571 -334.001295) (xy 257.065922 -333.949278) (xy 257.110553 -333.902539) (xy 257.160746 -333.861831)
			(xy 257.187954 -333.844392) (xy 257.198876 -333.837788) (xy 257.211322 -333.816452) (xy 257.21691 -333.70774)
			(xy 257.206496 -333.685134) (xy 257.196336 -333.677514) (xy 257.173591 -333.659332) (xy 257.133393 -333.617205)
			(xy 257.100056 -333.569463) (xy 257.074353 -333.517214) (xy 257.056879 -333.461669) (xy 257.04804 -333.404114)
			(xy 257.047492 -333.375) (xy 257.047978 -333.347749) (xy 257.055734 -333.293801) (xy 257.071089 -333.241506)
			(xy 257.093731 -333.191929) (xy 257.123197 -333.146079) (xy 257.158888 -333.104888) (xy 257.200079 -333.069197)
			(xy 257.245929 -333.039731) (xy 257.295506 -333.017089) (xy 257.347801 -333.001734) (xy 257.401749 -332.993978)
			(xy 257.456251 -332.993978) (xy 257.510199 -333.001734) (xy 257.562494 -333.017089) (xy 257.612071 -333.039731)
			(xy 257.657921 -333.069197) (xy 257.699112 -333.104888) (xy 257.734803 -333.146079) (xy 257.764269 -333.191929)
			(xy 257.786911 -333.241506) (xy 257.802266 -333.293801) (xy 257.810022 -333.347749) (xy 257.810508 -333.375)
			(xy 257.810009 -333.402224) (xy 257.80225 -333.456116) (xy 257.786903 -333.508357) (xy 257.764281 -333.557883)
			(xy 257.734844 -333.603688) (xy 257.699191 -333.644839) (xy 257.678936 -333.663036) (xy 257.669538 -333.671418)
			(xy 257.660394 -333.694532) (xy 257.672332 -333.802736) (xy 257.686302 -333.82331) (xy 257.697224 -333.829406)
			(xy 257.723757 -333.844238) (xy 257.773435 -333.879268) (xy 257.818579 -333.919974) (xy 257.858545 -333.965775)
			(xy 257.892762 -334.016016) (xy 257.920741 -334.069981) (xy 257.942083 -334.126898) (xy 257.956482 -334.185954)
			(xy 257.963734 -334.246307) (xy 257.964178 -334.2767) (xy 257.963734 -334.306818) (xy 257.956632 -334.366635)
			(xy 257.942517 -334.425195) (xy 257.921586 -334.481678) (xy 257.894131 -334.535294) (xy 257.860537 -334.585293)
			(xy 257.841242 -334.608424) (xy 257.835769 -334.615224) (xy 257.829408 -334.631466) (xy 257.828796 -334.640174)
			(xy 257.828034 -334.669892) (xy 257.828133 -334.678651) (xy 257.833603 -334.69528) (xy 257.838702 -334.702404)
			(xy 257.858751 -334.729205) (xy 257.892387 -334.787072) (xy 257.918138 -334.848853) (xy 257.935556 -334.91348)
			(xy 257.944341 -334.979834) (xy 257.944874 -335.0133) (xy 257.944352 -335.046083) (xy 257.935921 -335.111104)
			(xy 257.919198 -335.174501) (xy 257.894462 -335.235222) (xy 257.862123 -335.292257) (xy 257.822718 -335.344661)
			(xy 257.776901 -335.391562) (xy 257.725434 -335.432182) (xy 257.669171 -335.465846) (xy 257.639312 -335.47939)
			(xy 257.628898 -335.483962) (xy 257.614166 -335.50098) (xy 257.585972 -335.598008) (xy 257.589528 -335.620106)
			(xy 257.595878 -335.629758) (xy 257.612514 -335.655082) (xy 257.64034 -335.708908) (xy 257.66156 -335.765663)
			(xy 257.675872 -335.824541) (xy 257.683074 -335.884704) (xy 257.683508 -335.915) (xy 257.683077 -335.945791)
			(xy 257.675632 -336.00692) (xy 257.660851 -336.066701) (xy 257.63895 -336.124256) (xy 257.610251 -336.178741)
			(xy 257.593084 -336.204306) (xy 257.586988 -336.213196) (xy 257.582924 -336.23377) (xy 257.603244 -336.326988)
			(xy 257.615436 -336.344006) (xy 257.62458 -336.34934) (xy 257.648487 -336.364218) (xy 257.692048 -336.399896)
			(xy 257.729896 -336.441586) (xy 257.761209 -336.488383) (xy 257.785309 -336.539272) (xy 257.801672 -336.59315)
			(xy 257.809943 -336.648846) (xy 257.809943 -336.705154) (xy 257.801672 -336.76085) (xy 257.785309 -336.814728)
			(xy 257.761209 -336.865617) (xy 257.729896 -336.912414) (xy 257.692048 -336.954104) (xy 257.648487 -336.989782)
			(xy 257.62458 -337.00466) (xy 257.615436 -337.009994) (xy 257.603244 -337.027012) (xy 257.582924 -337.12023)
			(xy 257.586988 -337.140804) (xy 257.593084 -337.149694) (xy 257.61025 -337.175257) (xy 257.638915 -337.229755)
			(xy 257.660798 -337.287312) (xy 257.675579 -337.347089) (xy 257.683042 -337.408212) (xy 257.683508 -337.439)
			(xy 257.683006 -337.471848) (xy 257.674552 -337.536997) (xy 257.657772 -337.600514) (xy 257.632945 -337.661338)
			(xy 257.600486 -337.718454) (xy 257.560936 -337.770911) (xy 257.514955 -337.817834) (xy 257.489452 -337.838542)
			(xy 257.477768 -337.847686) (xy 257.468116 -337.875626) (xy 257.496056 -337.994244) (xy 257.517138 -338.014818)
			(xy 257.53187 -338.017866) (xy 257.562735 -338.024719) (xy 257.622584 -338.045103) (xy 257.679446 -338.072748)
			(xy 257.732444 -338.107226) (xy 257.78076 -338.148006) (xy 257.823651 -338.194459) (xy 257.860454 -338.245869)
			(xy 257.890603 -338.301444) (xy 257.913632 -338.360327) (xy 257.929186 -338.421609) (xy 257.937026 -338.484347)
			(xy 257.937508 -338.51596) (xy 257.937025 -338.546691) (xy 257.929621 -338.607706) (xy 257.914916 -338.667384)
			(xy 257.893124 -338.724853) (xy 257.864564 -338.779277) (xy 257.829652 -338.829862) (xy 257.788897 -338.875869)
			(xy 257.742893 -338.916627) (xy 257.692311 -338.951544) (xy 257.63789 -338.980108) (xy 257.580422 -339.001904)
			(xy 257.520746 -339.016614) (xy 257.459731 -339.024022) (xy 257.429 -339.024468) (xy 257.41717 -339.02438)
			(xy 257.393539 -339.023238) (xy 257.381756 -339.022182) (xy 257.371085 -339.021765) (xy 257.350875 -339.028591)
			(xy 257.34264 -339.03539) (xy 257.302 -339.072474) (xy 257.302508 -339.085174) (xy 257.343402 -339.120226)
			(xy 257.351465 -339.126583) (xy 257.370991 -339.132873) (xy 257.381248 -339.132418) (xy 257.393158 -339.131358)
			(xy 257.417044 -339.130215) (xy 257.429 -339.130132) (xy 257.460541 -339.130568) (xy 257.523137 -339.13837)
			(xy 257.584288 -339.153855) (xy 257.643054 -339.176785) (xy 257.698532 -339.206808) (xy 257.749871 -339.243463)
			(xy 257.796282 -339.286186) (xy 257.837052 -339.334321) (xy 257.871555 -339.38713) (xy 257.899261 -339.443801)
			(xy 257.919744 -339.503464) (xy 257.932691 -339.565202) (xy 257.937902 -339.628067) (xy 257.935296 -339.691094)
			(xy 257.924915 -339.753315) (xy 257.906918 -339.813774) (xy 257.881581 -339.871543) (xy 257.849292 -339.925734)
			(xy 257.810549 -339.975516) (xy 257.765946 -340.020122) (xy 257.716167 -340.05887) (xy 257.661979 -340.091162)
			(xy 257.604212 -340.116504) (xy 257.543754 -340.134506) (xy 257.481534 -340.144892) (xy 257.418507 -340.147502)
			(xy 257.355641 -340.142297) (xy 257.293902 -340.129355) (xy 257.234238 -340.108876) (xy 257.177565 -340.081174)
			(xy 257.124753 -340.046676) (xy 257.076615 -340.005909) (xy 257.033888 -339.959502) (xy 256.997229 -339.908166)
			(xy 256.967202 -339.85269) (xy 256.944268 -339.793926) (xy 256.928778 -339.732776) (xy 256.92097 -339.67018)
			(xy 256.920492 -339.63864) (xy 256.920582 -339.622851) (xy 256.922488 -339.591332) (xy 256.924302 -339.575648)
			(xy 256.925572 -339.565996) (xy 256.921 -339.547708) (xy 256.869438 -339.475826) (xy 256.85369 -339.465666)
			(xy 256.844038 -339.463634) (xy 256.815752 -339.457211) (xy 256.761366 -339.437058) (xy 256.710659 -339.408903)
			(xy 256.664799 -339.373395) (xy 256.624844 -339.331353) (xy 256.591715 -339.283746) (xy 256.566175 -339.231671)
			(xy 256.548815 -339.176331) (xy 256.540033 -339.119) (xy 256.539492 -339.09) (xy 240.719156 -339.09)
			(xy 240.766896 -339.093003) (xy 240.829686 -339.104981) (xy 240.890479 -339.124734) (xy 240.948318 -339.151951)
			(xy 241.002289 -339.186202) (xy 241.051542 -339.226947) (xy 241.095299 -339.273544) (xy 241.132872 -339.325259)
			(xy 241.163666 -339.381274) (xy 241.187198 -339.440707) (xy 241.203095 -339.502621) (xy 241.211106 -339.566039)
			(xy 241.211608 -339.598) (xy 241.211106 -339.629961) (xy 241.203095 -339.693379) (xy 241.187198 -339.755293)
			(xy 241.163666 -339.814726) (xy 241.132872 -339.870741) (xy 241.095299 -339.922456) (xy 241.051542 -339.969053)
			(xy 241.002289 -340.009798) (xy 240.948318 -340.044049) (xy 240.890479 -340.071266) (xy 240.829686 -340.091019)
			(xy 240.766896 -340.102997) (xy 240.7031 -340.107011) (xy 240.639304 -340.102997) (xy 240.576514 -340.091019)
			(xy 240.515721 -340.071266) (xy 240.457882 -340.044049) (xy 240.403911 -340.009798) (xy 240.354658 -339.969053)
			(xy 240.310901 -339.922456) (xy 240.273328 -339.870741) (xy 240.242534 -339.814726) (xy 240.219002 -339.755293)
			(xy 240.203105 -339.693379) (xy 240.195094 -339.629961) (xy 237.385352 -339.629961) (xy 237.385352 -340.772961)
			(xy 240.195094 -340.772961) (xy 240.195094 -340.709039) (xy 240.203105 -340.645621) (xy 240.219002 -340.583707)
			(xy 240.242534 -340.524274) (xy 240.273328 -340.468259) (xy 240.310901 -340.416544) (xy 240.354658 -340.369947)
			(xy 240.403911 -340.329202) (xy 240.457882 -340.294951) (xy 240.515721 -340.267734) (xy 240.576514 -340.247981)
			(xy 240.639304 -340.236003) (xy 240.7031 -340.23199) (xy 240.766896 -340.236003) (xy 240.829686 -340.247981)
			(xy 240.890479 -340.267734) (xy 240.948318 -340.294951) (xy 241.002289 -340.329202) (xy 241.051542 -340.369947)
			(xy 241.095299 -340.416544) (xy 241.098692 -340.421214) (xy 245.362982 -340.421214) (xy 245.367053 -340.365592)
			(xy 245.379179 -340.311155) (xy 245.399102 -340.259064) (xy 245.426398 -340.210429) (xy 245.460484 -340.166286)
			(xy 245.500633 -340.127577) (xy 245.545991 -340.095126) (xy 245.595591 -340.069625) (xy 245.648375 -340.051618)
			(xy 245.703218 -340.041488) (xy 245.758952 -340.039451) (xy 245.814389 -340.045551) (xy 245.868346 -340.059657)
			(xy 245.919675 -340.081469) (xy 245.967281 -340.110523) (xy 246.010149 -340.146198) (xy 246.047366 -340.187735)
			(xy 246.078139 -340.234248) (xy 246.101811 -340.284745) (xy 246.117879 -340.338152) (xy 246.125999 -340.393328)
			(xy 246.126508 -340.421214) (xy 246.125999 -340.4491) (xy 246.117879 -340.504276) (xy 246.101811 -340.557683)
			(xy 246.078139 -340.60818) (xy 246.047366 -340.654693) (xy 246.010149 -340.69623) (xy 245.967281 -340.731905)
			(xy 245.919675 -340.760959) (xy 245.868346 -340.782771) (xy 245.814389 -340.796877) (xy 245.758952 -340.802977)
			(xy 245.703218 -340.80094) (xy 245.648375 -340.79081) (xy 245.595591 -340.772803) (xy 245.545991 -340.747302)
			(xy 245.500633 -340.714851) (xy 245.460484 -340.676142) (xy 245.426398 -340.631999) (xy 245.399102 -340.583364)
			(xy 245.379179 -340.531273) (xy 245.367053 -340.476836) (xy 245.362982 -340.421214) (xy 241.098692 -340.421214)
			(xy 241.132872 -340.468259) (xy 241.163666 -340.524274) (xy 241.187198 -340.583707) (xy 241.203095 -340.645621)
			(xy 241.211106 -340.709039) (xy 241.211608 -340.741) (xy 241.211106 -340.772961) (xy 241.203095 -340.836379)
			(xy 241.187198 -340.898293) (xy 241.163666 -340.957726) (xy 241.132872 -341.013741) (xy 241.095299 -341.065456)
			(xy 241.051542 -341.112053) (xy 241.002289 -341.152798) (xy 240.948318 -341.187049) (xy 240.890479 -341.214266)
			(xy 240.829686 -341.234019) (xy 240.766896 -341.245997) (xy 240.7031 -341.250011) (xy 240.639304 -341.245997)
			(xy 240.576514 -341.234019) (xy 240.515721 -341.214266) (xy 240.457882 -341.187049) (xy 240.403911 -341.152798)
			(xy 240.354658 -341.112053) (xy 240.310901 -341.065456) (xy 240.273328 -341.013741) (xy 240.242534 -340.957726)
			(xy 240.219002 -340.898293) (xy 240.203105 -340.836379) (xy 240.195094 -340.772961) (xy 237.385352 -340.772961)
			(xy 237.385352 -341.915961) (xy 240.195094 -341.915961) (xy 240.195094 -341.852039) (xy 240.203105 -341.788621)
			(xy 240.219002 -341.726707) (xy 240.242534 -341.667274) (xy 240.273328 -341.611259) (xy 240.310901 -341.559544)
			(xy 240.354658 -341.512947) (xy 240.403911 -341.472202) (xy 240.457882 -341.437951) (xy 240.515721 -341.410734)
			(xy 240.576514 -341.390981) (xy 240.639304 -341.379003) (xy 240.7031 -341.37499) (xy 240.766896 -341.379003)
			(xy 240.829686 -341.390981) (xy 240.890479 -341.410734) (xy 240.948318 -341.437951) (xy 241.002289 -341.472202)
			(xy 241.051542 -341.512947) (xy 241.095299 -341.559544) (xy 241.132872 -341.611259) (xy 241.163666 -341.667274)
			(xy 241.187198 -341.726707) (xy 241.203095 -341.788621) (xy 241.211106 -341.852039) (xy 241.211608 -341.884)
			(xy 241.211106 -341.915961) (xy 241.203095 -341.979379) (xy 241.187198 -342.041293) (xy 241.163666 -342.100726)
			(xy 241.132872 -342.156741) (xy 241.095299 -342.208456) (xy 241.051542 -342.255053) (xy 241.039518 -342.265)
			(xy 256.666492 -342.265) (xy 256.666943 -342.233234) (xy 256.674879 -342.1702) (xy 256.690604 -342.108644)
			(xy 256.713873 -342.049526) (xy 256.744322 -341.993767) (xy 256.781479 -341.942233) (xy 256.824764 -341.895727)
			(xy 256.873503 -341.854975) (xy 256.926938 -341.820609) (xy 256.984237 -341.793165) (xy 257.014218 -341.782654)
			(xy 257.024124 -341.779352) (xy 257.039872 -341.765128) (xy 257.079496 -341.678514) (xy 257.080004 -341.657432)
			(xy 257.07594 -341.64778) (xy 257.066915 -341.624723) (xy 257.05424 -341.576859) (xy 257.047867 -341.527757)
			(xy 257.047492 -341.503) (xy 257.04818 -341.469659) (xy 257.059814 -341.403998) (xy 257.070606 -341.372444)
			(xy 257.074162 -341.362792) (xy 257.073146 -341.342726) (xy 257.033014 -341.258652) (xy 257.018028 -341.24519)
			(xy 257.008376 -341.241634) (xy 256.9788 -341.230911) (xy 256.922353 -341.203126) (xy 256.869767 -341.168588)
			(xy 256.821844 -341.127826) (xy 256.779317 -341.081462) (xy 256.742835 -341.030205) (xy 256.712957 -340.974838)
			(xy 256.690139 -340.916208) (xy 256.674729 -340.85521) (xy 256.666964 -340.792777) (xy 256.666492 -340.76132)
			(xy 256.666994 -340.729359) (xy 256.675005 -340.665941) (xy 256.690902 -340.604027) (xy 256.714434 -340.544594)
			(xy 256.745228 -340.488579) (xy 256.782801 -340.436864) (xy 256.826558 -340.390267) (xy 256.875811 -340.349522)
			(xy 256.929782 -340.315271) (xy 256.987621 -340.288054) (xy 257.048414 -340.268301) (xy 257.111204 -340.256323)
			(xy 257.175 -340.25231) (xy 257.238796 -340.256323) (xy 257.301586 -340.268301) (xy 257.362379 -340.288054)
			(xy 257.420218 -340.315271) (xy 257.474189 -340.349522) (xy 257.523442 -340.390267) (xy 257.567199 -340.436864)
			(xy 257.604772 -340.488579) (xy 257.635566 -340.544594) (xy 257.659098 -340.604027) (xy 257.674995 -340.665941)
			(xy 257.683006 -340.729359) (xy 257.683508 -340.76132) (xy 257.683078 -340.790665) (xy 257.676329 -340.848967)
			(xy 257.662911 -340.906103) (xy 257.643003 -340.961314) (xy 257.616869 -341.013865) (xy 257.601212 -341.038688)
			(xy 257.595624 -341.047324) (xy 257.591814 -341.067136) (xy 257.61188 -341.158068) (xy 257.623564 -341.174578)
			(xy 257.6322 -341.180166) (xy 257.655205 -341.195255) (xy 257.697085 -341.230929) (xy 257.733404 -341.272251)
			(xy 257.763407 -341.318363) (xy 257.786472 -341.368308) (xy 257.80212 -341.42105) (xy 257.810026 -341.475493)
			(xy 257.810508 -341.503) (xy 257.809974 -341.531154) (xy 257.80169 -341.58685) (xy 257.785319 -341.640726)
			(xy 257.761213 -341.691613) (xy 257.729896 -341.73841) (xy 257.692047 -341.7801) (xy 257.648486 -341.81578)
			(xy 257.62458 -341.83066) (xy 257.615436 -341.835994) (xy 257.603244 -341.853012) (xy 257.582924 -341.94623)
			(xy 257.586988 -341.966804) (xy 257.593084 -341.975694) (xy 257.61025 -342.001257) (xy 257.638915 -342.055755)
			(xy 257.660798 -342.113312) (xy 257.675579 -342.173089) (xy 257.683042 -342.234212) (xy 257.683508 -342.265)
			(xy 257.683006 -342.296961) (xy 257.674995 -342.360379) (xy 257.659098 -342.422293) (xy 257.635566 -342.481726)
			(xy 257.604772 -342.537741) (xy 257.567199 -342.589456) (xy 257.523442 -342.636053) (xy 257.474189 -342.676798)
			(xy 257.420218 -342.711049) (xy 257.362379 -342.738266) (xy 257.301586 -342.758019) (xy 257.238796 -342.769997)
			(xy 257.175 -342.774011) (xy 257.111204 -342.769997) (xy 257.048414 -342.758019) (xy 256.987621 -342.738266)
			(xy 256.929782 -342.711049) (xy 256.875811 -342.676798) (xy 256.826558 -342.636053) (xy 256.782801 -342.589456)
			(xy 256.745228 -342.537741) (xy 256.714434 -342.481726) (xy 256.690902 -342.422293) (xy 256.675005 -342.360379)
			(xy 256.666994 -342.296961) (xy 256.666492 -342.265) (xy 241.039518 -342.265) (xy 241.002289 -342.295798)
			(xy 240.948318 -342.330049) (xy 240.890479 -342.357266) (xy 240.829686 -342.377019) (xy 240.766896 -342.388997)
			(xy 240.7031 -342.393011) (xy 240.639304 -342.388997) (xy 240.576514 -342.377019) (xy 240.515721 -342.357266)
			(xy 240.457882 -342.330049) (xy 240.403911 -342.295798) (xy 240.354658 -342.255053) (xy 240.310901 -342.208456)
			(xy 240.273328 -342.156741) (xy 240.242534 -342.100726) (xy 240.219002 -342.041293) (xy 240.203105 -341.979379)
			(xy 240.195094 -341.915961) (xy 237.385352 -341.915961) (xy 237.385352 -346.146077) (xy 243.411496 -346.146077)
			(xy 243.411496 -346.082155) (xy 243.419507 -346.018737) (xy 243.435404 -345.956823) (xy 243.458936 -345.89739)
			(xy 243.48973 -345.841375) (xy 243.527303 -345.78966) (xy 243.57106 -345.743063) (xy 243.620313 -345.702318)
			(xy 243.674284 -345.668067) (xy 243.732123 -345.64085) (xy 243.792916 -345.621097) (xy 243.855706 -345.609119)
			(xy 243.919502 -345.605106) (xy 243.983298 -345.609119) (xy 244.046088 -345.621097) (xy 244.106881 -345.64085)
			(xy 244.16472 -345.668067) (xy 244.218691 -345.702318) (xy 244.267944 -345.743063) (xy 244.311701 -345.78966)
			(xy 244.349274 -345.841375) (xy 244.380068 -345.89739) (xy 244.4036 -345.956823) (xy 244.409541 -345.979961)
			(xy 252.221994 -345.979961) (xy 252.221994 -345.916039) (xy 252.230005 -345.852621) (xy 252.245902 -345.790707)
			(xy 252.269434 -345.731274) (xy 252.300228 -345.675259) (xy 252.337801 -345.623544) (xy 252.381558 -345.576947)
			(xy 252.430811 -345.536202) (xy 252.484782 -345.501951) (xy 252.542621 -345.474734) (xy 252.603414 -345.454981)
			(xy 252.666204 -345.443003) (xy 252.73 -345.43899) (xy 252.793796 -345.443003) (xy 252.856586 -345.454981)
			(xy 252.917379 -345.474734) (xy 252.975218 -345.501951) (xy 253.029189 -345.536202) (xy 253.078442 -345.576947)
			(xy 253.122199 -345.623544) (xy 253.159772 -345.675259) (xy 253.187645 -345.725961) (xy 257.555994 -345.725961)
			(xy 257.555994 -345.662039) (xy 257.564005 -345.598621) (xy 257.579902 -345.536707) (xy 257.603434 -345.477274)
			(xy 257.634228 -345.421259) (xy 257.671801 -345.369544) (xy 257.715558 -345.322947) (xy 257.764811 -345.282202)
			(xy 257.818782 -345.247951) (xy 257.876621 -345.220734) (xy 257.937414 -345.200981) (xy 258.000204 -345.189003)
			(xy 258.064 -345.18499) (xy 258.127796 -345.189003) (xy 258.190586 -345.200981) (xy 258.251379 -345.220734)
			(xy 258.309218 -345.247951) (xy 258.363189 -345.282202) (xy 258.412442 -345.322947) (xy 258.456199 -345.369544)
			(xy 258.493772 -345.421259) (xy 258.524566 -345.477274) (xy 258.548098 -345.536707) (xy 258.563995 -345.598621)
			(xy 258.572006 -345.662039) (xy 258.572508 -345.694) (xy 258.572006 -345.725961) (xy 258.563995 -345.789379)
			(xy 258.548098 -345.851293) (xy 258.524566 -345.910726) (xy 258.493772 -345.966741) (xy 258.456199 -346.018456)
			(xy 258.412442 -346.065053) (xy 258.363189 -346.105798) (xy 258.309218 -346.140049) (xy 258.251379 -346.167266)
			(xy 258.190586 -346.187019) (xy 258.127796 -346.198997) (xy 258.064 -346.203011) (xy 258.000204 -346.198997)
			(xy 257.937414 -346.187019) (xy 257.876621 -346.167266) (xy 257.818782 -346.140049) (xy 257.764811 -346.105798)
			(xy 257.715558 -346.065053) (xy 257.671801 -346.018456) (xy 257.634228 -345.966741) (xy 257.603434 -345.910726)
			(xy 257.579902 -345.851293) (xy 257.564005 -345.789379) (xy 257.555994 -345.725961) (xy 253.187645 -345.725961)
			(xy 253.190566 -345.731274) (xy 253.214098 -345.790707) (xy 253.229995 -345.852621) (xy 253.238006 -345.916039)
			(xy 253.238508 -345.948) (xy 253.238006 -345.979961) (xy 253.229995 -346.043379) (xy 253.214098 -346.105293)
			(xy 253.190566 -346.164726) (xy 253.159772 -346.220741) (xy 253.122199 -346.272456) (xy 253.078442 -346.319053)
			(xy 253.029189 -346.359798) (xy 252.975218 -346.394049) (xy 252.917379 -346.421266) (xy 252.856586 -346.441019)
			(xy 252.793796 -346.452997) (xy 252.73 -346.457011) (xy 252.666204 -346.452997) (xy 252.603414 -346.441019)
			(xy 252.542621 -346.421266) (xy 252.484782 -346.394049) (xy 252.430811 -346.359798) (xy 252.381558 -346.319053)
			(xy 252.337801 -346.272456) (xy 252.300228 -346.220741) (xy 252.269434 -346.164726) (xy 252.245902 -346.105293)
			(xy 252.230005 -346.043379) (xy 252.221994 -345.979961) (xy 244.409541 -345.979961) (xy 244.419497 -346.018737)
			(xy 244.427508 -346.082155) (xy 244.42801 -346.114116) (xy 244.427508 -346.146077) (xy 244.419497 -346.209495)
			(xy 244.4036 -346.271409) (xy 244.380068 -346.330842) (xy 244.349274 -346.386857) (xy 244.311701 -346.438572)
			(xy 244.267944 -346.485169) (xy 244.218691 -346.525914) (xy 244.16472 -346.560165) (xy 244.106881 -346.587382)
			(xy 244.046088 -346.607135) (xy 243.983298 -346.619113) (xy 243.919502 -346.623127) (xy 243.855706 -346.619113)
			(xy 243.792916 -346.607135) (xy 243.732123 -346.587382) (xy 243.674284 -346.560165) (xy 243.620313 -346.525914)
			(xy 243.57106 -346.485169) (xy 243.527303 -346.438572) (xy 243.48973 -346.386857) (xy 243.458936 -346.330842)
			(xy 243.435404 -346.271409) (xy 243.419507 -346.209495) (xy 243.411496 -346.146077) (xy 237.385352 -346.146077)
			(xy 237.385352 -347.236288) (xy 237.385729 -347.245336) (xy 237.392033 -347.262301) (xy 237.403826 -347.276029)
			(xy 237.419648 -347.284817) (xy 237.428532 -347.28658) (xy 237.530054 -347.302245) (xy 237.731909 -347.340483)
			(xy 237.93212 -347.386557) (xy 238.130385 -347.440397) (xy 238.197555 -347.46148) (xy 252.348098 -347.46148)
			(xy 252.353307 -347.398614) (xy 252.366253 -347.336874) (xy 252.386736 -347.27721) (xy 252.414441 -347.220538)
			(xy 252.448944 -347.167728) (xy 252.489714 -347.119591) (xy 252.536125 -347.076866) (xy 252.587464 -347.040211)
			(xy 252.642943 -347.010187) (xy 252.70171 -346.987256) (xy 252.762861 -346.97177) (xy 252.825459 -346.963968)
			(xy 252.857 -346.963492) (xy 252.878082 -346.964) (xy 252.889004 -346.964508) (xy 252.908562 -346.956888)
			(xy 252.976888 -346.888562) (xy 252.984508 -346.869004) (xy 252.984 -346.858082) (xy 252.983492 -346.837)
			(xy 252.983968 -346.805459) (xy 252.99177 -346.742861) (xy 253.007256 -346.68171) (xy 253.030187 -346.622943)
			(xy 253.060211 -346.567464) (xy 253.096866 -346.516125) (xy 253.139591 -346.469714) (xy 253.187728 -346.428944)
			(xy 253.240538 -346.394441) (xy 253.29721 -346.366736) (xy 253.356874 -346.346253) (xy 253.418614 -346.333307)
			(xy 253.48148 -346.328098) (xy 253.544509 -346.330705) (xy 253.60673 -346.341088) (xy 253.66719 -346.359088)
			(xy 253.724959 -346.384427) (xy 253.77915 -346.416718) (xy 253.82893 -346.455464) (xy 253.873536 -346.50007)
			(xy 253.912282 -346.54985) (xy 253.944573 -346.604041) (xy 253.969912 -346.66181) (xy 253.987912 -346.72227)
			(xy 253.998295 -346.784491) (xy 254.000902 -346.84752) (xy 253.995693 -346.910386) (xy 253.982747 -346.972126)
			(xy 253.962264 -347.03179) (xy 253.934559 -347.088462) (xy 253.900056 -347.141272) (xy 253.859286 -347.189409)
			(xy 253.812875 -347.232134) (xy 253.761536 -347.268789) (xy 253.706057 -347.298813) (xy 253.64729 -347.321744)
			(xy 253.586139 -347.33723) (xy 253.523541 -347.345032) (xy 253.492 -347.345508) (xy 253.470918 -347.345)
			(xy 253.459996 -347.344492) (xy 253.440438 -347.352112) (xy 253.372112 -347.420438) (xy 253.364492 -347.439996)
			(xy 253.365 -347.450918) (xy 253.365508 -347.472) (xy 253.365032 -347.503541) (xy 253.35723 -347.566139)
			(xy 253.341744 -347.62729) (xy 253.318813 -347.686057) (xy 253.288789 -347.741536) (xy 253.252134 -347.792875)
			(xy 253.209409 -347.839286) (xy 253.161272 -347.880056) (xy 253.108462 -347.914559) (xy 253.05179 -347.942264)
			(xy 252.992126 -347.962747) (xy 252.930386 -347.975693) (xy 252.86752 -347.980902) (xy 252.804491 -347.978295)
			(xy 252.74227 -347.967912) (xy 252.68181 -347.949912) (xy 252.624041 -347.924573) (xy 252.56985 -347.892282)
			(xy 252.52007 -347.853536) (xy 252.475464 -347.80893) (xy 252.436718 -347.75915) (xy 252.404427 -347.704959)
			(xy 252.379088 -347.64719) (xy 252.361088 -347.58673) (xy 252.350705 -347.524509) (xy 252.348098 -347.46148)
			(xy 238.197555 -347.46148) (xy 238.3264 -347.501921) (xy 238.51987 -347.571036) (xy 238.7105 -347.647638)
			(xy 238.898 -347.731608) (xy 239.082086 -347.822821) (xy 239.262479 -347.921138) (xy 239.438903 -348.026408)
			(xy 239.611092 -348.138473) (xy 239.778783 -348.257162) (xy 239.941722 -348.382295) (xy 240.099662 -348.513681)
			(xy 240.252363 -348.651122) (xy 240.399592 -348.794408) (xy 240.541127 -348.943323) (xy 240.676751 -349.097639)
			(xy 240.80626 -349.257122) (xy 240.929457 -349.42153) (xy 241.046153 -349.590614) (xy 241.156173 -349.764116)
			(xy 241.259349 -349.941774) (xy 241.355525 -350.123317) (xy 241.444553 -350.308469) (xy 241.5263 -350.49695)
			(xy 241.60064 -350.688472) (xy 241.667462 -350.882746) (xy 241.726663 -351.079476) (xy 241.778154 -351.278364)
			(xy 241.821856 -351.479106) (xy 241.857703 -351.681399) (xy 241.88564 -351.884935) (xy 241.905626 -352.089405)
			(xy 241.917629 -352.294499) (xy 241.921633 -352.499904) (xy 241.917629 -352.70531) (xy 241.905625 -352.910404)
			(xy 241.885639 -353.114874) (xy 241.857701 -353.31841) (xy 241.821854 -353.520703) (xy 241.778151 -353.721445)
			(xy 241.726661 -353.920332) (xy 241.667459 -354.117062) (xy 241.600637 -354.311336) (xy 241.526296 -354.502859)
			(xy 241.444549 -354.691339) (xy 241.355521 -354.876491) (xy 241.259345 -355.058034) (xy 241.156169 -355.235691)
			(xy 241.046149 -355.409193) (xy 240.929451 -355.578277) (xy 240.806255 -355.742685) (xy 240.676746 -355.902168)
			(xy 240.541121 -356.056484) (xy 240.399586 -356.205398) (xy 240.252356 -356.348684) (xy 240.099656 -356.486125)
			(xy 239.941715 -356.617511) (xy 239.778776 -356.742643) (xy 239.611084 -356.861332) (xy 239.438895 -356.973397)
			(xy 239.262471 -357.078667) (xy 239.082078 -357.176983) (xy 238.897992 -357.268195) (xy 238.710492 -357.352166)
			(xy 238.519862 -357.428767) (xy 238.326392 -357.497882) (xy 238.130376 -357.559406) (xy 237.932112 -357.613245)
			(xy 237.7319 -357.659319) (xy 237.530045 -357.697556) (xy 237.428532 -357.71328) (xy 237.419634 -357.714997)
			(xy 237.403793 -357.723773) (xy 237.392006 -357.737521) (xy 237.385751 -357.754516) (xy 237.385352 -357.763572)
			(xy 237.385352 -360.764074) (xy 253.856497 -360.764074) (xy 253.860504 -360.57917) (xy 253.872517 -360.394612)
			(xy 253.892513 -360.210748) (xy 253.920455 -360.027924) (xy 253.956291 -359.846481) (xy 253.999953 -359.66676)
			(xy 254.05136 -359.4891) (xy 254.110414 -359.313834) (xy 254.177005 -359.14129) (xy 254.251008 -358.971793)
			(xy 254.332284 -358.805661) (xy 254.42068 -358.643205) (xy 254.516031 -358.484731) (xy 254.618157 -358.330536)
			(xy 254.726866 -358.18091) (xy 254.841955 -358.036134) (xy 254.963208 -357.896479) (xy 255.090397 -357.762208)
			(xy 255.223282 -357.633572) (xy 255.361616 -357.510813) (xy 255.505137 -357.394163) (xy 255.653576 -357.283839)
			(xy 255.806656 -357.180048) (xy 255.964087 -357.082986) (xy 256.125576 -356.992836) (xy 256.290818 -356.909765)
			(xy 256.459504 -356.83393) (xy 256.631316 -356.765474) (xy 256.805932 -356.704524) (xy 256.983025 -356.651197)
			(xy 257.162262 -356.60559) (xy 257.343306 -356.567791) (xy 257.525817 -356.53787) (xy 257.709454 -356.515883)
			(xy 257.89387 -356.501871) (xy 258.07872 -356.495861) (xy 258.263657 -356.497865) (xy 258.448334 -356.507878)
			(xy 258.632404 -356.525881) (xy 258.81552 -356.551842) (xy 258.997341 -356.58571) (xy 259.177524 -356.627422)
			(xy 259.35573 -356.676901) (xy 259.531626 -356.734053) (xy 259.704881 -356.798771) (xy 259.87517 -356.870934)
			(xy 260.042173 -356.950405) (xy 260.205577 -357.037036) (xy 260.365074 -357.130665) (xy 260.520366 -357.231114)
			(xy 260.671161 -357.338197) (xy 260.817176 -357.451711) (xy 260.958136 -357.571443) (xy 261.093777 -357.69717)
			(xy 261.223845 -357.828654) (xy 261.348095 -357.96565) (xy 261.466293 -358.107899) (xy 261.578219 -358.255134)
			(xy 261.683662 -358.40708) (xy 261.782423 -358.563451) (xy 261.874318 -358.723954) (xy 261.959174 -358.888286)
			(xy 262.036832 -359.056141) (xy 262.107145 -359.227201) (xy 262.169982 -359.401147) (xy 262.225226 -359.577652)
			(xy 262.272771 -359.756384) (xy 262.312529 -359.937008) (xy 262.344426 -360.119185) (xy 262.368401 -360.302572)
			(xy 262.383008 -360.470704) (xy 271.47749 -360.470704) (xy 271.481519 -360.379698) (xy 271.493576 -360.289404)
			(xy 271.513566 -360.200529) (xy 271.541332 -360.113769) (xy 271.576658 -360.029802) (xy 271.619266 -359.949286)
			(xy 271.668824 -359.87285) (xy 271.724943 -359.801094) (xy 271.787184 -359.734578) (xy 271.855061 -359.673823)
			(xy 271.928041 -359.619305) (xy 272.005554 -359.571451) (xy 272.086993 -359.530634) (xy 272.171721 -359.497175)
			(xy 272.259075 -359.471334) (xy 272.34837 -359.453316) (xy 272.438908 -359.443259) (xy 272.529981 -359.441244)
			(xy 272.620876 -359.447286) (xy 272.710881 -359.461337) (xy 272.799292 -359.483288) (xy 272.885417 -359.512967)
			(xy 272.968582 -359.550141) (xy 273.048136 -359.59452) (xy 273.123456 -359.645757) (xy 273.193954 -359.70345)
			(xy 273.259076 -359.767147) (xy 273.318314 -359.836351) (xy 273.371204 -359.91052) (xy 273.417333 -359.989072)
			(xy 273.456338 -360.071395) (xy 273.487915 -360.156842) (xy 273.511816 -360.244746) (xy 273.527855 -360.334418)
			(xy 273.535906 -360.425156) (xy 273.53641 -360.470704) (xy 273.535906 -360.516252) (xy 273.527855 -360.60699)
			(xy 273.511816 -360.696662) (xy 273.487915 -360.784566) (xy 273.456338 -360.870013) (xy 273.417333 -360.952336)
			(xy 273.371204 -361.030888) (xy 273.318314 -361.105057) (xy 273.259076 -361.174261) (xy 273.193954 -361.237958)
			(xy 273.123456 -361.295651) (xy 273.048136 -361.346888) (xy 272.968582 -361.391267) (xy 272.885417 -361.428441)
			(xy 272.799292 -361.45812) (xy 272.710881 -361.480071) (xy 272.620876 -361.494122) (xy 272.529981 -361.500164)
			(xy 272.438908 -361.498149) (xy 272.34837 -361.488092) (xy 272.259075 -361.470074) (xy 272.171721 -361.444233)
			(xy 272.086993 -361.410774) (xy 272.005554 -361.369957) (xy 271.928041 -361.322103) (xy 271.855061 -361.267585)
			(xy 271.787184 -361.20683) (xy 271.724943 -361.140314) (xy 271.668824 -361.068558) (xy 271.619266 -360.992122)
			(xy 271.576658 -360.911606) (xy 271.541332 -360.827639) (xy 271.513566 -360.740879) (xy 271.493576 -360.652004)
			(xy 271.481519 -360.56171) (xy 271.47749 -360.470704) (xy 262.383008 -360.470704) (xy 262.384409 -360.486826)
			(xy 262.392421 -360.6716) (xy 262.392922 -360.764074) (xy 262.392421 -360.856548) (xy 262.384409 -361.041322)
			(xy 262.368401 -361.225576) (xy 262.344426 -361.408963) (xy 262.312529 -361.59114) (xy 262.272771 -361.771764)
			(xy 262.225226 -361.950496) (xy 262.169982 -362.127001) (xy 262.107145 -362.300947) (xy 262.036832 -362.472007)
			(xy 261.959174 -362.639862) (xy 261.874318 -362.804194) (xy 261.782423 -362.964697) (xy 261.753366 -363.010704)
			(xy 271.47749 -363.010704) (xy 271.481519 -362.919698) (xy 271.493576 -362.829404) (xy 271.513566 -362.740529)
			(xy 271.541332 -362.653769) (xy 271.576658 -362.569802) (xy 271.619266 -362.489286) (xy 271.668824 -362.41285)
			(xy 271.724943 -362.341094) (xy 271.787184 -362.274578) (xy 271.855061 -362.213823) (xy 271.928041 -362.159305)
			(xy 272.005554 -362.111451) (xy 272.086993 -362.070634) (xy 272.171721 -362.037175) (xy 272.259075 -362.011334)
			(xy 272.34837 -361.993316) (xy 272.438908 -361.983259) (xy 272.529981 -361.981244) (xy 272.620876 -361.987286)
			(xy 272.710881 -362.001337) (xy 272.799292 -362.023288) (xy 272.885417 -362.052967) (xy 272.968582 -362.090141)
			(xy 272.983195 -362.098293) (xy 274.067264 -362.098293) (xy 274.067264 -362.034371) (xy 274.075275 -361.970953)
			(xy 274.091172 -361.909039) (xy 274.114704 -361.849606) (xy 274.145498 -361.793591) (xy 274.183071 -361.741876)
			(xy 274.226828 -361.695279) (xy 274.276081 -361.654534) (xy 274.330052 -361.620283) (xy 274.387891 -361.593066)
			(xy 274.448684 -361.573313) (xy 274.511474 -361.561335) (xy 274.57527 -361.557322) (xy 274.639066 -361.561335)
			(xy 274.701856 -361.573313) (xy 274.762649 -361.593066) (xy 274.820488 -361.620283) (xy 274.874459 -361.654534)
			(xy 274.923712 -361.695279) (xy 274.967469 -361.741876) (xy 275.005042 -361.793591) (xy 275.035836 -361.849606)
			(xy 275.059368 -361.909039) (xy 275.075265 -361.970953) (xy 275.083276 -362.034371) (xy 275.083778 -362.066332)
			(xy 275.083276 -362.098293) (xy 275.075265 -362.161711) (xy 275.059368 -362.223625) (xy 275.035836 -362.283058)
			(xy 275.005042 -362.339073) (xy 274.967469 -362.390788) (xy 274.923712 -362.437385) (xy 274.874459 -362.47813)
			(xy 274.820488 -362.512381) (xy 274.762649 -362.539598) (xy 274.701856 -362.559351) (xy 274.639066 -362.571329)
			(xy 274.57527 -362.575343) (xy 274.511474 -362.571329) (xy 274.448684 -362.559351) (xy 274.387891 -362.539598)
			(xy 274.330052 -362.512381) (xy 274.276081 -362.47813) (xy 274.226828 -362.437385) (xy 274.183071 -362.390788)
			(xy 274.145498 -362.339073) (xy 274.114704 -362.283058) (xy 274.091172 -362.223625) (xy 274.075275 -362.161711)
			(xy 274.067264 -362.098293) (xy 272.983195 -362.098293) (xy 273.048136 -362.13452) (xy 273.123456 -362.185757)
			(xy 273.193954 -362.24345) (xy 273.259076 -362.307147) (xy 273.318314 -362.376351) (xy 273.371204 -362.45052)
			(xy 273.417333 -362.529072) (xy 273.456338 -362.611395) (xy 273.487915 -362.696842) (xy 273.511816 -362.784746)
			(xy 273.527855 -362.874418) (xy 273.535906 -362.965156) (xy 273.53641 -363.010704) (xy 273.535906 -363.056252)
			(xy 273.527855 -363.14699) (xy 273.511816 -363.236662) (xy 273.487915 -363.324566) (xy 273.456338 -363.410013)
			(xy 273.417333 -363.492336) (xy 273.371204 -363.570888) (xy 273.318314 -363.645057) (xy 273.259076 -363.714261)
			(xy 273.193954 -363.777958) (xy 273.123456 -363.835651) (xy 273.048136 -363.886888) (xy 272.968582 -363.931267)
			(xy 272.885417 -363.968441) (xy 272.799292 -363.99812) (xy 272.710881 -364.020071) (xy 272.620876 -364.034122)
			(xy 272.529981 -364.040164) (xy 272.438908 -364.038149) (xy 272.34837 -364.028092) (xy 272.259075 -364.010074)
			(xy 272.171721 -363.984233) (xy 272.086993 -363.950774) (xy 272.005554 -363.909957) (xy 271.928041 -363.862103)
			(xy 271.855061 -363.807585) (xy 271.787184 -363.74683) (xy 271.724943 -363.680314) (xy 271.668824 -363.608558)
			(xy 271.619266 -363.532122) (xy 271.576658 -363.451606) (xy 271.541332 -363.367639) (xy 271.513566 -363.280879)
			(xy 271.493576 -363.192004) (xy 271.481519 -363.10171) (xy 271.47749 -363.010704) (xy 261.753366 -363.010704)
			(xy 261.683662 -363.121068) (xy 261.578219 -363.273014) (xy 261.466293 -363.420249) (xy 261.348095 -363.562498)
			(xy 261.223845 -363.699494) (xy 261.093777 -363.830978) (xy 260.958136 -363.956705) (xy 260.817176 -364.076437)
			(xy 260.671161 -364.189951) (xy 260.629625 -364.219447) (xy 268.260316 -364.219447) (xy 268.260316 -364.155525)
			(xy 268.268327 -364.092107) (xy 268.284224 -364.030193) (xy 268.307756 -363.97076) (xy 268.33855 -363.914745)
			(xy 268.376123 -363.86303) (xy 268.41988 -363.816433) (xy 268.469133 -363.775688) (xy 268.523104 -363.741437)
			(xy 268.580943 -363.71422) (xy 268.641736 -363.694467) (xy 268.704526 -363.682489) (xy 268.768322 -363.678476)
			(xy 268.832118 -363.682489) (xy 268.894908 -363.694467) (xy 268.955701 -363.71422) (xy 269.01354 -363.741437)
			(xy 269.067511 -363.775688) (xy 269.116764 -363.816433) (xy 269.160521 -363.86303) (xy 269.198094 -363.914745)
			(xy 269.228888 -363.97076) (xy 269.25242 -364.030193) (xy 269.268317 -364.092107) (xy 269.276328 -364.155525)
			(xy 269.27683 -364.187486) (xy 269.276328 -364.219447) (xy 269.268317 -364.282865) (xy 269.25242 -364.344779)
			(xy 269.228888 -364.404212) (xy 269.198094 -364.460227) (xy 269.160521 -364.511942) (xy 269.116764 -364.558539)
			(xy 269.067511 -364.599284) (xy 269.01354 -364.633535) (xy 268.955701 -364.660752) (xy 268.894908 -364.680505)
			(xy 268.832118 -364.692483) (xy 268.768322 -364.696497) (xy 268.704526 -364.692483) (xy 268.641736 -364.680505)
			(xy 268.580943 -364.660752) (xy 268.523104 -364.633535) (xy 268.469133 -364.599284) (xy 268.41988 -364.558539)
			(xy 268.376123 -364.511942) (xy 268.33855 -364.460227) (xy 268.307756 -364.404212) (xy 268.284224 -364.344779)
			(xy 268.268327 -364.282865) (xy 268.260316 -364.219447) (xy 260.629625 -364.219447) (xy 260.520366 -364.297034)
			(xy 260.365074 -364.397483) (xy 260.205577 -364.491112) (xy 260.042173 -364.577743) (xy 259.87517 -364.657214)
			(xy 259.704881 -364.729377) (xy 259.531626 -364.794095) (xy 259.35573 -364.851247) (xy 259.177524 -364.900726)
			(xy 258.997341 -364.942438) (xy 258.81552 -364.976306) (xy 258.632404 -365.002267) (xy 258.448334 -365.02027)
			(xy 258.263657 -365.030283) (xy 258.07872 -365.032287) (xy 257.89387 -365.026277) (xy 257.709454 -365.012265)
			(xy 257.525817 -364.990278) (xy 257.343306 -364.960357) (xy 257.162262 -364.922558) (xy 256.983025 -364.876951)
			(xy 256.805932 -364.823624) (xy 256.631316 -364.762674) (xy 256.459504 -364.694218) (xy 256.290818 -364.618383)
			(xy 256.125576 -364.535312) (xy 255.964087 -364.445162) (xy 255.806656 -364.3481) (xy 255.653576 -364.244309)
			(xy 255.505137 -364.133985) (xy 255.361616 -364.017335) (xy 255.223282 -363.894576) (xy 255.090397 -363.76594)
			(xy 254.963208 -363.631669) (xy 254.841955 -363.492014) (xy 254.726866 -363.347238) (xy 254.618157 -363.197612)
			(xy 254.516031 -363.043417) (xy 254.42068 -362.884943) (xy 254.332284 -362.722487) (xy 254.251008 -362.556355)
			(xy 254.177005 -362.386858) (xy 254.110414 -362.214314) (xy 254.05136 -362.039048) (xy 253.999953 -361.861388)
			(xy 253.956291 -361.681667) (xy 253.920455 -361.500224) (xy 253.892513 -361.3174) (xy 253.872517 -361.133536)
			(xy 253.860504 -360.948978) (xy 253.856497 -360.764074) (xy 237.385352 -360.764074) (xy 237.385352 -363.613657)
			(xy 246.799094 -363.613657) (xy 246.799094 -363.549735) (xy 246.807105 -363.486317) (xy 246.823002 -363.424403)
			(xy 246.846534 -363.36497) (xy 246.877328 -363.308955) (xy 246.914901 -363.25724) (xy 246.958658 -363.210643)
			(xy 247.007911 -363.169898) (xy 247.061882 -363.135647) (xy 247.119721 -363.10843) (xy 247.180514 -363.088677)
			(xy 247.243304 -363.076699) (xy 247.3071 -363.072686) (xy 247.370896 -363.076699) (xy 247.433686 -363.088677)
			(xy 247.494479 -363.10843) (xy 247.552318 -363.135647) (xy 247.606289 -363.169898) (xy 247.655542 -363.210643)
			(xy 247.699299 -363.25724) (xy 247.736872 -363.308955) (xy 247.767666 -363.36497) (xy 247.791198 -363.424403)
			(xy 247.807095 -363.486317) (xy 247.815106 -363.549735) (xy 247.815608 -363.581696) (xy 247.815106 -363.613657)
			(xy 247.807095 -363.677075) (xy 247.791198 -363.738989) (xy 247.767666 -363.798422) (xy 247.736872 -363.854437)
			(xy 247.699299 -363.906152) (xy 247.655542 -363.952749) (xy 247.606289 -363.993494) (xy 247.552318 -364.027745)
			(xy 247.494479 -364.054962) (xy 247.433686 -364.074715) (xy 247.370896 -364.086693) (xy 247.3071 -364.090707)
			(xy 247.243304 -364.086693) (xy 247.180514 -364.074715) (xy 247.119721 -364.054962) (xy 247.061882 -364.027745)
			(xy 247.007911 -363.993494) (xy 246.958658 -363.952749) (xy 246.914901 -363.906152) (xy 246.877328 -363.854437)
			(xy 246.846534 -363.798422) (xy 246.823002 -363.738989) (xy 246.807105 -363.677075) (xy 246.799094 -363.613657)
			(xy 237.385352 -363.613657) (xy 237.385352 -367.063231) (xy 271.555712 -367.063231) (xy 271.555712 -366.999309)
			(xy 271.563723 -366.935891) (xy 271.57962 -366.873977) (xy 271.603152 -366.814544) (xy 271.633946 -366.758529)
			(xy 271.671519 -366.706814) (xy 271.715276 -366.660217) (xy 271.764529 -366.619472) (xy 271.8185 -366.585221)
			(xy 271.876339 -366.558004) (xy 271.937132 -366.538251) (xy 271.999922 -366.526273) (xy 272.063718 -366.52226)
			(xy 272.127514 -366.526273) (xy 272.190304 -366.538251) (xy 272.251097 -366.558004) (xy 272.308936 -366.585221)
			(xy 272.362907 -366.619472) (xy 272.41216 -366.660217) (xy 272.455917 -366.706814) (xy 272.49349 -366.758529)
			(xy 272.524284 -366.814544) (xy 272.547816 -366.873977) (xy 272.563713 -366.935891) (xy 272.571724 -366.999309)
			(xy 272.572226 -367.03127) (xy 272.571724 -367.063231) (xy 272.563713 -367.126649) (xy 272.547816 -367.188563)
			(xy 272.524284 -367.247996) (xy 272.49349 -367.304011) (xy 272.455917 -367.355726) (xy 272.41216 -367.402323)
			(xy 272.362907 -367.443068) (xy 272.308936 -367.477319) (xy 272.251097 -367.504536) (xy 272.190304 -367.524289)
			(xy 272.127514 -367.536267) (xy 272.063718 -367.540281) (xy 271.999922 -367.536267) (xy 271.937132 -367.524289)
			(xy 271.876339 -367.504536) (xy 271.8185 -367.477319) (xy 271.764529 -367.443068) (xy 271.715276 -367.402323)
			(xy 271.671519 -367.355726) (xy 271.633946 -367.304011) (xy 271.603152 -367.247996) (xy 271.57962 -367.188563)
			(xy 271.563723 -367.126649) (xy 271.555712 -367.063231) (xy 237.385352 -367.063231) (xy 237.385352 -367.879587)
			(xy 238.016028 -367.879587) (xy 238.016028 -367.815665) (xy 238.024039 -367.752247) (xy 238.039936 -367.690333)
			(xy 238.063468 -367.6309) (xy 238.094262 -367.574885) (xy 238.131835 -367.52317) (xy 238.175592 -367.476573)
			(xy 238.224845 -367.435828) (xy 238.278816 -367.401577) (xy 238.336655 -367.37436) (xy 238.397448 -367.354607)
			(xy 238.460238 -367.342629) (xy 238.524034 -367.338616) (xy 238.58783 -367.342629) (xy 238.65062 -367.354607)
			(xy 238.711413 -367.37436) (xy 238.769252 -367.401577) (xy 238.823223 -367.435828) (xy 238.872476 -367.476573)
			(xy 238.916233 -367.52317) (xy 238.953806 -367.574885) (xy 238.9846 -367.6309) (xy 239.008132 -367.690333)
			(xy 239.024029 -367.752247) (xy 239.03204 -367.815665) (xy 239.032542 -367.847626) (xy 239.03204 -367.879587)
			(xy 239.028896 -367.904479) (xy 239.294664 -367.904479) (xy 239.294664 -367.840557) (xy 239.302675 -367.777139)
			(xy 239.318572 -367.715225) (xy 239.342104 -367.655792) (xy 239.372898 -367.599777) (xy 239.410471 -367.548062)
			(xy 239.454228 -367.501465) (xy 239.503481 -367.46072) (xy 239.557452 -367.426469) (xy 239.615291 -367.399252)
			(xy 239.676084 -367.379499) (xy 239.738874 -367.367521) (xy 239.80267 -367.363508) (xy 239.866466 -367.367521)
			(xy 239.929256 -367.379499) (xy 239.990049 -367.399252) (xy 240.047888 -367.426469) (xy 240.101859 -367.46072)
			(xy 240.151112 -367.501465) (xy 240.194869 -367.548062) (xy 240.232442 -367.599777) (xy 240.263236 -367.655792)
			(xy 240.286768 -367.715225) (xy 240.302665 -367.777139) (xy 240.310676 -367.840557) (xy 240.311178 -367.872518)
			(xy 240.310676 -367.904479) (xy 240.310034 -367.909559) (xy 240.592858 -367.909559) (xy 240.592858 -367.845637)
			(xy 240.600869 -367.782219) (xy 240.616766 -367.720305) (xy 240.640298 -367.660872) (xy 240.671092 -367.604857)
			(xy 240.708665 -367.553142) (xy 240.752422 -367.506545) (xy 240.801675 -367.4658) (xy 240.855646 -367.431549)
			(xy 240.913485 -367.404332) (xy 240.974278 -367.384579) (xy 241.037068 -367.372601) (xy 241.100864 -367.368588)
			(xy 241.16466 -367.372601) (xy 241.22745 -367.384579) (xy 241.288243 -367.404332) (xy 241.346082 -367.431549)
			(xy 241.400053 -367.4658) (xy 241.449306 -367.506545) (xy 241.493063 -367.553142) (xy 241.530636 -367.604857)
			(xy 241.56143 -367.660872) (xy 241.584962 -367.720305) (xy 241.600859 -367.782219) (xy 241.60887 -367.845637)
			(xy 241.609253 -367.87) (xy 241.944346 -367.87) (xy 241.948361 -367.806198) (xy 241.96034 -367.743401)
			(xy 241.980095 -367.682602) (xy 242.007315 -367.624758) (xy 242.04157 -367.570781) (xy 242.082321 -367.521524)
			(xy 242.128923 -367.477763) (xy 242.180643 -367.440187) (xy 242.236665 -367.40939) (xy 242.296104 -367.385858)
			(xy 242.358025 -367.369961) (xy 242.42145 -367.36195) (xy 242.453414 -367.36147) (xy 242.483827 -367.361886)
			(xy 242.54422 -367.36914) (xy 242.603316 -367.383544) (xy 242.660274 -367.404891) (xy 242.71428 -367.432878)
			(xy 242.764564 -367.467104) (xy 242.810407 -367.507082) (xy 242.831112 -367.529364) (xy 242.838732 -367.538)
			(xy 242.860322 -367.54689) (xy 242.963446 -367.540032) (xy 242.983766 -367.528348) (xy 242.99037 -367.518696)
			(xy 243.008192 -367.493534) (xy 243.04894 -367.447258) (xy 243.094987 -367.40625) (xy 243.145657 -367.371115)
			(xy 243.200205 -367.342367) (xy 243.257831 -367.320429) (xy 243.317687 -367.305623) (xy 243.378894 -367.298167)
			(xy 243.409724 -367.297716) (xy 243.44012 -367.298167) (xy 243.500477 -367.305421) (xy 243.559538 -367.319823)
			(xy 243.61646 -367.341167) (xy 243.67043 -367.369148) (xy 243.720676 -367.403366) (xy 243.766482 -367.443334)
			(xy 243.787168 -367.46561) (xy 243.793772 -367.472722) (xy 243.81079 -367.481358) (xy 243.899182 -367.488978)
			(xy 243.91747 -367.483644) (xy 243.92509 -367.477548) (xy 243.951986 -367.457257) (xy 244.010132 -367.423222)
			(xy 244.072263 -367.397163) (xy 244.137291 -367.379536) (xy 244.204077 -367.370648) (xy 244.237764 -367.370106)
			(xy 244.269039 -367.370578) (xy 244.331121 -367.378211) (xy 244.391797 -367.393403) (xy 244.450151 -367.415924)
			(xy 244.505301 -367.445434) (xy 244.531134 -367.46307) (xy 244.538529 -367.467919) (xy 244.555573 -367.472598)
			(xy 244.564408 -367.472214) (xy 244.59438 -367.469928) (xy 244.603224 -367.468816) (xy 244.61936 -367.461277)
			(xy 244.625876 -367.455196) (xy 244.649781 -367.43231) (xy 244.702454 -367.392246) (xy 244.759881 -367.359357)
			(xy 244.821092 -367.3342) (xy 244.885049 -367.3172) (xy 244.950673 -367.308645) (xy 244.983762 -367.30813)
			(xy 245.012775 -367.308551) (xy 245.070423 -367.315162) (xy 245.126944 -367.328289) (xy 245.181604 -367.347763)
			(xy 245.233693 -367.37333) (xy 245.258336 -367.388648) (xy 245.267259 -367.393737) (xy 245.287502 -367.39711)
			(xy 245.307461 -367.392333) (xy 245.315994 -367.386616) (xy 245.342342 -367.367731) (xy 245.398921 -367.336088)
			(xy 245.459064 -367.311895) (xy 245.521794 -367.295545) (xy 245.586095 -367.287303) (xy 245.618508 -367.286794)
			(xy 245.652845 -367.287357) (xy 245.720894 -367.2966) (xy 245.78708 -367.314918) (xy 245.850199 -367.341977)
			(xy 245.909101 -367.377284) (xy 245.936262 -367.3983) (xy 245.945719 -367.405067) (xy 245.968411 -367.410033)
			(xy 245.990979 -367.40453) (xy 246.00027 -367.397538) (xy 246.023155 -367.379078) (xy 246.072409 -367.346968)
			(xy 246.12504 -367.320756) (xy 246.180344 -367.300793) (xy 246.237583 -367.287345) (xy 246.295991 -367.280593)
			(xy 246.32539 -367.28019) (xy 246.357353 -367.280674) (xy 246.420774 -367.288685) (xy 246.482691 -367.304582)
			(xy 246.542128 -367.328113) (xy 246.598146 -367.358909) (xy 246.649863 -367.396482) (xy 246.696463 -367.440242)
			(xy 246.737211 -367.489497) (xy 246.771464 -367.54347) (xy 246.798683 -367.601312) (xy 246.818437 -367.662108)
			(xy 246.830416 -367.724901) (xy 246.83443 -367.7887) (xy 246.830416 -367.852499) (xy 246.818437 -367.915292)
			(xy 246.798683 -367.976088) (xy 246.771464 -368.03393) (xy 246.737211 -368.087903) (xy 246.696463 -368.137158)
			(xy 246.649863 -368.180918) (xy 246.598146 -368.218491) (xy 246.542128 -368.249287) (xy 246.482691 -368.272818)
			(xy 246.420774 -368.288715) (xy 246.357353 -368.296726) (xy 246.32539 -368.297206) (xy 246.291053 -368.296645)
			(xy 246.223004 -368.287401) (xy 246.156818 -368.269083) (xy 246.093699 -368.242023) (xy 246.034797 -368.206716)
			(xy 246.007636 -368.1857) (xy 245.99818 -368.178932) (xy 245.975488 -368.173966) (xy 245.952919 -368.179469)
			(xy 245.943628 -368.186462) (xy 245.920744 -368.204923) (xy 245.87149 -368.237033) (xy 245.818858 -368.263245)
			(xy 245.763554 -368.283208) (xy 245.706315 -368.296655) (xy 245.647907 -368.303407) (xy 245.618508 -368.30381)
			(xy 245.589495 -368.303397) (xy 245.531847 -368.296784) (xy 245.475326 -368.283654) (xy 245.420666 -368.264179)
			(xy 245.368577 -368.23861) (xy 245.343934 -368.223292) (xy 245.335021 -368.218184) (xy 245.314772 -368.214824)
			(xy 245.294811 -368.219607) (xy 245.286276 -368.225324) (xy 245.25991 -368.244183) (xy 245.203336 -368.27583)
			(xy 245.143198 -368.300027) (xy 245.080471 -368.316383) (xy 245.016174 -368.324632) (xy 244.983762 -368.325146)
			(xy 244.952487 -368.32467) (xy 244.890405 -368.317039) (xy 244.829729 -368.301849) (xy 244.771374 -368.279328)
			(xy 244.716224 -368.249818) (xy 244.690392 -368.232182) (xy 244.682987 -368.227349) (xy 244.665951 -368.222659)
			(xy 244.657118 -368.223038) (xy 244.627146 -368.225324) (xy 244.618293 -368.226389) (xy 244.602159 -368.23396)
			(xy 244.59565 -368.240056) (xy 244.57177 -368.262969) (xy 244.519092 -368.303031) (xy 244.46166 -368.335918)
			(xy 244.400444 -368.36107) (xy 244.336482 -368.378064) (xy 244.270855 -368.386612) (xy 244.237764 -368.387122)
			(xy 244.207368 -368.386667) (xy 244.147012 -368.379412) (xy 244.087951 -368.36501) (xy 244.03103 -368.343666)
			(xy 243.97706 -368.315686) (xy 243.926813 -368.281469) (xy 243.881007 -368.241503) (xy 243.86032 -368.219228)
			(xy 243.853716 -368.212116) (xy 243.836698 -368.20348) (xy 243.748306 -368.19586) (xy 243.730018 -368.201194)
			(xy 243.722398 -368.20729) (xy 243.69551 -368.227592) (xy 243.637361 -368.261623) (xy 243.575228 -368.28768)
			(xy 243.510199 -368.305305) (xy 243.443412 -368.31419) (xy 243.409724 -368.314732) (xy 243.379311 -368.314289)
			(xy 243.31892 -368.307039) (xy 243.259824 -368.29264) (xy 243.202867 -368.271297) (xy 243.14886 -368.243315)
			(xy 243.098576 -368.209092) (xy 243.052731 -368.169118) (xy 243.032026 -368.146838) (xy 243.024406 -368.138202)
			(xy 243.002816 -368.129312) (xy 242.899692 -368.13617) (xy 242.879372 -368.147854) (xy 242.872768 -368.157506)
			(xy 242.854987 -368.182697) (xy 242.814232 -368.228973) (xy 242.768179 -368.269979) (xy 242.717503 -368.305112)
			(xy 242.662949 -368.333856) (xy 242.605318 -368.355789) (xy 242.545457 -368.37059) (xy 242.484246 -368.378039)
			(xy 242.453414 -368.378486) (xy 242.42145 -368.37805) (xy 242.358025 -368.370039) (xy 242.296104 -368.354142)
			(xy 242.236665 -368.33061) (xy 242.180643 -368.299813) (xy 242.128923 -368.262237) (xy 242.082321 -368.218476)
			(xy 242.04157 -368.169219) (xy 242.007315 -368.115242) (xy 241.980095 -368.057398) (xy 241.96034 -367.996599)
			(xy 241.948361 -367.933802) (xy 241.944346 -367.87) (xy 241.609253 -367.87) (xy 241.609372 -367.877598)
			(xy 241.60887 -367.909559) (xy 241.600859 -367.972977) (xy 241.584962 -368.034891) (xy 241.56143 -368.094324)
			(xy 241.530636 -368.150339) (xy 241.493063 -368.202054) (xy 241.449306 -368.248651) (xy 241.400053 -368.289396)
			(xy 241.346082 -368.323647) (xy 241.288243 -368.350864) (xy 241.22745 -368.370617) (xy 241.16466 -368.382595)
			(xy 241.100864 -368.386609) (xy 241.037068 -368.382595) (xy 240.974278 -368.370617) (xy 240.913485 -368.350864)
			(xy 240.855646 -368.323647) (xy 240.801675 -368.289396) (xy 240.752422 -368.248651) (xy 240.708665 -368.202054)
			(xy 240.671092 -368.150339) (xy 240.640298 -368.094324) (xy 240.616766 -368.034891) (xy 240.600869 -367.972977)
			(xy 240.592858 -367.909559) (xy 240.310034 -367.909559) (xy 240.302665 -367.967897) (xy 240.286768 -368.029811)
			(xy 240.263236 -368.089244) (xy 240.232442 -368.145259) (xy 240.194869 -368.196974) (xy 240.151112 -368.243571)
			(xy 240.101859 -368.284316) (xy 240.047888 -368.318567) (xy 239.990049 -368.345784) (xy 239.929256 -368.365537)
			(xy 239.866466 -368.377515) (xy 239.80267 -368.381529) (xy 239.738874 -368.377515) (xy 239.676084 -368.365537)
			(xy 239.615291 -368.345784) (xy 239.557452 -368.318567) (xy 239.503481 -368.284316) (xy 239.454228 -368.243571)
			(xy 239.410471 -368.196974) (xy 239.372898 -368.145259) (xy 239.342104 -368.089244) (xy 239.318572 -368.029811)
			(xy 239.302675 -367.967897) (xy 239.294664 -367.904479) (xy 239.028896 -367.904479) (xy 239.024029 -367.943005)
			(xy 239.008132 -368.004919) (xy 238.9846 -368.064352) (xy 238.953806 -368.120367) (xy 238.916233 -368.172082)
			(xy 238.872476 -368.218679) (xy 238.823223 -368.259424) (xy 238.769252 -368.293675) (xy 238.711413 -368.320892)
			(xy 238.65062 -368.340645) (xy 238.58783 -368.352623) (xy 238.524034 -368.356637) (xy 238.460238 -368.352623)
			(xy 238.397448 -368.340645) (xy 238.336655 -368.320892) (xy 238.278816 -368.293675) (xy 238.224845 -368.259424)
			(xy 238.175592 -368.218679) (xy 238.131835 -368.172082) (xy 238.094262 -368.120367) (xy 238.063468 -368.064352)
			(xy 238.039936 -368.004919) (xy 238.024039 -367.943005) (xy 238.016028 -367.879587) (xy 237.385352 -367.879587)
			(xy 237.385352 -369.039097) (xy 245.74982 -369.039097) (xy 245.74982 -368.975175) (xy 245.757831 -368.911757)
			(xy 245.773728 -368.849843) (xy 245.79726 -368.79041) (xy 245.828054 -368.734395) (xy 245.865627 -368.68268)
			(xy 245.909384 -368.636083) (xy 245.958637 -368.595338) (xy 246.012608 -368.561087) (xy 246.070447 -368.53387)
			(xy 246.13124 -368.514117) (xy 246.19403 -368.502139) (xy 246.257826 -368.498126) (xy 246.321622 -368.502139)
			(xy 246.384412 -368.514117) (xy 246.445205 -368.53387) (xy 246.503044 -368.561087) (xy 246.557015 -368.595338)
			(xy 246.606268 -368.636083) (xy 246.646737 -368.679179) (xy 247.320556 -368.679179) (xy 247.320556 -368.615257)
			(xy 247.328567 -368.551839) (xy 247.344464 -368.489925) (xy 247.367996 -368.430492) (xy 247.39879 -368.374477)
			(xy 247.436363 -368.322762) (xy 247.48012 -368.276165) (xy 247.529373 -368.23542) (xy 247.583344 -368.201169)
			(xy 247.641183 -368.173952) (xy 247.701976 -368.154199) (xy 247.764766 -368.142221) (xy 247.828562 -368.138208)
			(xy 247.892358 -368.142221) (xy 247.955148 -368.154199) (xy 248.015941 -368.173952) (xy 248.07378 -368.201169)
			(xy 248.127751 -368.23542) (xy 248.177004 -368.276165) (xy 248.220761 -368.322762) (xy 248.258334 -368.374477)
			(xy 248.289128 -368.430492) (xy 248.31266 -368.489925) (xy 248.328557 -368.551839) (xy 248.336568 -368.615257)
			(xy 248.33707 -368.647218) (xy 248.336568 -368.679179) (xy 248.330857 -368.724391) (xy 248.60986 -368.724391)
			(xy 248.60986 -368.660469) (xy 248.617871 -368.597051) (xy 248.633768 -368.535137) (xy 248.6573 -368.475704)
			(xy 248.688094 -368.419689) (xy 248.725667 -368.367974) (xy 248.769424 -368.321377) (xy 248.818677 -368.280632)
			(xy 248.872648 -368.246381) (xy 248.930487 -368.219164) (xy 248.99128 -368.199411) (xy 249.05407 -368.187433)
			(xy 249.117866 -368.18342) (xy 249.181662 -368.187433) (xy 249.244452 -368.199411) (xy 249.305245 -368.219164)
			(xy 249.363084 -368.246381) (xy 249.417055 -368.280632) (xy 249.466308 -368.321377) (xy 249.510065 -368.367974)
			(xy 249.547638 -368.419689) (xy 249.578432 -368.475704) (xy 249.601964 -368.535137) (xy 249.617861 -368.597051)
			(xy 249.625872 -368.660469) (xy 249.626374 -368.69243) (xy 249.625872 -368.724391) (xy 249.617861 -368.787809)
			(xy 249.610854 -368.8151) (xy 271.35018 -368.8151) (xy 271.354195 -368.751299) (xy 271.366174 -368.688505)
			(xy 271.38593 -368.627707) (xy 271.41315 -368.569865) (xy 271.447406 -368.51589) (xy 271.488157 -368.466635)
			(xy 271.534759 -368.422877) (xy 271.58648 -368.385304) (xy 271.642501 -368.354511) (xy 271.701941 -368.330982)
			(xy 271.763861 -368.315089) (xy 271.827284 -368.307082) (xy 271.859248 -368.306604) (xy 271.893816 -368.307209)
			(xy 271.962313 -368.316585) (xy 272.028907 -368.335157) (xy 272.09237 -368.362582) (xy 272.151531 -368.398356)
			(xy 272.17878 -368.419634) (xy 272.186072 -368.425017) (xy 272.203246 -368.430758) (xy 272.212308 -368.43081)
			(xy 272.242788 -368.429794) (xy 272.251845 -368.429102) (xy 272.268638 -368.422219) (xy 272.275554 -368.416332)
			(xy 272.299077 -368.395313) (xy 272.350425 -368.358668) (xy 272.405911 -368.328652) (xy 272.464682 -368.305727)
			(xy 272.525837 -368.290245) (xy 272.588436 -368.282442) (xy 272.619978 -368.281966) (xy 272.653018 -368.282473)
			(xy 272.718543 -368.291025) (xy 272.782406 -368.308) (xy 272.843529 -368.333112) (xy 272.900881 -368.365937)
			(xy 272.953492 -368.405921) (xy 272.977356 -368.428778) (xy 272.985738 -368.43716) (xy 273.007328 -368.444526)
			(xy 273.109436 -368.432588) (xy 273.12874 -368.420396) (xy 273.134836 -368.41049) (xy 273.15236 -368.38353)
			(xy 273.193105 -368.333786) (xy 273.239794 -368.289574) (xy 273.291682 -368.251597) (xy 273.347942 -368.220462)
			(xy 273.407678 -368.196664) (xy 273.469936 -368.180584) (xy 273.533724 -368.172478) (xy 273.565874 -368.171984)
			(xy 273.597837 -368.172479) (xy 273.661259 -368.180488) (xy 273.723177 -368.196383) (xy 273.746236 -368.205512)
			(xy 290.223954 -368.205512) (xy 290.228025 -368.14989) (xy 290.240151 -368.095453) (xy 290.260074 -368.043362)
			(xy 290.28737 -367.994727) (xy 290.321456 -367.950584) (xy 290.361605 -367.911875) (xy 290.406963 -367.879424)
			(xy 290.456563 -367.853923) (xy 290.509347 -367.835916) (xy 290.56419 -367.825786) (xy 290.619924 -367.823749)
			(xy 290.675361 -367.829849) (xy 290.729318 -367.843955) (xy 290.780647 -367.865767) (xy 290.828253 -367.894821)
			(xy 290.871121 -367.930496) (xy 290.908338 -367.972033) (xy 290.939111 -368.018546) (xy 290.962783 -368.069043)
			(xy 290.978851 -368.12245) (xy 290.986971 -368.177626) (xy 290.98748 -368.205512) (xy 290.986971 -368.233398)
			(xy 290.978851 -368.288574) (xy 290.962783 -368.341981) (xy 290.939111 -368.392478) (xy 290.908338 -368.438991)
			(xy 290.871121 -368.480528) (xy 290.828253 -368.516203) (xy 290.780647 -368.545257) (xy 290.729318 -368.567069)
			(xy 290.675361 -368.581175) (xy 290.619924 -368.587275) (xy 290.56419 -368.585238) (xy 290.509347 -368.575108)
			(xy 290.456563 -368.557101) (xy 290.406963 -368.5316) (xy 290.361605 -368.499149) (xy 290.321456 -368.46044)
			(xy 290.28737 -368.416297) (xy 290.260074 -368.367662) (xy 290.240151 -368.315571) (xy 290.228025 -368.261134)
			(xy 290.223954 -368.205512) (xy 273.746236 -368.205512) (xy 273.782615 -368.219914) (xy 273.838634 -368.250708)
			(xy 273.890353 -368.288281) (xy 273.936954 -368.33204) (xy 273.977703 -368.381295) (xy 274.011957 -368.435269)
			(xy 274.039176 -368.49311) (xy 274.058931 -368.553907) (xy 274.070909 -368.6167) (xy 274.074924 -368.6805)
			(xy 274.070909 -368.7443) (xy 274.058931 -368.807093) (xy 274.039176 -368.86789) (xy 274.011957 -368.925731)
			(xy 273.977703 -368.979705) (xy 273.936954 -369.02896) (xy 273.890353 -369.072719) (xy 273.838634 -369.110292)
			(xy 273.782615 -369.141086) (xy 273.723177 -369.164617) (xy 273.661259 -369.180512) (xy 273.620192 -369.185698)
			(xy 288.630866 -369.185698) (xy 288.634937 -369.130076) (xy 288.647063 -369.075639) (xy 288.666986 -369.023548)
			(xy 288.694282 -368.974913) (xy 288.728368 -368.93077) (xy 288.768517 -368.892061) (xy 288.813875 -368.85961)
			(xy 288.863475 -368.834109) (xy 288.916259 -368.816102) (xy 288.971102 -368.805972) (xy 289.026836 -368.803935)
			(xy 289.082273 -368.810035) (xy 289.13623 -368.824141) (xy 289.187559 -368.845953) (xy 289.235165 -368.875007)
			(xy 289.278033 -368.910682) (xy 289.31525 -368.952219) (xy 289.346023 -368.998732) (xy 289.369695 -369.049229)
			(xy 289.385763 -369.102636) (xy 289.393883 -369.157812) (xy 289.394392 -369.185698) (xy 289.393883 -369.213584)
			(xy 289.385763 -369.26876) (xy 289.369695 -369.322167) (xy 289.346023 -369.372664) (xy 289.31525 -369.419177)
			(xy 289.278033 -369.460714) (xy 289.235165 -369.496389) (xy 289.187559 -369.525443) (xy 289.13623 -369.547255)
			(xy 289.082273 -369.561361) (xy 289.026836 -369.567461) (xy 288.971102 -369.565424) (xy 288.916259 -369.555294)
			(xy 288.863475 -369.537287) (xy 288.813875 -369.511786) (xy 288.768517 -369.479335) (xy 288.728368 -369.440626)
			(xy 288.694282 -369.396483) (xy 288.666986 -369.347848) (xy 288.647063 -369.295757) (xy 288.634937 -369.24132)
			(xy 288.630866 -369.185698) (xy 273.620192 -369.185698) (xy 273.597837 -369.188521) (xy 273.565874 -369.189)
			(xy 273.532835 -369.188441) (xy 273.467313 -369.179897) (xy 273.403452 -369.16293) (xy 273.342329 -369.137828)
			(xy 273.284977 -369.105013) (xy 273.232362 -369.06504) (xy 273.208496 -369.042188) (xy 273.200114 -369.033806)
			(xy 273.178524 -369.02644) (xy 273.076416 -369.038378) (xy 273.057112 -369.05057) (xy 273.051016 -369.060476)
			(xy 273.033547 -369.087473) (xy 272.992792 -369.137214) (xy 272.946093 -369.181423) (xy 272.894197 -369.219395)
			(xy 272.837929 -369.250525) (xy 272.778187 -369.274317) (xy 272.715923 -369.290391) (xy 272.652131 -369.298491)
			(xy 272.619978 -369.298982) (xy 272.585409 -369.298422) (xy 272.51691 -369.289036) (xy 272.450315 -369.270453)
			(xy 272.386852 -369.243018) (xy 272.327693 -369.207235) (xy 272.300446 -369.185952) (xy 272.293176 -369.180536)
			(xy 272.275985 -369.174816) (xy 272.266918 -369.174776) (xy 272.236438 -369.175792) (xy 272.227377 -369.176453)
			(xy 272.210585 -369.183358) (xy 272.203672 -369.189254) (xy 272.180136 -369.210258) (xy 272.128791 -369.246906)
			(xy 272.073308 -369.276924) (xy 272.01454 -369.299851) (xy 271.953387 -369.315337) (xy 271.890789 -369.323142)
			(xy 271.859248 -369.32362) (xy 271.827284 -369.323118) (xy 271.763861 -369.315111) (xy 271.701941 -369.299218)
			(xy 271.642501 -369.275689) (xy 271.58648 -369.244896) (xy 271.534759 -369.207323) (xy 271.488157 -369.163565)
			(xy 271.447406 -369.11431) (xy 271.41315 -369.060335) (xy 271.38593 -369.002493) (xy 271.366174 -368.941695)
			(xy 271.354195 -368.878901) (xy 271.35018 -368.8151) (xy 249.610854 -368.8151) (xy 249.601964 -368.849723)
			(xy 249.578432 -368.909156) (xy 249.547638 -368.965171) (xy 249.510065 -369.016886) (xy 249.466308 -369.063483)
			(xy 249.417055 -369.104228) (xy 249.363084 -369.138479) (xy 249.305245 -369.165696) (xy 249.244452 -369.185449)
			(xy 249.181662 -369.197427) (xy 249.117866 -369.201441) (xy 249.05407 -369.197427) (xy 248.99128 -369.185449)
			(xy 248.930487 -369.165696) (xy 248.872648 -369.138479) (xy 248.818677 -369.104228) (xy 248.769424 -369.063483)
			(xy 248.725667 -369.016886) (xy 248.688094 -368.965171) (xy 248.6573 -368.909156) (xy 248.633768 -368.849723)
			(xy 248.617871 -368.787809) (xy 248.60986 -368.724391) (xy 248.330857 -368.724391) (xy 248.328557 -368.742597)
			(xy 248.31266 -368.804511) (xy 248.289128 -368.863944) (xy 248.258334 -368.919959) (xy 248.220761 -368.971674)
			(xy 248.177004 -369.018271) (xy 248.127751 -369.059016) (xy 248.07378 -369.093267) (xy 248.015941 -369.120484)
			(xy 247.955148 -369.140237) (xy 247.892358 -369.152215) (xy 247.828562 -369.156229) (xy 247.764766 -369.152215)
			(xy 247.701976 -369.140237) (xy 247.641183 -369.120484) (xy 247.583344 -369.093267) (xy 247.529373 -369.059016)
			(xy 247.48012 -369.018271) (xy 247.436363 -368.971674) (xy 247.39879 -368.919959) (xy 247.367996 -368.863944)
			(xy 247.344464 -368.804511) (xy 247.328567 -368.742597) (xy 247.320556 -368.679179) (xy 246.646737 -368.679179)
			(xy 246.650025 -368.68268) (xy 246.687598 -368.734395) (xy 246.718392 -368.79041) (xy 246.741924 -368.849843)
			(xy 246.757821 -368.911757) (xy 246.765832 -368.975175) (xy 246.766334 -369.007136) (xy 246.765832 -369.039097)
			(xy 246.757821 -369.102515) (xy 246.741924 -369.164429) (xy 246.718392 -369.223862) (xy 246.687598 -369.279877)
			(xy 246.650025 -369.331592) (xy 246.606268 -369.378189) (xy 246.557015 -369.418934) (xy 246.503044 -369.453185)
			(xy 246.445205 -369.480402) (xy 246.384412 -369.500155) (xy 246.321622 -369.512133) (xy 246.257826 -369.516147)
			(xy 246.19403 -369.512133) (xy 246.13124 -369.500155) (xy 246.070447 -369.480402) (xy 246.012608 -369.453185)
			(xy 245.958637 -369.418934) (xy 245.909384 -369.378189) (xy 245.865627 -369.331592) (xy 245.828054 -369.279877)
			(xy 245.79726 -369.223862) (xy 245.773728 -369.164429) (xy 245.757831 -369.102515) (xy 245.74982 -369.039097)
			(xy 237.385352 -369.039097) (xy 237.385352 -371.458553) (xy 237.538967 -371.458553) (xy 237.538967 -371.404047)
			(xy 237.546725 -371.350096) (xy 237.562081 -371.297798) (xy 237.584725 -371.248218) (xy 237.614194 -371.202365)
			(xy 237.649889 -371.161173) (xy 237.691083 -371.125481) (xy 237.736937 -371.096014) (xy 237.786519 -371.073374)
			(xy 237.838817 -371.05802) (xy 237.892769 -371.050266) (xy 237.920022 -371.049804) (xy 237.948488 -371.050285)
			(xy 238.004788 -371.058744) (xy 238.059208 -371.07547) (xy 238.11054 -371.100093) (xy 238.157646 -371.132067)
			(xy 238.199481 -371.170682) (xy 238.21771 -371.192552) (xy 238.224314 -371.200934) (xy 238.243364 -371.21084)
			(xy 238.340138 -371.216682) (xy 238.360204 -371.209062) (xy 238.367824 -371.201696) (xy 238.378746 -371.191536)
			(xy 238.387128 -371.183916) (xy 238.395764 -371.163596) (xy 238.392462 -371.06352) (xy 238.382556 -371.043708)
			(xy 238.37392 -371.036596) (xy 238.351914 -371.018403) (xy 238.313077 -370.976551) (xy 238.280904 -370.929383)
			(xy 238.256112 -370.877951) (xy 238.239256 -370.8234) (xy 238.23071 -370.766947) (xy 238.230156 -370.7384)
			(xy 238.230719 -370.709342) (xy 238.23955 -370.651901) (xy 238.256993 -370.596465) (xy 238.282643 -370.544316)
			(xy 238.315907 -370.496661) (xy 238.335566 -370.475256) (xy 238.34217 -370.468144) (xy 238.349536 -370.45011)
			(xy 238.349536 -370.360194) (xy 238.34217 -370.34216) (xy 238.335566 -370.335048) (xy 238.315921 -370.313628)
			(xy 238.282638 -370.265986) (xy 238.256976 -370.213841) (xy 238.23953 -370.158405) (xy 238.230704 -370.100962)
			(xy 238.230156 -370.071904) (xy 238.230681 -370.044654) (xy 238.238436 -369.99071) (xy 238.253789 -369.938418)
			(xy 238.276427 -369.888843) (xy 238.30589 -369.842995) (xy 238.341577 -369.801805) (xy 238.382763 -369.766114)
			(xy 238.428608 -369.736646) (xy 238.478181 -369.714003) (xy 238.530471 -369.698645) (xy 238.584415 -369.690884)
			(xy 238.611664 -369.690396) (xy 238.641678 -369.690999) (xy 238.700964 -369.700406) (xy 238.758047 -369.718977)
			(xy 238.811519 -369.746255) (xy 238.860062 -369.781567) (xy 238.881666 -369.80241) (xy 238.888778 -369.809522)
			(xy 238.906558 -369.817142) (xy 238.997236 -369.818666) (xy 239.01527 -369.811808) (xy 239.022636 -369.80495)
			(xy 239.043931 -369.785911) (xy 239.091131 -369.753742) (xy 239.142597 -369.728966) (xy 239.197181 -369.712136)
			(xy 239.253664 -369.703628) (xy 239.282224 -369.703096) (xy 239.311204 -369.703591) (xy 239.368496 -369.712356)
			(xy 239.423806 -369.729681) (xy 239.475861 -369.755168) (xy 239.523464 -369.788232) (xy 239.565523 -369.828111)
			(xy 239.583722 -369.85067) (xy 239.591342 -369.860576) (xy 239.614202 -369.87099) (xy 239.723422 -369.864132)
			(xy 239.744758 -369.850924) (xy 239.751362 -369.840256) (xy 239.766161 -369.816189) (xy 239.801781 -369.772335)
			(xy 239.843482 -369.734218) (xy 239.890352 -369.702673) (xy 239.941365 -369.67839) (xy 239.995402 -369.661901)
			(xy 240.051281 -369.653568) (xy 240.07953 -369.653058) (xy 240.109324 -369.65364) (xy 240.168188 -369.662895)
			(xy 240.224896 -369.681191) (xy 240.27807 -369.708083) (xy 240.326415 -369.742917) (xy 240.368755 -369.784845)
			(xy 240.38687 -369.808506) (xy 240.394236 -369.818412) (xy 240.415572 -369.829334) (xy 240.521998 -369.82908)
			(xy 240.543588 -369.818412) (xy 240.5507 -369.808506) (xy 240.568788 -369.78473) (xy 240.611148 -369.742606)
			(xy 240.659557 -369.707601) (xy 240.712831 -369.680572) (xy 240.769669 -369.662179) (xy 240.828678 -369.652872)
			(xy 240.858548 -369.652296) (xy 240.888564 -369.652846) (xy 240.947853 -369.662266) (xy 241.004936 -369.680849)
			(xy 241.058407 -369.708139) (xy 241.106948 -369.743462) (xy 241.12855 -369.76431) (xy 241.135662 -369.771422)
			(xy 241.153442 -369.779042) (xy 241.24412 -369.780566) (xy 241.262154 -369.773708) (xy 241.26952 -369.76685)
			(xy 241.290821 -369.747819) (xy 241.338019 -369.715649) (xy 241.389484 -369.690871) (xy 241.444067 -369.674039)
			(xy 241.500548 -369.665529) (xy 241.529108 -369.664996) (xy 241.558048 -369.665518) (xy 241.615266 -369.674254)
			(xy 241.670511 -369.691523) (xy 241.722517 -369.716931) (xy 241.770094 -369.749895) (xy 241.79149 -369.76939)
			(xy 241.798856 -369.776502) (xy 241.81816 -369.783868) (xy 241.911632 -369.779804) (xy 241.930174 -369.770914)
			(xy 241.937032 -369.763294) (xy 241.955222 -369.743572) (xy 241.99617 -369.708908) (xy 242.04157 -369.680321)
			(xy 242.090526 -369.658372) (xy 242.142072 -369.643496) (xy 242.195195 -369.635986) (xy 242.22202 -369.635532)
			(xy 242.249275 -369.635936) (xy 242.30323 -369.643697) (xy 242.355532 -369.659058) (xy 242.405115 -369.681705)
			(xy 242.45097 -369.711179) (xy 242.492163 -369.746879) (xy 242.527857 -369.788078) (xy 242.557323 -369.833938)
			(xy 242.579963 -369.883524) (xy 242.595316 -369.935828) (xy 242.603068 -369.989785) (xy 242.603528 -370.01704)
			(xy 242.60316 -370.037317) (xy 246.698764 -370.037317) (xy 246.698764 -369.973395) (xy 246.706775 -369.909977)
			(xy 246.722672 -369.848063) (xy 246.746204 -369.78863) (xy 246.776998 -369.732615) (xy 246.814571 -369.6809)
			(xy 246.858328 -369.634303) (xy 246.907581 -369.593558) (xy 246.961552 -369.559307) (xy 247.019391 -369.53209)
			(xy 247.080184 -369.512337) (xy 247.142974 -369.500359) (xy 247.20677 -369.496346) (xy 247.270566 -369.500359)
			(xy 247.333356 -369.512337) (xy 247.394149 -369.53209) (xy 247.451988 -369.559307) (xy 247.505959 -369.593558)
			(xy 247.555212 -369.634303) (xy 247.598969 -369.6809) (xy 247.636542 -369.732615) (xy 247.667336 -369.78863)
			(xy 247.690868 -369.848063) (xy 247.706765 -369.909977) (xy 247.714776 -369.973395) (xy 247.715278 -370.005356)
			(xy 247.714776 -370.037317) (xy 247.706765 -370.100735) (xy 247.690868 -370.162649) (xy 247.667336 -370.222082)
			(xy 247.636542 -370.278097) (xy 247.598969 -370.329812) (xy 247.555212 -370.376409) (xy 247.505959 -370.417154)
			(xy 247.451988 -370.451405) (xy 247.394149 -370.478622) (xy 247.333356 -370.498375) (xy 247.270566 -370.510353)
			(xy 247.20677 -370.514367) (xy 247.142974 -370.510353) (xy 247.080184 -370.498375) (xy 247.019391 -370.478622)
			(xy 246.961552 -370.451405) (xy 246.907581 -370.417154) (xy 246.858328 -370.376409) (xy 246.814571 -370.329812)
			(xy 246.776998 -370.278097) (xy 246.746204 -370.222082) (xy 246.722672 -370.162649) (xy 246.706775 -370.100735)
			(xy 246.698764 -370.037317) (xy 242.60316 -370.037317) (xy 242.603037 -370.0441) (xy 242.595379 -370.097676)
			(xy 242.580222 -370.149631) (xy 242.557872 -370.198921) (xy 242.528777 -370.244556) (xy 242.493522 -370.285618)
			(xy 242.47348 -370.303806) (xy 242.465352 -370.311172) (xy 242.456208 -370.330984) (xy 242.4557 -370.428774)
			(xy 242.46459 -370.44884) (xy 242.472718 -370.455952) (xy 242.492308 -370.474079) (xy 242.526727 -370.514871)
			(xy 242.541298 -370.537232) (xy 242.547902 -370.547646) (xy 242.568984 -370.560092) (xy 242.67541 -370.56695)
			(xy 242.698016 -370.557298) (xy 242.705636 -370.547646) (xy 242.723841 -370.526328) (xy 242.765478 -370.488792)
			(xy 242.812156 -370.457747) (xy 242.862872 -370.433861) (xy 242.916535 -370.417647) (xy 242.971992 -370.409454)
			(xy 243.000022 -370.408962) (xy 243.027272 -370.409457) (xy 243.081218 -370.417216) (xy 243.133511 -370.432572)
			(xy 243.183086 -370.455214) (xy 243.228935 -370.48468) (xy 243.270124 -370.52037) (xy 243.305816 -370.561558)
			(xy 243.335282 -370.607407) (xy 243.357925 -370.656982) (xy 243.373282 -370.709274) (xy 243.381042 -370.76322)
			(xy 243.38153 -370.79047) (xy 243.381084 -370.815921) (xy 243.374289 -370.866367) (xy 243.372896 -370.871453)
			(xy 247.910598 -370.871453) (xy 247.910598 -370.807531) (xy 247.918609 -370.744113) (xy 247.934506 -370.682199)
			(xy 247.958038 -370.622766) (xy 247.988832 -370.566751) (xy 248.026405 -370.515036) (xy 248.070162 -370.468439)
			(xy 248.119415 -370.427694) (xy 248.173386 -370.393443) (xy 248.231225 -370.366226) (xy 248.292018 -370.346473)
			(xy 248.354808 -370.334495) (xy 248.418604 -370.330482) (xy 248.4824 -370.334495) (xy 248.54519 -370.346473)
			(xy 248.605983 -370.366226) (xy 248.663822 -370.393443) (xy 248.717793 -370.427694) (xy 248.767046 -370.468439)
			(xy 248.810803 -370.515036) (xy 248.848376 -370.566751) (xy 248.87917 -370.622766) (xy 248.902702 -370.682199)
			(xy 248.918599 -370.744113) (xy 248.92661 -370.807531) (xy 248.927112 -370.839492) (xy 248.92661 -370.871453)
			(xy 248.918599 -370.934871) (xy 248.902702 -370.996785) (xy 248.87917 -371.056218) (xy 248.848376 -371.112233)
			(xy 248.810803 -371.163948) (xy 248.767046 -371.210545) (xy 248.717793 -371.25129) (xy 248.663822 -371.285541)
			(xy 248.605983 -371.312758) (xy 248.54519 -371.332511) (xy 248.4824 -371.344489) (xy 248.418604 -371.348503)
			(xy 248.354808 -371.344489) (xy 248.292018 -371.332511) (xy 248.231225 -371.312758) (xy 248.173386 -371.285541)
			(xy 248.119415 -371.25129) (xy 248.070162 -371.210545) (xy 248.026405 -371.163948) (xy 247.988832 -371.112233)
			(xy 247.958038 -371.056218) (xy 247.934506 -370.996785) (xy 247.918609 -370.934871) (xy 247.910598 -370.871453)
			(xy 243.372896 -370.871453) (xy 243.360844 -370.915461) (xy 243.351304 -370.93906) (xy 243.346478 -370.950998)
			(xy 243.34851 -370.975636) (xy 243.407438 -371.067584) (xy 243.428774 -371.079776) (xy 243.441728 -371.080284)
			(xy 243.468384 -371.081618) (xy 243.520964 -371.090763) (xy 243.571756 -371.107149) (xy 243.619767 -371.130456)
			(xy 243.66406 -371.160228) (xy 243.70377 -371.195886) (xy 243.738121 -371.236731) (xy 243.766442 -371.281966)
			(xy 243.78818 -371.330708) (xy 243.802911 -371.382004) (xy 243.810346 -371.434853) (xy 243.81079 -371.461538)
			(xy 243.810304 -371.488789) (xy 243.802548 -371.542737) (xy 243.80065 -371.5492) (xy 291.773357 -371.5492)
			(xy 291.777371 -371.485402) (xy 291.789349 -371.422611) (xy 291.809102 -371.361815) (xy 291.836318 -371.303975)
			(xy 291.870569 -371.250001) (xy 291.911315 -371.200746) (xy 291.957912 -371.156986) (xy 292.009626 -371.119411)
			(xy 292.065642 -371.088613) (xy 292.125076 -371.065079) (xy 292.186991 -371.049179) (xy 292.25041 -371.041164)
			(xy 292.282372 -371.04066) (xy 292.317104 -371.041239) (xy 292.38592 -371.050708) (xy 292.452805 -371.069458)
			(xy 292.516515 -371.097142) (xy 292.575861 -371.133243) (xy 292.603174 -371.154706) (xy 292.610497 -371.160183)
			(xy 292.627812 -371.166029) (xy 292.636956 -371.166136) (xy 292.667436 -371.16512) (xy 292.676499 -371.164468)
			(xy 292.693292 -371.157559) (xy 292.700202 -371.151658) (xy 292.723749 -371.130444) (xy 292.775221 -371.093462)
			(xy 292.830891 -371.063163) (xy 292.889894 -371.040018) (xy 292.951317 -371.024385) (xy 293.014206 -371.016507)
			(xy 293.045896 -371.016022) (xy 293.07786 -371.016443) (xy 293.141285 -371.024455) (xy 293.203206 -371.040353)
			(xy 293.262645 -371.063886) (xy 293.318667 -371.094684) (xy 293.370386 -371.13226) (xy 293.416989 -371.176022)
			(xy 293.457738 -371.22528) (xy 293.491993 -371.279257) (xy 293.519213 -371.337101) (xy 293.538968 -371.397901)
			(xy 293.550947 -371.460697) (xy 293.554962 -371.5245) (xy 293.550947 -371.588303) (xy 293.538968 -371.651099)
			(xy 293.519213 -371.711899) (xy 293.491993 -371.769743) (xy 293.457738 -371.82372) (xy 293.416989 -371.872978)
			(xy 293.370386 -371.91674) (xy 293.318667 -371.954316) (xy 293.262645 -371.985114) (xy 293.203206 -372.008647)
			(xy 293.141285 -372.024545) (xy 293.07786 -372.032557) (xy 293.045896 -372.033038) (xy 293.011164 -372.032447)
			(xy 292.942346 -372.022987) (xy 292.875457 -372.004245) (xy 292.811744 -371.976568) (xy 292.752393 -371.940473)
			(xy 292.725094 -371.918992) (xy 292.717753 -371.913544) (xy 292.700452 -371.90768) (xy 292.691312 -371.907562)
			(xy 292.660832 -371.908578) (xy 292.651767 -371.909216) (xy 292.634975 -371.916135) (xy 292.628066 -371.92204)
			(xy 292.604491 -371.943221) (xy 292.553025 -371.980207) (xy 292.497361 -372.010511) (xy 292.438364 -372.033662)
			(xy 292.376946 -372.049301) (xy 292.314061 -372.057187) (xy 292.282372 -372.057676) (xy 292.25041 -372.057236)
			(xy 292.186991 -372.049221) (xy 292.125076 -372.033321) (xy 292.065642 -372.009787) (xy 292.009626 -371.978989)
			(xy 291.957912 -371.941414) (xy 291.911315 -371.897654) (xy 291.870569 -371.848399) (xy 291.836318 -371.794425)
			(xy 291.809102 -371.736585) (xy 291.789349 -371.675789) (xy 291.777371 -371.612998) (xy 291.773357 -371.5492)
			(xy 243.80065 -371.5492) (xy 243.787193 -371.595032) (xy 243.764551 -371.644609) (xy 243.735085 -371.690459)
			(xy 243.699394 -371.73165) (xy 243.658203 -371.767341) (xy 243.612353 -371.796807) (xy 243.562776 -371.819449)
			(xy 243.510481 -371.834804) (xy 243.456533 -371.84256) (xy 243.402031 -371.84256) (xy 243.348083 -371.834804)
			(xy 243.295788 -371.819449) (xy 243.246211 -371.796807) (xy 243.200361 -371.767341) (xy 243.15917 -371.73165)
			(xy 243.123479 -371.690459) (xy 243.094013 -371.644609) (xy 243.071371 -371.595032) (xy 243.056016 -371.542737)
			(xy 243.04826 -371.488789) (xy 243.047774 -371.461538) (xy 243.048222 -371.436087) (xy 243.055016 -371.385641)
			(xy 243.068461 -371.336547) (xy 243.078 -371.312948) (xy 243.082826 -371.30101) (xy 243.080794 -371.276372)
			(xy 243.021866 -371.184424) (xy 243.00053 -371.172232) (xy 242.987576 -371.171724) (xy 242.96099 -371.170394)
			(xy 242.908547 -371.161279) (xy 242.85788 -371.144962) (xy 242.809975 -371.121757) (xy 242.765761 -371.092118)
			(xy 242.726098 -371.056618) (xy 242.691756 -371.015948) (xy 242.677188 -370.99367) (xy 242.670584 -370.983256)
			(xy 242.649502 -370.97081) (xy 242.543076 -370.963952) (xy 242.52047 -370.973604) (xy 242.51285 -370.983256)
			(xy 242.494653 -371.004581) (xy 242.453014 -371.042117) (xy 242.406334 -371.07316) (xy 242.355617 -371.097045)
			(xy 242.301952 -371.113258) (xy 242.246494 -371.121449) (xy 242.218464 -371.12194) (xy 242.191914 -371.121462)
			(xy 242.139329 -371.114089) (xy 242.088275 -371.099493) (xy 242.039741 -371.077954) (xy 241.994664 -371.049889)
			(xy 241.953917 -371.015842) (xy 241.935762 -370.996464) (xy 241.92865 -370.988844) (xy 241.910362 -370.980208)
			(xy 241.817144 -370.976398) (xy 241.798348 -370.98351) (xy 241.790728 -370.990622) (xy 241.769394 -371.010045)
			(xy 241.721929 -371.04284) (xy 241.670066 -371.068114) (xy 241.61499 -371.08529) (xy 241.557955 -371.093978)
			(xy 241.529108 -371.094508) (xy 241.499092 -371.09395) (xy 241.439802 -371.084537) (xy 241.382718 -371.065956)
			(xy 241.329246 -371.038667) (xy 241.280707 -371.003343) (xy 241.259106 -370.982494) (xy 241.251994 -370.975382)
			(xy 241.234214 -370.967762) (xy 241.143536 -370.966238) (xy 241.125502 -370.973096) (xy 241.118136 -370.979954)
			(xy 241.096853 -370.999007) (xy 241.04965 -371.031174) (xy 240.99818 -371.055947) (xy 240.943593 -371.072774)
			(xy 240.887109 -371.081278) (xy 240.858548 -371.081808) (xy 240.828753 -371.081256) (xy 240.769887 -371.071997)
			(xy 240.713177 -371.053695) (xy 240.660003 -371.026798) (xy 240.611659 -370.991958) (xy 240.569321 -370.950024)
			(xy 240.551208 -370.92636) (xy 240.543842 -370.916454) (xy 240.522506 -370.905532) (xy 240.41608 -370.905786)
			(xy 240.39449 -370.916454) (xy 240.387378 -370.92636) (xy 240.369293 -370.950139) (xy 240.326934 -370.992265)
			(xy 240.278525 -371.027271) (xy 240.225249 -371.0543) (xy 240.168411 -371.072691) (xy 240.1094 -371.081995)
			(xy 240.07953 -371.08257) (xy 240.050553 -371.082011) (xy 239.993264 -371.073256) (xy 239.937957 -371.055941)
			(xy 239.885903 -371.030466) (xy 239.838297 -370.997416) (xy 239.796234 -370.957549) (xy 239.778032 -370.934996)
			(xy 239.770412 -370.92509) (xy 239.747552 -370.914676) (xy 239.638332 -370.921534) (xy 239.616996 -370.934742)
			(xy 239.610392 -370.94541) (xy 239.595543 -370.969445) (xy 239.559933 -371.0133) (xy 239.518241 -371.05142)
			(xy 239.471379 -371.08297) (xy 239.420374 -371.107258) (xy 239.366344 -371.123754) (xy 239.31047 -371.132094)
			(xy 239.282224 -371.132608) (xy 239.252208 -371.13204) (xy 239.192919 -371.122629) (xy 239.135835 -371.104051)
			(xy 239.082363 -371.076764) (xy 239.033824 -371.041442) (xy 239.012222 -371.020594) (xy 239.00511 -371.013482)
			(xy 238.98733 -371.005862) (xy 238.896652 -371.004338) (xy 238.878618 -371.011196) (xy 238.871252 -371.018054)
			(xy 238.867696 -371.021102) (xy 238.859314 -371.028722) (xy 238.850678 -371.049042) (xy 238.85398 -371.149118)
			(xy 238.863886 -371.16893) (xy 238.872522 -371.176042) (xy 238.894486 -371.194284) (xy 238.933329 -371.236123)
			(xy 238.965509 -371.283281) (xy 238.990308 -371.334704) (xy 239.007172 -371.389247) (xy 239.015727 -371.445693)
			(xy 239.016286 -371.474238) (xy 239.015857 -371.501491) (xy 239.008095 -371.555442) (xy 238.992734 -371.607739)
			(xy 238.970087 -371.657318) (xy 238.940615 -371.703169) (xy 238.904917 -371.74436) (xy 238.863721 -371.780051)
			(xy 238.817865 -371.809516) (xy 238.768283 -371.832155) (xy 238.715983 -371.847508) (xy 238.662031 -371.855262)
			(xy 238.634778 -371.855746) (xy 238.606313 -371.855247) (xy 238.550014 -371.846789) (xy 238.495595 -371.830065)
			(xy 238.444263 -371.805446) (xy 238.397157 -371.773476) (xy 238.35532 -371.734866) (xy 238.33709 -371.712998)
			(xy 238.330486 -371.704616) (xy 238.311436 -371.69471) (xy 238.214662 -371.688868) (xy 238.194596 -371.696488)
			(xy 238.186976 -371.703854) (xy 238.165432 -371.724136) (xy 238.117285 -371.758524) (xy 238.064405 -371.785064)
			(xy 238.008061 -371.803121) (xy 237.949605 -371.812261) (xy 237.920022 -371.81282) (xy 237.892769 -371.812334)
			(xy 237.838817 -371.80458) (xy 237.786519 -371.789226) (xy 237.736937 -371.766586) (xy 237.691083 -371.737119)
			(xy 237.649889 -371.701427) (xy 237.614194 -371.660235) (xy 237.584725 -371.614382) (xy 237.562081 -371.564802)
			(xy 237.546725 -371.512504) (xy 237.538967 -371.458553) (xy 237.385352 -371.458553) (xy 237.385352 -372.344696)
			(xy 237.385776 -372.354765) (xy 237.393495 -372.373366) (xy 237.400338 -372.380764) (xy 238.976408 -373.956834)
			(xy 282.726384 -373.956834) (xy 282.726932 -373.921878) (xy 282.736502 -373.852623) (xy 282.755467 -373.785332)
			(xy 282.78347 -373.721272) (xy 282.819982 -373.661651) (xy 282.8417 -373.634254) (xy 282.846984 -373.627247)
			(xy 282.852965 -373.610761) (xy 282.853384 -373.601996) (xy 282.853384 -373.448072) (xy 282.853019 -373.439296)
			(xy 282.847034 -373.422794) (xy 282.8417 -373.415814) (xy 282.819993 -373.38841) (xy 282.783495 -373.328786)
			(xy 282.755501 -373.264726) (xy 282.736539 -373.197438) (xy 282.726965 -373.128188) (xy 282.726384 -373.093234)
			(xy 282.72687 -373.062503) (xy 282.734274 -373.001488) (xy 282.748979 -372.941811) (xy 282.770771 -372.884342)
			(xy 282.799331 -372.829919) (xy 282.834243 -372.779335) (xy 282.874998 -372.733328) (xy 282.921002 -372.692569)
			(xy 282.971583 -372.657653) (xy 283.026004 -372.629088) (xy 283.083471 -372.607292) (xy 283.143147 -372.592582)
			(xy 283.204161 -372.585172) (xy 283.234892 -372.584726) (xy 283.266082 -372.585189) (xy 283.32799 -372.592857)
			(xy 283.388497 -372.60803) (xy 283.446697 -372.630481) (xy 283.501719 -372.659874) (xy 283.5275 -372.677436)
			(xy 283.535882 -372.683278) (xy 283.555186 -372.687596) (xy 283.645864 -372.672102) (xy 283.662628 -372.661688)
			(xy 283.668724 -372.653306) (xy 283.68559 -372.630707) (xy 283.72522 -372.590594) (xy 283.770676 -372.557229)
			(xy 283.820824 -372.531447) (xy 283.874408 -372.513891) (xy 283.93009 -372.505) (xy 283.958284 -372.504462)
			(xy 283.984934 -372.504994) (xy 284.037638 -372.512936) (xy 284.08857 -372.528644) (xy 284.136592 -372.551768)
			(xy 284.180631 -372.581792) (xy 284.219703 -372.618043) (xy 284.252935 -372.659714) (xy 284.279585 -372.705872)
			(xy 284.299058 -372.755487) (xy 284.310919 -372.80745) (xy 284.314902 -372.8606) (xy 284.310919 -372.91375)
			(xy 284.299058 -372.965713) (xy 284.279585 -373.015328) (xy 284.252935 -373.061486) (xy 284.219703 -373.103157)
			(xy 284.180631 -373.139408) (xy 284.136592 -373.169432) (xy 284.08857 -373.192556) (xy 284.037638 -373.208264)
			(xy 283.984934 -373.216206) (xy 283.958284 -373.216678) (xy 283.929106 -373.216064) (xy 283.871539 -373.206483)
			(xy 283.84373 -373.197628) (xy 283.834078 -373.194326) (xy 283.814266 -373.195596) (xy 283.731462 -373.235982)
			(xy 283.718508 -373.250714) (xy 283.715206 -373.26062) (xy 283.704972 -373.288638) (xy 283.678876 -373.342277)
			(xy 283.64668 -373.392492) (xy 283.628084 -373.415814) (xy 283.622782 -373.422809) (xy 283.61681 -373.439304)
			(xy 283.6164 -373.448072) (xy 283.6164 -373.601996) (xy 283.616763 -373.610773) (xy 283.622747 -373.627276)
			(xy 283.628084 -373.634254) (xy 283.651625 -373.664095) (xy 283.673014 -373.699997) (xy 292.81729 -373.699997)
			(xy 292.81729 -373.636075) (xy 292.825301 -373.572657) (xy 292.841198 -373.510743) (xy 292.86473 -373.45131)
			(xy 292.895524 -373.395295) (xy 292.933097 -373.34358) (xy 292.976854 -373.296983) (xy 293.026107 -373.256238)
			(xy 293.080078 -373.221987) (xy 293.137917 -373.19477) (xy 293.19871 -373.175017) (xy 293.2615 -373.163039)
			(xy 293.325296 -373.159026) (xy 293.389092 -373.163039) (xy 293.451882 -373.175017) (xy 293.512675 -373.19477)
			(xy 293.570514 -373.221987) (xy 293.624485 -373.256238) (xy 293.673738 -373.296983) (xy 293.717495 -373.34358)
			(xy 293.755068 -373.395295) (xy 293.785862 -373.45131) (xy 293.809394 -373.510743) (xy 293.825291 -373.572657)
			(xy 293.833302 -373.636075) (xy 293.833804 -373.668036) (xy 293.83331 -373.699489) (xy 293.949876 -373.699489)
			(xy 293.949876 -373.635567) (xy 293.957887 -373.572149) (xy 293.973784 -373.510235) (xy 293.997316 -373.450802)
			(xy 294.02811 -373.394787) (xy 294.065683 -373.343072) (xy 294.10944 -373.296475) (xy 294.158693 -373.25573)
			(xy 294.212664 -373.221479) (xy 294.270503 -373.194262) (xy 294.331296 -373.174509) (xy 294.394086 -373.162531)
			(xy 294.457882 -373.158518) (xy 294.521678 -373.162531) (xy 294.584468 -373.174509) (xy 294.645261 -373.194262)
			(xy 294.7031 -373.221479) (xy 294.757071 -373.25573) (xy 294.806324 -373.296475) (xy 294.850081 -373.343072)
			(xy 294.887654 -373.394787) (xy 294.918448 -373.450802) (xy 294.94198 -373.510235) (xy 294.957877 -373.572149)
			(xy 294.965888 -373.635567) (xy 294.96639 -373.667528) (xy 294.965888 -373.699489) (xy 294.957877 -373.762907)
			(xy 294.94198 -373.824821) (xy 294.918448 -373.884254) (xy 294.887654 -373.940269) (xy 294.850081 -373.991984)
			(xy 294.806324 -374.038581) (xy 294.757071 -374.079326) (xy 294.7031 -374.113577) (xy 294.645261 -374.140794)
			(xy 294.584468 -374.160547) (xy 294.521678 -374.172525) (xy 294.457882 -374.176539) (xy 294.394086 -374.172525)
			(xy 294.331296 -374.160547) (xy 294.270503 -374.140794) (xy 294.212664 -374.113577) (xy 294.158693 -374.079326)
			(xy 294.10944 -374.038581) (xy 294.065683 -373.991984) (xy 294.02811 -373.940269) (xy 293.997316 -373.884254)
			(xy 293.973784 -373.824821) (xy 293.957887 -373.762907) (xy 293.949876 -373.699489) (xy 293.83331 -373.699489)
			(xy 293.833302 -373.699997) (xy 293.825291 -373.763415) (xy 293.809394 -373.825329) (xy 293.785862 -373.884762)
			(xy 293.755068 -373.940777) (xy 293.717495 -373.992492) (xy 293.673738 -374.039089) (xy 293.624485 -374.079834)
			(xy 293.570514 -374.114085) (xy 293.512675 -374.141302) (xy 293.451882 -374.161055) (xy 293.389092 -374.173033)
			(xy 293.325296 -374.177047) (xy 293.2615 -374.173033) (xy 293.19871 -374.161055) (xy 293.137917 -374.141302)
			(xy 293.080078 -374.114085) (xy 293.026107 -374.079834) (xy 292.976854 -374.039089) (xy 292.933097 -373.992492)
			(xy 292.895524 -373.940777) (xy 292.86473 -373.884762) (xy 292.841198 -373.825329) (xy 292.825301 -373.763415)
			(xy 292.81729 -373.699997) (xy 283.673014 -373.699997) (xy 283.690526 -373.72939) (xy 283.705554 -373.764302)
			(xy 283.70911 -373.773192) (xy 283.72181 -373.786654) (xy 283.80055 -373.8245) (xy 283.818838 -373.826024)
			(xy 283.828236 -373.823484) (xy 283.852709 -373.816762) (xy 283.902937 -373.809493) (xy 283.928312 -373.809006)
			(xy 283.954962 -373.809477) (xy 284.007666 -373.817422) (xy 284.058597 -373.833134) (xy 284.106618 -373.856261)
			(xy 284.150655 -373.886286) (xy 284.189726 -373.92254) (xy 284.222957 -373.964212) (xy 284.249606 -374.010371)
			(xy 284.269078 -374.059986) (xy 284.280939 -374.111949) (xy 284.284922 -374.1651) (xy 284.280939 -374.218251)
			(xy 284.269078 -374.270214) (xy 284.249606 -374.319829) (xy 284.222957 -374.365988) (xy 284.189726 -374.40766)
			(xy 284.150655 -374.443914) (xy 284.106618 -374.473939) (xy 284.058597 -374.497066) (xy 284.007666 -374.512778)
			(xy 283.954962 -374.520723) (xy 283.928312 -374.521222) (xy 283.902525 -374.520738) (xy 283.851493 -374.513282)
			(xy 283.802071 -374.498537) (xy 283.755296 -374.476814) (xy 283.712145 -374.448566) (xy 283.673524 -374.414387)
			(xy 283.656532 -374.394984) (xy 283.650182 -374.387872) (xy 283.633926 -374.378982) (xy 283.547566 -374.367044)
			(xy 283.529532 -374.371362) (xy 283.521658 -374.376696) (xy 283.496235 -374.393514) (xy 283.442159 -374.421652)
			(xy 283.385105 -374.443116) (xy 283.325892 -374.457599) (xy 283.265371 -374.464893) (xy 283.234892 -374.465342)
			(xy 283.204162 -374.464852) (xy 283.143151 -374.457443) (xy 283.083477 -374.442734) (xy 283.026011 -374.420941)
			(xy 282.971591 -374.392379) (xy 282.92101 -374.357467) (xy 282.875006 -374.316713) (xy 282.834249 -374.270711)
			(xy 282.799334 -374.220132) (xy 282.77077 -374.165713) (xy 282.748973 -374.108248) (xy 282.734262 -374.048575)
			(xy 282.72685 -373.987564) (xy 282.726384 -373.956834) (xy 238.976408 -373.956834) (xy 240.292128 -375.272554)
			(xy 240.299473 -375.279365) (xy 240.317936 -375.287094) (xy 240.327942 -375.28754) (xy 277.75535 -375.28754)
			(xy 277.765382 -375.287979) (xy 277.783954 -375.295556) (xy 277.791418 -375.302272) (xy 278.846788 -376.357642)
			(xy 278.853576 -376.365063) (xy 278.861193 -376.38366) (xy 278.86152 -376.39371) (xy 278.86152 -378.470668)
			(xy 285.209742 -378.470668) (xy 285.210303 -378.437329) (xy 285.219017 -378.371223) (xy 285.23629 -378.306822)
			(xy 285.261827 -378.245228) (xy 285.295191 -378.187497) (xy 285.335809 -378.134619) (xy 285.382986 -378.0875)
			(xy 285.409132 -378.066808) (xy 285.415944 -378.061125) (xy 285.425558 -378.046236) (xy 285.429504 -378.028958)
			(xy 285.427306 -378.011371) (xy 285.42361 -378.003308) (xy 285.410334 -377.976396) (xy 285.389515 -377.920113)
			(xy 285.375477 -377.861767) (xy 285.368417 -377.802173) (xy 285.367984 -377.772168) (xy 285.368487 -377.741122)
			(xy 285.376047 -377.679492) (xy 285.391052 -377.619241) (xy 285.413277 -377.561263) (xy 285.442393 -377.506421)
			(xy 285.477967 -377.45553) (xy 285.51947 -377.409346) (xy 285.566284 -377.368557) (xy 285.617715 -377.333768)
			(xy 285.672997 -377.305496) (xy 285.701994 -377.294394) (xy 285.710478 -377.290954) (xy 285.724409 -377.279099)
			(xy 285.729172 -377.27128) (xy 285.743904 -377.24461) (xy 285.747965 -377.23641) (xy 285.750575 -377.218314)
			(xy 285.748984 -377.209304) (xy 285.743398 -377.182345) (xy 285.737417 -377.127613) (xy 285.737046 -377.100084)
			(xy 285.737548 -377.068123) (xy 285.745559 -377.004705) (xy 285.761456 -376.942791) (xy 285.784988 -376.883358)
			(xy 285.815782 -376.827343) (xy 285.853355 -376.775628) (xy 285.897112 -376.729031) (xy 285.946365 -376.688286)
			(xy 286.000336 -376.654035) (xy 286.058175 -376.626818) (xy 286.118968 -376.607065) (xy 286.181758 -376.595087)
			(xy 286.245554 -376.591074) (xy 286.30935 -376.595087) (xy 286.37214 -376.607065) (xy 286.432933 -376.626818)
			(xy 286.490772 -376.654035) (xy 286.544743 -376.688286) (xy 286.593996 -376.729031) (xy 286.637753 -376.775628)
			(xy 286.675326 -376.827343) (xy 286.70612 -376.883358) (xy 286.729652 -376.942791) (xy 286.745549 -377.004705)
			(xy 286.75356 -377.068123) (xy 286.754062 -377.100084) (xy 286.753575 -377.13113) (xy 286.746009 -377.192759)
			(xy 286.731 -377.25301) (xy 286.713559 -377.2985) (xy 286.886326 -377.2985) (xy 286.890341 -377.234695)
			(xy 286.90232 -377.171897) (xy 286.922076 -377.111095) (xy 286.949297 -377.053249) (xy 286.983554 -376.99927)
			(xy 287.024305 -376.950011) (xy 287.07091 -376.906248) (xy 287.122631 -376.868671) (xy 287.178655 -376.837873)
			(xy 287.238097 -376.814339) (xy 287.30002 -376.798442) (xy 287.363447 -376.79043) (xy 287.395412 -376.78995)
			(xy 287.425223 -376.790387) (xy 287.484431 -376.797394) (xy 287.513522 -376.80392) (xy 287.522778 -376.805647)
			(xy 287.541409 -376.803027) (xy 287.549844 -376.79884) (xy 287.576768 -376.783854) (xy 287.584847 -376.778946)
			(xy 287.596989 -376.764478) (xy 287.60039 -376.75566) (xy 287.610915 -376.725725) (xy 287.63839 -376.668526)
			(xy 287.672771 -376.615191) (xy 287.713524 -376.566551) (xy 287.760013 -376.523362) (xy 287.811517 -376.486295)
			(xy 287.867235 -376.455927) (xy 287.926299 -376.432731) (xy 287.987791 -376.417067) (xy 288.050754 -376.409179)
			(xy 288.082482 -376.408696) (xy 288.114445 -376.409168) (xy 288.177868 -376.417178) (xy 288.239787 -376.433074)
			(xy 288.299225 -376.456605) (xy 288.355245 -376.487401) (xy 288.406964 -376.524975) (xy 288.453565 -376.568735)
			(xy 288.494314 -376.617991) (xy 288.528568 -376.671965) (xy 288.555788 -376.729808) (xy 288.575542 -376.790605)
			(xy 288.587521 -376.8534) (xy 288.591536 -376.9172) (xy 288.587521 -376.981) (xy 288.575542 -377.043795)
			(xy 288.555788 -377.104592) (xy 288.528568 -377.162435) (xy 288.494314 -377.216409) (xy 288.453565 -377.265665)
			(xy 288.406964 -377.309425) (xy 288.355245 -377.346999) (xy 288.299225 -377.377795) (xy 288.239787 -377.401326)
			(xy 288.177868 -377.417222) (xy 288.114445 -377.425232) (xy 288.082482 -377.425712) (xy 288.052671 -377.425277)
			(xy 287.993463 -377.418269) (xy 287.964372 -377.411742) (xy 287.955116 -377.410016) (xy 287.936485 -377.412637)
			(xy 287.92805 -377.416822) (xy 287.901126 -377.431808) (xy 287.89303 -377.436692) (xy 287.886448 -377.444549)
			(xy 299.675308 -377.444549) (xy 299.675308 -377.390051) (xy 299.683064 -377.336108) (xy 299.698418 -377.283818)
			(xy 299.721057 -377.234245) (xy 299.75052 -377.188398) (xy 299.786209 -377.147211) (xy 299.827395 -377.111523)
			(xy 299.873241 -377.082059) (xy 299.922814 -377.059419) (xy 299.975104 -377.044065) (xy 300.029047 -377.036308)
			(xy 300.056296 -377.035822) (xy 300.084998 -377.036838) (xy 300.098206 -377.037854) (xy 300.121828 -377.026932)
			(xy 300.18863 -376.936254) (xy 300.191932 -376.910346) (xy 300.186852 -376.8979) (xy 300.178317 -376.875389)
			(xy 300.166313 -376.828766) (xy 300.16028 -376.781002) (xy 300.159928 -376.75693) (xy 300.160414 -376.729679)
			(xy 300.16817 -376.675731) (xy 300.183525 -376.623436) (xy 300.206167 -376.573859) (xy 300.235633 -376.528009)
			(xy 300.271324 -376.486818) (xy 300.312515 -376.451127) (xy 300.358365 -376.421661) (xy 300.407942 -376.399019)
			(xy 300.460237 -376.383664) (xy 300.514185 -376.375908) (xy 300.568687 -376.375908) (xy 300.622635 -376.383664)
			(xy 300.67493 -376.399019) (xy 300.724507 -376.421661) (xy 300.770357 -376.451127) (xy 300.811548 -376.486818)
			(xy 300.847239 -376.528009) (xy 300.876705 -376.573859) (xy 300.899347 -376.623436) (xy 300.914702 -376.675731)
			(xy 300.922458 -376.729679) (xy 300.922944 -376.75693) (xy 300.92238 -376.786367) (xy 300.913325 -376.84454)
			(xy 300.90491 -376.872754) (xy 300.902545 -376.881363) (xy 300.903319 -376.899186) (xy 300.906434 -376.907552)
			(xy 300.918372 -376.935746) (xy 300.922188 -376.943983) (xy 300.934561 -376.957254) (xy 300.942502 -376.961654)
			(xy 300.968194 -376.974825) (xy 301.016701 -377.00614) (xy 301.039276 -377.024138) (xy 301.046279 -377.029403)
			(xy 301.062779 -377.035252) (xy 301.071534 -377.035568) (xy 301.225458 -377.035568) (xy 301.234208 -377.035237)
			(xy 301.250699 -377.029378) (xy 301.257716 -377.024138) (xy 301.280299 -377.006151) (xy 301.328804 -376.974835)
			(xy 301.35449 -376.961654) (xy 301.362424 -376.957243) (xy 301.374792 -376.943976) (xy 301.37862 -376.935746)
			(xy 301.390558 -376.907552) (xy 301.393577 -376.899163) (xy 301.394372 -376.881369) (xy 301.392082 -376.872754)
			(xy 301.383655 -376.844542) (xy 301.374594 -376.786368) (xy 301.374048 -376.75693) (xy 301.374534 -376.729679)
			(xy 301.38229 -376.675731) (xy 301.397645 -376.623436) (xy 301.420287 -376.573859) (xy 301.449753 -376.528009)
			(xy 301.485444 -376.486818) (xy 301.526635 -376.451127) (xy 301.572485 -376.421661) (xy 301.622062 -376.399019)
			(xy 301.674357 -376.383664) (xy 301.728305 -376.375908) (xy 301.782807 -376.375908) (xy 301.836755 -376.383664)
			(xy 301.88905 -376.399019) (xy 301.938627 -376.421661) (xy 301.984477 -376.451127) (xy 302.025668 -376.486818)
			(xy 302.061359 -376.528009) (xy 302.090825 -376.573859) (xy 302.113467 -376.623436) (xy 302.128822 -376.675731)
			(xy 302.136578 -376.729679) (xy 302.137064 -376.75693) (xy 302.136702 -376.781001) (xy 302.130665 -376.828764)
			(xy 302.118676 -376.87539) (xy 302.11014 -376.8979) (xy 302.10506 -376.910346) (xy 302.108362 -376.936254)
			(xy 302.175164 -377.026932) (xy 302.198786 -377.037854) (xy 302.211994 -377.036838) (xy 302.240696 -377.035822)
			(xy 302.267951 -377.036225) (xy 302.321907 -377.043982) (xy 302.374209 -377.059339) (xy 302.423794 -377.081983)
			(xy 302.469651 -377.111453) (xy 302.510848 -377.147149) (xy 302.546545 -377.188346) (xy 302.576015 -377.234203)
			(xy 302.59866 -377.283787) (xy 302.614017 -377.336089) (xy 302.621775 -377.390045) (xy 302.621775 -377.444549)
			(xy 306.482508 -377.444549) (xy 306.482508 -377.390051) (xy 306.490264 -377.336108) (xy 306.505618 -377.283818)
			(xy 306.528257 -377.234245) (xy 306.55772 -377.188398) (xy 306.593409 -377.147211) (xy 306.634595 -377.111523)
			(xy 306.680441 -377.082059) (xy 306.730014 -377.059419) (xy 306.782304 -377.044065) (xy 306.836247 -377.036308)
			(xy 306.863496 -377.035822) (xy 306.892198 -377.036838) (xy 306.905406 -377.037854) (xy 306.929028 -377.026932)
			(xy 306.99583 -376.936254) (xy 306.999132 -376.910346) (xy 306.994052 -376.8979) (xy 306.985517 -376.875389)
			(xy 306.973513 -376.828766) (xy 306.96748 -376.781002) (xy 306.967128 -376.75693) (xy 306.967614 -376.729679)
			(xy 306.97537 -376.675731) (xy 306.990725 -376.623436) (xy 307.013367 -376.573859) (xy 307.042833 -376.528009)
			(xy 307.078524 -376.486818) (xy 307.119715 -376.451127) (xy 307.165565 -376.421661) (xy 307.215142 -376.399019)
			(xy 307.267437 -376.383664) (xy 307.321385 -376.375908) (xy 307.375887 -376.375908) (xy 307.429835 -376.383664)
			(xy 307.48213 -376.399019) (xy 307.531707 -376.421661) (xy 307.577557 -376.451127) (xy 307.618748 -376.486818)
			(xy 307.654439 -376.528009) (xy 307.683905 -376.573859) (xy 307.706547 -376.623436) (xy 307.721902 -376.675731)
			(xy 307.729658 -376.729679) (xy 307.730144 -376.75693) (xy 307.72958 -376.786367) (xy 307.720525 -376.84454)
			(xy 307.71211 -376.872754) (xy 307.709745 -376.881363) (xy 307.710519 -376.899186) (xy 307.713634 -376.907552)
			(xy 307.725572 -376.935746) (xy 307.729388 -376.943983) (xy 307.741761 -376.957254) (xy 307.749702 -376.961654)
			(xy 307.775394 -376.974825) (xy 307.823901 -377.00614) (xy 307.846476 -377.024138) (xy 307.853479 -377.029403)
			(xy 307.869979 -377.035252) (xy 307.878734 -377.035568) (xy 308.032658 -377.035568) (xy 308.041408 -377.035237)
			(xy 308.057899 -377.029378) (xy 308.064916 -377.024138) (xy 308.087499 -377.006151) (xy 308.136004 -376.974835)
			(xy 308.16169 -376.961654) (xy 308.169624 -376.957243) (xy 308.181992 -376.943976) (xy 308.18582 -376.935746)
			(xy 308.197758 -376.907552) (xy 308.200777 -376.899163) (xy 308.201572 -376.881369) (xy 308.199282 -376.872754)
			(xy 308.190855 -376.844542) (xy 308.181794 -376.786368) (xy 308.181248 -376.75693) (xy 308.181734 -376.729679)
			(xy 308.18949 -376.675731) (xy 308.204845 -376.623436) (xy 308.227487 -376.573859) (xy 308.256953 -376.528009)
			(xy 308.292644 -376.486818) (xy 308.333835 -376.451127) (xy 308.379685 -376.421661) (xy 308.429262 -376.399019)
			(xy 308.481557 -376.383664) (xy 308.535505 -376.375908) (xy 308.590007 -376.375908) (xy 308.643955 -376.383664)
			(xy 308.69625 -376.399019) (xy 308.745827 -376.421661) (xy 308.791677 -376.451127) (xy 308.832868 -376.486818)
			(xy 308.868559 -376.528009) (xy 308.898025 -376.573859) (xy 308.920667 -376.623436) (xy 308.936022 -376.675731)
			(xy 308.943778 -376.729679) (xy 308.944264 -376.75693) (xy 308.943902 -376.781001) (xy 308.937865 -376.828764)
			(xy 308.925876 -376.87539) (xy 308.91734 -376.8979) (xy 308.91226 -376.910346) (xy 308.915562 -376.936254)
			(xy 308.982364 -377.026932) (xy 309.005986 -377.037854) (xy 309.019194 -377.036838) (xy 309.047896 -377.035822)
			(xy 309.075151 -377.036225) (xy 309.129107 -377.043982) (xy 309.181409 -377.059339) (xy 309.230994 -377.081983)
			(xy 309.276851 -377.111453) (xy 309.318048 -377.147149) (xy 309.353745 -377.188346) (xy 309.383215 -377.234203)
			(xy 309.40586 -377.283787) (xy 309.421217 -377.336089) (xy 309.428975 -377.390045) (xy 309.428975 -377.444549)
			(xy 313.289708 -377.444549) (xy 313.289708 -377.390051) (xy 313.297464 -377.336108) (xy 313.312818 -377.283818)
			(xy 313.335457 -377.234245) (xy 313.36492 -377.188398) (xy 313.400609 -377.147211) (xy 313.441795 -377.111523)
			(xy 313.487641 -377.082059) (xy 313.537214 -377.059419) (xy 313.589504 -377.044065) (xy 313.643447 -377.036308)
			(xy 313.670696 -377.035822) (xy 313.699398 -377.036838) (xy 313.712606 -377.037854) (xy 313.736228 -377.026932)
			(xy 313.80303 -376.936254) (xy 313.806332 -376.910346) (xy 313.801252 -376.8979) (xy 313.792717 -376.875389)
			(xy 313.780713 -376.828766) (xy 313.77468 -376.781002) (xy 313.774328 -376.75693) (xy 313.774814 -376.729679)
			(xy 313.78257 -376.675731) (xy 313.797925 -376.623436) (xy 313.820567 -376.573859) (xy 313.850033 -376.528009)
			(xy 313.885724 -376.486818) (xy 313.926915 -376.451127) (xy 313.972765 -376.421661) (xy 314.022342 -376.399019)
			(xy 314.074637 -376.383664) (xy 314.128585 -376.375908) (xy 314.183087 -376.375908) (xy 314.237035 -376.383664)
			(xy 314.28933 -376.399019) (xy 314.338907 -376.421661) (xy 314.384757 -376.451127) (xy 314.425948 -376.486818)
			(xy 314.461639 -376.528009) (xy 314.491105 -376.573859) (xy 314.513747 -376.623436) (xy 314.529102 -376.675731)
			(xy 314.536858 -376.729679) (xy 314.537344 -376.75693) (xy 314.53678 -376.786367) (xy 314.527725 -376.84454)
			(xy 314.51931 -376.872754) (xy 314.516945 -376.881363) (xy 314.517719 -376.899186) (xy 314.520834 -376.907552)
			(xy 314.532772 -376.935746) (xy 314.536588 -376.943983) (xy 314.548961 -376.957254) (xy 314.556902 -376.961654)
			(xy 314.582594 -376.974825) (xy 314.631101 -377.00614) (xy 314.653676 -377.024138) (xy 314.660679 -377.029403)
			(xy 314.677179 -377.035252) (xy 314.685934 -377.035568) (xy 314.839858 -377.035568) (xy 314.848608 -377.035237)
			(xy 314.865099 -377.029378) (xy 314.872116 -377.024138) (xy 314.894699 -377.006151) (xy 314.943204 -376.974835)
			(xy 314.96889 -376.961654) (xy 314.976824 -376.957243) (xy 314.989192 -376.943976) (xy 314.99302 -376.935746)
			(xy 315.004958 -376.907552) (xy 315.007977 -376.899163) (xy 315.008772 -376.881369) (xy 315.006482 -376.872754)
			(xy 314.998055 -376.844542) (xy 314.988994 -376.786368) (xy 314.988448 -376.75693) (xy 314.988934 -376.729679)
			(xy 314.99669 -376.675731) (xy 315.012045 -376.623436) (xy 315.034687 -376.573859) (xy 315.064153 -376.528009)
			(xy 315.099844 -376.486818) (xy 315.141035 -376.451127) (xy 315.186885 -376.421661) (xy 315.236462 -376.399019)
			(xy 315.288757 -376.383664) (xy 315.342705 -376.375908) (xy 315.397207 -376.375908) (xy 315.451155 -376.383664)
			(xy 315.50345 -376.399019) (xy 315.553027 -376.421661) (xy 315.598877 -376.451127) (xy 315.640068 -376.486818)
			(xy 315.675759 -376.528009) (xy 315.705225 -376.573859) (xy 315.727867 -376.623436) (xy 315.743222 -376.675731)
			(xy 315.750978 -376.729679) (xy 315.751464 -376.75693) (xy 315.751102 -376.781001) (xy 315.745065 -376.828764)
			(xy 315.733076 -376.87539) (xy 315.72454 -376.8979) (xy 315.71946 -376.910346) (xy 315.722762 -376.936254)
			(xy 315.789564 -377.026932) (xy 315.813186 -377.037854) (xy 315.826394 -377.036838) (xy 315.855096 -377.035822)
			(xy 315.882351 -377.036225) (xy 315.936307 -377.043982) (xy 315.988609 -377.059339) (xy 316.038194 -377.081983)
			(xy 316.084051 -377.111453) (xy 316.125248 -377.147149) (xy 316.160945 -377.188346) (xy 316.190415 -377.234203)
			(xy 316.21306 -377.283787) (xy 316.228417 -377.336089) (xy 316.236175 -377.390045) (xy 316.236175 -377.444549)
			(xy 320.096908 -377.444549) (xy 320.096908 -377.390051) (xy 320.104664 -377.336108) (xy 320.120018 -377.283818)
			(xy 320.142657 -377.234245) (xy 320.17212 -377.188398) (xy 320.207809 -377.147211) (xy 320.248995 -377.111523)
			(xy 320.294841 -377.082059) (xy 320.344414 -377.059419) (xy 320.396704 -377.044065) (xy 320.450647 -377.036308)
			(xy 320.477896 -377.035822) (xy 320.506598 -377.036838) (xy 320.519806 -377.037854) (xy 320.543428 -377.026932)
			(xy 320.61023 -376.936254) (xy 320.613532 -376.910346) (xy 320.608452 -376.8979) (xy 320.599917 -376.875389)
			(xy 320.587913 -376.828766) (xy 320.58188 -376.781002) (xy 320.581528 -376.75693) (xy 320.582014 -376.729679)
			(xy 320.58977 -376.675731) (xy 320.605125 -376.623436) (xy 320.627767 -376.573859) (xy 320.657233 -376.528009)
			(xy 320.692924 -376.486818) (xy 320.734115 -376.451127) (xy 320.779965 -376.421661) (xy 320.829542 -376.399019)
			(xy 320.881837 -376.383664) (xy 320.935785 -376.375908) (xy 320.990287 -376.375908) (xy 321.044235 -376.383664)
			(xy 321.09653 -376.399019) (xy 321.146107 -376.421661) (xy 321.191957 -376.451127) (xy 321.233148 -376.486818)
			(xy 321.268839 -376.528009) (xy 321.298305 -376.573859) (xy 321.320947 -376.623436) (xy 321.336302 -376.675731)
			(xy 321.344058 -376.729679) (xy 321.344544 -376.75693) (xy 321.34398 -376.786367) (xy 321.334925 -376.84454)
			(xy 321.32651 -376.872754) (xy 321.324145 -376.881363) (xy 321.324919 -376.899186) (xy 321.328034 -376.907552)
			(xy 321.339972 -376.935746) (xy 321.343788 -376.943983) (xy 321.356161 -376.957254) (xy 321.364102 -376.961654)
			(xy 321.389794 -376.974825) (xy 321.438301 -377.00614) (xy 321.460876 -377.024138) (xy 321.467879 -377.029403)
			(xy 321.484379 -377.035252) (xy 321.493134 -377.035568) (xy 321.647058 -377.035568) (xy 321.655808 -377.035237)
			(xy 321.672299 -377.029378) (xy 321.679316 -377.024138) (xy 321.701899 -377.006151) (xy 321.750404 -376.974835)
			(xy 321.77609 -376.961654) (xy 321.784024 -376.957243) (xy 321.796392 -376.943976) (xy 321.80022 -376.935746)
			(xy 321.812158 -376.907552) (xy 321.815177 -376.899163) (xy 321.815972 -376.881369) (xy 321.813682 -376.872754)
			(xy 321.805255 -376.844542) (xy 321.796194 -376.786368) (xy 321.795648 -376.75693) (xy 321.796134 -376.729679)
			(xy 321.80389 -376.675731) (xy 321.819245 -376.623436) (xy 321.841887 -376.573859) (xy 321.871353 -376.528009)
			(xy 321.907044 -376.486818) (xy 321.948235 -376.451127) (xy 321.994085 -376.421661) (xy 322.043662 -376.399019)
			(xy 322.095957 -376.383664) (xy 322.149905 -376.375908) (xy 322.204407 -376.375908) (xy 322.258355 -376.383664)
			(xy 322.31065 -376.399019) (xy 322.360227 -376.421661) (xy 322.406077 -376.451127) (xy 322.447268 -376.486818)
			(xy 322.482959 -376.528009) (xy 322.512425 -376.573859) (xy 322.535067 -376.623436) (xy 322.550422 -376.675731)
			(xy 322.558178 -376.729679) (xy 322.558664 -376.75693) (xy 322.558302 -376.781001) (xy 322.552265 -376.828764)
			(xy 322.540276 -376.87539) (xy 322.53174 -376.8979) (xy 322.52666 -376.910346) (xy 322.529962 -376.936254)
			(xy 322.596764 -377.026932) (xy 322.620386 -377.037854) (xy 322.633594 -377.036838) (xy 322.662296 -377.035822)
			(xy 322.689551 -377.036225) (xy 322.743507 -377.043982) (xy 322.795809 -377.059339) (xy 322.845394 -377.081983)
			(xy 322.891251 -377.111453) (xy 322.932448 -377.147149) (xy 322.968145 -377.188346) (xy 322.997615 -377.234203)
			(xy 323.02026 -377.283787) (xy 323.035617 -377.336089) (xy 323.043375 -377.390045) (xy 323.043375 -377.444549)
			(xy 323.500508 -377.444549) (xy 323.500508 -377.390051) (xy 323.508264 -377.336108) (xy 323.523618 -377.283818)
			(xy 323.546257 -377.234245) (xy 323.57572 -377.188398) (xy 323.611409 -377.147211) (xy 323.652595 -377.111523)
			(xy 323.698441 -377.082059) (xy 323.748014 -377.059419) (xy 323.800304 -377.044065) (xy 323.854247 -377.036308)
			(xy 323.881496 -377.035822) (xy 323.910198 -377.036838) (xy 323.923406 -377.037854) (xy 323.947028 -377.026932)
			(xy 324.01383 -376.936254) (xy 324.017132 -376.910346) (xy 324.012052 -376.8979) (xy 324.003517 -376.875389)
			(xy 323.991513 -376.828766) (xy 323.98548 -376.781002) (xy 323.985128 -376.75693) (xy 323.985614 -376.729679)
			(xy 323.99337 -376.675731) (xy 324.008725 -376.623436) (xy 324.031367 -376.573859) (xy 324.060833 -376.528009)
			(xy 324.096524 -376.486818) (xy 324.137715 -376.451127) (xy 324.183565 -376.421661) (xy 324.233142 -376.399019)
			(xy 324.285437 -376.383664) (xy 324.339385 -376.375908) (xy 324.393887 -376.375908) (xy 324.447835 -376.383664)
			(xy 324.50013 -376.399019) (xy 324.549707 -376.421661) (xy 324.595557 -376.451127) (xy 324.636748 -376.486818)
			(xy 324.672439 -376.528009) (xy 324.701905 -376.573859) (xy 324.724547 -376.623436) (xy 324.739902 -376.675731)
			(xy 324.747658 -376.729679) (xy 324.748144 -376.75693) (xy 324.74758 -376.786367) (xy 324.738525 -376.84454)
			(xy 324.73011 -376.872754) (xy 324.727745 -376.881363) (xy 324.728519 -376.899186) (xy 324.731634 -376.907552)
			(xy 324.743572 -376.935746) (xy 324.747388 -376.943983) (xy 324.759761 -376.957254) (xy 324.767702 -376.961654)
			(xy 324.793394 -376.974825) (xy 324.841901 -377.00614) (xy 324.864476 -377.024138) (xy 324.871479 -377.029403)
			(xy 324.887979 -377.035252) (xy 324.896734 -377.035568) (xy 325.050658 -377.035568) (xy 325.059408 -377.035237)
			(xy 325.075899 -377.029378) (xy 325.082916 -377.024138) (xy 325.105499 -377.006151) (xy 325.154004 -376.974835)
			(xy 325.17969 -376.961654) (xy 325.187624 -376.957243) (xy 325.199992 -376.943976) (xy 325.20382 -376.935746)
			(xy 325.215758 -376.907552) (xy 325.218777 -376.899163) (xy 325.219572 -376.881369) (xy 325.217282 -376.872754)
			(xy 325.208855 -376.844542) (xy 325.199794 -376.786368) (xy 325.199248 -376.75693) (xy 325.199734 -376.729679)
			(xy 325.20749 -376.675731) (xy 325.222845 -376.623436) (xy 325.245487 -376.573859) (xy 325.274953 -376.528009)
			(xy 325.310644 -376.486818) (xy 325.351835 -376.451127) (xy 325.397685 -376.421661) (xy 325.447262 -376.399019)
			(xy 325.499557 -376.383664) (xy 325.553505 -376.375908) (xy 325.608007 -376.375908) (xy 325.661955 -376.383664)
			(xy 325.71425 -376.399019) (xy 325.763827 -376.421661) (xy 325.809677 -376.451127) (xy 325.850868 -376.486818)
			(xy 325.886559 -376.528009) (xy 325.916025 -376.573859) (xy 325.938667 -376.623436) (xy 325.954022 -376.675731)
			(xy 325.961778 -376.729679) (xy 325.962264 -376.75693) (xy 325.961902 -376.781001) (xy 325.955865 -376.828764)
			(xy 325.943876 -376.87539) (xy 325.93534 -376.8979) (xy 325.93026 -376.910346) (xy 325.933562 -376.936254)
			(xy 326.000364 -377.026932) (xy 326.023986 -377.037854) (xy 326.037194 -377.036838) (xy 326.065896 -377.035822)
			(xy 326.093151 -377.036225) (xy 326.147107 -377.043982) (xy 326.199409 -377.059339) (xy 326.248994 -377.081983)
			(xy 326.294851 -377.111453) (xy 326.336048 -377.147149) (xy 326.371745 -377.188346) (xy 326.401215 -377.234203)
			(xy 326.42386 -377.283787) (xy 326.439217 -377.336089) (xy 326.446975 -377.390045) (xy 326.446975 -377.444555)
			(xy 326.439217 -377.498511) (xy 326.42386 -377.550813) (xy 326.401215 -377.600397) (xy 326.371745 -377.646254)
			(xy 326.336048 -377.687451) (xy 326.294851 -377.723147) (xy 326.248994 -377.752617) (xy 326.199409 -377.775261)
			(xy 326.147107 -377.790618) (xy 326.093151 -377.798375) (xy 326.065896 -377.798838) (xy 326.037194 -377.797822)
			(xy 326.023986 -377.796806) (xy 326.000364 -377.807728) (xy 325.933562 -377.898406) (xy 325.93026 -377.924314)
			(xy 325.93534 -377.93676) (xy 325.943892 -377.959265) (xy 325.95589 -378.005891) (xy 325.961916 -378.053657)
			(xy 325.962264 -378.07773) (xy 325.961778 -378.104981) (xy 325.954022 -378.158929) (xy 325.938667 -378.211224)
			(xy 325.916025 -378.260801) (xy 325.886559 -378.306651) (xy 325.850868 -378.347842) (xy 325.809677 -378.383533)
			(xy 325.763827 -378.412999) (xy 325.71425 -378.435641) (xy 325.661955 -378.450996) (xy 325.608007 -378.458752)
			(xy 325.553505 -378.458752) (xy 325.499557 -378.450996) (xy 325.447262 -378.435641) (xy 325.397685 -378.412999)
			(xy 325.351835 -378.383533) (xy 325.310644 -378.347842) (xy 325.274953 -378.306651) (xy 325.245487 -378.260801)
			(xy 325.222845 -378.211224) (xy 325.20749 -378.158929) (xy 325.199734 -378.104981) (xy 325.199248 -378.07773)
			(xy 325.199803 -378.048293) (xy 325.208864 -377.990119) (xy 325.217282 -377.961906) (xy 325.219662 -377.953301)
			(xy 325.218876 -377.935475) (xy 325.215758 -377.927108) (xy 325.20382 -377.898914) (xy 325.199987 -377.890686)
			(xy 325.187627 -377.877409) (xy 325.17969 -377.873006) (xy 325.153995 -377.859839) (xy 325.10549 -377.828521)
			(xy 325.082916 -377.810522) (xy 325.075918 -377.805249) (xy 325.059414 -377.799406) (xy 325.050658 -377.799092)
			(xy 324.896734 -377.799092) (xy 324.887984 -377.799428) (xy 324.871493 -377.805284) (xy 324.864476 -377.810522)
			(xy 324.841898 -377.828515) (xy 324.79339 -377.859827) (xy 324.767702 -377.873006) (xy 324.759753 -377.877394)
			(xy 324.747392 -377.890677) (xy 324.743572 -377.898914) (xy 324.731634 -377.927108) (xy 324.728585 -377.935488)
			(xy 324.72781 -377.95329) (xy 324.73011 -377.961906) (xy 324.738552 -377.990113) (xy 324.747603 -378.048291)
			(xy 324.748144 -378.07773) (xy 324.747658 -378.104981) (xy 324.739902 -378.158929) (xy 324.724547 -378.211224)
			(xy 324.701905 -378.260801) (xy 324.672439 -378.306651) (xy 324.636748 -378.347842) (xy 324.595557 -378.383533)
			(xy 324.549707 -378.412999) (xy 324.50013 -378.435641) (xy 324.447835 -378.450996) (xy 324.393887 -378.458752)
			(xy 324.339385 -378.458752) (xy 324.285437 -378.450996) (xy 324.233142 -378.435641) (xy 324.183565 -378.412999)
			(xy 324.137715 -378.383533) (xy 324.096524 -378.347842) (xy 324.060833 -378.306651) (xy 324.031367 -378.260801)
			(xy 324.008725 -378.211224) (xy 323.99337 -378.158929) (xy 323.985614 -378.104981) (xy 323.985128 -378.07773)
			(xy 323.985478 -378.053658) (xy 323.99152 -378.005895) (xy 324.003514 -377.95927) (xy 324.012052 -377.93676)
			(xy 324.017132 -377.924314) (xy 324.01383 -377.898406) (xy 323.947028 -377.807728) (xy 323.923406 -377.796806)
			(xy 323.910198 -377.797822) (xy 323.881496 -377.798838) (xy 323.854247 -377.798292) (xy 323.800304 -377.790535)
			(xy 323.748014 -377.775181) (xy 323.698441 -377.752541) (xy 323.652595 -377.723077) (xy 323.611409 -377.687389)
			(xy 323.57572 -377.646202) (xy 323.546257 -377.600355) (xy 323.523618 -377.550782) (xy 323.508264 -377.498492)
			(xy 323.500508 -377.444549) (xy 323.043375 -377.444549) (xy 323.043375 -377.444555) (xy 323.035617 -377.498511)
			(xy 323.02026 -377.550813) (xy 322.997615 -377.600397) (xy 322.968145 -377.646254) (xy 322.932448 -377.687451)
			(xy 322.891251 -377.723147) (xy 322.845394 -377.752617) (xy 322.795809 -377.775261) (xy 322.743507 -377.790618)
			(xy 322.689551 -377.798375) (xy 322.662296 -377.798838) (xy 322.633594 -377.797822) (xy 322.620386 -377.796806)
			(xy 322.596764 -377.807728) (xy 322.529962 -377.898406) (xy 322.52666 -377.924314) (xy 322.53174 -377.93676)
			(xy 322.540292 -377.959265) (xy 322.55229 -378.005891) (xy 322.558316 -378.053657) (xy 322.558664 -378.07773)
			(xy 322.558178 -378.104981) (xy 322.550422 -378.158929) (xy 322.535067 -378.211224) (xy 322.512425 -378.260801)
			(xy 322.482959 -378.306651) (xy 322.447268 -378.347842) (xy 322.406077 -378.383533) (xy 322.360227 -378.412999)
			(xy 322.31065 -378.435641) (xy 322.258355 -378.450996) (xy 322.204407 -378.458752) (xy 322.149905 -378.458752)
			(xy 322.095957 -378.450996) (xy 322.043662 -378.435641) (xy 321.994085 -378.412999) (xy 321.948235 -378.383533)
			(xy 321.907044 -378.347842) (xy 321.871353 -378.306651) (xy 321.841887 -378.260801) (xy 321.819245 -378.211224)
			(xy 321.80389 -378.158929) (xy 321.796134 -378.104981) (xy 321.795648 -378.07773) (xy 321.796203 -378.048293)
			(xy 321.805264 -377.990119) (xy 321.813682 -377.961906) (xy 321.816062 -377.953301) (xy 321.815276 -377.935475)
			(xy 321.812158 -377.927108) (xy 321.80022 -377.898914) (xy 321.796387 -377.890686) (xy 321.784027 -377.877409)
			(xy 321.77609 -377.873006) (xy 321.750395 -377.859839) (xy 321.70189 -377.828521) (xy 321.679316 -377.810522)
			(xy 321.672318 -377.805249) (xy 321.655814 -377.799406) (xy 321.647058 -377.799092) (xy 321.493134 -377.799092)
			(xy 321.484384 -377.799428) (xy 321.467893 -377.805284) (xy 321.460876 -377.810522) (xy 321.438298 -377.828515)
			(xy 321.38979 -377.859827) (xy 321.364102 -377.873006) (xy 321.356153 -377.877394) (xy 321.343792 -377.890677)
			(xy 321.339972 -377.898914) (xy 321.328034 -377.927108) (xy 321.324985 -377.935488) (xy 321.32421 -377.95329)
			(xy 321.32651 -377.961906) (xy 321.334952 -377.990113) (xy 321.344003 -378.048291) (xy 321.344544 -378.07773)
			(xy 321.344058 -378.104981) (xy 321.336302 -378.158929) (xy 321.320947 -378.211224) (xy 321.298305 -378.260801)
			(xy 321.268839 -378.306651) (xy 321.233148 -378.347842) (xy 321.191957 -378.383533) (xy 321.146107 -378.412999)
			(xy 321.09653 -378.435641) (xy 321.044235 -378.450996) (xy 320.990287 -378.458752) (xy 320.935785 -378.458752)
			(xy 320.881837 -378.450996) (xy 320.829542 -378.435641) (xy 320.779965 -378.412999) (xy 320.734115 -378.383533)
			(xy 320.692924 -378.347842) (xy 320.657233 -378.306651) (xy 320.627767 -378.260801) (xy 320.605125 -378.211224)
			(xy 320.58977 -378.158929) (xy 320.582014 -378.104981) (xy 320.581528 -378.07773) (xy 320.581878 -378.053658)
			(xy 320.58792 -378.005895) (xy 320.599914 -377.95927) (xy 320.608452 -377.93676) (xy 320.613532 -377.924314)
			(xy 320.61023 -377.898406) (xy 320.543428 -377.807728) (xy 320.519806 -377.796806) (xy 320.506598 -377.797822)
			(xy 320.477896 -377.798838) (xy 320.450647 -377.798292) (xy 320.396704 -377.790535) (xy 320.344414 -377.775181)
			(xy 320.294841 -377.752541) (xy 320.248995 -377.723077) (xy 320.207809 -377.687389) (xy 320.17212 -377.646202)
			(xy 320.142657 -377.600355) (xy 320.120018 -377.550782) (xy 320.104664 -377.498492) (xy 320.096908 -377.444549)
			(xy 316.236175 -377.444549) (xy 316.236175 -377.444555) (xy 316.228417 -377.498511) (xy 316.21306 -377.550813)
			(xy 316.190415 -377.600397) (xy 316.160945 -377.646254) (xy 316.125248 -377.687451) (xy 316.084051 -377.723147)
			(xy 316.038194 -377.752617) (xy 315.988609 -377.775261) (xy 315.936307 -377.790618) (xy 315.882351 -377.798375)
			(xy 315.855096 -377.798838) (xy 315.826394 -377.797822) (xy 315.813186 -377.796806) (xy 315.789564 -377.807728)
			(xy 315.722762 -377.898406) (xy 315.71946 -377.924314) (xy 315.72454 -377.93676) (xy 315.733092 -377.959265)
			(xy 315.74509 -378.005891) (xy 315.751116 -378.053657) (xy 315.751464 -378.07773) (xy 315.750978 -378.104981)
			(xy 315.743222 -378.158929) (xy 315.727867 -378.211224) (xy 315.705225 -378.260801) (xy 315.675759 -378.306651)
			(xy 315.640068 -378.347842) (xy 315.598877 -378.383533) (xy 315.553027 -378.412999) (xy 315.50345 -378.435641)
			(xy 315.451155 -378.450996) (xy 315.397207 -378.458752) (xy 315.342705 -378.458752) (xy 315.288757 -378.450996)
			(xy 315.236462 -378.435641) (xy 315.186885 -378.412999) (xy 315.141035 -378.383533) (xy 315.099844 -378.347842)
			(xy 315.064153 -378.306651) (xy 315.034687 -378.260801) (xy 315.012045 -378.211224) (xy 314.99669 -378.158929)
			(xy 314.988934 -378.104981) (xy 314.988448 -378.07773) (xy 314.989003 -378.048293) (xy 314.998064 -377.990119)
			(xy 315.006482 -377.961906) (xy 315.008862 -377.953301) (xy 315.008076 -377.935475) (xy 315.004958 -377.927108)
			(xy 314.99302 -377.898914) (xy 314.989187 -377.890686) (xy 314.976827 -377.877409) (xy 314.96889 -377.873006)
			(xy 314.943195 -377.859839) (xy 314.89469 -377.828521) (xy 314.872116 -377.810522) (xy 314.865118 -377.805249)
			(xy 314.848614 -377.799406) (xy 314.839858 -377.799092) (xy 314.685934 -377.799092) (xy 314.677184 -377.799428)
			(xy 314.660693 -377.805284) (xy 314.653676 -377.810522) (xy 314.631098 -377.828515) (xy 314.58259 -377.859827)
			(xy 314.556902 -377.873006) (xy 314.548953 -377.877394) (xy 314.536592 -377.890677) (xy 314.532772 -377.898914)
			(xy 314.520834 -377.927108) (xy 314.517785 -377.935488) (xy 314.51701 -377.95329) (xy 314.51931 -377.961906)
			(xy 314.527752 -377.990113) (xy 314.536803 -378.048291) (xy 314.537344 -378.07773) (xy 314.536858 -378.104981)
			(xy 314.529102 -378.158929) (xy 314.513747 -378.211224) (xy 314.491105 -378.260801) (xy 314.461639 -378.306651)
			(xy 314.425948 -378.347842) (xy 314.384757 -378.383533) (xy 314.338907 -378.412999) (xy 314.28933 -378.435641)
			(xy 314.237035 -378.450996) (xy 314.183087 -378.458752) (xy 314.128585 -378.458752) (xy 314.074637 -378.450996)
			(xy 314.022342 -378.435641) (xy 313.972765 -378.412999) (xy 313.926915 -378.383533) (xy 313.885724 -378.347842)
			(xy 313.850033 -378.306651) (xy 313.820567 -378.260801) (xy 313.797925 -378.211224) (xy 313.78257 -378.158929)
			(xy 313.774814 -378.104981) (xy 313.774328 -378.07773) (xy 313.774678 -378.053658) (xy 313.78072 -378.005895)
			(xy 313.792714 -377.95927) (xy 313.801252 -377.93676) (xy 313.806332 -377.924314) (xy 313.80303 -377.898406)
			(xy 313.736228 -377.807728) (xy 313.712606 -377.796806) (xy 313.699398 -377.797822) (xy 313.670696 -377.798838)
			(xy 313.643447 -377.798292) (xy 313.589504 -377.790535) (xy 313.537214 -377.775181) (xy 313.487641 -377.752541)
			(xy 313.441795 -377.723077) (xy 313.400609 -377.687389) (xy 313.36492 -377.646202) (xy 313.335457 -377.600355)
			(xy 313.312818 -377.550782) (xy 313.297464 -377.498492) (xy 313.289708 -377.444549) (xy 309.428975 -377.444549)
			(xy 309.428975 -377.444555) (xy 309.421217 -377.498511) (xy 309.40586 -377.550813) (xy 309.383215 -377.600397)
			(xy 309.353745 -377.646254) (xy 309.318048 -377.687451) (xy 309.276851 -377.723147) (xy 309.230994 -377.752617)
			(xy 309.181409 -377.775261) (xy 309.129107 -377.790618) (xy 309.075151 -377.798375) (xy 309.047896 -377.798838)
			(xy 309.019194 -377.797822) (xy 309.005986 -377.796806) (xy 308.982364 -377.807728) (xy 308.915562 -377.898406)
			(xy 308.91226 -377.924314) (xy 308.91734 -377.93676) (xy 308.925892 -377.959265) (xy 308.93789 -378.005891)
			(xy 308.943916 -378.053657) (xy 308.944264 -378.07773) (xy 308.943778 -378.104981) (xy 308.936022 -378.158929)
			(xy 308.920667 -378.211224) (xy 308.898025 -378.260801) (xy 308.868559 -378.306651) (xy 308.832868 -378.347842)
			(xy 308.791677 -378.383533) (xy 308.745827 -378.412999) (xy 308.69625 -378.435641) (xy 308.643955 -378.450996)
			(xy 308.590007 -378.458752) (xy 308.535505 -378.458752) (xy 308.481557 -378.450996) (xy 308.429262 -378.435641)
			(xy 308.379685 -378.412999) (xy 308.333835 -378.383533) (xy 308.292644 -378.347842) (xy 308.256953 -378.306651)
			(xy 308.227487 -378.260801) (xy 308.204845 -378.211224) (xy 308.18949 -378.158929) (xy 308.181734 -378.104981)
			(xy 308.181248 -378.07773) (xy 308.181803 -378.048293) (xy 308.190864 -377.990119) (xy 308.199282 -377.961906)
			(xy 308.201662 -377.953301) (xy 308.200876 -377.935475) (xy 308.197758 -377.927108) (xy 308.18582 -377.898914)
			(xy 308.181987 -377.890686) (xy 308.169627 -377.877409) (xy 308.16169 -377.873006) (xy 308.135995 -377.859839)
			(xy 308.08749 -377.828521) (xy 308.064916 -377.810522) (xy 308.057918 -377.805249) (xy 308.041414 -377.799406)
			(xy 308.032658 -377.799092) (xy 307.878734 -377.799092) (xy 307.869984 -377.799428) (xy 307.853493 -377.805284)
			(xy 307.846476 -377.810522) (xy 307.823898 -377.828515) (xy 307.77539 -377.859827) (xy 307.749702 -377.873006)
			(xy 307.741753 -377.877394) (xy 307.729392 -377.890677) (xy 307.725572 -377.898914) (xy 307.713634 -377.927108)
			(xy 307.710585 -377.935488) (xy 307.70981 -377.95329) (xy 307.71211 -377.961906) (xy 307.720552 -377.990113)
			(xy 307.729603 -378.048291) (xy 307.730144 -378.07773) (xy 307.729658 -378.104981) (xy 307.721902 -378.158929)
			(xy 307.706547 -378.211224) (xy 307.683905 -378.260801) (xy 307.654439 -378.306651) (xy 307.618748 -378.347842)
			(xy 307.577557 -378.383533) (xy 307.531707 -378.412999) (xy 307.48213 -378.435641) (xy 307.429835 -378.450996)
			(xy 307.375887 -378.458752) (xy 307.321385 -378.458752) (xy 307.267437 -378.450996) (xy 307.215142 -378.435641)
			(xy 307.165565 -378.412999) (xy 307.119715 -378.383533) (xy 307.078524 -378.347842) (xy 307.042833 -378.306651)
			(xy 307.013367 -378.260801) (xy 306.990725 -378.211224) (xy 306.97537 -378.158929) (xy 306.967614 -378.104981)
			(xy 306.967128 -378.07773) (xy 306.967478 -378.053658) (xy 306.97352 -378.005895) (xy 306.985514 -377.95927)
			(xy 306.994052 -377.93676) (xy 306.999132 -377.924314) (xy 306.99583 -377.898406) (xy 306.929028 -377.807728)
			(xy 306.905406 -377.796806) (xy 306.892198 -377.797822) (xy 306.863496 -377.798838) (xy 306.836247 -377.798292)
			(xy 306.782304 -377.790535) (xy 306.730014 -377.775181) (xy 306.680441 -377.752541) (xy 306.634595 -377.723077)
			(xy 306.593409 -377.687389) (xy 306.55772 -377.646202) (xy 306.528257 -377.600355) (xy 306.505618 -377.550782)
			(xy 306.490264 -377.498492) (xy 306.482508 -377.444549) (xy 302.621775 -377.444549) (xy 302.621775 -377.444555)
			(xy 302.614017 -377.498511) (xy 302.59866 -377.550813) (xy 302.576015 -377.600397) (xy 302.546545 -377.646254)
			(xy 302.510848 -377.687451) (xy 302.469651 -377.723147) (xy 302.423794 -377.752617) (xy 302.374209 -377.775261)
			(xy 302.321907 -377.790618) (xy 302.267951 -377.798375) (xy 302.240696 -377.798838) (xy 302.211994 -377.797822)
			(xy 302.198786 -377.796806) (xy 302.175164 -377.807728) (xy 302.108362 -377.898406) (xy 302.10506 -377.924314)
			(xy 302.11014 -377.93676) (xy 302.118692 -377.959265) (xy 302.13069 -378.005891) (xy 302.136716 -378.053657)
			(xy 302.137064 -378.07773) (xy 302.136578 -378.104981) (xy 302.128822 -378.158929) (xy 302.113467 -378.211224)
			(xy 302.090825 -378.260801) (xy 302.061359 -378.306651) (xy 302.025668 -378.347842) (xy 301.984477 -378.383533)
			(xy 301.938627 -378.412999) (xy 301.88905 -378.435641) (xy 301.836755 -378.450996) (xy 301.782807 -378.458752)
			(xy 301.728305 -378.458752) (xy 301.674357 -378.450996) (xy 301.622062 -378.435641) (xy 301.572485 -378.412999)
			(xy 301.526635 -378.383533) (xy 301.485444 -378.347842) (xy 301.449753 -378.306651) (xy 301.420287 -378.260801)
			(xy 301.397645 -378.211224) (xy 301.38229 -378.158929) (xy 301.374534 -378.104981) (xy 301.374048 -378.07773)
			(xy 301.374603 -378.048293) (xy 301.383664 -377.990119) (xy 301.392082 -377.961906) (xy 301.394462 -377.953301)
			(xy 301.393676 -377.935475) (xy 301.390558 -377.927108) (xy 301.37862 -377.898914) (xy 301.374787 -377.890686)
			(xy 301.362427 -377.877409) (xy 301.35449 -377.873006) (xy 301.328795 -377.859839) (xy 301.28029 -377.828521)
			(xy 301.257716 -377.810522) (xy 301.250718 -377.805249) (xy 301.234214 -377.799406) (xy 301.225458 -377.799092)
			(xy 301.071534 -377.799092) (xy 301.062784 -377.799428) (xy 301.046293 -377.805284) (xy 301.039276 -377.810522)
			(xy 301.016698 -377.828515) (xy 300.96819 -377.859827) (xy 300.942502 -377.873006) (xy 300.934553 -377.877394)
			(xy 300.922192 -377.890677) (xy 300.918372 -377.898914) (xy 300.906434 -377.927108) (xy 300.903385 -377.935488)
			(xy 300.90261 -377.95329) (xy 300.90491 -377.961906) (xy 300.913352 -377.990113) (xy 300.922403 -378.048291)
			(xy 300.922944 -378.07773) (xy 300.922458 -378.104981) (xy 300.914702 -378.158929) (xy 300.899347 -378.211224)
			(xy 300.876705 -378.260801) (xy 300.847239 -378.306651) (xy 300.811548 -378.347842) (xy 300.770357 -378.383533)
			(xy 300.724507 -378.412999) (xy 300.67493 -378.435641) (xy 300.622635 -378.450996) (xy 300.568687 -378.458752)
			(xy 300.514185 -378.458752) (xy 300.460237 -378.450996) (xy 300.407942 -378.435641) (xy 300.358365 -378.412999)
			(xy 300.312515 -378.383533) (xy 300.271324 -378.347842) (xy 300.235633 -378.306651) (xy 300.206167 -378.260801)
			(xy 300.183525 -378.211224) (xy 300.16817 -378.158929) (xy 300.160414 -378.104981) (xy 300.159928 -378.07773)
			(xy 300.160278 -378.053658) (xy 300.16632 -378.005895) (xy 300.178314 -377.95927) (xy 300.186852 -377.93676)
			(xy 300.191932 -377.924314) (xy 300.18863 -377.898406) (xy 300.121828 -377.807728) (xy 300.098206 -377.796806)
			(xy 300.084998 -377.797822) (xy 300.056296 -377.798838) (xy 300.029047 -377.798292) (xy 299.975104 -377.790535)
			(xy 299.922814 -377.775181) (xy 299.873241 -377.752541) (xy 299.827395 -377.723077) (xy 299.786209 -377.687389)
			(xy 299.75052 -377.646202) (xy 299.721057 -377.600355) (xy 299.698418 -377.550782) (xy 299.683064 -377.498492)
			(xy 299.675308 -377.444549) (xy 287.886448 -377.444549) (xy 287.880896 -377.451176) (xy 287.877504 -377.460002)
			(xy 287.86702 -377.489952) (xy 287.839538 -377.54715) (xy 287.805151 -377.600483) (xy 287.764393 -377.649122)
			(xy 287.717898 -377.692309) (xy 287.66639 -377.729374) (xy 287.610669 -377.759739) (xy 287.551602 -377.782934)
			(xy 287.490107 -377.798597) (xy 287.427141 -377.806484) (xy 287.395412 -377.806966) (xy 287.363447 -377.80657)
			(xy 287.30002 -377.798558) (xy 287.238097 -377.782661) (xy 287.178655 -377.759127) (xy 287.122631 -377.728329)
			(xy 287.07091 -377.690752) (xy 287.024305 -377.646989) (xy 286.983554 -377.59773) (xy 286.949297 -377.543751)
			(xy 286.922076 -377.485905) (xy 286.90232 -377.425103) (xy 286.890341 -377.362305) (xy 286.886326 -377.2985)
			(xy 286.713559 -377.2985) (xy 286.708771 -377.310987) (xy 286.679653 -377.365828) (xy 286.644078 -377.416718)
			(xy 286.602574 -377.462901) (xy 286.55576 -377.503691) (xy 286.50433 -377.538481) (xy 286.449048 -377.566754)
			(xy 286.420052 -377.577858) (xy 286.411568 -377.581296) (xy 286.397638 -377.593154) (xy 286.392874 -377.600972)
			(xy 286.378142 -377.627642) (xy 286.374053 -377.63583) (xy 286.371462 -377.653936) (xy 286.373062 -377.662948)
			(xy 286.378641 -377.689908) (xy 286.384627 -377.744639) (xy 286.385 -377.772168) (xy 286.384448 -377.805507)
			(xy 286.375731 -377.871613) (xy 286.358455 -377.936014) (xy 286.332916 -377.997607) (xy 286.299551 -378.055337)
			(xy 286.258932 -378.108215) (xy 286.211756 -378.155336) (xy 286.18561 -378.176028) (xy 286.178764 -378.181672)
			(xy 286.169161 -378.196579) (xy 286.165226 -378.213868) (xy 286.167432 -378.231462) (xy 286.171132 -378.239528)
			(xy 286.18438 -378.266453) (xy 286.205208 -378.322731) (xy 286.219253 -378.381073) (xy 286.226322 -378.440664)
			(xy 286.226758 -378.470668) (xy 286.226256 -378.502629) (xy 286.218245 -378.566047) (xy 286.202348 -378.627961)
			(xy 286.178816 -378.687394) (xy 286.148022 -378.743409) (xy 286.110449 -378.795124) (xy 286.066692 -378.841721)
			(xy 286.017439 -378.882466) (xy 285.963468 -378.916717) (xy 285.905629 -378.943934) (xy 285.844836 -378.963687)
			(xy 285.782046 -378.975665) (xy 285.71825 -378.979679) (xy 285.654454 -378.975665) (xy 285.591664 -378.963687)
			(xy 285.530871 -378.943934) (xy 285.473032 -378.916717) (xy 285.419061 -378.882466) (xy 285.369808 -378.841721)
			(xy 285.326051 -378.795124) (xy 285.288478 -378.743409) (xy 285.257684 -378.687394) (xy 285.234152 -378.627961)
			(xy 285.218255 -378.566047) (xy 285.210244 -378.502629) (xy 285.209742 -378.470668) (xy 278.86152 -378.470668)
			(xy 278.86152 -380.063205) (xy 279.462986 -380.063205) (xy 279.462986 -379.999283) (xy 279.470997 -379.935865)
			(xy 279.486894 -379.873951) (xy 279.510426 -379.814518) (xy 279.54122 -379.758503) (xy 279.578793 -379.706788)
			(xy 279.62255 -379.660191) (xy 279.671803 -379.619446) (xy 279.725774 -379.585195) (xy 279.783613 -379.557978)
			(xy 279.844406 -379.538225) (xy 279.907196 -379.526247) (xy 279.970992 -379.522234) (xy 280.034788 -379.526247)
			(xy 280.097578 -379.538225) (xy 280.158371 -379.557978) (xy 280.21621 -379.585195) (xy 280.270181 -379.619446)
			(xy 280.319434 -379.660191) (xy 280.363191 -379.706788) (xy 280.400764 -379.758503) (xy 280.431558 -379.814518)
			(xy 280.45509 -379.873951) (xy 280.463922 -379.908349) (xy 297.973508 -379.908349) (xy 297.973508 -379.853851)
			(xy 297.981264 -379.799908) (xy 297.996618 -379.747618) (xy 298.019257 -379.698045) (xy 298.04872 -379.652198)
			(xy 298.084409 -379.611011) (xy 298.125595 -379.575323) (xy 298.171441 -379.545859) (xy 298.221014 -379.523219)
			(xy 298.273304 -379.507865) (xy 298.327247 -379.500108) (xy 298.354496 -379.499622) (xy 298.383198 -379.500638)
			(xy 298.396406 -379.501654) (xy 298.420028 -379.490732) (xy 298.48683 -379.400054) (xy 298.490132 -379.374146)
			(xy 298.485052 -379.3617) (xy 298.476517 -379.339189) (xy 298.464513 -379.292566) (xy 298.45848 -379.244802)
			(xy 298.458128 -379.22073) (xy 298.458614 -379.193479) (xy 298.46637 -379.139531) (xy 298.481725 -379.087236)
			(xy 298.504367 -379.037659) (xy 298.533833 -378.991809) (xy 298.569524 -378.950618) (xy 298.610715 -378.914927)
			(xy 298.656565 -378.885461) (xy 298.706142 -378.862819) (xy 298.758437 -378.847464) (xy 298.812385 -378.839708)
			(xy 298.866887 -378.839708) (xy 298.920835 -378.847464) (xy 298.97313 -378.862819) (xy 299.022707 -378.885461)
			(xy 299.068557 -378.914927) (xy 299.109748 -378.950618) (xy 299.145439 -378.991809) (xy 299.174905 -379.037659)
			(xy 299.197547 -379.087236) (xy 299.212902 -379.139531) (xy 299.220658 -379.193479) (xy 299.221144 -379.22073)
			(xy 299.22058 -379.250167) (xy 299.211525 -379.30834) (xy 299.20311 -379.336554) (xy 299.200745 -379.345163)
			(xy 299.201519 -379.362986) (xy 299.204634 -379.371352) (xy 299.216572 -379.399546) (xy 299.220388 -379.407783)
			(xy 299.232761 -379.421054) (xy 299.240702 -379.425454) (xy 299.266394 -379.438625) (xy 299.314901 -379.46994)
			(xy 299.337476 -379.487938) (xy 299.344479 -379.493203) (xy 299.360979 -379.499052) (xy 299.369734 -379.499368)
			(xy 299.523658 -379.499368) (xy 299.532408 -379.499037) (xy 299.548899 -379.493178) (xy 299.555916 -379.487938)
			(xy 299.578499 -379.469951) (xy 299.627004 -379.438635) (xy 299.65269 -379.425454) (xy 299.660624 -379.421043)
			(xy 299.672992 -379.407776) (xy 299.67682 -379.399546) (xy 299.688758 -379.371352) (xy 299.691777 -379.362963)
			(xy 299.692572 -379.345169) (xy 299.690282 -379.336554) (xy 299.681855 -379.308342) (xy 299.672794 -379.250168)
			(xy 299.672248 -379.22073) (xy 299.672734 -379.193479) (xy 299.68049 -379.139531) (xy 299.695845 -379.087236)
			(xy 299.718487 -379.037659) (xy 299.747953 -378.991809) (xy 299.783644 -378.950618) (xy 299.824835 -378.914927)
			(xy 299.870685 -378.885461) (xy 299.920262 -378.862819) (xy 299.972557 -378.847464) (xy 300.026505 -378.839708)
			(xy 300.081007 -378.839708) (xy 300.134955 -378.847464) (xy 300.18725 -378.862819) (xy 300.236827 -378.885461)
			(xy 300.282677 -378.914927) (xy 300.323868 -378.950618) (xy 300.359559 -378.991809) (xy 300.389025 -379.037659)
			(xy 300.411667 -379.087236) (xy 300.427022 -379.139531) (xy 300.434778 -379.193479) (xy 300.435264 -379.22073)
			(xy 300.434902 -379.244801) (xy 300.428865 -379.292564) (xy 300.416876 -379.33919) (xy 300.40834 -379.3617)
			(xy 300.40326 -379.374146) (xy 300.406562 -379.400054) (xy 300.473364 -379.490732) (xy 300.496986 -379.501654)
			(xy 300.510194 -379.500638) (xy 300.538896 -379.499622) (xy 300.566151 -379.500025) (xy 300.620107 -379.507782)
			(xy 300.672409 -379.523139) (xy 300.721994 -379.545783) (xy 300.767851 -379.575253) (xy 300.809048 -379.610949)
			(xy 300.844745 -379.652146) (xy 300.874215 -379.698003) (xy 300.89686 -379.747587) (xy 300.912217 -379.799889)
			(xy 300.919975 -379.853845) (xy 300.919975 -379.908349) (xy 304.780708 -379.908349) (xy 304.780708 -379.853851)
			(xy 304.788464 -379.799908) (xy 304.803818 -379.747618) (xy 304.826457 -379.698045) (xy 304.85592 -379.652198)
			(xy 304.891609 -379.611011) (xy 304.932795 -379.575323) (xy 304.978641 -379.545859) (xy 305.028214 -379.523219)
			(xy 305.080504 -379.507865) (xy 305.134447 -379.500108) (xy 305.161696 -379.499622) (xy 305.190398 -379.500638)
			(xy 305.203606 -379.501654) (xy 305.227228 -379.490732) (xy 305.29403 -379.400054) (xy 305.297332 -379.374146)
			(xy 305.292252 -379.3617) (xy 305.283717 -379.339189) (xy 305.271713 -379.292566) (xy 305.26568 -379.244802)
			(xy 305.265328 -379.22073) (xy 305.265814 -379.193479) (xy 305.27357 -379.139531) (xy 305.288925 -379.087236)
			(xy 305.311567 -379.037659) (xy 305.341033 -378.991809) (xy 305.376724 -378.950618) (xy 305.417915 -378.914927)
			(xy 305.463765 -378.885461) (xy 305.513342 -378.862819) (xy 305.565637 -378.847464) (xy 305.619585 -378.839708)
			(xy 305.674087 -378.839708) (xy 305.728035 -378.847464) (xy 305.78033 -378.862819) (xy 305.829907 -378.885461)
			(xy 305.875757 -378.914927) (xy 305.916948 -378.950618) (xy 305.952639 -378.991809) (xy 305.982105 -379.037659)
			(xy 306.004747 -379.087236) (xy 306.020102 -379.139531) (xy 306.027858 -379.193479) (xy 306.028344 -379.22073)
			(xy 306.02778 -379.250167) (xy 306.018725 -379.30834) (xy 306.01031 -379.336554) (xy 306.007945 -379.345163)
			(xy 306.008719 -379.362986) (xy 306.011834 -379.371352) (xy 306.023772 -379.399546) (xy 306.027588 -379.407783)
			(xy 306.039961 -379.421054) (xy 306.047902 -379.425454) (xy 306.073594 -379.438625) (xy 306.122101 -379.46994)
			(xy 306.144676 -379.487938) (xy 306.151679 -379.493203) (xy 306.168179 -379.499052) (xy 306.176934 -379.499368)
			(xy 306.330858 -379.499368) (xy 306.339608 -379.499037) (xy 306.356099 -379.493178) (xy 306.363116 -379.487938)
			(xy 306.385699 -379.469951) (xy 306.434204 -379.438635) (xy 306.45989 -379.425454) (xy 306.467824 -379.421043)
			(xy 306.480192 -379.407776) (xy 306.48402 -379.399546) (xy 306.495958 -379.371352) (xy 306.498977 -379.362963)
			(xy 306.499772 -379.345169) (xy 306.497482 -379.336554) (xy 306.489055 -379.308342) (xy 306.479994 -379.250168)
			(xy 306.479448 -379.22073) (xy 306.479934 -379.193479) (xy 306.48769 -379.139531) (xy 306.503045 -379.087236)
			(xy 306.525687 -379.037659) (xy 306.555153 -378.991809) (xy 306.590844 -378.950618) (xy 306.632035 -378.914927)
			(xy 306.677885 -378.885461) (xy 306.727462 -378.862819) (xy 306.779757 -378.847464) (xy 306.833705 -378.839708)
			(xy 306.888207 -378.839708) (xy 306.942155 -378.847464) (xy 306.99445 -378.862819) (xy 307.044027 -378.885461)
			(xy 307.089877 -378.914927) (xy 307.131068 -378.950618) (xy 307.166759 -378.991809) (xy 307.196225 -379.037659)
			(xy 307.218867 -379.087236) (xy 307.234222 -379.139531) (xy 307.241978 -379.193479) (xy 307.242464 -379.22073)
			(xy 307.242102 -379.244801) (xy 307.236065 -379.292564) (xy 307.224076 -379.33919) (xy 307.21554 -379.3617)
			(xy 307.21046 -379.374146) (xy 307.213762 -379.400054) (xy 307.280564 -379.490732) (xy 307.304186 -379.501654)
			(xy 307.317394 -379.500638) (xy 307.346096 -379.499622) (xy 307.373351 -379.500025) (xy 307.427307 -379.507782)
			(xy 307.479609 -379.523139) (xy 307.529194 -379.545783) (xy 307.575051 -379.575253) (xy 307.616248 -379.610949)
			(xy 307.651945 -379.652146) (xy 307.681415 -379.698003) (xy 307.70406 -379.747587) (xy 307.719417 -379.799889)
			(xy 307.727175 -379.853845) (xy 307.727175 -379.908349) (xy 311.587908 -379.908349) (xy 311.587908 -379.853851)
			(xy 311.595664 -379.799908) (xy 311.611018 -379.747618) (xy 311.633657 -379.698045) (xy 311.66312 -379.652198)
			(xy 311.698809 -379.611011) (xy 311.739995 -379.575323) (xy 311.785841 -379.545859) (xy 311.835414 -379.523219)
			(xy 311.887704 -379.507865) (xy 311.941647 -379.500108) (xy 311.968896 -379.499622) (xy 311.997598 -379.500638)
			(xy 312.010806 -379.501654) (xy 312.034428 -379.490732) (xy 312.10123 -379.400054) (xy 312.104532 -379.374146)
			(xy 312.099452 -379.3617) (xy 312.090917 -379.339189) (xy 312.078913 -379.292566) (xy 312.07288 -379.244802)
			(xy 312.072528 -379.22073) (xy 312.073014 -379.193479) (xy 312.08077 -379.139531) (xy 312.096125 -379.087236)
			(xy 312.118767 -379.037659) (xy 312.148233 -378.991809) (xy 312.183924 -378.950618) (xy 312.225115 -378.914927)
			(xy 312.270965 -378.885461) (xy 312.320542 -378.862819) (xy 312.372837 -378.847464) (xy 312.426785 -378.839708)
			(xy 312.481287 -378.839708) (xy 312.535235 -378.847464) (xy 312.58753 -378.862819) (xy 312.637107 -378.885461)
			(xy 312.682957 -378.914927) (xy 312.724148 -378.950618) (xy 312.759839 -378.991809) (xy 312.789305 -379.037659)
			(xy 312.811947 -379.087236) (xy 312.827302 -379.139531) (xy 312.835058 -379.193479) (xy 312.835544 -379.22073)
			(xy 312.83498 -379.250167) (xy 312.825925 -379.30834) (xy 312.81751 -379.336554) (xy 312.815145 -379.345163)
			(xy 312.815919 -379.362986) (xy 312.819034 -379.371352) (xy 312.830972 -379.399546) (xy 312.834788 -379.407783)
			(xy 312.847161 -379.421054) (xy 312.855102 -379.425454) (xy 312.880794 -379.438625) (xy 312.929301 -379.46994)
			(xy 312.951876 -379.487938) (xy 312.958879 -379.493203) (xy 312.975379 -379.499052) (xy 312.984134 -379.499368)
			(xy 313.138058 -379.499368) (xy 313.146808 -379.499037) (xy 313.163299 -379.493178) (xy 313.170316 -379.487938)
			(xy 313.192899 -379.469951) (xy 313.241404 -379.438635) (xy 313.26709 -379.425454) (xy 313.275024 -379.421043)
			(xy 313.287392 -379.407776) (xy 313.29122 -379.399546) (xy 313.303158 -379.371352) (xy 313.306177 -379.362963)
			(xy 313.306972 -379.345169) (xy 313.304682 -379.336554) (xy 313.296255 -379.308342) (xy 313.287194 -379.250168)
			(xy 313.286648 -379.22073) (xy 313.287134 -379.193479) (xy 313.29489 -379.139531) (xy 313.310245 -379.087236)
			(xy 313.332887 -379.037659) (xy 313.362353 -378.991809) (xy 313.398044 -378.950618) (xy 313.439235 -378.914927)
			(xy 313.485085 -378.885461) (xy 313.534662 -378.862819) (xy 313.586957 -378.847464) (xy 313.640905 -378.839708)
			(xy 313.695407 -378.839708) (xy 313.749355 -378.847464) (xy 313.80165 -378.862819) (xy 313.851227 -378.885461)
			(xy 313.897077 -378.914927) (xy 313.938268 -378.950618) (xy 313.973959 -378.991809) (xy 314.003425 -379.037659)
			(xy 314.026067 -379.087236) (xy 314.041422 -379.139531) (xy 314.049178 -379.193479) (xy 314.049664 -379.22073)
			(xy 314.049302 -379.244801) (xy 314.043265 -379.292564) (xy 314.031276 -379.33919) (xy 314.02274 -379.3617)
			(xy 314.01766 -379.374146) (xy 314.020962 -379.400054) (xy 314.087764 -379.490732) (xy 314.111386 -379.501654)
			(xy 314.124594 -379.500638) (xy 314.153296 -379.499622) (xy 314.180551 -379.500025) (xy 314.234507 -379.507782)
			(xy 314.286809 -379.523139) (xy 314.336394 -379.545783) (xy 314.382251 -379.575253) (xy 314.423448 -379.610949)
			(xy 314.459145 -379.652146) (xy 314.488615 -379.698003) (xy 314.51126 -379.747587) (xy 314.526617 -379.799889)
			(xy 314.534375 -379.853845) (xy 314.534375 -379.908349) (xy 318.395108 -379.908349) (xy 318.395108 -379.853851)
			(xy 318.402864 -379.799908) (xy 318.418218 -379.747618) (xy 318.440857 -379.698045) (xy 318.47032 -379.652198)
			(xy 318.506009 -379.611011) (xy 318.547195 -379.575323) (xy 318.593041 -379.545859) (xy 318.642614 -379.523219)
			(xy 318.694904 -379.507865) (xy 318.748847 -379.500108) (xy 318.776096 -379.499622) (xy 318.804798 -379.500638)
			(xy 318.818006 -379.501654) (xy 318.841628 -379.490732) (xy 318.90843 -379.400054) (xy 318.911732 -379.374146)
			(xy 318.906652 -379.3617) (xy 318.898117 -379.339189) (xy 318.886113 -379.292566) (xy 318.88008 -379.244802)
			(xy 318.879728 -379.22073) (xy 318.880214 -379.193479) (xy 318.88797 -379.139531) (xy 318.903325 -379.087236)
			(xy 318.925967 -379.037659) (xy 318.955433 -378.991809) (xy 318.991124 -378.950618) (xy 319.032315 -378.914927)
			(xy 319.078165 -378.885461) (xy 319.127742 -378.862819) (xy 319.180037 -378.847464) (xy 319.233985 -378.839708)
			(xy 319.288487 -378.839708) (xy 319.342435 -378.847464) (xy 319.39473 -378.862819) (xy 319.444307 -378.885461)
			(xy 319.490157 -378.914927) (xy 319.531348 -378.950618) (xy 319.567039 -378.991809) (xy 319.596505 -379.037659)
			(xy 319.619147 -379.087236) (xy 319.634502 -379.139531) (xy 319.642258 -379.193479) (xy 319.642744 -379.22073)
			(xy 319.64218 -379.250167) (xy 319.633125 -379.30834) (xy 319.62471 -379.336554) (xy 319.622345 -379.345163)
			(xy 319.623119 -379.362986) (xy 319.626234 -379.371352) (xy 319.638172 -379.399546) (xy 319.641988 -379.407783)
			(xy 319.654361 -379.421054) (xy 319.662302 -379.425454) (xy 319.687994 -379.438625) (xy 319.736501 -379.46994)
			(xy 319.759076 -379.487938) (xy 319.766079 -379.493203) (xy 319.782579 -379.499052) (xy 319.791334 -379.499368)
			(xy 319.945258 -379.499368) (xy 319.954008 -379.499037) (xy 319.970499 -379.493178) (xy 319.977516 -379.487938)
			(xy 320.000099 -379.469951) (xy 320.048604 -379.438635) (xy 320.07429 -379.425454) (xy 320.082224 -379.421043)
			(xy 320.094592 -379.407776) (xy 320.09842 -379.399546) (xy 320.110358 -379.371352) (xy 320.113377 -379.362963)
			(xy 320.114172 -379.345169) (xy 320.111882 -379.336554) (xy 320.103455 -379.308342) (xy 320.094394 -379.250168)
			(xy 320.093848 -379.22073) (xy 320.094334 -379.193479) (xy 320.10209 -379.139531) (xy 320.117445 -379.087236)
			(xy 320.140087 -379.037659) (xy 320.169553 -378.991809) (xy 320.205244 -378.950618) (xy 320.246435 -378.914927)
			(xy 320.292285 -378.885461) (xy 320.341862 -378.862819) (xy 320.394157 -378.847464) (xy 320.448105 -378.839708)
			(xy 320.502607 -378.839708) (xy 320.556555 -378.847464) (xy 320.60885 -378.862819) (xy 320.658427 -378.885461)
			(xy 320.704277 -378.914927) (xy 320.745468 -378.950618) (xy 320.781159 -378.991809) (xy 320.810625 -379.037659)
			(xy 320.833267 -379.087236) (xy 320.848622 -379.139531) (xy 320.856378 -379.193479) (xy 320.856864 -379.22073)
			(xy 320.856502 -379.244801) (xy 320.850465 -379.292564) (xy 320.838476 -379.33919) (xy 320.82994 -379.3617)
			(xy 320.82486 -379.374146) (xy 320.828162 -379.400054) (xy 320.894964 -379.490732) (xy 320.918586 -379.501654)
			(xy 320.931794 -379.500638) (xy 320.960496 -379.499622) (xy 320.987751 -379.500025) (xy 321.041707 -379.507782)
			(xy 321.094009 -379.523139) (xy 321.143594 -379.545783) (xy 321.189451 -379.575253) (xy 321.230648 -379.610949)
			(xy 321.266345 -379.652146) (xy 321.295815 -379.698003) (xy 321.31846 -379.747587) (xy 321.333817 -379.799889)
			(xy 321.341575 -379.853845) (xy 321.341575 -379.908355) (xy 321.333817 -379.962311) (xy 321.31846 -380.014613)
			(xy 321.295815 -380.064197) (xy 321.266345 -380.110054) (xy 321.230648 -380.151251) (xy 321.189451 -380.186947)
			(xy 321.143594 -380.216417) (xy 321.094009 -380.239061) (xy 321.041707 -380.254418) (xy 320.987751 -380.262175)
			(xy 320.960496 -380.262638) (xy 320.931794 -380.261622) (xy 320.918586 -380.260606) (xy 320.894964 -380.271528)
			(xy 320.828162 -380.362206) (xy 320.82486 -380.388114) (xy 320.82994 -380.40056) (xy 320.838492 -380.423065)
			(xy 320.85049 -380.469691) (xy 320.856516 -380.517457) (xy 320.856864 -380.54153) (xy 320.856378 -380.568781)
			(xy 320.848622 -380.622729) (xy 320.833267 -380.675024) (xy 320.810625 -380.724601) (xy 320.781159 -380.770451)
			(xy 320.745468 -380.811642) (xy 320.704277 -380.847333) (xy 320.658427 -380.876799) (xy 320.60885 -380.899441)
			(xy 320.556555 -380.914796) (xy 320.502607 -380.922552) (xy 320.448105 -380.922552) (xy 320.394157 -380.914796)
			(xy 320.341862 -380.899441) (xy 320.292285 -380.876799) (xy 320.246435 -380.847333) (xy 320.205244 -380.811642)
			(xy 320.169553 -380.770451) (xy 320.140087 -380.724601) (xy 320.117445 -380.675024) (xy 320.10209 -380.622729)
			(xy 320.094334 -380.568781) (xy 320.093848 -380.54153) (xy 320.094403 -380.512093) (xy 320.103464 -380.453919)
			(xy 320.111882 -380.425706) (xy 320.114262 -380.417101) (xy 320.113476 -380.399275) (xy 320.110358 -380.390908)
			(xy 320.09842 -380.362714) (xy 320.094587 -380.354486) (xy 320.082227 -380.341209) (xy 320.07429 -380.336806)
			(xy 320.048595 -380.323639) (xy 320.00009 -380.292321) (xy 319.977516 -380.274322) (xy 319.970518 -380.269049)
			(xy 319.954014 -380.263206) (xy 319.945258 -380.262892) (xy 319.791334 -380.262892) (xy 319.782584 -380.263228)
			(xy 319.766093 -380.269084) (xy 319.759076 -380.274322) (xy 319.736498 -380.292315) (xy 319.68799 -380.323627)
			(xy 319.662302 -380.336806) (xy 319.654353 -380.341194) (xy 319.641992 -380.354477) (xy 319.638172 -380.362714)
			(xy 319.626234 -380.390908) (xy 319.623185 -380.399288) (xy 319.62241 -380.41709) (xy 319.62471 -380.425706)
			(xy 319.633152 -380.453913) (xy 319.642203 -380.512091) (xy 319.642744 -380.54153) (xy 319.642258 -380.568781)
			(xy 319.634502 -380.622729) (xy 319.619147 -380.675024) (xy 319.596505 -380.724601) (xy 319.567039 -380.770451)
			(xy 319.531348 -380.811642) (xy 319.490157 -380.847333) (xy 319.444307 -380.876799) (xy 319.39473 -380.899441)
			(xy 319.342435 -380.914796) (xy 319.288487 -380.922552) (xy 319.233985 -380.922552) (xy 319.180037 -380.914796)
			(xy 319.127742 -380.899441) (xy 319.078165 -380.876799) (xy 319.032315 -380.847333) (xy 318.991124 -380.811642)
			(xy 318.955433 -380.770451) (xy 318.925967 -380.724601) (xy 318.903325 -380.675024) (xy 318.88797 -380.622729)
			(xy 318.880214 -380.568781) (xy 318.879728 -380.54153) (xy 318.880078 -380.517458) (xy 318.88612 -380.469695)
			(xy 318.898114 -380.42307) (xy 318.906652 -380.40056) (xy 318.911732 -380.388114) (xy 318.90843 -380.362206)
			(xy 318.841628 -380.271528) (xy 318.818006 -380.260606) (xy 318.804798 -380.261622) (xy 318.776096 -380.262638)
			(xy 318.748847 -380.262092) (xy 318.694904 -380.254335) (xy 318.642614 -380.238981) (xy 318.593041 -380.216341)
			(xy 318.547195 -380.186877) (xy 318.506009 -380.151189) (xy 318.47032 -380.110002) (xy 318.440857 -380.064155)
			(xy 318.418218 -380.014582) (xy 318.402864 -379.962292) (xy 318.395108 -379.908349) (xy 314.534375 -379.908349)
			(xy 314.534375 -379.908355) (xy 314.526617 -379.962311) (xy 314.51126 -380.014613) (xy 314.488615 -380.064197)
			(xy 314.459145 -380.110054) (xy 314.423448 -380.151251) (xy 314.382251 -380.186947) (xy 314.336394 -380.216417)
			(xy 314.286809 -380.239061) (xy 314.234507 -380.254418) (xy 314.180551 -380.262175) (xy 314.153296 -380.262638)
			(xy 314.124594 -380.261622) (xy 314.111386 -380.260606) (xy 314.087764 -380.271528) (xy 314.020962 -380.362206)
			(xy 314.01766 -380.388114) (xy 314.02274 -380.40056) (xy 314.031292 -380.423065) (xy 314.04329 -380.469691)
			(xy 314.049316 -380.517457) (xy 314.049664 -380.54153) (xy 314.049178 -380.568781) (xy 314.041422 -380.622729)
			(xy 314.026067 -380.675024) (xy 314.003425 -380.724601) (xy 313.973959 -380.770451) (xy 313.938268 -380.811642)
			(xy 313.897077 -380.847333) (xy 313.851227 -380.876799) (xy 313.80165 -380.899441) (xy 313.749355 -380.914796)
			(xy 313.695407 -380.922552) (xy 313.640905 -380.922552) (xy 313.586957 -380.914796) (xy 313.534662 -380.899441)
			(xy 313.485085 -380.876799) (xy 313.439235 -380.847333) (xy 313.398044 -380.811642) (xy 313.362353 -380.770451)
			(xy 313.332887 -380.724601) (xy 313.310245 -380.675024) (xy 313.29489 -380.622729) (xy 313.287134 -380.568781)
			(xy 313.286648 -380.54153) (xy 313.287203 -380.512093) (xy 313.296264 -380.453919) (xy 313.304682 -380.425706)
			(xy 313.307062 -380.417101) (xy 313.306276 -380.399275) (xy 313.303158 -380.390908) (xy 313.29122 -380.362714)
			(xy 313.287387 -380.354486) (xy 313.275027 -380.341209) (xy 313.26709 -380.336806) (xy 313.241395 -380.323639)
			(xy 313.19289 -380.292321) (xy 313.170316 -380.274322) (xy 313.163318 -380.269049) (xy 313.146814 -380.263206)
			(xy 313.138058 -380.262892) (xy 312.984134 -380.262892) (xy 312.975384 -380.263228) (xy 312.958893 -380.269084)
			(xy 312.951876 -380.274322) (xy 312.929298 -380.292315) (xy 312.88079 -380.323627) (xy 312.855102 -380.336806)
			(xy 312.847153 -380.341194) (xy 312.834792 -380.354477) (xy 312.830972 -380.362714) (xy 312.819034 -380.390908)
			(xy 312.815985 -380.399288) (xy 312.81521 -380.41709) (xy 312.81751 -380.425706) (xy 312.825952 -380.453913)
			(xy 312.835003 -380.512091) (xy 312.835544 -380.54153) (xy 312.835058 -380.568781) (xy 312.827302 -380.622729)
			(xy 312.811947 -380.675024) (xy 312.789305 -380.724601) (xy 312.759839 -380.770451) (xy 312.724148 -380.811642)
			(xy 312.682957 -380.847333) (xy 312.637107 -380.876799) (xy 312.58753 -380.899441) (xy 312.535235 -380.914796)
			(xy 312.481287 -380.922552) (xy 312.426785 -380.922552) (xy 312.372837 -380.914796) (xy 312.320542 -380.899441)
			(xy 312.270965 -380.876799) (xy 312.225115 -380.847333) (xy 312.183924 -380.811642) (xy 312.148233 -380.770451)
			(xy 312.118767 -380.724601) (xy 312.096125 -380.675024) (xy 312.08077 -380.622729) (xy 312.073014 -380.568781)
			(xy 312.072528 -380.54153) (xy 312.072878 -380.517458) (xy 312.07892 -380.469695) (xy 312.090914 -380.42307)
			(xy 312.099452 -380.40056) (xy 312.104532 -380.388114) (xy 312.10123 -380.362206) (xy 312.034428 -380.271528)
			(xy 312.010806 -380.260606) (xy 311.997598 -380.261622) (xy 311.968896 -380.262638) (xy 311.941647 -380.262092)
			(xy 311.887704 -380.254335) (xy 311.835414 -380.238981) (xy 311.785841 -380.216341) (xy 311.739995 -380.186877)
			(xy 311.698809 -380.151189) (xy 311.66312 -380.110002) (xy 311.633657 -380.064155) (xy 311.611018 -380.014582)
			(xy 311.595664 -379.962292) (xy 311.587908 -379.908349) (xy 307.727175 -379.908349) (xy 307.727175 -379.908355)
			(xy 307.719417 -379.962311) (xy 307.70406 -380.014613) (xy 307.681415 -380.064197) (xy 307.651945 -380.110054)
			(xy 307.616248 -380.151251) (xy 307.575051 -380.186947) (xy 307.529194 -380.216417) (xy 307.479609 -380.239061)
			(xy 307.427307 -380.254418) (xy 307.373351 -380.262175) (xy 307.346096 -380.262638) (xy 307.317394 -380.261622)
			(xy 307.304186 -380.260606) (xy 307.280564 -380.271528) (xy 307.213762 -380.362206) (xy 307.21046 -380.388114)
			(xy 307.21554 -380.40056) (xy 307.224092 -380.423065) (xy 307.23609 -380.469691) (xy 307.242116 -380.517457)
			(xy 307.242464 -380.54153) (xy 307.241978 -380.568781) (xy 307.234222 -380.622729) (xy 307.218867 -380.675024)
			(xy 307.196225 -380.724601) (xy 307.166759 -380.770451) (xy 307.131068 -380.811642) (xy 307.089877 -380.847333)
			(xy 307.044027 -380.876799) (xy 306.99445 -380.899441) (xy 306.942155 -380.914796) (xy 306.888207 -380.922552)
			(xy 306.833705 -380.922552) (xy 306.779757 -380.914796) (xy 306.727462 -380.899441) (xy 306.677885 -380.876799)
			(xy 306.632035 -380.847333) (xy 306.590844 -380.811642) (xy 306.555153 -380.770451) (xy 306.525687 -380.724601)
			(xy 306.503045 -380.675024) (xy 306.48769 -380.622729) (xy 306.479934 -380.568781) (xy 306.479448 -380.54153)
			(xy 306.480003 -380.512093) (xy 306.489064 -380.453919) (xy 306.497482 -380.425706) (xy 306.499862 -380.417101)
			(xy 306.499076 -380.399275) (xy 306.495958 -380.390908) (xy 306.48402 -380.362714) (xy 306.480187 -380.354486)
			(xy 306.467827 -380.341209) (xy 306.45989 -380.336806) (xy 306.434195 -380.323639) (xy 306.38569 -380.292321)
			(xy 306.363116 -380.274322) (xy 306.356118 -380.269049) (xy 306.339614 -380.263206) (xy 306.330858 -380.262892)
			(xy 306.176934 -380.262892) (xy 306.168184 -380.263228) (xy 306.151693 -380.269084) (xy 306.144676 -380.274322)
			(xy 306.122098 -380.292315) (xy 306.07359 -380.323627) (xy 306.047902 -380.336806) (xy 306.039953 -380.341194)
			(xy 306.027592 -380.354477) (xy 306.023772 -380.362714) (xy 306.011834 -380.390908) (xy 306.008785 -380.399288)
			(xy 306.00801 -380.41709) (xy 306.01031 -380.425706) (xy 306.018752 -380.453913) (xy 306.027803 -380.512091)
			(xy 306.028344 -380.54153) (xy 306.027858 -380.568781) (xy 306.020102 -380.622729) (xy 306.004747 -380.675024)
			(xy 305.982105 -380.724601) (xy 305.952639 -380.770451) (xy 305.916948 -380.811642) (xy 305.875757 -380.847333)
			(xy 305.829907 -380.876799) (xy 305.78033 -380.899441) (xy 305.728035 -380.914796) (xy 305.674087 -380.922552)
			(xy 305.619585 -380.922552) (xy 305.565637 -380.914796) (xy 305.513342 -380.899441) (xy 305.463765 -380.876799)
			(xy 305.417915 -380.847333) (xy 305.376724 -380.811642) (xy 305.341033 -380.770451) (xy 305.311567 -380.724601)
			(xy 305.288925 -380.675024) (xy 305.27357 -380.622729) (xy 305.265814 -380.568781) (xy 305.265328 -380.54153)
			(xy 305.265678 -380.517458) (xy 305.27172 -380.469695) (xy 305.283714 -380.42307) (xy 305.292252 -380.40056)
			(xy 305.297332 -380.388114) (xy 305.29403 -380.362206) (xy 305.227228 -380.271528) (xy 305.203606 -380.260606)
			(xy 305.190398 -380.261622) (xy 305.161696 -380.262638) (xy 305.134447 -380.262092) (xy 305.080504 -380.254335)
			(xy 305.028214 -380.238981) (xy 304.978641 -380.216341) (xy 304.932795 -380.186877) (xy 304.891609 -380.151189)
			(xy 304.85592 -380.110002) (xy 304.826457 -380.064155) (xy 304.803818 -380.014582) (xy 304.788464 -379.962292)
			(xy 304.780708 -379.908349) (xy 300.919975 -379.908349) (xy 300.919975 -379.908355) (xy 300.912217 -379.962311)
			(xy 300.89686 -380.014613) (xy 300.874215 -380.064197) (xy 300.844745 -380.110054) (xy 300.809048 -380.151251)
			(xy 300.767851 -380.186947) (xy 300.721994 -380.216417) (xy 300.672409 -380.239061) (xy 300.620107 -380.254418)
			(xy 300.566151 -380.262175) (xy 300.538896 -380.262638) (xy 300.510194 -380.261622) (xy 300.496986 -380.260606)
			(xy 300.473364 -380.271528) (xy 300.406562 -380.362206) (xy 300.40326 -380.388114) (xy 300.40834 -380.40056)
			(xy 300.416892 -380.423065) (xy 300.42889 -380.469691) (xy 300.434916 -380.517457) (xy 300.435264 -380.54153)
			(xy 300.434778 -380.568781) (xy 300.427022 -380.622729) (xy 300.411667 -380.675024) (xy 300.389025 -380.724601)
			(xy 300.359559 -380.770451) (xy 300.323868 -380.811642) (xy 300.282677 -380.847333) (xy 300.236827 -380.876799)
			(xy 300.18725 -380.899441) (xy 300.134955 -380.914796) (xy 300.081007 -380.922552) (xy 300.026505 -380.922552)
			(xy 299.972557 -380.914796) (xy 299.920262 -380.899441) (xy 299.870685 -380.876799) (xy 299.824835 -380.847333)
			(xy 299.783644 -380.811642) (xy 299.747953 -380.770451) (xy 299.718487 -380.724601) (xy 299.695845 -380.675024)
			(xy 299.68049 -380.622729) (xy 299.672734 -380.568781) (xy 299.672248 -380.54153) (xy 299.672803 -380.512093)
			(xy 299.681864 -380.453919) (xy 299.690282 -380.425706) (xy 299.692662 -380.417101) (xy 299.691876 -380.399275)
			(xy 299.688758 -380.390908) (xy 299.67682 -380.362714) (xy 299.672987 -380.354486) (xy 299.660627 -380.341209)
			(xy 299.65269 -380.336806) (xy 299.626995 -380.323639) (xy 299.57849 -380.292321) (xy 299.555916 -380.274322)
			(xy 299.548918 -380.269049) (xy 299.532414 -380.263206) (xy 299.523658 -380.262892) (xy 299.369734 -380.262892)
			(xy 299.360984 -380.263228) (xy 299.344493 -380.269084) (xy 299.337476 -380.274322) (xy 299.314898 -380.292315)
			(xy 299.26639 -380.323627) (xy 299.240702 -380.336806) (xy 299.232753 -380.341194) (xy 299.220392 -380.354477)
			(xy 299.216572 -380.362714) (xy 299.204634 -380.390908) (xy 299.201585 -380.399288) (xy 299.20081 -380.41709)
			(xy 299.20311 -380.425706) (xy 299.211552 -380.453913) (xy 299.220603 -380.512091) (xy 299.221144 -380.54153)
			(xy 299.220658 -380.568781) (xy 299.212902 -380.622729) (xy 299.197547 -380.675024) (xy 299.174905 -380.724601)
			(xy 299.145439 -380.770451) (xy 299.109748 -380.811642) (xy 299.068557 -380.847333) (xy 299.022707 -380.876799)
			(xy 298.97313 -380.899441) (xy 298.920835 -380.914796) (xy 298.866887 -380.922552) (xy 298.812385 -380.922552)
			(xy 298.758437 -380.914796) (xy 298.706142 -380.899441) (xy 298.656565 -380.876799) (xy 298.610715 -380.847333)
			(xy 298.569524 -380.811642) (xy 298.533833 -380.770451) (xy 298.504367 -380.724601) (xy 298.481725 -380.675024)
			(xy 298.46637 -380.622729) (xy 298.458614 -380.568781) (xy 298.458128 -380.54153) (xy 298.458478 -380.517458)
			(xy 298.46452 -380.469695) (xy 298.476514 -380.42307) (xy 298.485052 -380.40056) (xy 298.490132 -380.388114)
			(xy 298.48683 -380.362206) (xy 298.420028 -380.271528) (xy 298.396406 -380.260606) (xy 298.383198 -380.261622)
			(xy 298.354496 -380.262638) (xy 298.327247 -380.262092) (xy 298.273304 -380.254335) (xy 298.221014 -380.238981)
			(xy 298.171441 -380.216341) (xy 298.125595 -380.186877) (xy 298.084409 -380.151189) (xy 298.04872 -380.110002)
			(xy 298.019257 -380.064155) (xy 297.996618 -380.014582) (xy 297.981264 -379.962292) (xy 297.973508 -379.908349)
			(xy 280.463922 -379.908349) (xy 280.470987 -379.935865) (xy 280.478998 -379.999283) (xy 280.4795 -380.031244)
			(xy 280.478998 -380.063205) (xy 280.470987 -380.126623) (xy 280.45509 -380.188537) (xy 280.431558 -380.24797)
			(xy 280.400764 -380.303985) (xy 280.363191 -380.3557) (xy 280.319434 -380.402297) (xy 280.270181 -380.443042)
			(xy 280.21621 -380.477293) (xy 280.158371 -380.50451) (xy 280.097578 -380.524263) (xy 280.034788 -380.536241)
			(xy 279.970992 -380.540255) (xy 279.907196 -380.536241) (xy 279.844406 -380.524263) (xy 279.783613 -380.50451)
			(xy 279.725774 -380.477293) (xy 279.671803 -380.443042) (xy 279.62255 -380.402297) (xy 279.578793 -380.3557)
			(xy 279.54122 -380.303985) (xy 279.510426 -380.24797) (xy 279.486894 -380.188537) (xy 279.470997 -380.126623)
			(xy 279.462986 -380.063205) (xy 278.86152 -380.063205) (xy 278.86152 -380.73203) (xy 278.862113 -380.744356)
			(xy 278.873565 -380.766184) (xy 278.883364 -380.773686) (xy 278.961596 -380.82855) (xy 278.986234 -380.831852)
			(xy 278.997918 -380.827788) (xy 279.025725 -380.818141) (xy 279.083002 -380.804584) (xy 279.141462 -380.797742)
			(xy 279.170892 -380.797308) (xy 279.202854 -380.797788) (xy 279.266273 -380.805799) (xy 279.328188 -380.821696)
			(xy 279.387623 -380.845227) (xy 279.44364 -380.876021) (xy 279.495355 -380.913594) (xy 279.541954 -380.957352)
			(xy 279.5827 -381.006606) (xy 279.616952 -381.060578) (xy 279.64417 -381.118417) (xy 279.663924 -381.179212)
			(xy 279.675902 -381.242003) (xy 279.679916 -381.3058) (xy 279.675902 -381.369597) (xy 279.663924 -381.432388)
			(xy 279.64417 -381.493183) (xy 279.616952 -381.551022) (xy 279.5827 -381.604994) (xy 279.541954 -381.654248)
			(xy 279.495355 -381.698006) (xy 279.44364 -381.735579) (xy 279.387623 -381.766373) (xy 279.328188 -381.789904)
			(xy 279.266273 -381.805801) (xy 279.202854 -381.813812) (xy 279.170892 -381.814324) (xy 279.141464 -381.81387)
			(xy 279.083008 -381.807016) (xy 279.025731 -381.79347) (xy 278.997918 -381.783844) (xy 278.986234 -381.77978)
			(xy 278.961596 -381.783082) (xy 278.883364 -381.837946) (xy 278.873703 -381.845563) (xy 278.862307 -381.867323)
			(xy 278.86152 -381.879602) (xy 278.86152 -382.671066) (xy 278.861142 -382.705657) (xy 278.854272 -382.774497)
			(xy 278.847804 -382.80848) (xy 278.846788 -382.81864) (xy 278.846788 -382.830324) (xy 278.880062 -382.863598)
			(xy 278.887464 -382.870435) (xy 278.906062 -382.878147) (xy 278.91613 -382.878584) (xy 279.922732 -382.878584)
			(xy 279.9328 -382.879012) (xy 279.951398 -382.886733) (xy 279.9588 -382.89357) (xy 280.245058 -383.179828)
			(xy 280.248106 -383.179828) (xy 280.861262 -383.792984) (xy 280.868099 -383.800385) (xy 280.875809 -383.818984)
			(xy 280.876248 -383.829052) (xy 280.876248 -384.973576) (xy 283.18841 -384.973576) (xy 283.188829 -384.94336)
			(xy 283.19602 -384.883357) (xy 283.210272 -384.824629) (xy 283.231387 -384.768005) (xy 283.259065 -384.714283)
			(xy 283.292916 -384.664222) (xy 283.312362 -384.64109) (xy 283.317999 -384.633961) (xy 283.324235 -384.6169)
			(xy 283.324554 -384.607816) (xy 283.324554 -384.577336) (xy 283.324249 -384.568252) (xy 283.317989 -384.551201)
			(xy 283.312362 -384.544062) (xy 283.292914 -384.520934) (xy 283.259077 -384.470866) (xy 283.231409 -384.417141)
			(xy 283.210301 -384.360517) (xy 283.196051 -384.301791) (xy 283.188859 -384.241791) (xy 283.18841 -384.211576)
			(xy 283.189016 -384.177336) (xy 283.198238 -384.109479) (xy 283.216472 -384.04347) (xy 283.243389 -383.980501)
			(xy 283.278504 -383.921709) (xy 283.299408 -383.894584) (xy 283.306024 -383.88519) (xy 283.311131 -383.862827)
			(xy 283.306047 -383.840458) (xy 283.299408 -383.831084) (xy 283.278483 -383.80397) (xy 283.243325 -383.745193)
			(xy 283.216386 -383.682225) (xy 283.198155 -383.616206) (xy 283.188964 -383.548337) (xy 283.18841 -383.514092)
			(xy 283.188894 -383.482926) (xy 283.19651 -383.42106) (xy 283.211627 -383.360587) (xy 283.234019 -383.302415)
			(xy 283.26335 -383.247414) (xy 283.299181 -383.196409) (xy 283.319728 -383.17297) (xy 283.325708 -383.165756)
			(xy 283.332469 -383.148294) (xy 283.332936 -383.138934) (xy 283.332936 -383.1082) (xy 283.332563 -383.098822)
			(xy 283.325782 -383.081336) (xy 283.319728 -383.074164) (xy 283.299156 -383.050745) (xy 283.263323 -382.999737)
			(xy 283.233992 -382.944733) (xy 283.211602 -382.886557) (xy 283.196488 -382.82608) (xy 283.188878 -382.76421)
			(xy 283.18841 -382.733042) (xy 283.188877 -382.70231) (xy 283.196281 -382.641294) (xy 283.210987 -382.581615)
			(xy 283.232779 -382.524144) (xy 283.26134 -382.46972) (xy 283.296253 -382.419135) (xy 283.33701 -382.373127)
			(xy 283.383016 -382.332368) (xy 283.433599 -382.297452) (xy 283.488022 -382.268889) (xy 283.545492 -382.247094)
			(xy 283.60517 -382.232386) (xy 283.666186 -382.224979) (xy 283.696918 -382.224534) (xy 283.728695 -382.225057)
			(xy 283.791753 -382.232982) (xy 283.853332 -382.248705) (xy 283.91247 -382.271982) (xy 283.968245 -382.30245)
			(xy 284.019787 -382.339632) (xy 284.043374 -382.360932) (xy 284.050303 -382.366802) (xy 284.067086 -382.373703)
			(xy 284.07614 -382.374394) (xy 284.106366 -382.375664) (xy 284.11549 -382.375638) (xy 284.132798 -382.369897)
			(xy 284.140148 -382.364488) (xy 284.167295 -382.343512) (xy 284.226164 -382.308281) (xy 284.289235 -382.281285)
			(xy 284.355362 -382.263012) (xy 284.423345 -382.253796) (xy 284.457648 -382.253236) (xy 284.488382 -382.253611)
			(xy 284.5494 -382.261025) (xy 284.60908 -382.275741) (xy 284.666552 -382.297543) (xy 284.720976 -382.326114)
			(xy 284.771559 -382.361036) (xy 284.817565 -382.4018) (xy 284.858321 -382.447813) (xy 284.893234 -382.498403)
			(xy 284.921795 -382.552832) (xy 284.943586 -382.610307) (xy 284.958291 -382.66999) (xy 284.965695 -382.73101)
			(xy 284.966156 -382.761744) (xy 284.965734 -382.791403) (xy 284.958803 -382.850314) (xy 284.945065 -382.90802)
			(xy 284.924705 -382.963734) (xy 284.898001 -383.016701) (xy 284.865315 -383.066201) (xy 284.846522 -383.08915)
			(xy 284.841106 -383.096247) (xy 284.834985 -383.112999) (xy 284.834584 -383.121916) (xy 284.834584 -383.152142)
			(xy 284.834911 -383.161075) (xy 284.841025 -383.17786) (xy 284.846522 -383.184908) (xy 284.865303 -383.207866)
			(xy 284.897986 -383.257365) (xy 284.924689 -383.310331) (xy 284.945048 -383.366044) (xy 284.958788 -383.423747)
			(xy 284.965722 -383.482656) (xy 284.966156 -383.512314) (xy 284.965586 -383.546651) (xy 284.956343 -383.614699)
			(xy 284.938026 -383.680885) (xy 284.910969 -383.744003) (xy 284.875664 -383.802907) (xy 284.85465 -383.830068)
			(xy 284.847826 -383.839404) (xy 284.842698 -383.861936) (xy 284.847857 -383.88446) (xy 284.85465 -383.893822)
			(xy 284.875648 -383.920995) (xy 284.91096 -383.979894) (xy 284.938022 -384.043009) (xy 284.956343 -384.109193)
			(xy 284.965589 -384.17724) (xy 284.966156 -384.211576) (xy 284.965717 -384.241792) (xy 284.958531 -384.301794)
			(xy 284.944283 -384.360522) (xy 284.923172 -384.417146) (xy 284.895498 -384.470868) (xy 284.861649 -384.52093)
			(xy 284.842204 -384.544062) (xy 284.836595 -384.551211) (xy 284.830341 -384.568256) (xy 284.830012 -384.577336)
			(xy 284.830012 -384.607816) (xy 284.830348 -384.616897) (xy 284.836588 -384.633948) (xy 284.842204 -384.64109)
			(xy 284.861623 -384.664241) (xy 284.895466 -384.714303) (xy 284.923138 -384.768023) (xy 284.944251 -384.824642)
			(xy 284.957345 -384.87858) (xy 286.799027 -384.87858) (xy 286.803034 -384.693676) (xy 286.815047 -384.509118)
			(xy 286.835043 -384.325254) (xy 286.862985 -384.14243) (xy 286.898821 -383.960987) (xy 286.942483 -383.781266)
			(xy 286.99389 -383.603606) (xy 287.052944 -383.42834) (xy 287.119535 -383.255796) (xy 287.193538 -383.086299)
			(xy 287.274814 -382.920167) (xy 287.36321 -382.757711) (xy 287.458561 -382.599237) (xy 287.560687 -382.445042)
			(xy 287.669396 -382.295416) (xy 287.784485 -382.15064) (xy 287.905738 -382.010985) (xy 288.032927 -381.876714)
			(xy 288.165812 -381.748078) (xy 288.304146 -381.625319) (xy 288.447667 -381.508669) (xy 288.596106 -381.398345)
			(xy 288.749186 -381.294554) (xy 288.906617 -381.197492) (xy 289.068106 -381.107342) (xy 289.233348 -381.024271)
			(xy 289.402034 -380.948436) (xy 289.573846 -380.87998) (xy 289.748462 -380.81903) (xy 289.925555 -380.765703)
			(xy 290.104792 -380.720096) (xy 290.285836 -380.682297) (xy 290.468347 -380.652376) (xy 290.651984 -380.630389)
			(xy 290.8364 -380.616377) (xy 291.02125 -380.610367) (xy 291.206187 -380.612371) (xy 291.390864 -380.622384)
			(xy 291.574934 -380.640387) (xy 291.75805 -380.666348) (xy 291.939871 -380.700216) (xy 292.120054 -380.741928)
			(xy 292.29826 -380.791407) (xy 292.474156 -380.848559) (xy 292.647411 -380.913277) (xy 292.8177 -380.98544)
			(xy 292.984703 -381.064911) (xy 293.148107 -381.151542) (xy 293.307604 -381.245171) (xy 293.462896 -381.34562)
			(xy 293.613691 -381.452703) (xy 293.759706 -381.566217) (xy 293.900666 -381.685949) (xy 294.036307 -381.811676)
			(xy 294.166375 -381.94316) (xy 294.290625 -382.080156) (xy 294.408823 -382.222405) (xy 294.520749 -382.36964)
			(xy 294.52249 -382.372149) (xy 303.078908 -382.372149) (xy 303.078908 -382.317651) (xy 303.086664 -382.263708)
			(xy 303.102018 -382.211418) (xy 303.124657 -382.161845) (xy 303.15412 -382.115998) (xy 303.189809 -382.074811)
			(xy 303.230995 -382.039123) (xy 303.276841 -382.009659) (xy 303.326414 -381.987019) (xy 303.378704 -381.971665)
			(xy 303.432647 -381.963908) (xy 303.459896 -381.963422) (xy 303.488598 -381.964438) (xy 303.501806 -381.965454)
			(xy 303.525428 -381.954532) (xy 303.59223 -381.863854) (xy 303.595532 -381.837946) (xy 303.590452 -381.8255)
			(xy 303.581917 -381.802989) (xy 303.569913 -381.756366) (xy 303.56388 -381.708602) (xy 303.563528 -381.68453)
			(xy 303.564014 -381.657279) (xy 303.57177 -381.603331) (xy 303.587125 -381.551036) (xy 303.609767 -381.501459)
			(xy 303.639233 -381.455609) (xy 303.674924 -381.414418) (xy 303.716115 -381.378727) (xy 303.761965 -381.349261)
			(xy 303.811542 -381.326619) (xy 303.863837 -381.311264) (xy 303.917785 -381.303508) (xy 303.972287 -381.303508)
			(xy 304.026235 -381.311264) (xy 304.07853 -381.326619) (xy 304.128107 -381.349261) (xy 304.173957 -381.378727)
			(xy 304.215148 -381.414418) (xy 304.250839 -381.455609) (xy 304.280305 -381.501459) (xy 304.302947 -381.551036)
			(xy 304.318302 -381.603331) (xy 304.326058 -381.657279) (xy 304.326544 -381.68453) (xy 304.32598 -381.713967)
			(xy 304.316925 -381.77214) (xy 304.30851 -381.800354) (xy 304.306145 -381.808963) (xy 304.306919 -381.826786)
			(xy 304.310034 -381.835152) (xy 304.321972 -381.863346) (xy 304.325788 -381.871583) (xy 304.338161 -381.884854)
			(xy 304.346102 -381.889254) (xy 304.371794 -381.902425) (xy 304.420301 -381.93374) (xy 304.442876 -381.951738)
			(xy 304.449879 -381.957003) (xy 304.466379 -381.962852) (xy 304.475134 -381.963168) (xy 304.629058 -381.963168)
			(xy 304.637808 -381.962837) (xy 304.654299 -381.956978) (xy 304.661316 -381.951738) (xy 304.683899 -381.933751)
			(xy 304.732404 -381.902435) (xy 304.75809 -381.889254) (xy 304.766024 -381.884843) (xy 304.778392 -381.871576)
			(xy 304.78222 -381.863346) (xy 304.794158 -381.835152) (xy 304.797177 -381.826763) (xy 304.797972 -381.808969)
			(xy 304.795682 -381.800354) (xy 304.787255 -381.772142) (xy 304.778194 -381.713968) (xy 304.777648 -381.68453)
			(xy 304.778134 -381.657279) (xy 304.78589 -381.603331) (xy 304.801245 -381.551036) (xy 304.823887 -381.501459)
			(xy 304.853353 -381.455609) (xy 304.889044 -381.414418) (xy 304.930235 -381.378727) (xy 304.976085 -381.349261)
			(xy 305.025662 -381.326619) (xy 305.077957 -381.311264) (xy 305.131905 -381.303508) (xy 305.186407 -381.303508)
			(xy 305.240355 -381.311264) (xy 305.29265 -381.326619) (xy 305.342227 -381.349261) (xy 305.388077 -381.378727)
			(xy 305.429268 -381.414418) (xy 305.464959 -381.455609) (xy 305.494425 -381.501459) (xy 305.517067 -381.551036)
			(xy 305.532422 -381.603331) (xy 305.540178 -381.657279) (xy 305.540664 -381.68453) (xy 305.540302 -381.708601)
			(xy 305.534265 -381.756364) (xy 305.522276 -381.80299) (xy 305.51374 -381.8255) (xy 305.50866 -381.837946)
			(xy 305.511962 -381.863854) (xy 305.578764 -381.954532) (xy 305.602386 -381.965454) (xy 305.615594 -381.964438)
			(xy 305.644296 -381.963422) (xy 305.671551 -381.963825) (xy 305.725507 -381.971582) (xy 305.777809 -381.986939)
			(xy 305.827394 -382.009583) (xy 305.873251 -382.039053) (xy 305.914448 -382.074749) (xy 305.950145 -382.115946)
			(xy 305.979615 -382.161803) (xy 306.00226 -382.211387) (xy 306.017617 -382.263689) (xy 306.025375 -382.317645)
			(xy 306.025375 -382.372149) (xy 309.886108 -382.372149) (xy 309.886108 -382.317651) (xy 309.893864 -382.263708)
			(xy 309.909218 -382.211418) (xy 309.931857 -382.161845) (xy 309.96132 -382.115998) (xy 309.997009 -382.074811)
			(xy 310.038195 -382.039123) (xy 310.084041 -382.009659) (xy 310.133614 -381.987019) (xy 310.185904 -381.971665)
			(xy 310.239847 -381.963908) (xy 310.267096 -381.963422) (xy 310.295798 -381.964438) (xy 310.309006 -381.965454)
			(xy 310.332628 -381.954532) (xy 310.39943 -381.863854) (xy 310.402732 -381.837946) (xy 310.397652 -381.8255)
			(xy 310.389117 -381.802989) (xy 310.377113 -381.756366) (xy 310.37108 -381.708602) (xy 310.370728 -381.68453)
			(xy 310.371214 -381.657279) (xy 310.37897 -381.603331) (xy 310.394325 -381.551036) (xy 310.416967 -381.501459)
			(xy 310.446433 -381.455609) (xy 310.482124 -381.414418) (xy 310.523315 -381.378727) (xy 310.569165 -381.349261)
			(xy 310.618742 -381.326619) (xy 310.671037 -381.311264) (xy 310.724985 -381.303508) (xy 310.779487 -381.303508)
			(xy 310.833435 -381.311264) (xy 310.88573 -381.326619) (xy 310.935307 -381.349261) (xy 310.981157 -381.378727)
			(xy 311.022348 -381.414418) (xy 311.058039 -381.455609) (xy 311.087505 -381.501459) (xy 311.110147 -381.551036)
			(xy 311.125502 -381.603331) (xy 311.133258 -381.657279) (xy 311.133744 -381.68453) (xy 311.13318 -381.713967)
			(xy 311.124125 -381.77214) (xy 311.11571 -381.800354) (xy 311.113345 -381.808963) (xy 311.114119 -381.826786)
			(xy 311.117234 -381.835152) (xy 311.129172 -381.863346) (xy 311.132988 -381.871583) (xy 311.145361 -381.884854)
			(xy 311.153302 -381.889254) (xy 311.178994 -381.902425) (xy 311.227501 -381.93374) (xy 311.250076 -381.951738)
			(xy 311.257079 -381.957003) (xy 311.273579 -381.962852) (xy 311.282334 -381.963168) (xy 311.436258 -381.963168)
			(xy 311.445008 -381.962837) (xy 311.461499 -381.956978) (xy 311.468516 -381.951738) (xy 311.491099 -381.933751)
			(xy 311.539604 -381.902435) (xy 311.56529 -381.889254) (xy 311.573224 -381.884843) (xy 311.585592 -381.871576)
			(xy 311.58942 -381.863346) (xy 311.601358 -381.835152) (xy 311.604377 -381.826763) (xy 311.605172 -381.808969)
			(xy 311.602882 -381.800354) (xy 311.594455 -381.772142) (xy 311.585394 -381.713968) (xy 311.584848 -381.68453)
			(xy 311.585334 -381.657279) (xy 311.59309 -381.603331) (xy 311.608445 -381.551036) (xy 311.631087 -381.501459)
			(xy 311.660553 -381.455609) (xy 311.696244 -381.414418) (xy 311.737435 -381.378727) (xy 311.783285 -381.349261)
			(xy 311.832862 -381.326619) (xy 311.885157 -381.311264) (xy 311.939105 -381.303508) (xy 311.993607 -381.303508)
			(xy 312.047555 -381.311264) (xy 312.09985 -381.326619) (xy 312.149427 -381.349261) (xy 312.195277 -381.378727)
			(xy 312.236468 -381.414418) (xy 312.272159 -381.455609) (xy 312.301625 -381.501459) (xy 312.324267 -381.551036)
			(xy 312.339622 -381.603331) (xy 312.347378 -381.657279) (xy 312.347864 -381.68453) (xy 312.347502 -381.708601)
			(xy 312.341465 -381.756364) (xy 312.329476 -381.80299) (xy 312.32094 -381.8255) (xy 312.31586 -381.837946)
			(xy 312.319162 -381.863854) (xy 312.385964 -381.954532) (xy 312.409586 -381.965454) (xy 312.422794 -381.964438)
			(xy 312.451496 -381.963422) (xy 312.478751 -381.963825) (xy 312.532707 -381.971582) (xy 312.585009 -381.986939)
			(xy 312.634594 -382.009583) (xy 312.680451 -382.039053) (xy 312.721648 -382.074749) (xy 312.757345 -382.115946)
			(xy 312.786815 -382.161803) (xy 312.80946 -382.211387) (xy 312.824817 -382.263689) (xy 312.832575 -382.317645)
			(xy 312.832575 -382.372149) (xy 316.693308 -382.372149) (xy 316.693308 -382.317651) (xy 316.701064 -382.263708)
			(xy 316.716418 -382.211418) (xy 316.739057 -382.161845) (xy 316.76852 -382.115998) (xy 316.804209 -382.074811)
			(xy 316.845395 -382.039123) (xy 316.891241 -382.009659) (xy 316.940814 -381.987019) (xy 316.993104 -381.971665)
			(xy 317.047047 -381.963908) (xy 317.074296 -381.963422) (xy 317.102998 -381.964438) (xy 317.116206 -381.965454)
			(xy 317.139828 -381.954532) (xy 317.20663 -381.863854) (xy 317.209932 -381.837946) (xy 317.204852 -381.8255)
			(xy 317.196317 -381.802989) (xy 317.184313 -381.756366) (xy 317.17828 -381.708602) (xy 317.177928 -381.68453)
			(xy 317.178414 -381.657279) (xy 317.18617 -381.603331) (xy 317.201525 -381.551036) (xy 317.224167 -381.501459)
			(xy 317.253633 -381.455609) (xy 317.289324 -381.414418) (xy 317.330515 -381.378727) (xy 317.376365 -381.349261)
			(xy 317.425942 -381.326619) (xy 317.478237 -381.311264) (xy 317.532185 -381.303508) (xy 317.586687 -381.303508)
			(xy 317.640635 -381.311264) (xy 317.69293 -381.326619) (xy 317.742507 -381.349261) (xy 317.788357 -381.378727)
			(xy 317.829548 -381.414418) (xy 317.865239 -381.455609) (xy 317.894705 -381.501459) (xy 317.917347 -381.551036)
			(xy 317.932702 -381.603331) (xy 317.940458 -381.657279) (xy 317.940944 -381.68453) (xy 317.94038 -381.713967)
			(xy 317.931325 -381.77214) (xy 317.92291 -381.800354) (xy 317.920545 -381.808963) (xy 317.921319 -381.826786)
			(xy 317.924434 -381.835152) (xy 317.936372 -381.863346) (xy 317.940188 -381.871583) (xy 317.952561 -381.884854)
			(xy 317.960502 -381.889254) (xy 317.986194 -381.902425) (xy 318.034701 -381.93374) (xy 318.057276 -381.951738)
			(xy 318.064279 -381.957003) (xy 318.080779 -381.962852) (xy 318.089534 -381.963168) (xy 318.243458 -381.963168)
			(xy 318.252208 -381.962837) (xy 318.268699 -381.956978) (xy 318.275716 -381.951738) (xy 318.298299 -381.933751)
			(xy 318.346804 -381.902435) (xy 318.37249 -381.889254) (xy 318.380424 -381.884843) (xy 318.392792 -381.871576)
			(xy 318.39662 -381.863346) (xy 318.408558 -381.835152) (xy 318.411577 -381.826763) (xy 318.412372 -381.808969)
			(xy 318.410082 -381.800354) (xy 318.401655 -381.772142) (xy 318.392594 -381.713968) (xy 318.392048 -381.68453)
			(xy 318.392534 -381.657279) (xy 318.40029 -381.603331) (xy 318.415645 -381.551036) (xy 318.438287 -381.501459)
			(xy 318.467753 -381.455609) (xy 318.503444 -381.414418) (xy 318.544635 -381.378727) (xy 318.590485 -381.349261)
			(xy 318.640062 -381.326619) (xy 318.692357 -381.311264) (xy 318.746305 -381.303508) (xy 318.800807 -381.303508)
			(xy 318.854755 -381.311264) (xy 318.90705 -381.326619) (xy 318.956627 -381.349261) (xy 319.002477 -381.378727)
			(xy 319.043668 -381.414418) (xy 319.079359 -381.455609) (xy 319.108825 -381.501459) (xy 319.131467 -381.551036)
			(xy 319.146822 -381.603331) (xy 319.154578 -381.657279) (xy 319.155064 -381.68453) (xy 319.154702 -381.708601)
			(xy 319.148665 -381.756364) (xy 319.136676 -381.80299) (xy 319.12814 -381.8255) (xy 319.12306 -381.837946)
			(xy 319.126362 -381.863854) (xy 319.193164 -381.954532) (xy 319.216786 -381.965454) (xy 319.229994 -381.964438)
			(xy 319.258696 -381.963422) (xy 319.285951 -381.963825) (xy 319.339907 -381.971582) (xy 319.392209 -381.986939)
			(xy 319.441794 -382.009583) (xy 319.487651 -382.039053) (xy 319.528848 -382.074749) (xy 319.564545 -382.115946)
			(xy 319.594015 -382.161803) (xy 319.61666 -382.211387) (xy 319.632017 -382.263689) (xy 319.639775 -382.317645)
			(xy 319.639775 -382.372155) (xy 319.632017 -382.426111) (xy 319.61666 -382.478413) (xy 319.594015 -382.527997)
			(xy 319.564545 -382.573854) (xy 319.528848 -382.615051) (xy 319.487651 -382.650747) (xy 319.441794 -382.680217)
			(xy 319.392209 -382.702861) (xy 319.339907 -382.718218) (xy 319.285951 -382.725975) (xy 319.258696 -382.726438)
			(xy 319.229994 -382.725422) (xy 319.216786 -382.724406) (xy 319.193164 -382.735328) (xy 319.126362 -382.826006)
			(xy 319.12306 -382.851914) (xy 319.12814 -382.86436) (xy 319.136692 -382.886865) (xy 319.14869 -382.933491)
			(xy 319.154716 -382.981257) (xy 319.155064 -383.00533) (xy 319.154578 -383.032581) (xy 319.146822 -383.086529)
			(xy 319.131467 -383.138824) (xy 319.108825 -383.188401) (xy 319.079359 -383.234251) (xy 319.043668 -383.275442)
			(xy 319.002477 -383.311133) (xy 318.956627 -383.340599) (xy 318.90705 -383.363241) (xy 318.854755 -383.378596)
			(xy 318.800807 -383.386352) (xy 318.746305 -383.386352) (xy 318.692357 -383.378596) (xy 318.640062 -383.363241)
			(xy 318.590485 -383.340599) (xy 318.544635 -383.311133) (xy 318.503444 -383.275442) (xy 318.467753 -383.234251)
			(xy 318.438287 -383.188401) (xy 318.415645 -383.138824) (xy 318.40029 -383.086529) (xy 318.392534 -383.032581)
			(xy 318.392048 -383.00533) (xy 318.392603 -382.975893) (xy 318.401664 -382.917719) (xy 318.410082 -382.889506)
			(xy 318.412462 -382.880901) (xy 318.411676 -382.863075) (xy 318.408558 -382.854708) (xy 318.39662 -382.826514)
			(xy 318.392787 -382.818286) (xy 318.380427 -382.805009) (xy 318.37249 -382.800606) (xy 318.346795 -382.787439)
			(xy 318.29829 -382.756121) (xy 318.275716 -382.738122) (xy 318.268718 -382.732849) (xy 318.252214 -382.727006)
			(xy 318.243458 -382.726692) (xy 318.089534 -382.726692) (xy 318.080784 -382.727028) (xy 318.064293 -382.732884)
			(xy 318.057276 -382.738122) (xy 318.034698 -382.756115) (xy 317.98619 -382.787427) (xy 317.960502 -382.800606)
			(xy 317.952553 -382.804994) (xy 317.940192 -382.818277) (xy 317.936372 -382.826514) (xy 317.924434 -382.854708)
			(xy 317.921385 -382.863088) (xy 317.92061 -382.88089) (xy 317.92291 -382.889506) (xy 317.931352 -382.917713)
			(xy 317.940403 -382.975891) (xy 317.940944 -383.00533) (xy 317.940458 -383.032581) (xy 317.932702 -383.086529)
			(xy 317.917347 -383.138824) (xy 317.894705 -383.188401) (xy 317.865239 -383.234251) (xy 317.829548 -383.275442)
			(xy 317.788357 -383.311133) (xy 317.742507 -383.340599) (xy 317.69293 -383.363241) (xy 317.640635 -383.378596)
			(xy 317.586687 -383.386352) (xy 317.532185 -383.386352) (xy 317.478237 -383.378596) (xy 317.425942 -383.363241)
			(xy 317.376365 -383.340599) (xy 317.330515 -383.311133) (xy 317.289324 -383.275442) (xy 317.253633 -383.234251)
			(xy 317.224167 -383.188401) (xy 317.201525 -383.138824) (xy 317.18617 -383.086529) (xy 317.178414 -383.032581)
			(xy 317.177928 -383.00533) (xy 317.178278 -382.981258) (xy 317.18432 -382.933495) (xy 317.196314 -382.88687)
			(xy 317.204852 -382.86436) (xy 317.209932 -382.851914) (xy 317.20663 -382.826006) (xy 317.139828 -382.735328)
			(xy 317.116206 -382.724406) (xy 317.102998 -382.725422) (xy 317.074296 -382.726438) (xy 317.047047 -382.725892)
			(xy 316.993104 -382.718135) (xy 316.940814 -382.702781) (xy 316.891241 -382.680141) (xy 316.845395 -382.650677)
			(xy 316.804209 -382.614989) (xy 316.76852 -382.573802) (xy 316.739057 -382.527955) (xy 316.716418 -382.478382)
			(xy 316.701064 -382.426092) (xy 316.693308 -382.372149) (xy 312.832575 -382.372149) (xy 312.832575 -382.372155)
			(xy 312.824817 -382.426111) (xy 312.80946 -382.478413) (xy 312.786815 -382.527997) (xy 312.757345 -382.573854)
			(xy 312.721648 -382.615051) (xy 312.680451 -382.650747) (xy 312.634594 -382.680217) (xy 312.585009 -382.702861)
			(xy 312.532707 -382.718218) (xy 312.478751 -382.725975) (xy 312.451496 -382.726438) (xy 312.422794 -382.725422)
			(xy 312.409586 -382.724406) (xy 312.385964 -382.735328) (xy 312.319162 -382.826006) (xy 312.31586 -382.851914)
			(xy 312.32094 -382.86436) (xy 312.329492 -382.886865) (xy 312.34149 -382.933491) (xy 312.347516 -382.981257)
			(xy 312.347864 -383.00533) (xy 312.347378 -383.032581) (xy 312.339622 -383.086529) (xy 312.324267 -383.138824)
			(xy 312.301625 -383.188401) (xy 312.272159 -383.234251) (xy 312.236468 -383.275442) (xy 312.195277 -383.311133)
			(xy 312.149427 -383.340599) (xy 312.09985 -383.363241) (xy 312.047555 -383.378596) (xy 311.993607 -383.386352)
			(xy 311.939105 -383.386352) (xy 311.885157 -383.378596) (xy 311.832862 -383.363241) (xy 311.783285 -383.340599)
			(xy 311.737435 -383.311133) (xy 311.696244 -383.275442) (xy 311.660553 -383.234251) (xy 311.631087 -383.188401)
			(xy 311.608445 -383.138824) (xy 311.59309 -383.086529) (xy 311.585334 -383.032581) (xy 311.584848 -383.00533)
			(xy 311.585403 -382.975893) (xy 311.594464 -382.917719) (xy 311.602882 -382.889506) (xy 311.605262 -382.880901)
			(xy 311.604476 -382.863075) (xy 311.601358 -382.854708) (xy 311.58942 -382.826514) (xy 311.585587 -382.818286)
			(xy 311.573227 -382.805009) (xy 311.56529 -382.800606) (xy 311.539595 -382.787439) (xy 311.49109 -382.756121)
			(xy 311.468516 -382.738122) (xy 311.461518 -382.732849) (xy 311.445014 -382.727006) (xy 311.436258 -382.726692)
			(xy 311.282334 -382.726692) (xy 311.273584 -382.727028) (xy 311.257093 -382.732884) (xy 311.250076 -382.738122)
			(xy 311.227498 -382.756115) (xy 311.17899 -382.787427) (xy 311.153302 -382.800606) (xy 311.145353 -382.804994)
			(xy 311.132992 -382.818277) (xy 311.129172 -382.826514) (xy 311.117234 -382.854708) (xy 311.114185 -382.863088)
			(xy 311.11341 -382.88089) (xy 311.11571 -382.889506) (xy 311.124152 -382.917713) (xy 311.133203 -382.975891)
			(xy 311.133744 -383.00533) (xy 311.133258 -383.032581) (xy 311.125502 -383.086529) (xy 311.110147 -383.138824)
			(xy 311.087505 -383.188401) (xy 311.058039 -383.234251) (xy 311.022348 -383.275442) (xy 310.981157 -383.311133)
			(xy 310.935307 -383.340599) (xy 310.88573 -383.363241) (xy 310.833435 -383.378596) (xy 310.779487 -383.386352)
			(xy 310.724985 -383.386352) (xy 310.671037 -383.378596) (xy 310.618742 -383.363241) (xy 310.569165 -383.340599)
			(xy 310.523315 -383.311133) (xy 310.482124 -383.275442) (xy 310.446433 -383.234251) (xy 310.416967 -383.188401)
			(xy 310.394325 -383.138824) (xy 310.37897 -383.086529) (xy 310.371214 -383.032581) (xy 310.370728 -383.00533)
			(xy 310.371078 -382.981258) (xy 310.37712 -382.933495) (xy 310.389114 -382.88687) (xy 310.397652 -382.86436)
			(xy 310.402732 -382.851914) (xy 310.39943 -382.826006) (xy 310.332628 -382.735328) (xy 310.309006 -382.724406)
			(xy 310.295798 -382.725422) (xy 310.267096 -382.726438) (xy 310.239847 -382.725892) (xy 310.185904 -382.718135)
			(xy 310.133614 -382.702781) (xy 310.084041 -382.680141) (xy 310.038195 -382.650677) (xy 309.997009 -382.614989)
			(xy 309.96132 -382.573802) (xy 309.931857 -382.527955) (xy 309.909218 -382.478382) (xy 309.893864 -382.426092)
			(xy 309.886108 -382.372149) (xy 306.025375 -382.372149) (xy 306.025375 -382.372155) (xy 306.017617 -382.426111)
			(xy 306.00226 -382.478413) (xy 305.979615 -382.527997) (xy 305.950145 -382.573854) (xy 305.914448 -382.615051)
			(xy 305.873251 -382.650747) (xy 305.827394 -382.680217) (xy 305.777809 -382.702861) (xy 305.725507 -382.718218)
			(xy 305.671551 -382.725975) (xy 305.644296 -382.726438) (xy 305.615594 -382.725422) (xy 305.602386 -382.724406)
			(xy 305.578764 -382.735328) (xy 305.511962 -382.826006) (xy 305.50866 -382.851914) (xy 305.51374 -382.86436)
			(xy 305.522292 -382.886865) (xy 305.53429 -382.933491) (xy 305.540316 -382.981257) (xy 305.540664 -383.00533)
			(xy 305.540178 -383.032581) (xy 305.532422 -383.086529) (xy 305.517067 -383.138824) (xy 305.494425 -383.188401)
			(xy 305.464959 -383.234251) (xy 305.429268 -383.275442) (xy 305.388077 -383.311133) (xy 305.342227 -383.340599)
			(xy 305.29265 -383.363241) (xy 305.240355 -383.378596) (xy 305.186407 -383.386352) (xy 305.131905 -383.386352)
			(xy 305.077957 -383.378596) (xy 305.025662 -383.363241) (xy 304.976085 -383.340599) (xy 304.930235 -383.311133)
			(xy 304.889044 -383.275442) (xy 304.853353 -383.234251) (xy 304.823887 -383.188401) (xy 304.801245 -383.138824)
			(xy 304.78589 -383.086529) (xy 304.778134 -383.032581) (xy 304.777648 -383.00533) (xy 304.778203 -382.975893)
			(xy 304.787264 -382.917719) (xy 304.795682 -382.889506) (xy 304.798062 -382.880901) (xy 304.797276 -382.863075)
			(xy 304.794158 -382.854708) (xy 304.78222 -382.826514) (xy 304.778387 -382.818286) (xy 304.766027 -382.805009)
			(xy 304.75809 -382.800606) (xy 304.732395 -382.787439) (xy 304.68389 -382.756121) (xy 304.661316 -382.738122)
			(xy 304.654318 -382.732849) (xy 304.637814 -382.727006) (xy 304.629058 -382.726692) (xy 304.475134 -382.726692)
			(xy 304.466384 -382.727028) (xy 304.449893 -382.732884) (xy 304.442876 -382.738122) (xy 304.420298 -382.756115)
			(xy 304.37179 -382.787427) (xy 304.346102 -382.800606) (xy 304.338153 -382.804994) (xy 304.325792 -382.818277)
			(xy 304.321972 -382.826514) (xy 304.310034 -382.854708) (xy 304.306985 -382.863088) (xy 304.30621 -382.88089)
			(xy 304.30851 -382.889506) (xy 304.316952 -382.917713) (xy 304.326003 -382.975891) (xy 304.326544 -383.00533)
			(xy 304.326058 -383.032581) (xy 304.318302 -383.086529) (xy 304.302947 -383.138824) (xy 304.280305 -383.188401)
			(xy 304.250839 -383.234251) (xy 304.215148 -383.275442) (xy 304.173957 -383.311133) (xy 304.128107 -383.340599)
			(xy 304.07853 -383.363241) (xy 304.026235 -383.378596) (xy 303.972287 -383.386352) (xy 303.917785 -383.386352)
			(xy 303.863837 -383.378596) (xy 303.811542 -383.363241) (xy 303.761965 -383.340599) (xy 303.716115 -383.311133)
			(xy 303.674924 -383.275442) (xy 303.639233 -383.234251) (xy 303.609767 -383.188401) (xy 303.587125 -383.138824)
			(xy 303.57177 -383.086529) (xy 303.564014 -383.032581) (xy 303.563528 -383.00533) (xy 303.563878 -382.981258)
			(xy 303.56992 -382.933495) (xy 303.581914 -382.88687) (xy 303.590452 -382.86436) (xy 303.595532 -382.851914)
			(xy 303.59223 -382.826006) (xy 303.525428 -382.735328) (xy 303.501806 -382.724406) (xy 303.488598 -382.725422)
			(xy 303.459896 -382.726438) (xy 303.432647 -382.725892) (xy 303.378704 -382.718135) (xy 303.326414 -382.702781)
			(xy 303.276841 -382.680141) (xy 303.230995 -382.650677) (xy 303.189809 -382.614989) (xy 303.15412 -382.573802)
			(xy 303.124657 -382.527955) (xy 303.102018 -382.478382) (xy 303.086664 -382.426092) (xy 303.078908 -382.372149)
			(xy 294.52249 -382.372149) (xy 294.626192 -382.521586) (xy 294.724953 -382.677957) (xy 294.816848 -382.83846)
			(xy 294.901704 -383.002792) (xy 294.979362 -383.170647) (xy 295.049675 -383.341707) (xy 295.112512 -383.515653)
			(xy 295.167756 -383.692158) (xy 295.215301 -383.87089) (xy 295.255059 -384.051514) (xy 295.281452 -384.202255)
			(xy 296.388955 -384.202255) (xy 296.388955 -384.147745) (xy 296.396714 -384.09379) (xy 296.412072 -384.041489)
			(xy 296.434718 -383.991906) (xy 296.46419 -383.946051) (xy 296.499888 -383.904857) (xy 296.541086 -383.869163)
			(xy 296.586945 -383.839696) (xy 296.63653 -383.817056) (xy 296.688833 -383.801704) (xy 296.742789 -383.793952)
			(xy 296.770044 -383.793492) (xy 296.794116 -383.793845) (xy 296.841879 -383.799886) (xy 296.888504 -383.811878)
			(xy 296.911014 -383.820416) (xy 296.92346 -383.825496) (xy 296.949368 -383.822194) (xy 297.040046 -383.755392)
			(xy 297.050968 -383.73177) (xy 297.049952 -383.718562) (xy 297.048936 -383.68986) (xy 297.049422 -383.662609)
			(xy 297.057178 -383.608661) (xy 297.072533 -383.556366) (xy 297.095175 -383.506789) (xy 297.124641 -383.460939)
			(xy 297.160332 -383.419748) (xy 297.201523 -383.384057) (xy 297.247373 -383.354591) (xy 297.29695 -383.331949)
			(xy 297.349245 -383.316594) (xy 297.403193 -383.308838) (xy 297.457695 -383.308838) (xy 297.511643 -383.316594)
			(xy 297.563938 -383.331949) (xy 297.613515 -383.354591) (xy 297.659365 -383.384057) (xy 297.700556 -383.419748)
			(xy 297.736247 -383.460939) (xy 297.765713 -383.506789) (xy 297.788355 -383.556366) (xy 297.80371 -383.608661)
			(xy 297.811466 -383.662609) (xy 297.811952 -383.68986) (xy 297.810936 -383.718562) (xy 297.80992 -383.73177)
			(xy 297.820842 -383.755392) (xy 297.91152 -383.822194) (xy 297.937428 -383.825496) (xy 297.949874 -383.820416)
			(xy 297.972379 -383.811863) (xy 298.019005 -383.799864) (xy 298.066771 -383.793839) (xy 298.090844 -383.793492)
			(xy 298.118093 -383.793981) (xy 298.172036 -383.801742) (xy 298.224326 -383.817101) (xy 298.273897 -383.839745)
			(xy 298.319742 -383.869212) (xy 298.360927 -383.904904) (xy 298.396614 -383.946093) (xy 298.426076 -383.991941)
			(xy 298.448714 -384.041516) (xy 298.464067 -384.093807) (xy 298.471822 -384.147751) (xy 298.471822 -384.202249)
			(xy 298.464067 -384.256193) (xy 298.448714 -384.308484) (xy 298.440144 -384.327252) (xy 326.236046 -384.327252)
			(xy 326.236046 -384.272748) (xy 326.243802 -384.218797) (xy 326.259158 -384.1665) (xy 326.281799 -384.11692)
			(xy 326.311265 -384.071067) (xy 326.346957 -384.029874) (xy 326.388148 -383.99418) (xy 326.433999 -383.96471)
			(xy 326.483578 -383.942066) (xy 326.535874 -383.926707) (xy 326.589824 -383.918947) (xy 326.617076 -383.91846)
			(xy 326.641148 -383.918806) (xy 326.688911 -383.92485) (xy 326.735537 -383.936845) (xy 326.758046 -383.945384)
			(xy 326.770492 -383.950464) (xy 326.7964 -383.947162) (xy 326.887078 -383.88036) (xy 326.898 -383.856738)
			(xy 326.896984 -383.84353) (xy 326.895968 -383.814828) (xy 326.896454 -383.787577) (xy 326.90421 -383.733629)
			(xy 326.919565 -383.681334) (xy 326.942207 -383.631757) (xy 326.971673 -383.585907) (xy 327.007364 -383.544716)
			(xy 327.048555 -383.509025) (xy 327.094405 -383.479559) (xy 327.143982 -383.456917) (xy 327.196277 -383.441562)
			(xy 327.250225 -383.433806) (xy 327.304727 -383.433806) (xy 327.358675 -383.441562) (xy 327.41097 -383.456917)
			(xy 327.460547 -383.479559) (xy 327.506397 -383.509025) (xy 327.547588 -383.544716) (xy 327.583279 -383.585907)
			(xy 327.612745 -383.631757) (xy 327.635387 -383.681334) (xy 327.650742 -383.733629) (xy 327.658498 -383.787577)
			(xy 327.658984 -383.814828) (xy 327.657968 -383.84353) (xy 327.656952 -383.856738) (xy 327.667874 -383.88036)
			(xy 327.758552 -383.947162) (xy 327.78446 -383.950464) (xy 327.796906 -383.945384) (xy 327.819417 -383.936849)
			(xy 327.86604 -383.924844) (xy 327.913804 -383.918811) (xy 327.937876 -383.91846) (xy 327.965128 -383.918986)
			(xy 328.019077 -383.926739) (xy 328.071373 -383.942092) (xy 328.120952 -383.964731) (xy 328.166804 -383.994196)
			(xy 328.207996 -384.029887) (xy 328.24369 -384.071076) (xy 328.273157 -384.116927) (xy 328.2958 -384.166504)
			(xy 328.311156 -384.2188) (xy 328.318913 -384.272748) (xy 328.318913 -384.327252) (xy 328.311156 -384.3812)
			(xy 328.2958 -384.433496) (xy 328.273157 -384.483073) (xy 328.24369 -384.528924) (xy 328.207996 -384.570113)
			(xy 328.166804 -384.605804) (xy 328.120952 -384.635269) (xy 328.071373 -384.657908) (xy 328.019077 -384.673261)
			(xy 327.965128 -384.681014) (xy 327.937876 -384.681476) (xy 327.908439 -384.680909) (xy 327.850266 -384.671856)
			(xy 327.822052 -384.663442) (xy 327.813442 -384.661084) (xy 327.79562 -384.661855) (xy 327.787254 -384.664966)
			(xy 327.75906 -384.676904) (xy 327.750818 -384.680711) (xy 327.737549 -384.693089) (xy 327.733152 -384.701034)
			(xy 327.719984 -384.726728) (xy 327.688667 -384.775234) (xy 327.670668 -384.797808) (xy 327.665366 -384.804804)
			(xy 327.659394 -384.821298) (xy 327.658984 -384.830066) (xy 327.658984 -384.98399) (xy 327.659353 -384.992766)
			(xy 327.665333 -385.009269) (xy 327.670668 -385.016248) (xy 327.688648 -385.038836) (xy 327.719969 -385.087338)
			(xy 327.733152 -385.113022) (xy 327.737552 -385.120963) (xy 327.750827 -385.133327) (xy 327.75906 -385.137152)
			(xy 327.787254 -385.14909) (xy 327.795642 -385.152112) (xy 327.813437 -385.152903) (xy 327.822052 -385.150614)
			(xy 327.850263 -385.142184) (xy 327.908438 -385.133125) (xy 327.937876 -385.13258) (xy 327.965129 -385.133066)
			(xy 328.019081 -385.14082) (xy 328.07138 -385.156173) (xy 328.120962 -385.178814) (xy 328.166816 -385.20828)
			(xy 328.208011 -385.243972) (xy 328.243706 -385.285164) (xy 328.273175 -385.331017) (xy 328.295819 -385.380597)
			(xy 328.311175 -385.432896) (xy 328.318933 -385.486847) (xy 328.318933 -385.541353) (xy 328.311175 -385.595304)
			(xy 328.295819 -385.647603) (xy 328.273175 -385.697183) (xy 328.243706 -385.743036) (xy 328.208011 -385.784228)
			(xy 328.166816 -385.81992) (xy 328.120962 -385.849386) (xy 328.07138 -385.872027) (xy 328.019081 -385.88738)
			(xy 327.965129 -385.895134) (xy 327.937876 -385.895596) (xy 327.913805 -385.89523) (xy 327.866042 -385.889194)
			(xy 327.819416 -385.877207) (xy 327.796906 -385.868672) (xy 327.78446 -385.863592) (xy 327.758552 -385.866894)
			(xy 327.667874 -385.933696) (xy 327.656952 -385.957318) (xy 327.657968 -385.970526) (xy 327.658984 -385.999228)
			(xy 327.658498 -386.026479) (xy 327.650742 -386.080427) (xy 327.635387 -386.132722) (xy 327.612745 -386.182299)
			(xy 327.583279 -386.228149) (xy 327.547588 -386.26934) (xy 327.506397 -386.305031) (xy 327.460547 -386.334497)
			(xy 327.41097 -386.357139) (xy 327.358675 -386.372494) (xy 327.304727 -386.38025) (xy 327.250225 -386.38025)
			(xy 327.196277 -386.372494) (xy 327.143982 -386.357139) (xy 327.094405 -386.334497) (xy 327.048555 -386.305031)
			(xy 327.007364 -386.26934) (xy 326.971673 -386.228149) (xy 326.942207 -386.182299) (xy 326.919565 -386.132722)
			(xy 326.90421 -386.080427) (xy 326.896454 -386.026479) (xy 326.895968 -385.999228) (xy 326.896984 -385.970526)
			(xy 326.898 -385.957318) (xy 326.887078 -385.933696) (xy 326.7964 -385.866894) (xy 326.770492 -385.863592)
			(xy 326.758046 -385.868672) (xy 326.735541 -385.877224) (xy 326.688915 -385.889221) (xy 326.641149 -385.895248)
			(xy 326.617076 -385.895596) (xy 326.589825 -385.895133) (xy 326.535878 -385.887373) (xy 326.483585 -385.872015)
			(xy 326.434009 -385.849372) (xy 326.38816 -385.819904) (xy 326.346971 -385.784212) (xy 326.311281 -385.743021)
			(xy 326.281816 -385.69717) (xy 326.259176 -385.647593) (xy 326.243822 -385.595298) (xy 326.236066 -385.541351)
			(xy 326.236066 -385.486849) (xy 326.243822 -385.432902) (xy 326.259176 -385.380607) (xy 326.281816 -385.33103)
			(xy 326.311281 -385.285179) (xy 326.346971 -385.243988) (xy 326.38816 -385.208296) (xy 326.434009 -385.178828)
			(xy 326.483585 -385.156185) (xy 326.535878 -385.140827) (xy 326.589825 -385.133067) (xy 326.617076 -385.13258)
			(xy 326.646513 -385.133137) (xy 326.704686 -385.142197) (xy 326.7329 -385.150614) (xy 326.741504 -385.153001)
			(xy 326.759332 -385.152212) (xy 326.767698 -385.14909) (xy 326.795892 -385.137152) (xy 326.804115 -385.13331)
			(xy 326.817394 -385.120956) (xy 326.8218 -385.113022) (xy 326.83497 -385.087329) (xy 326.866286 -385.038823)
			(xy 326.884284 -385.016248) (xy 326.889569 -385.009241) (xy 326.895549 -384.992756) (xy 326.895968 -384.98399)
			(xy 326.895968 -384.830066) (xy 326.895609 -384.821289) (xy 326.88962 -384.804787) (xy 326.884284 -384.797808)
			(xy 326.866295 -384.775226) (xy 326.83498 -384.726721) (xy 326.8218 -384.701034) (xy 326.817401 -384.693092)
			(xy 326.804126 -384.680727) (xy 326.795892 -384.676904) (xy 326.767698 -384.664966) (xy 326.759317 -384.661919)
			(xy 326.741516 -384.661142) (xy 326.7329 -384.663442) (xy 326.704692 -384.671881) (xy 326.646515 -384.680934)
			(xy 326.617076 -384.681476) (xy 326.589824 -384.681053) (xy 326.535874 -384.673293) (xy 326.483578 -384.657934)
			(xy 326.433999 -384.63529) (xy 326.388148 -384.60582) (xy 326.346957 -384.570126) (xy 326.311265 -384.528933)
			(xy 326.281799 -384.48308) (xy 326.259158 -384.4335) (xy 326.243802 -384.381203) (xy 326.236046 -384.327252)
			(xy 298.440144 -384.327252) (xy 298.426076 -384.358059) (xy 298.396614 -384.403907) (xy 298.360927 -384.445096)
			(xy 298.319742 -384.480788) (xy 298.273897 -384.510255) (xy 298.224326 -384.532899) (xy 298.172036 -384.548258)
			(xy 298.118093 -384.556019) (xy 298.090844 -384.556508) (xy 298.061407 -384.555947) (xy 298.003234 -384.54689)
			(xy 297.97502 -384.538474) (xy 297.966414 -384.536098) (xy 297.948588 -384.53688) (xy 297.940222 -384.539998)
			(xy 297.912028 -384.551936) (xy 297.90381 -384.555788) (xy 297.890529 -384.568135) (xy 297.88612 -384.576066)
			(xy 297.872947 -384.601757) (xy 297.841633 -384.650265) (xy 297.823636 -384.67284) (xy 297.818317 -384.679824)
			(xy 297.812357 -384.696327) (xy 297.811952 -384.705098) (xy 297.811952 -384.859022) (xy 297.812312 -384.867799)
			(xy 297.8183 -384.884301) (xy 297.823636 -384.89128) (xy 297.841625 -384.913862) (xy 297.87294 -384.962367)
			(xy 297.88612 -384.988054) (xy 297.890522 -384.995993) (xy 297.903796 -385.008358) (xy 297.912028 -385.012184)
			(xy 297.940222 -385.024122) (xy 297.9486 -385.027177) (xy 297.966404 -385.027946) (xy 297.97502 -385.025646)
			(xy 298.003233 -385.017224) (xy 298.061406 -385.00816) (xy 298.090844 -385.007612) (xy 298.118095 -385.008061)
			(xy 298.17204 -385.015823) (xy 298.224333 -385.031183) (xy 298.273907 -385.053827) (xy 298.319754 -385.083296)
			(xy 298.360941 -385.11899) (xy 298.39663 -385.160181) (xy 298.426094 -385.206032) (xy 298.448733 -385.255609)
			(xy 298.464087 -385.307903) (xy 298.471842 -385.361849) (xy 298.471842 -385.416351) (xy 298.464087 -385.470297)
			(xy 298.448733 -385.522591) (xy 298.426094 -385.572168) (xy 298.39663 -385.618019) (xy 298.360941 -385.65921)
			(xy 298.319754 -385.694904) (xy 298.273907 -385.724373) (xy 298.224333 -385.747017) (xy 298.17204 -385.762377)
			(xy 298.118095 -385.770139) (xy 298.090844 -385.770628) (xy 298.066772 -385.770277) (xy 298.019009 -385.764235)
			(xy 297.972384 -385.752242) (xy 297.949874 -385.743704) (xy 297.937428 -385.738624) (xy 297.91152 -385.741926)
			(xy 297.820842 -385.808728) (xy 297.80992 -385.83235) (xy 297.810936 -385.845558) (xy 297.811952 -385.87426)
			(xy 297.811466 -385.901511) (xy 297.80371 -385.955459) (xy 297.788355 -386.007754) (xy 297.765713 -386.057331)
			(xy 297.736247 -386.103181) (xy 297.700556 -386.144372) (xy 297.659365 -386.180063) (xy 297.613515 -386.209529)
			(xy 297.563938 -386.232171) (xy 297.511643 -386.247526) (xy 297.457695 -386.255282) (xy 297.403193 -386.255282)
			(xy 297.349245 -386.247526) (xy 297.29695 -386.232171) (xy 297.247373 -386.209529) (xy 297.201523 -386.180063)
			(xy 297.160332 -386.144372) (xy 297.124641 -386.103181) (xy 297.095175 -386.057331) (xy 297.072533 -386.007754)
			(xy 297.057178 -385.955459) (xy 297.049422 -385.901511) (xy 297.048936 -385.87426) (xy 297.049952 -385.845558)
			(xy 297.050968 -385.83235) (xy 297.040046 -385.808728) (xy 296.949368 -385.741926) (xy 296.92346 -385.738624)
			(xy 296.911014 -385.743704) (xy 296.888511 -385.752262) (xy 296.841884 -385.764258) (xy 296.794117 -385.770282)
			(xy 296.770044 -385.770628) (xy 296.742791 -385.770128) (xy 296.688838 -385.762376) (xy 296.636537 -385.747025)
			(xy 296.586954 -385.724386) (xy 296.541098 -385.694921) (xy 296.499902 -385.659229) (xy 296.464206 -385.618037)
			(xy 296.434735 -385.572184) (xy 296.412091 -385.522604) (xy 296.396733 -385.470305) (xy 296.388975 -385.416353)
			(xy 296.388975 -385.361847) (xy 296.396733 -385.307895) (xy 296.412091 -385.255596) (xy 296.434735 -385.206016)
			(xy 296.464206 -385.160163) (xy 296.499902 -385.118971) (xy 296.541098 -385.083279) (xy 296.586954 -385.053814)
			(xy 296.636537 -385.031175) (xy 296.688838 -385.015824) (xy 296.742791 -385.008072) (xy 296.770044 -385.007612)
			(xy 296.799481 -385.008175) (xy 296.857654 -385.017231) (xy 296.885868 -385.025646) (xy 296.894476 -385.028015)
			(xy 296.9123 -385.027237) (xy 296.920666 -385.024122) (xy 296.94886 -385.012184) (xy 296.957091 -385.008355)
			(xy 296.970367 -384.995993) (xy 296.974768 -384.988054) (xy 296.987932 -384.962358) (xy 297.019252 -384.913854)
			(xy 297.037252 -384.89128) (xy 297.042561 -384.884289) (xy 297.048528 -384.867791) (xy 297.048936 -384.859022)
			(xy 297.048936 -384.705098) (xy 297.048569 -384.696321) (xy 297.042587 -384.679819) (xy 297.037252 -384.67284)
			(xy 297.019272 -384.650252) (xy 296.987951 -384.601751) (xy 296.974768 -384.576066) (xy 296.970365 -384.568128)
			(xy 296.957092 -384.555762) (xy 296.94886 -384.551936) (xy 296.920666 -384.539998) (xy 296.91229 -384.536937)
			(xy 296.894485 -384.536171) (xy 296.885868 -384.538474) (xy 296.857656 -384.546899) (xy 296.799482 -384.555961)
			(xy 296.770044 -384.556508) (xy 296.742789 -384.556048) (xy 296.688833 -384.548296) (xy 296.63653 -384.532944)
			(xy 296.586945 -384.510304) (xy 296.541086 -384.480837) (xy 296.499888 -384.445143) (xy 296.46419 -384.403949)
			(xy 296.434718 -384.358094) (xy 296.412072 -384.308511) (xy 296.396714 -384.25621) (xy 296.388955 -384.202255)
			(xy 295.281452 -384.202255) (xy 295.286956 -384.233691) (xy 295.310931 -384.417078) (xy 295.326939 -384.601332)
			(xy 295.334951 -384.786106) (xy 295.335452 -384.87858) (xy 295.334951 -384.971054) (xy 295.326939 -385.155828)
			(xy 295.310931 -385.340082) (xy 295.286956 -385.523469) (xy 295.255059 -385.705646) (xy 295.215301 -385.88627)
			(xy 295.167756 -386.065002) (xy 295.112512 -386.241507) (xy 295.049675 -386.415453) (xy 294.979362 -386.586513)
			(xy 294.901704 -386.754368) (xy 294.816848 -386.9187) (xy 294.724953 -387.079203) (xy 294.626192 -387.235574)
			(xy 294.520749 -387.38752) (xy 294.408823 -387.534755) (xy 294.290625 -387.677004) (xy 294.241787 -387.730852)
			(xy 326.236046 -387.730852) (xy 326.236046 -387.676348) (xy 326.243802 -387.622397) (xy 326.259158 -387.5701)
			(xy 326.281799 -387.52052) (xy 326.311265 -387.474667) (xy 326.346957 -387.433474) (xy 326.388148 -387.39778)
			(xy 326.433999 -387.36831) (xy 326.483578 -387.345666) (xy 326.535874 -387.330307) (xy 326.589824 -387.322547)
			(xy 326.617076 -387.32206) (xy 326.641148 -387.322406) (xy 326.688911 -387.32845) (xy 326.735537 -387.340445)
			(xy 326.758046 -387.348984) (xy 326.770492 -387.354064) (xy 326.7964 -387.350762) (xy 326.887078 -387.28396)
			(xy 326.898 -387.260338) (xy 326.896984 -387.24713) (xy 326.895968 -387.218428) (xy 326.896454 -387.191177)
			(xy 326.90421 -387.137229) (xy 326.919565 -387.084934) (xy 326.942207 -387.035357) (xy 326.971673 -386.989507)
			(xy 327.007364 -386.948316) (xy 327.048555 -386.912625) (xy 327.094405 -386.883159) (xy 327.143982 -386.860517)
			(xy 327.196277 -386.845162) (xy 327.250225 -386.837406) (xy 327.304727 -386.837406) (xy 327.358675 -386.845162)
			(xy 327.41097 -386.860517) (xy 327.460547 -386.883159) (xy 327.506397 -386.912625) (xy 327.547588 -386.948316)
			(xy 327.583279 -386.989507) (xy 327.612745 -387.035357) (xy 327.635387 -387.084934) (xy 327.650742 -387.137229)
			(xy 327.658498 -387.191177) (xy 327.658984 -387.218428) (xy 327.657968 -387.24713) (xy 327.656952 -387.260338)
			(xy 327.667874 -387.28396) (xy 327.758552 -387.350762) (xy 327.78446 -387.354064) (xy 327.796906 -387.348984)
			(xy 327.819417 -387.340449) (xy 327.86604 -387.328444) (xy 327.913804 -387.322411) (xy 327.937876 -387.32206)
			(xy 327.965128 -387.322586) (xy 328.019077 -387.330339) (xy 328.071373 -387.345692) (xy 328.120952 -387.368331)
			(xy 328.166804 -387.397796) (xy 328.207996 -387.433487) (xy 328.24369 -387.474676) (xy 328.273157 -387.520527)
			(xy 328.2958 -387.570104) (xy 328.311156 -387.6224) (xy 328.318913 -387.676348) (xy 328.318913 -387.730852)
			(xy 328.311156 -387.7848) (xy 328.2958 -387.837096) (xy 328.273157 -387.886673) (xy 328.24369 -387.932524)
			(xy 328.207996 -387.973713) (xy 328.166804 -388.009404) (xy 328.120952 -388.038869) (xy 328.071373 -388.061508)
			(xy 328.019077 -388.076861) (xy 327.965128 -388.084614) (xy 327.937876 -388.085076) (xy 327.908439 -388.084509)
			(xy 327.850266 -388.075456) (xy 327.822052 -388.067042) (xy 327.813442 -388.064684) (xy 327.79562 -388.065455)
			(xy 327.787254 -388.068566) (xy 327.75906 -388.080504) (xy 327.750818 -388.084311) (xy 327.737549 -388.096689)
			(xy 327.733152 -388.104634) (xy 327.719984 -388.130328) (xy 327.688667 -388.178834) (xy 327.670668 -388.201408)
			(xy 327.665366 -388.208404) (xy 327.659394 -388.224898) (xy 327.658984 -388.233666) (xy 327.658984 -388.38759)
			(xy 327.659353 -388.396366) (xy 327.665333 -388.412869) (xy 327.670668 -388.419848) (xy 327.688648 -388.442436)
			(xy 327.719969 -388.490938) (xy 327.733152 -388.516622) (xy 327.737552 -388.524563) (xy 327.750827 -388.536927)
			(xy 327.75906 -388.540752) (xy 327.787254 -388.55269) (xy 327.795642 -388.555712) (xy 327.813437 -388.556503)
			(xy 327.822052 -388.554214) (xy 327.850263 -388.545784) (xy 327.908438 -388.536725) (xy 327.937876 -388.53618)
			(xy 327.965129 -388.536666) (xy 328.019081 -388.54442) (xy 328.07138 -388.559773) (xy 328.120962 -388.582414)
			(xy 328.166816 -388.61188) (xy 328.208011 -388.647572) (xy 328.243706 -388.688764) (xy 328.273175 -388.734617)
			(xy 328.295819 -388.784197) (xy 328.311175 -388.836496) (xy 328.318933 -388.890447) (xy 328.318933 -388.944953)
			(xy 328.311175 -388.998904) (xy 328.295819 -389.051203) (xy 328.273175 -389.100783) (xy 328.243706 -389.146636)
			(xy 328.208011 -389.187828) (xy 328.166816 -389.22352) (xy 328.120962 -389.252986) (xy 328.07138 -389.275627)
			(xy 328.019081 -389.29098) (xy 327.965129 -389.298734) (xy 327.937876 -389.299196) (xy 327.913805 -389.29883)
			(xy 327.866042 -389.292794) (xy 327.819416 -389.280807) (xy 327.796906 -389.272272) (xy 327.78446 -389.267192)
			(xy 327.758552 -389.270494) (xy 327.667874 -389.337296) (xy 327.656952 -389.360918) (xy 327.657968 -389.374126)
			(xy 327.658984 -389.402828) (xy 327.658498 -389.430079) (xy 327.650742 -389.484027) (xy 327.635387 -389.536322)
			(xy 327.612745 -389.585899) (xy 327.583279 -389.631749) (xy 327.547588 -389.67294) (xy 327.506397 -389.708631)
			(xy 327.460547 -389.738097) (xy 327.457582 -389.739451) (xy 328.916778 -389.739451) (xy 328.916778 -389.684949)
			(xy 328.924534 -389.631002) (xy 328.939889 -389.578708) (xy 328.962529 -389.529131) (xy 328.991995 -389.483281)
			(xy 329.027686 -389.442091) (xy 329.068875 -389.4064) (xy 329.114724 -389.376933) (xy 329.1643 -389.354292)
			(xy 329.216594 -389.338936) (xy 329.270541 -389.331178) (xy 329.297792 -389.330692) (xy 329.321729 -389.331041)
			(xy 329.36923 -389.337015) (xy 329.415607 -389.348897) (xy 329.438 -389.357362) (xy 329.449938 -389.362188)
			(xy 329.47483 -389.35914) (xy 329.565762 -389.295894) (xy 329.576938 -389.273796) (xy 329.576684 -389.260588)
			(xy 329.576684 -389.25246) (xy 329.577258 -389.222621) (xy 329.586574 -389.163675) (xy 329.595226 -389.135112)
			(xy 329.598528 -389.124698) (xy 329.595988 -389.1026) (xy 329.544172 -389.017764) (xy 329.52563 -389.005572)
			(xy 329.514708 -389.003794) (xy 329.48256 -388.998148) (xy 329.419978 -388.979598) (xy 329.360283 -388.953196)
			(xy 329.304455 -388.919376) (xy 329.253412 -388.878692) (xy 329.207991 -388.831814) (xy 329.168939 -388.779512)
			(xy 329.136898 -388.722644) (xy 329.112393 -388.662145) (xy 329.095829 -388.599009) (xy 329.087475 -388.534273)
			(xy 329.086972 -388.501636) (xy 329.087418 -388.471649) (xy 329.094464 -388.412091) (xy 329.108473 -388.353777)
			(xy 329.129251 -388.297519) (xy 329.156509 -388.244098) (xy 329.172824 -388.218934) (xy 329.178508 -388.209589)
			(xy 329.182098 -388.188038) (xy 329.17637 -388.166954) (xy 329.169776 -388.158228) (xy 329.147992 -388.130796)
			(xy 329.111332 -388.071109) (xy 329.08321 -388.006954) (xy 329.064159 -387.939547) (xy 329.05454 -387.870164)
			(xy 329.053952 -387.83514) (xy 329.054454 -387.803179) (xy 329.062465 -387.739761) (xy 329.078362 -387.677847)
			(xy 329.101894 -387.618414) (xy 329.132688 -387.562399) (xy 329.170261 -387.510684) (xy 329.214018 -387.464087)
			(xy 329.263271 -387.423342) (xy 329.317242 -387.389091) (xy 329.375081 -387.361874) (xy 329.435874 -387.342121)
			(xy 329.498664 -387.330143) (xy 329.56246 -387.32613) (xy 329.626256 -387.330143) (xy 329.689046 -387.342121)
			(xy 329.749839 -387.361874) (xy 329.807678 -387.389091) (xy 329.861649 -387.423342) (xy 329.910902 -387.464087)
			(xy 329.954659 -387.510684) (xy 329.955253 -387.511501) (xy 331.952594 -387.511501) (xy 331.952594 -387.447579)
			(xy 331.960605 -387.384161) (xy 331.976502 -387.322247) (xy 332.000034 -387.262814) (xy 332.030828 -387.206799)
			(xy 332.068401 -387.155084) (xy 332.112158 -387.108487) (xy 332.161411 -387.067742) (xy 332.215382 -387.033491)
			(xy 332.273221 -387.006274) (xy 332.334014 -386.986521) (xy 332.396804 -386.974543) (xy 332.4606 -386.97053)
			(xy 332.524396 -386.974543) (xy 332.587186 -386.986521) (xy 332.647979 -387.006274) (xy 332.705818 -387.033491)
			(xy 332.759789 -387.067742) (xy 332.809042 -387.108487) (xy 332.852799 -387.155084) (xy 332.890372 -387.206799)
			(xy 332.921166 -387.262814) (xy 332.944698 -387.322247) (xy 332.960595 -387.384161) (xy 332.968606 -387.447579)
			(xy 332.969108 -387.47954) (xy 332.968606 -387.511501) (xy 332.960595 -387.574919) (xy 332.944698 -387.636833)
			(xy 332.921166 -387.696266) (xy 332.890372 -387.752281) (xy 332.852799 -387.803996) (xy 332.809042 -387.850593)
			(xy 332.759789 -387.891338) (xy 332.705818 -387.925589) (xy 332.647979 -387.952806) (xy 332.587186 -387.972559)
			(xy 332.524396 -387.984537) (xy 332.4606 -387.988551) (xy 332.396804 -387.984537) (xy 332.334014 -387.972559)
			(xy 332.273221 -387.952806) (xy 332.215382 -387.925589) (xy 332.161411 -387.891338) (xy 332.112158 -387.850593)
			(xy 332.068401 -387.803996) (xy 332.030828 -387.752281) (xy 332.000034 -387.696266) (xy 331.976502 -387.636833)
			(xy 331.960605 -387.574919) (xy 331.952594 -387.511501) (xy 329.955253 -387.511501) (xy 329.992232 -387.562399)
			(xy 330.023026 -387.618414) (xy 330.046558 -387.677847) (xy 330.062455 -387.739761) (xy 330.070466 -387.803179)
			(xy 330.070968 -387.83514) (xy 330.070553 -387.865128) (xy 330.063499 -387.924686) (xy 330.049482 -387.983001)
			(xy 330.028697 -388.039259) (xy 330.001434 -388.092679) (xy 329.985116 -388.117842) (xy 329.979449 -388.127196)
			(xy 329.975848 -388.148742) (xy 329.981571 -388.169824) (xy 329.988164 -388.178548) (xy 330.009989 -388.205948)
			(xy 330.046642 -388.265645) (xy 330.074755 -388.329808) (xy 330.093796 -388.397221) (xy 330.103405 -388.46661)
			(xy 330.103988 -388.501636) (xy 330.103482 -388.534129) (xy 330.095197 -388.598586) (xy 330.078755 -388.661458)
			(xy 330.054424 -388.721718) (xy 330.038964 -388.750302) (xy 330.03363 -388.760208) (xy 330.033551 -388.761181)
			(xy 330.299054 -388.761181) (xy 330.299054 -388.697259) (xy 330.307065 -388.633841) (xy 330.322962 -388.571927)
			(xy 330.346494 -388.512494) (xy 330.377288 -388.456479) (xy 330.414861 -388.404764) (xy 330.458618 -388.358167)
			(xy 330.507871 -388.317422) (xy 330.561842 -388.283171) (xy 330.619681 -388.255954) (xy 330.680474 -388.236201)
			(xy 330.743264 -388.224223) (xy 330.80706 -388.22021) (xy 330.870856 -388.224223) (xy 330.933646 -388.236201)
			(xy 330.994439 -388.255954) (xy 331.052278 -388.283171) (xy 331.106249 -388.317422) (xy 331.155502 -388.358167)
			(xy 331.199259 -388.404764) (xy 331.236832 -388.456479) (xy 331.267626 -388.512494) (xy 331.291158 -388.571927)
			(xy 331.307055 -388.633841) (xy 331.315066 -388.697259) (xy 331.315568 -388.72922) (xy 331.315066 -388.761181)
			(xy 331.307055 -388.824599) (xy 331.291158 -388.886513) (xy 331.267626 -388.945946) (xy 331.236832 -389.001961)
			(xy 331.199259 -389.053676) (xy 331.155502 -389.100273) (xy 331.106249 -389.141018) (xy 331.052278 -389.175269)
			(xy 330.994439 -389.202486) (xy 330.933646 -389.222239) (xy 330.870856 -389.234217) (xy 330.80706 -389.238231)
			(xy 330.743264 -389.234217) (xy 330.680474 -389.222239) (xy 330.619681 -389.202486) (xy 330.561842 -389.175269)
			(xy 330.507871 -389.141018) (xy 330.458618 -389.100273) (xy 330.414861 -389.053676) (xy 330.377288 -389.001961)
			(xy 330.346494 -388.945946) (xy 330.322962 -388.886513) (xy 330.307065 -388.824599) (xy 330.299054 -388.761181)
			(xy 330.033551 -388.761181) (xy 330.031852 -388.782052) (xy 330.065888 -388.875524) (xy 330.081636 -388.891272)
			(xy 330.09205 -388.895082) (xy 330.118949 -388.905737) (xy 330.169437 -388.933991) (xy 330.215081 -388.969543)
			(xy 330.254836 -389.011578) (xy 330.287789 -389.059132) (xy 330.313186 -389.111116) (xy 330.330445 -389.166338)
			(xy 330.33917 -389.223532) (xy 330.3397 -389.25246) (xy 330.3397 -389.260588) (xy 330.339446 -389.273796)
			(xy 330.350622 -389.295894) (xy 330.441554 -389.35914) (xy 330.466446 -389.362188) (xy 330.478384 -389.357362)
			(xy 330.50079 -389.348937) (xy 330.547164 -389.337061) (xy 330.594657 -389.33107) (xy 330.618592 -389.330692)
			(xy 330.645845 -389.331155) (xy 330.699797 -389.338911) (xy 330.752096 -389.354266) (xy 330.801677 -389.376908)
			(xy 330.847531 -389.406376) (xy 330.888725 -389.44207) (xy 330.920309 -389.47852) (xy 331.923642 -389.47852)
			(xy 331.927713 -389.422898) (xy 331.939839 -389.368461) (xy 331.959762 -389.31637) (xy 331.987058 -389.267735)
			(xy 332.021144 -389.223592) (xy 332.061293 -389.184883) (xy 332.106651 -389.152432) (xy 332.156251 -389.126931)
			(xy 332.209035 -389.108924) (xy 332.263878 -389.098794) (xy 332.319612 -389.096757) (xy 332.375049 -389.102857)
			(xy 332.429006 -389.116963) (xy 332.480335 -389.138775) (xy 332.527941 -389.167829) (xy 332.570809 -389.203504)
			(xy 332.608026 -389.245041) (xy 332.638799 -389.291554) (xy 332.662471 -389.342051) (xy 332.678539 -389.395458)
			(xy 332.686659 -389.450634) (xy 332.687168 -389.47852) (xy 332.686659 -389.506406) (xy 332.678539 -389.561582)
			(xy 332.662471 -389.614989) (xy 332.638799 -389.665486) (xy 332.608026 -389.711999) (xy 332.570809 -389.753536)
			(xy 332.527941 -389.789211) (xy 332.480335 -389.818265) (xy 332.429006 -389.840077) (xy 332.375049 -389.854183)
			(xy 332.319612 -389.860283) (xy 332.263878 -389.858246) (xy 332.209035 -389.848116) (xy 332.156251 -389.830109)
			(xy 332.106651 -389.804608) (xy 332.061293 -389.772157) (xy 332.021144 -389.733448) (xy 331.987058 -389.689305)
			(xy 331.959762 -389.64067) (xy 331.939839 -389.588579) (xy 331.927713 -389.534142) (xy 331.923642 -389.47852)
			(xy 330.920309 -389.47852) (xy 330.924419 -389.483263) (xy 330.953888 -389.529116) (xy 330.976531 -389.578697)
			(xy 330.991887 -389.630995) (xy 330.999645 -389.684947) (xy 330.999645 -389.739453) (xy 330.991887 -389.793405)
			(xy 330.976531 -389.845703) (xy 330.953888 -389.895284) (xy 330.924419 -389.941137) (xy 330.888725 -389.98233)
			(xy 330.847531 -390.018024) (xy 330.801677 -390.047492) (xy 330.752096 -390.070134) (xy 330.699797 -390.085489)
			(xy 330.645845 -390.093245) (xy 330.618592 -390.093708) (xy 330.589156 -390.093136) (xy 330.530982 -390.084086)
			(xy 330.502768 -390.075674) (xy 330.494157 -390.073322) (xy 330.476336 -390.074088) (xy 330.46797 -390.077198)
			(xy 330.439776 -390.089136) (xy 330.431549 -390.092972) (xy 330.418273 -390.10533) (xy 330.413868 -390.113266)
			(xy 330.400699 -390.138959) (xy 330.369383 -390.187466) (xy 330.351384 -390.21004) (xy 330.346071 -390.217028)
			(xy 330.340106 -390.233528) (xy 330.3397 -390.242298) (xy 330.3397 -390.396222) (xy 330.34005 -390.405)
			(xy 330.346043 -390.421503) (xy 330.351384 -390.42848) (xy 330.369369 -390.451065) (xy 330.400686 -390.499568)
			(xy 330.413868 -390.525254) (xy 330.418253 -390.533204) (xy 330.431539 -390.545563) (xy 330.439776 -390.549384)
			(xy 330.46797 -390.561322) (xy 330.476355 -390.564351) (xy 330.494152 -390.565138) (xy 330.502768 -390.562846)
			(xy 330.530978 -390.554414) (xy 330.589154 -390.545356) (xy 330.618592 -390.544812) (xy 330.645847 -390.545234)
			(xy 330.699801 -390.552991) (xy 330.752103 -390.568347) (xy 330.801687 -390.59099) (xy 330.847543 -390.62046)
			(xy 330.888739 -390.656155) (xy 330.924436 -390.69735) (xy 330.953906 -390.743206) (xy 330.97655 -390.79279)
			(xy 330.991907 -390.845091) (xy 330.999665 -390.899045) (xy 330.999665 -390.953555) (xy 330.991907 -391.007509)
			(xy 330.97655 -391.05981) (xy 330.953906 -391.109394) (xy 330.924436 -391.15525) (xy 330.888739 -391.196445)
			(xy 330.847543 -391.23214) (xy 330.801687 -391.26161) (xy 330.752103 -391.284253) (xy 330.699801 -391.299609)
			(xy 330.645847 -391.307366) (xy 330.618592 -391.307828) (xy 330.594521 -391.307462) (xy 330.546758 -391.301427)
			(xy 330.500132 -391.289439) (xy 330.477622 -391.280904) (xy 330.465176 -391.275824) (xy 330.439268 -391.279126)
			(xy 330.390177 -391.315291) (xy 333.556561 -391.315291) (xy 333.556561 -391.263309) (xy 333.564693 -391.211967)
			(xy 333.580757 -391.16253) (xy 333.604356 -391.116214) (xy 333.634911 -391.07416) (xy 333.671668 -391.037404)
			(xy 333.713723 -391.006851) (xy 333.760039 -390.983253) (xy 333.809477 -390.967191) (xy 333.860819 -390.95906)
			(xy 333.88681 -390.958578) (xy 333.910008 -390.958961) (xy 333.955948 -390.965453) (xy 334.000533 -390.978294)
			(xy 334.042888 -390.997233) (xy 334.082184 -391.021899) (xy 334.10017 -391.036556) (xy 334.107282 -391.042652)
			(xy 334.124808 -391.048748) (xy 334.210406 -391.04697) (xy 334.227678 -391.039858) (xy 334.234536 -391.033508)
			(xy 334.252953 -391.01716) (xy 334.293734 -390.989556) (xy 334.338157 -390.968303) (xy 334.38524 -390.953872)
			(xy 334.433942 -390.94658) (xy 334.458564 -390.946132) (xy 334.483401 -390.946579) (xy 334.532518 -390.953998)
			(xy 334.57997 -390.968689) (xy 334.624686 -390.990322) (xy 334.665658 -391.018407) (xy 334.684116 -391.035032)
			(xy 334.691192 -391.041057) (xy 334.708374 -391.0481) (xy 334.717644 -391.048748) (xy 334.748886 -391.04951)
			(xy 334.758141 -391.049354) (xy 334.775594 -391.043229) (xy 334.782922 -391.037572) (xy 334.805455 -391.019365)
			(xy 334.855596 -390.990358) (xy 334.910019 -390.970516) (xy 334.967064 -390.960443) (xy 334.996028 -390.959848)
			(xy 335.02201 -390.960448) (xy 335.073334 -390.968581) (xy 335.122755 -390.984642) (xy 335.169054 -391.008236)
			(xy 335.211093 -391.038783) (xy 335.247836 -391.075529) (xy 335.278378 -391.11757) (xy 335.301968 -391.163871)
			(xy 335.318026 -391.213293) (xy 335.326154 -391.264618) (xy 335.326154 -391.316582) (xy 335.318026 -391.367907)
			(xy 335.301968 -391.417329) (xy 335.278378 -391.46363) (xy 335.247836 -391.505671) (xy 335.211093 -391.542417)
			(xy 335.169054 -391.572964) (xy 335.122755 -391.596558) (xy 335.073334 -391.612619) (xy 335.02201 -391.620752)
			(xy 334.996028 -391.621264) (xy 334.971191 -391.620823) (xy 334.922073 -391.613403) (xy 334.874622 -391.59871)
			(xy 334.829905 -391.577076) (xy 334.788933 -391.54899) (xy 334.770476 -391.532364) (xy 334.763402 -391.526335)
			(xy 334.746219 -391.519294) (xy 334.736948 -391.518648) (xy 334.705706 -391.517886) (xy 334.69645 -391.518039)
			(xy 334.678997 -391.524166) (xy 334.67167 -391.529824) (xy 334.649105 -391.547988) (xy 334.598975 -391.577005)
			(xy 334.544562 -391.596858) (xy 334.487525 -391.606945) (xy 334.458564 -391.607548) (xy 334.435368 -391.607117)
			(xy 334.38943 -391.600636) (xy 334.344846 -391.587805) (xy 334.30249 -391.568877) (xy 334.263191 -391.544222)
			(xy 334.245204 -391.52957) (xy 334.238092 -391.523474) (xy 334.220566 -391.517378) (xy 334.134968 -391.519156)
			(xy 334.117696 -391.526268) (xy 334.110838 -391.532618) (xy 334.092395 -391.548936) (xy 334.051621 -391.576543)
			(xy 334.007204 -391.597801) (xy 333.960128 -391.61224) (xy 333.911431 -391.619541) (xy 333.88681 -391.619994)
			(xy 333.860819 -391.61954) (xy 333.809477 -391.611409) (xy 333.760039 -391.595347) (xy 333.713723 -391.571749)
			(xy 333.671668 -391.541196) (xy 333.634911 -391.50444) (xy 333.604356 -391.462386) (xy 333.580757 -391.41607)
			(xy 333.564693 -391.366633) (xy 333.556561 -391.315291) (xy 330.390177 -391.315291) (xy 330.34859 -391.345928)
			(xy 330.337668 -391.36955) (xy 330.338684 -391.382758) (xy 330.3397 -391.41146) (xy 330.339214 -391.438711)
			(xy 330.331458 -391.492659) (xy 330.316103 -391.544954) (xy 330.293461 -391.594531) (xy 330.263995 -391.640381)
			(xy 330.228304 -391.681572) (xy 330.187113 -391.717263) (xy 330.141263 -391.746729) (xy 330.091686 -391.769371)
			(xy 330.039391 -391.784726) (xy 329.985443 -391.792482) (xy 329.930941 -391.792482) (xy 329.876993 -391.784726)
			(xy 329.824698 -391.769371) (xy 329.775121 -391.746729) (xy 329.729271 -391.717263) (xy 329.68808 -391.681572)
			(xy 329.652389 -391.640381) (xy 329.622923 -391.594531) (xy 329.600281 -391.544954) (xy 329.584926 -391.492659)
			(xy 329.57717 -391.438711) (xy 329.576684 -391.41146) (xy 329.5777 -391.382758) (xy 329.578716 -391.36955)
			(xy 329.567794 -391.345928) (xy 329.477116 -391.279126) (xy 329.451208 -391.275824) (xy 329.438762 -391.280904)
			(xy 329.416254 -391.289448) (xy 329.36963 -391.301449) (xy 329.321864 -391.307479) (xy 329.297792 -391.307828)
			(xy 329.270543 -391.307301) (xy 329.216599 -391.299544) (xy 329.164308 -391.284189) (xy 329.114734 -391.261549)
			(xy 329.068887 -391.232084) (xy 329.0277 -391.196394) (xy 328.992011 -391.155206) (xy 328.962547 -391.109359)
			(xy 328.939908 -391.059785) (xy 328.924554 -391.007494) (xy 328.916798 -390.953549) (xy 328.916798 -390.899051)
			(xy 328.924554 -390.845106) (xy 328.939908 -390.792815) (xy 328.962547 -390.743241) (xy 328.992011 -390.697394)
			(xy 329.0277 -390.656206) (xy 329.068887 -390.620516) (xy 329.114734 -390.591051) (xy 329.164308 -390.568411)
			(xy 329.216599 -390.553056) (xy 329.270543 -390.545299) (xy 329.297792 -390.544812) (xy 329.327229 -390.545364)
			(xy 329.385403 -390.554427) (xy 329.413616 -390.562846) (xy 329.422219 -390.565239) (xy 329.440048 -390.564445)
			(xy 329.448414 -390.561322) (xy 329.476608 -390.549384) (xy 329.484847 -390.54557) (xy 329.498118 -390.533197)
			(xy 329.502516 -390.525254) (xy 329.515676 -390.499556) (xy 329.546999 -390.451053) (xy 329.565 -390.42848)
			(xy 329.570315 -390.421493) (xy 329.576277 -390.404992) (xy 329.576684 -390.396222) (xy 329.576684 -390.242298)
			(xy 329.576307 -390.233523) (xy 329.57033 -390.217021) (xy 329.565 -390.21004) (xy 329.547016 -390.187455)
			(xy 329.515698 -390.138952) (xy 329.502516 -390.113266) (xy 329.498131 -390.105316) (xy 329.484845 -390.092956)
			(xy 329.476608 -390.089136) (xy 329.448414 -390.077198) (xy 329.440031 -390.07416) (xy 329.422232 -390.073379)
			(xy 329.413616 -390.075674) (xy 329.385407 -390.084111) (xy 329.327231 -390.093165) (xy 329.297792 -390.093708)
			(xy 329.270541 -390.093222) (xy 329.216594 -390.085464) (xy 329.1643 -390.070108) (xy 329.114724 -390.047467)
			(xy 329.068875 -390.018) (xy 329.027686 -389.982309) (xy 328.991995 -389.941119) (xy 328.962529 -389.895269)
			(xy 328.939889 -389.845692) (xy 328.924534 -389.793398) (xy 328.916778 -389.739451) (xy 327.457582 -389.739451)
			(xy 327.41097 -389.760739) (xy 327.358675 -389.776094) (xy 327.304727 -389.78385) (xy 327.250225 -389.78385)
			(xy 327.196277 -389.776094) (xy 327.143982 -389.760739) (xy 327.094405 -389.738097) (xy 327.048555 -389.708631)
			(xy 327.007364 -389.67294) (xy 326.971673 -389.631749) (xy 326.942207 -389.585899) (xy 326.919565 -389.536322)
			(xy 326.90421 -389.484027) (xy 326.896454 -389.430079) (xy 326.895968 -389.402828) (xy 326.896984 -389.374126)
			(xy 326.898 -389.360918) (xy 326.887078 -389.337296) (xy 326.7964 -389.270494) (xy 326.770492 -389.267192)
			(xy 326.758046 -389.272272) (xy 326.735541 -389.280824) (xy 326.688915 -389.292821) (xy 326.641149 -389.298848)
			(xy 326.617076 -389.299196) (xy 326.589825 -389.298733) (xy 326.535878 -389.290973) (xy 326.483585 -389.275615)
			(xy 326.434009 -389.252972) (xy 326.38816 -389.223504) (xy 326.346971 -389.187812) (xy 326.311281 -389.146621)
			(xy 326.281816 -389.10077) (xy 326.259176 -389.051193) (xy 326.243822 -388.998898) (xy 326.236066 -388.944951)
			(xy 326.236066 -388.890449) (xy 326.243822 -388.836502) (xy 326.259176 -388.784207) (xy 326.281816 -388.73463)
			(xy 326.311281 -388.688779) (xy 326.346971 -388.647588) (xy 326.38816 -388.611896) (xy 326.434009 -388.582428)
			(xy 326.483585 -388.559785) (xy 326.535878 -388.544427) (xy 326.589825 -388.536667) (xy 326.617076 -388.53618)
			(xy 326.646513 -388.536737) (xy 326.704686 -388.545797) (xy 326.7329 -388.554214) (xy 326.741504 -388.556601)
			(xy 326.759332 -388.555812) (xy 326.767698 -388.55269) (xy 326.795892 -388.540752) (xy 326.804115 -388.53691)
			(xy 326.817394 -388.524556) (xy 326.8218 -388.516622) (xy 326.83497 -388.490929) (xy 326.866286 -388.442423)
			(xy 326.884284 -388.419848) (xy 326.889569 -388.412841) (xy 326.895549 -388.396356) (xy 326.895968 -388.38759)
			(xy 326.895968 -388.233666) (xy 326.895609 -388.224889) (xy 326.88962 -388.208387) (xy 326.884284 -388.201408)
			(xy 326.866295 -388.178826) (xy 326.83498 -388.130321) (xy 326.8218 -388.104634) (xy 326.817401 -388.096692)
			(xy 326.804126 -388.084327) (xy 326.795892 -388.080504) (xy 326.767698 -388.068566) (xy 326.759317 -388.065519)
			(xy 326.741516 -388.064742) (xy 326.7329 -388.067042) (xy 326.704692 -388.075481) (xy 326.646515 -388.084534)
			(xy 326.617076 -388.085076) (xy 326.589824 -388.084653) (xy 326.535874 -388.076893) (xy 326.483578 -388.061534)
			(xy 326.433999 -388.03889) (xy 326.388148 -388.00942) (xy 326.346957 -387.973726) (xy 326.311265 -387.932533)
			(xy 326.281799 -387.88668) (xy 326.259158 -387.8371) (xy 326.243802 -387.784803) (xy 326.236046 -387.730852)
			(xy 294.241787 -387.730852) (xy 294.166375 -387.814) (xy 294.036307 -387.945484) (xy 293.900666 -388.071211)
			(xy 293.759706 -388.190943) (xy 293.613691 -388.304457) (xy 293.462896 -388.41154) (xy 293.307604 -388.511989)
			(xy 293.148107 -388.605618) (xy 292.984703 -388.692249) (xy 292.8177 -388.77172) (xy 292.647411 -388.843883)
			(xy 292.474156 -388.908601) (xy 292.29826 -388.965753) (xy 292.120054 -389.015232) (xy 291.939871 -389.056944)
			(xy 291.75805 -389.090812) (xy 291.574934 -389.116773) (xy 291.390864 -389.134776) (xy 291.206187 -389.144789)
			(xy 291.02125 -389.146793) (xy 290.8364 -389.140783) (xy 290.651984 -389.126771) (xy 290.468347 -389.104784)
			(xy 290.285836 -389.074863) (xy 290.104792 -389.037064) (xy 289.925555 -388.991457) (xy 289.748462 -388.93813)
			(xy 289.573846 -388.87718) (xy 289.402034 -388.808724) (xy 289.233348 -388.732889) (xy 289.068106 -388.649818)
			(xy 288.906617 -388.559668) (xy 288.749186 -388.462606) (xy 288.596106 -388.358815) (xy 288.447667 -388.248491)
			(xy 288.304146 -388.131841) (xy 288.165812 -388.009082) (xy 288.032927 -387.880446) (xy 287.905738 -387.746175)
			(xy 287.784485 -387.60652) (xy 287.669396 -387.461744) (xy 287.560687 -387.312118) (xy 287.458561 -387.157923)
			(xy 287.36321 -386.999449) (xy 287.274814 -386.836993) (xy 287.193538 -386.670861) (xy 287.119535 -386.501364)
			(xy 287.052944 -386.32882) (xy 286.99389 -386.153554) (xy 286.942483 -385.975894) (xy 286.898821 -385.796173)
			(xy 286.862985 -385.61473) (xy 286.835043 -385.431906) (xy 286.815047 -385.248042) (xy 286.803034 -385.063484)
			(xy 286.799027 -384.87858) (xy 284.957345 -384.87858) (xy 284.958507 -384.883365) (xy 284.965704 -384.943362)
			(xy 284.966156 -384.973576) (xy 284.965621 -385.004305) (xy 284.958217 -385.065314) (xy 284.943512 -385.124986)
			(xy 284.921723 -385.182451) (xy 284.893165 -385.236871) (xy 284.858257 -385.287451) (xy 284.817506 -385.333455)
			(xy 284.771508 -385.374212) (xy 284.720932 -385.409128) (xy 284.666517 -385.437693) (xy 284.609055 -385.459491)
			(xy 284.549385 -385.474204) (xy 284.488377 -385.481617) (xy 284.457648 -385.482084) (xy 284.427489 -385.481656)
			(xy 284.367596 -385.474519) (xy 284.30897 -385.46034) (xy 284.252435 -385.439317) (xy 284.198787 -385.411748)
			(xy 284.148781 -385.37802) (xy 284.12567 -385.35864) (xy 284.118518 -385.353037) (xy 284.101475 -385.346781)
			(xy 284.092396 -385.346448) (xy 284.06217 -385.346448) (xy 284.053088 -385.346769) (xy 284.036036 -385.353018)
			(xy 284.028896 -385.35864) (xy 284.005779 -385.378008) (xy 283.955758 -385.411703) (xy 283.902106 -385.439251)
			(xy 283.845575 -385.460267) (xy 283.786957 -385.474456) (xy 283.727073 -385.48162) (xy 283.696918 -385.482084)
			(xy 283.666185 -385.481645) (xy 283.605168 -385.474238) (xy 283.545488 -385.45953) (xy 283.488017 -385.437735)
			(xy 283.433592 -385.409171) (xy 283.383007 -385.374255) (xy 283.337 -385.333496) (xy 283.296241 -385.287488)
			(xy 283.261326 -385.236903) (xy 283.232762 -385.182477) (xy 283.210968 -385.125006) (xy 283.196261 -385.065326)
			(xy 283.188854 -385.004309) (xy 283.18841 -384.973576) (xy 280.876248 -384.973576) (xy 280.876248 -387.156706)
			(xy 280.87685 -387.168037) (xy 280.88661 -387.188486) (xy 280.895044 -387.196076) (xy 280.965148 -387.253226)
			(xy 280.986992 -387.25856) (xy 280.998422 -387.256274) (xy 281.023976 -387.25129) (xy 281.075767 -387.245944)
			(xy 281.1018 -387.245606) (xy 281.13376 -387.246108) (xy 281.197176 -387.254119) (xy 281.259089 -387.270016)
			(xy 281.31852 -387.293546) (xy 281.374534 -387.32434) (xy 281.426247 -387.361911) (xy 281.472842 -387.405668)
			(xy 281.513587 -387.454919) (xy 281.547837 -387.508889) (xy 281.575053 -387.566726) (xy 281.594805 -387.627518)
			(xy 281.606783 -387.690306) (xy 281.608446 -387.716733) (xy 282.604712 -387.716733) (xy 282.604712 -387.652811)
			(xy 282.612723 -387.589393) (xy 282.62862 -387.527479) (xy 282.652152 -387.468046) (xy 282.682946 -387.412031)
			(xy 282.720519 -387.360316) (xy 282.764276 -387.313719) (xy 282.813529 -387.272974) (xy 282.8675 -387.238723)
			(xy 282.925339 -387.211506) (xy 282.986132 -387.191753) (xy 283.048922 -387.179775) (xy 283.112718 -387.175762)
			(xy 283.176514 -387.179775) (xy 283.239304 -387.191753) (xy 283.300097 -387.211506) (xy 283.357936 -387.238723)
			(xy 283.411907 -387.272974) (xy 283.46116 -387.313719) (xy 283.504917 -387.360316) (xy 283.54249 -387.412031)
			(xy 283.573284 -387.468046) (xy 283.596816 -387.527479) (xy 283.612713 -387.589393) (xy 283.620724 -387.652811)
			(xy 283.621226 -387.684772) (xy 283.620724 -387.716733) (xy 283.612713 -387.780151) (xy 283.596816 -387.842065)
			(xy 283.573284 -387.901498) (xy 283.54249 -387.957513) (xy 283.504917 -388.009228) (xy 283.46116 -388.055825)
			(xy 283.411907 -388.09657) (xy 283.357936 -388.130821) (xy 283.300097 -388.158038) (xy 283.239304 -388.177791)
			(xy 283.176514 -388.189769) (xy 283.112718 -388.193783) (xy 283.048922 -388.189769) (xy 282.986132 -388.177791)
			(xy 282.925339 -388.158038) (xy 282.8675 -388.130821) (xy 282.813529 -388.09657) (xy 282.764276 -388.055825)
			(xy 282.720519 -388.009228) (xy 282.682946 -387.957513) (xy 282.652152 -387.901498) (xy 282.62862 -387.842065)
			(xy 282.612723 -387.780151) (xy 282.604712 -387.716733) (xy 281.608446 -387.716733) (xy 281.610797 -387.7541)
			(xy 281.606783 -387.817894) (xy 281.594805 -387.880682) (xy 281.575053 -387.941474) (xy 281.547837 -387.999311)
			(xy 281.513587 -388.053281) (xy 281.472842 -388.102532) (xy 281.426247 -388.146289) (xy 281.374534 -388.18386)
			(xy 281.31852 -388.214654) (xy 281.259089 -388.238184) (xy 281.197176 -388.254081) (xy 281.13376 -388.262092)
			(xy 281.1018 -388.262622) (xy 281.075767 -388.262279) (xy 281.023977 -388.256932) (xy 280.998422 -388.251954)
			(xy 280.986992 -388.249668) (xy 280.965148 -388.255002) (xy 280.895044 -388.312152) (xy 280.88665 -388.31977)
			(xy 280.876904 -388.340205) (xy 280.876248 -388.351522) (xy 280.876248 -389.739455) (xy 296.388955 -389.739455)
			(xy 296.388955 -389.684945) (xy 296.396714 -389.63099) (xy 296.412072 -389.578689) (xy 296.434718 -389.529106)
			(xy 296.46419 -389.483251) (xy 296.499888 -389.442057) (xy 296.541086 -389.406363) (xy 296.586945 -389.376896)
			(xy 296.63653 -389.354256) (xy 296.688833 -389.338904) (xy 296.742789 -389.331152) (xy 296.770044 -389.330692)
			(xy 296.793981 -389.331055) (xy 296.841481 -389.337024) (xy 296.887858 -389.3489) (xy 296.910252 -389.357362)
			(xy 296.92219 -389.362188) (xy 296.947082 -389.35914) (xy 297.038014 -389.295894) (xy 297.04919 -389.273796)
			(xy 297.048936 -389.260588) (xy 297.048936 -389.25246) (xy 297.049422 -389.225209) (xy 297.057178 -389.171261)
			(xy 297.072533 -389.118966) (xy 297.095175 -389.069389) (xy 297.124641 -389.023539) (xy 297.160332 -388.982348)
			(xy 297.201523 -388.946657) (xy 297.247373 -388.917191) (xy 297.29695 -388.894549) (xy 297.349245 -388.879194)
			(xy 297.403193 -388.871438) (xy 297.457695 -388.871438) (xy 297.511643 -388.879194) (xy 297.563938 -388.894549)
			(xy 297.613515 -388.917191) (xy 297.659365 -388.946657) (xy 297.700556 -388.982348) (xy 297.736247 -389.023539)
			(xy 297.765713 -389.069389) (xy 297.788355 -389.118966) (xy 297.80371 -389.171261) (xy 297.811466 -389.225209)
			(xy 297.811952 -389.25246) (xy 297.811952 -389.260588) (xy 297.811698 -389.273796) (xy 297.822874 -389.295894)
			(xy 297.913806 -389.35914) (xy 297.938698 -389.362188) (xy 297.950636 -389.357362) (xy 297.973037 -389.348921)
			(xy 298.019413 -389.337052) (xy 298.066909 -389.331067) (xy 298.090844 -389.330692) (xy 298.118093 -389.331181)
			(xy 298.172036 -389.338942) (xy 298.224326 -389.354301) (xy 298.273897 -389.376945) (xy 298.319742 -389.406412)
			(xy 298.360927 -389.442104) (xy 298.363209 -389.444738) (xy 299.34992 -389.444738) (xy 299.353991 -389.389116)
			(xy 299.366117 -389.334679) (xy 299.38604 -389.282588) (xy 299.413336 -389.233953) (xy 299.447422 -389.18981)
			(xy 299.487571 -389.151101) (xy 299.532929 -389.11865) (xy 299.582529 -389.093149) (xy 299.635313 -389.075142)
			(xy 299.690156 -389.065012) (xy 299.74589 -389.062975) (xy 299.801327 -389.069075) (xy 299.855284 -389.083181)
			(xy 299.906613 -389.104993) (xy 299.954219 -389.134047) (xy 299.997087 -389.169722) (xy 300.034304 -389.211259)
			(xy 300.065077 -389.257772) (xy 300.088749 -389.308269) (xy 300.104817 -389.361676) (xy 300.112937 -389.416852)
			(xy 300.113446 -389.444738) (xy 300.112937 -389.472624) (xy 300.104817 -389.5278) (xy 300.088749 -389.581207)
			(xy 300.065077 -389.631704) (xy 300.034304 -389.678217) (xy 299.997087 -389.719754) (xy 299.954219 -389.755429)
			(xy 299.906613 -389.784483) (xy 299.855284 -389.806295) (xy 299.801327 -389.820401) (xy 299.74589 -389.826501)
			(xy 299.690156 -389.824464) (xy 299.635313 -389.814334) (xy 299.582529 -389.796327) (xy 299.532929 -389.770826)
			(xy 299.487571 -389.738375) (xy 299.447422 -389.699666) (xy 299.413336 -389.655523) (xy 299.38604 -389.606888)
			(xy 299.366117 -389.554797) (xy 299.353991 -389.50036) (xy 299.34992 -389.444738) (xy 298.363209 -389.444738)
			(xy 298.396614 -389.483293) (xy 298.426076 -389.529141) (xy 298.448714 -389.578716) (xy 298.464067 -389.631007)
			(xy 298.471822 -389.684951) (xy 298.471822 -389.739449) (xy 298.464067 -389.793393) (xy 298.448714 -389.845684)
			(xy 298.426076 -389.895259) (xy 298.396614 -389.941107) (xy 298.360927 -389.982296) (xy 298.319742 -390.017988)
			(xy 298.273897 -390.047455) (xy 298.224326 -390.070099) (xy 298.172036 -390.085458) (xy 298.118093 -390.093219)
			(xy 298.090844 -390.093708) (xy 298.061407 -390.093147) (xy 298.003234 -390.08409) (xy 297.97502 -390.075674)
			(xy 297.966414 -390.073298) (xy 297.948588 -390.07408) (xy 297.940222 -390.077198) (xy 297.912028 -390.089136)
			(xy 297.90381 -390.092988) (xy 297.890529 -390.105335) (xy 297.88612 -390.113266) (xy 297.872947 -390.138957)
			(xy 297.841633 -390.187465) (xy 297.823636 -390.21004) (xy 297.818317 -390.217024) (xy 297.812357 -390.233527)
			(xy 297.811952 -390.242298) (xy 297.811952 -390.396222) (xy 297.812312 -390.404999) (xy 297.8183 -390.421501)
			(xy 297.823636 -390.42848) (xy 297.841625 -390.451062) (xy 297.87294 -390.499567) (xy 297.88612 -390.525254)
			(xy 297.890522 -390.533193) (xy 297.903796 -390.545558) (xy 297.912028 -390.549384) (xy 297.940222 -390.561322)
			(xy 297.9486 -390.564377) (xy 297.966404 -390.565146) (xy 297.97502 -390.562846) (xy 298.003233 -390.554424)
			(xy 298.061406 -390.54536) (xy 298.090844 -390.544812) (xy 298.118095 -390.545261) (xy 298.17204 -390.553023)
			(xy 298.224333 -390.568383) (xy 298.273907 -390.591027) (xy 298.319754 -390.620496) (xy 298.360941 -390.65619)
			(xy 298.39663 -390.697381) (xy 298.426094 -390.743232) (xy 298.448733 -390.792809) (xy 298.464087 -390.845103)
			(xy 298.471842 -390.899049) (xy 298.471842 -390.953551) (xy 298.464087 -391.007497) (xy 298.448733 -391.059791)
			(xy 298.426094 -391.109368) (xy 298.39663 -391.155219) (xy 298.360941 -391.19641) (xy 298.319754 -391.232104)
			(xy 298.273907 -391.261573) (xy 298.224333 -391.284217) (xy 298.17204 -391.299577) (xy 298.118095 -391.307339)
			(xy 298.090844 -391.307828) (xy 298.066772 -391.307477) (xy 298.019009 -391.301435) (xy 297.972384 -391.289442)
			(xy 297.949874 -391.280904) (xy 297.937428 -391.275824) (xy 297.91152 -391.279126) (xy 297.862436 -391.315286)
			(xy 301.028887 -391.315286) (xy 301.028887 -391.263314) (xy 301.037017 -391.211981) (xy 301.053077 -391.162551)
			(xy 301.07667 -391.116242) (xy 301.107217 -391.074194) (xy 301.143965 -391.037442) (xy 301.18601 -391.00689)
			(xy 301.232316 -390.983291) (xy 301.281744 -390.967226) (xy 301.333076 -390.95909) (xy 301.359062 -390.958578)
			(xy 301.382296 -390.958962) (xy 301.428308 -390.965464) (xy 301.472955 -390.978343) (xy 301.51536 -390.997348)
			(xy 301.554685 -391.022102) (xy 301.572676 -391.03681) (xy 301.579788 -391.042906) (xy 301.596298 -391.049002)
			(xy 301.680626 -391.049002) (xy 301.697136 -391.042906) (xy 301.704248 -391.03681) (xy 301.722246 -391.022113)
			(xy 301.761573 -390.997364) (xy 301.803976 -390.978363) (xy 301.848621 -390.965481) (xy 301.894629 -390.958974)
			(xy 301.917862 -390.958578) (xy 301.946457 -390.95917) (xy 302.002792 -390.969025) (xy 302.056595 -390.988414)
			(xy 302.106266 -391.016759) (xy 302.128682 -391.034524) (xy 302.13554 -391.040112) (xy 302.152304 -391.046208)
			(xy 302.2346 -391.046208) (xy 302.251364 -391.040366) (xy 302.258222 -391.034778) (xy 302.280586 -391.017141)
			(xy 302.330103 -390.989006) (xy 302.383702 -390.969756) (xy 302.439805 -390.95996) (xy 302.46828 -390.95934)
			(xy 302.494274 -390.959726) (xy 302.545622 -390.967856) (xy 302.595067 -390.983919) (xy 302.64139 -391.007519)
			(xy 302.68345 -391.038075) (xy 302.720212 -391.074835) (xy 302.750771 -391.116893) (xy 302.774374 -391.163215)
			(xy 302.79044 -391.212658) (xy 302.798084 -391.260917) (xy 303.48606 -391.260917) (xy 303.48606 -391.208943)
			(xy 303.49419 -391.157608) (xy 303.510251 -391.108178) (xy 303.533847 -391.061868) (xy 303.564397 -391.01982)
			(xy 303.601148 -390.983069) (xy 303.643196 -390.952519) (xy 303.689506 -390.928923) (xy 303.738936 -390.912862)
			(xy 303.790271 -390.904732) (xy 303.842245 -390.904732) (xy 303.89358 -390.912862) (xy 303.94301 -390.928923)
			(xy 303.98932 -390.952519) (xy 304.031368 -390.983069) (xy 304.068119 -391.01982) (xy 304.098669 -391.061868)
			(xy 304.122265 -391.108178) (xy 304.138326 -391.157608) (xy 304.146456 -391.208943) (xy 304.146966 -391.23493)
			(xy 304.146456 -391.260917) (xy 304.68621 -391.260917) (xy 304.68621 -391.208943) (xy 304.69434 -391.157608)
			(xy 304.710401 -391.108178) (xy 304.733997 -391.061868) (xy 304.764547 -391.01982) (xy 304.801298 -390.983069)
			(xy 304.843346 -390.952519) (xy 304.889656 -390.928923) (xy 304.939086 -390.912862) (xy 304.990421 -390.904732)
			(xy 305.042395 -390.904732) (xy 305.09373 -390.912862) (xy 305.14316 -390.928923) (xy 305.18947 -390.952519)
			(xy 305.231518 -390.983069) (xy 305.268269 -391.01982) (xy 305.298819 -391.061868) (xy 305.322415 -391.108178)
			(xy 305.338476 -391.157608) (xy 305.346606 -391.208943) (xy 305.347116 -391.23493) (xy 305.346606 -391.260917)
			(xy 305.886106 -391.260917) (xy 305.886106 -391.208943) (xy 305.894236 -391.157608) (xy 305.910297 -391.108178)
			(xy 305.933893 -391.061868) (xy 305.964443 -391.01982) (xy 306.001194 -390.983069) (xy 306.043242 -390.952519)
			(xy 306.089552 -390.928923) (xy 306.138982 -390.912862) (xy 306.190317 -390.904732) (xy 306.242291 -390.904732)
			(xy 306.293626 -390.912862) (xy 306.343056 -390.928923) (xy 306.389366 -390.952519) (xy 306.431414 -390.983069)
			(xy 306.468165 -391.01982) (xy 306.498715 -391.061868) (xy 306.522311 -391.108178) (xy 306.538372 -391.157608)
			(xy 306.546502 -391.208943) (xy 306.547012 -391.23493) (xy 306.546502 -391.260917) (xy 307.086002 -391.260917)
			(xy 307.086002 -391.208943) (xy 307.094132 -391.157608) (xy 307.110193 -391.108178) (xy 307.133789 -391.061868)
			(xy 307.164339 -391.01982) (xy 307.20109 -390.983069) (xy 307.243138 -390.952519) (xy 307.289448 -390.928923)
			(xy 307.338878 -390.912862) (xy 307.390213 -390.904732) (xy 307.442187 -390.904732) (xy 307.493522 -390.912862)
			(xy 307.542952 -390.928923) (xy 307.589262 -390.952519) (xy 307.63131 -390.983069) (xy 307.668061 -391.01982)
			(xy 307.698611 -391.061868) (xy 307.722207 -391.108178) (xy 307.738268 -391.157608) (xy 307.746398 -391.208943)
			(xy 307.746908 -391.23493) (xy 307.746398 -391.260917) (xy 308.286152 -391.260917) (xy 308.286152 -391.208943)
			(xy 308.294282 -391.157608) (xy 308.310343 -391.108178) (xy 308.333939 -391.061868) (xy 308.364489 -391.01982)
			(xy 308.40124 -390.983069) (xy 308.443288 -390.952519) (xy 308.489598 -390.928923) (xy 308.539028 -390.912862)
			(xy 308.590363 -390.904732) (xy 308.642337 -390.904732) (xy 308.693672 -390.912862) (xy 308.743102 -390.928923)
			(xy 308.789412 -390.952519) (xy 308.83146 -390.983069) (xy 308.868211 -391.01982) (xy 308.898761 -391.061868)
			(xy 308.922357 -391.108178) (xy 308.938418 -391.157608) (xy 308.946548 -391.208943) (xy 308.947058 -391.23493)
			(xy 308.946548 -391.260917) (xy 309.486048 -391.260917) (xy 309.486048 -391.208943) (xy 309.494178 -391.157608)
			(xy 309.510239 -391.108178) (xy 309.533835 -391.061868) (xy 309.564385 -391.01982) (xy 309.601136 -390.983069)
			(xy 309.643184 -390.952519) (xy 309.689494 -390.928923) (xy 309.738924 -390.912862) (xy 309.790259 -390.904732)
			(xy 309.842233 -390.904732) (xy 309.893568 -390.912862) (xy 309.942998 -390.928923) (xy 309.989308 -390.952519)
			(xy 310.031356 -390.983069) (xy 310.068107 -391.01982) (xy 310.098657 -391.061868) (xy 310.122253 -391.108178)
			(xy 310.138314 -391.157608) (xy 310.146444 -391.208943) (xy 310.146954 -391.23493) (xy 310.146444 -391.260917)
			(xy 310.686198 -391.260917) (xy 310.686198 -391.208943) (xy 310.694328 -391.157608) (xy 310.710389 -391.108178)
			(xy 310.733985 -391.061868) (xy 310.764535 -391.01982) (xy 310.801286 -390.983069) (xy 310.843334 -390.952519)
			(xy 310.889644 -390.928923) (xy 310.939074 -390.912862) (xy 310.990409 -390.904732) (xy 311.042383 -390.904732)
			(xy 311.093718 -390.912862) (xy 311.143148 -390.928923) (xy 311.189458 -390.952519) (xy 311.231506 -390.983069)
			(xy 311.268257 -391.01982) (xy 311.298807 -391.061868) (xy 311.322403 -391.108178) (xy 311.338464 -391.157608)
			(xy 311.346594 -391.208943) (xy 311.347104 -391.23493) (xy 311.346594 -391.260917) (xy 311.886094 -391.260917)
			(xy 311.886094 -391.208943) (xy 311.894224 -391.157608) (xy 311.910285 -391.108178) (xy 311.933881 -391.061868)
			(xy 311.964431 -391.01982) (xy 312.001182 -390.983069) (xy 312.04323 -390.952519) (xy 312.08954 -390.928923)
			(xy 312.13897 -390.912862) (xy 312.190305 -390.904732) (xy 312.242279 -390.904732) (xy 312.293614 -390.912862)
			(xy 312.343044 -390.928923) (xy 312.389354 -390.952519) (xy 312.431402 -390.983069) (xy 312.468153 -391.01982)
			(xy 312.498703 -391.061868) (xy 312.522299 -391.108178) (xy 312.53836 -391.157608) (xy 312.54649 -391.208943)
			(xy 312.547 -391.23493) (xy 312.54649 -391.260917) (xy 313.08599 -391.260917) (xy 313.08599 -391.208943)
			(xy 313.09412 -391.157608) (xy 313.110181 -391.108178) (xy 313.133777 -391.061868) (xy 313.164327 -391.01982)
			(xy 313.201078 -390.983069) (xy 313.243126 -390.952519) (xy 313.289436 -390.928923) (xy 313.338866 -390.912862)
			(xy 313.390201 -390.904732) (xy 313.442175 -390.904732) (xy 313.49351 -390.912862) (xy 313.54294 -390.928923)
			(xy 313.58925 -390.952519) (xy 313.631298 -390.983069) (xy 313.668049 -391.01982) (xy 313.698599 -391.061868)
			(xy 313.722195 -391.108178) (xy 313.738256 -391.157608) (xy 313.746386 -391.208943) (xy 313.746896 -391.23493)
			(xy 313.746386 -391.260917) (xy 314.28614 -391.260917) (xy 314.28614 -391.208943) (xy 314.29427 -391.157608)
			(xy 314.310331 -391.108178) (xy 314.333927 -391.061868) (xy 314.364477 -391.01982) (xy 314.401228 -390.983069)
			(xy 314.443276 -390.952519) (xy 314.489586 -390.928923) (xy 314.539016 -390.912862) (xy 314.590351 -390.904732)
			(xy 314.642325 -390.904732) (xy 314.69366 -390.912862) (xy 314.74309 -390.928923) (xy 314.7894 -390.952519)
			(xy 314.831448 -390.983069) (xy 314.868199 -391.01982) (xy 314.898749 -391.061868) (xy 314.922345 -391.108178)
			(xy 314.938406 -391.157608) (xy 314.946536 -391.208943) (xy 314.947046 -391.23493) (xy 314.946536 -391.260917)
			(xy 315.486036 -391.260917) (xy 315.486036 -391.208943) (xy 315.494166 -391.157608) (xy 315.510227 -391.108178)
			(xy 315.533823 -391.061868) (xy 315.564373 -391.01982) (xy 315.601124 -390.983069) (xy 315.643172 -390.952519)
			(xy 315.689482 -390.928923) (xy 315.738912 -390.912862) (xy 315.790247 -390.904732) (xy 315.842221 -390.904732)
			(xy 315.893556 -390.912862) (xy 315.942986 -390.928923) (xy 315.989296 -390.952519) (xy 316.031344 -390.983069)
			(xy 316.068095 -391.01982) (xy 316.098645 -391.061868) (xy 316.122241 -391.108178) (xy 316.138302 -391.157608)
			(xy 316.146432 -391.208943) (xy 316.146942 -391.23493) (xy 316.146432 -391.260917) (xy 316.686186 -391.260917)
			(xy 316.686186 -391.208943) (xy 316.694316 -391.157608) (xy 316.710377 -391.108178) (xy 316.733973 -391.061868)
			(xy 316.764523 -391.01982) (xy 316.801274 -390.983069) (xy 316.843322 -390.952519) (xy 316.889632 -390.928923)
			(xy 316.939062 -390.912862) (xy 316.990397 -390.904732) (xy 317.042371 -390.904732) (xy 317.093706 -390.912862)
			(xy 317.143136 -390.928923) (xy 317.189446 -390.952519) (xy 317.231494 -390.983069) (xy 317.268245 -391.01982)
			(xy 317.298795 -391.061868) (xy 317.322391 -391.108178) (xy 317.338452 -391.157608) (xy 317.346582 -391.208943)
			(xy 317.347092 -391.23493) (xy 317.346582 -391.260917) (xy 317.886082 -391.260917) (xy 317.886082 -391.208943)
			(xy 317.894212 -391.157608) (xy 317.910273 -391.108178) (xy 317.933869 -391.061868) (xy 317.964419 -391.01982)
			(xy 318.00117 -390.983069) (xy 318.043218 -390.952519) (xy 318.089528 -390.928923) (xy 318.138958 -390.912862)
			(xy 318.190293 -390.904732) (xy 318.242267 -390.904732) (xy 318.293602 -390.912862) (xy 318.343032 -390.928923)
			(xy 318.389342 -390.952519) (xy 318.43139 -390.983069) (xy 318.468141 -391.01982) (xy 318.498691 -391.061868)
			(xy 318.522287 -391.108178) (xy 318.538348 -391.157608) (xy 318.546478 -391.208943) (xy 318.546988 -391.23493)
			(xy 318.546478 -391.260917) (xy 319.085978 -391.260917) (xy 319.085978 -391.208943) (xy 319.094108 -391.157608)
			(xy 319.110169 -391.108178) (xy 319.133765 -391.061868) (xy 319.164315 -391.01982) (xy 319.201066 -390.983069)
			(xy 319.243114 -390.952519) (xy 319.289424 -390.928923) (xy 319.338854 -390.912862) (xy 319.390189 -390.904732)
			(xy 319.442163 -390.904732) (xy 319.493498 -390.912862) (xy 319.542928 -390.928923) (xy 319.589238 -390.952519)
			(xy 319.631286 -390.983069) (xy 319.668037 -391.01982) (xy 319.698587 -391.061868) (xy 319.722183 -391.108178)
			(xy 319.738244 -391.157608) (xy 319.746374 -391.208943) (xy 319.746884 -391.23493) (xy 319.746374 -391.260917)
			(xy 320.286128 -391.260917) (xy 320.286128 -391.208943) (xy 320.294258 -391.157608) (xy 320.310319 -391.108178)
			(xy 320.333915 -391.061868) (xy 320.364465 -391.01982) (xy 320.401216 -390.983069) (xy 320.443264 -390.952519)
			(xy 320.489574 -390.928923) (xy 320.539004 -390.912862) (xy 320.590339 -390.904732) (xy 320.642313 -390.904732)
			(xy 320.693648 -390.912862) (xy 320.743078 -390.928923) (xy 320.789388 -390.952519) (xy 320.831436 -390.983069)
			(xy 320.868187 -391.01982) (xy 320.898737 -391.061868) (xy 320.922333 -391.108178) (xy 320.938394 -391.157608)
			(xy 320.946524 -391.208943) (xy 320.947034 -391.23493) (xy 320.946524 -391.260917) (xy 321.486024 -391.260917)
			(xy 321.486024 -391.208943) (xy 321.494154 -391.157608) (xy 321.510215 -391.108178) (xy 321.533811 -391.061868)
			(xy 321.564361 -391.01982) (xy 321.601112 -390.983069) (xy 321.64316 -390.952519) (xy 321.68947 -390.928923)
			(xy 321.7389 -390.912862) (xy 321.790235 -390.904732) (xy 321.842209 -390.904732) (xy 321.893544 -390.912862)
			(xy 321.942974 -390.928923) (xy 321.989284 -390.952519) (xy 322.031332 -390.983069) (xy 322.068083 -391.01982)
			(xy 322.098633 -391.061868) (xy 322.122229 -391.108178) (xy 322.13829 -391.157608) (xy 322.14642 -391.208943)
			(xy 322.14693 -391.23493) (xy 322.14642 -391.260917) (xy 322.144002 -391.276188) (xy 322.553072 -391.276188)
			(xy 322.553072 -391.224212) (xy 322.561202 -391.172875) (xy 322.577263 -391.123442) (xy 322.600859 -391.07713)
			(xy 322.631409 -391.035079) (xy 322.668161 -390.998324) (xy 322.710209 -390.967772) (xy 322.75652 -390.944172)
			(xy 322.805951 -390.928108) (xy 322.857288 -390.919973) (xy 322.883276 -390.919462) (xy 322.90705 -390.919867)
			(xy 322.95411 -390.926669) (xy 322.999707 -390.940149) (xy 323.0429 -390.96003) (xy 323.082795 -390.9859)
			(xy 323.100954 -391.00125) (xy 323.108072 -391.006938) (xy 323.125124 -391.013321) (xy 323.134228 -391.013696)
			(xy 323.165724 -391.013696) (xy 323.174826 -391.013313) (xy 323.191876 -391.006931) (xy 323.198998 -391.00125)
			(xy 323.217161 -390.985906) (xy 323.257061 -390.960049) (xy 323.300254 -390.940174) (xy 323.345848 -390.92669)
			(xy 323.392903 -390.919876) (xy 323.416676 -390.919462) (xy 323.442664 -390.920003) (xy 323.494001 -390.928131)
			(xy 323.543434 -390.944189) (xy 323.589747 -390.967784) (xy 323.631798 -390.998333) (xy 323.668552 -391.035084)
			(xy 323.699104 -391.077133) (xy 323.722701 -391.123444) (xy 323.738764 -391.172876) (xy 323.746895 -391.224212)
			(xy 323.746895 -391.276188) (xy 323.738764 -391.327524) (xy 323.722701 -391.376956) (xy 323.699104 -391.423267)
			(xy 323.668552 -391.465316) (xy 323.631798 -391.502067) (xy 323.589747 -391.532616) (xy 323.543434 -391.556211)
			(xy 323.494001 -391.572269) (xy 323.442664 -391.580397) (xy 323.416676 -391.580878) (xy 323.392901 -391.580492)
			(xy 323.345841 -391.573684) (xy 323.300244 -391.560199) (xy 323.257051 -391.540314) (xy 323.217157 -391.514442)
			(xy 323.198998 -391.49909) (xy 323.191899 -391.493374) (xy 323.174832 -391.48701) (xy 323.165724 -391.486644)
			(xy 323.134228 -391.486644) (xy 323.125128 -391.487043) (xy 323.108077 -391.493413) (xy 323.100954 -391.49909)
			(xy 323.082777 -391.514416) (xy 323.04288 -391.540274) (xy 322.999691 -391.560153) (xy 322.9541 -391.573641)
			(xy 322.907048 -391.580461) (xy 322.883276 -391.580878) (xy 322.857288 -391.580427) (xy 322.805951 -391.572292)
			(xy 322.75652 -391.556228) (xy 322.710209 -391.532628) (xy 322.668161 -391.502076) (xy 322.631409 -391.465321)
			(xy 322.600859 -391.42327) (xy 322.577263 -391.376958) (xy 322.561202 -391.327525) (xy 322.553072 -391.276188)
			(xy 322.144002 -391.276188) (xy 322.13829 -391.312252) (xy 322.122229 -391.361682) (xy 322.098633 -391.407992)
			(xy 322.068083 -391.45004) (xy 322.031332 -391.486791) (xy 321.989284 -391.517341) (xy 321.942974 -391.540937)
			(xy 321.893544 -391.556998) (xy 321.842209 -391.565128) (xy 321.790235 -391.565128) (xy 321.7389 -391.556998)
			(xy 321.68947 -391.540937) (xy 321.64316 -391.517341) (xy 321.601112 -391.486791) (xy 321.564361 -391.45004)
			(xy 321.533811 -391.407992) (xy 321.510215 -391.361682) (xy 321.494154 -391.312252) (xy 321.486024 -391.260917)
			(xy 320.946524 -391.260917) (xy 320.938394 -391.312252) (xy 320.922333 -391.361682) (xy 320.898737 -391.407992)
			(xy 320.868187 -391.45004) (xy 320.831436 -391.486791) (xy 320.789388 -391.517341) (xy 320.743078 -391.540937)
			(xy 320.693648 -391.556998) (xy 320.642313 -391.565128) (xy 320.590339 -391.565128) (xy 320.539004 -391.556998)
			(xy 320.489574 -391.540937) (xy 320.443264 -391.517341) (xy 320.401216 -391.486791) (xy 320.364465 -391.45004)
			(xy 320.333915 -391.407992) (xy 320.310319 -391.361682) (xy 320.294258 -391.312252) (xy 320.286128 -391.260917)
			(xy 319.746374 -391.260917) (xy 319.738244 -391.312252) (xy 319.722183 -391.361682) (xy 319.698587 -391.407992)
			(xy 319.668037 -391.45004) (xy 319.631286 -391.486791) (xy 319.589238 -391.517341) (xy 319.542928 -391.540937)
			(xy 319.493498 -391.556998) (xy 319.442163 -391.565128) (xy 319.390189 -391.565128) (xy 319.338854 -391.556998)
			(xy 319.289424 -391.540937) (xy 319.243114 -391.517341) (xy 319.201066 -391.486791) (xy 319.164315 -391.45004)
			(xy 319.133765 -391.407992) (xy 319.110169 -391.361682) (xy 319.094108 -391.312252) (xy 319.085978 -391.260917)
			(xy 318.546478 -391.260917) (xy 318.538348 -391.312252) (xy 318.522287 -391.361682) (xy 318.498691 -391.407992)
			(xy 318.468141 -391.45004) (xy 318.43139 -391.486791) (xy 318.389342 -391.517341) (xy 318.343032 -391.540937)
			(xy 318.293602 -391.556998) (xy 318.242267 -391.565128) (xy 318.190293 -391.565128) (xy 318.138958 -391.556998)
			(xy 318.089528 -391.540937) (xy 318.043218 -391.517341) (xy 318.00117 -391.486791) (xy 317.964419 -391.45004)
			(xy 317.933869 -391.407992) (xy 317.910273 -391.361682) (xy 317.894212 -391.312252) (xy 317.886082 -391.260917)
			(xy 317.346582 -391.260917) (xy 317.338452 -391.312252) (xy 317.322391 -391.361682) (xy 317.298795 -391.407992)
			(xy 317.268245 -391.45004) (xy 317.231494 -391.486791) (xy 317.189446 -391.517341) (xy 317.143136 -391.540937)
			(xy 317.093706 -391.556998) (xy 317.042371 -391.565128) (xy 316.990397 -391.565128) (xy 316.939062 -391.556998)
			(xy 316.889632 -391.540937) (xy 316.843322 -391.517341) (xy 316.801274 -391.486791) (xy 316.764523 -391.45004)
			(xy 316.733973 -391.407992) (xy 316.710377 -391.361682) (xy 316.694316 -391.312252) (xy 316.686186 -391.260917)
			(xy 316.146432 -391.260917) (xy 316.138302 -391.312252) (xy 316.122241 -391.361682) (xy 316.098645 -391.407992)
			(xy 316.068095 -391.45004) (xy 316.031344 -391.486791) (xy 315.989296 -391.517341) (xy 315.942986 -391.540937)
			(xy 315.893556 -391.556998) (xy 315.842221 -391.565128) (xy 315.790247 -391.565128) (xy 315.738912 -391.556998)
			(xy 315.689482 -391.540937) (xy 315.643172 -391.517341) (xy 315.601124 -391.486791) (xy 315.564373 -391.45004)
			(xy 315.533823 -391.407992) (xy 315.510227 -391.361682) (xy 315.494166 -391.312252) (xy 315.486036 -391.260917)
			(xy 314.946536 -391.260917) (xy 314.938406 -391.312252) (xy 314.922345 -391.361682) (xy 314.898749 -391.407992)
			(xy 314.868199 -391.45004) (xy 314.831448 -391.486791) (xy 314.7894 -391.517341) (xy 314.74309 -391.540937)
			(xy 314.69366 -391.556998) (xy 314.642325 -391.565128) (xy 314.590351 -391.565128) (xy 314.539016 -391.556998)
			(xy 314.489586 -391.540937) (xy 314.443276 -391.517341) (xy 314.401228 -391.486791) (xy 314.364477 -391.45004)
			(xy 314.333927 -391.407992) (xy 314.310331 -391.361682) (xy 314.29427 -391.312252) (xy 314.28614 -391.260917)
			(xy 313.746386 -391.260917) (xy 313.738256 -391.312252) (xy 313.722195 -391.361682) (xy 313.698599 -391.407992)
			(xy 313.668049 -391.45004) (xy 313.631298 -391.486791) (xy 313.58925 -391.517341) (xy 313.54294 -391.540937)
			(xy 313.49351 -391.556998) (xy 313.442175 -391.565128) (xy 313.390201 -391.565128) (xy 313.338866 -391.556998)
			(xy 313.289436 -391.540937) (xy 313.243126 -391.517341) (xy 313.201078 -391.486791) (xy 313.164327 -391.45004)
			(xy 313.133777 -391.407992) (xy 313.110181 -391.361682) (xy 313.09412 -391.312252) (xy 313.08599 -391.260917)
			(xy 312.54649 -391.260917) (xy 312.53836 -391.312252) (xy 312.522299 -391.361682) (xy 312.498703 -391.407992)
			(xy 312.468153 -391.45004) (xy 312.431402 -391.486791) (xy 312.389354 -391.517341) (xy 312.343044 -391.540937)
			(xy 312.293614 -391.556998) (xy 312.242279 -391.565128) (xy 312.190305 -391.565128) (xy 312.13897 -391.556998)
			(xy 312.08954 -391.540937) (xy 312.04323 -391.517341) (xy 312.001182 -391.486791) (xy 311.964431 -391.45004)
			(xy 311.933881 -391.407992) (xy 311.910285 -391.361682) (xy 311.894224 -391.312252) (xy 311.886094 -391.260917)
			(xy 311.346594 -391.260917) (xy 311.338464 -391.312252) (xy 311.322403 -391.361682) (xy 311.298807 -391.407992)
			(xy 311.268257 -391.45004) (xy 311.231506 -391.486791) (xy 311.189458 -391.517341) (xy 311.143148 -391.540937)
			(xy 311.093718 -391.556998) (xy 311.042383 -391.565128) (xy 310.990409 -391.565128) (xy 310.939074 -391.556998)
			(xy 310.889644 -391.540937) (xy 310.843334 -391.517341) (xy 310.801286 -391.486791) (xy 310.764535 -391.45004)
			(xy 310.733985 -391.407992) (xy 310.710389 -391.361682) (xy 310.694328 -391.312252) (xy 310.686198 -391.260917)
			(xy 310.146444 -391.260917) (xy 310.138314 -391.312252) (xy 310.122253 -391.361682) (xy 310.098657 -391.407992)
			(xy 310.068107 -391.45004) (xy 310.031356 -391.486791) (xy 309.989308 -391.517341) (xy 309.942998 -391.540937)
			(xy 309.893568 -391.556998) (xy 309.842233 -391.565128) (xy 309.790259 -391.565128) (xy 309.738924 -391.556998)
			(xy 309.689494 -391.540937) (xy 309.643184 -391.517341) (xy 309.601136 -391.486791) (xy 309.564385 -391.45004)
			(xy 309.533835 -391.407992) (xy 309.510239 -391.361682) (xy 309.494178 -391.312252) (xy 309.486048 -391.260917)
			(xy 308.946548 -391.260917) (xy 308.938418 -391.312252) (xy 308.922357 -391.361682) (xy 308.898761 -391.407992)
			(xy 308.868211 -391.45004) (xy 308.83146 -391.486791) (xy 308.789412 -391.517341) (xy 308.743102 -391.540937)
			(xy 308.693672 -391.556998) (xy 308.642337 -391.565128) (xy 308.590363 -391.565128) (xy 308.539028 -391.556998)
			(xy 308.489598 -391.540937) (xy 308.443288 -391.517341) (xy 308.40124 -391.486791) (xy 308.364489 -391.45004)
			(xy 308.333939 -391.407992) (xy 308.310343 -391.361682) (xy 308.294282 -391.312252) (xy 308.286152 -391.260917)
			(xy 307.746398 -391.260917) (xy 307.738268 -391.312252) (xy 307.722207 -391.361682) (xy 307.698611 -391.407992)
			(xy 307.668061 -391.45004) (xy 307.63131 -391.486791) (xy 307.589262 -391.517341) (xy 307.542952 -391.540937)
			(xy 307.493522 -391.556998) (xy 307.442187 -391.565128) (xy 307.390213 -391.565128) (xy 307.338878 -391.556998)
			(xy 307.289448 -391.540937) (xy 307.243138 -391.517341) (xy 307.20109 -391.486791) (xy 307.164339 -391.45004)
			(xy 307.133789 -391.407992) (xy 307.110193 -391.361682) (xy 307.094132 -391.312252) (xy 307.086002 -391.260917)
			(xy 306.546502 -391.260917) (xy 306.538372 -391.312252) (xy 306.522311 -391.361682) (xy 306.498715 -391.407992)
			(xy 306.468165 -391.45004) (xy 306.431414 -391.486791) (xy 306.389366 -391.517341) (xy 306.343056 -391.540937)
			(xy 306.293626 -391.556998) (xy 306.242291 -391.565128) (xy 306.190317 -391.565128) (xy 306.138982 -391.556998)
			(xy 306.089552 -391.540937) (xy 306.043242 -391.517341) (xy 306.001194 -391.486791) (xy 305.964443 -391.45004)
			(xy 305.933893 -391.407992) (xy 305.910297 -391.361682) (xy 305.894236 -391.312252) (xy 305.886106 -391.260917)
			(xy 305.346606 -391.260917) (xy 305.338476 -391.312252) (xy 305.322415 -391.361682) (xy 305.298819 -391.407992)
			(xy 305.268269 -391.45004) (xy 305.231518 -391.486791) (xy 305.18947 -391.517341) (xy 305.14316 -391.540937)
			(xy 305.09373 -391.556998) (xy 305.042395 -391.565128) (xy 304.990421 -391.565128) (xy 304.939086 -391.556998)
			(xy 304.889656 -391.540937) (xy 304.843346 -391.517341) (xy 304.801298 -391.486791) (xy 304.764547 -391.45004)
			(xy 304.733997 -391.407992) (xy 304.710401 -391.361682) (xy 304.69434 -391.312252) (xy 304.68621 -391.260917)
			(xy 304.146456 -391.260917) (xy 304.138326 -391.312252) (xy 304.122265 -391.361682) (xy 304.098669 -391.407992)
			(xy 304.068119 -391.45004) (xy 304.031368 -391.486791) (xy 303.98932 -391.517341) (xy 303.94301 -391.540937)
			(xy 303.89358 -391.556998) (xy 303.842245 -391.565128) (xy 303.790271 -391.565128) (xy 303.738936 -391.556998)
			(xy 303.689506 -391.540937) (xy 303.643196 -391.517341) (xy 303.601148 -391.486791) (xy 303.564397 -391.45004)
			(xy 303.533847 -391.407992) (xy 303.510251 -391.361682) (xy 303.49419 -391.312252) (xy 303.48606 -391.260917)
			(xy 302.798084 -391.260917) (xy 302.798573 -391.264006) (xy 302.798573 -391.315994) (xy 302.79044 -391.367342)
			(xy 302.774374 -391.416785) (xy 302.750771 -391.463107) (xy 302.720212 -391.505165) (xy 302.68345 -391.541925)
			(xy 302.64139 -391.572481) (xy 302.595067 -391.596081) (xy 302.545622 -391.612144) (xy 302.494274 -391.620274)
			(xy 302.46828 -391.620756) (xy 302.439687 -391.620133) (xy 302.383354 -391.610287) (xy 302.32955 -391.590907)
			(xy 302.279877 -391.56257) (xy 302.25746 -391.54481) (xy 302.250602 -391.539222) (xy 302.233838 -391.533126)
			(xy 302.151542 -391.533126) (xy 302.134778 -391.538968) (xy 302.12792 -391.544556) (xy 302.105568 -391.56221)
			(xy 302.056048 -391.590344) (xy 302.002445 -391.609589) (xy 301.946338 -391.619379) (xy 301.917862 -391.619994)
			(xy 301.894628 -391.619602) (xy 301.848617 -391.613103) (xy 301.803969 -391.600226) (xy 301.761564 -391.581223)
			(xy 301.722239 -391.556469) (xy 301.704248 -391.541762) (xy 301.697136 -391.535666) (xy 301.680626 -391.52957)
			(xy 301.596298 -391.52957) (xy 301.579788 -391.535666) (xy 301.572676 -391.541762) (xy 301.554666 -391.556444)
			(xy 301.515343 -391.581195) (xy 301.472943 -391.600201) (xy 301.4283 -391.613086) (xy 301.382294 -391.619596)
			(xy 301.359062 -391.619994) (xy 301.333076 -391.61951) (xy 301.281744 -391.611374) (xy 301.232316 -391.595309)
			(xy 301.18601 -391.57171) (xy 301.143965 -391.541158) (xy 301.107217 -391.504406) (xy 301.07667 -391.462358)
			(xy 301.053077 -391.416049) (xy 301.037017 -391.366619) (xy 301.028887 -391.315286) (xy 297.862436 -391.315286)
			(xy 297.820842 -391.345928) (xy 297.80992 -391.36955) (xy 297.810936 -391.382758) (xy 297.811952 -391.41146)
			(xy 297.811466 -391.438711) (xy 297.80371 -391.492659) (xy 297.788355 -391.544954) (xy 297.765713 -391.594531)
			(xy 297.736247 -391.640381) (xy 297.700556 -391.681572) (xy 297.659365 -391.717263) (xy 297.613515 -391.746729)
			(xy 297.563938 -391.769371) (xy 297.511643 -391.784726) (xy 297.457695 -391.792482) (xy 297.403193 -391.792482)
			(xy 297.349245 -391.784726) (xy 297.29695 -391.769371) (xy 297.247373 -391.746729) (xy 297.201523 -391.717263)
			(xy 297.160332 -391.681572) (xy 297.124641 -391.640381) (xy 297.095175 -391.594531) (xy 297.072533 -391.544954)
			(xy 297.057178 -391.492659) (xy 297.049422 -391.438711) (xy 297.048936 -391.41146) (xy 297.049952 -391.382758)
			(xy 297.050968 -391.36955) (xy 297.040046 -391.345928) (xy 296.949368 -391.279126) (xy 296.92346 -391.275824)
			(xy 296.911014 -391.280904) (xy 296.888511 -391.289462) (xy 296.841884 -391.301458) (xy 296.794117 -391.307482)
			(xy 296.770044 -391.307828) (xy 296.742791 -391.307328) (xy 296.688838 -391.299576) (xy 296.636537 -391.284225)
			(xy 296.586954 -391.261586) (xy 296.541098 -391.232121) (xy 296.499902 -391.196429) (xy 296.464206 -391.155237)
			(xy 296.434735 -391.109384) (xy 296.412091 -391.059804) (xy 296.396733 -391.007505) (xy 296.388975 -390.953553)
			(xy 296.388975 -390.899047) (xy 296.396733 -390.845095) (xy 296.412091 -390.792796) (xy 296.434735 -390.743216)
			(xy 296.464206 -390.697363) (xy 296.499902 -390.656171) (xy 296.541098 -390.620479) (xy 296.586954 -390.591014)
			(xy 296.636537 -390.568375) (xy 296.688838 -390.553024) (xy 296.742791 -390.545272) (xy 296.770044 -390.544812)
			(xy 296.799481 -390.545375) (xy 296.857654 -390.554431) (xy 296.885868 -390.562846) (xy 296.894476 -390.565215)
			(xy 296.9123 -390.564437) (xy 296.920666 -390.561322) (xy 296.94886 -390.549384) (xy 296.957091 -390.545555)
			(xy 296.970367 -390.533193) (xy 296.974768 -390.525254) (xy 296.987932 -390.499558) (xy 297.019252 -390.451054)
			(xy 297.037252 -390.42848) (xy 297.042561 -390.421489) (xy 297.048528 -390.404991) (xy 297.048936 -390.396222)
			(xy 297.048936 -390.242298) (xy 297.048569 -390.233521) (xy 297.042587 -390.217019) (xy 297.037252 -390.21004)
			(xy 297.019272 -390.187452) (xy 296.987951 -390.138951) (xy 296.974768 -390.113266) (xy 296.970365 -390.105328)
			(xy 296.957092 -390.092962) (xy 296.94886 -390.089136) (xy 296.920666 -390.077198) (xy 296.91229 -390.074137)
			(xy 296.894485 -390.073371) (xy 296.885868 -390.075674) (xy 296.857656 -390.084099) (xy 296.799482 -390.093161)
			(xy 296.770044 -390.093708) (xy 296.742789 -390.093248) (xy 296.688833 -390.085496) (xy 296.63653 -390.070144)
			(xy 296.586945 -390.047504) (xy 296.541086 -390.018037) (xy 296.499888 -389.982343) (xy 296.46419 -389.941149)
			(xy 296.434718 -389.895294) (xy 296.412072 -389.845711) (xy 296.396714 -389.79341) (xy 296.388955 -389.739455)
			(xy 280.876248 -389.739455) (xy 280.876248 -392.067499) (xy 282.419292 -392.067499) (xy 282.419292 -392.003577)
			(xy 282.427303 -391.940159) (xy 282.4432 -391.878245) (xy 282.466732 -391.818812) (xy 282.497526 -391.762797)
			(xy 282.535099 -391.711082) (xy 282.578856 -391.664485) (xy 282.628109 -391.62374) (xy 282.68208 -391.589489)
			(xy 282.739919 -391.562272) (xy 282.800712 -391.542519) (xy 282.863502 -391.530541) (xy 282.927298 -391.526528)
			(xy 282.991094 -391.530541) (xy 283.053884 -391.542519) (xy 283.114677 -391.562272) (xy 283.172516 -391.589489)
			(xy 283.226487 -391.62374) (xy 283.27574 -391.664485) (xy 283.319497 -391.711082) (xy 283.35707 -391.762797)
			(xy 283.387864 -391.818812) (xy 283.411396 -391.878245) (xy 283.427293 -391.940159) (xy 283.435304 -392.003577)
			(xy 283.435806 -392.035538) (xy 283.435304 -392.067499) (xy 283.428015 -392.1252) (xy 299.683676 -392.1252)
			(xy 299.687747 -392.069578) (xy 299.699873 -392.015141) (xy 299.719796 -391.96305) (xy 299.747092 -391.914415)
			(xy 299.781178 -391.870272) (xy 299.821327 -391.831563) (xy 299.866685 -391.799112) (xy 299.916285 -391.773611)
			(xy 299.969069 -391.755604) (xy 300.023912 -391.745474) (xy 300.079646 -391.743437) (xy 300.135083 -391.749537)
			(xy 300.18904 -391.763643) (xy 300.240369 -391.785455) (xy 300.287975 -391.814509) (xy 300.330843 -391.850184)
			(xy 300.36806 -391.891721) (xy 300.398833 -391.938234) (xy 300.422505 -391.988731) (xy 300.438573 -392.042138)
			(xy 300.446693 -392.097314) (xy 300.447202 -392.1252) (xy 300.446693 -392.153086) (xy 300.438573 -392.208262)
			(xy 300.422505 -392.261669) (xy 300.398833 -392.312166) (xy 300.36806 -392.358679) (xy 300.330843 -392.400216)
			(xy 300.287975 -392.435891) (xy 300.240369 -392.464945) (xy 300.18904 -392.486757) (xy 300.135083 -392.500863)
			(xy 300.079646 -392.506963) (xy 300.023912 -392.504926) (xy 299.969069 -392.494796) (xy 299.916285 -392.476789)
			(xy 299.866685 -392.451288) (xy 299.821327 -392.418837) (xy 299.781178 -392.380128) (xy 299.747092 -392.335985)
			(xy 299.719796 -392.28735) (xy 299.699873 -392.235259) (xy 299.687747 -392.180822) (xy 299.683676 -392.1252)
			(xy 283.428015 -392.1252) (xy 283.427293 -392.130917) (xy 283.411396 -392.192831) (xy 283.387864 -392.252264)
			(xy 283.35707 -392.308279) (xy 283.319497 -392.359994) (xy 283.27574 -392.406591) (xy 283.226487 -392.447336)
			(xy 283.172516 -392.481587) (xy 283.114677 -392.508804) (xy 283.053884 -392.528557) (xy 282.991094 -392.540535)
			(xy 282.927298 -392.544549) (xy 282.863502 -392.540535) (xy 282.800712 -392.528557) (xy 282.739919 -392.508804)
			(xy 282.68208 -392.481587) (xy 282.628109 -392.447336) (xy 282.578856 -392.406591) (xy 282.535099 -392.359994)
			(xy 282.497526 -392.308279) (xy 282.466732 -392.252264) (xy 282.4432 -392.192831) (xy 282.427303 -392.130917)
			(xy 282.419292 -392.067499) (xy 280.876248 -392.067499) (xy 280.876248 -393.137855) (xy 282.07436 -393.137855)
			(xy 282.07436 -393.073933) (xy 282.082371 -393.010515) (xy 282.098268 -392.948601) (xy 282.1218 -392.889168)
			(xy 282.152594 -392.833153) (xy 282.190167 -392.781438) (xy 282.233924 -392.734841) (xy 282.283177 -392.694096)
			(xy 282.337148 -392.659845) (xy 282.394987 -392.632628) (xy 282.45578 -392.612875) (xy 282.51857 -392.600897)
			(xy 282.582366 -392.596884) (xy 282.646162 -392.600897) (xy 282.708952 -392.612875) (xy 282.769745 -392.632628)
			(xy 282.827584 -392.659845) (xy 282.881555 -392.694096) (xy 282.930808 -392.734841) (xy 282.974565 -392.781438)
			(xy 283.012138 -392.833153) (xy 283.042932 -392.889168) (xy 283.066464 -392.948601) (xy 283.082361 -393.010515)
			(xy 283.090372 -393.073933) (xy 283.090874 -393.105894) (xy 283.090372 -393.137855) (xy 283.082361 -393.201273)
			(xy 283.066464 -393.263187) (xy 283.042932 -393.32262) (xy 283.012138 -393.378635) (xy 282.974565 -393.43035)
			(xy 282.930808 -393.476947) (xy 282.881555 -393.517692) (xy 282.827584 -393.551943) (xy 282.769745 -393.57916)
			(xy 282.708952 -393.598913) (xy 282.646162 -393.610891) (xy 282.582366 -393.614905) (xy 282.51857 -393.610891)
			(xy 282.45578 -393.598913) (xy 282.394987 -393.57916) (xy 282.337148 -393.551943) (xy 282.283177 -393.517692)
			(xy 282.233924 -393.476947) (xy 282.190167 -393.43035) (xy 282.152594 -393.378635) (xy 282.1218 -393.32262)
			(xy 282.098268 -393.263187) (xy 282.082371 -393.201273) (xy 282.07436 -393.137855) (xy 280.876248 -393.137855)
			(xy 280.876248 -394.070078) (xy 283.861 -394.070078) (xy 283.865071 -394.014456) (xy 283.877197 -393.960019)
			(xy 283.89712 -393.907928) (xy 283.924416 -393.859293) (xy 283.958502 -393.81515) (xy 283.998651 -393.776441)
			(xy 284.044009 -393.74399) (xy 284.093609 -393.718489) (xy 284.146393 -393.700482) (xy 284.201236 -393.690352)
			(xy 284.25697 -393.688315) (xy 284.312407 -393.694415) (xy 284.366364 -393.708521) (xy 284.417693 -393.730333)
			(xy 284.465299 -393.759387) (xy 284.508167 -393.795062) (xy 284.545384 -393.836599) (xy 284.576157 -393.883112)
			(xy 284.599829 -393.933609) (xy 284.615897 -393.987016) (xy 284.61758 -393.99845) (xy 294.51046 -393.99845)
			(xy 294.510873 -393.968733) (xy 294.517813 -393.909705) (xy 294.531581 -393.851888) (xy 294.55199 -393.796068)
			(xy 294.578761 -393.743004) (xy 294.611531 -393.69342) (xy 294.649853 -393.647991) (xy 294.671242 -393.627356)
			(xy 294.678608 -393.620498) (xy 294.686736 -393.603226) (xy 294.692324 -393.514072) (xy 294.686228 -393.49553)
			(xy 294.679878 -393.488164) (xy 294.663231 -393.467504) (xy 294.635233 -393.422437) (xy 294.61376 -393.373921)
			(xy 294.599228 -393.322894) (xy 294.591918 -393.270344) (xy 294.591486 -393.243816) (xy 294.59201 -393.216113)
			(xy 294.600049 -393.161294) (xy 294.615932 -393.108213) (xy 294.639324 -393.057987) (xy 294.669733 -393.011673)
			(xy 294.706521 -392.970243) (xy 294.748914 -392.934568) (xy 294.796021 -392.9054) (xy 294.84685 -392.88335)
			(xy 294.900334 -392.868884) (xy 294.927782 -392.865102) (xy 294.937688 -392.863832) (xy 294.954198 -392.854942)
			(xy 295.011856 -392.78687) (xy 295.017698 -392.768836) (xy 295.017444 -392.75893) (xy 295.016682 -392.73353)
			(xy 295.017136 -392.701987) (xy 295.024936 -392.639384) (xy 295.040419 -392.578226) (xy 295.063349 -392.519454)
			(xy 295.093372 -392.463969) (xy 295.130028 -392.412624) (xy 295.172753 -392.366208) (xy 295.220892 -392.325433)
			(xy 295.273705 -392.290925) (xy 295.33038 -392.263216) (xy 295.390048 -392.242729) (xy 295.451792 -392.22978)
			(xy 295.514663 -392.224569) (xy 295.577696 -392.227174) (xy 295.639923 -392.237555) (xy 295.700387 -392.255555)
			(xy 295.758161 -392.280895) (xy 295.812357 -392.313187) (xy 295.862142 -392.351935) (xy 295.906752 -392.396543)
			(xy 295.945502 -392.446327) (xy 295.977796 -392.500521) (xy 296.003138 -392.558294) (xy 296.02114 -392.618758)
			(xy 296.031524 -392.680984) (xy 296.034132 -392.744017) (xy 296.028922 -392.806889) (xy 296.015976 -392.868633)
			(xy 295.995492 -392.928301) (xy 295.967785 -392.984978) (xy 295.933279 -393.037792) (xy 295.927445 -393.04468)
			(xy 299.683676 -393.04468) (xy 299.687747 -392.989058) (xy 299.699873 -392.934621) (xy 299.719796 -392.88253)
			(xy 299.747092 -392.833895) (xy 299.781178 -392.789752) (xy 299.821327 -392.751043) (xy 299.866685 -392.718592)
			(xy 299.916285 -392.693091) (xy 299.969069 -392.675084) (xy 300.023912 -392.664954) (xy 300.079646 -392.662917)
			(xy 300.135083 -392.669017) (xy 300.18904 -392.683123) (xy 300.240369 -392.704935) (xy 300.287975 -392.733989)
			(xy 300.330454 -392.76934) (xy 300.943754 -392.76934) (xy 300.943754 -392.709404) (xy 300.951577 -392.649982)
			(xy 300.96709 -392.592089) (xy 300.990026 -392.536716) (xy 301.019993 -392.48481) (xy 301.05648 -392.43726)
			(xy 301.09886 -392.39488) (xy 301.14641 -392.358393) (xy 301.198316 -392.328426) (xy 301.253689 -392.30549)
			(xy 301.311582 -392.289977) (xy 301.371004 -392.282154) (xy 301.43094 -392.282154) (xy 301.490362 -392.289977)
			(xy 301.548255 -392.30549) (xy 301.603628 -392.328426) (xy 301.655534 -392.358393) (xy 301.703084 -392.39488)
			(xy 301.745464 -392.43726) (xy 301.781951 -392.48481) (xy 301.811918 -392.536716) (xy 301.834854 -392.592089)
			(xy 301.850367 -392.649982) (xy 301.85819 -392.709404) (xy 301.85868 -392.739372) (xy 301.85819 -392.76934)
			(xy 301.850367 -392.828762) (xy 301.834854 -392.886655) (xy 301.811918 -392.942028) (xy 301.781951 -392.993934)
			(xy 301.745464 -393.041484) (xy 301.703084 -393.083864) (xy 301.655534 -393.120351) (xy 301.603628 -393.150318)
			(xy 301.548255 -393.173254) (xy 301.490362 -393.188767) (xy 301.43094 -393.19659) (xy 301.371004 -393.19659)
			(xy 301.311582 -393.188767) (xy 301.253689 -393.173254) (xy 301.198316 -393.150318) (xy 301.14641 -393.120351)
			(xy 301.09886 -393.083864) (xy 301.05648 -393.041484) (xy 301.019993 -392.993934) (xy 300.990026 -392.942028)
			(xy 300.96709 -392.886655) (xy 300.951577 -392.828762) (xy 300.943754 -392.76934) (xy 300.330454 -392.76934)
			(xy 300.330843 -392.769664) (xy 300.36806 -392.811201) (xy 300.398833 -392.857714) (xy 300.422505 -392.908211)
			(xy 300.438573 -392.961618) (xy 300.446693 -393.016794) (xy 300.447202 -393.04468) (xy 300.446693 -393.072566)
			(xy 300.438573 -393.127742) (xy 300.422505 -393.181149) (xy 300.398833 -393.231646) (xy 300.36806 -393.278159)
			(xy 300.330843 -393.319696) (xy 300.287975 -393.355371) (xy 300.240369 -393.384425) (xy 300.18904 -393.406237)
			(xy 300.135083 -393.420343) (xy 300.079646 -393.426443) (xy 300.023912 -393.424406) (xy 299.969069 -393.414276)
			(xy 299.916285 -393.396269) (xy 299.866685 -393.370768) (xy 299.821327 -393.338317) (xy 299.781178 -393.299608)
			(xy 299.747092 -393.255465) (xy 299.719796 -393.20683) (xy 299.699873 -393.154739) (xy 299.687747 -393.100302)
			(xy 299.683676 -393.04468) (xy 295.927445 -393.04468) (xy 295.892506 -393.085932) (xy 295.846091 -393.12866)
			(xy 295.794748 -393.165317) (xy 295.739264 -393.195343) (xy 295.680493 -393.218275) (xy 295.619336 -393.233761)
			(xy 295.556733 -393.241563) (xy 295.52519 -393.242038) (xy 295.508759 -393.241884) (xy 295.475967 -393.239723)
			(xy 295.459658 -393.23772) (xy 295.450006 -393.23645) (xy 295.431718 -393.241276) (xy 295.359328 -393.293092)
			(xy 295.348914 -393.30884) (xy 295.347136 -393.318746) (xy 295.342089 -393.342115) (xy 295.326919 -393.387455)
			(xy 295.3062 -393.430544) (xy 295.293542 -393.450826) (xy 295.288208 -393.458954) (xy 295.284398 -393.478004)
			(xy 295.300654 -393.565634) (xy 295.311068 -393.582144) (xy 295.318942 -393.587732) (xy 295.346205 -393.60832)
			(xy 295.39547 -393.655652) (xy 295.437957 -393.709153) (xy 295.4729 -393.767859) (xy 295.499672 -393.830714)
			(xy 295.517789 -393.896586) (xy 295.526927 -393.964291) (xy 295.527364 -393.991454) (xy 299.684638 -393.991454)
			(xy 299.684638 -393.936946) (xy 299.692395 -393.882993) (xy 299.707751 -393.830694) (xy 299.730395 -393.781112)
			(xy 299.759863 -393.735257) (xy 299.795558 -393.694062) (xy 299.836752 -393.658367) (xy 299.882606 -393.628897)
			(xy 299.932188 -393.606254) (xy 299.984487 -393.590896) (xy 300.03844 -393.583138) (xy 300.065694 -393.582652)
			(xy 300.094327 -393.583205) (xy 300.150949 -393.591764) (xy 300.205656 -393.608688) (xy 300.257219 -393.6336)
			(xy 300.30448 -393.665938) (xy 300.346377 -393.704976) (xy 300.381968 -393.749838) (xy 300.396656 -393.774422)
			(xy 300.403768 -393.786614) (xy 300.427644 -393.80033) (xy 300.544738 -393.798044) (xy 300.568106 -393.78382)
			(xy 300.57471 -393.771374) (xy 300.589643 -393.744119) (xy 300.625774 -393.693554) (xy 300.668418 -393.648346)
			(xy 300.716789 -393.609327) (xy 300.769998 -393.577216) (xy 300.827063 -393.552603) (xy 300.886936 -393.535943)
			(xy 300.948512 -393.527541) (xy 300.979586 -393.527026) (xy 301.009556 -393.527474) (xy 301.068984 -393.535297)
			(xy 301.126882 -393.55081) (xy 301.182259 -393.573748) (xy 301.234169 -393.603718) (xy 301.281722 -393.640208)
			(xy 301.324105 -393.682593) (xy 301.360593 -393.730148) (xy 301.390561 -393.782059) (xy 301.413497 -393.837437)
			(xy 301.429007 -393.895336) (xy 301.436827 -393.954764) (xy 301.437294 -393.984734) (xy 301.436783 -394.015614)
			(xy 301.428468 -394.076811) (xy 301.411994 -394.136333) (xy 301.387661 -394.193096) (xy 301.355911 -394.246069)
			(xy 301.346739 -394.25753) (xy 302.833786 -394.25753) (xy 302.834303 -394.231542) (xy 302.842429 -394.180205)
			(xy 302.858487 -394.130771) (xy 302.882081 -394.084459) (xy 302.912629 -394.042407) (xy 302.94938 -394.005652)
			(xy 302.991428 -393.975099) (xy 303.037738 -393.951501) (xy 303.08717 -393.935438) (xy 303.138506 -393.927306)
			(xy 303.164494 -393.926822) (xy 303.180927 -393.927054) (xy 303.213627 -393.930358) (xy 303.229772 -393.933426)
			(xy 303.242726 -393.935966) (xy 303.267872 -393.928092) (xy 303.345088 -393.846304) (xy 303.351692 -393.820904)
			(xy 303.34839 -393.808204) (xy 303.341384 -393.779762) (xy 303.333866 -393.721669) (xy 303.333404 -393.69238)
			(xy 303.333929 -393.661492) (xy 303.342234 -393.600277) (xy 303.358691 -393.540733) (xy 303.383001 -393.483941)
			(xy 303.398428 -393.457176) (xy 303.40427 -393.44727) (xy 303.406556 -393.424918) (xy 303.373282 -393.329668)
			(xy 303.357534 -393.313666) (xy 303.346866 -393.309602) (xy 303.323478 -393.300434) (xy 303.279582 -393.276012)
			(xy 303.239886 -393.245228) (xy 303.205306 -393.208792) (xy 303.176638 -393.167543) (xy 303.154541 -393.122431)
			(xy 303.139525 -393.074495) (xy 303.131936 -393.024839) (xy 303.131474 -392.999722) (xy 303.131984 -392.973735)
			(xy 303.140114 -392.9224) (xy 303.156175 -392.87297) (xy 303.179771 -392.82666) (xy 303.210321 -392.784612)
			(xy 303.247072 -392.747861) (xy 303.28912 -392.717311) (xy 303.33543 -392.693715) (xy 303.38486 -392.677654)
			(xy 303.436195 -392.669524) (xy 303.488169 -392.669524) (xy 303.539504 -392.677654) (xy 303.588934 -392.693715)
			(xy 303.635244 -392.717311) (xy 303.677292 -392.747861) (xy 303.714043 -392.784612) (xy 303.744593 -392.82666)
			(xy 303.768189 -392.87297) (xy 303.78425 -392.9224) (xy 303.79238 -392.973735) (xy 303.79289 -392.999722)
			(xy 304.33137 -392.999722) (xy 304.33188 -392.973735) (xy 304.34001 -392.9224) (xy 304.356071 -392.87297)
			(xy 304.379667 -392.82666) (xy 304.410217 -392.784612) (xy 304.446968 -392.747861) (xy 304.489016 -392.717311)
			(xy 304.535326 -392.693715) (xy 304.584756 -392.677654) (xy 304.636091 -392.669524) (xy 304.688065 -392.669524)
			(xy 304.7394 -392.677654) (xy 304.78883 -392.693715) (xy 304.83514 -392.717311) (xy 304.877188 -392.747861)
			(xy 304.913939 -392.784612) (xy 304.944489 -392.82666) (xy 304.968085 -392.87297) (xy 304.984146 -392.9224)
			(xy 304.992276 -392.973735) (xy 304.992786 -392.999722) (xy 305.53152 -392.999722) (xy 305.53203 -392.973735)
			(xy 305.54016 -392.9224) (xy 305.556221 -392.87297) (xy 305.579817 -392.82666) (xy 305.610367 -392.784612)
			(xy 305.647118 -392.747861) (xy 305.689166 -392.717311) (xy 305.735476 -392.693715) (xy 305.784906 -392.677654)
			(xy 305.836241 -392.669524) (xy 305.888215 -392.669524) (xy 305.93955 -392.677654) (xy 305.98898 -392.693715)
			(xy 306.03529 -392.717311) (xy 306.077338 -392.747861) (xy 306.114089 -392.784612) (xy 306.144639 -392.82666)
			(xy 306.168235 -392.87297) (xy 306.184296 -392.9224) (xy 306.192426 -392.973735) (xy 306.192936 -392.999722)
			(xy 306.731416 -392.999722) (xy 306.731926 -392.973735) (xy 306.740056 -392.9224) (xy 306.756117 -392.87297)
			(xy 306.779713 -392.82666) (xy 306.810263 -392.784612) (xy 306.847014 -392.747861) (xy 306.889062 -392.717311)
			(xy 306.935372 -392.693715) (xy 306.984802 -392.677654) (xy 307.036137 -392.669524) (xy 307.088111 -392.669524)
			(xy 307.139446 -392.677654) (xy 307.188876 -392.693715) (xy 307.235186 -392.717311) (xy 307.277234 -392.747861)
			(xy 307.313985 -392.784612) (xy 307.344535 -392.82666) (xy 307.368131 -392.87297) (xy 307.384192 -392.9224)
			(xy 307.392322 -392.973735) (xy 307.392832 -392.999722) (xy 307.931566 -392.999722) (xy 307.932076 -392.973735)
			(xy 307.940206 -392.9224) (xy 307.956267 -392.87297) (xy 307.979863 -392.82666) (xy 308.010413 -392.784612)
			(xy 308.047164 -392.747861) (xy 308.089212 -392.717311) (xy 308.135522 -392.693715) (xy 308.184952 -392.677654)
			(xy 308.236287 -392.669524) (xy 308.288261 -392.669524) (xy 308.339596 -392.677654) (xy 308.389026 -392.693715)
			(xy 308.435336 -392.717311) (xy 308.477384 -392.747861) (xy 308.514135 -392.784612) (xy 308.544685 -392.82666)
			(xy 308.568281 -392.87297) (xy 308.584342 -392.9224) (xy 308.592472 -392.973735) (xy 308.592982 -392.999722)
			(xy 309.131462 -392.999722) (xy 309.131972 -392.973735) (xy 309.140102 -392.9224) (xy 309.156163 -392.87297)
			(xy 309.179759 -392.82666) (xy 309.210309 -392.784612) (xy 309.24706 -392.747861) (xy 309.289108 -392.717311)
			(xy 309.335418 -392.693715) (xy 309.384848 -392.677654) (xy 309.436183 -392.669524) (xy 309.488157 -392.669524)
			(xy 309.539492 -392.677654) (xy 309.588922 -392.693715) (xy 309.635232 -392.717311) (xy 309.67728 -392.747861)
			(xy 309.714031 -392.784612) (xy 309.744581 -392.82666) (xy 309.768177 -392.87297) (xy 309.784238 -392.9224)
			(xy 309.792368 -392.973735) (xy 309.792878 -392.999722) (xy 310.331358 -392.999722) (xy 310.331868 -392.973735)
			(xy 310.339998 -392.9224) (xy 310.356059 -392.87297) (xy 310.379655 -392.82666) (xy 310.410205 -392.784612)
			(xy 310.446956 -392.747861) (xy 310.489004 -392.717311) (xy 310.535314 -392.693715) (xy 310.584744 -392.677654)
			(xy 310.636079 -392.669524) (xy 310.688053 -392.669524) (xy 310.739388 -392.677654) (xy 310.788818 -392.693715)
			(xy 310.835128 -392.717311) (xy 310.877176 -392.747861) (xy 310.913927 -392.784612) (xy 310.944477 -392.82666)
			(xy 310.968073 -392.87297) (xy 310.984134 -392.9224) (xy 310.992264 -392.973735) (xy 310.992774 -392.999722)
			(xy 311.531508 -392.999722) (xy 311.532018 -392.973735) (xy 311.540148 -392.9224) (xy 311.556209 -392.87297)
			(xy 311.579805 -392.82666) (xy 311.610355 -392.784612) (xy 311.647106 -392.747861) (xy 311.689154 -392.717311)
			(xy 311.735464 -392.693715) (xy 311.784894 -392.677654) (xy 311.836229 -392.669524) (xy 311.888203 -392.669524)
			(xy 311.939538 -392.677654) (xy 311.988968 -392.693715) (xy 312.035278 -392.717311) (xy 312.077326 -392.747861)
			(xy 312.114077 -392.784612) (xy 312.144627 -392.82666) (xy 312.168223 -392.87297) (xy 312.184284 -392.9224)
			(xy 312.192414 -392.973735) (xy 312.192924 -392.999722) (xy 312.731404 -392.999722) (xy 312.731914 -392.973735)
			(xy 312.740044 -392.9224) (xy 312.756105 -392.87297) (xy 312.779701 -392.82666) (xy 312.810251 -392.784612)
			(xy 312.847002 -392.747861) (xy 312.88905 -392.717311) (xy 312.93536 -392.693715) (xy 312.98479 -392.677654)
			(xy 313.036125 -392.669524) (xy 313.088099 -392.669524) (xy 313.139434 -392.677654) (xy 313.188864 -392.693715)
			(xy 313.235174 -392.717311) (xy 313.277222 -392.747861) (xy 313.313973 -392.784612) (xy 313.344523 -392.82666)
			(xy 313.368119 -392.87297) (xy 313.38418 -392.9224) (xy 313.39231 -392.973735) (xy 313.39282 -392.999722)
			(xy 313.931554 -392.999722) (xy 313.932064 -392.973735) (xy 313.940194 -392.9224) (xy 313.956255 -392.87297)
			(xy 313.979851 -392.82666) (xy 314.010401 -392.784612) (xy 314.047152 -392.747861) (xy 314.0892 -392.717311)
			(xy 314.13551 -392.693715) (xy 314.18494 -392.677654) (xy 314.236275 -392.669524) (xy 314.288249 -392.669524)
			(xy 314.339584 -392.677654) (xy 314.389014 -392.693715) (xy 314.435324 -392.717311) (xy 314.477372 -392.747861)
			(xy 314.514123 -392.784612) (xy 314.544673 -392.82666) (xy 314.568269 -392.87297) (xy 314.58433 -392.9224)
			(xy 314.59246 -392.973735) (xy 314.59297 -392.999722) (xy 315.13145 -392.999722) (xy 315.13196 -392.973735)
			(xy 315.14009 -392.9224) (xy 315.156151 -392.87297) (xy 315.179747 -392.82666) (xy 315.210297 -392.784612)
			(xy 315.247048 -392.747861) (xy 315.289096 -392.717311) (xy 315.335406 -392.693715) (xy 315.384836 -392.677654)
			(xy 315.436171 -392.669524) (xy 315.488145 -392.669524) (xy 315.53948 -392.677654) (xy 315.58891 -392.693715)
			(xy 315.63522 -392.717311) (xy 315.677268 -392.747861) (xy 315.714019 -392.784612) (xy 315.744569 -392.82666)
			(xy 315.768165 -392.87297) (xy 315.784226 -392.9224) (xy 315.792356 -392.973735) (xy 315.792866 -392.999722)
			(xy 316.331346 -392.999722) (xy 316.331856 -392.973735) (xy 316.339986 -392.9224) (xy 316.356047 -392.87297)
			(xy 316.379643 -392.82666) (xy 316.410193 -392.784612) (xy 316.446944 -392.747861) (xy 316.488992 -392.717311)
			(xy 316.535302 -392.693715) (xy 316.584732 -392.677654) (xy 316.636067 -392.669524) (xy 316.688041 -392.669524)
			(xy 316.739376 -392.677654) (xy 316.788806 -392.693715) (xy 316.835116 -392.717311) (xy 316.877164 -392.747861)
			(xy 316.913915 -392.784612) (xy 316.944465 -392.82666) (xy 316.968061 -392.87297) (xy 316.984122 -392.9224)
			(xy 316.992252 -392.973735) (xy 316.992762 -392.999722) (xy 317.531496 -392.999722) (xy 317.532006 -392.973735)
			(xy 317.540136 -392.9224) (xy 317.556197 -392.87297) (xy 317.579793 -392.82666) (xy 317.610343 -392.784612)
			(xy 317.647094 -392.747861) (xy 317.689142 -392.717311) (xy 317.735452 -392.693715) (xy 317.784882 -392.677654)
			(xy 317.836217 -392.669524) (xy 317.888191 -392.669524) (xy 317.939526 -392.677654) (xy 317.988956 -392.693715)
			(xy 318.035266 -392.717311) (xy 318.077314 -392.747861) (xy 318.114065 -392.784612) (xy 318.144615 -392.82666)
			(xy 318.168211 -392.87297) (xy 318.184272 -392.9224) (xy 318.192402 -392.973735) (xy 318.192912 -392.999722)
			(xy 318.731392 -392.999722) (xy 318.731902 -392.973735) (xy 318.740032 -392.9224) (xy 318.756093 -392.87297)
			(xy 318.779689 -392.82666) (xy 318.810239 -392.784612) (xy 318.84699 -392.747861) (xy 318.889038 -392.717311)
			(xy 318.935348 -392.693715) (xy 318.984778 -392.677654) (xy 319.036113 -392.669524) (xy 319.088087 -392.669524)
			(xy 319.139422 -392.677654) (xy 319.188852 -392.693715) (xy 319.235162 -392.717311) (xy 319.27721 -392.747861)
			(xy 319.313961 -392.784612) (xy 319.344511 -392.82666) (xy 319.368107 -392.87297) (xy 319.384168 -392.9224)
			(xy 319.392298 -392.973735) (xy 319.392808 -392.999722) (xy 319.931542 -392.999722) (xy 319.932052 -392.973735)
			(xy 319.940182 -392.9224) (xy 319.956243 -392.87297) (xy 319.979839 -392.82666) (xy 320.010389 -392.784612)
			(xy 320.04714 -392.747861) (xy 320.089188 -392.717311) (xy 320.135498 -392.693715) (xy 320.184928 -392.677654)
			(xy 320.236263 -392.669524) (xy 320.288237 -392.669524) (xy 320.339572 -392.677654) (xy 320.389002 -392.693715)
			(xy 320.435312 -392.717311) (xy 320.47736 -392.747861) (xy 320.514111 -392.784612) (xy 320.544661 -392.82666)
			(xy 320.568257 -392.87297) (xy 320.584318 -392.9224) (xy 320.592448 -392.973735) (xy 320.592958 -392.999722)
			(xy 321.131438 -392.999722) (xy 321.131948 -392.973735) (xy 321.140078 -392.9224) (xy 321.156139 -392.87297)
			(xy 321.179735 -392.82666) (xy 321.210285 -392.784612) (xy 321.247036 -392.747861) (xy 321.289084 -392.717311)
			(xy 321.335394 -392.693715) (xy 321.384824 -392.677654) (xy 321.436159 -392.669524) (xy 321.488133 -392.669524)
			(xy 321.539468 -392.677654) (xy 321.588898 -392.693715) (xy 321.635208 -392.717311) (xy 321.677256 -392.747861)
			(xy 321.714007 -392.784612) (xy 321.744557 -392.82666) (xy 321.768153 -392.87297) (xy 321.784214 -392.9224)
			(xy 321.792344 -392.973735) (xy 321.792854 -392.999722) (xy 321.792324 -393.026824) (xy 321.783514 -393.080307)
			(xy 321.775328 -393.106148) (xy 321.771518 -393.11707) (xy 321.774058 -393.139422) (xy 321.826636 -393.225274)
			(xy 321.845686 -393.23772) (xy 321.856862 -393.239498) (xy 321.886184 -393.244181) (xy 321.943355 -393.260233)
			(xy 321.997969 -393.283547) (xy 322.049108 -393.313729) (xy 322.095913 -393.350273) (xy 322.137597 -393.392564)
			(xy 322.173461 -393.439893) (xy 322.2029 -393.491463) (xy 322.219247 -393.531344) (xy 323.302122 -393.531344)
			(xy 323.302547 -393.502708) (xy 323.309704 -393.445886) (xy 323.323886 -393.390398) (xy 323.344873 -393.33711)
			(xy 323.372338 -393.286854) (xy 323.388736 -393.263374) (xy 323.394412 -393.254857) (xy 323.399022 -393.23493)
			(xy 323.395455 -393.214791) (xy 323.39026 -393.20597) (xy 323.372773 -393.177993) (xy 323.345144 -393.11808)
			(xy 323.326398 -393.054823) (xy 323.316925 -392.98953) (xy 323.316346 -392.956542) (xy 323.316808 -392.927301)
			(xy 323.324241 -392.869294) (xy 323.339002 -392.812706) (xy 323.360853 -392.75846) (xy 323.389436 -392.707439)
			(xy 323.424286 -392.660476) (xy 323.464835 -392.618335) (xy 323.510423 -392.581703) (xy 323.560305 -392.551177)
			(xy 323.61367 -392.527255) (xy 323.669648 -392.510327) (xy 323.727326 -392.500667) (xy 323.756528 -392.499088)
			(xy 323.76618 -392.498834) (xy 323.783706 -392.491214) (xy 323.84619 -392.428222) (xy 323.85381 -392.41095)
			(xy 323.854064 -392.401044) (xy 323.855653 -392.368494) (xy 323.866143 -392.304172) (xy 323.884763 -392.241718)
			(xy 323.91121 -392.182155) (xy 323.945051 -392.126459) (xy 323.985729 -392.075542) (xy 324.032579 -392.03024)
			(xy 324.084833 -391.991294) (xy 324.141634 -391.959343) (xy 324.202051 -391.93491) (xy 324.265095 -391.918397)
			(xy 324.329733 -391.910073) (xy 324.362318 -391.909554) (xy 324.395901 -391.910123) (xy 324.462484 -391.918949)
			(xy 324.527324 -391.936469) (xy 324.58929 -391.96238) (xy 324.647303 -391.99623) (xy 324.70035 -392.037427)
			(xy 324.747506 -392.085255) (xy 324.78795 -392.138878) (xy 324.820977 -392.197363) (xy 324.833996 -392.228324)
			(xy 324.839584 -392.24204) (xy 324.863206 -392.259058) (xy 324.984364 -392.266678) (xy 325.010018 -392.252454)
			(xy 325.01713 -392.2395) (xy 325.034073 -392.210169) (xy 325.07448 -392.155808) (xy 325.121742 -392.107288)
			(xy 325.175024 -392.065467) (xy 325.233384 -392.031086) (xy 325.295789 -392.004751) (xy 325.361137 -391.986929)
			(xy 325.428271 -391.977934) (xy 325.462138 -391.977372) (xy 325.50139 -391.978139) (xy 325.578955 -391.990257)
			(xy 325.61657 -392.001502) (xy 325.629016 -392.005312) (xy 325.654924 -392.000232) (xy 325.740522 -391.927334)
			(xy 325.74992 -391.902696) (xy 325.747888 -391.889742) (xy 325.745989 -391.875914) (xy 325.743954 -391.848073)
			(xy 325.743824 -391.834116) (xy 325.74431 -391.806865) (xy 325.752066 -391.752917) (xy 325.767421 -391.700622)
			(xy 325.790063 -391.651045) (xy 325.819529 -391.605195) (xy 325.85522 -391.564004) (xy 325.896411 -391.528313)
			(xy 325.942261 -391.498847) (xy 325.991838 -391.476205) (xy 326.044133 -391.46085) (xy 326.098081 -391.453094)
			(xy 326.152583 -391.453094) (xy 326.206531 -391.46085) (xy 326.258826 -391.476205) (xy 326.308403 -391.498847)
			(xy 326.354253 -391.528313) (xy 326.395444 -391.564004) (xy 326.431135 -391.605195) (xy 326.460601 -391.651045)
			(xy 326.483243 -391.700622) (xy 326.498598 -391.752917) (xy 326.506354 -391.806865) (xy 326.50684 -391.834116)
			(xy 326.506166 -391.865763) (xy 326.495693 -391.928185) (xy 326.486012 -391.958322) (xy 326.483605 -391.96662)
			(xy 326.483861 -391.983884) (xy 326.48652 -391.992104) (xy 326.49668 -392.020298) (xy 326.499972 -392.028543)
			(xy 326.511284 -392.04221) (xy 326.518778 -392.046968) (xy 326.547098 -392.064151) (xy 326.599479 -392.104699)
			(xy 326.619831 -392.1252) (xy 332.211424 -392.1252) (xy 332.215495 -392.069578) (xy 332.227621 -392.015141)
			(xy 332.247544 -391.96305) (xy 332.27484 -391.914415) (xy 332.308926 -391.870272) (xy 332.349075 -391.831563)
			(xy 332.394433 -391.799112) (xy 332.444033 -391.773611) (xy 332.496817 -391.755604) (xy 332.55166 -391.745474)
			(xy 332.607394 -391.743437) (xy 332.662831 -391.749537) (xy 332.716788 -391.763643) (xy 332.768117 -391.785455)
			(xy 332.815723 -391.814509) (xy 332.858591 -391.850184) (xy 332.895808 -391.891721) (xy 332.926581 -391.938234)
			(xy 332.950253 -391.988731) (xy 332.966321 -392.042138) (xy 332.974441 -392.097314) (xy 332.97495 -392.1252)
			(xy 332.974441 -392.153086) (xy 332.966321 -392.208262) (xy 332.950253 -392.261669) (xy 332.926581 -392.312166)
			(xy 332.895808 -392.358679) (xy 332.858591 -392.400216) (xy 332.815723 -392.435891) (xy 332.768117 -392.464945)
			(xy 332.716788 -392.486757) (xy 332.662831 -392.500863) (xy 332.607394 -392.506963) (xy 332.55166 -392.504926)
			(xy 332.496817 -392.494796) (xy 332.444033 -392.476789) (xy 332.394433 -392.451288) (xy 332.349075 -392.418837)
			(xy 332.308926 -392.380128) (xy 332.27484 -392.335985) (xy 332.247544 -392.28735) (xy 332.227621 -392.235259)
			(xy 332.215495 -392.180822) (xy 332.211424 -392.1252) (xy 326.619831 -392.1252) (xy 326.646148 -392.151709)
			(xy 326.686313 -392.204384) (xy 326.719295 -392.261831) (xy 326.744534 -392.323075) (xy 326.761603 -392.38708)
			(xy 326.770211 -392.452759) (xy 326.770746 -392.48588) (xy 326.770328 -392.51599) (xy 326.763197 -392.575788)
			(xy 326.749054 -392.634325) (xy 326.728099 -392.690782) (xy 326.700624 -392.744371) (xy 326.667014 -392.79434)
			(xy 326.627738 -392.839991) (xy 326.583348 -392.880686) (xy 326.559164 -392.89863) (xy 326.5497 -392.906256)
			(xy 326.538699 -392.927892) (xy 326.538082 -392.940032) (xy 326.538082 -393.022328) (xy 326.538689 -393.034463)
			(xy 326.543906 -393.04468) (xy 332.211424 -393.04468) (xy 332.215495 -392.989058) (xy 332.227621 -392.934621)
			(xy 332.247544 -392.88253) (xy 332.27484 -392.833895) (xy 332.308926 -392.789752) (xy 332.349075 -392.751043)
			(xy 332.394433 -392.718592) (xy 332.444033 -392.693091) (xy 332.496817 -392.675084) (xy 332.55166 -392.664954)
			(xy 332.607394 -392.662917) (xy 332.662831 -392.669017) (xy 332.716788 -392.683123) (xy 332.768117 -392.704935)
			(xy 332.815723 -392.733989) (xy 332.858202 -392.76934) (xy 333.471502 -392.76934) (xy 333.471502 -392.709404)
			(xy 333.479325 -392.649982) (xy 333.494838 -392.592089) (xy 333.517774 -392.536716) (xy 333.547741 -392.48481)
			(xy 333.584228 -392.43726) (xy 333.626608 -392.39488) (xy 333.674158 -392.358393) (xy 333.726064 -392.328426)
			(xy 333.781437 -392.30549) (xy 333.83933 -392.289977) (xy 333.898752 -392.282154) (xy 333.958688 -392.282154)
			(xy 334.01811 -392.289977) (xy 334.076003 -392.30549) (xy 334.131376 -392.328426) (xy 334.183282 -392.358393)
			(xy 334.230832 -392.39488) (xy 334.273212 -392.43726) (xy 334.309699 -392.48481) (xy 334.339666 -392.536716)
			(xy 334.362602 -392.592089) (xy 334.378115 -392.649982) (xy 334.385938 -392.709404) (xy 334.386428 -392.739372)
			(xy 334.385938 -392.76934) (xy 334.378115 -392.828762) (xy 334.362602 -392.886655) (xy 334.339666 -392.942028)
			(xy 334.309699 -392.993934) (xy 334.273212 -393.041484) (xy 334.230832 -393.083864) (xy 334.183282 -393.120351)
			(xy 334.131376 -393.150318) (xy 334.076003 -393.173254) (xy 334.01811 -393.188767) (xy 333.958688 -393.19659)
			(xy 333.898752 -393.19659) (xy 333.83933 -393.188767) (xy 333.781437 -393.173254) (xy 333.726064 -393.150318)
			(xy 333.674158 -393.120351) (xy 333.626608 -393.083864) (xy 333.584228 -393.041484) (xy 333.547741 -392.993934)
			(xy 333.517774 -392.942028) (xy 333.494838 -392.886655) (xy 333.479325 -392.828762) (xy 333.471502 -392.76934)
			(xy 332.858202 -392.76934) (xy 332.858591 -392.769664) (xy 332.895808 -392.811201) (xy 332.926581 -392.857714)
			(xy 332.950253 -392.908211) (xy 332.966321 -392.961618) (xy 332.974441 -393.016794) (xy 332.97495 -393.04468)
			(xy 332.974441 -393.072566) (xy 332.966321 -393.127742) (xy 332.950253 -393.181149) (xy 332.926581 -393.231646)
			(xy 332.895808 -393.278159) (xy 332.858591 -393.319696) (xy 332.815723 -393.355371) (xy 332.768117 -393.384425)
			(xy 332.716788 -393.406237) (xy 332.662831 -393.420343) (xy 332.607394 -393.426443) (xy 332.55166 -393.424406)
			(xy 332.496817 -393.414276) (xy 332.444033 -393.396269) (xy 332.394433 -393.370768) (xy 332.349075 -393.338317)
			(xy 332.308926 -393.299608) (xy 332.27484 -393.255465) (xy 332.247544 -393.20683) (xy 332.227621 -393.154739)
			(xy 332.215495 -393.100302) (xy 332.211424 -393.04468) (xy 326.543906 -393.04468) (xy 326.549724 -393.056076)
			(xy 326.559164 -393.06373) (xy 326.583358 -393.081662) (xy 326.62776 -393.122347) (xy 326.667043 -393.167995)
			(xy 326.700656 -393.217966) (xy 326.728127 -393.271558) (xy 326.749072 -393.328022) (xy 326.763198 -393.386566)
			(xy 326.770306 -393.446368) (xy 326.770746 -393.47648) (xy 326.770225 -393.507209) (xy 326.76282 -393.56822)
			(xy 326.748115 -393.627893) (xy 326.726324 -393.685358) (xy 326.697766 -393.739778) (xy 326.662856 -393.790359)
			(xy 326.622104 -393.836363) (xy 326.576105 -393.87712) (xy 326.525528 -393.912036) (xy 326.471111 -393.9406)
			(xy 326.413648 -393.962397) (xy 326.353977 -393.977109) (xy 326.292967 -393.984522) (xy 326.262238 -393.984988)
			(xy 326.230113 -393.984517) (xy 326.166377 -393.976406) (xy 326.104169 -393.960335) (xy 326.044481 -393.936558)
			(xy 325.988261 -393.905455) (xy 325.936405 -393.867521) (xy 325.912734 -393.845796) (xy 325.905388 -393.839452)
			(xy 325.887378 -393.832261) (xy 325.877682 -393.831826) (xy 325.846694 -393.831826) (xy 325.836992 -393.832252)
			(xy 325.818966 -393.839422) (xy 325.811642 -393.845796) (xy 325.795894 -393.860274) (xy 325.787004 -393.867894)
			(xy 325.778114 -393.888468) (xy 325.781416 -393.990576) (xy 325.781863 -393.991458) (xy 332.212315 -393.991458)
			(xy 332.212315 -393.936942) (xy 332.220074 -393.882982) (xy 332.235434 -393.830675) (xy 332.258082 -393.781087)
			(xy 332.287557 -393.735227) (xy 332.323259 -393.694029) (xy 332.364461 -393.658332) (xy 332.410324 -393.628862)
			(xy 332.459915 -393.606219) (xy 332.512223 -393.590865) (xy 332.566184 -393.583112) (xy 332.593442 -393.582652)
			(xy 332.622076 -393.583167) (xy 332.6787 -393.591733) (xy 332.733408 -393.608664) (xy 332.784971 -393.633582)
			(xy 332.832232 -393.665926) (xy 332.874127 -393.704969) (xy 332.909717 -393.749836) (xy 332.924404 -393.774422)
			(xy 332.931516 -393.786614) (xy 332.955392 -393.80033) (xy 333.072486 -393.798044) (xy 333.095854 -393.78382)
			(xy 333.102458 -393.771374) (xy 333.117429 -393.744141) (xy 333.153555 -393.693577) (xy 333.196194 -393.648368)
			(xy 333.244559 -393.609348) (xy 333.297762 -393.577234) (xy 333.354822 -393.552618) (xy 333.41469 -393.535952)
			(xy 333.476262 -393.527544) (xy 333.507334 -393.527026) (xy 333.537304 -393.52745) (xy 333.59673 -393.535278)
			(xy 333.654626 -393.550796) (xy 333.710002 -393.573738) (xy 333.761909 -393.603712) (xy 333.80946 -393.640205)
			(xy 333.85184 -393.682592) (xy 333.888326 -393.730148) (xy 333.918292 -393.782059) (xy 333.941226 -393.837438)
			(xy 333.956735 -393.895337) (xy 333.964554 -393.954764) (xy 333.965042 -393.984734) (xy 333.964547 -394.015614)
			(xy 333.956231 -394.076813) (xy 333.939755 -394.136335) (xy 333.915419 -394.193099) (xy 333.883665 -394.246072)
			(xy 333.845071 -394.294289) (xy 333.823056 -394.31595) (xy 333.81442 -394.324332) (xy 333.806292 -394.346684)
			(xy 333.81823 -394.451078) (xy 333.831184 -394.47089) (xy 333.841598 -394.47724) (xy 333.866945 -394.492735)
			(xy 333.913797 -394.529264) (xy 333.955527 -394.571549) (xy 333.991434 -394.618879) (xy 334.020914 -394.670458)
			(xy 334.04347 -394.725418) (xy 334.058724 -394.782835) (xy 334.06642 -394.841744) (xy 334.066896 -394.871448)
			(xy 334.06644 -394.902108) (xy 334.058247 -394.962877) (xy 334.042014 -395.022009) (xy 334.018032 -395.078444)
			(xy 333.986731 -395.131172) (xy 333.94867 -395.179249) (xy 333.926942 -395.200886) (xy 333.919206 -395.209201)
			(xy 333.911202 -395.23042) (xy 333.913111 -395.253018) (xy 333.918306 -395.263116) (xy 333.932445 -395.288584)
			(xy 333.952514 -395.343264) (xy 333.962676 -395.400616) (xy 333.963264 -395.42974) (xy 333.962754 -395.455727)
			(xy 333.954624 -395.507062) (xy 333.938563 -395.556492) (xy 333.914967 -395.602802) (xy 333.884417 -395.64485)
			(xy 333.847666 -395.681601) (xy 333.805618 -395.712151) (xy 333.759308 -395.735747) (xy 333.709878 -395.751808)
			(xy 333.658543 -395.759938) (xy 333.606569 -395.759938) (xy 333.555234 -395.751808) (xy 333.505804 -395.735747)
			(xy 333.459494 -395.712151) (xy 333.417446 -395.681601) (xy 333.380695 -395.64485) (xy 333.350145 -395.602802)
			(xy 333.326549 -395.556492) (xy 333.310488 -395.507062) (xy 333.302358 -395.455727) (xy 333.301848 -395.42974)
			(xy 333.302273 -395.405227) (xy 333.309456 -395.356731) (xy 333.32373 -395.30983) (xy 333.333852 -395.2875)
			(xy 333.338246 -395.277037) (xy 333.338292 -395.254369) (xy 333.328555 -395.233899) (xy 333.320136 -395.226286)
			(xy 333.297912 -395.207625) (xy 333.257904 -395.165587) (xy 333.223533 -395.118828) (xy 333.195351 -395.068097)
			(xy 333.173811 -395.01421) (xy 333.159258 -394.958032) (xy 333.151926 -394.900464) (xy 333.15148 -394.871448)
			(xy 333.151987 -394.840568) (xy 333.160304 -394.779371) (xy 333.176779 -394.71985) (xy 333.201113 -394.663086)
			(xy 333.232864 -394.610113) (xy 333.271453 -394.561894) (xy 333.293466 -394.540232) (xy 333.302102 -394.53185)
			(xy 333.31023 -394.509498) (xy 333.298292 -394.405104) (xy 333.285338 -394.385292) (xy 333.274924 -394.378942)
			(xy 333.251543 -394.364714) (xy 333.208032 -394.331511) (xy 333.168797 -394.293348) (xy 333.134401 -394.250773)
			(xy 333.105336 -394.204394) (xy 333.093314 -394.179806) (xy 333.087218 -394.167106) (xy 333.064358 -394.151612)
			(xy 332.947518 -394.144246) (xy 332.923134 -394.156692) (xy 332.915514 -394.16863) (xy 332.900462 -394.191536)
			(xy 332.864765 -394.233128) (xy 332.823484 -394.269183) (xy 332.777467 -394.298959) (xy 332.727662 -394.321842)
			(xy 332.675094 -394.337362) (xy 332.620847 -394.345198) (xy 332.593442 -394.345668) (xy 332.566184 -394.345288)
			(xy 332.512223 -394.337535) (xy 332.459915 -394.322181) (xy 332.410324 -394.299538) (xy 332.364461 -394.270068)
			(xy 332.323259 -394.234371) (xy 332.287557 -394.193173) (xy 332.258082 -394.147313) (xy 332.235434 -394.097725)
			(xy 332.220074 -394.045418) (xy 332.212315 -393.991458) (xy 325.781863 -393.991458) (xy 325.791576 -394.010642)
			(xy 325.800974 -394.017754) (xy 325.827295 -394.038434) (xy 325.874833 -394.085558) (xy 325.915774 -394.138514)
			(xy 325.94941 -394.196386) (xy 325.975159 -394.258172) (xy 325.992575 -394.322803) (xy 326.001357 -394.389162)
			(xy 326.001888 -394.42263) (xy 326.001472 -394.453362) (xy 325.99406 -394.514379) (xy 325.979347 -394.574057)
			(xy 325.957548 -394.631526) (xy 325.928981 -394.685949) (xy 325.894062 -394.736532) (xy 325.853301 -394.782537)
			(xy 325.807292 -394.823293) (xy 325.756706 -394.858207) (xy 325.70228 -394.886769) (xy 325.644809 -394.908562)
			(xy 325.585129 -394.923269) (xy 325.524112 -394.930675) (xy 325.49338 -394.931138) (xy 325.461878 -394.930652)
			(xy 325.399357 -394.922863) (xy 325.338278 -394.907407) (xy 325.279577 -394.884521) (xy 325.224154 -394.854557)
			(xy 325.198232 -394.83665) (xy 325.18731 -394.82903) (xy 325.161402 -394.826236) (xy 325.057008 -394.870178)
			(xy 325.041006 -394.890752) (xy 325.038974 -394.90396) (xy 325.033538 -394.936309) (xy 325.015308 -394.999323)
			(xy 324.989128 -395.059471) (xy 324.955432 -395.115754) (xy 324.914781 -395.167238) (xy 324.867848 -395.213069)
			(xy 324.815412 -395.252486) (xy 324.758344 -395.284834) (xy 324.697591 -395.309577) (xy 324.634161 -395.326305)
			(xy 324.569107 -395.33474) (xy 324.536308 -395.335252) (xy 324.504904 -395.334719) (xy 324.442575 -395.326985)
			(xy 324.381673 -395.311633) (xy 324.323126 -395.288897) (xy 324.267824 -395.259123) (xy 324.216611 -395.222766)
			(xy 324.170265 -395.180377) (xy 324.129492 -395.132603) (xy 324.094914 -395.080171) (xy 324.067057 -395.02388)
			(xy 324.046344 -394.964586) (xy 324.033092 -394.903193) (xy 324.029832 -394.871956) (xy 324.028816 -394.861796)
			(xy 324.02018 -394.844778) (xy 323.952108 -394.785342) (xy 323.93382 -394.778992) (xy 323.92366 -394.7795)
			(xy 323.89953 -394.780008) (xy 323.868799 -394.779534) (xy 323.807783 -394.772129) (xy 323.748106 -394.757423)
			(xy 323.690636 -394.73563) (xy 323.636212 -394.707069) (xy 323.585628 -394.672156) (xy 323.539621 -394.6314)
			(xy 323.498862 -394.585396) (xy 323.463946 -394.534814) (xy 323.435382 -394.480391) (xy 323.413586 -394.422923)
			(xy 323.398876 -394.363246) (xy 323.391468 -394.302231) (xy 323.391022 -394.2715) (xy 323.391446 -394.240719)
			(xy 323.398862 -394.179605) (xy 323.413598 -394.119833) (xy 323.435438 -394.062275) (xy 323.464064 -394.007773)
			(xy 323.481192 -393.982194) (xy 323.48627 -393.9742) (xy 323.490719 -393.955807) (xy 323.489828 -393.94638)
			(xy 323.48551 -393.915646) (xy 323.483848 -393.906382) (xy 323.474724 -393.889939) (xy 323.46773 -393.883642)
			(xy 323.445905 -393.864953) (xy 323.406599 -393.823039) (xy 323.372851 -393.776534) (xy 323.345191 -393.72617)
			(xy 323.324054 -393.672738) (xy 323.309774 -393.617081) (xy 323.302574 -393.560074) (xy 323.302122 -393.531344)
			(xy 322.219247 -393.531344) (xy 322.225422 -393.546408) (xy 322.240646 -393.603805) (xy 322.248317 -393.662689)
			(xy 322.248784 -393.69238) (xy 322.248257 -393.723443) (xy 322.239845 -393.784996) (xy 322.23202 -393.815062)
			(xy 322.229226 -393.825222) (xy 322.231766 -393.845034) (xy 322.279264 -393.92733) (xy 322.295266 -393.939522)
			(xy 322.305426 -393.942062) (xy 322.33453 -393.950079) (xy 322.390497 -393.97271) (xy 322.443003 -394.002502)
			(xy 322.491137 -394.038937) (xy 322.534064 -394.081384) (xy 322.571039 -394.129105) (xy 322.601419 -394.181272)
			(xy 322.624679 -394.23698) (xy 322.640414 -394.295263) (xy 322.64835 -394.355108) (xy 322.648834 -394.385292)
			(xy 322.648732 -394.399042) (xy 322.64708 -394.426493) (xy 322.645532 -394.440156) (xy 322.644813 -394.448844)
			(xy 322.648587 -394.465853) (xy 322.652898 -394.47343) (xy 322.6689 -394.49883) (xy 322.673669 -394.505867)
			(xy 322.686912 -394.516509) (xy 322.694808 -394.519658) (xy 322.718583 -394.528582) (xy 322.763232 -394.552775)
			(xy 322.803657 -394.583509) (xy 322.838908 -394.620063) (xy 322.868157 -394.661576) (xy 322.890714 -394.707073)
			(xy 322.90605 -394.755484) (xy 322.913805 -394.805671) (xy 322.914264 -394.831062) (xy 322.91379 -394.857052)
			(xy 322.905663 -394.908394) (xy 322.889603 -394.957832) (xy 322.866006 -395.004148) (xy 322.835453 -395.046202)
			(xy 322.798697 -395.082957) (xy 322.756643 -395.113509) (xy 322.710326 -395.137105) (xy 322.660888 -395.153164)
			(xy 322.609546 -395.16129) (xy 322.583556 -395.16177) (xy 322.558649 -395.161268) (xy 322.509395 -395.153818)
			(xy 322.461816 -395.139063) (xy 322.416989 -395.117336) (xy 322.37593 -395.08913) (xy 322.339566 -395.055084)
			(xy 322.308723 -395.015967) (xy 322.284096 -394.972666) (xy 322.266245 -394.92616) (xy 322.260468 -394.901928)
			(xy 322.258304 -394.893708) (xy 322.249494 -394.879188) (xy 322.243196 -394.87348) (xy 322.219828 -394.85443)
			(xy 322.212938 -394.849227) (xy 322.196704 -394.843382) (xy 322.188078 -394.843) (xy 322.158242 -394.842293)
			(xy 322.099119 -394.834145) (xy 322.041558 -394.818382) (xy 321.986534 -394.79527) (xy 321.93498 -394.765202)
			(xy 321.887773 -394.728688) (xy 321.845712 -394.686347) (xy 321.809511 -394.638899) (xy 321.779785 -394.587148)
			(xy 321.757038 -394.531972) (xy 321.741656 -394.474307) (xy 321.733899 -394.415133) (xy 321.733418 -394.385292)
			(xy 321.73394 -394.354229) (xy 321.742355 -394.292675) (xy 321.750182 -394.26261) (xy 321.752976 -394.25245)
			(xy 321.750436 -394.232638) (xy 321.702938 -394.150342) (xy 321.686936 -394.13815) (xy 321.676776 -394.13561)
			(xy 321.647664 -394.127617) (xy 321.591696 -394.104984) (xy 321.539189 -394.07519) (xy 321.491054 -394.038753)
			(xy 321.448127 -393.996304) (xy 321.411153 -393.94858) (xy 321.380774 -393.896409) (xy 321.357516 -393.840698)
			(xy 321.341784 -393.782413) (xy 321.33385 -393.722566) (xy 321.333368 -393.69238) (xy 321.333898 -393.661492)
			(xy 321.342203 -393.600277) (xy 321.358658 -393.540733) (xy 321.382967 -393.483941) (xy 321.398392 -393.457176)
			(xy 321.404234 -393.44727) (xy 321.40652 -393.424918) (xy 321.373246 -393.329668) (xy 321.357498 -393.313666)
			(xy 321.34683 -393.309602) (xy 321.323434 -393.300454) (xy 321.279539 -393.276027) (xy 321.239845 -393.245239)
			(xy 321.205266 -393.2088) (xy 321.176599 -393.167549) (xy 321.154504 -393.122435) (xy 321.139489 -393.074497)
			(xy 321.1319 -393.024839) (xy 321.131438 -392.999722) (xy 320.592958 -392.999722) (xy 320.592428 -393.026824)
			(xy 320.583618 -393.080307) (xy 320.575432 -393.106148) (xy 320.571622 -393.11707) (xy 320.574162 -393.139422)
			(xy 320.62674 -393.225274) (xy 320.64579 -393.23772) (xy 320.656966 -393.239498) (xy 320.686289 -393.244178)
			(xy 320.74346 -393.260231) (xy 320.798073 -393.283544) (xy 320.849212 -393.313727) (xy 320.896017 -393.350271)
			(xy 320.937702 -393.392563) (xy 320.973565 -393.439892) (xy 321.003005 -393.491462) (xy 321.025526 -393.546408)
			(xy 321.04075 -393.603805) (xy 321.048421 -393.662689) (xy 321.048888 -393.69238) (xy 321.04836 -393.723443)
			(xy 321.039949 -393.784996) (xy 321.032124 -393.815062) (xy 321.02933 -393.825222) (xy 321.03187 -393.845034)
			(xy 321.079368 -393.92733) (xy 321.09537 -393.939522) (xy 321.10553 -393.942062) (xy 321.134604 -393.950144)
			(xy 321.190529 -393.972804) (xy 321.242994 -394.002614) (xy 321.291089 -394.039057) (xy 321.33398 -394.081501)
			(xy 321.370925 -394.129212) (xy 321.401282 -394.181361) (xy 321.424527 -394.237047) (xy 321.440255 -394.295303)
			(xy 321.448195 -394.355121) (xy 321.448684 -394.385292) (xy 321.448559 -394.399427) (xy 321.446777 -394.427641)
			(xy 321.445128 -394.44168) (xy 321.444372 -394.450287) (xy 321.448009 -394.467166) (xy 321.45224 -394.4747)
			(xy 321.467988 -394.5001) (xy 321.472699 -394.507159) (xy 321.485804 -394.517929) (xy 321.493642 -394.521182)
			(xy 321.517026 -394.530359) (xy 321.560921 -394.554781) (xy 321.600616 -394.585564) (xy 321.635196 -394.621998)
			(xy 321.663865 -394.663246) (xy 321.685962 -394.708356) (xy 321.70098 -394.756291) (xy 321.708571 -394.805946)
			(xy 321.709034 -394.831062) (xy 321.70862 -394.855265) (xy 321.701545 -394.90315) (xy 321.687555 -394.94949)
			(xy 321.666951 -394.993291) (xy 321.653916 -395.013688) (xy 321.649124 -395.021642) (xy 321.645094 -395.039755)
			(xy 321.646042 -395.048994) (xy 321.65036 -395.079982) (xy 321.652054 -395.089275) (xy 321.661328 -395.105717)
			(xy 321.668394 -395.111986) (xy 321.690468 -395.130685) (xy 321.730243 -395.172692) (xy 321.764408 -395.219376)
			(xy 321.792418 -395.269993) (xy 321.813828 -395.323736) (xy 321.828295 -395.379748) (xy 321.835589 -395.437137)
			(xy 321.836034 -395.466062) (xy 325.883522 -395.466062) (xy 325.887593 -395.41044) (xy 325.899719 -395.356003)
			(xy 325.919642 -395.303912) (xy 325.946938 -395.255277) (xy 325.981024 -395.211134) (xy 326.021173 -395.172425)
			(xy 326.066531 -395.139974) (xy 326.116131 -395.114473) (xy 326.168915 -395.096466) (xy 326.223758 -395.086336)
			(xy 326.279492 -395.084299) (xy 326.334929 -395.090399) (xy 326.388886 -395.104505) (xy 326.440215 -395.126317)
			(xy 326.487821 -395.155371) (xy 326.530689 -395.191046) (xy 326.567906 -395.232583) (xy 326.598679 -395.279096)
			(xy 326.622351 -395.329593) (xy 326.638419 -395.383) (xy 326.646539 -395.438176) (xy 326.647048 -395.466062)
			(xy 326.646539 -395.493948) (xy 326.638419 -395.549124) (xy 326.622351 -395.602531) (xy 326.598679 -395.653028)
			(xy 326.567906 -395.699541) (xy 326.530689 -395.741078) (xy 326.487821 -395.776753) (xy 326.440215 -395.805807)
			(xy 326.388886 -395.827619) (xy 326.334929 -395.841725) (xy 326.279492 -395.847825) (xy 326.223758 -395.845788)
			(xy 326.168915 -395.835658) (xy 326.116131 -395.817651) (xy 326.066531 -395.79215) (xy 326.021173 -395.759699)
			(xy 325.981024 -395.72099) (xy 325.946938 -395.676847) (xy 325.919642 -395.628212) (xy 325.899719 -395.576121)
			(xy 325.887593 -395.521684) (xy 325.883522 -395.466062) (xy 321.836034 -395.466062) (xy 321.835445 -395.499383)
			(xy 321.825782 -395.565322) (xy 321.806656 -395.629161) (xy 321.793108 -395.65961) (xy 321.78885 -395.670072)
			(xy 321.788964 -395.692635) (xy 321.798704 -395.712987) (xy 321.807078 -395.72057) (xy 321.829304 -395.739268)
			(xy 321.869369 -395.781319) (xy 321.903792 -395.828101) (xy 321.93202 -395.878861) (xy 321.953599 -395.932786)
			(xy 321.968182 -395.989007) (xy 321.975535 -396.046621) (xy 321.975988 -396.075662) (xy 321.975498 -396.104666)
			(xy 321.968188 -396.162213) (xy 321.964494 -396.1765) (xy 327.956924 -396.1765) (xy 327.960995 -396.120878)
			(xy 327.973121 -396.066441) (xy 327.993044 -396.01435) (xy 328.02034 -395.965715) (xy 328.054426 -395.921572)
			(xy 328.094575 -395.882863) (xy 328.139933 -395.850412) (xy 328.189533 -395.824911) (xy 328.242317 -395.806904)
			(xy 328.29716 -395.796774) (xy 328.352894 -395.794737) (xy 328.408331 -395.800837) (xy 328.462288 -395.814943)
			(xy 328.513617 -395.836755) (xy 328.561223 -395.865809) (xy 328.604091 -395.901484) (xy 328.641308 -395.943021)
			(xy 328.672081 -395.989534) (xy 328.695753 -396.040031) (xy 328.711821 -396.093438) (xy 328.719941 -396.148614)
			(xy 328.720362 -396.171674) (xy 329.301856 -396.171674) (xy 329.302433 -396.136719) (xy 329.311997 -396.067466)
			(xy 329.330956 -396.000175) (xy 329.358952 -395.936115) (xy 329.395457 -395.876492) (xy 329.417172 -395.849094)
			(xy 329.422478 -395.842101) (xy 329.428446 -395.825605) (xy 329.428856 -395.816836) (xy 329.428856 -395.662912)
			(xy 329.428478 -395.654137) (xy 329.422503 -395.637635) (xy 329.417172 -395.630654) (xy 329.39548 -395.603239)
			(xy 329.35898 -395.543617) (xy 329.330984 -395.479561) (xy 329.312018 -395.412276) (xy 329.30244 -395.343028)
			(xy 329.301856 -395.308074) (xy 329.302332 -395.277344) (xy 329.309742 -395.216332) (xy 329.324453 -395.156658)
			(xy 329.346248 -395.099192) (xy 329.374811 -395.044772) (xy 329.409725 -394.994191) (xy 329.45048 -394.948187)
			(xy 329.496483 -394.907431) (xy 329.547063 -394.872516) (xy 329.601483 -394.843952) (xy 329.658948 -394.822156)
			(xy 329.718622 -394.807444) (xy 329.779634 -394.800032) (xy 329.810364 -394.799566) (xy 329.822 -394.799606)
			(xy 329.845251 -394.800622) (xy 329.856846 -394.801598) (xy 329.866498 -394.802614) (xy 329.884786 -394.79728)
			(xy 329.95489 -394.743432) (xy 329.964542 -394.727176) (xy 329.96632 -394.717778) (xy 329.971302 -394.691511)
			(xy 329.987592 -394.64059) (xy 330.010835 -394.592445) (xy 330.040575 -394.548018) (xy 330.07623 -394.508181)
			(xy 330.117099 -394.473714) (xy 330.162383 -394.445295) (xy 330.211192 -394.423479) (xy 330.262569 -394.408695)
			(xy 330.315509 -394.401233) (xy 330.34224 -394.400786) (xy 330.369492 -394.401241) (xy 330.42344 -394.409002)
			(xy 330.475735 -394.424362) (xy 330.525312 -394.447008) (xy 330.571162 -394.476478) (xy 330.612352 -394.512172)
			(xy 330.648043 -394.553365) (xy 330.677509 -394.599217) (xy 330.70015 -394.648796) (xy 330.715505 -394.701093)
			(xy 330.723262 -394.755042) (xy 330.723748 -394.782294) (xy 330.72329 -394.809244) (xy 330.715691 -394.862607)
			(xy 330.700658 -394.914369) (xy 330.67849 -394.963501) (xy 330.649628 -395.009023) (xy 330.614647 -395.050031)
			(xy 330.574243 -395.085708) (xy 330.52922 -395.115343) (xy 330.480475 -395.138348) (xy 330.428977 -395.154263)
			(xy 330.402438 -395.158976) (xy 330.392786 -395.1605) (xy 330.37653 -395.170152) (xy 330.32192 -395.239748)
			(xy 330.316586 -395.257782) (xy 330.317348 -395.267434) (xy 330.318872 -395.308074) (xy 330.31826 -395.343028)
			(xy 330.308703 -395.412279) (xy 330.289752 -395.479569) (xy 330.261764 -395.54363) (xy 330.225267 -395.603254)
			(xy 330.203556 -395.630654) (xy 330.198275 -395.637663) (xy 330.192291 -395.654147) (xy 330.191872 -395.662912)
			(xy 330.191872 -395.816836) (xy 330.192221 -395.825614) (xy 330.198216 -395.842116) (xy 330.203556 -395.849094)
			(xy 330.22526 -395.8765) (xy 330.26176 -395.936123) (xy 330.289755 -396.000182) (xy 330.308718 -396.06747)
			(xy 330.318291 -396.13672) (xy 330.318872 -396.171674) (xy 330.318428 -396.202892) (xy 330.310811 -396.26486)
			(xy 330.295664 -396.32543) (xy 330.273215 -396.38369) (xy 330.258928 -396.41145) (xy 330.254356 -396.419578)
			(xy 330.25207 -396.437612) (xy 330.27112 -396.520924) (xy 330.281026 -396.53591) (xy 330.288646 -396.541498)
			(xy 330.309181 -396.55694) (xy 330.346316 -396.592449) (xy 330.378349 -396.632621) (xy 330.404699 -396.676729)
			(xy 330.405958 -396.679674) (xy 332.336392 -396.679674) (xy 332.340463 -396.624052) (xy 332.352589 -396.569615)
			(xy 332.372512 -396.517524) (xy 332.399808 -396.468889) (xy 332.433894 -396.424746) (xy 332.474043 -396.386037)
			(xy 332.519401 -396.353586) (xy 332.569001 -396.328085) (xy 332.621785 -396.310078) (xy 332.676628 -396.299948)
			(xy 332.732362 -396.297911) (xy 332.787799 -396.304011) (xy 332.841756 -396.318117) (xy 332.893085 -396.339929)
			(xy 332.940691 -396.368983) (xy 332.983559 -396.404658) (xy 333.020776 -396.446195) (xy 333.051549 -396.492708)
			(xy 333.075221 -396.543205) (xy 333.091289 -396.596612) (xy 333.099409 -396.651788) (xy 333.099918 -396.679674)
			(xy 333.099471 -396.704137) (xy 333.302358 -396.704137) (xy 333.302358 -396.652163) (xy 333.310488 -396.600828)
			(xy 333.326549 -396.551398) (xy 333.350145 -396.505088) (xy 333.380695 -396.46304) (xy 333.417446 -396.426289)
			(xy 333.459494 -396.395739) (xy 333.505804 -396.372143) (xy 333.555234 -396.356082) (xy 333.606569 -396.347952)
			(xy 333.658543 -396.347952) (xy 333.709878 -396.356082) (xy 333.759308 -396.372143) (xy 333.805618 -396.395739)
			(xy 333.847666 -396.426289) (xy 333.884417 -396.46304) (xy 333.914967 -396.505088) (xy 333.938563 -396.551398)
			(xy 333.954624 -396.600828) (xy 333.962754 -396.652163) (xy 333.963264 -396.67815) (xy 333.962754 -396.704137)
			(xy 333.954624 -396.755472) (xy 333.938563 -396.804902) (xy 333.914967 -396.851212) (xy 333.884417 -396.89326)
			(xy 333.847666 -396.930011) (xy 333.805618 -396.960561) (xy 333.759308 -396.984157) (xy 333.709878 -397.000218)
			(xy 333.658543 -397.008348) (xy 333.606569 -397.008348) (xy 333.555234 -397.000218) (xy 333.505804 -396.984157)
			(xy 333.459494 -396.960561) (xy 333.417446 -396.930011) (xy 333.380695 -396.89326) (xy 333.350145 -396.851212)
			(xy 333.326549 -396.804902) (xy 333.310488 -396.755472) (xy 333.302358 -396.704137) (xy 333.099471 -396.704137)
			(xy 333.099409 -396.70756) (xy 333.091289 -396.762736) (xy 333.075221 -396.816143) (xy 333.051549 -396.86664)
			(xy 333.020776 -396.913153) (xy 332.983559 -396.95469) (xy 332.940691 -396.990365) (xy 332.893085 -397.019419)
			(xy 332.841756 -397.041231) (xy 332.787799 -397.055337) (xy 332.732362 -397.061437) (xy 332.676628 -397.0594)
			(xy 332.621785 -397.04927) (xy 332.569001 -397.031263) (xy 332.519401 -397.005762) (xy 332.474043 -396.973311)
			(xy 332.433894 -396.934602) (xy 332.399808 -396.890459) (xy 332.372512 -396.841824) (xy 332.352589 -396.789733)
			(xy 332.340463 -396.735296) (xy 332.336392 -396.679674) (xy 330.405958 -396.679674) (xy 330.42489 -396.723975)
			(xy 330.438558 -396.773503) (xy 330.445453 -396.824418) (xy 330.445872 -396.850108) (xy 330.445417 -396.877479)
			(xy 330.437598 -396.931659) (xy 330.422106 -396.984162) (xy 330.399262 -397.033909) (xy 330.369535 -397.079875)
			(xy 330.351892 -397.100806) (xy 330.345796 -397.107918) (xy 330.339446 -397.124936) (xy 330.339446 -397.21028)
			(xy 330.345796 -397.227298) (xy 330.351892 -397.23441) (xy 330.369548 -397.255328) (xy 330.399258 -397.301305)
			(xy 330.42209 -397.351056) (xy 330.437577 -397.40356) (xy 330.445401 -397.457738) (xy 330.445872 -397.485108)
			(xy 330.445386 -397.512359) (xy 330.43763 -397.566307) (xy 330.422275 -397.618602) (xy 330.399633 -397.668179)
			(xy 330.370167 -397.714029) (xy 330.334476 -397.75522) (xy 330.293285 -397.790911) (xy 330.247435 -397.820377)
			(xy 330.197858 -397.843019) (xy 330.145563 -397.858374) (xy 330.091615 -397.86613) (xy 330.037113 -397.86613)
			(xy 329.983165 -397.858374) (xy 329.93087 -397.843019) (xy 329.881293 -397.820377) (xy 329.835443 -397.790911)
			(xy 329.794252 -397.75522) (xy 329.758561 -397.714029) (xy 329.729095 -397.668179) (xy 329.706453 -397.618602)
			(xy 329.691098 -397.566307) (xy 329.683342 -397.512359) (xy 329.682856 -397.485108) (xy 329.683313 -397.457737)
			(xy 329.691131 -397.403557) (xy 329.706621 -397.351054) (xy 329.729466 -397.301307) (xy 329.759193 -397.255341)
			(xy 329.776836 -397.23441) (xy 329.782932 -397.227298) (xy 329.789282 -397.21028) (xy 329.789282 -397.124936)
			(xy 329.782932 -397.107918) (xy 329.776836 -397.100806) (xy 329.759192 -397.079878) (xy 329.72948 -397.033905)
			(xy 329.706644 -396.984156) (xy 329.691154 -396.931654) (xy 329.683328 -396.877478) (xy 329.682856 -396.850108)
			(xy 329.683144 -396.828584) (xy 329.687981 -396.785809) (xy 329.692508 -396.764764) (xy 329.69454 -396.75562)
			(xy 329.692254 -396.737586) (xy 329.651868 -396.662148) (xy 329.638406 -396.65021) (xy 329.629516 -396.646908)
			(xy 329.600981 -396.635568) (xy 329.546637 -396.606981) (xy 329.496131 -396.572057) (xy 329.4502 -396.531305)
			(xy 329.40951 -396.485317) (xy 329.374656 -396.434763) (xy 329.346144 -396.380379) (xy 329.32439 -396.322958)
			(xy 329.309709 -396.263334) (xy 329.302317 -396.202376) (xy 329.301856 -396.171674) (xy 328.720362 -396.171674)
			(xy 328.72045 -396.1765) (xy 328.719941 -396.204386) (xy 328.711821 -396.259562) (xy 328.695753 -396.312969)
			(xy 328.672081 -396.363466) (xy 328.641308 -396.409979) (xy 328.604091 -396.451516) (xy 328.561223 -396.487191)
			(xy 328.513617 -396.516245) (xy 328.462288 -396.538057) (xy 328.408331 -396.552163) (xy 328.352894 -396.558263)
			(xy 328.29716 -396.556226) (xy 328.242317 -396.546096) (xy 328.189533 -396.528089) (xy 328.139933 -396.502588)
			(xy 328.094575 -396.470137) (xy 328.054426 -396.431428) (xy 328.02034 -396.387285) (xy 327.993044 -396.33865)
			(xy 327.973121 -396.286559) (xy 327.960995 -396.232122) (xy 327.956924 -396.1765) (xy 321.964494 -396.1765)
			(xy 321.953667 -396.218374) (xy 321.932169 -396.272252) (xy 321.904037 -396.322982) (xy 321.869722 -396.369753)
			(xy 321.829774 -396.411814) (xy 321.807586 -396.4305) (xy 321.800474 -396.436088) (xy 321.79133 -396.451328)
			(xy 321.77609 -396.534132) (xy 321.778884 -396.551404) (xy 321.783456 -396.559532) (xy 321.796032 -396.582718)
			(xy 321.813906 -396.63234) (xy 321.820729 -396.671292) (xy 323.368924 -396.671292) (xy 323.369414 -396.641324)
			(xy 323.377237 -396.581902) (xy 323.39275 -396.524009) (xy 323.415686 -396.468636) (xy 323.445653 -396.41673)
			(xy 323.48214 -396.36918) (xy 323.52452 -396.3268) (xy 323.57207 -396.290313) (xy 323.623976 -396.260346)
			(xy 323.679349 -396.23741) (xy 323.737242 -396.221897) (xy 323.796664 -396.214074) (xy 323.8566 -396.214074)
			(xy 323.916022 -396.221897) (xy 323.973915 -396.23741) (xy 324.029288 -396.260346) (xy 324.081194 -396.290313)
			(xy 324.128744 -396.3268) (xy 324.171124 -396.36918) (xy 324.207611 -396.41673) (xy 324.237578 -396.468636)
			(xy 324.260514 -396.524009) (xy 324.276027 -396.581902) (xy 324.28385 -396.641324) (xy 324.28434 -396.671292)
			(xy 324.283778 -396.703116) (xy 324.274961 -396.766151) (xy 324.257495 -396.827356) (xy 324.231718 -396.885552)
			(xy 324.198127 -396.939614) (xy 324.178168 -396.964408) (xy 324.172326 -396.97152) (xy 324.16623 -396.989046)
			(xy 324.16877 -397.075152) (xy 324.175882 -397.09217) (xy 324.182232 -397.099028) (xy 324.194718 -397.112555)
			(xy 324.217733 -397.141292) (xy 324.228206 -397.156432) (xy 324.236334 -397.168116) (xy 324.261988 -397.180054)
			(xy 324.37959 -397.166846) (xy 324.401942 -397.149574) (xy 324.407022 -397.136366) (xy 324.417869 -397.109862)
			(xy 324.446352 -397.060182) (xy 324.48194 -397.015318) (xy 324.523836 -396.976278) (xy 324.571096 -396.943938)
			(xy 324.622659 -396.919026) (xy 324.677366 -396.902102) (xy 324.733989 -396.893545) (xy 324.762622 -396.893034)
			(xy 324.789993 -396.893479) (xy 324.844173 -396.901301) (xy 324.896677 -396.916794) (xy 324.946424 -396.939641)
			(xy 324.992389 -396.96937) (xy 325.01332 -396.987014) (xy 325.020432 -396.99311) (xy 325.03745 -396.99946)
			(xy 325.122794 -396.99946) (xy 325.139812 -396.99311) (xy 325.146924 -396.987014) (xy 325.167857 -396.969373)
			(xy 325.213825 -396.939649) (xy 325.263571 -396.916803) (xy 325.316073 -396.901307) (xy 325.370251 -396.893478)
			(xy 325.424993 -396.893478) (xy 325.479171 -396.901307) (xy 325.531673 -396.916803) (xy 325.581419 -396.939649)
			(xy 325.627387 -396.969373) (xy 325.64832 -396.987014) (xy 325.655432 -396.99311) (xy 325.67245 -396.99946)
			(xy 325.757794 -396.99946) (xy 325.774812 -396.99311) (xy 325.781924 -396.987014) (xy 325.802876 -396.969399)
			(xy 325.848843 -396.939683) (xy 325.898585 -396.916842) (xy 325.951082 -396.901346) (xy 326.005254 -396.893511)
			(xy 326.032622 -396.893034) (xy 326.059875 -396.893437) (xy 326.113827 -396.901197) (xy 326.166124 -396.916556)
			(xy 326.215704 -396.939201) (xy 326.261557 -396.968671) (xy 326.302749 -397.004366) (xy 326.338442 -397.045561)
			(xy 326.36791 -397.091415) (xy 326.390552 -397.140996) (xy 326.402107 -397.180352) (xy 327.740985 -397.180352)
			(xy 327.740985 -397.125848) (xy 327.748742 -397.071899) (xy 327.764099 -397.019603) (xy 327.786741 -396.970025)
			(xy 327.816209 -396.924175) (xy 327.851903 -396.882984) (xy 327.893095 -396.847294) (xy 327.938948 -396.817829)
			(xy 327.988528 -396.795189) (xy 328.040825 -396.779837) (xy 328.094774 -396.772083) (xy 328.122026 -396.771622)
			(xy 328.149397 -396.772067) (xy 328.203577 -396.779889) (xy 328.256081 -396.795383) (xy 328.305827 -396.818229)
			(xy 328.351793 -396.847959) (xy 328.372724 -396.865602) (xy 328.379836 -396.871698) (xy 328.396854 -396.878048)
			(xy 328.482198 -396.878048) (xy 328.499216 -396.871698) (xy 328.506328 -396.865602) (xy 328.527277 -396.847984)
			(xy 328.573245 -396.818269) (xy 328.622988 -396.795429) (xy 328.675485 -396.779933) (xy 328.729658 -396.772099)
			(xy 328.757026 -396.771622) (xy 328.784278 -396.77205) (xy 328.838227 -396.77981) (xy 328.890523 -396.795168)
			(xy 328.940101 -396.817813) (xy 328.985952 -396.847282) (xy 329.027142 -396.882976) (xy 329.062834 -396.924169)
			(xy 329.0923 -396.970022) (xy 329.114941 -397.019601) (xy 329.130296 -397.071898) (xy 329.138052 -397.125848)
			(xy 329.138052 -397.180352) (xy 329.130296 -397.234302) (xy 329.114941 -397.286599) (xy 329.0923 -397.336178)
			(xy 329.062834 -397.382031) (xy 329.027142 -397.423224) (xy 328.985952 -397.458918) (xy 328.940101 -397.488387)
			(xy 328.890523 -397.511032) (xy 328.838227 -397.52639) (xy 328.784278 -397.53415) (xy 328.757026 -397.534638)
			(xy 328.729656 -397.534172) (xy 328.675476 -397.526356) (xy 328.622972 -397.510868) (xy 328.573225 -397.488026)
			(xy 328.527259 -397.4583) (xy 328.506328 -397.440658) (xy 328.499216 -397.434562) (xy 328.482198 -397.428212)
			(xy 328.396854 -397.428212) (xy 328.379836 -397.434562) (xy 328.372724 -397.440658) (xy 328.351788 -397.458293)
			(xy 328.305817 -397.488007) (xy 328.256071 -397.510844) (xy 328.203571 -397.526336) (xy 328.149395 -397.534164)
			(xy 328.122026 -397.534638) (xy 328.094774 -397.534117) (xy 328.040825 -397.526363) (xy 327.988528 -397.511011)
			(xy 327.938948 -397.488371) (xy 327.893095 -397.458906) (xy 327.851903 -397.423216) (xy 327.816209 -397.382025)
			(xy 327.786741 -397.336175) (xy 327.764099 -397.286597) (xy 327.748742 -397.234301) (xy 327.740985 -397.180352)
			(xy 326.402107 -397.180352) (xy 326.405907 -397.193295) (xy 326.413664 -397.247247) (xy 326.413664 -397.301753)
			(xy 326.405907 -397.355705) (xy 326.390552 -397.408004) (xy 326.36791 -397.457585) (xy 326.338442 -397.503439)
			(xy 326.302749 -397.544634) (xy 326.261557 -397.580329) (xy 326.215704 -397.609799) (xy 326.166124 -397.632444)
			(xy 326.113827 -397.647803) (xy 326.059875 -397.655563) (xy 326.032622 -397.65605) (xy 326.005252 -397.655583)
			(xy 325.951072 -397.647767) (xy 325.898569 -397.632279) (xy 325.848822 -397.609437) (xy 325.802855 -397.579712)
			(xy 325.781924 -397.56207) (xy 325.774812 -397.555974) (xy 325.757794 -397.549624) (xy 325.67245 -397.549624)
			(xy 325.655432 -397.555974) (xy 325.64832 -397.56207) (xy 325.627387 -397.579711) (xy 325.581419 -397.609435)
			(xy 325.531673 -397.632281) (xy 325.479171 -397.647777) (xy 325.424993 -397.655606) (xy 325.370251 -397.655606)
			(xy 325.316073 -397.647777) (xy 325.263571 -397.632281) (xy 325.213825 -397.609435) (xy 325.167857 -397.579711)
			(xy 325.146924 -397.56207) (xy 325.139812 -397.555974) (xy 325.122794 -397.549624) (xy 325.03745 -397.549624)
			(xy 325.020432 -397.555974) (xy 325.01332 -397.56207) (xy 324.992387 -397.579709) (xy 324.946415 -397.609421)
			(xy 324.896668 -397.632258) (xy 324.844167 -397.647749) (xy 324.789991 -397.655577) (xy 324.762622 -397.65605)
			(xy 324.734021 -397.655534) (xy 324.677458 -397.647003) (xy 324.622801 -397.630127) (xy 324.571274 -397.605285)
			(xy 324.524031 -397.573033) (xy 324.482129 -397.534093) (xy 324.463918 -397.512032) (xy 324.455282 -397.500856)
			(xy 324.428612 -397.49095) (xy 324.31228 -397.513302) (xy 324.291452 -397.532098) (xy 324.287388 -397.545814)
			(xy 324.277292 -397.57716) (xy 324.249319 -397.636779) (xy 324.213079 -397.691766) (xy 324.19163 -397.716756)
			(xy 324.18528 -397.723868) (xy 324.178676 -397.74114) (xy 324.178676 -397.827246) (xy 324.18528 -397.844518)
			(xy 324.19163 -397.85163) (xy 324.213208 -397.876866) (xy 324.249581 -397.932413) (xy 324.277548 -397.992632)
			(xy 324.296522 -398.05626) (xy 324.306105 -398.121962) (xy 324.306692 -398.15516) (xy 324.306174 -398.186762)
			(xy 324.29747 -398.249363) (xy 324.280222 -398.310168) (xy 324.25476 -398.368016) (xy 324.23862 -398.39519)
			(xy 324.234105 -398.403424) (xy 324.230672 -398.421866) (xy 324.23408 -398.440312) (xy 324.23862 -398.44853)
			(xy 324.254745 -398.47571) (xy 324.280173 -398.533567) (xy 324.297413 -398.594368) (xy 324.30614 -398.656961)
			(xy 324.306692 -398.68856) (xy 324.306151 -398.720174) (xy 324.297434 -398.782798) (xy 324.280186 -398.843629)
			(xy 324.254737 -398.901509) (xy 324.221569 -398.95534) (xy 324.181313 -399.004097) (xy 324.134735 -399.046855)
			(xy 324.082718 -399.0828) (xy 324.054724 -399.0975) (xy 324.045415 -399.10277) (xy 324.0319 -399.119327)
			(xy 324.026246 -399.139937) (xy 324.027292 -399.150586) (xy 324.029097 -399.163144) (xy 324.031003 -399.188445)
			(xy 324.031102 -399.201132) (xy 324.030592 -399.227119) (xy 324.022462 -399.278454) (xy 324.006401 -399.327884)
			(xy 323.982805 -399.374194) (xy 323.952255 -399.416242) (xy 323.915504 -399.452993) (xy 323.873456 -399.483543)
			(xy 323.827146 -399.507139) (xy 323.777716 -399.5232) (xy 323.726381 -399.53133) (xy 323.674407 -399.53133)
			(xy 323.623072 -399.5232) (xy 323.573642 -399.507139) (xy 323.527332 -399.483543) (xy 323.485284 -399.452993)
			(xy 323.448533 -399.416242) (xy 323.417983 -399.374194) (xy 323.394387 -399.327884) (xy 323.378326 -399.278454)
			(xy 323.370196 -399.227119) (xy 323.369686 -399.201132) (xy 323.370092 -399.177394) (xy 323.376888 -399.130408)
			(xy 323.390331 -399.084875) (xy 323.410145 -399.041732) (xy 323.435922 -399.001864) (xy 323.45122 -398.983708)
			(xy 323.457931 -398.97531) (xy 323.464266 -398.954789) (xy 323.461676 -398.933468) (xy 323.456554 -398.924018)
			(xy 323.441046 -398.89725) (xy 323.41663 -398.840409) (xy 323.400108 -398.780792) (xy 323.391779 -398.719492)
			(xy 323.391276 -398.68856) (xy 323.391794 -398.656958) (xy 323.400496 -398.594356) (xy 323.417744 -398.533551)
			(xy 323.443207 -398.475704) (xy 323.459348 -398.44853) (xy 323.463929 -398.440328) (xy 323.467343 -398.421866)
			(xy 323.463905 -398.403408) (xy 323.459348 -398.39519) (xy 323.443228 -398.368007) (xy 323.4178 -398.310151)
			(xy 323.400558 -398.249351) (xy 323.39183 -398.186758) (xy 323.391276 -398.15516) (xy 323.391838 -398.121925)
			(xy 323.401447 -398.056155) (xy 323.420471 -397.992466) (xy 323.448511 -397.932201) (xy 323.484976 -397.876627)
			(xy 323.506592 -397.851376) (xy 323.512942 -397.844264) (xy 323.519546 -397.826992) (xy 323.519546 -397.740886)
			(xy 323.512942 -397.723614) (xy 323.506592 -397.716502) (xy 323.485033 -397.691251) (xy 323.448656 -397.635708)
			(xy 323.420686 -397.575493) (xy 323.401707 -397.511868) (xy 323.39212 -397.446169) (xy 323.39153 -397.412972)
			(xy 323.392055 -397.381146) (xy 323.400879 -397.318109) (xy 323.418352 -397.256903) (xy 323.444138 -397.198708)
			(xy 323.477739 -397.144648) (xy 323.497702 -397.119856) (xy 323.503544 -397.112744) (xy 323.50964 -397.095218)
			(xy 323.5071 -397.009112) (xy 323.499988 -396.992094) (xy 323.493638 -396.985236) (xy 323.474148 -396.963969)
			(xy 323.440156 -396.917359) (xy 323.412292 -396.866847) (xy 323.390998 -396.813232) (xy 323.376612 -396.757367)
			(xy 323.369362 -396.700136) (xy 323.368924 -396.671292) (xy 321.820729 -396.671292) (xy 321.823006 -396.684291)
			(xy 321.823588 -396.710662) (xy 321.82352 -396.720021) (xy 321.822376 -396.738703) (xy 321.821302 -396.748)
			(xy 321.820286 -396.75689) (xy 321.824096 -396.773654) (xy 321.868038 -396.843504) (xy 321.881754 -396.853918)
			(xy 321.890136 -396.856712) (xy 321.914164 -396.865182) (xy 321.959336 -396.888734) (xy 322.000141 -396.919233)
			(xy 322.03552 -396.955888) (xy 322.064556 -396.997747) (xy 322.086495 -397.043725) (xy 322.094098 -397.06804)
			(xy 322.095622 -397.073882) (xy 322.415916 -397.627602) (xy 322.41998 -397.63192) (xy 322.436168 -397.649642)
			(xy 322.463596 -397.689028) (xy 322.484742 -397.732114) (xy 322.499119 -397.777906) (xy 322.506396 -397.825346)
			(xy 322.506848 -397.849344) (xy 322.506447 -397.87415) (xy 322.498675 -397.923151) (xy 322.48333 -397.970332)
			(xy 322.460791 -398.014529) (xy 322.431611 -398.054654) (xy 322.396512 -398.089718) (xy 322.356357 -398.118857)
			(xy 322.312137 -398.141352) (xy 322.264941 -398.156649) (xy 322.215933 -398.164371) (xy 322.191126 -398.164812)
			(xy 322.165732 -398.164289) (xy 322.1156 -398.156162) (xy 322.067415 -398.140114) (xy 322.02242 -398.11656)
			(xy 321.981777 -398.086105) (xy 321.946534 -398.049537) (xy 321.9176 -398.007798) (xy 321.895721 -397.961966)
			(xy 321.888104 -397.937736) (xy 321.88658 -397.931894) (xy 321.566286 -397.378174) (xy 321.562222 -397.373856)
			(xy 321.546057 -397.356127) (xy 321.518691 -397.316723) (xy 321.497602 -397.273632) (xy 321.483276 -397.227846)
			(xy 321.476042 -397.18042) (xy 321.475608 -397.156432) (xy 321.475689 -397.144384) (xy 321.477472 -397.120355)
			(xy 321.479164 -397.108426) (xy 321.480434 -397.099536) (xy 321.477386 -397.082518) (xy 321.435222 -397.011652)
			(xy 321.422014 -397.000476) (xy 321.413632 -396.997428) (xy 321.391876 -396.989054) (xy 321.351019 -396.966608)
			(xy 321.314049 -396.93821) (xy 321.281828 -396.904522) (xy 321.255104 -396.866325) (xy 321.2345 -396.824509)
			(xy 321.220493 -396.780046) (xy 321.21341 -396.733971) (xy 321.212972 -396.710662) (xy 321.213541 -396.684289)
			(xy 321.222623 -396.632331) (xy 321.24051 -396.582711) (xy 321.253104 -396.559532) (xy 321.257676 -396.551404)
			(xy 321.26047 -396.534132) (xy 321.24523 -396.451328) (xy 321.236086 -396.436088) (xy 321.228974 -396.4305)
			(xy 321.206798 -396.4118) (xy 321.166852 -396.369737) (xy 321.132536 -396.322968) (xy 321.104398 -396.272241)
			(xy 321.082889 -396.218367) (xy 321.068353 -396.16221) (xy 321.061023 -396.104666) (xy 321.060572 -396.075662)
			(xy 321.061169 -396.042341) (xy 321.070828 -395.976403) (xy 321.089952 -395.912563) (xy 321.103498 -395.882114)
			(xy 321.107731 -395.871644) (xy 321.107626 -395.849088) (xy 321.097897 -395.828738) (xy 321.089528 -395.821154)
			(xy 321.067267 -395.802496) (xy 321.027203 -395.760439) (xy 320.992783 -395.71365) (xy 320.96456 -395.662882)
			(xy 320.942987 -395.608951) (xy 320.928411 -395.552724) (xy 320.921066 -395.495105) (xy 320.920618 -395.466062)
			(xy 320.921082 -395.437136) (xy 320.928365 -395.379745) (xy 320.942823 -395.323729) (xy 320.964225 -395.269982)
			(xy 320.99223 -395.21936) (xy 321.026391 -395.172672) (xy 321.066164 -395.130661) (xy 321.088258 -395.111986)
			(xy 321.09523 -395.105638) (xy 321.104488 -395.089235) (xy 321.106292 -395.079982) (xy 321.11061 -395.048994)
			(xy 321.11152 -395.039758) (xy 321.107493 -395.021657) (xy 321.102736 -395.013688) (xy 321.086431 -394.987841)
			(xy 321.062526 -394.931606) (xy 321.055238 -394.901928) (xy 321.053169 -394.893769) (xy 321.044474 -394.879367)
			(xy 321.03822 -394.873734) (xy 321.015106 -394.854684) (xy 321.008219 -394.849448) (xy 320.991994 -394.843476)
			(xy 320.983356 -394.843) (xy 320.953719 -394.841996) (xy 320.895054 -394.833346) (xy 320.837997 -394.817195)
			(xy 320.783503 -394.793811) (xy 320.732484 -394.763588) (xy 320.685794 -394.727031) (xy 320.644215 -394.684751)
			(xy 320.608443 -394.637456) (xy 320.579076 -394.585939) (xy 320.556607 -394.531062) (xy 320.541411 -394.473743)
			(xy 320.533743 -394.414942) (xy 320.533268 -394.385292) (xy 320.533785 -394.354166) (xy 320.542195 -394.292484)
			(xy 320.550032 -394.262356) (xy 320.552826 -394.252196) (xy 320.550286 -394.232384) (xy 320.503042 -394.150342)
			(xy 320.48704 -394.13815) (xy 320.47688 -394.13561) (xy 320.447769 -394.127614) (xy 320.391801 -394.104982)
			(xy 320.339294 -394.075189) (xy 320.291159 -394.038751) (xy 320.248232 -393.996302) (xy 320.211257 -393.948579)
			(xy 320.180878 -393.896409) (xy 320.15762 -393.840698) (xy 320.141888 -393.782413) (xy 320.133954 -393.722565)
			(xy 320.133472 -393.69238) (xy 320.134002 -393.661492) (xy 320.142306 -393.600277) (xy 320.158762 -393.540733)
			(xy 320.18307 -393.483941) (xy 320.198496 -393.457176) (xy 320.204338 -393.44727) (xy 320.206624 -393.424918)
			(xy 320.17335 -393.329668) (xy 320.157602 -393.313666) (xy 320.146934 -393.309602) (xy 320.123539 -393.300452)
			(xy 320.079644 -393.276025) (xy 320.03995 -393.245238) (xy 320.005371 -393.208799) (xy 319.976704 -393.167548)
			(xy 319.954608 -393.122434) (xy 319.939593 -393.074497) (xy 319.932004 -393.024839) (xy 319.931542 -392.999722)
			(xy 319.392808 -392.999722) (xy 319.392275 -393.026824) (xy 319.383467 -393.080306) (xy 319.375282 -393.106148)
			(xy 319.371472 -393.11707) (xy 319.374012 -393.139422) (xy 319.42659 -393.225274) (xy 319.44564 -393.23772)
			(xy 319.456816 -393.239498) (xy 319.486132 -393.244217) (xy 319.543303 -393.260264) (xy 319.597917 -393.283572)
			(xy 319.649056 -393.313749) (xy 319.695862 -393.350289) (xy 319.737548 -393.392577) (xy 319.773412 -393.439903)
			(xy 319.802853 -393.49147) (xy 319.825375 -393.546413) (xy 319.840599 -393.603808) (xy 319.848271 -393.66269)
			(xy 319.848738 -393.69238) (xy 319.848212 -393.723443) (xy 319.839799 -393.784996) (xy 319.831974 -393.815062)
			(xy 319.82918 -393.825222) (xy 319.83172 -393.845034) (xy 319.879218 -393.92733) (xy 319.89522 -393.939522)
			(xy 319.90538 -393.942062) (xy 319.934495 -393.950043) (xy 319.990461 -393.972681) (xy 320.042966 -394.002478)
			(xy 320.091098 -394.038918) (xy 320.134024 -394.081369) (xy 320.170997 -394.129094) (xy 320.201376 -394.181264)
			(xy 320.224635 -394.236975) (xy 320.240369 -394.29526) (xy 320.248305 -394.355107) (xy 320.248788 -394.385292)
			(xy 320.248663 -394.399427) (xy 320.246881 -394.427641) (xy 320.245232 -394.44168) (xy 320.244475 -394.450287)
			(xy 320.248113 -394.467167) (xy 320.252344 -394.4747) (xy 320.268092 -394.5001) (xy 320.272801 -394.50716)
			(xy 320.285907 -394.517929) (xy 320.293746 -394.521182) (xy 320.317131 -394.530357) (xy 320.361026 -394.554779)
			(xy 320.400721 -394.585562) (xy 320.4353 -394.621997) (xy 320.463969 -394.663245) (xy 320.486066 -394.708356)
			(xy 320.501084 -394.756291) (xy 320.508675 -394.805946) (xy 320.509138 -394.831062) (xy 320.508723 -394.855265)
			(xy 320.501648 -394.90315) (xy 320.487659 -394.94949) (xy 320.467055 -394.993291) (xy 320.45402 -395.013688)
			(xy 320.449229 -395.021643) (xy 320.445198 -395.039755) (xy 320.446146 -395.048994) (xy 320.450464 -395.079982)
			(xy 320.452157 -395.089275) (xy 320.461431 -395.105717) (xy 320.468498 -395.111986) (xy 320.490572 -395.130684)
			(xy 320.530347 -395.172691) (xy 320.564512 -395.219376) (xy 320.592523 -395.269993) (xy 320.613932 -395.323736)
			(xy 320.628399 -395.379748) (xy 320.635693 -395.437137) (xy 320.636138 -395.466062) (xy 320.635548 -395.499383)
			(xy 320.625886 -395.565322) (xy 320.60676 -395.629161) (xy 320.593212 -395.65961) (xy 320.588953 -395.670072)
			(xy 320.589066 -395.692635) (xy 320.598807 -395.712988) (xy 320.607182 -395.72057) (xy 320.629409 -395.739267)
			(xy 320.669474 -395.781318) (xy 320.703897 -395.8281) (xy 320.732124 -395.878861) (xy 320.753703 -395.932786)
			(xy 320.768286 -395.989007) (xy 320.775639 -396.046621) (xy 320.776092 -396.075662) (xy 320.775601 -396.104666)
			(xy 320.76829 -396.162212) (xy 320.75377 -396.218374) (xy 320.732272 -396.272252) (xy 320.70414 -396.322982)
			(xy 320.669825 -396.369753) (xy 320.629878 -396.411814) (xy 320.60769 -396.4305) (xy 320.600578 -396.436088)
			(xy 320.591434 -396.451328) (xy 320.576194 -396.534132) (xy 320.578988 -396.551404) (xy 320.58356 -396.559532)
			(xy 320.596137 -396.582718) (xy 320.61401 -396.63234) (xy 320.62311 -396.684291) (xy 320.623692 -396.710662)
			(xy 320.623624 -396.720021) (xy 320.62248 -396.738703) (xy 320.621406 -396.748) (xy 320.62039 -396.75689)
			(xy 320.6242 -396.773654) (xy 320.668142 -396.843504) (xy 320.681858 -396.853918) (xy 320.69024 -396.856712)
			(xy 320.714346 -396.86517) (xy 320.759636 -396.888802) (xy 320.800529 -396.919417) (xy 320.835959 -396.956219)
			(xy 320.865 -396.998245) (xy 320.886895 -397.0444) (xy 320.894456 -397.068802) (xy 320.89598 -397.074644)
			(xy 321.215766 -397.627602) (xy 321.21983 -397.63192) (xy 321.236023 -397.649625) (xy 321.263387 -397.689034)
			(xy 321.284472 -397.732132) (xy 321.298791 -397.777923) (xy 321.306015 -397.825354) (xy 321.306444 -397.849344)
			(xy 321.306022 -397.874136) (xy 321.298259 -397.923109) (xy 321.282931 -397.970264) (xy 321.260415 -398.014441)
			(xy 321.231266 -398.054552) (xy 321.1962 -398.08961) (xy 321.156083 -398.118751) (xy 321.111901 -398.141257)
			(xy 321.064742 -398.156575) (xy 321.015768 -398.164328) (xy 320.990976 -398.164812) (xy 320.965581 -398.164333)
			(xy 320.915446 -398.156198) (xy 320.86726 -398.140143) (xy 320.822266 -398.116582) (xy 320.781623 -398.086121)
			(xy 320.746381 -398.049548) (xy 320.717448 -398.007804) (xy 320.69557 -397.961967) (xy 320.687954 -397.937736)
			(xy 320.68643 -397.931894) (xy 320.365882 -397.377412) (xy 320.361818 -397.373094) (xy 320.345713 -397.355438)
			(xy 320.318527 -397.316137) (xy 320.297577 -397.273187) (xy 320.283342 -397.227569) (xy 320.276147 -397.180326)
			(xy 320.275712 -397.156432) (xy 320.275793 -397.144384) (xy 320.277576 -397.120355) (xy 320.279268 -397.108426)
			(xy 320.280538 -397.099536) (xy 320.27749 -397.082518) (xy 320.235326 -397.011652) (xy 320.222118 -397.000476)
			(xy 320.213736 -396.997428) (xy 320.191981 -396.989051) (xy 320.151123 -396.966606) (xy 320.114154 -396.938209)
			(xy 320.081933 -396.904521) (xy 320.055209 -396.866324) (xy 320.034604 -396.824509) (xy 320.020597 -396.780046)
			(xy 320.013514 -396.73397) (xy 320.013076 -396.710662) (xy 320.013645 -396.684289) (xy 320.022727 -396.632331)
			(xy 320.040614 -396.58271) (xy 320.053208 -396.559532) (xy 320.05778 -396.551404) (xy 320.060574 -396.534132)
			(xy 320.045334 -396.451328) (xy 320.03619 -396.436088) (xy 320.029078 -396.4305) (xy 320.006903 -396.411799)
			(xy 319.966957 -396.369736) (xy 319.93264 -396.322967) (xy 319.904502 -396.27224) (xy 319.882993 -396.218367)
			(xy 319.868457 -396.162209) (xy 319.861127 -396.104666) (xy 319.860676 -396.075662) (xy 319.861273 -396.042341)
			(xy 319.870932 -395.976402) (xy 319.890056 -395.912563) (xy 319.903602 -395.882114) (xy 319.907834 -395.871643)
			(xy 319.907728 -395.849088) (xy 319.898 -395.828738) (xy 319.889632 -395.821154) (xy 319.867372 -395.802495)
			(xy 319.827308 -395.760438) (xy 319.792888 -395.713649) (xy 319.764664 -395.662882) (xy 319.743091 -395.608951)
			(xy 319.728515 -395.552724) (xy 319.72117 -395.495105) (xy 319.720722 -395.466062) (xy 319.721184 -395.437136)
			(xy 319.728467 -395.379745) (xy 319.742925 -395.323729) (xy 319.764328 -395.269981) (xy 319.792333 -395.21936)
			(xy 319.826494 -395.172671) (xy 319.866268 -395.13066) (xy 319.888362 -395.111986) (xy 319.895334 -395.105639)
			(xy 319.904592 -395.089235) (xy 319.906396 -395.079982) (xy 319.910714 -395.048994) (xy 319.911623 -395.039758)
			(xy 319.907596 -395.021657) (xy 319.90284 -395.013688) (xy 319.886535 -394.98784) (xy 319.86263 -394.931606)
			(xy 319.855342 -394.901928) (xy 319.853272 -394.89377) (xy 319.844578 -394.879367) (xy 319.838324 -394.873734)
			(xy 319.81521 -394.854684) (xy 319.808322 -394.84945) (xy 319.792098 -394.843477) (xy 319.78346 -394.843)
			(xy 319.753823 -394.841992) (xy 319.695158 -394.833343) (xy 319.638101 -394.817192) (xy 319.583607 -394.793809)
			(xy 319.532588 -394.763586) (xy 319.485898 -394.727029) (xy 319.444319 -394.68475) (xy 319.408547 -394.637456)
			(xy 319.37918 -394.585939) (xy 319.356711 -394.531062) (xy 319.341515 -394.473743) (xy 319.333847 -394.414941)
			(xy 319.333372 -394.385292) (xy 319.333892 -394.354229) (xy 319.342309 -394.292675) (xy 319.350136 -394.26261)
			(xy 319.35293 -394.25245) (xy 319.35039 -394.232638) (xy 319.302892 -394.150342) (xy 319.28689 -394.13815)
			(xy 319.27673 -394.13561) (xy 319.247609 -394.127648) (xy 319.191642 -394.10501) (xy 319.139136 -394.075211)
			(xy 319.091002 -394.038769) (xy 319.048076 -393.996316) (xy 319.011103 -393.948589) (xy 318.980725 -393.896416)
			(xy 318.957468 -393.840703) (xy 318.941737 -393.782416) (xy 318.933803 -393.722566) (xy 318.933322 -393.69238)
			(xy 318.933845 -393.661492) (xy 318.94215 -393.600276) (xy 318.958608 -393.540732) (xy 318.982919 -393.483941)
			(xy 318.998346 -393.457176) (xy 319.004188 -393.44727) (xy 319.006474 -393.424918) (xy 318.9732 -393.329668)
			(xy 318.957452 -393.313666) (xy 318.946784 -393.309602) (xy 318.9234 -393.300425) (xy 318.879503 -393.276004)
			(xy 318.839807 -393.245222) (xy 318.805226 -393.208788) (xy 318.776557 -393.16754) (xy 318.75446 -393.122429)
			(xy 318.739444 -393.074494) (xy 318.731854 -393.024838) (xy 318.731392 -392.999722) (xy 318.192912 -392.999722)
			(xy 318.192379 -393.026824) (xy 318.183571 -393.080306) (xy 318.175386 -393.106148) (xy 318.171576 -393.11707)
			(xy 318.174116 -393.139422) (xy 318.226694 -393.225274) (xy 318.245744 -393.23772) (xy 318.25692 -393.239498)
			(xy 318.286237 -393.244214) (xy 318.343407 -393.260261) (xy 318.398021 -393.28357) (xy 318.449161 -393.313747)
			(xy 318.495967 -393.350288) (xy 318.537652 -393.392576) (xy 318.573516 -393.439902) (xy 318.602957 -393.49147)
			(xy 318.625479 -393.546413) (xy 318.640703 -393.603808) (xy 318.648375 -393.66269) (xy 318.648842 -393.69238)
			(xy 318.648315 -393.723443) (xy 318.639903 -393.784996) (xy 318.632078 -393.815062) (xy 318.629284 -393.825222)
			(xy 318.631824 -393.845034) (xy 318.679322 -393.92733) (xy 318.695324 -393.939522) (xy 318.705484 -393.942062)
			(xy 318.734568 -393.950108) (xy 318.790493 -393.972775) (xy 318.842957 -394.00259) (xy 318.89105 -394.039038)
			(xy 318.93394 -394.081487) (xy 318.970883 -394.129201) (xy 319.001239 -394.181354) (xy 319.024482 -394.237042)
			(xy 319.04021 -394.295301) (xy 319.048149 -394.35512) (xy 319.048638 -394.385292) (xy 319.048513 -394.399427)
			(xy 319.046731 -394.427641) (xy 319.045082 -394.44168) (xy 319.044318 -394.450287) (xy 319.047959 -394.467168)
			(xy 319.052194 -394.4747) (xy 319.067942 -394.5001) (xy 319.072635 -394.507173) (xy 319.085752 -394.517935)
			(xy 319.093596 -394.521182) (xy 319.11697 -394.530384) (xy 319.160867 -394.5548) (xy 319.200563 -394.585578)
			(xy 319.235145 -394.622009) (xy 319.263816 -394.663253) (xy 319.285915 -394.708361) (xy 319.300933 -394.756293)
			(xy 319.308525 -394.805947) (xy 319.308988 -394.831062) (xy 319.308565 -394.855264) (xy 319.301491 -394.903149)
			(xy 319.287504 -394.949489) (xy 319.266904 -394.993291) (xy 319.25387 -395.013688) (xy 319.249082 -395.021645)
			(xy 319.245048 -395.039756) (xy 319.245996 -395.048994) (xy 319.250314 -395.079982) (xy 319.251992 -395.089279)
			(xy 319.261275 -395.105721) (xy 319.268348 -395.111986) (xy 319.290433 -395.130672) (xy 319.330206 -395.172682)
			(xy 319.364368 -395.21937) (xy 319.392376 -395.269989) (xy 319.413784 -395.323733) (xy 319.42825 -395.379747)
			(xy 319.435543 -395.437136) (xy 319.435988 -395.466062) (xy 319.435394 -395.499383) (xy 319.425732 -395.565321)
			(xy 319.406608 -395.629161) (xy 319.393062 -395.65961) (xy 319.388786 -395.670068) (xy 319.388899 -395.692637)
			(xy 319.39865 -395.712991) (xy 319.407032 -395.72057) (xy 319.429269 -395.739255) (xy 319.469332 -395.781309)
			(xy 319.503752 -395.828094) (xy 319.531978 -395.878857) (xy 319.553555 -395.932783) (xy 319.568137 -395.989005)
			(xy 319.575489 -396.046621) (xy 319.575942 -396.075662) (xy 319.575469 -396.104667) (xy 319.568158 -396.162215)
			(xy 319.553636 -396.218377) (xy 319.532135 -396.272256) (xy 319.504 -396.322986) (xy 319.469681 -396.369756)
			(xy 319.42973 -396.411816) (xy 319.40754 -396.4305) (xy 319.400428 -396.436088) (xy 319.391284 -396.451328)
			(xy 319.376044 -396.534132) (xy 319.378838 -396.551404) (xy 319.38341 -396.559532) (xy 319.395983 -396.58272)
			(xy 319.413858 -396.632341) (xy 319.42296 -396.684292) (xy 319.423542 -396.710662) (xy 319.423473 -396.720021)
			(xy 319.42233 -396.738703) (xy 319.421256 -396.748) (xy 319.42024 -396.75689) (xy 319.42405 -396.773654)
			(xy 319.467992 -396.843504) (xy 319.481708 -396.853918) (xy 319.49009 -396.856712) (xy 319.514108 -396.865207)
			(xy 319.559282 -396.888752) (xy 319.600089 -396.919246) (xy 319.63547 -396.955896) (xy 319.664508 -396.997751)
			(xy 319.686448 -397.043726) (xy 319.694052 -397.06804) (xy 319.695576 -397.073882) (xy 320.01587 -397.627602)
			(xy 320.019934 -397.63192) (xy 320.036128 -397.649624) (xy 320.063491 -397.689034) (xy 320.084576 -397.732131)
			(xy 320.098895 -397.777923) (xy 320.106119 -397.825354) (xy 320.106548 -397.849344) (xy 320.106123 -397.874136)
			(xy 320.098359 -397.923108) (xy 320.083031 -397.970263) (xy 320.060516 -398.01444) (xy 320.031367 -398.054551)
			(xy 319.996302 -398.089608) (xy 319.956185 -398.118749) (xy 319.912004 -398.141256) (xy 319.864846 -398.156574)
			(xy 319.815872 -398.164328) (xy 319.79108 -398.164812) (xy 319.765685 -398.164329) (xy 319.715551 -398.156195)
			(xy 319.667365 -398.140141) (xy 319.62237 -398.11658) (xy 319.581728 -398.08612) (xy 319.546485 -398.049547)
			(xy 319.517552 -398.007804) (xy 319.495674 -397.961967) (xy 319.488058 -397.937736) (xy 319.486534 -397.931894)
			(xy 319.16624 -397.378174) (xy 319.162176 -397.373856) (xy 319.145969 -397.356151) (xy 319.118546 -397.316759)
			(xy 319.097404 -397.273669) (xy 319.083031 -397.227874) (xy 319.075758 -397.180431) (xy 319.075308 -397.156432)
			(xy 319.07545 -397.14438) (xy 319.077356 -397.12035) (xy 319.079118 -397.108426) (xy 319.080388 -397.099536)
			(xy 319.07734 -397.082518) (xy 319.035176 -397.011652) (xy 319.021968 -397.000476) (xy 319.013586 -396.997428)
			(xy 318.991842 -396.989024) (xy 318.950983 -396.966585) (xy 318.914011 -396.938194) (xy 318.881788 -396.904509)
			(xy 318.855062 -396.866317) (xy 318.834456 -396.824504) (xy 318.820448 -396.780043) (xy 318.813364 -396.73397)
			(xy 318.812926 -396.710662) (xy 318.813488 -396.684289) (xy 318.822572 -396.63233) (xy 318.840462 -396.58271)
			(xy 318.853058 -396.559532) (xy 318.85763 -396.551404) (xy 318.860424 -396.534132) (xy 318.845184 -396.451328)
			(xy 318.83604 -396.436088) (xy 318.828928 -396.4305) (xy 318.806763 -396.411787) (xy 318.766815 -396.369728)
			(xy 318.732496 -396.322961) (xy 318.704356 -396.272236) (xy 318.682845 -396.218365) (xy 318.668308 -396.162208)
			(xy 318.660977 -396.104666) (xy 318.660526 -396.075662) (xy 318.661127 -396.042341) (xy 318.670786 -395.976403)
			(xy 318.689907 -395.912563) (xy 318.703452 -395.882114) (xy 318.7077 -395.871648) (xy 318.707596 -395.849086)
			(xy 318.697857 -395.828735) (xy 318.689482 -395.821154) (xy 318.667211 -395.802508) (xy 318.62715 -395.760447)
			(xy 318.592732 -395.713655) (xy 318.564511 -395.662886) (xy 318.542939 -395.608953) (xy 318.528364 -395.552725)
			(xy 318.52102 -395.495105) (xy 318.520572 -395.466062) (xy 318.521016 -395.437135) (xy 318.5283 -395.379742)
			(xy 318.54276 -395.323725) (xy 318.564165 -395.269977) (xy 318.592173 -395.219356) (xy 318.626338 -395.172668)
			(xy 318.666115 -395.130659) (xy 318.688212 -395.111986) (xy 318.695176 -395.105631) (xy 318.70444 -395.089233)
			(xy 318.706246 -395.079982) (xy 318.710564 -395.048994) (xy 318.711465 -395.039757) (xy 318.707442 -395.021658)
			(xy 318.70269 -395.013688) (xy 318.686381 -394.987843) (xy 318.662478 -394.931607) (xy 318.655192 -394.901928)
			(xy 318.653135 -394.893765) (xy 318.644433 -394.879364) (xy 318.638174 -394.873734) (xy 318.61506 -394.854684)
			(xy 318.608185 -394.84943) (xy 318.591951 -394.843469) (xy 318.58331 -394.843) (xy 318.553675 -394.841946)
			(xy 318.495012 -394.833303) (xy 318.437955 -394.817158) (xy 318.383461 -394.793781) (xy 318.332442 -394.763563)
			(xy 318.285752 -394.72701) (xy 318.244172 -394.684734) (xy 318.208399 -394.637444) (xy 318.179032 -394.58593)
			(xy 318.156562 -394.531055) (xy 318.141365 -394.473739) (xy 318.133697 -394.41494) (xy 318.133222 -394.385292)
			(xy 318.13374 -394.354166) (xy 318.142149 -394.292484) (xy 318.149986 -394.262356) (xy 318.15278 -394.252196)
			(xy 318.15024 -394.232384) (xy 318.102996 -394.150342) (xy 318.086994 -394.13815) (xy 318.076834 -394.13561)
			(xy 318.047714 -394.127645) (xy 317.991747 -394.105007) (xy 317.93924 -394.075209) (xy 317.891107 -394.038767)
			(xy 317.848181 -393.996315) (xy 317.811208 -393.948588) (xy 317.780829 -393.896415) (xy 317.757572 -393.840702)
			(xy 317.741841 -393.782415) (xy 317.733907 -393.722566) (xy 317.733426 -393.69238) (xy 317.733948 -393.661492)
			(xy 317.742254 -393.600276) (xy 317.758711 -393.540732) (xy 317.783023 -393.483941) (xy 317.79845 -393.457176)
			(xy 317.804292 -393.44727) (xy 317.806578 -393.424918) (xy 317.773304 -393.329668) (xy 317.757556 -393.313666)
			(xy 317.746888 -393.309602) (xy 317.723505 -393.300422) (xy 317.679608 -393.276003) (xy 317.639912 -393.245221)
			(xy 317.605331 -393.208787) (xy 317.576661 -393.16754) (xy 317.554564 -393.122429) (xy 317.539548 -393.074494)
			(xy 317.531958 -393.024838) (xy 317.531496 -392.999722) (xy 316.992762 -392.999722) (xy 316.992231 -393.026824)
			(xy 316.983422 -393.080307) (xy 316.975236 -393.106148) (xy 316.971426 -393.11707) (xy 316.973966 -393.139422)
			(xy 317.026544 -393.225274) (xy 317.045594 -393.23772) (xy 317.05677 -393.239498) (xy 317.086093 -393.244175)
			(xy 317.143264 -393.260228) (xy 317.197878 -393.283542) (xy 317.249017 -393.313725) (xy 317.295822 -393.35027)
			(xy 317.337506 -393.392562) (xy 317.373369 -393.439891) (xy 317.402809 -393.491462) (xy 317.42533 -393.546407)
			(xy 317.440554 -393.603805) (xy 317.448225 -393.662689) (xy 317.448692 -393.69238) (xy 317.448164 -393.723443)
			(xy 317.439753 -393.784996) (xy 317.431928 -393.815062) (xy 317.429134 -393.825222) (xy 317.431674 -393.845034)
			(xy 317.479172 -393.92733) (xy 317.495174 -393.939522) (xy 317.505334 -393.942062) (xy 317.53444 -393.950074)
			(xy 317.590406 -393.972706) (xy 317.642912 -394.002499) (xy 317.691046 -394.038934) (xy 317.733973 -394.081382)
			(xy 317.770947 -394.129103) (xy 317.801328 -394.181271) (xy 317.824587 -394.236979) (xy 317.840322 -394.295262)
			(xy 317.848258 -394.355107) (xy 317.848742 -394.385292) (xy 317.848617 -394.399427) (xy 317.846835 -394.427641)
			(xy 317.845186 -394.44168) (xy 317.844421 -394.450287) (xy 317.848063 -394.467168) (xy 317.852298 -394.4747)
			(xy 317.868046 -394.5001) (xy 317.872738 -394.507174) (xy 317.885856 -394.517935) (xy 317.8937 -394.521182)
			(xy 317.917075 -394.530381) (xy 317.960972 -394.554798) (xy 318.000668 -394.585577) (xy 318.035249 -394.622008)
			(xy 318.06392 -394.663252) (xy 318.086019 -394.70836) (xy 318.101037 -394.756293) (xy 318.108629 -394.805947)
			(xy 318.109092 -394.831062) (xy 318.108668 -394.855264) (xy 318.101594 -394.903149) (xy 318.087608 -394.949489)
			(xy 318.067007 -394.993291) (xy 318.053974 -395.013688) (xy 318.049186 -395.021645) (xy 318.045152 -395.039756)
			(xy 318.0461 -395.048994) (xy 318.050418 -395.079982) (xy 318.052094 -395.08928) (xy 318.061379 -395.105721)
			(xy 318.068452 -395.111986) (xy 318.090538 -395.130671) (xy 318.13031 -395.172682) (xy 318.164473 -395.219369)
			(xy 318.192481 -395.269988) (xy 318.213888 -395.323733) (xy 318.228354 -395.379747) (xy 318.235647 -395.437136)
			(xy 318.236092 -395.466062) (xy 318.235497 -395.499383) (xy 318.225836 -395.565321) (xy 318.206712 -395.629161)
			(xy 318.193166 -395.65961) (xy 318.188922 -395.670076) (xy 318.189036 -395.692633) (xy 318.198768 -395.712984)
			(xy 318.207136 -395.72057) (xy 318.229374 -395.739254) (xy 318.269436 -395.781309) (xy 318.303857 -395.828094)
			(xy 318.332082 -395.878857) (xy 318.353659 -395.932783) (xy 318.368241 -395.989005) (xy 318.375593 -396.046621)
			(xy 318.376046 -396.075662) (xy 318.375571 -396.104667) (xy 318.36826 -396.162214) (xy 318.353738 -396.218377)
			(xy 318.332238 -396.272255) (xy 318.304103 -396.322986) (xy 318.269785 -396.369756) (xy 318.229834 -396.411815)
			(xy 318.207644 -396.4305) (xy 318.200532 -396.436088) (xy 318.191388 -396.451328) (xy 318.176148 -396.534132)
			(xy 318.178942 -396.551404) (xy 318.183514 -396.559532) (xy 318.196087 -396.58272) (xy 318.213962 -396.63234)
			(xy 318.223064 -396.684291) (xy 318.223646 -396.710662) (xy 318.223577 -396.720021) (xy 318.222434 -396.738703)
			(xy 318.22136 -396.748) (xy 318.220344 -396.75689) (xy 318.224154 -396.773654) (xy 318.268096 -396.843504)
			(xy 318.281812 -396.853918) (xy 318.290194 -396.856712) (xy 318.31429 -396.865195) (xy 318.359581 -396.88882)
			(xy 318.400477 -396.91943) (xy 318.435908 -396.956227) (xy 318.464952 -396.99825) (xy 318.486848 -397.044401)
			(xy 318.49441 -397.068802) (xy 318.495934 -397.074644) (xy 318.81572 -397.627602) (xy 318.819784 -397.63192)
			(xy 318.835973 -397.649641) (xy 318.8634 -397.689028) (xy 318.884546 -397.732114) (xy 318.898923 -397.777906)
			(xy 318.9062 -397.825346) (xy 318.906652 -397.849344) (xy 318.906247 -397.87415) (xy 318.898475 -397.92315)
			(xy 318.883131 -397.970331) (xy 318.860591 -398.014528) (xy 318.831413 -398.054653) (xy 318.796314 -398.089717)
			(xy 318.75616 -398.118856) (xy 318.71194 -398.141351) (xy 318.664745 -398.156648) (xy 318.615737 -398.164371)
			(xy 318.59093 -398.164812) (xy 318.565537 -398.164285) (xy 318.515404 -398.156159) (xy 318.467219 -398.140112)
			(xy 318.422225 -398.116558) (xy 318.381582 -398.086104) (xy 318.346338 -398.049536) (xy 318.317404 -398.007798)
			(xy 318.295525 -397.961965) (xy 318.287908 -397.937736) (xy 318.286384 -397.931894) (xy 317.965836 -397.377412)
			(xy 317.961772 -397.373094) (xy 317.945672 -397.355421) (xy 317.918423 -397.316143) (xy 317.897411 -397.273204)
			(xy 317.883118 -397.227586) (xy 317.875871 -397.180334) (xy 317.875412 -397.156432) (xy 317.875554 -397.14438)
			(xy 317.87746 -397.12035) (xy 317.879222 -397.108426) (xy 317.880492 -397.099536) (xy 317.877444 -397.082518)
			(xy 317.83528 -397.011652) (xy 317.822072 -397.000476) (xy 317.81369 -396.997428) (xy 317.791947 -396.989022)
			(xy 317.751087 -396.966584) (xy 317.714116 -396.938192) (xy 317.681893 -396.904509) (xy 317.655167 -396.866316)
			(xy 317.63456 -396.824503) (xy 317.620552 -396.780043) (xy 317.613468 -396.733969) (xy 317.61303 -396.710662)
			(xy 317.613592 -396.684289) (xy 317.622676 -396.63233) (xy 317.640566 -396.58271) (xy 317.653162 -396.559532)
			(xy 317.657734 -396.551404) (xy 317.660528 -396.534132) (xy 317.645288 -396.451328) (xy 317.636144 -396.436088)
			(xy 317.629032 -396.4305) (xy 317.606868 -396.411786) (xy 317.566919 -396.369727) (xy 317.5326 -396.322961)
			(xy 317.50446 -396.272236) (xy 317.482949 -396.218364) (xy 317.468412 -396.162208) (xy 317.461081 -396.104666)
			(xy 317.46063 -396.075662) (xy 317.461231 -396.042341) (xy 317.470889 -395.976403) (xy 317.490011 -395.912563)
			(xy 317.503556 -395.882114) (xy 317.507803 -395.871647) (xy 317.507698 -395.849086) (xy 317.497961 -395.828735)
			(xy 317.489586 -395.821154) (xy 317.467316 -395.802507) (xy 317.427255 -395.760446) (xy 317.392837 -395.713655)
			(xy 317.364615 -395.662885) (xy 317.343043 -395.608953) (xy 317.328468 -395.552725) (xy 317.321124 -395.495105)
			(xy 317.320676 -395.466062) (xy 317.321119 -395.437135) (xy 317.328403 -395.379742) (xy 317.342863 -395.323725)
			(xy 317.364267 -395.269977) (xy 317.392276 -395.219356) (xy 317.426442 -395.172668) (xy 317.466219 -395.130659)
			(xy 317.488316 -395.111986) (xy 317.495281 -395.105631) (xy 317.504544 -395.089233) (xy 317.50635 -395.079982)
			(xy 317.510668 -395.048994) (xy 317.511569 -395.039757) (xy 317.507546 -395.021658) (xy 317.502794 -395.013688)
			(xy 317.486485 -394.987843) (xy 317.462582 -394.931607) (xy 317.455296 -394.901928) (xy 317.453238 -394.893766)
			(xy 317.444536 -394.879365) (xy 317.438278 -394.873734) (xy 317.415164 -394.854684) (xy 317.408288 -394.849431)
			(xy 317.392055 -394.84347) (xy 317.383414 -394.843) (xy 317.353779 -394.841943) (xy 317.295116 -394.8333)
			(xy 317.23806 -394.817155) (xy 317.183566 -394.793778) (xy 317.132546 -394.763561) (xy 317.085856 -394.727008)
			(xy 317.044276 -394.684733) (xy 317.008503 -394.637443) (xy 316.979136 -394.585929) (xy 316.956666 -394.531055)
			(xy 316.941469 -394.473739) (xy 316.933801 -394.41494) (xy 316.933326 -394.385292) (xy 316.933848 -394.354229)
			(xy 316.942263 -394.292675) (xy 316.95009 -394.26261) (xy 316.952884 -394.25245) (xy 316.950344 -394.232638)
			(xy 316.902846 -394.150342) (xy 316.886844 -394.13815) (xy 316.876684 -394.13561) (xy 316.847574 -394.127612)
			(xy 316.791606 -394.10498) (xy 316.739098 -394.075187) (xy 316.690963 -394.03875) (xy 316.648036 -393.996301)
			(xy 316.611062 -393.948578) (xy 316.580682 -393.896408) (xy 316.557424 -393.840697) (xy 316.541692 -393.782413)
			(xy 316.533758 -393.722565) (xy 316.533276 -393.69238) (xy 316.533805 -393.661492) (xy 316.54211 -393.600277)
			(xy 316.558566 -393.540733) (xy 316.582874 -393.483941) (xy 316.5983 -393.457176) (xy 316.604142 -393.44727)
			(xy 316.606428 -393.424918) (xy 316.573154 -393.329668) (xy 316.557406 -393.313666) (xy 316.546738 -393.309602)
			(xy 316.523344 -393.300449) (xy 316.479449 -393.276023) (xy 316.439754 -393.245237) (xy 316.405175 -393.208798)
			(xy 316.376508 -393.167547) (xy 316.354412 -393.122434) (xy 316.339397 -393.074497) (xy 316.331808 -393.024839)
			(xy 316.331346 -392.999722) (xy 315.792866 -392.999722) (xy 315.792335 -393.026824) (xy 315.783526 -393.080307)
			(xy 315.77534 -393.106148) (xy 315.77153 -393.11707) (xy 315.77407 -393.139422) (xy 315.826648 -393.225274)
			(xy 315.845698 -393.23772) (xy 315.856874 -393.239498) (xy 315.886198 -393.244172) (xy 315.943369 -393.260225)
			(xy 315.997982 -393.28354) (xy 316.049121 -393.313723) (xy 316.095926 -393.350268) (xy 316.13761 -393.392561)
			(xy 316.173474 -393.43989) (xy 316.202913 -393.491461) (xy 316.225434 -393.546407) (xy 316.240658 -393.603804)
			(xy 316.248329 -393.662689) (xy 316.248796 -393.69238) (xy 316.248271 -393.723443) (xy 316.239858 -393.784997)
			(xy 316.232032 -393.815062) (xy 316.229238 -393.825222) (xy 316.231778 -393.845034) (xy 316.279276 -393.92733)
			(xy 316.295278 -393.939522) (xy 316.305438 -393.942062) (xy 316.334545 -393.950071) (xy 316.390511 -393.972704)
			(xy 316.443017 -394.002497) (xy 316.491151 -394.038933) (xy 316.534077 -394.08138) (xy 316.571051 -394.129102)
			(xy 316.601432 -394.18127) (xy 316.624691 -394.236979) (xy 316.640426 -394.295262) (xy 316.648362 -394.355107)
			(xy 316.648846 -394.385292) (xy 316.648721 -394.399427) (xy 316.646939 -394.427641) (xy 316.64529 -394.44168)
			(xy 316.644524 -394.450287) (xy 316.648167 -394.467168) (xy 316.652402 -394.4747) (xy 316.66815 -394.5001)
			(xy 316.67286 -394.507162) (xy 316.685959 -394.517942) (xy 316.693804 -394.521182) (xy 316.717147 -394.530424)
			(xy 316.760991 -394.554876) (xy 316.800636 -394.585672) (xy 316.835171 -394.622107) (xy 316.863804 -394.663342)
			(xy 316.885876 -394.708431) (xy 316.900881 -394.756337) (xy 316.908473 -394.805961) (xy 316.908942 -394.831062)
			(xy 316.908526 -394.855265) (xy 316.901452 -394.90315) (xy 316.887463 -394.94949) (xy 316.866859 -394.993291)
			(xy 316.853824 -395.013688) (xy 316.849033 -395.021643) (xy 316.845002 -395.039755) (xy 316.84595 -395.048994)
			(xy 316.850268 -395.079982) (xy 316.85196 -395.089275) (xy 316.861235 -395.105717) (xy 316.868302 -395.111986)
			(xy 316.890377 -395.130683) (xy 316.930152 -395.172691) (xy 316.964317 -395.219375) (xy 316.992327 -395.269993)
			(xy 317.013736 -395.323736) (xy 317.028203 -395.379748) (xy 317.035497 -395.437137) (xy 317.035942 -395.466062)
			(xy 317.035352 -395.499383) (xy 317.02569 -395.565322) (xy 317.006564 -395.629161) (xy 316.993016 -395.65961)
			(xy 316.988755 -395.670071) (xy 316.988869 -395.692635) (xy 316.998611 -395.712988) (xy 317.006986 -395.72057)
			(xy 317.029213 -395.739266) (xy 317.069278 -395.781317) (xy 317.103701 -395.8281) (xy 317.131929 -395.878861)
			(xy 317.153507 -395.932785) (xy 317.16809 -395.989007) (xy 317.175443 -396.046621) (xy 317.175896 -396.075662)
			(xy 317.175403 -396.104666) (xy 317.168093 -396.162212) (xy 317.153573 -396.218374) (xy 317.132074 -396.272251)
			(xy 317.103943 -396.322982) (xy 317.069629 -396.369753) (xy 317.029681 -396.411814) (xy 317.007494 -396.4305)
			(xy 317.000382 -396.436088) (xy 316.991238 -396.451328) (xy 316.975998 -396.534132) (xy 316.978792 -396.551404)
			(xy 316.983364 -396.559532) (xy 316.995941 -396.582718) (xy 317.013814 -396.63234) (xy 317.022914 -396.684291)
			(xy 317.023496 -396.710662) (xy 317.023428 -396.720021) (xy 317.022284 -396.738703) (xy 317.02121 -396.748)
			(xy 317.020194 -396.75689) (xy 317.024004 -396.773654) (xy 317.067946 -396.843504) (xy 317.081662 -396.853918)
			(xy 317.090044 -396.856712) (xy 317.114073 -396.865178) (xy 317.159245 -396.888731) (xy 317.20005 -396.919231)
			(xy 317.235429 -396.955886) (xy 317.264465 -396.997746) (xy 317.286403 -397.043724) (xy 317.294006 -397.06804)
			(xy 317.29553 -397.073882) (xy 317.615824 -397.627602) (xy 317.619888 -397.63192) (xy 317.636078 -397.64964)
			(xy 317.663504 -397.689028) (xy 317.68465 -397.732114) (xy 317.699027 -397.777906) (xy 317.706304 -397.825346)
			(xy 317.706756 -397.849344) (xy 317.706347 -397.87415) (xy 317.698575 -397.92315) (xy 317.683231 -397.97033)
			(xy 317.660692 -398.014527) (xy 317.631514 -398.054651) (xy 317.596415 -398.089715) (xy 317.556262 -398.118854)
			(xy 317.512043 -398.14135) (xy 317.464848 -398.156648) (xy 317.415841 -398.164371) (xy 317.391034 -398.164812)
			(xy 317.365641 -398.164282) (xy 317.315508 -398.156156) (xy 317.267324 -398.14011) (xy 317.222329 -398.116556)
			(xy 317.181686 -398.086103) (xy 317.146443 -398.049535) (xy 317.117508 -398.007797) (xy 317.095629 -397.961965)
			(xy 317.088012 -397.937736) (xy 317.086488 -397.931894) (xy 316.766194 -397.378174) (xy 316.76213 -397.373856)
			(xy 316.745967 -397.356126) (xy 316.7186 -397.316722) (xy 316.69751 -397.273631) (xy 316.683184 -397.227846)
			(xy 316.67595 -397.18042) (xy 316.675516 -397.156432) (xy 316.675597 -397.144384) (xy 316.677379 -397.120355)
			(xy 316.679072 -397.108426) (xy 316.680342 -397.099536) (xy 316.677294 -397.082518) (xy 316.63513 -397.011652)
			(xy 316.621922 -397.000476) (xy 316.61354 -396.997428) (xy 316.591786 -396.989049) (xy 316.550928 -396.966604)
			(xy 316.513959 -396.938208) (xy 316.481737 -396.90452) (xy 316.455013 -396.866324) (xy 316.434408 -396.824508)
			(xy 316.420401 -396.780046) (xy 316.413318 -396.73397) (xy 316.41288 -396.710662) (xy 316.413448 -396.684289)
			(xy 316.422531 -396.632331) (xy 316.440418 -396.58271) (xy 316.453012 -396.559532) (xy 316.457584 -396.551404)
			(xy 316.460378 -396.534132) (xy 316.445138 -396.451328) (xy 316.435994 -396.436088) (xy 316.428882 -396.4305)
			(xy 316.406708 -396.411798) (xy 316.366761 -396.369736) (xy 316.332445 -396.322967) (xy 316.304307 -396.27224)
			(xy 316.282798 -396.218367) (xy 316.268261 -396.162209) (xy 316.260931 -396.104666) (xy 316.26048 -396.075662)
			(xy 316.261076 -396.042341) (xy 316.270736 -395.976402) (xy 316.289859 -395.912563) (xy 316.303406 -395.882114)
			(xy 316.307636 -395.871643) (xy 316.307531 -395.849088) (xy 316.297803 -395.828738) (xy 316.289436 -395.821154)
			(xy 316.267176 -395.802494) (xy 316.227113 -395.760437) (xy 316.192692 -395.713649) (xy 316.164468 -395.662881)
			(xy 316.142895 -395.608951) (xy 316.128319 -395.552724) (xy 316.120974 -395.495105) (xy 316.120526 -395.466062)
			(xy 316.120987 -395.437136) (xy 316.12827 -395.379744) (xy 316.142728 -395.323728) (xy 316.164131 -395.269981)
			(xy 316.192136 -395.21936) (xy 316.226298 -395.172671) (xy 316.266071 -395.13066) (xy 316.288166 -395.111986)
			(xy 316.295139 -395.10564) (xy 316.304396 -395.089235) (xy 316.3062 -395.079982) (xy 316.310518 -395.048994)
			(xy 316.311427 -395.039757) (xy 316.3074 -395.021657) (xy 316.302644 -395.013688) (xy 316.28634 -394.98784)
			(xy 316.262434 -394.931606) (xy 316.255146 -394.901928) (xy 316.253075 -394.89377) (xy 316.244382 -394.879367)
			(xy 316.238128 -394.873734) (xy 316.215014 -394.854684) (xy 316.208183 -394.849479) (xy 316.192091 -394.843508)
			(xy 316.183518 -394.843) (xy 316.153883 -394.841939) (xy 316.09522 -394.833297) (xy 316.038164 -394.817153)
			(xy 315.98367 -394.793776) (xy 315.932651 -394.763559) (xy 315.88596 -394.727007) (xy 315.84438 -394.684732)
			(xy 315.808607 -394.637442) (xy 315.77924 -394.585929) (xy 315.75677 -394.531055) (xy 315.741573 -394.473739)
			(xy 315.733905 -394.41494) (xy 315.73343 -394.385292) (xy 315.733951 -394.354229) (xy 315.742367 -394.292675)
			(xy 315.750194 -394.26261) (xy 315.752988 -394.25245) (xy 315.750448 -394.232638) (xy 315.70295 -394.150342)
			(xy 315.686948 -394.13815) (xy 315.676788 -394.13561) (xy 315.647678 -394.127609) (xy 315.59171 -394.104978)
			(xy 315.539203 -394.075185) (xy 315.491068 -394.038749) (xy 315.448141 -393.9963) (xy 315.411166 -393.948577)
			(xy 315.380786 -393.896408) (xy 315.357528 -393.840697) (xy 315.341796 -393.782412) (xy 315.333862 -393.722565)
			(xy 315.33338 -393.69238) (xy 315.333909 -393.661492) (xy 315.342213 -393.600277) (xy 315.358669 -393.540733)
			(xy 315.382978 -393.483941) (xy 315.398404 -393.457176) (xy 315.404246 -393.44727) (xy 315.406532 -393.424918)
			(xy 315.373258 -393.329668) (xy 315.35751 -393.313666) (xy 315.346842 -393.309602) (xy 315.323449 -393.300447)
			(xy 315.279553 -393.276022) (xy 315.239859 -393.245235) (xy 315.20528 -393.208797) (xy 315.176612 -393.167547)
			(xy 315.154516 -393.122434) (xy 315.139501 -393.074496) (xy 315.131912 -393.024839) (xy 315.13145 -392.999722)
			(xy 314.59297 -392.999722) (xy 314.592439 -393.026824) (xy 314.58363 -393.080307) (xy 314.575444 -393.106148)
			(xy 314.571634 -393.11707) (xy 314.574174 -393.139422) (xy 314.626752 -393.225528) (xy 314.645548 -393.23772)
			(xy 314.656978 -393.239498) (xy 314.686272 -393.244279) (xy 314.743406 -393.260356) (xy 314.797982 -393.283685)
			(xy 314.849085 -393.313874) (xy 314.895855 -393.350417) (xy 314.937509 -393.392699) (xy 314.973347 -393.440011)
			(xy 315.002768 -393.49156) (xy 315.025277 -393.54648) (xy 315.040498 -393.603848) (xy 315.048174 -393.662703)
			(xy 315.048646 -393.69238) (xy 315.048119 -393.723443) (xy 315.039707 -393.784996) (xy 315.031882 -393.815062)
			(xy 315.029088 -393.825222) (xy 315.031628 -393.845034) (xy 315.079126 -393.92733) (xy 315.095128 -393.939522)
			(xy 315.105288 -393.942062) (xy 315.134404 -393.950038) (xy 315.19037 -393.972676) (xy 315.242875 -394.002475)
			(xy 315.291007 -394.038916) (xy 315.333933 -394.081367) (xy 315.370906 -394.129092) (xy 315.401285 -394.181263)
			(xy 315.424543 -394.236974) (xy 315.440277 -394.295259) (xy 315.448213 -394.355106) (xy 315.448696 -394.385292)
			(xy 315.448571 -394.399427) (xy 315.446789 -394.427641) (xy 315.44514 -394.44168) (xy 315.444382 -394.450287)
			(xy 315.44802 -394.467167) (xy 315.452252 -394.4747) (xy 315.468 -394.5001) (xy 315.472707 -394.507162)
			(xy 315.485814 -394.51793) (xy 315.493654 -394.521182) (xy 315.517041 -394.530352) (xy 315.560936 -394.554776)
			(xy 315.60063 -394.58556) (xy 315.635209 -394.621996) (xy 315.663878 -394.663244) (xy 315.685975 -394.708355)
			(xy 315.700992 -394.75629) (xy 315.708583 -394.805946) (xy 315.709046 -394.831062) (xy 315.70863 -394.855265)
			(xy 315.701555 -394.90315) (xy 315.687566 -394.94949) (xy 315.666963 -394.993291) (xy 315.653928 -395.013688)
			(xy 315.649137 -395.021643) (xy 315.645106 -395.039756) (xy 315.646054 -395.048994) (xy 315.650372 -395.079982)
			(xy 315.652062 -395.089276) (xy 315.661338 -395.105718) (xy 315.668406 -395.111986) (xy 315.690482 -395.130682)
			(xy 315.730257 -395.17269) (xy 315.764421 -395.219375) (xy 315.792431 -395.269992) (xy 315.81384 -395.323735)
			(xy 315.828307 -395.379748) (xy 315.835601 -395.437137) (xy 315.836046 -395.466062) (xy 315.835456 -395.499383)
			(xy 315.825793 -395.565322) (xy 315.806667 -395.629161) (xy 315.79312 -395.65961) (xy 315.788858 -395.670071)
			(xy 315.788972 -395.692635) (xy 315.798714 -395.712988) (xy 315.80709 -395.72057) (xy 315.829318 -395.739265)
			(xy 315.869383 -395.781317) (xy 315.903805 -395.828099) (xy 315.932033 -395.87886) (xy 315.953611 -395.932785)
			(xy 315.968194 -395.989007) (xy 315.975547 -396.046621) (xy 315.976 -396.075662) (xy 315.975542 -396.104668)
			(xy 315.96823 -396.162216) (xy 315.953706 -396.21838) (xy 315.932203 -396.272259) (xy 315.904066 -396.322989)
			(xy 315.869744 -396.369758) (xy 315.829789 -396.411816) (xy 315.807598 -396.4305) (xy 315.800486 -396.436088)
			(xy 315.791342 -396.451328) (xy 315.776102 -396.534132) (xy 315.778896 -396.551404) (xy 315.783468 -396.559532)
			(xy 315.796037 -396.582722) (xy 315.813915 -396.632341) (xy 315.823018 -396.684292) (xy 315.8236 -396.710662)
			(xy 315.823532 -396.720021) (xy 315.822388 -396.738703) (xy 315.821314 -396.748) (xy 315.820298 -396.75689)
			(xy 315.824108 -396.773654) (xy 315.86805 -396.843504) (xy 315.881766 -396.853918) (xy 315.890148 -396.856712)
			(xy 315.914178 -396.865175) (xy 315.95935 -396.888729) (xy 316.000155 -396.91923) (xy 316.035534 -396.955886)
			(xy 316.064569 -396.997746) (xy 316.086507 -397.043724) (xy 316.09411 -397.06804) (xy 316.095634 -397.073882)
			(xy 316.415928 -397.627602) (xy 316.419992 -397.63192) (xy 316.436182 -397.64964) (xy 316.463609 -397.689027)
			(xy 316.484754 -397.732114) (xy 316.499131 -397.777906) (xy 316.506408 -397.825346) (xy 316.50686 -397.849344)
			(xy 316.506447 -397.87415) (xy 316.498675 -397.923149) (xy 316.483331 -397.970329) (xy 316.460793 -398.014525)
			(xy 316.431615 -398.05465) (xy 316.396517 -398.089714) (xy 316.356364 -398.118853) (xy 316.312146 -398.141349)
			(xy 316.264951 -398.156647) (xy 316.215944 -398.164371) (xy 316.191138 -398.164812) (xy 316.165745 -398.164278)
			(xy 316.115613 -398.156153) (xy 316.067428 -398.140107) (xy 316.022434 -398.116554) (xy 315.98179 -398.086101)
			(xy 315.946547 -398.049534) (xy 315.917612 -398.007797) (xy 315.895733 -397.961965) (xy 315.888116 -397.937736)
			(xy 315.886592 -397.931894) (xy 315.566298 -397.378174) (xy 315.562234 -397.373856) (xy 315.546071 -397.356125)
			(xy 315.518704 -397.316722) (xy 315.497615 -397.273631) (xy 315.483288 -397.227846) (xy 315.476054 -397.18042)
			(xy 315.47562 -397.156432) (xy 315.475701 -397.144384) (xy 315.477483 -397.120355) (xy 315.479176 -397.108426)
			(xy 315.480446 -397.099536) (xy 315.477398 -397.082518) (xy 315.435234 -397.011652) (xy 315.422026 -397.000476)
			(xy 315.413644 -396.997428) (xy 315.391891 -396.989047) (xy 315.351033 -396.966603) (xy 315.314063 -396.938207)
			(xy 315.281842 -396.904519) (xy 315.255117 -396.866323) (xy 315.234512 -396.824508) (xy 315.220505 -396.780046)
			(xy 315.213422 -396.73397) (xy 315.212984 -396.710662) (xy 315.213552 -396.684289) (xy 315.222634 -396.632331)
			(xy 315.240522 -396.58271) (xy 315.253116 -396.559532) (xy 315.257688 -396.551404) (xy 315.260482 -396.534132)
			(xy 315.245242 -396.451328) (xy 315.236098 -396.436088) (xy 315.228986 -396.4305) (xy 315.206812 -396.411797)
			(xy 315.166866 -396.369735) (xy 315.132549 -396.322966) (xy 315.104411 -396.27224) (xy 315.082902 -396.218367)
			(xy 315.068365 -396.162209) (xy 315.061035 -396.104666) (xy 315.060584 -396.075662) (xy 315.06118 -396.042341)
			(xy 315.07084 -395.976402) (xy 315.089963 -395.912563) (xy 315.10351 -395.882114) (xy 315.107739 -395.871643)
			(xy 315.107634 -395.849088) (xy 315.097907 -395.828739) (xy 315.08954 -395.821154) (xy 315.067281 -395.802493)
			(xy 315.027217 -395.760437) (xy 314.992797 -395.713648) (xy 314.964573 -395.662881) (xy 314.942999 -395.608951)
			(xy 314.928423 -395.552724) (xy 314.921078 -395.495105) (xy 314.92063 -395.466062) (xy 314.921089 -395.437136)
			(xy 314.928373 -395.379744) (xy 314.942831 -395.323728) (xy 314.964233 -395.269981) (xy 314.992239 -395.219359)
			(xy 315.026401 -395.172671) (xy 315.066175 -395.13066) (xy 315.08827 -395.111986) (xy 315.095243 -395.10564)
			(xy 315.1045 -395.089235) (xy 315.106304 -395.079982) (xy 315.110622 -395.048994) (xy 315.11153 -395.039757)
			(xy 315.107504 -395.021657) (xy 315.102748 -395.013688) (xy 315.086435 -394.987845) (xy 315.062535 -394.931608)
			(xy 315.05525 -394.901928) (xy 315.053178 -394.89377) (xy 315.044485 -394.879368) (xy 315.038232 -394.873734)
			(xy 315.015118 -394.854684) (xy 315.008228 -394.849453) (xy 314.992005 -394.843478) (xy 314.983368 -394.843)
			(xy 314.953732 -394.841985) (xy 314.895067 -394.833337) (xy 314.83801 -394.817187) (xy 314.783516 -394.793805)
			(xy 314.732497 -394.763582) (xy 314.685807 -394.727026) (xy 314.644227 -394.684747) (xy 314.608455 -394.637454)
			(xy 314.579088 -394.585937) (xy 314.556619 -394.531061) (xy 314.541423 -394.473742) (xy 314.533755 -394.414941)
			(xy 314.53328 -394.385292) (xy 314.5338 -394.354229) (xy 314.542217 -394.292675) (xy 314.550044 -394.26261)
			(xy 314.552838 -394.25245) (xy 314.550298 -394.232638) (xy 314.5028 -394.150342) (xy 314.486798 -394.13815)
			(xy 314.476638 -394.13561) (xy 314.447519 -394.127643) (xy 314.391551 -394.105005) (xy 314.339045 -394.075207)
			(xy 314.290911 -394.038766) (xy 314.247985 -393.996314) (xy 314.211012 -393.948587) (xy 314.180633 -393.896415)
			(xy 314.157376 -393.840702) (xy 314.141645 -393.782415) (xy 314.133711 -393.722566) (xy 314.13323 -393.69238)
			(xy 314.133705 -393.661458) (xy 314.141987 -393.600171) (xy 314.158452 -393.540559) (xy 314.182799 -393.48371)
			(xy 314.198254 -393.456922) (xy 314.20435 -393.44727) (xy 314.206636 -393.424918) (xy 314.173108 -393.329668)
			(xy 314.15736 -393.313666) (xy 314.146692 -393.309602) (xy 314.123343 -393.300376) (xy 314.079498 -393.275922)
			(xy 314.039853 -393.245123) (xy 314.005318 -393.208686) (xy 313.976686 -393.167449) (xy 313.954615 -393.122358)
			(xy 313.939612 -393.074449) (xy 313.932022 -393.024823) (xy 313.931554 -392.999722) (xy 313.39282 -392.999722)
			(xy 313.392287 -393.026824) (xy 313.383479 -393.080306) (xy 313.375294 -393.106148) (xy 313.371484 -393.11707)
			(xy 313.374024 -393.139422) (xy 313.426602 -393.225274) (xy 313.445652 -393.23772) (xy 313.456828 -393.239498)
			(xy 313.486146 -393.244208) (xy 313.543316 -393.260256) (xy 313.59793 -393.283565) (xy 313.64907 -393.313744)
			(xy 313.695876 -393.350285) (xy 313.737561 -393.392574) (xy 313.773425 -393.4399) (xy 313.802865 -393.491468)
			(xy 313.825387 -393.546412) (xy 313.840611 -393.603807) (xy 313.848283 -393.66269) (xy 313.84875 -393.69238)
			(xy 313.848223 -393.723443) (xy 313.839811 -393.784996) (xy 313.831986 -393.815062) (xy 313.829192 -393.825222)
			(xy 313.831732 -393.845034) (xy 313.87923 -393.92733) (xy 313.895232 -393.939522) (xy 313.905392 -393.942062)
			(xy 313.934509 -393.950035) (xy 313.990475 -393.972674) (xy 314.04298 -394.002473) (xy 314.091112 -394.038914)
			(xy 314.134037 -394.081366) (xy 314.17101 -394.129091) (xy 314.201389 -394.181262) (xy 314.224647 -394.236974)
			(xy 314.240381 -394.295259) (xy 314.248317 -394.355106) (xy 314.2488 -394.385292) (xy 314.248675 -394.399427)
			(xy 314.246893 -394.427641) (xy 314.245244 -394.44168) (xy 314.244485 -394.450287) (xy 314.248124 -394.467167)
			(xy 314.252356 -394.4747) (xy 314.268104 -394.5001) (xy 314.272797 -394.507176) (xy 314.285907 -394.517948)
			(xy 314.293758 -394.521182) (xy 314.317112 -394.530395) (xy 314.360955 -394.554853) (xy 314.400598 -394.585656)
			(xy 314.435131 -394.622095) (xy 314.463762 -394.663334) (xy 314.485832 -394.708426) (xy 314.500836 -394.756335)
			(xy 314.508427 -394.80596) (xy 314.508896 -394.831062) (xy 314.508471 -394.855264) (xy 314.501398 -394.903149)
			(xy 314.487411 -394.949488) (xy 314.466811 -394.99329) (xy 314.453778 -395.013688) (xy 314.448991 -395.021645)
			(xy 314.444956 -395.039756) (xy 314.445904 -395.048994) (xy 314.450222 -395.079982) (xy 314.451897 -395.08928)
			(xy 314.461182 -395.105721) (xy 314.468256 -395.111986) (xy 314.490343 -395.13067) (xy 314.530115 -395.172681)
			(xy 314.564277 -395.219369) (xy 314.592285 -395.269988) (xy 314.613692 -395.323733) (xy 314.628158 -395.379747)
			(xy 314.635451 -395.437136) (xy 314.635896 -395.466062) (xy 314.635301 -395.499383) (xy 314.62564 -395.565321)
			(xy 314.606516 -395.629161) (xy 314.59297 -395.65961) (xy 314.588725 -395.670075) (xy 314.588839 -395.692634)
			(xy 314.598571 -395.712985) (xy 314.60694 -395.72057) (xy 314.629158 -395.739278) (xy 314.669225 -395.781326)
			(xy 314.70365 -395.828105) (xy 314.731879 -395.878864) (xy 314.75346 -395.932788) (xy 314.768044 -395.989008)
			(xy 314.775397 -396.046622) (xy 314.77585 -396.075662) (xy 314.775374 -396.104667) (xy 314.768063 -396.162214)
			(xy 314.753541 -396.218377) (xy 314.732041 -396.272255) (xy 314.703906 -396.322985) (xy 314.669588 -396.369755)
			(xy 314.629637 -396.411815) (xy 314.607448 -396.4305) (xy 314.600336 -396.436088) (xy 314.591192 -396.451328)
			(xy 314.575952 -396.534132) (xy 314.578746 -396.551404) (xy 314.583318 -396.559532) (xy 314.595891 -396.58272)
			(xy 314.613766 -396.63234) (xy 314.622868 -396.684291) (xy 314.62345 -396.710662) (xy 314.623381 -396.720021)
			(xy 314.622238 -396.738703) (xy 314.621164 -396.748) (xy 314.620148 -396.75689) (xy 314.623958 -396.773654)
			(xy 314.6679 -396.843504) (xy 314.681616 -396.853918) (xy 314.689998 -396.856712) (xy 314.714018 -396.865202)
			(xy 314.759191 -396.888749) (xy 314.799998 -396.919244) (xy 314.835379 -396.955894) (xy 314.864416 -396.99775)
			(xy 314.886356 -397.043726) (xy 314.89396 -397.06804) (xy 314.895484 -397.073882) (xy 315.215778 -397.627602)
			(xy 315.219842 -397.63192) (xy 315.236037 -397.649623) (xy 315.2634 -397.689033) (xy 315.284484 -397.732131)
			(xy 315.298803 -397.777923) (xy 315.306028 -397.825354) (xy 315.306456 -397.849344) (xy 315.306023 -397.874135)
			(xy 315.29826 -397.923107) (xy 315.282932 -397.970261) (xy 315.260417 -398.014438) (xy 315.231269 -398.054548)
			(xy 315.196205 -398.089605) (xy 315.15609 -398.118746) (xy 315.111909 -398.141254) (xy 315.064752 -398.156573)
			(xy 315.015779 -398.164327) (xy 314.990988 -398.164812) (xy 314.965593 -398.164322) (xy 314.915459 -398.15619)
			(xy 314.867273 -398.140136) (xy 314.822279 -398.116576) (xy 314.781636 -398.086118) (xy 314.746394 -398.049545)
			(xy 314.71746 -398.007803) (xy 314.695582 -397.961967) (xy 314.687966 -397.937736) (xy 314.686442 -397.931894)
			(xy 314.366148 -397.378174) (xy 314.362084 -397.373856) (xy 314.345878 -397.35615) (xy 314.318455 -397.316758)
			(xy 314.297313 -397.273668) (xy 314.282939 -397.227874) (xy 314.275666 -397.180431) (xy 314.275216 -397.156432)
			(xy 314.275358 -397.14438) (xy 314.277264 -397.12035) (xy 314.279026 -397.108426) (xy 314.280296 -397.099536)
			(xy 314.277248 -397.082518) (xy 314.235084 -397.011652) (xy 314.221876 -397.000476) (xy 314.213494 -396.997428)
			(xy 314.191751 -396.98902) (xy 314.150892 -396.966582) (xy 314.113921 -396.938191) (xy 314.081697 -396.904508)
			(xy 314.054971 -396.866315) (xy 314.034364 -396.824503) (xy 314.020356 -396.780043) (xy 314.013272 -396.733969)
			(xy 314.012834 -396.710662) (xy 314.013395 -396.684289) (xy 314.022479 -396.63233) (xy 314.04037 -396.58271)
			(xy 314.052966 -396.559532) (xy 314.057538 -396.551404) (xy 314.060332 -396.534132) (xy 314.045092 -396.451328)
			(xy 314.035948 -396.436088) (xy 314.028836 -396.4305) (xy 314.006673 -396.411785) (xy 313.966724 -396.369726)
			(xy 313.932405 -396.32296) (xy 313.904264 -396.272236) (xy 313.882753 -396.218364) (xy 313.868216 -396.162208)
			(xy 313.860885 -396.104666) (xy 313.860434 -396.075662) (xy 313.861035 -396.042341) (xy 313.870693 -395.976403)
			(xy 313.889815 -395.912563) (xy 313.90336 -395.882114) (xy 313.907606 -395.871647) (xy 313.907501 -395.849087)
			(xy 313.897764 -395.828735) (xy 313.88939 -395.821154) (xy 313.867121 -395.802506) (xy 313.827059 -395.760445)
			(xy 313.792641 -395.713654) (xy 313.764419 -395.662885) (xy 313.742847 -395.608953) (xy 313.728272 -395.552725)
			(xy 313.720928 -395.495105) (xy 313.72048 -395.466062) (xy 313.720921 -395.437135) (xy 313.728205 -395.379742)
			(xy 313.742665 -395.323725) (xy 313.76407 -395.269977) (xy 313.792079 -395.219355) (xy 313.826245 -395.172668)
			(xy 313.866023 -395.130659) (xy 313.88812 -395.111986) (xy 313.895085 -395.105632) (xy 313.904348 -395.089234)
			(xy 313.906154 -395.079982) (xy 313.910472 -395.048994) (xy 313.911372 -395.039757) (xy 313.90735 -395.021658)
			(xy 313.902598 -395.013688) (xy 313.886289 -394.987843) (xy 313.862386 -394.931607) (xy 313.8551 -394.901928)
			(xy 313.853041 -394.893766) (xy 313.84434 -394.879365) (xy 313.838082 -394.873734) (xy 313.814968 -394.854684)
			(xy 313.808149 -394.84946) (xy 313.792048 -394.843501) (xy 313.783472 -394.843) (xy 313.753836 -394.841981)
			(xy 313.695171 -394.833334) (xy 313.638114 -394.817184) (xy 313.58362 -394.793802) (xy 313.532601 -394.763581)
			(xy 313.485911 -394.727024) (xy 313.444332 -394.684746) (xy 313.408559 -394.637453) (xy 313.379193 -394.585937)
			(xy 313.356723 -394.53106) (xy 313.341527 -394.473742) (xy 313.333859 -394.414941) (xy 313.333384 -394.385292)
			(xy 313.333904 -394.354229) (xy 313.342321 -394.292675) (xy 313.350148 -394.26261) (xy 313.352942 -394.25245)
			(xy 313.350402 -394.232638) (xy 313.302904 -394.150342) (xy 313.286902 -394.13815) (xy 313.276742 -394.13561)
			(xy 313.247624 -394.12764) (xy 313.191656 -394.105003) (xy 313.13915 -394.075206) (xy 313.091016 -394.038765)
			(xy 313.04809 -393.996313) (xy 313.011116 -393.948587) (xy 312.980738 -393.896414) (xy 312.957481 -393.840701)
			(xy 312.941749 -393.782415) (xy 312.933815 -393.722566) (xy 312.933334 -393.69238) (xy 312.933855 -393.661492)
			(xy 312.942161 -393.600276) (xy 312.958619 -393.540732) (xy 312.98293 -393.48394) (xy 312.998358 -393.457176)
			(xy 313.0042 -393.44727) (xy 313.006486 -393.424918) (xy 312.973212 -393.329668) (xy 312.957464 -393.313666)
			(xy 312.946796 -393.309602) (xy 312.923415 -393.300418) (xy 312.879517 -393.275999) (xy 312.839821 -393.245219)
			(xy 312.80524 -393.208785) (xy 312.77657 -393.167539) (xy 312.754472 -393.122428) (xy 312.739456 -393.074493)
			(xy 312.731866 -393.024838) (xy 312.731404 -392.999722) (xy 312.192924 -392.999722) (xy 312.192395 -393.026824)
			(xy 312.183585 -393.080307) (xy 312.175398 -393.106148) (xy 312.171588 -393.11707) (xy 312.174128 -393.139422)
			(xy 312.226706 -393.225274) (xy 312.245756 -393.23772) (xy 312.256932 -393.239498) (xy 312.28625 -393.244204)
			(xy 312.343421 -393.260253) (xy 312.398035 -393.283563) (xy 312.449174 -393.313742) (xy 312.49598 -393.350283)
			(xy 312.537665 -393.392573) (xy 312.573529 -393.439899) (xy 312.602969 -393.491468) (xy 312.625491 -393.546411)
			(xy 312.640715 -393.603807) (xy 312.648387 -393.66269) (xy 312.648854 -393.69238) (xy 312.648327 -393.723443)
			(xy 312.639915 -393.784996) (xy 312.63209 -393.815062) (xy 312.629296 -393.825222) (xy 312.631836 -393.845034)
			(xy 312.679334 -393.92733) (xy 312.695336 -393.939522) (xy 312.705496 -393.942062) (xy 312.734582 -393.9501)
			(xy 312.790507 -393.972768) (xy 312.842971 -394.002585) (xy 312.891064 -394.039034) (xy 312.933953 -394.081484)
			(xy 312.970896 -394.129199) (xy 313.001251 -394.181352) (xy 313.024494 -394.237041) (xy 313.040222 -394.2953)
			(xy 313.048161 -394.35512) (xy 313.04865 -394.385292) (xy 313.048525 -394.399427) (xy 313.046743 -394.427641)
			(xy 313.045094 -394.44168) (xy 313.044328 -394.450287) (xy 313.04797 -394.467168) (xy 313.052206 -394.4747)
			(xy 313.067954 -394.5001) (xy 313.072675 -394.507151) (xy 313.085773 -394.517925) (xy 313.093608 -394.521182)
			(xy 313.116985 -394.530377) (xy 313.160881 -394.554795) (xy 313.200577 -394.585574) (xy 313.235158 -394.622006)
			(xy 313.263828 -394.663251) (xy 313.285927 -394.70836) (xy 313.300945 -394.756293) (xy 313.308537 -394.805947)
			(xy 313.309 -394.831062) (xy 313.308575 -394.855264) (xy 313.301501 -394.903149) (xy 313.287515 -394.949488)
			(xy 313.266915 -394.99329) (xy 313.253882 -395.013688) (xy 313.249095 -395.021645) (xy 313.24506 -395.039756)
			(xy 313.246008 -395.048994) (xy 313.250326 -395.079982) (xy 313.252 -395.08928) (xy 313.261286 -395.105721)
			(xy 313.26836 -395.111986) (xy 313.290448 -395.130669) (xy 313.330219 -395.17268) (xy 313.364381 -395.219368)
			(xy 313.392389 -395.269988) (xy 313.413797 -395.323733) (xy 313.428262 -395.379746) (xy 313.435555 -395.437136)
			(xy 313.436 -395.466062) (xy 313.435414 -395.499384) (xy 313.425751 -395.565322) (xy 313.406623 -395.629161)
			(xy 313.393074 -395.65961) (xy 313.388827 -395.670075) (xy 313.388941 -395.692634) (xy 313.398675 -395.712985)
			(xy 313.407044 -395.72057) (xy 313.429263 -395.739277) (xy 313.46933 -395.781325) (xy 313.503754 -395.828105)
			(xy 313.531984 -395.878864) (xy 313.553564 -395.932787) (xy 313.568148 -395.989008) (xy 313.575501 -396.046621)
			(xy 313.575954 -396.075662) (xy 313.575476 -396.104667) (xy 313.568166 -396.162214) (xy 313.553644 -396.218377)
			(xy 313.532144 -396.272255) (xy 313.504009 -396.322985) (xy 313.469692 -396.369755) (xy 313.429741 -396.411815)
			(xy 313.407552 -396.4305) (xy 313.40044 -396.436088) (xy 313.391296 -396.451328) (xy 313.376056 -396.534132)
			(xy 313.37885 -396.551404) (xy 313.383422 -396.559532) (xy 313.395996 -396.582719) (xy 313.413871 -396.63234)
			(xy 313.422972 -396.684291) (xy 313.423554 -396.710662) (xy 313.423485 -396.720021) (xy 313.422342 -396.738703)
			(xy 313.421268 -396.748) (xy 313.420252 -396.75689) (xy 313.424062 -396.773654) (xy 313.468004 -396.843504)
			(xy 313.48172 -396.853918) (xy 313.490102 -396.856712) (xy 313.514123 -396.8652) (xy 313.559296 -396.888748)
			(xy 313.600102 -396.919243) (xy 313.635483 -396.955894) (xy 313.66452 -396.99775) (xy 313.68646 -397.043725)
			(xy 313.694064 -397.06804) (xy 313.695588 -397.073882) (xy 314.015882 -397.627602) (xy 314.019946 -397.63192)
			(xy 314.036142 -397.649622) (xy 314.063505 -397.689033) (xy 314.084589 -397.732131) (xy 314.098907 -397.777923)
			(xy 314.106132 -397.825354) (xy 314.10656 -397.849344) (xy 314.106123 -397.874135) (xy 314.09836 -397.923106)
			(xy 314.083033 -397.97026) (xy 314.060518 -398.014436) (xy 314.03137 -398.054547) (xy 313.996307 -398.089604)
			(xy 313.956192 -398.118745) (xy 313.912012 -398.141252) (xy 313.864856 -398.156572) (xy 313.815883 -398.164327)
			(xy 313.791092 -398.164812) (xy 313.765697 -398.164319) (xy 313.715563 -398.156187) (xy 313.667378 -398.140134)
			(xy 313.622383 -398.116575) (xy 313.581741 -398.086116) (xy 313.546498 -398.049544) (xy 313.517565 -398.007802)
			(xy 313.495687 -397.961967) (xy 313.48807 -397.937736) (xy 313.486546 -397.931894) (xy 313.166252 -397.378174)
			(xy 313.162188 -397.373856) (xy 313.145983 -397.356149) (xy 313.118559 -397.316758) (xy 313.097417 -397.273668)
			(xy 313.083043 -397.227874) (xy 313.07577 -397.180431) (xy 313.07532 -397.156432) (xy 313.075462 -397.14438)
			(xy 313.077368 -397.12035) (xy 313.07913 -397.108426) (xy 313.0804 -397.099536) (xy 313.077352 -397.082518)
			(xy 313.035188 -397.011652) (xy 313.02198 -397.000476) (xy 313.013598 -396.997428) (xy 312.991856 -396.989017)
			(xy 312.950997 -396.96658) (xy 312.914025 -396.93819) (xy 312.881801 -396.904507) (xy 312.855075 -396.866315)
			(xy 312.834468 -396.824503) (xy 312.82046 -396.780043) (xy 312.813376 -396.733969) (xy 312.812938 -396.710662)
			(xy 312.813499 -396.684289) (xy 312.822583 -396.63233) (xy 312.840474 -396.58271) (xy 312.85307 -396.559532)
			(xy 312.857642 -396.551404) (xy 312.860436 -396.534132) (xy 312.845196 -396.451328) (xy 312.836052 -396.436088)
			(xy 312.82894 -396.4305) (xy 312.806778 -396.411784) (xy 312.766829 -396.369726) (xy 312.732509 -396.32296)
			(xy 312.704369 -396.272235) (xy 312.682858 -396.218364) (xy 312.66832 -396.162208) (xy 312.660989 -396.104666)
			(xy 312.660538 -396.075662) (xy 312.661138 -396.042341) (xy 312.670797 -395.976403) (xy 312.689919 -395.912563)
			(xy 312.703464 -395.882114) (xy 312.707708 -395.871647) (xy 312.707604 -395.849087) (xy 312.697867 -395.828736)
			(xy 312.689494 -395.821154) (xy 312.667226 -395.802505) (xy 312.627164 -395.760445) (xy 312.592745 -395.713654)
			(xy 312.564523 -395.662885) (xy 312.542951 -395.608953) (xy 312.528376 -395.552725) (xy 312.521032 -395.495105)
			(xy 312.520584 -395.466062) (xy 312.521024 -395.437135) (xy 312.528308 -395.379742) (xy 312.542768 -395.323725)
			(xy 312.564173 -395.269976) (xy 312.592182 -395.219355) (xy 312.626349 -395.172668) (xy 312.666127 -395.130659)
			(xy 312.688224 -395.111986) (xy 312.69519 -395.105633) (xy 312.704452 -395.089234) (xy 312.706258 -395.079982)
			(xy 312.710576 -395.048994) (xy 312.711476 -395.039757) (xy 312.707454 -395.021658) (xy 312.702702 -395.013688)
			(xy 312.686394 -394.987843) (xy 312.66249 -394.931607) (xy 312.655204 -394.901928) (xy 312.653144 -394.893766)
			(xy 312.644444 -394.879365) (xy 312.638186 -394.873734) (xy 312.615072 -394.854684) (xy 312.608194 -394.849435)
			(xy 312.591962 -394.843471) (xy 312.583322 -394.843) (xy 312.553684 -394.842027) (xy 312.495018 -394.833373)
			(xy 312.43796 -394.817218) (xy 312.383466 -394.793831) (xy 312.332447 -394.763604) (xy 312.285757 -394.727044)
			(xy 312.244179 -394.684761) (xy 312.208407 -394.637465) (xy 312.179041 -394.585945) (xy 312.156572 -394.531066)
			(xy 312.141377 -394.473745) (xy 312.133709 -394.414942) (xy 312.133234 -394.385292) (xy 312.133752 -394.354166)
			(xy 312.142161 -394.292484) (xy 312.149998 -394.262356) (xy 312.152792 -394.252196) (xy 312.150252 -394.232384)
			(xy 312.103008 -394.150342) (xy 312.087006 -394.13815) (xy 312.076846 -394.13561) (xy 312.047728 -394.127637)
			(xy 311.991761 -394.105001) (xy 311.939254 -394.075204) (xy 311.89112 -394.038763) (xy 311.848194 -393.996312)
			(xy 311.811221 -393.948586) (xy 311.780842 -393.896414) (xy 311.757585 -393.840701) (xy 311.741853 -393.782415)
			(xy 311.733919 -393.722566) (xy 311.733438 -393.69238) (xy 311.733958 -393.661492) (xy 311.742264 -393.600276)
			(xy 311.758722 -393.540732) (xy 311.783034 -393.48394) (xy 311.798462 -393.457176) (xy 311.804304 -393.44727)
			(xy 311.80659 -393.424918) (xy 311.773316 -393.329668) (xy 311.757568 -393.313666) (xy 311.7469 -393.309602)
			(xy 311.72352 -393.300416) (xy 311.679622 -393.275998) (xy 311.639926 -393.245217) (xy 311.605344 -393.208785)
			(xy 311.576674 -393.167538) (xy 311.554577 -393.122428) (xy 311.53956 -393.074493) (xy 311.53197 -393.024838)
			(xy 311.531508 -392.999722) (xy 310.992774 -392.999722) (xy 310.992243 -393.026824) (xy 310.983434 -393.080307)
			(xy 310.975248 -393.106148) (xy 310.971438 -393.11707) (xy 310.973978 -393.139422) (xy 311.026556 -393.225274)
			(xy 311.045606 -393.23772) (xy 311.056782 -393.239498) (xy 311.086107 -393.244165) (xy 311.143278 -393.26022)
			(xy 311.197892 -393.283536) (xy 311.24903 -393.31372) (xy 311.295835 -393.350266) (xy 311.337519 -393.392559)
			(xy 311.373382 -393.439889) (xy 311.402821 -393.49146) (xy 311.425342 -393.546406) (xy 311.440566 -393.603804)
			(xy 311.448237 -393.662689) (xy 311.448704 -393.69238) (xy 311.448179 -393.723443) (xy 311.439766 -393.784997)
			(xy 311.43194 -393.815062) (xy 311.429146 -393.825222) (xy 311.431686 -393.845034) (xy 311.479184 -393.92733)
			(xy 311.495186 -393.939522) (xy 311.505346 -393.942062) (xy 311.534454 -393.950066) (xy 311.590421 -393.972699)
			(xy 311.642926 -394.002493) (xy 311.69106 -394.03893) (xy 311.733986 -394.081378) (xy 311.77096 -394.1291)
			(xy 311.801341 -394.181269) (xy 311.8246 -394.236978) (xy 311.840334 -394.295261) (xy 311.848271 -394.355107)
			(xy 311.848754 -394.385292) (xy 311.848629 -394.399427) (xy 311.846847 -394.427641) (xy 311.845198 -394.44168)
			(xy 311.844432 -394.450287) (xy 311.848074 -394.467168) (xy 311.85231 -394.4747) (xy 311.868058 -394.5001)
			(xy 311.872778 -394.507152) (xy 311.885876 -394.517926) (xy 311.893712 -394.521182) (xy 311.917089 -394.530375)
			(xy 311.960986 -394.554793) (xy 312.000682 -394.585573) (xy 312.035263 -394.622005) (xy 312.063933 -394.66325)
			(xy 312.086031 -394.708359) (xy 312.101049 -394.756293) (xy 312.108641 -394.805946) (xy 312.109104 -394.831062)
			(xy 312.108678 -394.855264) (xy 312.101605 -394.903149) (xy 312.087618 -394.949488) (xy 312.067019 -394.99329)
			(xy 312.053986 -395.013688) (xy 312.049199 -395.021645) (xy 312.045164 -395.039756) (xy 312.046112 -395.048994)
			(xy 312.05043 -395.079982) (xy 312.052103 -395.089281) (xy 312.061389 -395.105722) (xy 312.068464 -395.111986)
			(xy 312.090552 -395.130668) (xy 312.130324 -395.17268) (xy 312.164486 -395.219368) (xy 312.192494 -395.269987)
			(xy 312.213901 -395.323733) (xy 312.228366 -395.379746) (xy 312.235659 -395.437136) (xy 312.236104 -395.466062)
			(xy 312.235518 -395.499384) (xy 312.225854 -395.565322) (xy 312.206727 -395.629161) (xy 312.193178 -395.65961)
			(xy 312.18893 -395.670075) (xy 312.189044 -395.692634) (xy 312.198778 -395.712985) (xy 312.207148 -395.72057)
			(xy 312.229367 -395.739276) (xy 312.269434 -395.781324) (xy 312.303859 -395.828104) (xy 312.332088 -395.878864)
			(xy 312.353668 -395.932787) (xy 312.368252 -395.989008) (xy 312.375605 -396.046621) (xy 312.376058 -396.075662)
			(xy 312.375579 -396.104667) (xy 312.368268 -396.162214) (xy 312.353747 -396.218376) (xy 312.332246 -396.272254)
			(xy 312.304113 -396.322985) (xy 312.269795 -396.369755) (xy 312.229845 -396.411815) (xy 312.207656 -396.4305)
			(xy 312.200544 -396.436088) (xy 312.1914 -396.451328) (xy 312.17616 -396.534132) (xy 312.178954 -396.551404)
			(xy 312.183526 -396.559532) (xy 312.1961 -396.582719) (xy 312.213975 -396.63234) (xy 312.223076 -396.684291)
			(xy 312.223658 -396.710662) (xy 312.223589 -396.720021) (xy 312.222446 -396.738703) (xy 312.221372 -396.748)
			(xy 312.220356 -396.75689) (xy 312.224166 -396.773654) (xy 312.268108 -396.843504) (xy 312.281824 -396.853918)
			(xy 312.290206 -396.856712) (xy 312.314305 -396.865189) (xy 312.359596 -396.888815) (xy 312.40049 -396.919427)
			(xy 312.435922 -396.956225) (xy 312.464964 -396.998248) (xy 312.48686 -397.044401) (xy 312.494422 -397.068802)
			(xy 312.495946 -397.074644) (xy 312.815732 -397.627602) (xy 312.819796 -397.63192) (xy 312.835987 -397.649639)
			(xy 312.863413 -397.689027) (xy 312.884559 -397.732114) (xy 312.898935 -397.777905) (xy 312.906212 -397.825346)
			(xy 312.906664 -397.849344) (xy 312.906247 -397.87415) (xy 312.898476 -397.923149) (xy 312.883132 -397.970328)
			(xy 312.860593 -398.014524) (xy 312.831416 -398.054649) (xy 312.796319 -398.089713) (xy 312.756166 -398.118851)
			(xy 312.711948 -398.141347) (xy 312.664755 -398.156646) (xy 312.615748 -398.16437) (xy 312.590942 -398.164812)
			(xy 312.565549 -398.164275) (xy 312.515417 -398.15615) (xy 312.467232 -398.140105) (xy 312.422238 -398.116552)
			(xy 312.381595 -398.0861) (xy 312.346351 -398.049534) (xy 312.317417 -398.007796) (xy 312.295537 -397.961965)
			(xy 312.28792 -397.937736) (xy 312.286396 -397.931894) (xy 311.965848 -397.377412) (xy 311.961784 -397.373094)
			(xy 311.945686 -397.355419) (xy 311.918436 -397.316142) (xy 311.897424 -397.273203) (xy 311.88313 -397.227586)
			(xy 311.875883 -397.180334) (xy 311.875424 -397.156432) (xy 311.875566 -397.14438) (xy 311.877472 -397.12035)
			(xy 311.879234 -397.108426) (xy 311.880504 -397.099536) (xy 311.877456 -397.082518) (xy 311.835292 -397.011652)
			(xy 311.822084 -397.000476) (xy 311.813702 -396.997428) (xy 311.791961 -396.989015) (xy 311.751102 -396.966578)
			(xy 311.71413 -396.938189) (xy 311.681906 -396.904506) (xy 311.655179 -396.866314) (xy 311.634572 -396.824502)
			(xy 311.620564 -396.780042) (xy 311.61348 -396.733969) (xy 311.613042 -396.710662) (xy 311.613602 -396.684289)
			(xy 311.622687 -396.63233) (xy 311.640578 -396.58271) (xy 311.653174 -396.559532) (xy 311.657746 -396.551404)
			(xy 311.66054 -396.534132) (xy 311.6453 -396.451328) (xy 311.636156 -396.436088) (xy 311.629044 -396.4305)
			(xy 311.606883 -396.411783) (xy 311.566933 -396.369725) (xy 311.532614 -396.322959) (xy 311.504473 -396.272235)
			(xy 311.482962 -396.218364) (xy 311.468424 -396.162208) (xy 311.461093 -396.104666) (xy 311.460642 -396.075662)
			(xy 311.461242 -396.042341) (xy 311.4709 -395.976403) (xy 311.490022 -395.912563) (xy 311.503568 -395.882114)
			(xy 311.507811 -395.871646) (xy 311.507706 -395.849087) (xy 311.497971 -395.828736) (xy 311.489598 -395.821154)
			(xy 311.467331 -395.802504) (xy 311.427269 -395.760444) (xy 311.39285 -395.713654) (xy 311.364628 -395.662884)
			(xy 311.343056 -395.608953) (xy 311.32848 -395.552725) (xy 311.321136 -395.495105) (xy 311.320688 -395.466062)
			(xy 311.321126 -395.437135) (xy 311.328411 -395.379742) (xy 311.342871 -395.323724) (xy 311.364276 -395.269976)
			(xy 311.392286 -395.219355) (xy 311.426452 -395.172667) (xy 311.466231 -395.130659) (xy 311.488328 -395.111986)
			(xy 311.495294 -395.105633) (xy 311.504556 -395.089234) (xy 311.506362 -395.079982) (xy 311.51068 -395.048994)
			(xy 311.511579 -395.039757) (xy 311.507557 -395.021658) (xy 311.502806 -395.013688) (xy 311.486498 -394.987842)
			(xy 311.462595 -394.931607) (xy 311.455308 -394.901928) (xy 311.453247 -394.893767) (xy 311.444547 -394.879365)
			(xy 311.43829 -394.873734) (xy 311.415176 -394.854684) (xy 311.408297 -394.849436) (xy 311.392066 -394.843472)
			(xy 311.383426 -394.843) (xy 311.353788 -394.842024) (xy 311.295122 -394.83337) (xy 311.238065 -394.817215)
			(xy 311.18357 -394.793829) (xy 311.132551 -394.763602) (xy 311.085862 -394.727042) (xy 311.044283 -394.68476)
			(xy 311.008511 -394.637464) (xy 310.979145 -394.585945) (xy 310.956676 -394.531066) (xy 310.941481 -394.473745)
			(xy 310.933813 -394.414942) (xy 310.933338 -394.385292) (xy 310.933859 -394.354229) (xy 310.942275 -394.292675)
			(xy 310.950102 -394.26261) (xy 310.952896 -394.25245) (xy 310.950356 -394.232638) (xy 310.902858 -394.150342)
			(xy 310.886856 -394.13815) (xy 310.876696 -394.13561) (xy 310.847588 -394.127604) (xy 310.79162 -394.104973)
			(xy 310.739112 -394.075182) (xy 310.690977 -394.038746) (xy 310.648049 -393.996298) (xy 310.611075 -393.948576)
			(xy 310.580695 -393.896406) (xy 310.557436 -393.840696) (xy 310.541704 -393.782412) (xy 310.53377 -393.722565)
			(xy 310.533288 -393.69238) (xy 310.533815 -393.661492) (xy 310.54212 -393.600277) (xy 310.558577 -393.540733)
			(xy 310.582886 -393.483941) (xy 310.598312 -393.457176) (xy 310.604154 -393.44727) (xy 310.60644 -393.424918)
			(xy 310.573166 -393.329668) (xy 310.557418 -393.313666) (xy 310.54675 -393.309602) (xy 310.523359 -393.300443)
			(xy 310.479463 -393.276018) (xy 310.439768 -393.245233) (xy 310.405189 -393.208796) (xy 310.376521 -393.167546)
			(xy 310.354425 -393.122433) (xy 310.339409 -393.074496) (xy 310.33182 -393.024839) (xy 310.331358 -392.999722)
			(xy 309.792878 -392.999722) (xy 309.792347 -393.026824) (xy 309.783538 -393.080307) (xy 309.775352 -393.106148)
			(xy 309.771542 -393.11707) (xy 309.774082 -393.139422) (xy 309.82666 -393.225274) (xy 309.84571 -393.23772)
			(xy 309.856886 -393.239498) (xy 309.886211 -393.244162) (xy 309.943382 -393.260218) (xy 309.997996 -393.283533)
			(xy 310.049135 -393.313718) (xy 310.095939 -393.350264) (xy 310.137623 -393.392558) (xy 310.173486 -393.439888)
			(xy 310.202925 -393.491459) (xy 310.225446 -393.546406) (xy 310.24067 -393.603804) (xy 310.248341 -393.662689)
			(xy 310.248808 -393.69238) (xy 310.248283 -393.723443) (xy 310.23987 -393.784997) (xy 310.232044 -393.815062)
			(xy 310.22925 -393.825222) (xy 310.23179 -393.845034) (xy 310.279288 -393.92733) (xy 310.29529 -393.939522)
			(xy 310.30545 -393.942062) (xy 310.334559 -393.950063) (xy 310.390525 -393.972697) (xy 310.443031 -394.002491)
			(xy 310.491164 -394.038929) (xy 310.534091 -394.081377) (xy 310.571065 -394.1291) (xy 310.601445 -394.181268)
			(xy 310.624704 -394.236978) (xy 310.640438 -394.295261) (xy 310.648375 -394.355107) (xy 310.648858 -394.385292)
			(xy 310.648733 -394.399427) (xy 310.646951 -394.427641) (xy 310.645302 -394.44168) (xy 310.644535 -394.450287)
			(xy 310.648178 -394.467168) (xy 310.652414 -394.4747) (xy 310.668162 -394.5001) (xy 310.672868 -394.507165)
			(xy 310.68597 -394.517943) (xy 310.693816 -394.521182) (xy 310.717161 -394.530417) (xy 310.761005 -394.554871)
			(xy 310.800649 -394.585669) (xy 310.835185 -394.622104) (xy 310.863817 -394.66334) (xy 310.885889 -394.70843)
			(xy 310.900893 -394.756337) (xy 310.908485 -394.805961) (xy 310.908954 -394.831062) (xy 310.908536 -394.855264)
			(xy 310.901462 -394.90315) (xy 310.887473 -394.949489) (xy 310.866871 -394.993291) (xy 310.853836 -395.013688)
			(xy 310.849046 -395.021643) (xy 310.845014 -395.039756) (xy 310.845962 -395.048994) (xy 310.85028 -395.079982)
			(xy 310.851968 -395.089276) (xy 310.861245 -395.105718) (xy 310.868314 -395.111986) (xy 310.890392 -395.13068)
			(xy 310.930166 -395.172689) (xy 310.96433 -395.219374) (xy 310.99234 -395.269992) (xy 311.013748 -395.323735)
			(xy 311.028215 -395.379748) (xy 311.035509 -395.437137) (xy 311.035954 -395.466062) (xy 311.035363 -395.499383)
			(xy 311.025701 -395.565322) (xy 311.006575 -395.629161) (xy 310.993028 -395.65961) (xy 310.988764 -395.670071)
			(xy 310.988877 -395.692635) (xy 310.998621 -395.712988) (xy 311.006998 -395.72057) (xy 311.029228 -395.739263)
			(xy 311.069292 -395.781315) (xy 311.103714 -395.828098) (xy 311.131941 -395.87886) (xy 311.15352 -395.932785)
			(xy 311.168102 -395.989006) (xy 311.175455 -396.046621) (xy 311.175908 -396.075662) (xy 311.175447 -396.104668)
			(xy 311.168136 -396.162216) (xy 311.153612 -396.21838) (xy 311.13211 -396.272258) (xy 311.103972 -396.322989)
			(xy 311.069652 -396.369758) (xy 311.029697 -396.411816) (xy 311.007506 -396.4305) (xy 311.000394 -396.436088)
			(xy 310.99125 -396.451328) (xy 310.97601 -396.534132) (xy 310.978804 -396.551404) (xy 310.983376 -396.559532)
			(xy 310.995946 -396.582721) (xy 311.013823 -396.632341) (xy 311.022926 -396.684292) (xy 311.023508 -396.710662)
			(xy 311.023439 -396.720021) (xy 311.022296 -396.738703) (xy 311.021222 -396.748) (xy 311.020206 -396.75689)
			(xy 311.024016 -396.773654) (xy 311.067958 -396.843504) (xy 311.081674 -396.853918) (xy 311.090056 -396.856712)
			(xy 311.114087 -396.865171) (xy 311.159259 -396.888726) (xy 311.200064 -396.919228) (xy 311.235442 -396.955884)
			(xy 311.264477 -396.997745) (xy 311.286415 -397.043724) (xy 311.294018 -397.06804) (xy 311.295542 -397.073882)
			(xy 311.615836 -397.627602) (xy 311.6199 -397.63192) (xy 311.636092 -397.649639) (xy 311.663518 -397.689027)
			(xy 311.684663 -397.732113) (xy 311.699039 -397.777905) (xy 311.706316 -397.825346) (xy 311.706768 -397.849344)
			(xy 311.706347 -397.874149) (xy 311.698576 -397.923148) (xy 311.683232 -397.970327) (xy 311.660694 -398.014523)
			(xy 311.631517 -398.054647) (xy 311.59642 -398.089711) (xy 311.556268 -398.11885) (xy 311.512051 -398.141346)
			(xy 311.464858 -398.156645) (xy 311.415852 -398.16437) (xy 311.391046 -398.164812) (xy 311.365653 -398.164271)
			(xy 311.315521 -398.156148) (xy 311.267337 -398.140103) (xy 311.222342 -398.116551) (xy 311.181699 -398.086099)
			(xy 311.146456 -398.049533) (xy 311.117521 -398.007796) (xy 311.095641 -397.961965) (xy 311.088024 -397.937736)
			(xy 311.0865 -397.931894) (xy 310.766206 -397.378174) (xy 310.762142 -397.373856) (xy 310.745981 -397.356124)
			(xy 310.718613 -397.316721) (xy 310.697523 -397.273631) (xy 310.683196 -397.227846) (xy 310.675962 -397.18042)
			(xy 310.675528 -397.156432) (xy 310.675609 -397.144384) (xy 310.677391 -397.120355) (xy 310.679084 -397.108426)
			(xy 310.680354 -397.099536) (xy 310.677306 -397.082518) (xy 310.635142 -397.011652) (xy 310.621934 -397.000476)
			(xy 310.613552 -396.997428) (xy 310.5918 -396.989043) (xy 310.550942 -396.966599) (xy 310.513972 -396.938204)
			(xy 310.48175 -396.904517) (xy 310.455026 -396.866322) (xy 310.43442 -396.824507) (xy 310.420413 -396.780045)
			(xy 310.41333 -396.73397) (xy 310.412892 -396.710662) (xy 310.413459 -396.684289) (xy 310.422542 -396.632331)
			(xy 310.44043 -396.58271) (xy 310.453024 -396.559532) (xy 310.457596 -396.551404) (xy 310.46039 -396.534132)
			(xy 310.44515 -396.451328) (xy 310.436006 -396.436088) (xy 310.428894 -396.4305) (xy 310.406722 -396.411795)
			(xy 310.366775 -396.369734) (xy 310.332458 -396.322965) (xy 310.30432 -396.272239) (xy 310.28281 -396.218366)
			(xy 310.268273 -396.162209) (xy 310.260943 -396.104666) (xy 310.260492 -396.075662) (xy 310.261087 -396.042341)
			(xy 310.270747 -395.976402) (xy 310.289871 -395.912563) (xy 310.303418 -395.882114) (xy 310.307645 -395.871642)
			(xy 310.307539 -395.849088) (xy 310.297814 -395.828739) (xy 310.289448 -395.821154) (xy 310.267191 -395.802491)
			(xy 310.227126 -395.760435) (xy 310.192705 -395.713647) (xy 310.164481 -395.66288) (xy 310.142907 -395.60895)
			(xy 310.128331 -395.552724) (xy 310.120986 -395.495105) (xy 310.120538 -395.466062) (xy 310.120995 -395.437136)
			(xy 310.128278 -395.379744) (xy 310.142736 -395.323728) (xy 310.164139 -395.26998) (xy 310.192146 -395.219359)
			(xy 310.226308 -395.17267) (xy 310.266083 -395.13066) (xy 310.288178 -395.111986) (xy 310.295153 -395.105641)
			(xy 310.304408 -395.089236) (xy 310.306212 -395.079982) (xy 310.31053 -395.048994) (xy 310.311437 -395.039757)
			(xy 310.307411 -395.021657) (xy 310.302656 -395.013688) (xy 310.286344 -394.987845) (xy 310.262443 -394.931607)
			(xy 310.255158 -394.901928) (xy 310.25311 -394.893762) (xy 310.244402 -394.879362) (xy 310.23814 -394.873734)
			(xy 310.215026 -394.854684) (xy 310.208192 -394.849483) (xy 310.192102 -394.84351) (xy 310.18353 -394.843)
			(xy 310.153892 -394.84202) (xy 310.095226 -394.833367) (xy 310.038169 -394.817212) (xy 309.983675 -394.793826)
			(xy 309.932656 -394.7636) (xy 309.885966 -394.727041) (xy 309.844387 -394.684759) (xy 309.808616 -394.637463)
			(xy 309.779249 -394.585944) (xy 309.756781 -394.531065) (xy 309.741585 -394.473745) (xy 309.733917 -394.414942)
			(xy 309.733442 -394.385292) (xy 309.733963 -394.354229) (xy 309.742379 -394.292675) (xy 309.750206 -394.26261)
			(xy 309.753 -394.25245) (xy 309.75046 -394.232638) (xy 309.702962 -394.150342) (xy 309.68696 -394.13815)
			(xy 309.6768 -394.13561) (xy 309.647674 -394.127668) (xy 309.591707 -394.105026) (xy 309.539201 -394.075224)
			(xy 309.491068 -394.038779) (xy 309.448143 -393.996324) (xy 309.411171 -393.948595) (xy 309.380794 -393.89642)
			(xy 309.357537 -393.840705) (xy 309.341806 -393.782417) (xy 309.333873 -393.722567) (xy 309.333392 -393.69238)
			(xy 309.333919 -393.661492) (xy 309.342224 -393.600277) (xy 309.35868 -393.540733) (xy 309.38299 -393.483941)
			(xy 309.398416 -393.457176) (xy 309.404258 -393.44727) (xy 309.406544 -393.424918) (xy 309.37327 -393.329668)
			(xy 309.357522 -393.313666) (xy 309.346854 -393.309602) (xy 309.323464 -393.300441) (xy 309.279568 -393.276017)
			(xy 309.239873 -393.245232) (xy 309.205293 -393.208795) (xy 309.176625 -393.167545) (xy 309.154529 -393.122432)
			(xy 309.139513 -393.074496) (xy 309.131924 -393.024839) (xy 309.131462 -392.999722) (xy 308.592982 -392.999722)
			(xy 308.59245 -393.026824) (xy 308.583642 -393.080307) (xy 308.575456 -393.106148) (xy 308.571646 -393.11707)
			(xy 308.574186 -393.139422) (xy 308.626764 -393.225528) (xy 308.64556 -393.23772) (xy 308.65699 -393.239498)
			(xy 308.686285 -393.244269) (xy 308.74342 -393.260348) (xy 308.797996 -393.283679) (xy 308.849098 -393.313869)
			(xy 308.895869 -393.350412) (xy 308.937522 -393.392695) (xy 308.97336 -393.440009) (xy 309.00278 -393.491558)
			(xy 309.025289 -393.546478) (xy 309.04051 -393.603848) (xy 309.048186 -393.662703) (xy 309.048658 -393.69238)
			(xy 309.048131 -393.723443) (xy 309.039719 -393.784996) (xy 309.031894 -393.815062) (xy 309.0291 -393.825222)
			(xy 309.03164 -393.845034) (xy 309.079138 -393.92733) (xy 309.09514 -393.939522) (xy 309.1053 -393.942062)
			(xy 309.134419 -393.95003) (xy 309.190384 -393.97267) (xy 309.242889 -394.002469) (xy 309.291021 -394.038911)
			(xy 309.333946 -394.081364) (xy 309.370918 -394.12909) (xy 309.401297 -394.181261) (xy 309.424555 -394.236973)
			(xy 309.440289 -394.295258) (xy 309.448225 -394.355106) (xy 309.448708 -394.385292) (xy 309.448583 -394.399427)
			(xy 309.446801 -394.427641) (xy 309.445152 -394.44168) (xy 309.444392 -394.450287) (xy 309.448031 -394.467167)
			(xy 309.452264 -394.4747) (xy 309.468012 -394.5001) (xy 309.472715 -394.507165) (xy 309.485825 -394.517931)
			(xy 309.493666 -394.521182) (xy 309.517055 -394.530346) (xy 309.56095 -394.554771) (xy 309.600644 -394.585556)
			(xy 309.635223 -394.621993) (xy 309.663891 -394.663242) (xy 309.685987 -394.708354) (xy 309.701004 -394.75629)
			(xy 309.708595 -394.805946) (xy 309.709058 -394.831062) (xy 309.70864 -394.855264) (xy 309.701565 -394.90315)
			(xy 309.687577 -394.949489) (xy 309.666975 -394.993291) (xy 309.65394 -395.013688) (xy 309.64915 -395.021643)
			(xy 309.645118 -395.039756) (xy 309.646066 -395.048994) (xy 309.650384 -395.079982) (xy 309.652071 -395.089277)
			(xy 309.661349 -395.105719) (xy 309.668418 -395.111986) (xy 309.690497 -395.130679) (xy 309.73027 -395.172688)
			(xy 309.764434 -395.219373) (xy 309.792444 -395.269991) (xy 309.813853 -395.323735) (xy 309.828319 -395.379748)
			(xy 309.835613 -395.437137) (xy 309.836058 -395.466062) (xy 309.835467 -395.499383) (xy 309.825804 -395.565322)
			(xy 309.806679 -395.629161) (xy 309.793132 -395.65961) (xy 309.788866 -395.67007) (xy 309.78898 -395.692636)
			(xy 309.798725 -395.712989) (xy 309.807102 -395.72057) (xy 309.829333 -395.739262) (xy 309.869397 -395.781315)
			(xy 309.903819 -395.828098) (xy 309.932046 -395.87886) (xy 309.953624 -395.932785) (xy 309.968206 -395.989006)
			(xy 309.975559 -396.046621) (xy 309.976012 -396.075662) (xy 309.97555 -396.104668) (xy 309.968238 -396.162216)
			(xy 309.953715 -396.218379) (xy 309.932213 -396.272258) (xy 309.904076 -396.322988) (xy 309.869755 -396.369758)
			(xy 309.829801 -396.411816) (xy 309.80761 -396.4305) (xy 309.800498 -396.436088) (xy 309.791354 -396.451328)
			(xy 309.776114 -396.534132) (xy 309.778908 -396.551404) (xy 309.78348 -396.559532) (xy 309.79605 -396.582721)
			(xy 309.813927 -396.632341) (xy 309.82303 -396.684292) (xy 309.823612 -396.710662) (xy 309.823543 -396.720021)
			(xy 309.8224 -396.738703) (xy 309.821326 -396.748) (xy 309.82031 -396.75689) (xy 309.82412 -396.773654)
			(xy 309.868062 -396.843504) (xy 309.881778 -396.853918) (xy 309.89016 -396.856712) (xy 309.914192 -396.865169)
			(xy 309.959364 -396.888725) (xy 310.000168 -396.919227) (xy 310.035547 -396.955884) (xy 310.064581 -396.997745)
			(xy 310.086519 -397.043724) (xy 310.094122 -397.06804) (xy 310.095646 -397.073882) (xy 310.41594 -397.627602)
			(xy 310.420004 -397.63192) (xy 310.436196 -397.649638) (xy 310.463622 -397.689026) (xy 310.484767 -397.732113)
			(xy 310.499143 -397.777905) (xy 310.50642 -397.825346) (xy 310.506872 -397.849344) (xy 310.506447 -397.874149)
			(xy 310.498676 -397.923148) (xy 310.483333 -397.970326) (xy 310.460795 -398.014522) (xy 310.431618 -398.054646)
			(xy 310.396522 -398.08971) (xy 310.356371 -398.118849) (xy 310.312154 -398.141345) (xy 310.264961 -398.156644)
			(xy 310.215956 -398.16437) (xy 310.19115 -398.164812) (xy 310.165757 -398.164268) (xy 310.115626 -398.156145)
			(xy 310.067441 -398.1401) (xy 310.022447 -398.116549) (xy 309.981803 -398.086097) (xy 309.94656 -398.049532)
			(xy 309.917625 -398.007795) (xy 309.895745 -397.961965) (xy 309.888128 -397.937736) (xy 309.886604 -397.931894)
			(xy 309.56631 -397.378174) (xy 309.562246 -397.373856) (xy 309.546085 -397.356123) (xy 309.518718 -397.316721)
			(xy 309.497627 -397.273631) (xy 309.4833 -397.227845) (xy 309.476066 -397.180419) (xy 309.475632 -397.156432)
			(xy 309.475713 -397.144384) (xy 309.477495 -397.120355) (xy 309.479188 -397.108426) (xy 309.480458 -397.099536)
			(xy 309.47741 -397.082518) (xy 309.435246 -397.011652) (xy 309.422038 -397.000476) (xy 309.413656 -396.997428)
			(xy 309.391905 -396.98904) (xy 309.351047 -396.966598) (xy 309.314077 -396.938203) (xy 309.281855 -396.904516)
			(xy 309.25513 -396.866321) (xy 309.234524 -396.824507) (xy 309.220517 -396.780045) (xy 309.213434 -396.73397)
			(xy 309.212996 -396.710662) (xy 309.213562 -396.684289) (xy 309.222645 -396.632331) (xy 309.240533 -396.58271)
			(xy 309.253128 -396.559532) (xy 309.2577 -396.551404) (xy 309.260494 -396.534132) (xy 309.245254 -396.451328)
			(xy 309.23611 -396.436088) (xy 309.228998 -396.4305) (xy 309.206827 -396.411794) (xy 309.16688 -396.369733)
			(xy 309.132563 -396.322965) (xy 309.104424 -396.272239) (xy 309.082914 -396.218366) (xy 309.068377 -396.162209)
			(xy 309.061047 -396.104666) (xy 309.060596 -396.075662) (xy 309.061191 -396.042341) (xy 309.070851 -395.976402)
			(xy 309.089975 -395.912563) (xy 309.103522 -395.882114) (xy 309.107747 -395.871642) (xy 309.107642 -395.849089)
			(xy 309.097918 -395.828739) (xy 309.089552 -395.821154) (xy 309.067296 -395.802491) (xy 309.027231 -395.760434)
			(xy 308.99281 -395.713647) (xy 308.964585 -395.66288) (xy 308.943012 -395.60895) (xy 308.928435 -395.552724)
			(xy 308.92109 -395.495105) (xy 308.920642 -395.466062) (xy 308.921097 -395.437136) (xy 308.928381 -395.379744)
			(xy 308.942839 -395.323727) (xy 308.964242 -395.26998) (xy 308.992249 -395.219358) (xy 309.026412 -395.17267)
			(xy 309.066187 -395.13066) (xy 309.088282 -395.111986) (xy 309.095257 -395.105642) (xy 309.104513 -395.089236)
			(xy 309.106316 -395.079982) (xy 309.110634 -395.048994) (xy 309.11154 -395.039757) (xy 309.107515 -395.021657)
			(xy 309.10276 -395.013688) (xy 309.086448 -394.987845) (xy 309.062548 -394.931607) (xy 309.055262 -394.901928)
			(xy 309.053213 -394.893762) (xy 309.044506 -394.879362) (xy 309.038244 -394.873734) (xy 309.01513 -394.854684)
			(xy 309.008237 -394.849458) (xy 308.992016 -394.84348) (xy 308.98338 -394.843) (xy 308.953744 -394.841974)
			(xy 308.89508 -394.833327) (xy 308.838023 -394.817178) (xy 308.783529 -394.793798) (xy 308.73251 -394.763577)
			(xy 308.68582 -394.727021) (xy 308.64424 -394.684743) (xy 308.608468 -394.637451) (xy 308.579101 -394.585935)
			(xy 308.556631 -394.531059) (xy 308.541435 -394.473741) (xy 308.533767 -394.414941) (xy 308.533292 -394.385292)
			(xy 308.533812 -394.354229) (xy 308.542228 -394.292675) (xy 308.550056 -394.26261) (xy 308.55285 -394.25245)
			(xy 308.55031 -394.232638) (xy 308.502812 -394.150342) (xy 308.48681 -394.13815) (xy 308.47665 -394.13561)
			(xy 308.447533 -394.127635) (xy 308.391565 -394.104999) (xy 308.339059 -394.075202) (xy 308.290925 -394.038762)
			(xy 308.247998 -393.996311) (xy 308.211025 -393.948585) (xy 308.180646 -393.896413) (xy 308.157389 -393.840701)
			(xy 308.141657 -393.782414) (xy 308.133723 -393.722566) (xy 308.133242 -393.69238) (xy 308.133715 -393.661458)
			(xy 308.141997 -393.600171) (xy 308.158463 -393.540559) (xy 308.182811 -393.48371) (xy 308.198266 -393.456922)
			(xy 308.204362 -393.44727) (xy 308.206648 -393.424918) (xy 308.17312 -393.329668) (xy 308.157372 -393.313666)
			(xy 308.146704 -393.309602) (xy 308.123357 -393.300369) (xy 308.079513 -393.275917) (xy 308.039867 -393.245119)
			(xy 308.005331 -393.208683) (xy 307.976699 -393.167447) (xy 307.954627 -393.122356) (xy 307.939624 -393.074448)
			(xy 307.932034 -393.024823) (xy 307.931566 -392.999722) (xy 307.392832 -392.999722) (xy 307.392303 -393.026824)
			(xy 307.383493 -393.080307) (xy 307.375306 -393.106148) (xy 307.371496 -393.11707) (xy 307.374036 -393.139422)
			(xy 307.426614 -393.225274) (xy 307.445664 -393.23772) (xy 307.45684 -393.239498) (xy 307.486159 -393.244198)
			(xy 307.54333 -393.260248) (xy 307.597944 -393.283559) (xy 307.649083 -393.313739) (xy 307.695889 -393.350281)
			(xy 307.737574 -393.39257) (xy 307.773438 -393.439898) (xy 307.802878 -393.491466) (xy 307.825399 -393.546411)
			(xy 307.840623 -393.603806) (xy 307.848295 -393.66269) (xy 307.848762 -393.69238) (xy 307.848235 -393.723443)
			(xy 307.839823 -393.784996) (xy 307.831998 -393.815062) (xy 307.829204 -393.825222) (xy 307.831744 -393.845034)
			(xy 307.879242 -393.92733) (xy 307.895244 -393.939522) (xy 307.905404 -393.942062) (xy 307.934504 -393.950094)
			(xy 307.990471 -393.972722) (xy 308.042977 -394.002512) (xy 308.091112 -394.038945) (xy 308.13404 -394.081389)
			(xy 308.171015 -394.129109) (xy 308.201396 -394.181275) (xy 308.224656 -394.236982) (xy 308.240391 -394.295264)
			(xy 308.248328 -394.355108) (xy 308.248812 -394.385292) (xy 308.248687 -394.399427) (xy 308.246905 -394.427641)
			(xy 308.245256 -394.44168) (xy 308.244495 -394.450287) (xy 308.248135 -394.467167) (xy 308.252368 -394.4747)
			(xy 308.268116 -394.5001) (xy 308.272837 -394.507154) (xy 308.285928 -394.517938) (xy 308.29377 -394.521182)
			(xy 308.317127 -394.530388) (xy 308.360969 -394.554848) (xy 308.400612 -394.585652) (xy 308.435145 -394.622092)
			(xy 308.463775 -394.663332) (xy 308.485845 -394.708424) (xy 308.500848 -394.756334) (xy 308.50844 -394.80596)
			(xy 308.508908 -394.831062) (xy 308.508481 -394.855264) (xy 308.501408 -394.903149) (xy 308.487422 -394.949488)
			(xy 308.466823 -394.99329) (xy 308.45379 -395.013688) (xy 308.449003 -395.021646) (xy 308.444968 -395.039756)
			(xy 308.445916 -395.048994) (xy 308.450234 -395.079982) (xy 308.451906 -395.089281) (xy 308.461193 -395.105722)
			(xy 308.468268 -395.111986) (xy 308.490357 -395.130667) (xy 308.530129 -395.172679) (xy 308.56429 -395.219367)
			(xy 308.592298 -395.269987) (xy 308.613705 -395.323732) (xy 308.62817 -395.379746) (xy 308.635463 -395.437136)
			(xy 308.635908 -395.466062) (xy 308.635321 -395.499384) (xy 308.625658 -395.565322) (xy 308.606531 -395.629161)
			(xy 308.592982 -395.65961) (xy 308.588733 -395.670074) (xy 308.588847 -395.692634) (xy 308.598581 -395.712985)
			(xy 308.606952 -395.72057) (xy 308.629172 -395.739275) (xy 308.669239 -395.781323) (xy 308.703663 -395.828104)
			(xy 308.731892 -395.878863) (xy 308.753472 -395.932787) (xy 308.768056 -395.989008) (xy 308.775409 -396.046621)
			(xy 308.775862 -396.075662) (xy 308.775381 -396.104667) (xy 308.768071 -396.162214) (xy 308.753549 -396.218376)
			(xy 308.732049 -396.272254) (xy 308.703916 -396.322985) (xy 308.669599 -396.369755) (xy 308.629649 -396.411815)
			(xy 308.60746 -396.4305) (xy 308.600348 -396.436088) (xy 308.591204 -396.451328) (xy 308.575964 -396.534132)
			(xy 308.578758 -396.551404) (xy 308.58333 -396.559532) (xy 308.595904 -396.582719) (xy 308.613779 -396.63234)
			(xy 308.62288 -396.684291) (xy 308.623462 -396.710662) (xy 308.623393 -396.720021) (xy 308.62225 -396.738703)
			(xy 308.621176 -396.748) (xy 308.62016 -396.75689) (xy 308.62397 -396.773654) (xy 308.667912 -396.843504)
			(xy 308.681628 -396.853918) (xy 308.69001 -396.856712) (xy 308.714032 -396.865196) (xy 308.759205 -396.888744)
			(xy 308.800011 -396.91924) (xy 308.835392 -396.955892) (xy 308.864429 -396.997749) (xy 308.886368 -397.043725)
			(xy 308.893972 -397.06804) (xy 308.895496 -397.073882) (xy 309.21579 -397.627602) (xy 309.219854 -397.63192)
			(xy 309.236051 -397.649621) (xy 309.263414 -397.689032) (xy 309.284497 -397.73213) (xy 309.298816 -397.777923)
			(xy 309.30604 -397.825354) (xy 309.306468 -397.849344) (xy 309.306023 -397.874135) (xy 309.29826 -397.923105)
			(xy 309.282933 -397.970259) (xy 309.260419 -398.014434) (xy 309.231273 -398.054544) (xy 309.196211 -398.089601)
			(xy 309.156096 -398.118742) (xy 309.111918 -398.14125) (xy 309.064762 -398.15657) (xy 309.015791 -398.164326)
			(xy 308.991 -398.164812) (xy 308.965606 -398.164312) (xy 308.915472 -398.156181) (xy 308.867286 -398.140129)
			(xy 308.822292 -398.116571) (xy 308.781649 -398.086114) (xy 308.746407 -398.049543) (xy 308.717473 -398.007801)
			(xy 308.695595 -397.961967) (xy 308.687978 -397.937736) (xy 308.686454 -397.931894) (xy 308.36616 -397.378174)
			(xy 308.362096 -397.373856) (xy 308.345892 -397.356148) (xy 308.318468 -397.316757) (xy 308.297325 -397.273668)
			(xy 308.282952 -397.227873) (xy 308.275678 -397.18043) (xy 308.275228 -397.156432) (xy 308.27537 -397.14438)
			(xy 308.277276 -397.12035) (xy 308.279038 -397.108426) (xy 308.280308 -397.099536) (xy 308.27726 -397.082518)
			(xy 308.235096 -397.011652) (xy 308.221888 -397.000476) (xy 308.213506 -396.997428) (xy 308.191766 -396.989013)
			(xy 308.150906 -396.966577) (xy 308.113934 -396.938187) (xy 308.08171 -396.904505) (xy 308.054984 -396.866314)
			(xy 308.034376 -396.824502) (xy 308.020368 -396.780042) (xy 308.013284 -396.733969) (xy 308.012846 -396.710662)
			(xy 308.013406 -396.684289) (xy 308.02249 -396.63233) (xy 308.040381 -396.58271) (xy 308.052978 -396.559532)
			(xy 308.05755 -396.551404) (xy 308.060344 -396.534132) (xy 308.045104 -396.451328) (xy 308.03596 -396.436088)
			(xy 308.028848 -396.4305) (xy 308.006667 -396.411807) (xy 307.966722 -396.369742) (xy 307.932407 -396.322971)
			(xy 307.90427 -396.272243) (xy 307.882762 -396.218368) (xy 307.868227 -396.16221) (xy 307.860896 -396.104666)
			(xy 307.860446 -396.075662) (xy 307.861045 -396.042341) (xy 307.870704 -395.976403) (xy 307.889826 -395.912563)
			(xy 307.903372 -395.882114) (xy 307.907614 -395.871646) (xy 307.907509 -395.849087) (xy 307.897774 -395.828736)
			(xy 307.889402 -395.821154) (xy 307.867135 -395.802503) (xy 307.827073 -395.760443) (xy 307.792654 -395.713653)
			(xy 307.764432 -395.662884) (xy 307.74286 -395.608952) (xy 307.728284 -395.552725) (xy 307.72094 -395.495105)
			(xy 307.720492 -395.466062) (xy 307.720929 -395.437135) (xy 307.728213 -395.379742) (xy 307.742674 -395.323724)
			(xy 307.764079 -395.269976) (xy 307.792089 -395.219354) (xy 307.826256 -395.172667) (xy 307.866035 -395.130659)
			(xy 307.888132 -395.111986) (xy 307.895099 -395.105634) (xy 307.90436 -395.089234) (xy 307.906166 -395.079982)
			(xy 307.910484 -395.048994) (xy 307.911382 -395.039757) (xy 307.907361 -395.021658) (xy 307.90261 -395.013688)
			(xy 307.886302 -394.987842) (xy 307.862399 -394.931607) (xy 307.855112 -394.901928) (xy 307.85305 -394.893767)
			(xy 307.844351 -394.879366) (xy 307.838094 -394.873734) (xy 307.81498 -394.854684) (xy 307.808158 -394.849465)
			(xy 307.792059 -394.843503) (xy 307.783484 -394.843) (xy 307.753848 -394.84197) (xy 307.695184 -394.833324)
			(xy 307.638127 -394.817176) (xy 307.583633 -394.793796) (xy 307.532614 -394.763575) (xy 307.485924 -394.72702)
			(xy 307.444344 -394.684742) (xy 307.408572 -394.63745) (xy 307.379205 -394.585935) (xy 307.356735 -394.531059)
			(xy 307.341539 -394.473741) (xy 307.333871 -394.414941) (xy 307.333396 -394.385292) (xy 307.333916 -394.354229)
			(xy 307.342332 -394.292675) (xy 307.35016 -394.26261) (xy 307.352954 -394.25245) (xy 307.350414 -394.232638)
			(xy 307.302916 -394.150342) (xy 307.286914 -394.13815) (xy 307.276754 -394.13561) (xy 307.247638 -394.127632)
			(xy 307.19167 -394.104997) (xy 307.139163 -394.0752) (xy 307.091029 -394.038761) (xy 307.048103 -393.99631)
			(xy 307.011129 -393.948584) (xy 306.98075 -393.896413) (xy 306.957493 -393.8407) (xy 306.941761 -393.782414)
			(xy 306.933827 -393.722566) (xy 306.933346 -393.69238) (xy 306.933865 -393.661492) (xy 306.942171 -393.600276)
			(xy 306.95863 -393.540732) (xy 306.982942 -393.48394) (xy 306.99837 -393.457176) (xy 307.004212 -393.44727)
			(xy 307.006498 -393.424918) (xy 306.973224 -393.329668) (xy 306.957476 -393.313666) (xy 306.946808 -393.309602)
			(xy 306.923429 -393.300412) (xy 306.879532 -393.275994) (xy 306.839835 -393.245215) (xy 306.805253 -393.208783)
			(xy 306.776583 -393.167537) (xy 306.754485 -393.122427) (xy 306.739468 -393.074493) (xy 306.731878 -393.024838)
			(xy 306.731416 -392.999722) (xy 306.192936 -392.999722) (xy 306.192407 -393.026824) (xy 306.183597 -393.080307)
			(xy 306.17541 -393.106148) (xy 306.1716 -393.11707) (xy 306.17414 -393.139422) (xy 306.226718 -393.225274)
			(xy 306.245768 -393.23772) (xy 306.256944 -393.239498) (xy 306.286264 -393.244195) (xy 306.343434 -393.260245)
			(xy 306.398048 -393.283556) (xy 306.449188 -393.313737) (xy 306.495993 -393.350279) (xy 306.537678 -393.392569)
			(xy 306.573542 -393.439897) (xy 306.602982 -393.491466) (xy 306.625503 -393.54641) (xy 306.640727 -393.603806)
			(xy 306.648399 -393.662689) (xy 306.648866 -393.69238) (xy 306.648339 -393.723443) (xy 306.639927 -393.784996)
			(xy 306.632102 -393.815062) (xy 306.629308 -393.825222) (xy 306.631848 -393.845034) (xy 306.679346 -393.92733)
			(xy 306.695348 -393.939522) (xy 306.705508 -393.942062) (xy 306.734596 -393.950092) (xy 306.790521 -393.972762)
			(xy 306.842985 -394.00258) (xy 306.891077 -394.03903) (xy 306.933966 -394.08148) (xy 306.970908 -394.129196)
			(xy 307.001264 -394.18135) (xy 307.024507 -394.23704) (xy 307.040234 -394.295299) (xy 307.048173 -394.35512)
			(xy 307.048662 -394.385292) (xy 307.048537 -394.399427) (xy 307.046755 -394.427641) (xy 307.045106 -394.44168)
			(xy 307.044339 -394.450287) (xy 307.047982 -394.467168) (xy 307.052218 -394.4747) (xy 307.067966 -394.5001)
			(xy 307.072684 -394.507154) (xy 307.085784 -394.517926) (xy 307.09362 -394.521182) (xy 307.116999 -394.530371)
			(xy 307.160895 -394.55479) (xy 307.200591 -394.58557) (xy 307.235172 -394.622003) (xy 307.263841 -394.663249)
			(xy 307.285939 -394.708358) (xy 307.300957 -394.756292) (xy 307.308549 -394.805946) (xy 307.309012 -394.831062)
			(xy 307.308585 -394.855264) (xy 307.301512 -394.903148) (xy 307.287526 -394.949488) (xy 307.266927 -394.99329)
			(xy 307.253894 -395.013688) (xy 307.249108 -395.021646) (xy 307.245072 -395.039756) (xy 307.24602 -395.048994)
			(xy 307.250338 -395.079982) (xy 307.252009 -395.089281) (xy 307.261297 -395.105722) (xy 307.268372 -395.111986)
			(xy 307.290462 -395.130666) (xy 307.330233 -395.172678) (xy 307.364395 -395.219367) (xy 307.392402 -395.269987)
			(xy 307.413809 -395.323732) (xy 307.428274 -395.379746) (xy 307.435567 -395.437136) (xy 307.436012 -395.466062)
			(xy 307.435425 -395.499384) (xy 307.425762 -395.565322) (xy 307.406634 -395.629161) (xy 307.393086 -395.65961)
			(xy 307.388835 -395.670074) (xy 307.388949 -395.692634) (xy 307.398685 -395.712986) (xy 307.407056 -395.72057)
			(xy 307.429277 -395.739274) (xy 307.469343 -395.781323) (xy 307.503768 -395.828103) (xy 307.531996 -395.878863)
			(xy 307.553576 -395.932787) (xy 307.56816 -395.989007) (xy 307.575513 -396.046621) (xy 307.575966 -396.075662)
			(xy 307.575484 -396.104667) (xy 307.568173 -396.162214) (xy 307.553652 -396.218376) (xy 307.532152 -396.272254)
			(xy 307.504019 -396.322984) (xy 307.469702 -396.369754) (xy 307.429753 -396.411815) (xy 307.407564 -396.4305)
			(xy 307.400452 -396.436088) (xy 307.391308 -396.451328) (xy 307.376068 -396.534132) (xy 307.378862 -396.551404)
			(xy 307.383434 -396.559532) (xy 307.396009 -396.582719) (xy 307.413883 -396.63234) (xy 307.422984 -396.684291)
			(xy 307.423566 -396.710662) (xy 307.423497 -396.720021) (xy 307.422354 -396.738703) (xy 307.42128 -396.748)
			(xy 307.420264 -396.75689) (xy 307.424074 -396.773654) (xy 307.468016 -396.843504) (xy 307.481732 -396.853918)
			(xy 307.490114 -396.856712) (xy 307.514137 -396.865194) (xy 307.55931 -396.888743) (xy 307.600116 -396.919239)
			(xy 307.635496 -396.955892) (xy 307.664533 -396.997749) (xy 307.686472 -397.043725) (xy 307.694076 -397.06804)
			(xy 307.6956 -397.073882) (xy 308.015894 -397.627602) (xy 308.019958 -397.63192) (xy 308.036156 -397.649621)
			(xy 308.063518 -397.689032) (xy 308.084601 -397.73213) (xy 308.09892 -397.777923) (xy 308.106144 -397.825354)
			(xy 308.106572 -397.849344) (xy 308.106123 -397.874135) (xy 308.09836 -397.923105) (xy 308.083034 -397.970258)
			(xy 308.06052 -398.014433) (xy 308.031374 -398.054543) (xy 307.996312 -398.0896) (xy 307.956199 -398.118741)
			(xy 307.912021 -398.141249) (xy 307.864866 -398.15657) (xy 307.815895 -398.164326) (xy 307.791104 -398.164812)
			(xy 307.76571 -398.164308) (xy 307.715576 -398.156178) (xy 307.667391 -398.140127) (xy 307.622396 -398.116569)
			(xy 307.581754 -398.086112) (xy 307.546511 -398.049542) (xy 307.517577 -398.007801) (xy 307.495699 -397.961966)
			(xy 307.488082 -397.937736) (xy 307.486558 -397.931894) (xy 307.166264 -397.378174) (xy 307.1622 -397.373856)
			(xy 307.145997 -397.356147) (xy 307.118572 -397.316757) (xy 307.09743 -397.273667) (xy 307.083056 -397.227873)
			(xy 307.075782 -397.18043) (xy 307.075332 -397.156432) (xy 307.075474 -397.14438) (xy 307.07738 -397.12035)
			(xy 307.079142 -397.108426) (xy 307.080412 -397.099536) (xy 307.077364 -397.082518) (xy 307.0352 -397.011652)
			(xy 307.021992 -397.000476) (xy 307.01361 -396.997428) (xy 306.991871 -396.989011) (xy 306.951011 -396.966575)
			(xy 306.914039 -396.938186) (xy 306.881815 -396.904504) (xy 306.855088 -396.866313) (xy 306.834481 -396.824501)
			(xy 306.820472 -396.780042) (xy 306.813388 -396.733969) (xy 306.81295 -396.710662) (xy 306.813522 -396.684289)
			(xy 306.822604 -396.632331) (xy 306.840489 -396.582711) (xy 306.853082 -396.559532) (xy 306.857654 -396.551404)
			(xy 306.860448 -396.534132) (xy 306.845208 -396.451328) (xy 306.836064 -396.436088) (xy 306.828952 -396.4305)
			(xy 306.806771 -396.411806) (xy 306.766827 -396.369741) (xy 306.732511 -396.32297) (xy 306.704375 -396.272242)
			(xy 306.682866 -396.218368) (xy 306.668331 -396.16221) (xy 306.661 -396.104666) (xy 306.66055 -396.075662)
			(xy 306.661149 -396.042341) (xy 306.670808 -395.976403) (xy 306.68993 -395.912563) (xy 306.703476 -395.882114)
			(xy 306.707716 -395.871646) (xy 306.707611 -395.849087) (xy 306.697878 -395.828736) (xy 306.689506 -395.821154)
			(xy 306.66724 -395.802502) (xy 306.627178 -395.760443) (xy 306.592759 -395.713653) (xy 306.564536 -395.662884)
			(xy 306.542964 -395.608952) (xy 306.528388 -395.552725) (xy 306.521044 -395.495105) (xy 306.520596 -395.466062)
			(xy 306.521031 -395.437135) (xy 306.528316 -395.379741) (xy 306.542776 -395.323724) (xy 306.564182 -395.269975)
			(xy 306.592192 -395.219354) (xy 306.626359 -395.172667) (xy 306.666138 -395.130659) (xy 306.688236 -395.111986)
			(xy 306.695204 -395.105634) (xy 306.704465 -395.089234) (xy 306.70627 -395.079982) (xy 306.710588 -395.048994)
			(xy 306.711486 -395.039757) (xy 306.707465 -395.021658) (xy 306.702714 -395.013688) (xy 306.686407 -394.987842)
			(xy 306.662503 -394.931607) (xy 306.655216 -394.901928) (xy 306.653153 -394.893767) (xy 306.644455 -394.879366)
			(xy 306.638198 -394.873734) (xy 306.615084 -394.854684) (xy 306.608203 -394.849439) (xy 306.591973 -394.843473)
			(xy 306.583334 -394.843) (xy 306.553696 -394.842016) (xy 306.495031 -394.833364) (xy 306.437973 -394.81721)
			(xy 306.383479 -394.793824) (xy 306.33246 -394.763599) (xy 306.28577 -394.727039) (xy 306.244192 -394.684757)
			(xy 306.20842 -394.637462) (xy 306.179054 -394.585943) (xy 306.156585 -394.531065) (xy 306.141389 -394.473744)
			(xy 306.133721 -394.414942) (xy 306.133246 -394.385292) (xy 306.133764 -394.354166) (xy 306.142173 -394.292484)
			(xy 306.15001 -394.262356) (xy 306.152804 -394.252196) (xy 306.150264 -394.232384) (xy 306.10302 -394.150342)
			(xy 306.087018 -394.13815) (xy 306.076858 -394.13561) (xy 306.047743 -394.127629) (xy 305.991775 -394.104994)
			(xy 305.939268 -394.075198) (xy 305.891134 -394.038759) (xy 305.848208 -393.996308) (xy 305.811234 -393.948583)
			(xy 305.780855 -393.896412) (xy 305.757597 -393.8407) (xy 305.741865 -393.782414) (xy 305.733932 -393.722566)
			(xy 305.73345 -393.69238) (xy 305.733969 -393.661492) (xy 305.742275 -393.600276) (xy 305.758733 -393.540732)
			(xy 305.783046 -393.48394) (xy 305.798474 -393.457176) (xy 305.804316 -393.44727) (xy 305.806602 -393.424918)
			(xy 305.773328 -393.329668) (xy 305.75758 -393.313666) (xy 305.746912 -393.309602) (xy 305.723534 -393.300409)
			(xy 305.679636 -393.275993) (xy 305.639939 -393.245214) (xy 305.605357 -393.208782) (xy 305.576687 -393.167536)
			(xy 305.554589 -393.122427) (xy 305.539572 -393.074492) (xy 305.531982 -393.024838) (xy 305.53152 -392.999722)
			(xy 304.992786 -392.999722) (xy 304.992254 -393.026824) (xy 304.983446 -393.080307) (xy 304.97526 -393.106148)
			(xy 304.97145 -393.11707) (xy 304.97399 -393.139422) (xy 305.026568 -393.225274) (xy 305.045618 -393.23772)
			(xy 305.056794 -393.239498) (xy 305.086107 -393.244234) (xy 305.143278 -393.260278) (xy 305.197892 -393.283584)
			(xy 305.249032 -393.313759) (xy 305.295838 -393.350297) (xy 305.337524 -393.392583) (xy 305.373389 -393.439907)
			(xy 305.40283 -393.491474) (xy 305.425352 -393.546415) (xy 305.440577 -393.603809) (xy 305.448249 -393.66269)
			(xy 305.448716 -393.69238) (xy 305.44819 -393.723443) (xy 305.439778 -393.784996) (xy 305.431952 -393.815062)
			(xy 305.429158 -393.825222) (xy 305.431698 -393.845034) (xy 305.479196 -393.92733) (xy 305.495198 -393.939522)
			(xy 305.505358 -393.942062) (xy 305.534469 -393.950058) (xy 305.590435 -393.972693) (xy 305.64294 -394.002488)
			(xy 305.691074 -394.038926) (xy 305.734 -394.081375) (xy 305.770973 -394.129098) (xy 305.801353 -394.181267)
			(xy 305.824612 -394.236977) (xy 305.840346 -394.295261) (xy 305.848283 -394.355107) (xy 305.848766 -394.385292)
			(xy 305.848641 -394.399427) (xy 305.846859 -394.427641) (xy 305.84521 -394.44168) (xy 305.844456 -394.450287)
			(xy 305.848092 -394.467166) (xy 305.852322 -394.4747) (xy 305.86807 -394.5001) (xy 305.872786 -394.507155)
			(xy 305.885887 -394.517927) (xy 305.893724 -394.521182) (xy 305.917104 -394.530368) (xy 305.961 -394.554788)
			(xy 306.000695 -394.585569) (xy 306.035276 -394.622002) (xy 306.063946 -394.663249) (xy 306.086044 -394.708358)
			(xy 306.101061 -394.756292) (xy 306.108653 -394.805946) (xy 306.109116 -394.831062) (xy 306.108688 -394.855264)
			(xy 306.101615 -394.903148) (xy 306.087629 -394.949488) (xy 306.067031 -394.99329) (xy 306.053998 -395.013688)
			(xy 306.049212 -395.021646) (xy 306.045176 -395.039756) (xy 306.046124 -395.048994) (xy 306.050442 -395.079982)
			(xy 306.052112 -395.089281) (xy 306.0614 -395.105722) (xy 306.068476 -395.111986) (xy 306.090567 -395.130665)
			(xy 306.130338 -395.172678) (xy 306.164499 -395.219366) (xy 306.192506 -395.269987) (xy 306.213913 -395.323732)
			(xy 306.228378 -395.379746) (xy 306.235671 -395.437136) (xy 306.236116 -395.466062) (xy 306.235528 -395.499384)
			(xy 306.225865 -395.565322) (xy 306.206738 -395.629161) (xy 306.19319 -395.65961) (xy 306.188938 -395.670074)
			(xy 306.189052 -395.692634) (xy 306.198788 -395.712986) (xy 306.20716 -395.72057) (xy 306.229382 -395.739273)
			(xy 306.269448 -395.781322) (xy 306.303872 -395.828103) (xy 306.332101 -395.878863) (xy 306.35368 -395.932787)
			(xy 306.368264 -395.989007) (xy 306.375617 -396.046621) (xy 306.37607 -396.075662) (xy 306.375587 -396.104667)
			(xy 306.368276 -396.162213) (xy 306.353755 -396.218376) (xy 306.332255 -396.272253) (xy 306.304122 -396.322984)
			(xy 306.269806 -396.369754) (xy 306.229857 -396.411815) (xy 306.207668 -396.4305) (xy 306.200556 -396.436088)
			(xy 306.191412 -396.451328) (xy 306.176172 -396.534132) (xy 306.178966 -396.551404) (xy 306.183538 -396.559532)
			(xy 306.196113 -396.582719) (xy 306.213987 -396.63234) (xy 306.223088 -396.684291) (xy 306.22367 -396.710662)
			(xy 306.223601 -396.720021) (xy 306.222458 -396.738703) (xy 306.221384 -396.748) (xy 306.220368 -396.75689)
			(xy 306.224178 -396.773654) (xy 306.26812 -396.843504) (xy 306.281836 -396.853918) (xy 306.290218 -396.856712)
			(xy 306.314319 -396.865182) (xy 306.35961 -396.88881) (xy 306.400504 -396.919423) (xy 306.435935 -396.956223)
			(xy 306.464977 -396.998247) (xy 306.486872 -397.0444) (xy 306.494434 -397.068802) (xy 306.495958 -397.074644)
			(xy 306.815744 -397.627602) (xy 306.819808 -397.63192) (xy 306.836001 -397.649637) (xy 306.863427 -397.689026)
			(xy 306.884571 -397.732113) (xy 306.898947 -397.777905) (xy 306.906224 -397.825346) (xy 306.906676 -397.849344)
			(xy 306.906247 -397.874149) (xy 306.898476 -397.923147) (xy 306.883133 -397.970325) (xy 306.860596 -398.014521)
			(xy 306.83142 -398.054645) (xy 306.796324 -398.089708) (xy 306.756173 -398.118847) (xy 306.711957 -398.141344)
			(xy 306.664764 -398.156644) (xy 306.615759 -398.164369) (xy 306.590954 -398.164812) (xy 306.565558 -398.164352)
			(xy 306.515423 -398.156214) (xy 306.467236 -398.140156) (xy 306.422242 -398.116592) (xy 306.3816 -398.086129)
			(xy 306.346358 -398.049553) (xy 306.317425 -398.007807) (xy 306.295548 -397.961968) (xy 306.287932 -397.937736)
			(xy 306.286408 -397.931894) (xy 305.96586 -397.377412) (xy 305.961796 -397.373094) (xy 305.9457 -397.355418)
			(xy 305.918449 -397.316141) (xy 305.897436 -397.273203) (xy 305.883143 -397.227586) (xy 305.875895 -397.180334)
			(xy 305.875436 -397.156432) (xy 305.875578 -397.14438) (xy 305.877484 -397.12035) (xy 305.879246 -397.108426)
			(xy 305.880516 -397.099536) (xy 305.877468 -397.082518) (xy 305.835304 -397.011652) (xy 305.822096 -397.000476)
			(xy 305.813714 -396.997428) (xy 305.791976 -396.989009) (xy 305.751116 -396.966573) (xy 305.714144 -396.938185)
			(xy 305.681919 -396.904503) (xy 305.655192 -396.866312) (xy 305.634585 -396.824501) (xy 305.620576 -396.780042)
			(xy 305.613492 -396.733969) (xy 305.613054 -396.710662) (xy 305.613626 -396.684289) (xy 305.622707 -396.632331)
			(xy 305.640593 -396.582711) (xy 305.653186 -396.559532) (xy 305.657758 -396.551404) (xy 305.660552 -396.534132)
			(xy 305.645312 -396.451328) (xy 305.636168 -396.436088) (xy 305.629056 -396.4305) (xy 305.606876 -396.411805)
			(xy 305.566931 -396.36974) (xy 305.532616 -396.32297) (xy 305.504479 -396.272242) (xy 305.482971 -396.218368)
			(xy 305.468435 -396.16221) (xy 305.461105 -396.104666) (xy 305.460654 -396.075662) (xy 305.461253 -396.042341)
			(xy 305.470912 -395.976403) (xy 305.490034 -395.912563) (xy 305.50358 -395.882114) (xy 305.507819 -395.871645)
			(xy 305.507714 -395.849087) (xy 305.497981 -395.828737) (xy 305.48961 -395.821154) (xy 305.467345 -395.802501)
			(xy 305.427282 -395.760442) (xy 305.392863 -395.713652) (xy 305.36464 -395.662883) (xy 305.343068 -395.608952)
			(xy 305.328492 -395.552725) (xy 305.321148 -395.495105) (xy 305.3207 -395.466062) (xy 305.321134 -395.437135)
			(xy 305.328418 -395.379741) (xy 305.342879 -395.323723) (xy 305.364285 -395.269975) (xy 305.392295 -395.219354)
			(xy 305.426463 -395.172667) (xy 305.466242 -395.130658) (xy 305.48834 -395.111986) (xy 305.495308 -395.105635)
			(xy 305.504569 -395.089234) (xy 305.506374 -395.079982) (xy 305.510692 -395.048994) (xy 305.511589 -395.039757)
			(xy 305.507568 -395.021658) (xy 305.502818 -395.013688) (xy 305.486511 -394.987842) (xy 305.462607 -394.931607)
			(xy 305.45532 -394.901928) (xy 305.453256 -394.893768) (xy 305.444558 -394.879366) (xy 305.438302 -394.873734)
			(xy 305.415188 -394.854684) (xy 305.408306 -394.849441) (xy 305.392077 -394.843474) (xy 305.383438 -394.843)
			(xy 305.3538 -394.842013) (xy 305.295135 -394.833361) (xy 305.238078 -394.817207) (xy 305.183583 -394.793822)
			(xy 305.132564 -394.763597) (xy 305.085875 -394.727037) (xy 305.044296 -394.684756) (xy 305.008524 -394.637461)
			(xy 304.979158 -394.585943) (xy 304.956689 -394.531064) (xy 304.941493 -394.473744) (xy 304.933825 -394.414942)
			(xy 304.93335 -394.385292) (xy 304.933871 -394.354229) (xy 304.942287 -394.292675) (xy 304.950114 -394.26261)
			(xy 304.952908 -394.25245) (xy 304.950368 -394.232638) (xy 304.90287 -394.150342) (xy 304.886868 -394.13815)
			(xy 304.876708 -394.13561) (xy 304.847583 -394.127662) (xy 304.791616 -394.105021) (xy 304.73911 -394.07522)
			(xy 304.690977 -394.038776) (xy 304.648052 -393.996322) (xy 304.61108 -393.948593) (xy 304.580702 -393.896419)
			(xy 304.557446 -393.840705) (xy 304.541714 -393.782417) (xy 304.533781 -393.722567) (xy 304.5333 -393.69238)
			(xy 304.533826 -393.661492) (xy 304.542131 -393.600277) (xy 304.558588 -393.540733) (xy 304.582898 -393.483941)
			(xy 304.598324 -393.457176) (xy 304.604166 -393.44727) (xy 304.606452 -393.424918) (xy 304.573178 -393.329668)
			(xy 304.55743 -393.313666) (xy 304.546762 -393.309602) (xy 304.523373 -393.300436) (xy 304.479477 -393.276013)
			(xy 304.439782 -393.245229) (xy 304.405202 -393.208793) (xy 304.376534 -393.167544) (xy 304.354437 -393.122432)
			(xy 304.339421 -393.074495) (xy 304.331832 -393.024839) (xy 304.33137 -392.999722) (xy 303.79289 -392.999722)
			(xy 303.792358 -393.026824) (xy 303.78355 -393.080306) (xy 303.775364 -393.106148) (xy 303.771554 -393.11707)
			(xy 303.774094 -393.139422) (xy 303.826672 -393.225274) (xy 303.845722 -393.23772) (xy 303.856898 -393.239498)
			(xy 303.886212 -393.244231) (xy 303.943382 -393.260276) (xy 303.997996 -393.283582) (xy 304.049136 -393.313757)
			(xy 304.095942 -393.350296) (xy 304.137628 -393.392582) (xy 304.173493 -393.439906) (xy 304.202934 -393.491473)
			(xy 304.225456 -393.546415) (xy 304.240681 -393.603809) (xy 304.248353 -393.66269) (xy 304.24882 -393.69238)
			(xy 304.248294 -393.723443) (xy 304.239882 -393.784996) (xy 304.232056 -393.815062) (xy 304.229262 -393.825222)
			(xy 304.231802 -393.845034) (xy 304.2793 -393.92733) (xy 304.295302 -393.939522) (xy 304.305462 -393.942062)
			(xy 304.334573 -393.950055) (xy 304.39054 -393.97269) (xy 304.443045 -394.002486) (xy 304.491178 -394.038924)
			(xy 304.534104 -394.081374) (xy 304.571078 -394.129097) (xy 304.601457 -394.181267) (xy 304.624716 -394.236977)
			(xy 304.64045 -394.29526) (xy 304.648387 -394.355107) (xy 304.64887 -394.385292) (xy 304.648744 -394.399427)
			(xy 304.646963 -394.427641) (xy 304.645314 -394.44168) (xy 304.644559 -394.450287) (xy 304.648196 -394.467166)
			(xy 304.652426 -394.4747) (xy 304.668174 -394.5001) (xy 304.672876 -394.507168) (xy 304.68598 -394.517945)
			(xy 304.693828 -394.521182) (xy 304.717176 -394.530411) (xy 304.761019 -394.554866) (xy 304.800663 -394.585665)
			(xy 304.835198 -394.622102) (xy 304.86383 -394.663339) (xy 304.885901 -394.708429) (xy 304.900905 -394.756336)
			(xy 304.908497 -394.805961) (xy 304.908966 -394.831062) (xy 304.908546 -394.855264) (xy 304.901472 -394.903149)
			(xy 304.887484 -394.949489) (xy 304.866882 -394.993291) (xy 304.853848 -395.013688) (xy 304.849058 -395.021644)
			(xy 304.845026 -395.039756) (xy 304.845974 -395.048994) (xy 304.850292 -395.079982) (xy 304.851976 -395.089277)
			(xy 304.861256 -395.105719) (xy 304.868326 -395.111986) (xy 304.890406 -395.130677) (xy 304.93018 -395.172687)
			(xy 304.964343 -395.219372) (xy 304.992352 -395.269991) (xy 305.013761 -395.323735) (xy 305.028227 -395.379747)
			(xy 305.035521 -395.437137) (xy 305.035966 -395.466062) (xy 305.035374 -395.499383) (xy 305.025712 -395.565322)
			(xy 305.006587 -395.629161) (xy 304.99304 -395.65961) (xy 304.988772 -395.67007) (xy 304.988885 -395.692636)
			(xy 304.998632 -395.712989) (xy 305.00701 -395.72057) (xy 305.029242 -395.73926) (xy 305.069306 -395.781313)
			(xy 305.103728 -395.828097) (xy 305.131954 -395.878859) (xy 305.153532 -395.932784) (xy 305.168115 -395.989006)
			(xy 305.175467 -396.046621) (xy 305.17592 -396.075662) (xy 305.175455 -396.104667) (xy 305.168143 -396.162216)
			(xy 305.15362 -396.218379) (xy 305.132118 -396.272257) (xy 305.103982 -396.322988) (xy 305.069662 -396.369757)
			(xy 305.029709 -396.411816) (xy 305.007518 -396.4305) (xy 305.000406 -396.436088) (xy 304.991262 -396.451328)
			(xy 304.976022 -396.534132) (xy 304.978816 -396.551404) (xy 304.983388 -396.559532) (xy 304.995959 -396.582721)
			(xy 305.013836 -396.632341) (xy 305.022938 -396.684292) (xy 305.02352 -396.710662) (xy 305.023451 -396.720021)
			(xy 305.022308 -396.738703) (xy 305.021234 -396.748) (xy 305.020218 -396.75689) (xy 305.024028 -396.773654)
			(xy 305.06797 -396.843504) (xy 305.081686 -396.853918) (xy 305.090068 -396.856712) (xy 305.114082 -396.865218)
			(xy 305.159256 -396.888761) (xy 305.200064 -396.919252) (xy 305.235446 -396.9559) (xy 305.264484 -396.997753)
			(xy 305.286426 -397.043726) (xy 305.29403 -397.06804) (xy 305.295554 -397.073882) (xy 305.615848 -397.627602)
			(xy 305.619912 -397.63192) (xy 305.636106 -397.649637) (xy 305.663531 -397.689025) (xy 305.684675 -397.732113)
			(xy 305.699052 -397.777905) (xy 305.706328 -397.825346) (xy 305.70678 -397.849344) (xy 305.706347 -397.874149)
			(xy 305.698576 -397.923146) (xy 305.683233 -397.970324) (xy 305.660696 -398.014519) (xy 305.631521 -398.054643)
			(xy 305.596425 -398.089707) (xy 305.556275 -398.118846) (xy 305.512059 -398.141343) (xy 305.464868 -398.156643)
			(xy 305.415863 -398.164369) (xy 305.391058 -398.164812) (xy 305.365662 -398.164348) (xy 305.315527 -398.156211)
			(xy 305.267341 -398.140154) (xy 305.222346 -398.11659) (xy 305.181704 -398.086127) (xy 305.146462 -398.049552)
			(xy 305.117529 -398.007806) (xy 305.095652 -397.961968) (xy 305.088036 -397.937736) (xy 305.086512 -397.931894)
			(xy 304.766218 -397.378174) (xy 304.762154 -397.373856) (xy 304.745995 -397.356122) (xy 304.718626 -397.31672)
			(xy 304.697536 -397.27363) (xy 304.683208 -397.227845) (xy 304.675974 -397.180419) (xy 304.67554 -397.156432)
			(xy 304.675621 -397.144384) (xy 304.677403 -397.120355) (xy 304.679096 -397.108426) (xy 304.680366 -397.099536)
			(xy 304.677318 -397.082518) (xy 304.635154 -397.011652) (xy 304.621946 -397.000476) (xy 304.613564 -396.997428)
			(xy 304.591815 -396.989036) (xy 304.550957 -396.966594) (xy 304.513986 -396.9382) (xy 304.481764 -396.904514)
			(xy 304.455039 -396.86632) (xy 304.434433 -396.824506) (xy 304.420425 -396.780044) (xy 304.413342 -396.73397)
			(xy 304.412904 -396.710662) (xy 304.413469 -396.684289) (xy 304.422552 -396.63233) (xy 304.440441 -396.58271)
			(xy 304.453036 -396.559532) (xy 304.457608 -396.551404) (xy 304.460402 -396.534132) (xy 304.445162 -396.451328)
			(xy 304.436018 -396.436088) (xy 304.428906 -396.4305) (xy 304.406737 -396.411792) (xy 304.366789 -396.369731)
			(xy 304.332471 -396.322964) (xy 304.304332 -396.272238) (xy 304.282822 -396.218366) (xy 304.268286 -396.162209)
			(xy 304.260955 -396.104666) (xy 304.260504 -396.075662) (xy 304.261107 -396.042341) (xy 304.270765 -395.976403)
			(xy 304.289886 -395.912564) (xy 304.30343 -395.882114) (xy 304.307653 -395.871641) (xy 304.307547 -395.849089)
			(xy 304.297824 -395.82874) (xy 304.28946 -395.821154) (xy 304.267205 -395.802489) (xy 304.22714 -395.760433)
			(xy 304.192719 -395.713646) (xy 304.164494 -395.66288) (xy 304.14292 -395.60895) (xy 304.128343 -395.552723)
			(xy 304.120998 -395.495105) (xy 304.12055 -395.466062) (xy 304.121002 -395.437136) (xy 304.128286 -395.379743)
			(xy 304.142745 -395.323727) (xy 304.164148 -395.269979) (xy 304.192155 -395.219358) (xy 304.226319 -395.17267)
			(xy 304.266094 -395.13066) (xy 304.28819 -395.111986) (xy 304.295167 -395.105643) (xy 304.304421 -395.089236)
			(xy 304.306224 -395.079982) (xy 304.310542 -395.048994) (xy 304.311447 -395.039757) (xy 304.307422 -395.021657)
			(xy 304.302668 -395.013688) (xy 304.286357 -394.987844) (xy 304.262456 -394.931607) (xy 304.25517 -394.901928)
			(xy 304.253119 -394.893763) (xy 304.244413 -394.879363) (xy 304.238152 -394.873734) (xy 304.215038 -394.854684)
			(xy 304.208201 -394.849488) (xy 304.192114 -394.843512) (xy 304.183542 -394.843) (xy 304.153905 -394.842009)
			(xy 304.095239 -394.833357) (xy 304.038182 -394.817204) (xy 303.983688 -394.793819) (xy 303.932669 -394.763595)
			(xy 303.885979 -394.727036) (xy 303.8444 -394.684755) (xy 303.808628 -394.63746) (xy 303.779262 -394.585942)
			(xy 303.756793 -394.531064) (xy 303.741597 -394.473744) (xy 303.733929 -394.414942) (xy 303.733454 -394.385292)
			(xy 303.733975 -394.354229) (xy 303.742391 -394.292675) (xy 303.750218 -394.26261) (xy 303.753012 -394.25245)
			(xy 303.750472 -394.232638) (xy 303.702974 -394.150342) (xy 303.686972 -394.13815) (xy 303.676812 -394.13561)
			(xy 303.665091 -394.132463) (xy 303.641965 -394.125093) (xy 303.630584 -394.120878) (xy 303.618138 -394.116306)
			(xy 303.59223 -394.120116) (xy 303.502822 -394.188696) (xy 303.492408 -394.212826) (xy 303.493678 -394.22578)
			(xy 303.495202 -394.25753) (xy 303.494814 -394.281206) (xy 303.488083 -394.328077) (xy 303.474719 -394.373503)
			(xy 303.46523 -394.395198) (xy 303.460912 -394.404596) (xy 303.46015 -394.424662) (xy 303.492408 -394.511022)
			(xy 303.506124 -394.525754) (xy 303.515522 -394.530072) (xy 303.539884 -394.541776) (xy 303.584756 -394.571899)
			(xy 303.624135 -394.608914) (xy 303.656975 -394.651837) (xy 303.682402 -394.699526) (xy 303.699741 -394.750714)
			(xy 303.70853 -394.80404) (xy 303.70907 -394.831062) (xy 303.70865 -394.855264) (xy 303.701576 -394.903149)
			(xy 303.687588 -394.949489) (xy 303.666986 -394.993291) (xy 303.653952 -395.013688) (xy 303.649163 -395.021644)
			(xy 303.64513 -395.039756) (xy 303.646078 -395.048994) (xy 303.650396 -395.079982) (xy 303.652079 -395.089278)
			(xy 303.661359 -395.105719) (xy 303.66843 -395.111986) (xy 303.690511 -395.130676) (xy 303.730284 -395.172686)
			(xy 303.764448 -395.219372) (xy 303.792457 -395.26999) (xy 303.813865 -395.323734) (xy 303.828331 -395.379747)
			(xy 303.835625 -395.437137) (xy 303.83607 -395.466062) (xy 303.835478 -395.499383) (xy 303.825816 -395.565322)
			(xy 303.806691 -395.629161) (xy 303.793144 -395.65961) (xy 303.788874 -395.670069) (xy 303.788988 -395.692636)
			(xy 303.798735 -395.712989) (xy 303.807114 -395.72057) (xy 303.829347 -395.739259) (xy 303.869411 -395.781313)
			(xy 303.903832 -395.828096) (xy 303.932059 -395.878859) (xy 303.953636 -395.932784) (xy 303.968219 -395.989006)
			(xy 303.975571 -396.046621) (xy 303.976024 -396.075662) (xy 303.975557 -396.104667) (xy 303.968246 -396.162215)
			(xy 303.953723 -396.218379) (xy 303.932221 -396.272257) (xy 303.904085 -396.322988) (xy 303.869766 -396.369757)
			(xy 303.829812 -396.411816) (xy 303.807622 -396.4305) (xy 303.80051 -396.436088) (xy 303.791366 -396.451328)
			(xy 303.776126 -396.534132) (xy 303.77892 -396.551404) (xy 303.783492 -396.559532) (xy 303.796063 -396.582721)
			(xy 303.81394 -396.632341) (xy 303.823042 -396.684292) (xy 303.823624 -396.710662) (xy 303.823555 -396.720021)
			(xy 303.822412 -396.738703) (xy 303.821338 -396.748) (xy 303.820322 -396.75689) (xy 303.824132 -396.773654)
			(xy 303.868074 -396.843504) (xy 303.88179 -396.853918) (xy 303.890172 -396.856712) (xy 303.914187 -396.865216)
			(xy 303.959361 -396.88876) (xy 304.000168 -396.919251) (xy 304.03555 -396.955899) (xy 304.064589 -396.997753)
			(xy 304.08653 -397.043726) (xy 304.094134 -397.06804) (xy 304.095658 -397.073882) (xy 304.415952 -397.627602)
			(xy 304.420016 -397.63192) (xy 304.43621 -397.649636) (xy 304.463635 -397.689025) (xy 304.48478 -397.732113)
			(xy 304.499156 -397.777905) (xy 304.506432 -397.825346) (xy 304.506884 -397.849344) (xy 304.506447 -397.874149)
			(xy 304.498676 -397.923146) (xy 304.483334 -397.970323) (xy 304.460797 -398.014518) (xy 304.431622 -398.054642)
			(xy 304.396527 -398.089705) (xy 304.356377 -398.118845) (xy 304.312162 -398.141342) (xy 304.264971 -398.156642)
			(xy 304.215967 -398.164369) (xy 304.191162 -398.164812) (xy 304.165766 -398.164345) (xy 304.115631 -398.156208)
			(xy 304.067445 -398.140151) (xy 304.022451 -398.116588) (xy 303.981808 -398.086126) (xy 303.946566 -398.049551)
			(xy 303.917633 -398.007806) (xy 303.895756 -397.961968) (xy 303.88814 -397.937736) (xy 303.886616 -397.931894)
			(xy 303.566322 -397.378174) (xy 303.562258 -397.373856) (xy 303.546099 -397.356121) (xy 303.518731 -397.31672)
			(xy 303.49764 -397.27363) (xy 303.483312 -397.227845) (xy 303.476078 -397.180419) (xy 303.475644 -397.156432)
			(xy 303.475725 -397.144384) (xy 303.477507 -397.120355) (xy 303.4792 -397.108426) (xy 303.48047 -397.099536)
			(xy 303.477422 -397.082518) (xy 303.435258 -397.011652) (xy 303.42205 -397.000476) (xy 303.413668 -396.997428)
			(xy 303.39192 -396.989034) (xy 303.351061 -396.966593) (xy 303.314091 -396.938199) (xy 303.281868 -396.904514)
			(xy 303.255143 -396.866319) (xy 303.234537 -396.824506) (xy 303.220529 -396.780044) (xy 303.213446 -396.73397)
			(xy 303.213008 -396.710662) (xy 303.213573 -396.684289) (xy 303.222656 -396.63233) (xy 303.240545 -396.58271)
			(xy 303.25314 -396.559532) (xy 303.257712 -396.551404) (xy 303.260506 -396.534132) (xy 303.245266 -396.451328)
			(xy 303.236122 -396.436088) (xy 303.22901 -396.4305) (xy 303.206841 -396.411791) (xy 303.166894 -396.369731)
			(xy 303.132576 -396.322963) (xy 303.104437 -396.272238) (xy 303.082927 -396.218365) (xy 303.06839 -396.162209)
			(xy 303.061059 -396.104666) (xy 303.060608 -396.075662) (xy 303.061211 -396.042341) (xy 303.070869 -395.976403)
			(xy 303.089989 -395.912564) (xy 303.103534 -395.882114) (xy 303.107755 -395.871641) (xy 303.10765 -395.849089)
			(xy 303.097928 -395.82874) (xy 303.089564 -395.821154) (xy 303.067289 -395.802512) (xy 303.027229 -395.76045)
			(xy 302.992812 -395.713658) (xy 302.964591 -395.662887) (xy 302.94302 -395.608954) (xy 302.928446 -395.552726)
			(xy 302.921102 -395.495105) (xy 302.920654 -395.466062) (xy 302.921105 -395.437136) (xy 302.928388 -395.379743)
			(xy 302.942847 -395.323726) (xy 302.964251 -395.269979) (xy 302.992258 -395.219357) (xy 303.026422 -395.172669)
			(xy 303.066198 -395.13066) (xy 303.088294 -395.111986) (xy 303.095271 -395.105644) (xy 303.104525 -395.089236)
			(xy 303.106328 -395.079982) (xy 303.110646 -395.048994) (xy 303.11155 -395.039757) (xy 303.107526 -395.021658)
			(xy 303.102772 -395.013688) (xy 303.089781 -394.993267) (xy 303.069202 -394.949464) (xy 303.055216 -394.903133)
			(xy 303.048121 -394.85526) (xy 303.047654 -394.831062) (xy 303.048034 -394.807386) (xy 303.054768 -394.760515)
			(xy 303.068135 -394.715088) (xy 303.077626 -394.693394) (xy 303.081944 -394.683996) (xy 303.082706 -394.66393)
			(xy 303.050448 -394.57757) (xy 303.036732 -394.562838) (xy 303.027334 -394.55852) (xy 303.002958 -394.546843)
			(xy 302.958089 -394.516713) (xy 302.918712 -394.479693) (xy 302.885874 -394.436765) (xy 302.860449 -394.389072)
			(xy 302.843112 -394.337881) (xy 302.834325 -394.284553) (xy 302.833786 -394.25753) (xy 301.346739 -394.25753)
			(xy 301.317321 -394.294288) (xy 301.295308 -394.31595) (xy 301.286672 -394.324332) (xy 301.278544 -394.346684)
			(xy 301.290482 -394.451078) (xy 301.303436 -394.47089) (xy 301.31385 -394.47724) (xy 301.339186 -394.492753)
			(xy 301.38604 -394.529278) (xy 301.427772 -394.571559) (xy 301.463681 -394.618886) (xy 301.493162 -394.670463)
			(xy 301.515721 -394.725421) (xy 301.530976 -394.782837) (xy 301.538671 -394.841744) (xy 301.539148 -394.871448)
			(xy 301.538676 -394.902107) (xy 301.530484 -394.962875) (xy 301.514253 -395.022006) (xy 301.490274 -395.078441)
			(xy 301.458977 -395.131169) (xy 301.42092 -395.179248) (xy 301.399194 -395.200886) (xy 301.391457 -395.209199)
			(xy 301.38346 -395.23042) (xy 301.385367 -395.253017) (xy 301.390558 -395.263116) (xy 301.404693 -395.288586)
			(xy 301.424764 -395.343264) (xy 301.434928 -395.400617) (xy 301.435516 -395.42974) (xy 301.435006 -395.455727)
			(xy 301.426876 -395.507062) (xy 301.410815 -395.556492) (xy 301.387219 -395.602802) (xy 301.356669 -395.64485)
			(xy 301.319918 -395.681601) (xy 301.27787 -395.712151) (xy 301.23156 -395.735747) (xy 301.18213 -395.751808)
			(xy 301.130795 -395.759938) (xy 301.078821 -395.759938) (xy 301.027486 -395.751808) (xy 300.978056 -395.735747)
			(xy 300.931746 -395.712151) (xy 300.889698 -395.681601) (xy 300.852947 -395.64485) (xy 300.822397 -395.602802)
			(xy 300.798801 -395.556492) (xy 300.78274 -395.507062) (xy 300.77461 -395.455727) (xy 300.7741 -395.42974)
			(xy 300.77452 -395.405227) (xy 300.781705 -395.35673) (xy 300.795981 -395.309829) (xy 300.806104 -395.2875)
			(xy 300.810481 -395.277032) (xy 300.810527 -395.254371) (xy 300.8008 -395.233903) (xy 300.792388 -395.226286)
			(xy 300.770175 -395.207612) (xy 300.730164 -395.165578) (xy 300.695791 -395.118822) (xy 300.667607 -395.068093)
			(xy 300.646065 -395.014208) (xy 300.631511 -394.958031) (xy 300.624178 -394.900464) (xy 300.623732 -394.871448)
			(xy 300.624223 -394.840568) (xy 300.632541 -394.779369) (xy 300.649018 -394.719847) (xy 300.673355 -394.663083)
			(xy 300.705109 -394.610111) (xy 300.743703 -394.561893) (xy 300.765718 -394.540232) (xy 300.774354 -394.53185)
			(xy 300.782482 -394.509498) (xy 300.770544 -394.405104) (xy 300.75759 -394.385292) (xy 300.747176 -394.378942)
			(xy 300.723786 -394.364728) (xy 300.680277 -394.331521) (xy 300.641044 -394.293354) (xy 300.60665 -394.250776)
			(xy 300.577587 -394.204395) (xy 300.565566 -394.179806) (xy 300.55947 -394.167106) (xy 300.53661 -394.151612)
			(xy 300.41977 -394.144246) (xy 300.395386 -394.156692) (xy 300.387766 -394.16863) (xy 300.37268 -394.191512)
			(xy 300.336989 -394.233104) (xy 300.295713 -394.269161) (xy 300.249702 -394.29894) (xy 300.199902 -394.321827)
			(xy 300.14734 -394.337352) (xy 300.093097 -394.345194) (xy 300.065694 -394.345668) (xy 300.03844 -394.345262)
			(xy 299.984487 -394.337504) (xy 299.932188 -394.322146) (xy 299.882606 -394.299503) (xy 299.836752 -394.270033)
			(xy 299.795558 -394.234338) (xy 299.759863 -394.193143) (xy 299.730395 -394.147288) (xy 299.707751 -394.097706)
			(xy 299.692395 -394.045407) (xy 299.684638 -393.991454) (xy 295.527364 -393.991454) (xy 295.527476 -393.99845)
			(xy 295.526974 -394.030411) (xy 295.518963 -394.093829) (xy 295.503066 -394.155743) (xy 295.479534 -394.215176)
			(xy 295.44874 -394.271191) (xy 295.411167 -394.322906) (xy 295.36741 -394.369503) (xy 295.318157 -394.410248)
			(xy 295.264186 -394.444499) (xy 295.206347 -394.471716) (xy 295.145554 -394.491469) (xy 295.082764 -394.503447)
			(xy 295.018968 -394.507461) (xy 294.955172 -394.503447) (xy 294.892382 -394.491469) (xy 294.831589 -394.471716)
			(xy 294.77375 -394.444499) (xy 294.719779 -394.410248) (xy 294.670526 -394.369503) (xy 294.626769 -394.322906)
			(xy 294.589196 -394.271191) (xy 294.558402 -394.215176) (xy 294.53487 -394.155743) (xy 294.518973 -394.093829)
			(xy 294.510962 -394.030411) (xy 294.51046 -393.99845) (xy 284.61758 -393.99845) (xy 284.624017 -394.042192)
			(xy 284.624526 -394.070078) (xy 284.624017 -394.097964) (xy 284.615897 -394.15314) (xy 284.599829 -394.206547)
			(xy 284.576157 -394.257044) (xy 284.545384 -394.303557) (xy 284.508167 -394.345094) (xy 284.465299 -394.380769)
			(xy 284.417693 -394.409823) (xy 284.366364 -394.431635) (xy 284.312407 -394.445741) (xy 284.25697 -394.451841)
			(xy 284.201236 -394.449804) (xy 284.146393 -394.439674) (xy 284.093609 -394.421667) (xy 284.044009 -394.396166)
			(xy 283.998651 -394.363715) (xy 283.958502 -394.325006) (xy 283.924416 -394.280863) (xy 283.89712 -394.232228)
			(xy 283.877197 -394.180137) (xy 283.865071 -394.1257) (xy 283.861 -394.070078) (xy 280.876248 -394.070078)
			(xy 280.876248 -395.019784) (xy 280.881582 -395.025118) (xy 280.881582 -395.343083) (xy 283.83458 -395.343083)
			(xy 283.83458 -395.279161) (xy 283.842591 -395.215743) (xy 283.858488 -395.153829) (xy 283.88202 -395.094396)
			(xy 283.912814 -395.038381) (xy 283.950387 -394.986666) (xy 283.994144 -394.940069) (xy 284.043397 -394.899324)
			(xy 284.097368 -394.865073) (xy 284.155207 -394.837856) (xy 284.216 -394.818103) (xy 284.27879 -394.806125)
			(xy 284.342586 -394.802112) (xy 284.406382 -394.806125) (xy 284.469172 -394.818103) (xy 284.529965 -394.837856)
			(xy 284.587804 -394.865073) (xy 284.641775 -394.899324) (xy 284.691028 -394.940069) (xy 284.734785 -394.986666)
			(xy 284.772358 -395.038381) (xy 284.803152 -395.094396) (xy 284.826684 -395.153829) (xy 284.842581 -395.215743)
			(xy 284.847218 -395.252448) (xy 287.789874 -395.252448) (xy 287.79034 -395.22093) (xy 287.798144 -395.158379)
			(xy 287.813612 -395.097271) (xy 287.836509 -395.038541) (xy 287.866484 -394.983088) (xy 287.903077 -394.931761)
			(xy 287.945729 -394.885346) (xy 287.969452 -394.86459) (xy 287.976269 -394.858256) (xy 287.985262 -394.841985)
			(xy 287.986978 -394.83284) (xy 287.991042 -394.802106) (xy 287.991897 -394.792994) (xy 287.987874 -394.775156)
			(xy 287.983168 -394.767308) (xy 287.968105 -394.74373) (xy 287.944271 -394.693112) (xy 287.928089 -394.639555)
			(xy 287.919908 -394.584208) (xy 287.919414 -394.556234) (xy 287.9199 -394.528983) (xy 287.927656 -394.475035)
			(xy 287.943011 -394.42274) (xy 287.965653 -394.373163) (xy 287.995119 -394.327313) (xy 288.03081 -394.286122)
			(xy 288.072001 -394.250431) (xy 288.117851 -394.220965) (xy 288.167428 -394.198323) (xy 288.219723 -394.182968)
			(xy 288.273671 -394.175212) (xy 288.328173 -394.175212) (xy 288.382121 -394.182968) (xy 288.434416 -394.198323)
			(xy 288.483993 -394.220965) (xy 288.529843 -394.250431) (xy 288.571034 -394.286122) (xy 288.606725 -394.327313)
			(xy 288.636191 -394.373163) (xy 288.658833 -394.42274) (xy 288.674188 -394.475035) (xy 288.681944 -394.528983)
			(xy 288.68243 -394.556234) (xy 288.681913 -394.584552) (xy 288.673541 -394.640567) (xy 288.656972 -394.694726)
			(xy 288.632571 -394.745836) (xy 288.617152 -394.769594) (xy 288.612388 -394.777426) (xy 288.608218 -394.795261)
			(xy 288.609024 -394.804392) (xy 288.612834 -394.835126) (xy 288.614453 -394.844318) (xy 288.623311 -394.860731)
			(xy 288.630106 -394.86713) (xy 288.653471 -394.88788) (xy 288.695485 -394.934138) (xy 288.731513 -394.985196)
			(xy 288.761011 -395.040285) (xy 288.783535 -395.098575) (xy 288.798744 -395.159185) (xy 288.80641 -395.221203)
			(xy 288.80689 -395.252448) (xy 288.806792 -395.258657) (xy 292.070421 -395.258657) (xy 292.070421 -395.204143)
			(xy 292.07818 -395.150184) (xy 292.093539 -395.097879) (xy 292.116186 -395.048292) (xy 292.14566 -395.002433)
			(xy 292.181361 -394.961235) (xy 292.222562 -394.925538) (xy 292.268423 -394.896069) (xy 292.318012 -394.873426)
			(xy 292.370319 -394.858072) (xy 292.424279 -394.850318) (xy 292.451536 -394.849858) (xy 292.480512 -394.850422)
			(xy 292.537797 -394.859202) (xy 292.593091 -394.876553) (xy 292.645122 -394.902075) (xy 292.669214 -394.918184)
			(xy 292.677342 -394.923772) (xy 292.69563 -394.92809) (xy 292.783514 -394.915644) (xy 292.800024 -394.906246)
			(xy 292.80612 -394.898626) (xy 292.826876 -394.873816) (xy 292.873641 -394.829124) (xy 292.925693 -394.790721)
			(xy 292.982194 -394.759226) (xy 293.042232 -394.735147) (xy 293.104837 -394.718873) (xy 293.169001 -394.710666)
			(xy 293.201344 -394.710158) (xy 293.230878 -394.710582) (xy 293.289552 -394.717396) (xy 293.347041 -394.730963)
			(xy 293.402572 -394.751098) (xy 293.455395 -394.777532) (xy 293.5048 -394.809908) (xy 293.527734 -394.828522)
			(xy 293.534635 -394.833887) (xy 293.551009 -394.839977) (xy 293.559738 -394.84046) (xy 293.58971 -394.840714)
			(xy 293.598524 -394.840409) (xy 293.615148 -394.834553) (xy 293.622222 -394.829284) (xy 293.649509 -394.807843)
			(xy 293.708825 -394.771823) (xy 293.772489 -394.744207) (xy 293.839319 -394.725509) (xy 293.908072 -394.716078)
			(xy 293.94277 -394.715492) (xy 293.973501 -394.715966) (xy 294.034517 -394.723371) (xy 294.094194 -394.738077)
			(xy 294.151664 -394.75987) (xy 294.206088 -394.788431) (xy 294.256672 -394.823344) (xy 294.302679 -394.8641)
			(xy 294.343438 -394.910104) (xy 294.378354 -394.960686) (xy 294.406918 -395.015109) (xy 294.428714 -395.072577)
			(xy 294.443424 -395.132254) (xy 294.450832 -395.193269) (xy 294.451278 -395.224) (xy 294.450836 -395.254943)
			(xy 294.443347 -395.316375) (xy 294.428457 -395.376444) (xy 294.406385 -395.43426) (xy 294.377458 -395.48897)
			(xy 294.342103 -395.539764) (xy 294.300844 -395.58589) (xy 294.254291 -395.626667) (xy 294.203132 -395.661491)
			(xy 294.148124 -395.689847) (xy 294.090081 -395.711316) (xy 294.02986 -395.72558) (xy 293.999158 -395.72946)
			(xy 293.987474 -395.73073) (xy 293.96817 -395.742922) (xy 293.913306 -395.82979) (xy 293.910766 -395.85265)
			(xy 293.914576 -395.863572) (xy 293.923526 -395.890516) (xy 293.936089 -395.945887) (xy 293.942393 -396.002315)
			(xy 293.94277 -396.030704) (xy 293.942268 -396.062665) (xy 293.934257 -396.126083) (xy 293.91836 -396.187997)
			(xy 293.894828 -396.24743) (xy 293.864034 -396.303445) (xy 293.826461 -396.35516) (xy 293.782704 -396.401757)
			(xy 293.733451 -396.442502) (xy 293.67948 -396.476753) (xy 293.621641 -396.50397) (xy 293.560848 -396.523723)
			(xy 293.498058 -396.535701) (xy 293.434262 -396.539715) (xy 293.370466 -396.535701) (xy 293.307676 -396.523723)
			(xy 293.246883 -396.50397) (xy 293.189044 -396.476753) (xy 293.135073 -396.442502) (xy 293.08582 -396.401757)
			(xy 293.042063 -396.35516) (xy 293.00449 -396.303445) (xy 292.973696 -396.24743) (xy 292.950164 -396.187997)
			(xy 292.934267 -396.126083) (xy 292.926256 -396.062665) (xy 292.925754 -396.030704) (xy 292.926194 -395.999843)
			(xy 292.93364 -395.938571) (xy 292.948458 -395.878654) (xy 292.97043 -395.820975) (xy 292.984428 -395.793468)
			(xy 292.989254 -395.784578) (xy 292.991032 -395.765274) (xy 292.96614 -395.678406) (xy 292.954456 -395.663166)
			(xy 292.94582 -395.65834) (xy 292.921862 -395.64395) (xy 292.87692 -395.610727) (xy 292.835893 -395.572775)
			(xy 292.817296 -395.551914) (xy 292.810946 -395.544548) (xy 292.794182 -395.535658) (xy 292.70579 -395.52626)
			(xy 292.687502 -395.53134) (xy 292.679628 -395.537182) (xy 292.654741 -395.554957) (xy 292.60052 -395.583237)
			(xy 292.542481 -395.602505) (xy 292.482112 -395.612266) (xy 292.451536 -395.612874) (xy 292.424279 -395.612482)
			(xy 292.370319 -395.604728) (xy 292.318012 -395.589374) (xy 292.268423 -395.566731) (xy 292.222562 -395.537262)
			(xy 292.181361 -395.501565) (xy 292.14566 -395.460367) (xy 292.116186 -395.414508) (xy 292.093539 -395.364921)
			(xy 292.07818 -395.312616) (xy 292.070421 -395.258657) (xy 288.806792 -395.258657) (xy 288.806388 -395.284409)
			(xy 288.798377 -395.347827) (xy 288.78248 -395.409741) (xy 288.758948 -395.469174) (xy 288.728154 -395.525189)
			(xy 288.690581 -395.576904) (xy 288.646824 -395.623501) (xy 288.597571 -395.664246) (xy 288.5436 -395.698497)
			(xy 288.485761 -395.725714) (xy 288.424968 -395.745467) (xy 288.362178 -395.757445) (xy 288.298382 -395.761459)
			(xy 288.234586 -395.757445) (xy 288.171796 -395.745467) (xy 288.111003 -395.725714) (xy 288.053164 -395.698497)
			(xy 287.999193 -395.664246) (xy 287.94994 -395.623501) (xy 287.906183 -395.576904) (xy 287.86861 -395.525189)
			(xy 287.837816 -395.469174) (xy 287.814284 -395.409741) (xy 287.798387 -395.347827) (xy 287.790376 -395.284409)
			(xy 287.789874 -395.252448) (xy 284.847218 -395.252448) (xy 284.850592 -395.279161) (xy 284.851094 -395.311122)
			(xy 284.850592 -395.343083) (xy 284.842581 -395.406501) (xy 284.826684 -395.468415) (xy 284.803152 -395.527848)
			(xy 284.772358 -395.583863) (xy 284.734785 -395.635578) (xy 284.691028 -395.682175) (xy 284.641775 -395.72292)
			(xy 284.587804 -395.757171) (xy 284.529965 -395.784388) (xy 284.469172 -395.804141) (xy 284.406382 -395.816119)
			(xy 284.342586 -395.820133) (xy 284.27879 -395.816119) (xy 284.216 -395.804141) (xy 284.155207 -395.784388)
			(xy 284.097368 -395.757171) (xy 284.043397 -395.72292) (xy 283.994144 -395.682175) (xy 283.950387 -395.635578)
			(xy 283.912814 -395.583863) (xy 283.88202 -395.527848) (xy 283.858488 -395.468415) (xy 283.842591 -395.406501)
			(xy 283.83458 -395.343083) (xy 280.881582 -395.343083) (xy 280.881582 -395.926521) (xy 281.864048 -395.926521)
			(xy 281.864048 -395.862599) (xy 281.872059 -395.799181) (xy 281.887956 -395.737267) (xy 281.911488 -395.677834)
			(xy 281.942282 -395.621819) (xy 281.979855 -395.570104) (xy 282.023612 -395.523507) (xy 282.072865 -395.482762)
			(xy 282.126836 -395.448511) (xy 282.184675 -395.421294) (xy 282.245468 -395.401541) (xy 282.308258 -395.389563)
			(xy 282.372054 -395.38555) (xy 282.43585 -395.389563) (xy 282.49864 -395.401541) (xy 282.559433 -395.421294)
			(xy 282.617272 -395.448511) (xy 282.671243 -395.482762) (xy 282.720496 -395.523507) (xy 282.764253 -395.570104)
			(xy 282.801826 -395.621819) (xy 282.83262 -395.677834) (xy 282.856152 -395.737267) (xy 282.872049 -395.799181)
			(xy 282.88006 -395.862599) (xy 282.880562 -395.89456) (xy 282.88006 -395.926521) (xy 282.872049 -395.989939)
			(xy 282.856152 -396.051853) (xy 282.83262 -396.111286) (xy 282.801826 -396.167301) (xy 282.764253 -396.219016)
			(xy 282.720496 -396.265613) (xy 282.671243 -396.306358) (xy 282.617272 -396.340609) (xy 282.559433 -396.367826)
			(xy 282.49864 -396.387579) (xy 282.43585 -396.399557) (xy 282.372054 -396.403571) (xy 282.308258 -396.399557)
			(xy 282.245468 -396.387579) (xy 282.184675 -396.367826) (xy 282.126836 -396.340609) (xy 282.072865 -396.306358)
			(xy 282.023612 -396.265613) (xy 281.979855 -396.219016) (xy 281.942282 -396.167301) (xy 281.911488 -396.111286)
			(xy 281.887956 -396.051853) (xy 281.872059 -395.989939) (xy 281.864048 -395.926521) (xy 280.881582 -395.926521)
			(xy 280.881582 -396.980367) (xy 289.7223 -396.980367) (xy 289.7223 -396.916445) (xy 289.730311 -396.853027)
			(xy 289.746208 -396.791113) (xy 289.76974 -396.73168) (xy 289.800534 -396.675665) (xy 289.838107 -396.62395)
			(xy 289.881864 -396.577353) (xy 289.931117 -396.536608) (xy 289.985088 -396.502357) (xy 290.042927 -396.47514)
			(xy 290.10372 -396.455387) (xy 290.16651 -396.443409) (xy 290.230306 -396.439396) (xy 290.294102 -396.443409)
			(xy 290.356892 -396.455387) (xy 290.417685 -396.47514) (xy 290.475524 -396.502357) (xy 290.529495 -396.536608)
			(xy 290.578748 -396.577353) (xy 290.622505 -396.62395) (xy 290.660078 -396.675665) (xy 290.690872 -396.73168)
			(xy 290.714404 -396.791113) (xy 290.730301 -396.853027) (xy 290.738312 -396.916445) (xy 290.738814 -396.948406)
			(xy 290.738312 -396.980367) (xy 290.737221 -396.989003) (xy 291.03675 -396.989003) (xy 291.03675 -396.925081)
			(xy 291.044761 -396.861663) (xy 291.060658 -396.799749) (xy 291.08419 -396.740316) (xy 291.114984 -396.684301)
			(xy 291.152557 -396.632586) (xy 291.196314 -396.585989) (xy 291.245567 -396.545244) (xy 291.299538 -396.510993)
			(xy 291.357377 -396.483776) (xy 291.41817 -396.464023) (xy 291.48096 -396.452045) (xy 291.544756 -396.448032)
			(xy 291.608552 -396.452045) (xy 291.671342 -396.464023) (xy 291.732135 -396.483776) (xy 291.789974 -396.510993)
			(xy 291.843945 -396.545244) (xy 291.893198 -396.585989) (xy 291.909642 -396.6035) (xy 295.876642 -396.6035)
			(xy 295.880657 -396.539695) (xy 295.892637 -396.476896) (xy 295.912394 -396.416094) (xy 295.939616 -396.358248)
			(xy 295.973874 -396.30427) (xy 296.014627 -396.255011) (xy 296.061233 -396.211249) (xy 296.112956 -396.173674)
			(xy 296.168981 -396.142878) (xy 296.228425 -396.119347) (xy 296.290348 -396.103452) (xy 296.353776 -396.095444)
			(xy 296.385742 -396.094966) (xy 296.417867 -396.09545) (xy 296.481606 -396.103543) (xy 296.543818 -396.119596)
			(xy 296.603515 -396.143353) (xy 296.631868 -396.158466) (xy 296.64279 -396.164562) (xy 296.667174 -396.165324)
			(xy 296.764456 -396.118588) (xy 296.779188 -396.09903) (xy 296.78122 -396.086584) (xy 296.787268 -396.054135)
			(xy 296.806625 -395.991031) (xy 296.833989 -395.930963) (xy 296.868897 -395.874943) (xy 296.889424 -395.849094)
			(xy 296.894724 -395.842097) (xy 296.900697 -395.825604) (xy 296.901108 -395.816836) (xy 296.901108 -395.662912)
			(xy 296.90074 -395.654135) (xy 296.894759 -395.637633) (xy 296.889424 -395.630654) (xy 296.867739 -395.603233)
			(xy 296.831237 -395.543614) (xy 296.803238 -395.479559) (xy 296.784271 -395.412275) (xy 296.774692 -395.343027)
			(xy 296.774108 -395.308074) (xy 296.774532 -395.277342) (xy 296.781943 -395.216326) (xy 296.796656 -395.156648)
			(xy 296.818454 -395.099179) (xy 296.84702 -395.044757) (xy 296.881938 -394.994174) (xy 296.922699 -394.948169)
			(xy 296.968707 -394.907412) (xy 297.019292 -394.872499) (xy 297.073718 -394.843937) (xy 297.131189 -394.822143)
			(xy 297.190867 -394.807436) (xy 297.251884 -394.800029) (xy 297.282616 -394.799566) (xy 297.303541 -394.799767)
			(xy 297.345251 -394.803204) (xy 297.365928 -394.806424) (xy 297.375072 -394.807948) (xy 297.392852 -394.804646)
			(xy 297.464988 -394.760958) (xy 297.476164 -394.746988) (xy 297.479212 -394.738352) (xy 297.48801 -394.713344)
			(xy 297.511495 -394.665816) (xy 297.541337 -394.622) (xy 297.57696 -394.582741) (xy 297.617679 -394.548794)
			(xy 297.662707 -394.520815) (xy 297.711177 -394.499344) (xy 297.762154 -394.484793) (xy 297.814656 -394.477444)
			(xy 297.841162 -394.476986) (xy 297.868414 -394.477491) (xy 297.922363 -394.485242) (xy 297.97466 -394.500593)
			(xy 298.024239 -394.523231) (xy 298.070092 -394.552694) (xy 298.111285 -394.588384) (xy 298.146979 -394.629573)
			(xy 298.176448 -394.675422) (xy 298.199091 -394.724999) (xy 298.214448 -394.777294) (xy 298.222206 -394.831242)
			(xy 298.22267 -394.858494) (xy 298.222107 -394.886464) (xy 298.213966 -394.941808) (xy 298.197827 -394.995369)
			(xy 298.174037 -395.045998) (xy 298.143107 -395.092609) (xy 298.1057 -395.134201) (xy 298.062619 -395.169883)
			(xy 298.014787 -395.198889) (xy 297.963231 -395.220597) (xy 297.909057 -395.234541) (xy 297.881294 -395.23797)
			(xy 297.87215 -395.238732) (xy 297.855894 -395.24686) (xy 297.797982 -395.308074) (xy 297.79087 -395.324584)
			(xy 297.790362 -395.333728) (xy 297.788274 -395.366047) (xy 297.776862 -395.4298) (xy 297.75744 -395.491585)
			(xy 297.730322 -395.5504) (xy 297.69595 -395.605292) (xy 297.675808 -395.630654) (xy 297.670521 -395.637659)
			(xy 297.664542 -395.654146) (xy 297.664124 -395.662912) (xy 297.664124 -395.816836) (xy 297.664484 -395.825613)
			(xy 297.670472 -395.842115) (xy 297.675808 -395.849094) (xy 297.697519 -395.876494) (xy 297.734017 -395.93612)
			(xy 297.76201 -396.00018) (xy 297.780971 -396.067469) (xy 297.790543 -396.136719) (xy 297.791124 -396.171674)
			(xy 297.790383 -396.210651) (xy 297.778527 -396.287698) (xy 297.767502 -396.32509) (xy 297.763946 -396.336266)
			(xy 297.766994 -396.358872) (xy 297.82389 -396.444216) (xy 297.843448 -396.4559) (xy 297.855132 -396.456916)
			(xy 297.883235 -396.459951) (xy 297.938162 -396.473286) (xy 297.990521 -396.494579) (xy 298.039166 -396.523364)
			(xy 298.083033 -396.55901) (xy 298.12116 -396.600737) (xy 298.152714 -396.647633) (xy 298.167963 -396.679674)
			(xy 299.808644 -396.679674) (xy 299.812715 -396.624052) (xy 299.824841 -396.569615) (xy 299.844764 -396.517524)
			(xy 299.87206 -396.468889) (xy 299.906146 -396.424746) (xy 299.946295 -396.386037) (xy 299.991653 -396.353586)
			(xy 300.041253 -396.328085) (xy 300.094037 -396.310078) (xy 300.14888 -396.299948) (xy 300.204614 -396.297911)
			(xy 300.260051 -396.304011) (xy 300.314008 -396.318117) (xy 300.365337 -396.339929) (xy 300.412943 -396.368983)
			(xy 300.455811 -396.404658) (xy 300.493028 -396.446195) (xy 300.523801 -396.492708) (xy 300.547473 -396.543205)
			(xy 300.563541 -396.596612) (xy 300.571661 -396.651788) (xy 300.57217 -396.679674) (xy 300.571723 -396.704137)
			(xy 300.77461 -396.704137) (xy 300.77461 -396.652163) (xy 300.78274 -396.600828) (xy 300.798801 -396.551398)
			(xy 300.822397 -396.505088) (xy 300.852947 -396.46304) (xy 300.889698 -396.426289) (xy 300.931746 -396.395739)
			(xy 300.978056 -396.372143) (xy 301.027486 -396.356082) (xy 301.078821 -396.347952) (xy 301.130795 -396.347952)
			(xy 301.18213 -396.356082) (xy 301.23156 -396.372143) (xy 301.27787 -396.395739) (xy 301.319918 -396.426289)
			(xy 301.356669 -396.46304) (xy 301.387219 -396.505088) (xy 301.410815 -396.551398) (xy 301.426876 -396.600828)
			(xy 301.435006 -396.652163) (xy 301.435516 -396.67815) (xy 301.435006 -396.704137) (xy 301.426876 -396.755472)
			(xy 301.410815 -396.804902) (xy 301.387219 -396.851212) (xy 301.356669 -396.89326) (xy 301.319918 -396.930011)
			(xy 301.27787 -396.960561) (xy 301.23156 -396.984157) (xy 301.18213 -397.000218) (xy 301.130795 -397.008348)
			(xy 301.078821 -397.008348) (xy 301.027486 -397.000218) (xy 300.978056 -396.984157) (xy 300.931746 -396.960561)
			(xy 300.889698 -396.930011) (xy 300.852947 -396.89326) (xy 300.822397 -396.851212) (xy 300.798801 -396.804902)
			(xy 300.78274 -396.755472) (xy 300.77461 -396.704137) (xy 300.571723 -396.704137) (xy 300.571661 -396.70756)
			(xy 300.563541 -396.762736) (xy 300.547473 -396.816143) (xy 300.523801 -396.86664) (xy 300.493028 -396.913153)
			(xy 300.455811 -396.95469) (xy 300.412943 -396.990365) (xy 300.365337 -397.019419) (xy 300.314008 -397.041231)
			(xy 300.260051 -397.055337) (xy 300.204614 -397.061437) (xy 300.14888 -397.0594) (xy 300.094037 -397.04927)
			(xy 300.041253 -397.031263) (xy 299.991653 -397.005762) (xy 299.946295 -396.973311) (xy 299.906146 -396.934602)
			(xy 299.87206 -396.890459) (xy 299.844764 -396.841824) (xy 299.824841 -396.789733) (xy 299.812715 -396.735296)
			(xy 299.808644 -396.679674) (xy 298.167963 -396.679674) (xy 298.177004 -396.698671) (xy 298.1935 -396.752734)
			(xy 298.201838 -396.808638) (xy 298.20235 -396.8369) (xy 298.201864 -396.864151) (xy 298.194108 -396.918099)
			(xy 298.178753 -396.970394) (xy 298.156111 -397.019971) (xy 298.126645 -397.065821) (xy 298.090954 -397.107012)
			(xy 298.049763 -397.142703) (xy 298.003913 -397.172169) (xy 297.954336 -397.194811) (xy 297.902041 -397.210166)
			(xy 297.848093 -397.217922) (xy 297.793591 -397.217922) (xy 297.739643 -397.210166) (xy 297.687348 -397.194811)
			(xy 297.637771 -397.172169) (xy 297.591921 -397.142703) (xy 297.55073 -397.107012) (xy 297.515039 -397.065821)
			(xy 297.485573 -397.019971) (xy 297.462931 -396.970394) (xy 297.447576 -396.918099) (xy 297.43982 -396.864151)
			(xy 297.439334 -396.8369) (xy 297.439436 -396.825441) (xy 297.440834 -396.802566) (xy 297.442128 -396.79118)
			(xy 297.443398 -396.779496) (xy 297.436032 -396.757906) (xy 297.364658 -396.6845) (xy 297.343068 -396.676626)
			(xy 297.331384 -396.677896) (xy 297.319221 -396.678974) (xy 297.294827 -396.680119) (xy 297.282616 -396.680182)
			(xy 297.250491 -396.67968) (xy 297.186753 -396.671593) (xy 297.124541 -396.655545) (xy 297.064843 -396.631792)
			(xy 297.03649 -396.616682) (xy 297.025568 -396.610586) (xy 297.001184 -396.609824) (xy 296.903902 -396.65656)
			(xy 296.88917 -396.676118) (xy 296.887138 -396.688564) (xy 296.881168 -396.720447) (xy 296.862263 -396.782498)
			(xy 296.835622 -396.84164) (xy 296.801677 -396.896916) (xy 296.760979 -396.947426) (xy 296.714189 -396.992351)
			(xy 296.662067 -397.030963) (xy 296.605458 -397.062633) (xy 296.545281 -397.086848) (xy 296.482514 -397.103215)
			(xy 296.418175 -397.111469) (xy 296.385742 -397.111982) (xy 296.353776 -397.111556) (xy 296.290348 -397.103548)
			(xy 296.228425 -397.087653) (xy 296.168981 -397.064122) (xy 296.112956 -397.033326) (xy 296.061233 -396.995751)
			(xy 296.014627 -396.951989) (xy 295.973874 -396.90273) (xy 295.939616 -396.848752) (xy 295.912394 -396.790906)
			(xy 295.892637 -396.730104) (xy 295.880657 -396.667305) (xy 295.876642 -396.6035) (xy 291.909642 -396.6035)
			(xy 291.936955 -396.632586) (xy 291.974528 -396.684301) (xy 292.005322 -396.740316) (xy 292.028854 -396.799749)
			(xy 292.044751 -396.861663) (xy 292.052762 -396.925081) (xy 292.053264 -396.957042) (xy 292.052762 -396.989003)
			(xy 292.044751 -397.052421) (xy 292.028854 -397.114335) (xy 292.005322 -397.173768) (xy 291.974528 -397.229783)
			(xy 291.936955 -397.281498) (xy 291.893198 -397.328095) (xy 291.843945 -397.36884) (xy 291.789974 -397.403091)
			(xy 291.732135 -397.430308) (xy 291.671342 -397.450061) (xy 291.608552 -397.462039) (xy 291.544756 -397.466053)
			(xy 291.48096 -397.462039) (xy 291.41817 -397.450061) (xy 291.357377 -397.430308) (xy 291.299538 -397.403091)
			(xy 291.245567 -397.36884) (xy 291.196314 -397.328095) (xy 291.152557 -397.281498) (xy 291.114984 -397.229783)
			(xy 291.08419 -397.173768) (xy 291.060658 -397.114335) (xy 291.044761 -397.052421) (xy 291.03675 -396.989003)
			(xy 290.737221 -396.989003) (xy 290.730301 -397.043785) (xy 290.714404 -397.105699) (xy 290.690872 -397.165132)
			(xy 290.660078 -397.221147) (xy 290.622505 -397.272862) (xy 290.578748 -397.319459) (xy 290.529495 -397.360204)
			(xy 290.475524 -397.394455) (xy 290.417685 -397.421672) (xy 290.356892 -397.441425) (xy 290.294102 -397.453403)
			(xy 290.230306 -397.457417) (xy 290.16651 -397.453403) (xy 290.10372 -397.441425) (xy 290.042927 -397.421672)
			(xy 289.985088 -397.394455) (xy 289.931117 -397.360204) (xy 289.881864 -397.319459) (xy 289.838107 -397.272862)
			(xy 289.800534 -397.221147) (xy 289.76974 -397.165132) (xy 289.746208 -397.105699) (xy 289.730311 -397.043785)
			(xy 289.7223 -396.980367) (xy 280.881582 -396.980367) (xy 280.881582 -398.513808) (xy 287.467802 -398.513808)
			(xy 287.468245 -398.483076) (xy 287.475653 -398.422059) (xy 287.490362 -398.36238) (xy 287.512157 -398.30491)
			(xy 287.540721 -398.250485) (xy 287.575637 -398.199901) (xy 287.616395 -398.153894) (xy 287.662402 -398.113136)
			(xy 287.712987 -398.07822) (xy 287.767412 -398.049656) (xy 287.824882 -398.027861) (xy 287.884561 -398.013153)
			(xy 287.945578 -398.005745) (xy 287.97631 -398.0053) (xy 288.00863 -398.005806) (xy 288.072747 -398.014022)
			(xy 288.135307 -398.030293) (xy 288.195301 -398.054359) (xy 288.251764 -398.085831) (xy 288.303784 -398.124202)
			(xy 288.350524 -398.168855) (xy 288.391232 -398.219068) (xy 288.42525 -398.274034) (xy 288.439098 -398.303242)
			(xy 288.444686 -398.31518) (xy 288.465006 -398.33042) (xy 288.575242 -398.346676) (xy 288.599118 -398.33804)
			(xy 288.608008 -398.328134) (xy 288.628732 -398.305264) (xy 288.674791 -398.264181) (xy 288.725485 -398.228978)
			(xy 288.780069 -398.200172) (xy 288.837739 -398.178187) (xy 288.897647 -398.163346) (xy 288.958911 -398.15587)
			(xy 288.98977 -398.155414) (xy 289.021735 -398.155849) (xy 289.085161 -398.163858) (xy 289.147083 -398.179754)
			(xy 289.206525 -398.203285) (xy 289.262548 -398.234082) (xy 289.31427 -398.271657) (xy 289.360874 -398.315418)
			(xy 289.401626 -398.364676) (xy 289.435882 -398.418653) (xy 289.463103 -398.476498) (xy 289.482859 -398.537299)
			(xy 289.494839 -398.600096) (xy 289.498854 -398.6639) (xy 289.494839 -398.727704) (xy 289.482859 -398.790501)
			(xy 289.463103 -398.851302) (xy 289.435882 -398.909147) (xy 289.426444 -398.924018) (xy 292.273226 -398.924018)
			(xy 292.277297 -398.868396) (xy 292.289423 -398.813959) (xy 292.309346 -398.761868) (xy 292.336642 -398.713233)
			(xy 292.370728 -398.66909) (xy 292.410877 -398.630381) (xy 292.456235 -398.59793) (xy 292.505835 -398.572429)
			(xy 292.558619 -398.554422) (xy 292.613462 -398.544292) (xy 292.669196 -398.542255) (xy 292.724633 -398.548355)
			(xy 292.77859 -398.562461) (xy 292.829919 -398.584273) (xy 292.877525 -398.613327) (xy 292.920393 -398.649002)
			(xy 292.95761 -398.690539) (xy 292.988383 -398.737052) (xy 293.012055 -398.787549) (xy 293.028123 -398.840956)
			(xy 293.036243 -398.896132) (xy 293.036752 -398.924018) (xy 293.036243 -398.951904) (xy 293.028123 -399.00708)
			(xy 293.027819 -399.008092) (xy 300.635416 -399.008092) (xy 300.635972 -398.9748) (xy 300.645592 -398.908915)
			(xy 300.664671 -398.845123) (xy 300.692806 -398.784776) (xy 300.7106 -398.756632) (xy 300.715662 -398.748115)
			(xy 300.71948 -398.728693) (xy 300.715657 -398.709272) (xy 300.7106 -398.700752) (xy 300.692824 -398.672601)
			(xy 300.66473 -398.612242) (xy 300.645661 -398.548455) (xy 300.636018 -398.48258) (xy 300.635416 -398.449292)
			(xy 300.635906 -398.419324) (xy 300.643729 -398.359902) (xy 300.659242 -398.302009) (xy 300.682178 -398.246636)
			(xy 300.712145 -398.19473) (xy 300.748632 -398.14718) (xy 300.791012 -398.1048) (xy 300.838562 -398.068313)
			(xy 300.890468 -398.038346) (xy 300.945841 -398.01541) (xy 301.003734 -397.999897) (xy 301.063156 -397.992074)
			(xy 301.123092 -397.992074) (xy 301.182514 -397.999897) (xy 301.240407 -398.01541) (xy 301.29578 -398.038346)
			(xy 301.347686 -398.068313) (xy 301.395236 -398.1048) (xy 301.437616 -398.14718) (xy 301.474103 -398.19473)
			(xy 301.50407 -398.246636) (xy 301.527006 -398.302009) (xy 301.542519 -398.359902) (xy 301.550342 -398.419324)
			(xy 301.550832 -398.449292) (xy 301.550261 -398.482584) (xy 301.541588 -398.542002) (xy 303.085004 -398.542002)
			(xy 303.088964 -398.492948) (xy 303.100741 -398.445164) (xy 303.120032 -398.399888) (xy 303.146335 -398.358292)
			(xy 303.17897 -398.321455) (xy 303.217091 -398.29033) (xy 303.259712 -398.265723) (xy 303.305728 -398.248271)
			(xy 303.353947 -398.238427) (xy 303.403122 -398.236446) (xy 303.451977 -398.242378) (xy 303.499248 -398.25607)
			(xy 303.54371 -398.277168) (xy 303.584213 -398.305124) (xy 303.619706 -398.339216) (xy 303.649271 -398.37856)
			(xy 303.672142 -398.422137) (xy 303.687726 -398.468818) (xy 303.695621 -398.517395) (xy 303.696116 -398.542002)
			(xy 304.285154 -398.542002) (xy 304.289114 -398.492948) (xy 304.300891 -398.445164) (xy 304.320182 -398.399888)
			(xy 304.346485 -398.358292) (xy 304.37912 -398.321455) (xy 304.417241 -398.29033) (xy 304.459862 -398.265723)
			(xy 304.505878 -398.248271) (xy 304.554097 -398.238427) (xy 304.603272 -398.236446) (xy 304.652127 -398.242378)
			(xy 304.699398 -398.25607) (xy 304.74386 -398.277168) (xy 304.784363 -398.305124) (xy 304.819856 -398.339216)
			(xy 304.849421 -398.37856) (xy 304.872292 -398.422137) (xy 304.887876 -398.468818) (xy 304.895771 -398.517395)
			(xy 304.896266 -398.542002) (xy 305.485304 -398.542002) (xy 305.489264 -398.492948) (xy 305.501041 -398.445164)
			(xy 305.520332 -398.399888) (xy 305.546635 -398.358292) (xy 305.57927 -398.321455) (xy 305.617391 -398.29033)
			(xy 305.660012 -398.265723) (xy 305.706028 -398.248271) (xy 305.754247 -398.238427) (xy 305.803422 -398.236446)
			(xy 305.852277 -398.242378) (xy 305.899548 -398.25607) (xy 305.94401 -398.277168) (xy 305.984513 -398.305124)
			(xy 306.020006 -398.339216) (xy 306.049571 -398.37856) (xy 306.072442 -398.422137) (xy 306.088026 -398.468818)
			(xy 306.095921 -398.517395) (xy 306.096416 -398.542002) (xy 306.6852 -398.542002) (xy 306.68916 -398.492948)
			(xy 306.700937 -398.445164) (xy 306.720228 -398.399888) (xy 306.746531 -398.358292) (xy 306.779166 -398.321455)
			(xy 306.817287 -398.29033) (xy 306.859908 -398.265723) (xy 306.905924 -398.248271) (xy 306.954143 -398.238427)
			(xy 307.003318 -398.236446) (xy 307.052173 -398.242378) (xy 307.099444 -398.25607) (xy 307.143906 -398.277168)
			(xy 307.184409 -398.305124) (xy 307.219902 -398.339216) (xy 307.249467 -398.37856) (xy 307.272338 -398.422137)
			(xy 307.287922 -398.468818) (xy 307.295817 -398.517395) (xy 307.296312 -398.542002) (xy 307.88535 -398.542002)
			(xy 307.88931 -398.492948) (xy 307.901087 -398.445164) (xy 307.920378 -398.399888) (xy 307.946681 -398.358292)
			(xy 307.979316 -398.321455) (xy 308.017437 -398.29033) (xy 308.060058 -398.265723) (xy 308.106074 -398.248271)
			(xy 308.154293 -398.238427) (xy 308.203468 -398.236446) (xy 308.252323 -398.242378) (xy 308.299594 -398.25607)
			(xy 308.344056 -398.277168) (xy 308.384559 -398.305124) (xy 308.420052 -398.339216) (xy 308.449617 -398.37856)
			(xy 308.472488 -398.422137) (xy 308.488072 -398.468818) (xy 308.495967 -398.517395) (xy 308.496462 -398.542002)
			(xy 309.085246 -398.542002) (xy 309.089206 -398.492948) (xy 309.100983 -398.445164) (xy 309.120274 -398.399888)
			(xy 309.146577 -398.358292) (xy 309.179212 -398.321455) (xy 309.217333 -398.29033) (xy 309.259954 -398.265723)
			(xy 309.30597 -398.248271) (xy 309.354189 -398.238427) (xy 309.403364 -398.236446) (xy 309.452219 -398.242378)
			(xy 309.49949 -398.25607) (xy 309.543952 -398.277168) (xy 309.584455 -398.305124) (xy 309.619948 -398.339216)
			(xy 309.649513 -398.37856) (xy 309.672384 -398.422137) (xy 309.687968 -398.468818) (xy 309.695863 -398.517395)
			(xy 309.696358 -398.542002) (xy 310.285142 -398.542002) (xy 310.289102 -398.492948) (xy 310.300879 -398.445164)
			(xy 310.32017 -398.399888) (xy 310.346473 -398.358292) (xy 310.379108 -398.321455) (xy 310.417229 -398.29033)
			(xy 310.45985 -398.265723) (xy 310.505866 -398.248271) (xy 310.554085 -398.238427) (xy 310.60326 -398.236446)
			(xy 310.652115 -398.242378) (xy 310.699386 -398.25607) (xy 310.743848 -398.277168) (xy 310.784351 -398.305124)
			(xy 310.819844 -398.339216) (xy 310.849409 -398.37856) (xy 310.87228 -398.422137) (xy 310.887864 -398.468818)
			(xy 310.895759 -398.517395) (xy 310.896254 -398.542002) (xy 311.485292 -398.542002) (xy 311.489252 -398.492948)
			(xy 311.501029 -398.445164) (xy 311.52032 -398.399888) (xy 311.546623 -398.358292) (xy 311.579258 -398.321455)
			(xy 311.617379 -398.29033) (xy 311.66 -398.265723) (xy 311.706016 -398.248271) (xy 311.754235 -398.238427)
			(xy 311.80341 -398.236446) (xy 311.852265 -398.242378) (xy 311.899536 -398.25607) (xy 311.943998 -398.277168)
			(xy 311.984501 -398.305124) (xy 312.019994 -398.339216) (xy 312.049559 -398.37856) (xy 312.07243 -398.422137)
			(xy 312.088014 -398.468818) (xy 312.095909 -398.517395) (xy 312.096404 -398.542002) (xy 312.685188 -398.542002)
			(xy 312.689148 -398.492948) (xy 312.700925 -398.445164) (xy 312.720216 -398.399888) (xy 312.746519 -398.358292)
			(xy 312.779154 -398.321455) (xy 312.817275 -398.29033) (xy 312.859896 -398.265723) (xy 312.905912 -398.248271)
			(xy 312.954131 -398.238427) (xy 313.003306 -398.236446) (xy 313.052161 -398.242378) (xy 313.099432 -398.25607)
			(xy 313.143894 -398.277168) (xy 313.184397 -398.305124) (xy 313.21989 -398.339216) (xy 313.249455 -398.37856)
			(xy 313.272326 -398.422137) (xy 313.28791 -398.468818) (xy 313.295805 -398.517395) (xy 313.2963 -398.542002)
			(xy 313.885338 -398.542002) (xy 313.889298 -398.492948) (xy 313.901075 -398.445164) (xy 313.920366 -398.399888)
			(xy 313.946669 -398.358292) (xy 313.979304 -398.321455) (xy 314.017425 -398.29033) (xy 314.060046 -398.265723)
			(xy 314.106062 -398.248271) (xy 314.154281 -398.238427) (xy 314.203456 -398.236446) (xy 314.252311 -398.242378)
			(xy 314.299582 -398.25607) (xy 314.344044 -398.277168) (xy 314.384547 -398.305124) (xy 314.42004 -398.339216)
			(xy 314.449605 -398.37856) (xy 314.472476 -398.422137) (xy 314.48806 -398.468818) (xy 314.495955 -398.517395)
			(xy 314.49645 -398.542002) (xy 315.085234 -398.542002) (xy 315.089194 -398.492948) (xy 315.100971 -398.445164)
			(xy 315.120262 -398.399888) (xy 315.146565 -398.358292) (xy 315.1792 -398.321455) (xy 315.217321 -398.29033)
			(xy 315.259942 -398.265723) (xy 315.305958 -398.248271) (xy 315.354177 -398.238427) (xy 315.403352 -398.236446)
			(xy 315.452207 -398.242378) (xy 315.499478 -398.25607) (xy 315.54394 -398.277168) (xy 315.584443 -398.305124)
			(xy 315.619936 -398.339216) (xy 315.649501 -398.37856) (xy 315.672372 -398.422137) (xy 315.687956 -398.468818)
			(xy 315.695851 -398.517395) (xy 315.696346 -398.542002) (xy 316.28513 -398.542002) (xy 316.28909 -398.492948)
			(xy 316.300867 -398.445164) (xy 316.320158 -398.399888) (xy 316.346461 -398.358292) (xy 316.379096 -398.321455)
			(xy 316.417217 -398.29033) (xy 316.459838 -398.265723) (xy 316.505854 -398.248271) (xy 316.554073 -398.238427)
			(xy 316.603248 -398.236446) (xy 316.652103 -398.242378) (xy 316.699374 -398.25607) (xy 316.743836 -398.277168)
			(xy 316.784339 -398.305124) (xy 316.819832 -398.339216) (xy 316.849397 -398.37856) (xy 316.872268 -398.422137)
			(xy 316.887852 -398.468818) (xy 316.895747 -398.517395) (xy 316.896242 -398.542002) (xy 317.48528 -398.542002)
			(xy 317.48924 -398.492948) (xy 317.501017 -398.445164) (xy 317.520308 -398.399888) (xy 317.546611 -398.358292)
			(xy 317.579246 -398.321455) (xy 317.617367 -398.29033) (xy 317.659988 -398.265723) (xy 317.706004 -398.248271)
			(xy 317.754223 -398.238427) (xy 317.803398 -398.236446) (xy 317.852253 -398.242378) (xy 317.899524 -398.25607)
			(xy 317.943986 -398.277168) (xy 317.984489 -398.305124) (xy 318.019982 -398.339216) (xy 318.049547 -398.37856)
			(xy 318.072418 -398.422137) (xy 318.088002 -398.468818) (xy 318.095897 -398.517395) (xy 318.096392 -398.542002)
			(xy 318.685176 -398.542002) (xy 318.689136 -398.492948) (xy 318.700913 -398.445164) (xy 318.720204 -398.399888)
			(xy 318.746507 -398.358292) (xy 318.779142 -398.321455) (xy 318.817263 -398.29033) (xy 318.859884 -398.265723)
			(xy 318.9059 -398.248271) (xy 318.954119 -398.238427) (xy 319.003294 -398.236446) (xy 319.052149 -398.242378)
			(xy 319.09942 -398.25607) (xy 319.143882 -398.277168) (xy 319.184385 -398.305124) (xy 319.219878 -398.339216)
			(xy 319.249443 -398.37856) (xy 319.272314 -398.422137) (xy 319.287898 -398.468818) (xy 319.295793 -398.517395)
			(xy 319.296288 -398.542002) (xy 319.885326 -398.542002) (xy 319.889286 -398.492948) (xy 319.901063 -398.445164)
			(xy 319.920354 -398.399888) (xy 319.946657 -398.358292) (xy 319.979292 -398.321455) (xy 320.017413 -398.29033)
			(xy 320.060034 -398.265723) (xy 320.10605 -398.248271) (xy 320.154269 -398.238427) (xy 320.203444 -398.236446)
			(xy 320.252299 -398.242378) (xy 320.29957 -398.25607) (xy 320.344032 -398.277168) (xy 320.384535 -398.305124)
			(xy 320.420028 -398.339216) (xy 320.449593 -398.37856) (xy 320.472464 -398.422137) (xy 320.488048 -398.468818)
			(xy 320.495943 -398.517395) (xy 320.496438 -398.542002) (xy 321.085222 -398.542002) (xy 321.089182 -398.492948)
			(xy 321.100959 -398.445164) (xy 321.12025 -398.399888) (xy 321.146553 -398.358292) (xy 321.179188 -398.321455)
			(xy 321.217309 -398.29033) (xy 321.25993 -398.265723) (xy 321.305946 -398.248271) (xy 321.354165 -398.238427)
			(xy 321.40334 -398.236446) (xy 321.452195 -398.242378) (xy 321.499466 -398.25607) (xy 321.543928 -398.277168)
			(xy 321.584431 -398.305124) (xy 321.619924 -398.339216) (xy 321.649489 -398.37856) (xy 321.67236 -398.422137)
			(xy 321.687944 -398.468818) (xy 321.695839 -398.517395) (xy 321.696334 -398.542002) (xy 321.695839 -398.566609)
			(xy 321.695615 -398.567989) (xy 322.414902 -398.567989) (xy 322.414902 -398.516015) (xy 322.423032 -398.46468)
			(xy 322.439093 -398.41525) (xy 322.462689 -398.36894) (xy 322.493239 -398.326892) (xy 322.52999 -398.290141)
			(xy 322.572038 -398.259591) (xy 322.618348 -398.235995) (xy 322.667778 -398.219934) (xy 322.719113 -398.211804)
			(xy 322.771087 -398.211804) (xy 322.822422 -398.219934) (xy 322.871852 -398.235995) (xy 322.918162 -398.259591)
			(xy 322.96021 -398.290141) (xy 322.996961 -398.326892) (xy 323.027511 -398.36894) (xy 323.051107 -398.41525)
			(xy 323.067168 -398.46468) (xy 323.075298 -398.516015) (xy 323.075808 -398.542002) (xy 323.075298 -398.567989)
			(xy 323.067168 -398.619324) (xy 323.051107 -398.668754) (xy 323.027511 -398.715064) (xy 322.996961 -398.757112)
			(xy 322.96021 -398.793863) (xy 322.918162 -398.824413) (xy 322.871852 -398.848009) (xy 322.822422 -398.86407)
			(xy 322.771087 -398.8722) (xy 322.719113 -398.8722) (xy 322.667778 -398.86407) (xy 322.618348 -398.848009)
			(xy 322.572038 -398.824413) (xy 322.52999 -398.793863) (xy 322.493239 -398.757112) (xy 322.462689 -398.715064)
			(xy 322.439093 -398.668754) (xy 322.423032 -398.619324) (xy 322.414902 -398.567989) (xy 321.695615 -398.567989)
			(xy 321.687944 -398.615186) (xy 321.67236 -398.661867) (xy 321.649489 -398.705444) (xy 321.619924 -398.744788)
			(xy 321.584431 -398.77888) (xy 321.543928 -398.806836) (xy 321.499466 -398.827934) (xy 321.452195 -398.841626)
			(xy 321.40334 -398.847558) (xy 321.354165 -398.845577) (xy 321.305946 -398.835733) (xy 321.25993 -398.818281)
			(xy 321.217309 -398.793674) (xy 321.179188 -398.762549) (xy 321.146553 -398.725712) (xy 321.12025 -398.684116)
			(xy 321.100959 -398.63884) (xy 321.089182 -398.591056) (xy 321.085222 -398.542002) (xy 320.496438 -398.542002)
			(xy 320.495943 -398.566609) (xy 320.488048 -398.615186) (xy 320.472464 -398.661867) (xy 320.449593 -398.705444)
			(xy 320.420028 -398.744788) (xy 320.384535 -398.77888) (xy 320.344032 -398.806836) (xy 320.29957 -398.827934)
			(xy 320.252299 -398.841626) (xy 320.203444 -398.847558) (xy 320.154269 -398.845577) (xy 320.10605 -398.835733)
			(xy 320.060034 -398.818281) (xy 320.017413 -398.793674) (xy 319.979292 -398.762549) (xy 319.946657 -398.725712)
			(xy 319.920354 -398.684116) (xy 319.901063 -398.63884) (xy 319.889286 -398.591056) (xy 319.885326 -398.542002)
			(xy 319.296288 -398.542002) (xy 319.295793 -398.566609) (xy 319.287898 -398.615186) (xy 319.272314 -398.661867)
			(xy 319.249443 -398.705444) (xy 319.219878 -398.744788) (xy 319.184385 -398.77888) (xy 319.143882 -398.806836)
			(xy 319.09942 -398.827934) (xy 319.052149 -398.841626) (xy 319.003294 -398.847558) (xy 318.954119 -398.845577)
			(xy 318.9059 -398.835733) (xy 318.859884 -398.818281) (xy 318.817263 -398.793674) (xy 318.779142 -398.762549)
			(xy 318.746507 -398.725712) (xy 318.720204 -398.684116) (xy 318.700913 -398.63884) (xy 318.689136 -398.591056)
			(xy 318.685176 -398.542002) (xy 318.096392 -398.542002) (xy 318.095897 -398.566609) (xy 318.088002 -398.615186)
			(xy 318.072418 -398.661867) (xy 318.049547 -398.705444) (xy 318.019982 -398.744788) (xy 317.984489 -398.77888)
			(xy 317.943986 -398.806836) (xy 317.899524 -398.827934) (xy 317.852253 -398.841626) (xy 317.803398 -398.847558)
			(xy 317.754223 -398.845577) (xy 317.706004 -398.835733) (xy 317.659988 -398.818281) (xy 317.617367 -398.793674)
			(xy 317.579246 -398.762549) (xy 317.546611 -398.725712) (xy 317.520308 -398.684116) (xy 317.501017 -398.63884)
			(xy 317.48924 -398.591056) (xy 317.48528 -398.542002) (xy 316.896242 -398.542002) (xy 316.895747 -398.566609)
			(xy 316.887852 -398.615186) (xy 316.872268 -398.661867) (xy 316.849397 -398.705444) (xy 316.819832 -398.744788)
			(xy 316.784339 -398.77888) (xy 316.743836 -398.806836) (xy 316.699374 -398.827934) (xy 316.652103 -398.841626)
			(xy 316.603248 -398.847558) (xy 316.554073 -398.845577) (xy 316.505854 -398.835733) (xy 316.459838 -398.818281)
			(xy 316.417217 -398.793674) (xy 316.379096 -398.762549) (xy 316.346461 -398.725712) (xy 316.320158 -398.684116)
			(xy 316.300867 -398.63884) (xy 316.28909 -398.591056) (xy 316.28513 -398.542002) (xy 315.696346 -398.542002)
			(xy 315.695851 -398.566609) (xy 315.687956 -398.615186) (xy 315.672372 -398.661867) (xy 315.649501 -398.705444)
			(xy 315.619936 -398.744788) (xy 315.584443 -398.77888) (xy 315.54394 -398.806836) (xy 315.499478 -398.827934)
			(xy 315.452207 -398.841626) (xy 315.403352 -398.847558) (xy 315.354177 -398.845577) (xy 315.305958 -398.835733)
			(xy 315.259942 -398.818281) (xy 315.217321 -398.793674) (xy 315.1792 -398.762549) (xy 315.146565 -398.725712)
			(xy 315.120262 -398.684116) (xy 315.100971 -398.63884) (xy 315.089194 -398.591056) (xy 315.085234 -398.542002)
			(xy 314.49645 -398.542002) (xy 314.495955 -398.566609) (xy 314.48806 -398.615186) (xy 314.472476 -398.661867)
			(xy 314.449605 -398.705444) (xy 314.42004 -398.744788) (xy 314.384547 -398.77888) (xy 314.344044 -398.806836)
			(xy 314.299582 -398.827934) (xy 314.252311 -398.841626) (xy 314.203456 -398.847558) (xy 314.154281 -398.845577)
			(xy 314.106062 -398.835733) (xy 314.060046 -398.818281) (xy 314.017425 -398.793674) (xy 313.979304 -398.762549)
			(xy 313.946669 -398.725712) (xy 313.920366 -398.684116) (xy 313.901075 -398.63884) (xy 313.889298 -398.591056)
			(xy 313.885338 -398.542002) (xy 313.2963 -398.542002) (xy 313.295805 -398.566609) (xy 313.28791 -398.615186)
			(xy 313.272326 -398.661867) (xy 313.249455 -398.705444) (xy 313.21989 -398.744788) (xy 313.184397 -398.77888)
			(xy 313.143894 -398.806836) (xy 313.099432 -398.827934) (xy 313.052161 -398.841626) (xy 313.003306 -398.847558)
			(xy 312.954131 -398.845577) (xy 312.905912 -398.835733) (xy 312.859896 -398.818281) (xy 312.817275 -398.793674)
			(xy 312.779154 -398.762549) (xy 312.746519 -398.725712) (xy 312.720216 -398.684116) (xy 312.700925 -398.63884)
			(xy 312.689148 -398.591056) (xy 312.685188 -398.542002) (xy 312.096404 -398.542002) (xy 312.095909 -398.566609)
			(xy 312.088014 -398.615186) (xy 312.07243 -398.661867) (xy 312.049559 -398.705444) (xy 312.019994 -398.744788)
			(xy 311.984501 -398.77888) (xy 311.943998 -398.806836) (xy 311.899536 -398.827934) (xy 311.852265 -398.841626)
			(xy 311.80341 -398.847558) (xy 311.754235 -398.845577) (xy 311.706016 -398.835733) (xy 311.66 -398.818281)
			(xy 311.617379 -398.793674) (xy 311.579258 -398.762549) (xy 311.546623 -398.725712) (xy 311.52032 -398.684116)
			(xy 311.501029 -398.63884) (xy 311.489252 -398.591056) (xy 311.485292 -398.542002) (xy 310.896254 -398.542002)
			(xy 310.895759 -398.566609) (xy 310.887864 -398.615186) (xy 310.87228 -398.661867) (xy 310.849409 -398.705444)
			(xy 310.819844 -398.744788) (xy 310.784351 -398.77888) (xy 310.743848 -398.806836) (xy 310.699386 -398.827934)
			(xy 310.652115 -398.841626) (xy 310.60326 -398.847558) (xy 310.554085 -398.845577) (xy 310.505866 -398.835733)
			(xy 310.45985 -398.818281) (xy 310.417229 -398.793674) (xy 310.379108 -398.762549) (xy 310.346473 -398.725712)
			(xy 310.32017 -398.684116) (xy 310.300879 -398.63884) (xy 310.289102 -398.591056) (xy 310.285142 -398.542002)
			(xy 309.696358 -398.542002) (xy 309.695863 -398.566609) (xy 309.687968 -398.615186) (xy 309.672384 -398.661867)
			(xy 309.649513 -398.705444) (xy 309.619948 -398.744788) (xy 309.584455 -398.77888) (xy 309.543952 -398.806836)
			(xy 309.49949 -398.827934) (xy 309.452219 -398.841626) (xy 309.403364 -398.847558) (xy 309.354189 -398.845577)
			(xy 309.30597 -398.835733) (xy 309.259954 -398.818281) (xy 309.217333 -398.793674) (xy 309.179212 -398.762549)
			(xy 309.146577 -398.725712) (xy 309.120274 -398.684116) (xy 309.100983 -398.63884) (xy 309.089206 -398.591056)
			(xy 309.085246 -398.542002) (xy 308.496462 -398.542002) (xy 308.495967 -398.566609) (xy 308.488072 -398.615186)
			(xy 308.472488 -398.661867) (xy 308.449617 -398.705444) (xy 308.420052 -398.744788) (xy 308.384559 -398.77888)
			(xy 308.344056 -398.806836) (xy 308.299594 -398.827934) (xy 308.252323 -398.841626) (xy 308.203468 -398.847558)
			(xy 308.154293 -398.845577) (xy 308.106074 -398.835733) (xy 308.060058 -398.818281) (xy 308.017437 -398.793674)
			(xy 307.979316 -398.762549) (xy 307.946681 -398.725712) (xy 307.920378 -398.684116) (xy 307.901087 -398.63884)
			(xy 307.88931 -398.591056) (xy 307.88535 -398.542002) (xy 307.296312 -398.542002) (xy 307.295817 -398.566609)
			(xy 307.287922 -398.615186) (xy 307.272338 -398.661867) (xy 307.249467 -398.705444) (xy 307.219902 -398.744788)
			(xy 307.184409 -398.77888) (xy 307.143906 -398.806836) (xy 307.099444 -398.827934) (xy 307.052173 -398.841626)
			(xy 307.003318 -398.847558) (xy 306.954143 -398.845577) (xy 306.905924 -398.835733) (xy 306.859908 -398.818281)
			(xy 306.817287 -398.793674) (xy 306.779166 -398.762549) (xy 306.746531 -398.725712) (xy 306.720228 -398.684116)
			(xy 306.700937 -398.63884) (xy 306.68916 -398.591056) (xy 306.6852 -398.542002) (xy 306.096416 -398.542002)
			(xy 306.095921 -398.566609) (xy 306.088026 -398.615186) (xy 306.072442 -398.661867) (xy 306.049571 -398.705444)
			(xy 306.020006 -398.744788) (xy 305.984513 -398.77888) (xy 305.94401 -398.806836) (xy 305.899548 -398.827934)
			(xy 305.852277 -398.841626) (xy 305.803422 -398.847558) (xy 305.754247 -398.845577) (xy 305.706028 -398.835733)
			(xy 305.660012 -398.818281) (xy 305.617391 -398.793674) (xy 305.57927 -398.762549) (xy 305.546635 -398.725712)
			(xy 305.520332 -398.684116) (xy 305.501041 -398.63884) (xy 305.489264 -398.591056) (xy 305.485304 -398.542002)
			(xy 304.896266 -398.542002) (xy 304.895771 -398.566609) (xy 304.887876 -398.615186) (xy 304.872292 -398.661867)
			(xy 304.849421 -398.705444) (xy 304.819856 -398.744788) (xy 304.784363 -398.77888) (xy 304.74386 -398.806836)
			(xy 304.699398 -398.827934) (xy 304.652127 -398.841626) (xy 304.603272 -398.847558) (xy 304.554097 -398.845577)
			(xy 304.505878 -398.835733) (xy 304.459862 -398.818281) (xy 304.417241 -398.793674) (xy 304.37912 -398.762549)
			(xy 304.346485 -398.725712) (xy 304.320182 -398.684116) (xy 304.300891 -398.63884) (xy 304.289114 -398.591056)
			(xy 304.285154 -398.542002) (xy 303.696116 -398.542002) (xy 303.695621 -398.566609) (xy 303.687726 -398.615186)
			(xy 303.672142 -398.661867) (xy 303.649271 -398.705444) (xy 303.619706 -398.744788) (xy 303.584213 -398.77888)
			(xy 303.54371 -398.806836) (xy 303.499248 -398.827934) (xy 303.451977 -398.841626) (xy 303.403122 -398.847558)
			(xy 303.353947 -398.845577) (xy 303.305728 -398.835733) (xy 303.259712 -398.818281) (xy 303.217091 -398.793674)
			(xy 303.17897 -398.762549) (xy 303.146335 -398.725712) (xy 303.120032 -398.684116) (xy 303.100741 -398.63884)
			(xy 303.088964 -398.591056) (xy 303.085004 -398.542002) (xy 301.541588 -398.542002) (xy 301.540644 -398.548468)
			(xy 301.521569 -398.612259) (xy 301.49344 -398.672608) (xy 301.475648 -398.700752) (xy 301.470603 -398.709277)
			(xy 301.466785 -398.728693) (xy 301.470598 -398.748111) (xy 301.475648 -398.756632) (xy 301.493423 -398.784783)
			(xy 301.521516 -398.845142) (xy 301.540586 -398.908929) (xy 301.550229 -398.974804) (xy 301.550832 -399.008092)
			(xy 301.550387 -399.037392) (xy 301.542941 -399.095515) (xy 301.528118 -399.152208) (xy 301.517558 -399.179542)
			(xy 301.513494 -399.189194) (xy 301.514002 -399.20926) (xy 301.551848 -399.295112) (xy 301.566326 -399.309082)
			(xy 301.576232 -399.312638) (xy 301.599601 -399.321818) (xy 301.643446 -399.346279) (xy 301.683091 -399.377085)
			(xy 301.717625 -399.413528) (xy 301.746254 -399.454773) (xy 301.768322 -399.49987) (xy 301.78332 -399.547784)
			(xy 301.790905 -399.597415) (xy 301.79137 -399.622518) (xy 301.79086 -399.648505) (xy 301.78273 -399.69984)
			(xy 301.766669 -399.74927) (xy 301.743073 -399.79558) (xy 301.712523 -399.837628) (xy 301.675772 -399.874379)
			(xy 301.633724 -399.904929) (xy 301.587414 -399.928525) (xy 301.537984 -399.944586) (xy 301.486649 -399.952716)
			(xy 301.434675 -399.952716) (xy 301.38334 -399.944586) (xy 301.33391 -399.928525) (xy 301.2876 -399.904929)
			(xy 301.245552 -399.874379) (xy 301.208801 -399.837628) (xy 301.178251 -399.79558) (xy 301.154655 -399.74927)
			(xy 301.138594 -399.69984) (xy 301.130464 -399.648505) (xy 301.129954 -399.622518) (xy 301.130056 -399.611307)
			(xy 301.131582 -399.588936) (xy 301.133002 -399.577814) (xy 301.134526 -399.5674) (xy 301.129192 -399.547842)
			(xy 301.071534 -399.473928) (xy 301.053754 -399.464276) (xy 301.04334 -399.463006) (xy 301.013155 -399.459184)
			(xy 300.954079 -399.444624) (xy 300.897454 -399.422363) (xy 300.844278 -399.392794) (xy 300.795491 -399.356439)
			(xy 300.751951 -399.313939) (xy 300.714428 -399.266044) (xy 300.683583 -399.213598) (xy 300.65996 -399.157528)
			(xy 300.643977 -399.098821) (xy 300.635915 -399.038514) (xy 300.635416 -399.008092) (xy 293.027819 -399.008092)
			(xy 293.012055 -399.060487) (xy 292.988383 -399.110984) (xy 292.95761 -399.157497) (xy 292.920393 -399.199034)
			(xy 292.877525 -399.234709) (xy 292.829919 -399.263763) (xy 292.77859 -399.285575) (xy 292.724633 -399.299681)
			(xy 292.669196 -399.305781) (xy 292.613462 -399.303744) (xy 292.558619 -399.293614) (xy 292.505835 -399.275607)
			(xy 292.456235 -399.250106) (xy 292.410877 -399.217655) (xy 292.370728 -399.178946) (xy 292.336642 -399.134803)
			(xy 292.309346 -399.086168) (xy 292.289423 -399.034077) (xy 292.277297 -398.97964) (xy 292.273226 -398.924018)
			(xy 289.426444 -398.924018) (xy 289.401626 -398.963124) (xy 289.360874 -399.012382) (xy 289.31427 -399.056143)
			(xy 289.262548 -399.093718) (xy 289.206525 -399.124515) (xy 289.147083 -399.148046) (xy 289.085161 -399.163942)
			(xy 289.021735 -399.171951) (xy 288.98977 -399.17243) (xy 288.95745 -399.171897) (xy 288.893332 -399.16369)
			(xy 288.830772 -399.147425) (xy 288.770776 -399.123365) (xy 288.714312 -399.091897) (xy 288.662291 -399.053528)
			(xy 288.615551 -399.008876) (xy 288.574844 -398.958663) (xy 288.540829 -398.903696) (xy 288.526982 -398.874488)
			(xy 288.521394 -398.86255) (xy 288.501074 -398.84731) (xy 288.390838 -398.831054) (xy 288.366962 -398.83969)
			(xy 288.358072 -398.849596) (xy 288.340853 -398.868684) (xy 288.303192 -398.903679) (xy 288.282888 -398.919446)
			(xy 288.274252 -398.92605) (xy 288.264092 -398.94383) (xy 288.253678 -399.038826) (xy 288.259774 -399.058384)
			(xy 288.266632 -399.066512) (xy 288.283378 -399.086834) (xy 288.311693 -399.131233) (xy 288.333631 -399.179103)
			(xy 288.348776 -399.229537) (xy 288.353246 -399.255488) (xy 288.355024 -399.26641) (xy 288.366962 -399.284698)
			(xy 288.449766 -399.33753) (xy 288.471356 -399.340578) (xy 288.482024 -399.33753) (xy 288.507939 -399.330514)
			(xy 288.561098 -399.322997) (xy 288.587942 -399.322544) (xy 288.615192 -399.323039) (xy 288.669137 -399.3308)
			(xy 288.721429 -399.346158) (xy 288.771003 -399.3688) (xy 288.816851 -399.398266) (xy 288.858039 -399.433957)
			(xy 288.89373 -399.475144) (xy 288.923197 -399.520992) (xy 288.94584 -399.570566) (xy 288.956101 -399.6055)
			(xy 297.438824 -399.6055) (xy 297.442895 -399.549878) (xy 297.455021 -399.495441) (xy 297.474944 -399.44335)
			(xy 297.50224 -399.394715) (xy 297.536326 -399.350572) (xy 297.576475 -399.311863) (xy 297.621833 -399.279412)
			(xy 297.671433 -399.253911) (xy 297.724217 -399.235904) (xy 297.77906 -399.225774) (xy 297.834794 -399.223737)
			(xy 297.890231 -399.229837) (xy 297.944188 -399.243943) (xy 297.995517 -399.265755) (xy 298.043123 -399.294809)
			(xy 298.085991 -399.330484) (xy 298.123208 -399.372021) (xy 298.153981 -399.418534) (xy 298.177653 -399.469031)
			(xy 298.193721 -399.522438) (xy 298.201841 -399.577614) (xy 298.20235 -399.6055) (xy 298.201841 -399.633386)
			(xy 298.193721 -399.688562) (xy 298.177653 -399.741969) (xy 298.153981 -399.792466) (xy 298.123208 -399.838979)
			(xy 298.085991 -399.880516) (xy 298.043123 -399.916191) (xy 297.995517 -399.945245) (xy 297.944188 -399.967057)
			(xy 297.890231 -399.981163) (xy 297.834794 -399.987263) (xy 297.77906 -399.985226) (xy 297.724217 -399.975096)
			(xy 297.671433 -399.957089) (xy 297.621833 -399.931588) (xy 297.576475 -399.899137) (xy 297.536326 -399.860428)
			(xy 297.50224 -399.816285) (xy 297.474944 -399.76765) (xy 297.455021 -399.715559) (xy 297.442895 -399.661122)
			(xy 297.438824 -399.6055) (xy 288.956101 -399.6055) (xy 288.961199 -399.622857) (xy 288.968961 -399.676802)
			(xy 288.96945 -399.704052) (xy 288.969226 -399.722459) (xy 288.965668 -399.7591) (xy 288.962338 -399.777204)
			(xy 288.960052 -399.78965) (xy 288.967164 -399.81378) (xy 289.044126 -399.891504) (xy 289.068256 -399.89887)
			(xy 289.080702 -399.896584) (xy 289.103793 -399.89253) (xy 289.150478 -399.888207) (xy 289.17392 -399.887948)
			(xy 289.20465 -399.888437) (xy 289.265661 -399.895847) (xy 289.325334 -399.910557) (xy 289.3828 -399.932351)
			(xy 289.437219 -399.960913) (xy 289.4878 -399.995825) (xy 289.533804 -400.036579) (xy 289.57456 -400.082581)
			(xy 289.609475 -400.13316) (xy 289.638039 -400.187579) (xy 289.659836 -400.245043) (xy 289.674549 -400.304715)
			(xy 289.681961 -400.365726) (xy 289.682428 -400.396456) (xy 289.681928 -400.42818) (xy 289.674017 -400.491134)
			(xy 289.658337 -400.552614) (xy 289.635132 -400.611668) (xy 289.604762 -400.667376) (xy 289.569228 -400.71675)
			(xy 302.163988 -400.71675) (xy 302.164377 -400.693516) (xy 302.170877 -400.647505) (xy 302.183755 -400.602857)
			(xy 302.202758 -400.560452) (xy 302.227512 -400.521127) (xy 302.24222 -400.503136) (xy 302.248316 -400.496024)
			(xy 302.254412 -400.479514) (xy 302.254412 -400.395186) (xy 302.248316 -400.378676) (xy 302.24222 -400.371564)
			(xy 302.22753 -400.35356) (xy 302.20278 -400.314235) (xy 302.183777 -400.271833) (xy 302.170894 -400.22719)
			(xy 302.164385 -400.181183) (xy 302.163988 -400.15795) (xy 302.164498 -400.131963) (xy 302.172628 -400.080628)
			(xy 302.188689 -400.031198) (xy 302.212285 -399.984888) (xy 302.242835 -399.94284) (xy 302.279586 -399.906089)
			(xy 302.321634 -399.875539) (xy 302.367944 -399.851943) (xy 302.417374 -399.835882) (xy 302.468709 -399.827752)
			(xy 302.520683 -399.827752) (xy 302.572018 -399.835882) (xy 302.621448 -399.851943) (xy 302.667758 -399.875539)
			(xy 302.709806 -399.906089) (xy 302.746557 -399.94284) (xy 302.777107 -399.984888) (xy 302.800703 -400.031198)
			(xy 302.816764 -400.080628) (xy 302.824894 -400.131963) (xy 302.825404 -400.15795) (xy 302.825017 -400.181184)
			(xy 302.818517 -400.227196) (xy 302.805638 -400.271843) (xy 302.786634 -400.314248) (xy 302.76188 -400.353574)
			(xy 302.747172 -400.371564) (xy 302.741076 -400.378676) (xy 302.73498 -400.395186) (xy 302.73498 -400.479514)
			(xy 302.741076 -400.496024) (xy 302.747172 -400.503136) (xy 302.761861 -400.521141) (xy 302.786611 -400.560465)
			(xy 302.805615 -400.602867) (xy 302.818498 -400.64751) (xy 302.825007 -400.693517) (xy 302.825404 -400.71675)
			(xy 302.824894 -400.742737) (xy 302.816764 -400.794072) (xy 302.800703 -400.843502) (xy 302.777107 -400.889812)
			(xy 302.746557 -400.93186) (xy 302.709806 -400.968611) (xy 302.667758 -400.999161) (xy 302.621448 -401.022757)
			(xy 302.572018 -401.038818) (xy 302.520683 -401.046948) (xy 302.468709 -401.046948) (xy 302.417374 -401.038818)
			(xy 302.367944 -401.022757) (xy 302.321634 -400.999161) (xy 302.279586 -400.968611) (xy 302.242835 -400.93186)
			(xy 302.212285 -400.889812) (xy 302.188689 -400.843502) (xy 302.172628 -400.794072) (xy 302.164498 -400.742737)
			(xy 302.163988 -400.71675) (xy 289.569228 -400.71675) (xy 289.567699 -400.718874) (xy 289.524518 -400.765362)
			(xy 289.475891 -400.806119) (xy 289.422571 -400.840511) (xy 289.365389 -400.868003) (xy 289.335464 -400.878548)
			(xy 289.32505 -400.882104) (xy 289.309302 -400.896582) (xy 289.270694 -400.987006) (xy 289.271202 -401.008342)
			(xy 289.275774 -401.018248) (xy 289.287296 -401.043829) (xy 289.303577 -401.097518) (xy 289.311831 -401.153011)
			(xy 289.31235 -401.181062) (xy 289.311864 -401.208313) (xy 289.304108 -401.262261) (xy 289.288753 -401.314556)
			(xy 289.266111 -401.364133) (xy 289.236645 -401.409983) (xy 289.200954 -401.451174) (xy 289.159763 -401.486865)
			(xy 289.113913 -401.516331) (xy 289.064336 -401.538973) (xy 289.012041 -401.554328) (xy 288.958093 -401.562084)
			(xy 288.903591 -401.562084) (xy 288.849643 -401.554328) (xy 288.797348 -401.538973) (xy 288.747771 -401.516331)
			(xy 288.701921 -401.486865) (xy 288.66073 -401.451174) (xy 288.625039 -401.409983) (xy 288.595573 -401.364133)
			(xy 288.572931 -401.314556) (xy 288.557576 -401.262261) (xy 288.54982 -401.208313) (xy 288.549334 -401.181062)
			(xy 288.549908 -401.152658) (xy 288.558342 -401.09648) (xy 288.575006 -401.042171) (xy 288.599529 -400.990929)
			(xy 288.631373 -400.943885) (xy 288.669833 -400.902076) (xy 288.714062 -400.866426) (xy 288.73831 -400.851624)
			(xy 288.747962 -400.846036) (xy 288.760154 -400.828764) (xy 288.779458 -400.732498) (xy 288.774886 -400.71167)
			(xy 288.768028 -400.70278) (xy 288.748615 -400.676228) (xy 288.716095 -400.619053) (xy 288.69122 -400.558162)
			(xy 288.674403 -400.494572) (xy 288.665927 -400.429344) (xy 288.665412 -400.396456) (xy 288.665866 -400.366758)
			(xy 288.672819 -400.30777) (xy 288.686592 -400.249993) (xy 288.6964 -400.221958) (xy 288.700718 -400.21002)
			(xy 288.697162 -400.185128) (xy 288.633408 -400.096228) (xy 288.610802 -400.085052) (xy 288.598102 -400.085306)
			(xy 288.587942 -400.08556) (xy 288.560903 -400.085119) (xy 288.507368 -400.077462) (xy 288.455451 -400.062323)
			(xy 288.406191 -400.040006) (xy 288.360575 -400.010959) (xy 288.319517 -399.975762) (xy 288.28384 -399.935121)
			(xy 288.254257 -399.88985) (xy 288.231362 -399.840856) (xy 288.215614 -399.78912) (xy 288.211006 -399.762472)
			(xy 288.209228 -399.75155) (xy 288.19729 -399.733262) (xy 288.114486 -399.68043) (xy 288.092896 -399.677382)
			(xy 288.082228 -399.68043) (xy 288.056311 -399.687437) (xy 288.003154 -399.694959) (xy 287.97631 -399.695416)
			(xy 287.949058 -399.694935) (xy 287.895108 -399.68718) (xy 287.842811 -399.671826) (xy 287.793231 -399.649185)
			(xy 287.747378 -399.619719) (xy 287.706186 -399.584027) (xy 287.670492 -399.542836) (xy 287.641024 -399.496985)
			(xy 287.618381 -399.447406) (xy 287.603024 -399.39511) (xy 287.595266 -399.34116) (xy 287.594802 -399.313908)
			(xy 287.595237 -399.286973) (xy 287.602832 -399.23364) (xy 287.617857 -399.181906) (xy 287.640013 -399.132802)
			(xy 287.66886 -399.087305) (xy 287.685988 -399.066512) (xy 287.692846 -399.058384) (xy 287.698942 -399.038826)
			(xy 287.688528 -398.94383) (xy 287.678368 -398.92605) (xy 287.669732 -398.919446) (xy 287.643256 -398.898816)
			(xy 287.59549 -398.85166) (xy 287.554346 -398.798627) (xy 287.52054 -398.74064) (xy 287.49466 -398.678708)
			(xy 287.477157 -398.613908) (xy 287.468335 -398.547369) (xy 287.467802 -398.513808) (xy 280.881582 -398.513808)
			(xy 280.881582 -399.463514) (xy 280.882007 -399.473584) (xy 280.889723 -399.492186) (xy 280.896568 -399.499582)
			(xy 283.664152 -402.267166) (xy 283.671054 -402.273515) (xy 283.688157 -402.281162) (xy 283.706868 -402.282127)
			(xy 283.724668 -402.276281) (xy 283.732224 -402.270722) (xy 283.752715 -402.2546) (xy 283.797264 -402.227511)
			(xy 283.845087 -402.206741) (xy 283.895293 -402.192677) (xy 283.946947 -402.185579) (xy 283.973016 -402.185124)
			(xy 284.002332 -402.185662) (xy 284.060272 -402.194638) (xy 284.116157 -402.212376) (xy 284.168668 -402.238458)
			(xy 284.216569 -402.272269) (xy 284.258731 -402.313013) (xy 284.29416 -402.35973) (xy 284.30855 -402.385276)
			(xy 284.313228 -402.393136) (xy 284.327003 -402.405151) (xy 284.344115 -402.411575) (xy 284.353254 -402.411946)
			(xy 289.709098 -402.411946) (xy 289.720716 -402.411368) (xy 289.741598 -402.40117) (xy 289.74923 -402.392388)
			(xy 289.805872 -402.319998) (xy 289.810698 -402.297138) (xy 289.80765 -402.285708) (xy 289.800515 -402.255218)
			(xy 289.79287 -402.193066) (xy 289.79241 -402.161756) (xy 289.792984 -402.127982) (xy 289.801968 -402.061034)
			(xy 289.819731 -401.995864) (xy 289.845961 -401.933616) (xy 289.880197 -401.875387) (xy 289.921838 -401.822201)
			(xy 289.97015 -401.774992) (xy 289.99688 -401.75434) (xy 290.004754 -401.748244) (xy 290.014914 -401.731734)
			(xy 290.0299 -401.643596) (xy 290.02609 -401.624546) (xy 290.020502 -401.616418) (xy 290.005372 -401.592798)
			(xy 289.981454 -401.54206) (xy 289.965216 -401.48837) (xy 289.957005 -401.432882) (xy 289.956494 -401.404836)
			(xy 289.95698 -401.377585) (xy 289.964736 -401.323637) (xy 289.980091 -401.271342) (xy 290.002733 -401.221765)
			(xy 290.032199 -401.175915) (xy 290.06789 -401.134724) (xy 290.109081 -401.099033) (xy 290.154931 -401.069567)
			(xy 290.204508 -401.046925) (xy 290.256803 -401.03157) (xy 290.310751 -401.023814) (xy 290.365253 -401.023814)
			(xy 290.419201 -401.03157) (xy 290.471496 -401.046925) (xy 290.521073 -401.069567) (xy 290.566923 -401.099033)
			(xy 290.608114 -401.134724) (xy 290.643805 -401.175915) (xy 290.673271 -401.221765) (xy 290.695913 -401.271342)
			(xy 290.711268 -401.323637) (xy 290.719024 -401.377585) (xy 290.71951 -401.404836) (xy 290.719057 -401.431008)
			(xy 290.711862 -401.482856) (xy 290.697654 -401.533236) (xy 290.676699 -401.581203) (xy 290.649388 -401.625859)
			(xy 290.63315 -401.64639) (xy 290.627054 -401.65401) (xy 290.621212 -401.672552) (xy 290.627816 -401.76196)
			(xy 290.636198 -401.779232) (xy 290.64331 -401.785836) (xy 290.665368 -401.806512) (xy 290.704927 -401.852236)
			(xy 290.738787 -401.902328) (xy 290.76647 -401.956079) (xy 290.787585 -402.012734) (xy 290.801836 -402.071492)
			(xy 290.80902 -402.131525) (xy 290.809426 -402.161756) (xy 290.808999 -402.193069) (xy 290.80136 -402.255225)
			(xy 290.794186 -402.285708) (xy 290.791138 -402.297138) (xy 290.795964 -402.319998) (xy 290.852606 -402.392388)
			(xy 290.86019 -402.401232) (xy 290.881101 -402.411447) (xy 290.892738 -402.411946) (xy 296.564812 -402.411946)
			(xy 296.570146 -402.410676) (xy 296.596744 -402.405299) (xy 296.650708 -402.399573) (xy 296.677842 -402.399246)
			(xy 296.70248 -402.399754) (xy 296.713148 -402.400262) (xy 296.733214 -402.392642) (xy 296.80154 -402.324824)
			(xy 296.809414 -402.304758) (xy 296.808906 -402.29409) (xy 296.808398 -402.272754) (xy 296.808865 -402.242025)
			(xy 296.816278 -402.181015) (xy 296.83099 -402.121344) (xy 296.852788 -402.063881) (xy 296.881353 -402.009465)
			(xy 296.916268 -401.958888) (xy 296.957025 -401.912888) (xy 297.003029 -401.872136) (xy 297.053609 -401.837226)
			(xy 297.108029 -401.808667) (xy 297.165494 -401.786875) (xy 297.225167 -401.772169) (xy 297.286177 -401.764762)
			(xy 297.316906 -401.764246) (xy 297.347601 -401.764725) (xy 297.408541 -401.772146) (xy 297.468146 -401.786845)
			(xy 297.52555 -401.808606) (xy 297.57992 -401.837115) (xy 297.60545 -401.854162) (xy 297.614202 -401.859633)
			(xy 297.634406 -401.863761) (xy 297.65461 -401.859633) (xy 297.663362 -401.854162) (xy 297.688888 -401.837104)
			(xy 297.743249 -401.808569) (xy 297.800653 -401.786793) (xy 297.860262 -401.772092) (xy 297.921208 -401.764683)
			(xy 297.951906 -401.764246) (xy 297.982601 -401.764725) (xy 298.043541 -401.772146) (xy 298.103146 -401.786845)
			(xy 298.16055 -401.808606) (xy 298.21492 -401.837115) (xy 298.24045 -401.854162) (xy 298.249202 -401.859633)
			(xy 298.269406 -401.863761) (xy 298.28961 -401.859633) (xy 298.298362 -401.854162) (xy 298.323888 -401.837104)
			(xy 298.378249 -401.808569) (xy 298.435653 -401.786793) (xy 298.495262 -401.772092) (xy 298.556208 -401.764683)
			(xy 298.586906 -401.764246) (xy 298.617601 -401.764725) (xy 298.678541 -401.772146) (xy 298.738146 -401.786845)
			(xy 298.79555 -401.808606) (xy 298.84992 -401.837115) (xy 298.87545 -401.854162) (xy 298.884202 -401.859633)
			(xy 298.904406 -401.863761) (xy 298.92461 -401.859633) (xy 298.933362 -401.854162) (xy 298.958888 -401.837104)
			(xy 299.013249 -401.808569) (xy 299.070653 -401.786793) (xy 299.130262 -401.772092) (xy 299.191208 -401.764683)
			(xy 299.221906 -401.764246) (xy 299.252638 -401.76471) (xy 299.313653 -401.772119) (xy 299.373331 -401.786828)
			(xy 299.430801 -401.808622) (xy 299.485224 -401.837185) (xy 299.535809 -401.872099) (xy 299.581817 -401.912855)
			(xy 299.622577 -401.958859) (xy 299.657494 -402.009441) (xy 299.686061 -402.063863) (xy 299.70786 -402.121331)
			(xy 299.722574 -402.181007) (xy 299.729988 -402.242022) (xy 299.730414 -402.272754) (xy 299.729398 -402.303996)
			(xy 299.72889 -402.314664) (xy 299.736002 -402.334222) (xy 299.793914 -402.395944) (xy 299.801363 -402.40317)
			(xy 299.820379 -402.411426) (xy 299.830744 -402.411946) (xy 299.841412 -402.411946) (xy 299.846746 -402.410676)
			(xy 299.873344 -402.405299) (xy 299.927308 -402.399573) (xy 299.954442 -402.399246) (xy 299.981576 -402.399568)
			(xy 300.035541 -402.405293) (xy 300.062138 -402.410676) (xy 300.067472 -402.411946) (xy 303.384712 -402.411946)
			(xy 303.395132 -402.411434) (xy 303.414264 -402.403165) (xy 303.421796 -402.395944) (xy 303.479708 -402.334476)
			(xy 303.48682 -402.314664) (xy 303.486058 -402.30425) (xy 303.48555 -402.284438) (xy 303.486098 -402.256949)
			(xy 303.495194 -402.202728) (xy 303.513124 -402.150756) (xy 303.539397 -402.102461) (xy 303.555908 -402.080476)
			(xy 303.56175 -402.07311) (xy 303.567084 -402.05533) (xy 303.56175 -401.969224) (xy 303.55413 -401.95246)
			(xy 303.547526 -401.945856) (xy 303.526505 -401.924223) (xy 303.490871 -401.875557) (xy 303.463337 -401.821891)
			(xy 303.444589 -401.764562) (xy 303.435094 -401.704997) (xy 303.434496 -401.674838) (xy 303.434496 -400.811238)
			(xy 303.434939 -400.78488) (xy 303.442195 -400.732666) (xy 303.456575 -400.68195) (xy 303.477804 -400.633698)
			(xy 303.505478 -400.58883) (xy 303.539068 -400.548203) (xy 303.558194 -400.53006) (xy 303.565306 -400.52371)
			(xy 303.573434 -400.506946) (xy 303.581816 -400.420332) (xy 303.576736 -400.402552) (xy 303.571148 -400.394678)
			(xy 303.556991 -400.374833) (xy 303.534505 -400.331585) (xy 303.519187 -400.28531) (xy 303.511428 -400.237186)
			(xy 303.51095 -400.212814) (xy 303.511472 -400.187559) (xy 303.519785 -400.137737) (xy 303.536186 -400.089963)
			(xy 303.560227 -400.04554) (xy 303.591251 -400.00568) (xy 303.628413 -399.97147) (xy 303.670699 -399.943844)
			(xy 303.716955 -399.923554) (xy 303.76592 -399.911154) (xy 303.816258 -399.906983) (xy 303.866596 -399.911154)
			(xy 303.915561 -399.923554) (xy 303.961817 -399.943844) (xy 304.004103 -399.97147) (xy 304.041265 -400.00568)
			(xy 304.072289 -400.04554) (xy 304.09633 -400.089963) (xy 304.112731 -400.137737) (xy 304.121044 -400.187559)
			(xy 304.121566 -400.212814) (xy 304.121068 -400.237184) (xy 304.113288 -400.2853) (xy 304.097977 -400.331573)
			(xy 304.075521 -400.374833) (xy 304.061368 -400.394678) (xy 304.05578 -400.402552) (xy 304.0507 -400.420332)
			(xy 304.059082 -400.506946) (xy 304.06721 -400.52371) (xy 304.074322 -400.53006) (xy 304.093446 -400.548201)
			(xy 304.127022 -400.588837) (xy 304.154685 -400.633708) (xy 304.175909 -400.681959) (xy 304.190289 -400.732672)
			(xy 304.197553 -400.784882) (xy 304.19802 -400.811238) (xy 304.19802 -401.674838) (xy 304.197453 -401.704999)
			(xy 304.187965 -401.764571) (xy 304.169217 -401.821905) (xy 304.141675 -401.875573) (xy 304.106027 -401.924236)
			(xy 304.08499 -401.945856) (xy 304.078386 -401.95246) (xy 304.070766 -401.969224) (xy 304.065432 -402.05533)
			(xy 304.070766 -402.07311) (xy 304.076608 -402.080476) (xy 304.09313 -402.102453) (xy 304.119404 -402.150747)
			(xy 304.137325 -402.202723) (xy 304.146399 -402.256948) (xy 304.146966 -402.284438) (xy 304.146458 -402.30425)
			(xy 304.145696 -402.314664) (xy 304.152808 -402.334476) (xy 304.21072 -402.395944) (xy 304.218222 -402.403206)
			(xy 304.237374 -402.411462) (xy 304.247804 -402.411946) (xy 304.584608 -402.411946) (xy 304.595028 -402.411435)
			(xy 304.614161 -402.403166) (xy 304.621692 -402.395944) (xy 304.679604 -402.334476) (xy 304.686716 -402.314664)
			(xy 304.685954 -402.30425) (xy 304.685446 -402.284438) (xy 304.685994 -402.256949) (xy 304.69509 -402.202728)
			(xy 304.71302 -402.150756) (xy 304.739292 -402.102461) (xy 304.755804 -402.080476) (xy 304.761646 -402.07311)
			(xy 304.76698 -402.05533) (xy 304.761646 -401.969224) (xy 304.754026 -401.95246) (xy 304.747422 -401.945856)
			(xy 304.726401 -401.924223) (xy 304.690768 -401.875557) (xy 304.663234 -401.821891) (xy 304.644486 -401.764561)
			(xy 304.634991 -401.704996) (xy 304.634392 -401.674838) (xy 304.634392 -400.811238) (xy 304.634835 -400.78488)
			(xy 304.642091 -400.732666) (xy 304.656471 -400.68195) (xy 304.6777 -400.633698) (xy 304.705374 -400.58883)
			(xy 304.738964 -400.548202) (xy 304.75809 -400.53006) (xy 304.765202 -400.523456) (xy 304.773584 -400.506946)
			(xy 304.781712 -400.420078) (xy 304.776886 -400.402298) (xy 304.771044 -400.394678) (xy 304.756939 -400.374813)
			(xy 304.734548 -400.331546) (xy 304.719302 -400.285276) (xy 304.711588 -400.237173) (xy 304.7111 -400.212814)
			(xy 304.711622 -400.187559) (xy 304.719935 -400.137737) (xy 304.736336 -400.089963) (xy 304.760377 -400.04554)
			(xy 304.791401 -400.00568) (xy 304.828563 -399.97147) (xy 304.870849 -399.943844) (xy 304.917105 -399.923554)
			(xy 304.96607 -399.911154) (xy 305.016408 -399.906983) (xy 305.066746 -399.911154) (xy 305.115711 -399.923554)
			(xy 305.161967 -399.943844) (xy 305.204253 -399.97147) (xy 305.241415 -400.00568) (xy 305.272439 -400.04554)
			(xy 305.29648 -400.089963) (xy 305.312881 -400.137737) (xy 305.321194 -400.187559) (xy 305.321716 -400.212814)
			(xy 305.321238 -400.237216) (xy 305.313479 -400.285399) (xy 305.298162 -400.331737) (xy 305.275676 -400.375051)
			(xy 305.261518 -400.394932) (xy 305.25593 -400.402552) (xy 305.25085 -400.420332) (xy 305.258978 -400.5072)
			(xy 305.26736 -400.52371) (xy 305.274472 -400.530314) (xy 305.293567 -400.548446) (xy 305.327088 -400.589054)
			(xy 305.354705 -400.633887) (xy 305.375893 -400.682093) (xy 305.390249 -400.732755) (xy 305.397501 -400.78491)
			(xy 305.397916 -400.811238) (xy 305.397916 -401.674838) (xy 305.397349 -401.704999) (xy 305.387861 -401.764571)
			(xy 305.369112 -401.821905) (xy 305.341571 -401.875573) (xy 305.305923 -401.924235) (xy 305.284886 -401.945856)
			(xy 305.278282 -401.95246) (xy 305.270662 -401.969224) (xy 305.265328 -402.05533) (xy 305.270662 -402.07311)
			(xy 305.276504 -402.080476) (xy 305.293026 -402.102453) (xy 305.319301 -402.150747) (xy 305.337222 -402.202723)
			(xy 305.346296 -402.256948) (xy 305.346862 -402.284438) (xy 305.346354 -402.30425) (xy 305.345592 -402.314664)
			(xy 305.352704 -402.334476) (xy 305.410616 -402.395944) (xy 305.418117 -402.403206) (xy 305.43727 -402.411464)
			(xy 305.4477 -402.411946) (xy 305.783996 -402.411946) (xy 305.794065 -402.411522) (xy 305.812666 -402.403803)
			(xy 305.820064 -402.39696) (xy 305.877976 -402.339048) (xy 305.885596 -402.320252) (xy 305.885596 -402.310346)
			(xy 305.885971 -402.286898) (xy 305.892524 -402.240462) (xy 305.905561 -402.195415) (xy 305.924822 -402.152657)
			(xy 305.949921 -402.113044) (xy 305.964844 -402.094954) (xy 305.971448 -402.087334) (xy 305.977544 -402.069046)
			(xy 305.97221 -401.978876) (xy 305.964082 -401.96135) (xy 305.956716 -401.954492) (xy 305.937846 -401.936365)
			(xy 305.904744 -401.89584) (xy 305.877485 -401.851176) (xy 305.85658 -401.803208) (xy 305.84242 -401.752835)
			(xy 305.83527 -401.701001) (xy 305.834796 -401.674838) (xy 305.834796 -400.811238) (xy 305.835236 -400.784891)
			(xy 305.842475 -400.732697) (xy 305.856821 -400.681994) (xy 305.878002 -400.633744) (xy 305.905614 -400.588865)
			(xy 305.939135 -400.548208) (xy 305.95824 -400.53006) (xy 305.965352 -400.52371) (xy 305.97348 -400.506946)
			(xy 305.981862 -400.420332) (xy 305.976782 -400.402552) (xy 305.971194 -400.394678) (xy 305.957035 -400.374834)
			(xy 305.934545 -400.331586) (xy 305.919225 -400.285311) (xy 305.911465 -400.237187) (xy 305.910996 -400.212814)
			(xy 305.911518 -400.187559) (xy 305.919831 -400.137737) (xy 305.936232 -400.089963) (xy 305.960273 -400.04554)
			(xy 305.991297 -400.00568) (xy 306.028459 -399.97147) (xy 306.070745 -399.943844) (xy 306.117001 -399.923554)
			(xy 306.165966 -399.911154) (xy 306.216304 -399.906983) (xy 306.266642 -399.911154) (xy 306.315607 -399.923554)
			(xy 306.361863 -399.943844) (xy 306.404149 -399.97147) (xy 306.441311 -400.00568) (xy 306.472335 -400.04554)
			(xy 306.496376 -400.089963) (xy 306.512777 -400.137737) (xy 306.52109 -400.187559) (xy 306.521612 -400.212814)
			(xy 306.521113 -400.237184) (xy 306.513333 -400.285299) (xy 306.498019 -400.331571) (xy 306.47556 -400.374828)
			(xy 306.461414 -400.394678) (xy 306.455826 -400.402552) (xy 306.450746 -400.420332) (xy 306.459128 -400.506946)
			(xy 306.467256 -400.52371) (xy 306.474368 -400.53006) (xy 306.49346 -400.54822) (xy 306.526973 -400.588879)
			(xy 306.554581 -400.633758) (xy 306.575762 -400.682004) (xy 306.590112 -400.732703) (xy 306.59736 -400.784893)
			(xy 306.597812 -400.811238) (xy 306.597812 -401.674838) (xy 306.597385 -401.701004) (xy 306.590243 -401.752846)
			(xy 306.576083 -401.803226) (xy 306.555172 -401.851199) (xy 306.527902 -401.895864) (xy 306.494785 -401.936384)
			(xy 306.475892 -401.954492) (xy 306.468526 -401.96135) (xy 306.460398 -401.978876) (xy 306.455064 -402.069046)
			(xy 306.46116 -402.087334) (xy 306.467764 -402.094954) (xy 306.48269 -402.113044) (xy 306.507818 -402.152644)
			(xy 306.527092 -402.1954) (xy 306.540125 -402.240453) (xy 306.546654 -402.286895) (xy 306.547012 -402.310346)
			(xy 306.547012 -402.320252) (xy 306.554632 -402.339048) (xy 306.612544 -402.39696) (xy 306.619943 -402.403804)
			(xy 306.638542 -402.411528) (xy 306.648612 -402.411946) (xy 306.98694 -402.411946) (xy 306.997758 -402.411514)
			(xy 307.017512 -402.402707) (xy 307.02504 -402.394928) (xy 307.082698 -402.329904) (xy 307.089048 -402.309076)
			(xy 307.087778 -402.298408) (xy 307.08669 -402.288602) (xy 307.085548 -402.268904) (xy 307.085492 -402.259038)
			(xy 307.085991 -402.233257) (xy 307.094006 -402.182321) (xy 307.109831 -402.133248) (xy 307.133082 -402.087226)
			(xy 307.147722 -402.065998) (xy 307.152802 -402.058886) (xy 307.157628 -402.041868) (xy 307.15204 -401.959572)
			(xy 307.144928 -401.94357) (xy 307.138832 -401.936966) (xy 307.119379 -401.91558) (xy 307.086491 -401.868037)
			(xy 307.061146 -401.816079) (xy 307.043924 -401.760894) (xy 307.035218 -401.703743) (xy 307.034692 -401.674838)
			(xy 307.034692 -400.811238) (xy 307.035132 -400.784891) (xy 307.042371 -400.732697) (xy 307.056717 -400.681994)
			(xy 307.077897 -400.633744) (xy 307.10551 -400.588864) (xy 307.13903 -400.548207) (xy 307.158136 -400.53006)
			(xy 307.165248 -400.52371) (xy 307.173376 -400.506946) (xy 307.181758 -400.420332) (xy 307.176678 -400.402552)
			(xy 307.17109 -400.394678) (xy 307.156931 -400.374834) (xy 307.134442 -400.331586) (xy 307.119122 -400.285311)
			(xy 307.111362 -400.237187) (xy 307.110892 -400.212814) (xy 307.111414 -400.187559) (xy 307.119727 -400.137737)
			(xy 307.136128 -400.089963) (xy 307.160169 -400.04554) (xy 307.191193 -400.00568) (xy 307.228355 -399.97147)
			(xy 307.270641 -399.943844) (xy 307.316897 -399.923554) (xy 307.365862 -399.911154) (xy 307.4162 -399.906983)
			(xy 307.466538 -399.911154) (xy 307.515503 -399.923554) (xy 307.561759 -399.943844) (xy 307.604045 -399.97147)
			(xy 307.641207 -400.00568) (xy 307.672231 -400.04554) (xy 307.696272 -400.089963) (xy 307.712673 -400.137737)
			(xy 307.720986 -400.187559) (xy 307.721508 -400.212814) (xy 307.721009 -400.237184) (xy 307.713229 -400.285299)
			(xy 307.697915 -400.331571) (xy 307.675455 -400.374828) (xy 307.66131 -400.394678) (xy 307.655722 -400.402552)
			(xy 307.650642 -400.420332) (xy 307.659024 -400.506946) (xy 307.667152 -400.52371) (xy 307.674264 -400.53006)
			(xy 307.693356 -400.54822) (xy 307.726869 -400.588879) (xy 307.754478 -400.633757) (xy 307.775659 -400.682004)
			(xy 307.790009 -400.732703) (xy 307.797257 -400.784893) (xy 307.797708 -400.811238) (xy 307.797708 -401.674838)
			(xy 307.7972 -401.703747) (xy 307.788524 -401.76091) (xy 307.771314 -401.816107) (xy 307.745966 -401.868072)
			(xy 307.713062 -401.915613) (xy 307.693568 -401.936966) (xy 307.687472 -401.94357) (xy 307.68036 -401.959572)
			(xy 307.674772 -402.041868) (xy 307.679598 -402.058886) (xy 307.684678 -402.065998) (xy 307.69934 -402.087212)
			(xy 307.7226 -402.133235) (xy 307.738426 -402.182313) (xy 307.746434 -402.233255) (xy 307.746908 -402.259038)
			(xy 307.74685 -402.268904) (xy 307.745705 -402.288602) (xy 307.744622 -402.298408) (xy 307.743352 -402.309076)
			(xy 307.749702 -402.329904) (xy 307.80736 -402.394928) (xy 307.814931 -402.402645) (xy 307.83466 -402.411436)
			(xy 307.84546 -402.411946) (xy 308.184042 -402.411946) (xy 308.194108 -402.411514) (xy 308.212696 -402.403783)
			(xy 308.22011 -402.39696) (xy 308.278022 -402.339048) (xy 308.285642 -402.320252) (xy 308.285642 -402.310346)
			(xy 308.286017 -402.286898) (xy 308.292571 -402.240463) (xy 308.305609 -402.195417) (xy 308.324872 -402.152661)
			(xy 308.349974 -402.11305) (xy 308.36489 -402.094954) (xy 308.371494 -402.087334) (xy 308.37759 -402.069046)
			(xy 308.372256 -401.978876) (xy 308.364128 -401.96135) (xy 308.356762 -401.954492) (xy 308.337862 -401.936378)
			(xy 308.304699 -401.895873) (xy 308.27738 -401.851217) (xy 308.256417 -401.803248) (xy 308.242204 -401.752865)
			(xy 308.235007 -401.701012) (xy 308.234588 -401.674838) (xy 308.234588 -400.811238) (xy 308.235031 -400.78488)
			(xy 308.242287 -400.732666) (xy 308.256667 -400.68195) (xy 308.277896 -400.633697) (xy 308.305569 -400.588829)
			(xy 308.339159 -400.548201) (xy 308.358286 -400.53006) (xy 308.365398 -400.52371) (xy 308.373526 -400.506946)
			(xy 308.381908 -400.420332) (xy 308.376828 -400.402552) (xy 308.37124 -400.394678) (xy 308.357083 -400.374833)
			(xy 308.334598 -400.331585) (xy 308.31928 -400.285309) (xy 308.311522 -400.237186) (xy 308.311042 -400.212814)
			(xy 308.311564 -400.187559) (xy 308.319877 -400.137737) (xy 308.336278 -400.089963) (xy 308.360319 -400.04554)
			(xy 308.391343 -400.00568) (xy 308.428505 -399.97147) (xy 308.470791 -399.943844) (xy 308.517047 -399.923554)
			(xy 308.566012 -399.911154) (xy 308.61635 -399.906983) (xy 308.666688 -399.911154) (xy 308.715653 -399.923554)
			(xy 308.761909 -399.943844) (xy 308.804195 -399.97147) (xy 308.841357 -400.00568) (xy 308.872381 -400.04554)
			(xy 308.896422 -400.089963) (xy 308.912823 -400.137737) (xy 308.921136 -400.187559) (xy 308.921658 -400.212814)
			(xy 308.92116 -400.237184) (xy 308.91338 -400.2853) (xy 308.898068 -400.331573) (xy 308.875612 -400.374832)
			(xy 308.86146 -400.394678) (xy 308.855872 -400.402552) (xy 308.850792 -400.420332) (xy 308.859174 -400.506946)
			(xy 308.867302 -400.52371) (xy 308.874414 -400.53006) (xy 308.893539 -400.548201) (xy 308.927115 -400.588837)
			(xy 308.954779 -400.633708) (xy 308.976003 -400.681959) (xy 308.990384 -400.732672) (xy 308.997648 -400.784882)
			(xy 308.998112 -400.811238) (xy 308.998112 -401.674838) (xy 308.997664 -401.701012) (xy 308.990478 -401.752865)
			(xy 308.976274 -401.80325) (xy 308.955318 -401.85122) (xy 308.928003 -401.895878) (xy 308.894842 -401.936383)
			(xy 308.875938 -401.954492) (xy 308.868572 -401.96135) (xy 308.860444 -401.978876) (xy 308.85511 -402.069046)
			(xy 308.861206 -402.087334) (xy 308.86781 -402.094954) (xy 308.882739 -402.113043) (xy 308.907871 -402.152642)
			(xy 308.927148 -402.195398) (xy 308.940183 -402.240451) (xy 308.946713 -402.286895) (xy 308.947058 -402.310346)
			(xy 308.947058 -402.320252) (xy 308.954678 -402.339048) (xy 309.01259 -402.39696) (xy 309.019986 -402.403812)
			(xy 309.038584 -402.411557) (xy 309.048658 -402.411946) (xy 309.383938 -402.411946) (xy 309.394004 -402.411514)
			(xy 309.412593 -402.403784) (xy 309.420006 -402.39696) (xy 309.477918 -402.339048) (xy 309.485538 -402.320252)
			(xy 309.485538 -402.310346) (xy 309.485913 -402.286898) (xy 309.492467 -402.240463) (xy 309.505505 -402.195417)
			(xy 309.524768 -402.152661) (xy 309.549869 -402.113049) (xy 309.564786 -402.094954) (xy 309.57139 -402.087334)
			(xy 309.577486 -402.069046) (xy 309.572152 -401.978876) (xy 309.564024 -401.96135) (xy 309.556658 -401.954492)
			(xy 309.537758 -401.936378) (xy 309.504596 -401.895873) (xy 309.477277 -401.851217) (xy 309.456314 -401.803248)
			(xy 309.442101 -401.752865) (xy 309.434904 -401.701012) (xy 309.434484 -401.674838) (xy 309.434484 -400.811238)
			(xy 309.434927 -400.78488) (xy 309.442183 -400.732666) (xy 309.456563 -400.681949) (xy 309.477791 -400.633697)
			(xy 309.505464 -400.588829) (xy 309.539054 -400.5482) (xy 309.558182 -400.53006) (xy 309.565294 -400.52371)
			(xy 309.573422 -400.506946) (xy 309.581804 -400.420332) (xy 309.576724 -400.402552) (xy 309.571136 -400.394678)
			(xy 309.556979 -400.374833) (xy 309.534494 -400.331585) (xy 309.519177 -400.285309) (xy 309.511419 -400.237186)
			(xy 309.510938 -400.212814) (xy 309.51146 -400.187559) (xy 309.519773 -400.137737) (xy 309.536174 -400.089963)
			(xy 309.560215 -400.04554) (xy 309.591239 -400.00568) (xy 309.628401 -399.97147) (xy 309.670687 -399.943844)
			(xy 309.716943 -399.923554) (xy 309.765908 -399.911154) (xy 309.816246 -399.906983) (xy 309.866584 -399.911154)
			(xy 309.915549 -399.923554) (xy 309.961805 -399.943844) (xy 310.004091 -399.97147) (xy 310.041253 -400.00568)
			(xy 310.072277 -400.04554) (xy 310.096318 -400.089963) (xy 310.112719 -400.137737) (xy 310.121032 -400.187559)
			(xy 310.121554 -400.212814) (xy 310.121056 -400.237184) (xy 310.113276 -400.2853) (xy 310.097964 -400.331573)
			(xy 310.075507 -400.374832) (xy 310.061356 -400.394678) (xy 310.055768 -400.402552) (xy 310.050688 -400.420332)
			(xy 310.05907 -400.506946) (xy 310.067198 -400.52371) (xy 310.07431 -400.53006) (xy 310.093435 -400.548201)
			(xy 310.127011 -400.588837) (xy 310.154675 -400.633707) (xy 310.1759 -400.681958) (xy 310.190281 -400.732672)
			(xy 310.197545 -400.784882) (xy 310.198008 -400.811238) (xy 310.198008 -401.674838) (xy 310.19756 -401.701012)
			(xy 310.190374 -401.752865) (xy 310.17617 -401.803249) (xy 310.155213 -401.85122) (xy 310.127898 -401.895877)
			(xy 310.094737 -401.936382) (xy 310.075834 -401.954492) (xy 310.068468 -401.96135) (xy 310.06034 -401.978876)
			(xy 310.055006 -402.069046) (xy 310.061102 -402.087334) (xy 310.067706 -402.094954) (xy 310.082635 -402.113043)
			(xy 310.107767 -402.152642) (xy 310.127044 -402.195398) (xy 310.140079 -402.240451) (xy 310.14661 -402.286895)
			(xy 310.146954 -402.310346) (xy 310.146954 -402.320252) (xy 310.154574 -402.339048) (xy 310.212486 -402.39696)
			(xy 310.219887 -402.403797) (xy 310.238486 -402.411507) (xy 310.248554 -402.411946) (xy 310.587136 -402.411946)
			(xy 310.597954 -402.411515) (xy 310.61771 -402.402709) (xy 310.625236 -402.394928) (xy 310.682894 -402.329904)
			(xy 310.689244 -402.309076) (xy 310.687974 -402.298408) (xy 310.686886 -402.288602) (xy 310.685744 -402.268904)
			(xy 310.685688 -402.259038) (xy 310.686187 -402.233257) (xy 310.694201 -402.182321) (xy 310.710026 -402.133247)
			(xy 310.733278 -402.087225) (xy 310.747918 -402.065998) (xy 310.752998 -402.058886) (xy 310.757824 -402.041868)
			(xy 310.752236 -401.959572) (xy 310.745124 -401.94357) (xy 310.739028 -401.936966) (xy 310.719575 -401.91558)
			(xy 310.686688 -401.868036) (xy 310.661343 -401.816078) (xy 310.644121 -401.760893) (xy 310.635415 -401.703743)
			(xy 310.634888 -401.674838) (xy 310.634888 -400.811238) (xy 310.635328 -400.784891) (xy 310.642567 -400.732697)
			(xy 310.656913 -400.681993) (xy 310.678093 -400.633744) (xy 310.705705 -400.588864) (xy 310.739226 -400.548206)
			(xy 310.758332 -400.53006) (xy 310.765444 -400.52371) (xy 310.773572 -400.506946) (xy 310.781954 -400.420332)
			(xy 310.776874 -400.402552) (xy 310.771286 -400.394678) (xy 310.757127 -400.374834) (xy 310.734638 -400.331586)
			(xy 310.719319 -400.285311) (xy 310.711559 -400.237187) (xy 310.711088 -400.212814) (xy 310.71161 -400.187559)
			(xy 310.719923 -400.137737) (xy 310.736324 -400.089963) (xy 310.760365 -400.04554) (xy 310.791389 -400.00568)
			(xy 310.828551 -399.97147) (xy 310.870837 -399.943844) (xy 310.917093 -399.923554) (xy 310.966058 -399.911154)
			(xy 311.016396 -399.906983) (xy 311.066734 -399.911154) (xy 311.115699 -399.923554) (xy 311.161955 -399.943844)
			(xy 311.204241 -399.97147) (xy 311.241403 -400.00568) (xy 311.272427 -400.04554) (xy 311.296468 -400.089963)
			(xy 311.312869 -400.137737) (xy 311.321182 -400.187559) (xy 311.321704 -400.212814) (xy 311.321205 -400.237184)
			(xy 311.313425 -400.285299) (xy 311.298111 -400.331571) (xy 311.275651 -400.374828) (xy 311.261506 -400.394678)
			(xy 311.255918 -400.402552) (xy 311.250838 -400.420332) (xy 311.25922 -400.506946) (xy 311.267348 -400.52371)
			(xy 311.27446 -400.53006) (xy 311.293552 -400.548219) (xy 311.327066 -400.588879) (xy 311.354675 -400.633757)
			(xy 311.375856 -400.682004) (xy 311.390206 -400.732703) (xy 311.397455 -400.784893) (xy 311.397904 -400.811238)
			(xy 311.397904 -401.674838) (xy 311.397396 -401.703747) (xy 311.388719 -401.76091) (xy 311.37151 -401.816107)
			(xy 311.346162 -401.868072) (xy 311.313258 -401.915613) (xy 311.293764 -401.936966) (xy 311.287668 -401.94357)
			(xy 311.280556 -401.959572) (xy 311.274968 -402.041868) (xy 311.279794 -402.058886) (xy 311.284874 -402.065998)
			(xy 311.299536 -402.087212) (xy 311.322797 -402.133235) (xy 311.338623 -402.182313) (xy 311.34663 -402.233255)
			(xy 311.347104 -402.259038) (xy 311.347046 -402.268904) (xy 311.345901 -402.288602) (xy 311.344818 -402.298408)
			(xy 311.343548 -402.309076) (xy 311.349898 -402.329904) (xy 311.407556 -402.394928) (xy 311.415127 -402.402645)
			(xy 311.434856 -402.411438) (xy 311.445656 -402.411946) (xy 311.784746 -402.411946) (xy 311.795172 -402.411446)
			(xy 311.814322 -402.403194) (xy 311.82183 -402.395944) (xy 311.879742 -402.334476) (xy 311.886854 -402.314664)
			(xy 311.886092 -402.30425) (xy 311.885584 -402.284438) (xy 311.886133 -402.256949) (xy 311.895229 -402.202729)
			(xy 311.913161 -402.150758) (xy 311.939436 -402.102465) (xy 311.955942 -402.080476) (xy 311.961784 -402.07311)
			(xy 311.967118 -402.05533) (xy 311.961784 -401.969224) (xy 311.954164 -401.95246) (xy 311.94756 -401.945856)
			(xy 311.926563 -401.924213) (xy 311.890979 -401.875533) (xy 311.863493 -401.821864) (xy 311.844789 -401.76454)
			(xy 311.835332 -401.704987) (xy 311.834784 -401.674838) (xy 311.834784 -400.811238) (xy 311.835224 -400.784891)
			(xy 311.842463 -400.732697) (xy 311.856808 -400.681993) (xy 311.877989 -400.633743) (xy 311.905601 -400.588863)
			(xy 311.939121 -400.548205) (xy 311.958228 -400.53006) (xy 311.96534 -400.52371) (xy 311.973468 -400.506946)
			(xy 311.98185 -400.420332) (xy 311.97677 -400.402552) (xy 311.971182 -400.394678) (xy 311.957024 -400.374834)
			(xy 311.934535 -400.331586) (xy 311.919215 -400.28531) (xy 311.911456 -400.237187) (xy 311.910984 -400.212814)
			(xy 311.911506 -400.187559) (xy 311.919819 -400.137737) (xy 311.93622 -400.089963) (xy 311.960261 -400.04554)
			(xy 311.991285 -400.00568) (xy 312.028447 -399.97147) (xy 312.070733 -399.943844) (xy 312.116989 -399.923554)
			(xy 312.165954 -399.911154) (xy 312.216292 -399.906983) (xy 312.26663 -399.911154) (xy 312.315595 -399.923554)
			(xy 312.361851 -399.943844) (xy 312.404137 -399.97147) (xy 312.441299 -400.00568) (xy 312.472323 -400.04554)
			(xy 312.496364 -400.089963) (xy 312.512765 -400.137737) (xy 312.521078 -400.187559) (xy 312.5216 -400.212814)
			(xy 312.521101 -400.237184) (xy 312.513321 -400.285299) (xy 312.498006 -400.33157) (xy 312.475546 -400.374827)
			(xy 312.461402 -400.394678) (xy 312.455814 -400.402552) (xy 312.450734 -400.420332) (xy 312.459116 -400.506946)
			(xy 312.467244 -400.52371) (xy 312.474356 -400.53006) (xy 312.493448 -400.548219) (xy 312.526962 -400.588878)
			(xy 312.554572 -400.633757) (xy 312.575753 -400.682003) (xy 312.590104 -400.732702) (xy 312.597352 -400.784893)
			(xy 312.5978 -400.811238) (xy 312.5978 -401.674838) (xy 312.597249 -401.704987) (xy 312.5878 -401.76454)
			(xy 312.569095 -401.821863) (xy 312.541602 -401.875528) (xy 312.506005 -401.924197) (xy 312.485024 -401.945856)
			(xy 312.47842 -401.95246) (xy 312.4708 -401.969224) (xy 312.465466 -402.05533) (xy 312.4708 -402.07311)
			(xy 312.476642 -402.080476) (xy 312.493167 -402.102452) (xy 312.519446 -402.150745) (xy 312.537371 -402.202721)
			(xy 312.546447 -402.256948) (xy 312.547 -402.284438) (xy 312.546492 -402.30425) (xy 312.54573 -402.314664)
			(xy 312.552842 -402.334476) (xy 312.610754 -402.395944) (xy 312.618258 -402.4032) (xy 312.63741 -402.411444)
			(xy 312.647838 -402.411946) (xy 312.984134 -402.411946) (xy 312.9942 -402.411515) (xy 313.012791 -402.403786)
			(xy 313.020202 -402.39696) (xy 313.078114 -402.339048) (xy 313.085734 -402.320252) (xy 313.085734 -402.310346)
			(xy 313.086109 -402.286898) (xy 313.092663 -402.240463) (xy 313.105701 -402.195417) (xy 313.124963 -402.15266)
			(xy 313.150065 -402.113049) (xy 313.164982 -402.094954) (xy 313.171586 -402.087334) (xy 313.177682 -402.069046)
			(xy 313.172348 -401.978876) (xy 313.16422 -401.96135) (xy 313.156854 -401.954492) (xy 313.137955 -401.936378)
			(xy 313.104792 -401.895873) (xy 313.077474 -401.851217) (xy 313.056511 -401.803248) (xy 313.042299 -401.752865)
			(xy 313.035102 -401.701012) (xy 313.03468 -401.674838) (xy 313.03468 -400.811238) (xy 313.035145 -400.784915)
			(xy 313.042422 -400.732773) (xy 313.056788 -400.682124) (xy 313.077971 -400.633927) (xy 313.10557 -400.589094)
			(xy 313.139063 -400.548475) (xy 313.158124 -400.530314) (xy 313.165236 -400.52371) (xy 313.173618 -400.5072)
			(xy 313.181746 -400.420332) (xy 313.176666 -400.402552) (xy 313.171078 -400.394932) (xy 313.156915 -400.375054)
			(xy 313.134421 -400.33174) (xy 313.119099 -400.285402) (xy 313.111338 -400.237217) (xy 313.11088 -400.212814)
			(xy 313.111402 -400.187559) (xy 313.119715 -400.137737) (xy 313.136116 -400.089963) (xy 313.160157 -400.04554)
			(xy 313.191181 -400.00568) (xy 313.228343 -399.97147) (xy 313.270629 -399.943844) (xy 313.316885 -399.923554)
			(xy 313.36585 -399.911154) (xy 313.416188 -399.906983) (xy 313.466526 -399.911154) (xy 313.515491 -399.923554)
			(xy 313.561747 -399.943844) (xy 313.604033 -399.97147) (xy 313.641195 -400.00568) (xy 313.672219 -400.04554)
			(xy 313.69626 -400.089963) (xy 313.712661 -400.137737) (xy 313.720974 -400.187559) (xy 313.721496 -400.212814)
			(xy 313.721042 -400.237175) (xy 313.713339 -400.285285) (xy 313.698083 -400.331556) (xy 313.675662 -400.374813)
			(xy 313.661552 -400.394678) (xy 313.65571 -400.402298) (xy 313.650884 -400.420078) (xy 313.659012 -400.506946)
			(xy 313.667394 -400.523456) (xy 313.674506 -400.53006) (xy 313.693631 -400.548201) (xy 313.727208 -400.588837)
			(xy 313.754872 -400.633707) (xy 313.776097 -400.681958) (xy 313.790478 -400.732671) (xy 313.797742 -400.784882)
			(xy 313.798204 -400.811238) (xy 313.798204 -401.674838) (xy 313.797756 -401.701012) (xy 313.79057 -401.752865)
			(xy 313.776366 -401.803249) (xy 313.755409 -401.85122) (xy 313.728094 -401.895877) (xy 313.694932 -401.936382)
			(xy 313.67603 -401.954492) (xy 313.668664 -401.96135) (xy 313.660536 -401.978876) (xy 313.655202 -402.069046)
			(xy 313.661298 -402.087334) (xy 313.667902 -402.094954) (xy 313.682831 -402.113043) (xy 313.707963 -402.152642)
			(xy 313.727241 -402.195398) (xy 313.740276 -402.240451) (xy 313.746807 -402.286895) (xy 313.74715 -402.310346)
			(xy 313.74715 -402.320252) (xy 313.75477 -402.339048) (xy 313.812682 -402.39696) (xy 313.820083 -402.403798)
			(xy 313.838682 -402.411509) (xy 313.84875 -402.411946) (xy 314.18403 -402.411946) (xy 314.194097 -402.411516)
			(xy 314.212688 -402.403788) (xy 314.220098 -402.39696) (xy 314.27801 -402.339048) (xy 314.28563 -402.320252)
			(xy 314.28563 -402.310346) (xy 314.286005 -402.286898) (xy 314.292558 -402.240463) (xy 314.305596 -402.195416)
			(xy 314.324859 -402.15266) (xy 314.34996 -402.113048) (xy 314.364878 -402.094954) (xy 314.371482 -402.087334)
			(xy 314.377578 -402.069046) (xy 314.372244 -401.978876) (xy 314.364116 -401.96135) (xy 314.35675 -401.954492)
			(xy 314.337851 -401.936378) (xy 314.304689 -401.895872) (xy 314.27737 -401.851216) (xy 314.256408 -401.803247)
			(xy 314.242196 -401.752864) (xy 314.234999 -401.701012) (xy 314.234576 -401.674838) (xy 314.234576 -400.811238)
			(xy 314.235019 -400.78488) (xy 314.242275 -400.732666) (xy 314.256654 -400.681949) (xy 314.277883 -400.633696)
			(xy 314.305555 -400.588828) (xy 314.339145 -400.548199) (xy 314.358274 -400.53006) (xy 314.365386 -400.52371)
			(xy 314.373514 -400.506946) (xy 314.381896 -400.420332) (xy 314.376816 -400.402552) (xy 314.371228 -400.394678)
			(xy 314.357072 -400.374833) (xy 314.334587 -400.331584) (xy 314.31927 -400.285309) (xy 314.311512 -400.237186)
			(xy 314.31103 -400.212814) (xy 314.311552 -400.187559) (xy 314.319865 -400.137737) (xy 314.336266 -400.089963)
			(xy 314.360307 -400.04554) (xy 314.391331 -400.00568) (xy 314.428493 -399.97147) (xy 314.470779 -399.943844)
			(xy 314.517035 -399.923554) (xy 314.566 -399.911154) (xy 314.616338 -399.906983) (xy 314.666676 -399.911154)
			(xy 314.715641 -399.923554) (xy 314.761897 -399.943844) (xy 314.804183 -399.97147) (xy 314.841345 -400.00568)
			(xy 314.872369 -400.04554) (xy 314.89641 -400.089963) (xy 314.912811 -400.137737) (xy 314.921124 -400.187559)
			(xy 314.921646 -400.212814) (xy 314.921148 -400.237184) (xy 314.913368 -400.2853) (xy 314.898056 -400.331572)
			(xy 314.875598 -400.374831) (xy 314.861448 -400.394678) (xy 314.85586 -400.402552) (xy 314.85078 -400.420332)
			(xy 314.859162 -400.506946) (xy 314.86729 -400.52371) (xy 314.874402 -400.53006) (xy 314.893527 -400.548201)
			(xy 314.927105 -400.588836) (xy 314.954769 -400.633707) (xy 314.975994 -400.681958) (xy 314.990375 -400.732671)
			(xy 314.997639 -400.784882) (xy 314.9981 -400.811238) (xy 314.9981 -401.674838) (xy 314.997652 -401.701012)
			(xy 314.990466 -401.752865) (xy 314.976262 -401.803249) (xy 314.955305 -401.851219) (xy 314.927989 -401.895876)
			(xy 314.894827 -401.936381) (xy 314.875926 -401.954492) (xy 314.86856 -401.96135) (xy 314.860432 -401.978876)
			(xy 314.855098 -402.069046) (xy 314.861194 -402.087334) (xy 314.867798 -402.094954) (xy 314.882727 -402.113043)
			(xy 314.90786 -402.152642) (xy 314.927138 -402.195397) (xy 314.940173 -402.240451) (xy 314.946703 -402.286895)
			(xy 314.947046 -402.310346) (xy 314.947046 -402.320252) (xy 314.954666 -402.339048) (xy 315.012578 -402.39696)
			(xy 315.019979 -402.403799) (xy 315.038578 -402.411511) (xy 315.048646 -402.411946) (xy 315.38418 -402.411946)
			(xy 315.394243 -402.411507) (xy 315.412821 -402.403766) (xy 315.420248 -402.39696) (xy 315.47816 -402.339048)
			(xy 315.48578 -402.320252) (xy 315.48578 -402.310346) (xy 315.486155 -402.286898) (xy 315.492708 -402.240462)
			(xy 315.505744 -402.195414) (xy 315.525004 -402.152656) (xy 315.550103 -402.113042) (xy 315.565028 -402.094954)
			(xy 315.571632 -402.087334) (xy 315.577728 -402.069046) (xy 315.572394 -401.978876) (xy 315.564266 -401.96135)
			(xy 315.5569 -401.954492) (xy 315.538031 -401.936364) (xy 315.50493 -401.89584) (xy 315.477672 -401.851175)
			(xy 315.456768 -401.803207) (xy 315.442608 -401.752835) (xy 315.435459 -401.701) (xy 315.43498 -401.674838)
			(xy 315.43498 -400.811238) (xy 315.4354 -400.784919) (xy 315.442598 -400.732775) (xy 315.456903 -400.682118)
			(xy 315.478043 -400.633912) (xy 315.505616 -400.589073) (xy 315.539097 -400.548456) (xy 315.55817 -400.530314)
			(xy 315.565282 -400.52371) (xy 315.573664 -400.5072) (xy 315.581792 -400.420332) (xy 315.576712 -400.402552)
			(xy 315.571124 -400.394932) (xy 315.556963 -400.375053) (xy 315.534473 -400.331739) (xy 315.519154 -400.2854)
			(xy 315.511395 -400.237216) (xy 315.510926 -400.212814) (xy 315.511448 -400.187559) (xy 315.519761 -400.137737)
			(xy 315.536162 -400.089963) (xy 315.560203 -400.04554) (xy 315.591227 -400.00568) (xy 315.628389 -399.97147)
			(xy 315.670675 -399.943844) (xy 315.716931 -399.923554) (xy 315.765896 -399.911154) (xy 315.816234 -399.906983)
			(xy 315.866572 -399.911154) (xy 315.915537 -399.923554) (xy 315.961793 -399.943844) (xy 316.004079 -399.97147)
			(xy 316.041241 -400.00568) (xy 316.072265 -400.04554) (xy 316.096306 -400.089963) (xy 316.112707 -400.137737)
			(xy 316.12102 -400.187559) (xy 316.121542 -400.212814) (xy 316.121088 -400.237175) (xy 316.113383 -400.285284)
			(xy 316.098125 -400.331554) (xy 316.075701 -400.374809) (xy 316.061598 -400.394678) (xy 316.055756 -400.402298)
			(xy 316.05093 -400.420078) (xy 316.059058 -400.506946) (xy 316.06744 -400.523456) (xy 316.074552 -400.53006)
			(xy 316.093645 -400.548219) (xy 316.127159 -400.588878) (xy 316.154769 -400.633757) (xy 316.17595 -400.682003)
			(xy 316.190301 -400.732702) (xy 316.197549 -400.784892) (xy 316.197996 -400.811238) (xy 316.197996 -401.674838)
			(xy 316.197569 -401.701004) (xy 316.190426 -401.752846) (xy 316.176267 -401.803226) (xy 316.155355 -401.851198)
			(xy 316.128084 -401.895862) (xy 316.094966 -401.936381) (xy 316.076076 -401.954492) (xy 316.06871 -401.96135)
			(xy 316.060582 -401.978876) (xy 316.055248 -402.069046) (xy 316.061344 -402.087334) (xy 316.067948 -402.094954)
			(xy 316.082875 -402.113044) (xy 316.108004 -402.152644) (xy 316.127279 -402.1954) (xy 316.140312 -402.240452)
			(xy 316.146842 -402.286895) (xy 316.147196 -402.310346) (xy 316.147196 -402.320252) (xy 316.154816 -402.339048)
			(xy 316.212728 -402.39696) (xy 316.220126 -402.403807) (xy 316.238725 -402.411537) (xy 316.248796 -402.411946)
			(xy 316.584076 -402.411946) (xy 316.594139 -402.411507) (xy 316.612718 -402.403768) (xy 316.620144 -402.39696)
			(xy 316.678056 -402.339048) (xy 316.685676 -402.320252) (xy 316.685676 -402.310346) (xy 316.686051 -402.286898)
			(xy 316.692603 -402.240462) (xy 316.70564 -402.195414) (xy 316.7249 -402.152656) (xy 316.749998 -402.113042)
			(xy 316.764924 -402.094954) (xy 316.771528 -402.087334) (xy 316.777624 -402.069046) (xy 316.77229 -401.978876)
			(xy 316.764162 -401.96135) (xy 316.756796 -401.954492) (xy 316.737927 -401.936364) (xy 316.704826 -401.89584)
			(xy 316.677569 -401.851175) (xy 316.656664 -401.803207) (xy 316.642505 -401.752835) (xy 316.635356 -401.701)
			(xy 316.634876 -401.674838) (xy 316.634876 -400.811238) (xy 316.635316 -400.784891) (xy 316.642555 -400.732696)
			(xy 316.6569 -400.681993) (xy 316.67808 -400.633743) (xy 316.705692 -400.588862) (xy 316.739211 -400.548204)
			(xy 316.75832 -400.53006) (xy 316.765432 -400.52371) (xy 316.77356 -400.506946) (xy 316.781942 -400.420332)
			(xy 316.776862 -400.402552) (xy 316.771274 -400.394678) (xy 316.757116 -400.374834) (xy 316.734628 -400.331586)
			(xy 316.719309 -400.28531) (xy 316.711549 -400.237187) (xy 316.711076 -400.212814) (xy 316.711598 -400.187559)
			(xy 316.719911 -400.137737) (xy 316.736312 -400.089963) (xy 316.760353 -400.04554) (xy 316.791377 -400.00568)
			(xy 316.828539 -399.97147) (xy 316.870825 -399.943844) (xy 316.917081 -399.923554) (xy 316.966046 -399.911154)
			(xy 317.016384 -399.906983) (xy 317.066722 -399.911154) (xy 317.115687 -399.923554) (xy 317.161943 -399.943844)
			(xy 317.204229 -399.97147) (xy 317.241391 -400.00568) (xy 317.272415 -400.04554) (xy 317.296456 -400.089963)
			(xy 317.312857 -400.137737) (xy 317.32117 -400.187559) (xy 317.321692 -400.212814) (xy 317.321193 -400.237184)
			(xy 317.313413 -400.285299) (xy 317.298098 -400.33157) (xy 317.275637 -400.374826) (xy 317.261494 -400.394678)
			(xy 317.255906 -400.402552) (xy 317.250826 -400.420332) (xy 317.259208 -400.506946) (xy 317.267336 -400.52371)
			(xy 317.274448 -400.53006) (xy 317.293541 -400.548219) (xy 317.327055 -400.588878) (xy 317.354665 -400.633756)
			(xy 317.375847 -400.682003) (xy 317.390198 -400.732702) (xy 317.397447 -400.784892) (xy 317.397892 -400.811238)
			(xy 317.397892 -401.674838) (xy 317.397465 -401.701004) (xy 317.390322 -401.752846) (xy 317.376162 -401.803225)
			(xy 317.355251 -401.851197) (xy 317.32798 -401.895862) (xy 317.294861 -401.93638) (xy 317.275972 -401.954492)
			(xy 317.268606 -401.96135) (xy 317.260478 -401.978876) (xy 317.255144 -402.069046) (xy 317.26124 -402.087334)
			(xy 317.267844 -402.094954) (xy 317.282771 -402.113044) (xy 317.307901 -402.152643) (xy 317.327176 -402.195399)
			(xy 317.340209 -402.240452) (xy 317.346739 -402.286895) (xy 317.347092 -402.310346) (xy 317.347092 -402.320252)
			(xy 317.354712 -402.339048) (xy 317.412624 -402.39696) (xy 317.420022 -402.403807) (xy 317.43862 -402.411539)
			(xy 317.448692 -402.411946) (xy 317.78702 -402.411946) (xy 317.79784 -402.411518) (xy 317.8176 -402.402716)
			(xy 317.82512 -402.394928) (xy 317.882778 -402.329904) (xy 317.889128 -402.309076) (xy 317.887858 -402.298408)
			(xy 317.88677 -402.288602) (xy 317.885628 -402.268904) (xy 317.885572 -402.259038) (xy 317.886071 -402.233257)
			(xy 317.894085 -402.182321) (xy 317.909909 -402.133247) (xy 317.93316 -402.087224) (xy 317.947802 -402.065998)
			(xy 317.952882 -402.058886) (xy 317.957708 -402.041868) (xy 317.95212 -401.959572) (xy 317.945008 -401.94357)
			(xy 317.938912 -401.936966) (xy 317.91946 -401.915579) (xy 317.886574 -401.868036) (xy 317.86123 -401.816078)
			(xy 317.844009 -401.760893) (xy 317.835304 -401.703743) (xy 317.834772 -401.674838) (xy 317.834772 -400.811238)
			(xy 317.835212 -400.784891) (xy 317.84245 -400.732696) (xy 317.856796 -400.681993) (xy 317.877975 -400.633742)
			(xy 317.905587 -400.588862) (xy 317.939106 -400.548203) (xy 317.958216 -400.53006) (xy 317.965328 -400.52371)
			(xy 317.973456 -400.506946) (xy 317.981838 -400.420332) (xy 317.976758 -400.402552) (xy 317.97117 -400.394678)
			(xy 317.957012 -400.374834) (xy 317.934524 -400.331586) (xy 317.919205 -400.28531) (xy 317.911446 -400.237187)
			(xy 317.910972 -400.212814) (xy 317.911494 -400.187559) (xy 317.919807 -400.137737) (xy 317.936208 -400.089963)
			(xy 317.960249 -400.04554) (xy 317.991273 -400.00568) (xy 318.028435 -399.97147) (xy 318.070721 -399.943844)
			(xy 318.116977 -399.923554) (xy 318.165942 -399.911154) (xy 318.21628 -399.906983) (xy 318.266618 -399.911154)
			(xy 318.315583 -399.923554) (xy 318.361839 -399.943844) (xy 318.404125 -399.97147) (xy 318.441287 -400.00568)
			(xy 318.472311 -400.04554) (xy 318.496352 -400.089963) (xy 318.512753 -400.137737) (xy 318.521066 -400.187559)
			(xy 318.521588 -400.212814) (xy 318.521089 -400.237184) (xy 318.513308 -400.285298) (xy 318.497994 -400.33157)
			(xy 318.475533 -400.374826) (xy 318.46139 -400.394678) (xy 318.455802 -400.402552) (xy 318.450722 -400.420332)
			(xy 318.459104 -400.506946) (xy 318.467232 -400.52371) (xy 318.474344 -400.53006) (xy 318.493437 -400.548219)
			(xy 318.526952 -400.588878) (xy 318.554562 -400.633756) (xy 318.575744 -400.682003) (xy 318.590095 -400.732702)
			(xy 318.597344 -400.784892) (xy 318.597788 -400.811238) (xy 318.597788 -401.674838) (xy 318.59728 -401.703747)
			(xy 318.588603 -401.76091) (xy 318.571393 -401.816106) (xy 318.546044 -401.86807) (xy 318.513139 -401.91561)
			(xy 318.493648 -401.936966) (xy 318.487552 -401.94357) (xy 318.48044 -401.959572) (xy 318.474852 -402.041868)
			(xy 318.479678 -402.058886) (xy 318.484758 -402.065998) (xy 318.499421 -402.087212) (xy 318.522683 -402.133234)
			(xy 318.53851 -402.182313) (xy 318.546517 -402.233254) (xy 318.546988 -402.259038) (xy 318.54693 -402.268904)
			(xy 318.545786 -402.288602) (xy 318.544702 -402.298408) (xy 318.543432 -402.309076) (xy 318.549782 -402.329904)
			(xy 318.60744 -402.394928) (xy 318.615009 -402.402648) (xy 318.634738 -402.411447) (xy 318.64554 -402.411946)
			(xy 318.983868 -402.411946) (xy 318.993931 -402.411509) (xy 319.012513 -402.403771) (xy 319.019936 -402.39696)
			(xy 319.077848 -402.339048) (xy 319.085468 -402.320252) (xy 319.085468 -402.310346) (xy 319.085843 -402.286898)
			(xy 319.092395 -402.240462) (xy 319.105431 -402.195414) (xy 319.124691 -402.152655) (xy 319.149789 -402.113041)
			(xy 319.164716 -402.094954) (xy 319.17132 -402.087334) (xy 319.177416 -402.069046) (xy 319.172082 -401.978876)
			(xy 319.163954 -401.96135) (xy 319.156588 -401.954492) (xy 319.137715 -401.936366) (xy 319.104607 -401.895844)
			(xy 319.077343 -401.851181) (xy 319.056433 -401.803213) (xy 319.04227 -401.752838) (xy 319.035119 -401.701002)
			(xy 319.034668 -401.674838) (xy 319.034668 -400.811238) (xy 319.035108 -400.784891) (xy 319.042346 -400.732696)
			(xy 319.056692 -400.681992) (xy 319.077871 -400.633742) (xy 319.105483 -400.588861) (xy 319.139002 -400.548202)
			(xy 319.158112 -400.53006) (xy 319.165224 -400.52371) (xy 319.173352 -400.506946) (xy 319.181734 -400.420332)
			(xy 319.176654 -400.402552) (xy 319.171066 -400.394678) (xy 319.156908 -400.374833) (xy 319.134421 -400.331585)
			(xy 319.119102 -400.28531) (xy 319.111343 -400.237186) (xy 319.110868 -400.212814) (xy 319.11139 -400.187559)
			(xy 319.119703 -400.137737) (xy 319.136104 -400.089963) (xy 319.160145 -400.04554) (xy 319.191169 -400.00568)
			(xy 319.228331 -399.97147) (xy 319.270617 -399.943844) (xy 319.316873 -399.923554) (xy 319.365838 -399.911154)
			(xy 319.416176 -399.906983) (xy 319.466514 -399.911154) (xy 319.515479 -399.923554) (xy 319.561735 -399.943844)
			(xy 319.604021 -399.97147) (xy 319.641183 -400.00568) (xy 319.672207 -400.04554) (xy 319.696248 -400.089963)
			(xy 319.712649 -400.137737) (xy 319.720962 -400.187559) (xy 319.721484 -400.212814) (xy 319.720986 -400.237184)
			(xy 319.713207 -400.2853) (xy 319.697896 -400.331574) (xy 319.675441 -400.374834) (xy 319.661286 -400.394678)
			(xy 319.655698 -400.402552) (xy 319.650618 -400.420332) (xy 319.659 -400.506946) (xy 319.667128 -400.52371)
			(xy 319.67424 -400.53006) (xy 319.693333 -400.548219) (xy 319.726848 -400.588878) (xy 319.754459 -400.633756)
			(xy 319.775641 -400.682002) (xy 319.789992 -400.732702) (xy 319.797241 -400.784892) (xy 319.797684 -400.811238)
			(xy 319.797684 -401.674838) (xy 319.797257 -401.701004) (xy 319.790114 -401.752846) (xy 319.775954 -401.803225)
			(xy 319.755042 -401.851197) (xy 319.727771 -401.895861) (xy 319.694652 -401.936379) (xy 319.675764 -401.954492)
			(xy 319.668398 -401.96135) (xy 319.66027 -401.978876) (xy 319.654936 -402.069046) (xy 319.661032 -402.087334)
			(xy 319.667636 -402.094954) (xy 319.682564 -402.113044) (xy 319.707694 -402.152643) (xy 319.726969 -402.195399)
			(xy 319.740003 -402.240452) (xy 319.746532 -402.286895) (xy 319.746884 -402.310346) (xy 319.746884 -402.320252)
			(xy 319.754504 -402.339048) (xy 319.812416 -402.39696) (xy 319.819813 -402.403808) (xy 319.838412 -402.411543)
			(xy 319.848484 -402.411946) (xy 320.184018 -402.411946) (xy 320.194086 -402.411518) (xy 320.21268 -402.403793)
			(xy 320.220086 -402.39696) (xy 320.277998 -402.339048) (xy 320.285618 -402.320252) (xy 320.285618 -402.310346)
			(xy 320.285993 -402.286898) (xy 320.292546 -402.240463) (xy 320.305584 -402.195416) (xy 320.324846 -402.152659)
			(xy 320.349946 -402.113047) (xy 320.364866 -402.094954) (xy 320.37147 -402.087334) (xy 320.377566 -402.069046)
			(xy 320.372232 -401.978876) (xy 320.364104 -401.96135) (xy 320.356738 -401.954492) (xy 320.337839 -401.936378)
			(xy 320.304678 -401.895872) (xy 320.277361 -401.851216) (xy 320.2564 -401.803247) (xy 320.242187 -401.752864)
			(xy 320.234991 -401.701012) (xy 320.234564 -401.674838) (xy 320.234564 -400.811238) (xy 320.235007 -400.78488)
			(xy 320.242263 -400.732666) (xy 320.256642 -400.681948) (xy 320.27787 -400.633695) (xy 320.305542 -400.588826)
			(xy 320.33913 -400.548196) (xy 320.358262 -400.53006) (xy 320.365374 -400.52371) (xy 320.373502 -400.506946)
			(xy 320.381884 -400.420332) (xy 320.376804 -400.402552) (xy 320.371216 -400.394678) (xy 320.357056 -400.374834)
			(xy 320.334565 -400.331587) (xy 320.319244 -400.285311) (xy 320.311483 -400.237187) (xy 320.311018 -400.212814)
			(xy 320.31154 -400.187559) (xy 320.319853 -400.137737) (xy 320.336254 -400.089963) (xy 320.360295 -400.04554)
			(xy 320.391319 -400.00568) (xy 320.428481 -399.97147) (xy 320.470767 -399.943844) (xy 320.517023 -399.923554)
			(xy 320.565988 -399.911154) (xy 320.616326 -399.906983) (xy 320.666664 -399.911154) (xy 320.715629 -399.923554)
			(xy 320.761885 -399.943844) (xy 320.804171 -399.97147) (xy 320.841333 -400.00568) (xy 320.872357 -400.04554)
			(xy 320.896398 -400.089963) (xy 320.912799 -400.137737) (xy 320.921112 -400.187559) (xy 320.921634 -400.212814)
			(xy 320.921136 -400.237184) (xy 320.913356 -400.285299) (xy 320.898043 -400.331572) (xy 320.875585 -400.37483)
			(xy 320.861436 -400.394678) (xy 320.855848 -400.402552) (xy 320.850768 -400.420332) (xy 320.85915 -400.506946)
			(xy 320.867278 -400.52371) (xy 320.87439 -400.53006) (xy 320.893511 -400.548203) (xy 320.927081 -400.588841)
			(xy 320.954739 -400.633713) (xy 320.975959 -400.681963) (xy 320.990337 -400.732675) (xy 320.997599 -400.784883)
			(xy 320.998088 -400.811238) (xy 320.998088 -401.674838) (xy 320.99764 -401.701012) (xy 320.990454 -401.752864)
			(xy 320.976249 -401.803248) (xy 320.955292 -401.851218) (xy 320.927976 -401.895874) (xy 320.894813 -401.936378)
			(xy 320.875914 -401.954492) (xy 320.868548 -401.96135) (xy 320.86042 -401.978876) (xy 320.855086 -402.069046)
			(xy 320.861182 -402.087334) (xy 320.867786 -402.094954) (xy 320.882711 -402.113045) (xy 320.907838 -402.152645)
			(xy 320.927111 -402.195401) (xy 320.940142 -402.240453) (xy 320.946671 -402.286896) (xy 320.947034 -402.310346)
			(xy 320.947034 -402.320252) (xy 320.954654 -402.339048) (xy 321.012566 -402.39696) (xy 321.019966 -402.4038)
			(xy 321.038565 -402.411517) (xy 321.048634 -402.411946) (xy 321.384676 -402.411946) (xy 321.395099 -402.411441)
			(xy 321.414241 -402.403181) (xy 321.42176 -402.395944) (xy 321.479672 -402.334476) (xy 321.486784 -402.314664)
			(xy 321.486022 -402.30425) (xy 321.485514 -402.284438) (xy 321.486063 -402.256949) (xy 321.49516 -402.20273)
			(xy 321.513093 -402.150759) (xy 321.53937 -402.102468) (xy 321.555872 -402.080476) (xy 321.561714 -402.07311)
			(xy 321.567048 -402.05533) (xy 321.561714 -401.969224) (xy 321.554094 -401.95246) (xy 321.54749 -401.945856)
			(xy 321.526471 -401.924222) (xy 321.49084 -401.875555) (xy 321.463309 -401.821889) (xy 321.444563 -401.76456)
			(xy 321.435069 -401.704996) (xy 321.43446 -401.674838) (xy 321.43446 -400.811238) (xy 321.434903 -400.78488)
			(xy 321.442159 -400.732666) (xy 321.456538 -400.681948) (xy 321.477765 -400.633695) (xy 321.505437 -400.588826)
			(xy 321.539026 -400.548195) (xy 321.558158 -400.53006) (xy 321.56527 -400.52371) (xy 321.573398 -400.506946)
			(xy 321.58178 -400.420332) (xy 321.5767 -400.402552) (xy 321.571112 -400.394678) (xy 321.556952 -400.374834)
			(xy 321.534461 -400.331587) (xy 321.51914 -400.285311) (xy 321.51138 -400.237187) (xy 321.510914 -400.212814)
			(xy 321.511436 -400.187559) (xy 321.519749 -400.137737) (xy 321.53615 -400.089963) (xy 321.560191 -400.04554)
			(xy 321.591215 -400.00568) (xy 321.628377 -399.97147) (xy 321.670663 -399.943844) (xy 321.716919 -399.923554)
			(xy 321.765884 -399.911154) (xy 321.816222 -399.906983) (xy 321.86656 -399.911154) (xy 321.915525 -399.923554)
			(xy 321.961781 -399.943844) (xy 322.004067 -399.97147) (xy 322.041229 -400.00568) (xy 322.072253 -400.04554)
			(xy 322.096294 -400.089963) (xy 322.112695 -400.137737) (xy 322.121008 -400.187559) (xy 322.12153 -400.212814)
			(xy 322.121032 -400.237184) (xy 322.113252 -400.285299) (xy 322.097938 -400.331572) (xy 322.07548 -400.37483)
			(xy 322.061332 -400.394678) (xy 322.055744 -400.402552) (xy 322.050664 -400.420332) (xy 322.059046 -400.506946)
			(xy 322.067174 -400.52371) (xy 322.074286 -400.53006) (xy 322.093408 -400.548203) (xy 322.126978 -400.588841)
			(xy 322.154636 -400.633712) (xy 322.175856 -400.681963) (xy 322.190234 -400.732675) (xy 322.197496 -400.784883)
			(xy 322.197984 -400.811238) (xy 322.197984 -401.674838) (xy 322.197417 -401.705) (xy 322.18793 -401.764572)
			(xy 322.169184 -401.821909) (xy 322.141646 -401.87558) (xy 322.106003 -401.924246) (xy 322.084954 -401.945856)
			(xy 322.07835 -401.95246) (xy 322.07073 -401.969224) (xy 322.065396 -402.05533) (xy 322.07073 -402.07311)
			(xy 322.076572 -402.080476) (xy 322.093096 -402.102452) (xy 322.119373 -402.150746) (xy 322.137296 -402.202722)
			(xy 322.146371 -402.256948) (xy 322.14693 -402.284438) (xy 322.146422 -402.30425) (xy 322.14566 -402.314664)
			(xy 322.152772 -402.334476) (xy 322.210684 -402.395944) (xy 322.218184 -402.403211) (xy 322.237336 -402.411481)
			(xy 322.247768 -402.411946) (xy 323.99859 -402.411946) (xy 324.00866 -402.411523) (xy 324.027262 -402.403805)
			(xy 324.034658 -402.39696) (xy 324.323964 -402.107654) (xy 324.330425 -402.100559) (xy 324.33798 -402.082935)
			(xy 324.338696 -402.073364) (xy 324.341236 -401.994116) (xy 324.334886 -401.976336) (xy 324.328536 -401.968716)
			(xy 324.308988 -401.945583) (xy 324.276709 -401.89434) (xy 324.252929 -401.838642) (xy 324.238246 -401.779887)
			(xy 324.235064 -401.749768) (xy 324.233794 -401.737576) (xy 324.22084 -401.716748) (xy 324.1294 -401.661884)
			(xy 324.105016 -401.66036) (xy 324.093586 -401.665186) (xy 324.061797 -401.678205) (xy 323.995595 -401.696535)
			(xy 323.927527 -401.705783) (xy 323.89318 -401.706334) (xy 323.861637 -401.705857) (xy 323.799037 -401.698051)
			(xy 323.737882 -401.682562) (xy 323.679113 -401.659628) (xy 323.623632 -401.6296) (xy 323.572292 -401.592941)
			(xy 323.52588 -401.550212) (xy 323.48511 -401.502071) (xy 323.450608 -401.449257) (xy 323.422903 -401.39258)
			(xy 323.402422 -401.332912) (xy 323.389479 -401.271168) (xy 323.384272 -401.208298) (xy 323.386882 -401.145267)
			(xy 323.397268 -401.083042) (xy 323.415271 -401.02258) (xy 323.440615 -400.964809) (xy 323.47291 -400.910617)
			(xy 323.51166 -400.860835) (xy 323.55627 -400.816229) (xy 323.606055 -400.777484) (xy 323.66025 -400.745194)
			(xy 323.718023 -400.719855) (xy 323.778487 -400.701857) (xy 323.840713 -400.691477) (xy 323.903744 -400.688873)
			(xy 323.966614 -400.694085) (xy 324.028356 -400.707034) (xy 324.088022 -400.727521) (xy 324.144697 -400.755231)
			(xy 324.197508 -400.789738) (xy 324.245645 -400.830512) (xy 324.28837 -400.876928) (xy 324.325025 -400.928272)
			(xy 324.355047 -400.983755) (xy 324.377976 -401.042526) (xy 324.39346 -401.103682) (xy 324.40126 -401.166283)
			(xy 324.401688 -401.197826) (xy 324.39991 -401.239228) (xy 324.398894 -401.25142) (xy 324.408292 -401.274026)
			(xy 324.489572 -401.343368) (xy 324.513194 -401.34921) (xy 324.525132 -401.346162) (xy 324.54727 -401.341142)
			(xy 324.59235 -401.335789) (xy 324.615048 -401.335494) (xy 324.642554 -401.335999) (xy 324.696991 -401.343945)
			(xy 324.749723 -401.35962) (xy 324.79966 -401.382702) (xy 324.845767 -401.412712) (xy 324.866762 -401.43049)
			(xy 324.874382 -401.43684) (xy 324.892162 -401.44319) (xy 324.97141 -401.44065) (xy 324.980986 -401.439961)
			(xy 324.998615 -401.432396) (xy 325.0057 -401.425918) (xy 325.22414 -401.207478) (xy 325.231252 -401.193508)
			(xy 325.232522 -401.18538) (xy 325.238137 -401.154209) (xy 325.256093 -401.093471) (xy 325.281452 -401.035432)
			(xy 325.313822 -400.980991) (xy 325.3527 -400.93099) (xy 325.397486 -400.886203) (xy 325.447487 -400.847324)
			(xy 325.501928 -400.814955) (xy 325.559966 -400.789595) (xy 325.620705 -400.771638) (xy 325.651876 -400.766026)
			(xy 325.660004 -400.764756) (xy 325.673974 -400.757644) (xy 327.15962 -399.271998) (xy 327.166058 -399.264933)
			(xy 327.173637 -399.2474) (xy 327.174335 -399.228312) (xy 327.171558 -399.219166) (xy 327.135998 -399.118836)
			(xy 327.112884 -399.100802) (xy 327.098152 -399.099278) (xy 327.069156 -399.095648) (xy 327.01266 -399.080717)
			(xy 326.959097 -399.057359) (xy 326.909716 -399.026117) (xy 326.887332 -399.00733) (xy 326.88022 -399.001234)
			(xy 326.863202 -398.994884) (xy 326.777858 -398.994884) (xy 326.76084 -399.001234) (xy 326.753728 -399.00733)
			(xy 326.732797 -399.024972) (xy 326.68683 -399.054699) (xy 326.637084 -399.077544) (xy 326.58458 -399.093037)
			(xy 326.530401 -399.100859) (xy 326.50303 -399.10131) (xy 326.475776 -399.100849) (xy 326.421821 -399.093095)
			(xy 326.369519 -399.077742) (xy 326.319935 -399.055101) (xy 326.274078 -399.025633) (xy 326.232882 -398.98994)
			(xy 326.197185 -398.948746) (xy 326.167714 -398.902891) (xy 326.145069 -398.853309) (xy 326.129711 -398.801008)
			(xy 326.121953 -398.747054) (xy 326.121953 -398.692546) (xy 326.129711 -398.638592) (xy 326.145069 -398.586291)
			(xy 326.167714 -398.536709) (xy 326.197185 -398.490854) (xy 326.232882 -398.44966) (xy 326.274078 -398.413967)
			(xy 326.319935 -398.384499) (xy 326.369519 -398.361858) (xy 326.421821 -398.346505) (xy 326.475776 -398.338751)
			(xy 326.50303 -398.338294) (xy 326.530399 -398.338768) (xy 326.584576 -398.346595) (xy 326.637077 -398.362086)
			(xy 326.686825 -398.38492) (xy 326.7328 -398.414631) (xy 326.753728 -398.432274) (xy 326.76084 -398.43837)
			(xy 326.777858 -398.44472) (xy 326.863202 -398.44472) (xy 326.88022 -398.43837) (xy 326.887332 -398.432274)
			(xy 326.908264 -398.414635) (xy 326.954232 -398.384915) (xy 327.003979 -398.362077) (xy 327.056482 -398.346593)
			(xy 327.11066 -398.338779) (xy 327.13803 -398.338294) (xy 327.166011 -398.338787) (xy 327.221374 -398.346965)
			(xy 327.274948 -398.363141) (xy 327.325585 -398.386968) (xy 327.372199 -398.417935) (xy 327.41379 -398.455379)
			(xy 327.449467 -398.498495) (xy 327.478464 -398.54636) (xy 327.500159 -398.597946) (xy 327.514087 -398.652148)
			(xy 327.517506 -398.679924) (xy 327.51903 -398.694656) (xy 327.537064 -398.71777) (xy 327.637394 -398.75333)
			(xy 327.646538 -398.756162) (xy 327.665653 -398.755515) (xy 327.68319 -398.747882) (xy 327.690226 -398.741392)
			(xy 327.749662 -398.681956) (xy 327.757061 -398.675113) (xy 327.77566 -398.667392) (xy 327.78573 -398.66697)
			(xy 328.985372 -398.66697) (xy 328.995423 -398.667474) (xy 329.013986 -398.675193) (xy 329.02144 -398.681956)
			(xy 329.549506 -399.210022) (xy 329.558959 -399.218453) (xy 329.583212 -399.225648) (xy 329.595734 -399.223738)
			(xy 329.691746 -399.203926) (xy 329.71105 -399.187416) (xy 329.715876 -399.175478) (xy 329.728468 -399.145268)
			(xy 329.762446 -399.089335) (xy 329.78344 -399.064226) (xy 329.789536 -399.057114) (xy 329.795886 -399.040096)
			(xy 329.795886 -398.954752) (xy 329.789536 -398.937734) (xy 329.78344 -398.930622) (xy 329.765795 -398.909692)
			(xy 329.736063 -398.863727) (xy 329.713215 -398.81398) (xy 329.69772 -398.761476) (xy 329.689897 -398.707295)
			(xy 329.68946 -398.679924) (xy 329.689946 -398.652673) (xy 329.697702 -398.598725) (xy 329.713057 -398.54643)
			(xy 329.735699 -398.496853) (xy 329.765165 -398.451003) (xy 329.800856 -398.409812) (xy 329.842047 -398.374121)
			(xy 329.887897 -398.344655) (xy 329.937474 -398.322013) (xy 329.989769 -398.306658) (xy 330.043717 -398.298902)
			(xy 330.098219 -398.298902) (xy 330.152167 -398.306658) (xy 330.204462 -398.322013) (xy 330.254039 -398.344655)
			(xy 330.299889 -398.374121) (xy 330.34108 -398.409812) (xy 330.376771 -398.451003) (xy 330.406237 -398.496853)
			(xy 330.428879 -398.54643) (xy 330.444234 -398.598725) (xy 330.45199 -398.652673) (xy 330.452476 -398.679924)
			(xy 330.452003 -398.707293) (xy 330.444175 -398.761469) (xy 330.428685 -398.813971) (xy 330.405849 -398.863719)
			(xy 330.376138 -398.909692) (xy 330.358496 -398.930622) (xy 330.3524 -398.937734) (xy 330.34605 -398.954752)
			(xy 330.34605 -399.008092) (xy 333.163164 -399.008092) (xy 333.163728 -398.9748) (xy 333.173347 -398.908916)
			(xy 333.192424 -398.845124) (xy 333.220555 -398.784776) (xy 333.238348 -398.756632) (xy 333.243407 -398.748114)
			(xy 333.24722 -398.728693) (xy 333.243401 -398.709273) (xy 333.238348 -398.700752) (xy 333.220566 -398.672605)
			(xy 333.192474 -398.612244) (xy 333.173407 -398.548456) (xy 333.163765 -398.482581) (xy 333.163164 -398.449292)
			(xy 333.163654 -398.419324) (xy 333.171477 -398.359902) (xy 333.18699 -398.302009) (xy 333.209926 -398.246636)
			(xy 333.239893 -398.19473) (xy 333.27638 -398.14718) (xy 333.31876 -398.1048) (xy 333.36631 -398.068313)
			(xy 333.418216 -398.038346) (xy 333.473589 -398.01541) (xy 333.531482 -397.999897) (xy 333.590904 -397.992074)
			(xy 333.65084 -397.992074) (xy 333.710262 -397.999897) (xy 333.768155 -398.01541) (xy 333.823528 -398.038346)
			(xy 333.875434 -398.068313) (xy 333.922984 -398.1048) (xy 333.965364 -398.14718) (xy 334.001851 -398.19473)
			(xy 334.031818 -398.246636) (xy 334.054754 -398.302009) (xy 334.070267 -398.359902) (xy 334.07809 -398.419324)
			(xy 334.07858 -398.449292) (xy 334.078017 -398.482584) (xy 334.069343 -398.542002) (xy 335.612752 -398.542002)
			(xy 335.616712 -398.492948) (xy 335.628489 -398.445164) (xy 335.64778 -398.399888) (xy 335.674083 -398.358292)
			(xy 335.706718 -398.321455) (xy 335.744839 -398.29033) (xy 335.78746 -398.265723) (xy 335.833476 -398.248271)
			(xy 335.881695 -398.238427) (xy 335.93087 -398.236446) (xy 335.979725 -398.242378) (xy 336.026996 -398.25607)
			(xy 336.071458 -398.277168) (xy 336.111961 -398.305124) (xy 336.147454 -398.339216) (xy 336.177019 -398.37856)
			(xy 336.19989 -398.422137) (xy 336.215474 -398.468818) (xy 336.223369 -398.517395) (xy 336.223864 -398.542002)
			(xy 336.812902 -398.542002) (xy 336.816862 -398.492948) (xy 336.828639 -398.445164) (xy 336.84793 -398.399888)
			(xy 336.874233 -398.358292) (xy 336.906868 -398.321455) (xy 336.944989 -398.29033) (xy 336.98761 -398.265723)
			(xy 337.033626 -398.248271) (xy 337.081845 -398.238427) (xy 337.13102 -398.236446) (xy 337.179875 -398.242378)
			(xy 337.227146 -398.25607) (xy 337.271608 -398.277168) (xy 337.312111 -398.305124) (xy 337.347604 -398.339216)
			(xy 337.377169 -398.37856) (xy 337.40004 -398.422137) (xy 337.415624 -398.468818) (xy 337.423519 -398.517395)
			(xy 337.424014 -398.542002) (xy 338.013052 -398.542002) (xy 338.017012 -398.492948) (xy 338.028789 -398.445164)
			(xy 338.04808 -398.399888) (xy 338.074383 -398.358292) (xy 338.107018 -398.321455) (xy 338.145139 -398.29033)
			(xy 338.18776 -398.265723) (xy 338.233776 -398.248271) (xy 338.281995 -398.238427) (xy 338.33117 -398.236446)
			(xy 338.380025 -398.242378) (xy 338.427296 -398.25607) (xy 338.471758 -398.277168) (xy 338.512261 -398.305124)
			(xy 338.547754 -398.339216) (xy 338.577319 -398.37856) (xy 338.60019 -398.422137) (xy 338.615774 -398.468818)
			(xy 338.623669 -398.517395) (xy 338.624164 -398.542002) (xy 339.212948 -398.542002) (xy 339.216908 -398.492948)
			(xy 339.228685 -398.445164) (xy 339.247976 -398.399888) (xy 339.274279 -398.358292) (xy 339.306914 -398.321455)
			(xy 339.345035 -398.29033) (xy 339.387656 -398.265723) (xy 339.433672 -398.248271) (xy 339.481891 -398.238427)
			(xy 339.531066 -398.236446) (xy 339.579921 -398.242378) (xy 339.627192 -398.25607) (xy 339.671654 -398.277168)
			(xy 339.712157 -398.305124) (xy 339.74765 -398.339216) (xy 339.777215 -398.37856) (xy 339.800086 -398.422137)
			(xy 339.81567 -398.468818) (xy 339.823565 -398.517395) (xy 339.82406 -398.542002) (xy 340.413098 -398.542002)
			(xy 340.417058 -398.492948) (xy 340.428835 -398.445164) (xy 340.448126 -398.399888) (xy 340.474429 -398.358292)
			(xy 340.507064 -398.321455) (xy 340.545185 -398.29033) (xy 340.587806 -398.265723) (xy 340.633822 -398.248271)
			(xy 340.682041 -398.238427) (xy 340.731216 -398.236446) (xy 340.780071 -398.242378) (xy 340.827342 -398.25607)
			(xy 340.871804 -398.277168) (xy 340.912307 -398.305124) (xy 340.9478 -398.339216) (xy 340.977365 -398.37856)
			(xy 341.000236 -398.422137) (xy 341.01582 -398.468818) (xy 341.023715 -398.517395) (xy 341.02421 -398.542002)
			(xy 341.612994 -398.542002) (xy 341.616954 -398.492948) (xy 341.628731 -398.445164) (xy 341.648022 -398.399888)
			(xy 341.674325 -398.358292) (xy 341.70696 -398.321455) (xy 341.745081 -398.29033) (xy 341.787702 -398.265723)
			(xy 341.833718 -398.248271) (xy 341.881937 -398.238427) (xy 341.931112 -398.236446) (xy 341.979967 -398.242378)
			(xy 342.027238 -398.25607) (xy 342.0717 -398.277168) (xy 342.112203 -398.305124) (xy 342.147696 -398.339216)
			(xy 342.177261 -398.37856) (xy 342.200132 -398.422137) (xy 342.215716 -398.468818) (xy 342.223611 -398.517395)
			(xy 342.224106 -398.542002) (xy 342.81289 -398.542002) (xy 342.81685 -398.492948) (xy 342.828627 -398.445164)
			(xy 342.847918 -398.399888) (xy 342.874221 -398.358292) (xy 342.906856 -398.321455) (xy 342.944977 -398.29033)
			(xy 342.987598 -398.265723) (xy 343.033614 -398.248271) (xy 343.081833 -398.238427) (xy 343.131008 -398.236446)
			(xy 343.179863 -398.242378) (xy 343.227134 -398.25607) (xy 343.271596 -398.277168) (xy 343.312099 -398.305124)
			(xy 343.347592 -398.339216) (xy 343.377157 -398.37856) (xy 343.400028 -398.422137) (xy 343.415612 -398.468818)
			(xy 343.423507 -398.517395) (xy 343.424002 -398.542002) (xy 344.01304 -398.542002) (xy 344.017 -398.492948)
			(xy 344.028777 -398.445164) (xy 344.048068 -398.399888) (xy 344.074371 -398.358292) (xy 344.107006 -398.321455)
			(xy 344.145127 -398.29033) (xy 344.187748 -398.265723) (xy 344.233764 -398.248271) (xy 344.281983 -398.238427)
			(xy 344.331158 -398.236446) (xy 344.380013 -398.242378) (xy 344.427284 -398.25607) (xy 344.471746 -398.277168)
			(xy 344.512249 -398.305124) (xy 344.547742 -398.339216) (xy 344.577307 -398.37856) (xy 344.600178 -398.422137)
			(xy 344.615762 -398.468818) (xy 344.623657 -398.517395) (xy 344.624152 -398.542002) (xy 345.212936 -398.542002)
			(xy 345.216896 -398.492948) (xy 345.228673 -398.445164) (xy 345.247964 -398.399888) (xy 345.274267 -398.358292)
			(xy 345.306902 -398.321455) (xy 345.345023 -398.29033) (xy 345.387644 -398.265723) (xy 345.43366 -398.248271)
			(xy 345.481879 -398.238427) (xy 345.531054 -398.236446) (xy 345.579909 -398.242378) (xy 345.62718 -398.25607)
			(xy 345.671642 -398.277168) (xy 345.712145 -398.305124) (xy 345.747638 -398.339216) (xy 345.777203 -398.37856)
			(xy 345.800074 -398.422137) (xy 345.815658 -398.468818) (xy 345.823553 -398.517395) (xy 345.824048 -398.542002)
			(xy 346.413086 -398.542002) (xy 346.417046 -398.492948) (xy 346.428823 -398.445164) (xy 346.448114 -398.399888)
			(xy 346.474417 -398.358292) (xy 346.507052 -398.321455) (xy 346.545173 -398.29033) (xy 346.587794 -398.265723)
			(xy 346.63381 -398.248271) (xy 346.682029 -398.238427) (xy 346.731204 -398.236446) (xy 346.780059 -398.242378)
			(xy 346.82733 -398.25607) (xy 346.871792 -398.277168) (xy 346.912295 -398.305124) (xy 346.947788 -398.339216)
			(xy 346.977353 -398.37856) (xy 347.000224 -398.422137) (xy 347.015808 -398.468818) (xy 347.023703 -398.517395)
			(xy 347.024198 -398.542002) (xy 347.612982 -398.542002) (xy 347.616942 -398.492948) (xy 347.628719 -398.445164)
			(xy 347.64801 -398.399888) (xy 347.674313 -398.358292) (xy 347.706948 -398.321455) (xy 347.745069 -398.29033)
			(xy 347.78769 -398.265723) (xy 347.833706 -398.248271) (xy 347.881925 -398.238427) (xy 347.9311 -398.236446)
			(xy 347.979955 -398.242378) (xy 348.027226 -398.25607) (xy 348.071688 -398.277168) (xy 348.112191 -398.305124)
			(xy 348.147684 -398.339216) (xy 348.177249 -398.37856) (xy 348.20012 -398.422137) (xy 348.215704 -398.468818)
			(xy 348.223599 -398.517395) (xy 348.224094 -398.542002) (xy 348.812878 -398.542002) (xy 348.816838 -398.492948)
			(xy 348.828615 -398.445164) (xy 348.847906 -398.399888) (xy 348.874209 -398.358292) (xy 348.906844 -398.321455)
			(xy 348.944965 -398.29033) (xy 348.987586 -398.265723) (xy 349.033602 -398.248271) (xy 349.081821 -398.238427)
			(xy 349.130996 -398.236446) (xy 349.179851 -398.242378) (xy 349.227122 -398.25607) (xy 349.271584 -398.277168)
			(xy 349.312087 -398.305124) (xy 349.34758 -398.339216) (xy 349.377145 -398.37856) (xy 349.400016 -398.422137)
			(xy 349.4156 -398.468818) (xy 349.423495 -398.517395) (xy 349.42399 -398.542002) (xy 350.013028 -398.542002)
			(xy 350.016988 -398.492948) (xy 350.028765 -398.445164) (xy 350.048056 -398.399888) (xy 350.074359 -398.358292)
			(xy 350.106994 -398.321455) (xy 350.145115 -398.29033) (xy 350.187736 -398.265723) (xy 350.233752 -398.248271)
			(xy 350.281971 -398.238427) (xy 350.331146 -398.236446) (xy 350.380001 -398.242378) (xy 350.427272 -398.25607)
			(xy 350.471734 -398.277168) (xy 350.512237 -398.305124) (xy 350.54773 -398.339216) (xy 350.577295 -398.37856)
			(xy 350.600166 -398.422137) (xy 350.61575 -398.468818) (xy 350.623645 -398.517395) (xy 350.62414 -398.542002)
			(xy 351.212924 -398.542002) (xy 351.216884 -398.492948) (xy 351.228661 -398.445164) (xy 351.247952 -398.399888)
			(xy 351.274255 -398.358292) (xy 351.30689 -398.321455) (xy 351.345011 -398.29033) (xy 351.387632 -398.265723)
			(xy 351.433648 -398.248271) (xy 351.481867 -398.238427) (xy 351.531042 -398.236446) (xy 351.579897 -398.242378)
			(xy 351.627168 -398.25607) (xy 351.67163 -398.277168) (xy 351.712133 -398.305124) (xy 351.747626 -398.339216)
			(xy 351.777191 -398.37856) (xy 351.800062 -398.422137) (xy 351.815646 -398.468818) (xy 351.823541 -398.517395)
			(xy 351.824036 -398.542002) (xy 352.413074 -398.542002) (xy 352.417034 -398.492948) (xy 352.428811 -398.445164)
			(xy 352.448102 -398.399888) (xy 352.474405 -398.358292) (xy 352.50704 -398.321455) (xy 352.545161 -398.29033)
			(xy 352.587782 -398.265723) (xy 352.633798 -398.248271) (xy 352.682017 -398.238427) (xy 352.731192 -398.236446)
			(xy 352.780047 -398.242378) (xy 352.827318 -398.25607) (xy 352.87178 -398.277168) (xy 352.912283 -398.305124)
			(xy 352.947776 -398.339216) (xy 352.977341 -398.37856) (xy 353.000212 -398.422137) (xy 353.015796 -398.468818)
			(xy 353.023691 -398.517395) (xy 353.024186 -398.542002) (xy 353.61297 -398.542002) (xy 353.61693 -398.492948)
			(xy 353.628707 -398.445164) (xy 353.647998 -398.399888) (xy 353.674301 -398.358292) (xy 353.706936 -398.321455)
			(xy 353.745057 -398.29033) (xy 353.787678 -398.265723) (xy 353.833694 -398.248271) (xy 353.881913 -398.238427)
			(xy 353.931088 -398.236446) (xy 353.979943 -398.242378) (xy 354.027214 -398.25607) (xy 354.071676 -398.277168)
			(xy 354.112179 -398.305124) (xy 354.147672 -398.339216) (xy 354.177237 -398.37856) (xy 354.200108 -398.422137)
			(xy 354.215692 -398.468818) (xy 354.223587 -398.517395) (xy 354.224082 -398.542002) (xy 354.223587 -398.566609)
			(xy 354.223363 -398.567989) (xy 354.94265 -398.567989) (xy 354.94265 -398.516015) (xy 354.95078 -398.46468)
			(xy 354.966841 -398.41525) (xy 354.990437 -398.36894) (xy 355.020987 -398.326892) (xy 355.057738 -398.290141)
			(xy 355.099786 -398.259591) (xy 355.146096 -398.235995) (xy 355.195526 -398.219934) (xy 355.246861 -398.211804)
			(xy 355.298835 -398.211804) (xy 355.35017 -398.219934) (xy 355.3996 -398.235995) (xy 355.44591 -398.259591)
			(xy 355.487958 -398.290141) (xy 355.524709 -398.326892) (xy 355.555259 -398.36894) (xy 355.578855 -398.41525)
			(xy 355.594916 -398.46468) (xy 355.603046 -398.516015) (xy 355.603556 -398.542002) (xy 355.603046 -398.567989)
			(xy 355.594916 -398.619324) (xy 355.578855 -398.668754) (xy 355.555259 -398.715064) (xy 355.524709 -398.757112)
			(xy 355.487958 -398.793863) (xy 355.44591 -398.824413) (xy 355.3996 -398.848009) (xy 355.35017 -398.86407)
			(xy 355.298835 -398.8722) (xy 355.246861 -398.8722) (xy 355.195526 -398.86407) (xy 355.146096 -398.848009)
			(xy 355.099786 -398.824413) (xy 355.057738 -398.793863) (xy 355.020987 -398.757112) (xy 354.990437 -398.715064)
			(xy 354.966841 -398.668754) (xy 354.95078 -398.619324) (xy 354.94265 -398.567989) (xy 354.223363 -398.567989)
			(xy 354.215692 -398.615186) (xy 354.200108 -398.661867) (xy 354.177237 -398.705444) (xy 354.147672 -398.744788)
			(xy 354.112179 -398.77888) (xy 354.071676 -398.806836) (xy 354.027214 -398.827934) (xy 353.979943 -398.841626)
			(xy 353.931088 -398.847558) (xy 353.881913 -398.845577) (xy 353.833694 -398.835733) (xy 353.787678 -398.818281)
			(xy 353.745057 -398.793674) (xy 353.706936 -398.762549) (xy 353.674301 -398.725712) (xy 353.647998 -398.684116)
			(xy 353.628707 -398.63884) (xy 353.61693 -398.591056) (xy 353.61297 -398.542002) (xy 353.024186 -398.542002)
			(xy 353.023691 -398.566609) (xy 353.015796 -398.615186) (xy 353.000212 -398.661867) (xy 352.977341 -398.705444)
			(xy 352.947776 -398.744788) (xy 352.912283 -398.77888) (xy 352.87178 -398.806836) (xy 352.827318 -398.827934)
			(xy 352.780047 -398.841626) (xy 352.731192 -398.847558) (xy 352.682017 -398.845577) (xy 352.633798 -398.835733)
			(xy 352.587782 -398.818281) (xy 352.545161 -398.793674) (xy 352.50704 -398.762549) (xy 352.474405 -398.725712)
			(xy 352.448102 -398.684116) (xy 352.428811 -398.63884) (xy 352.417034 -398.591056) (xy 352.413074 -398.542002)
			(xy 351.824036 -398.542002) (xy 351.823541 -398.566609) (xy 351.815646 -398.615186) (xy 351.800062 -398.661867)
			(xy 351.777191 -398.705444) (xy 351.747626 -398.744788) (xy 351.712133 -398.77888) (xy 351.67163 -398.806836)
			(xy 351.627168 -398.827934) (xy 351.579897 -398.841626) (xy 351.531042 -398.847558) (xy 351.481867 -398.845577)
			(xy 351.433648 -398.835733) (xy 351.387632 -398.818281) (xy 351.345011 -398.793674) (xy 351.30689 -398.762549)
			(xy 351.274255 -398.725712) (xy 351.247952 -398.684116) (xy 351.228661 -398.63884) (xy 351.216884 -398.591056)
			(xy 351.212924 -398.542002) (xy 350.62414 -398.542002) (xy 350.623645 -398.566609) (xy 350.61575 -398.615186)
			(xy 350.600166 -398.661867) (xy 350.577295 -398.705444) (xy 350.54773 -398.744788) (xy 350.512237 -398.77888)
			(xy 350.471734 -398.806836) (xy 350.427272 -398.827934) (xy 350.380001 -398.841626) (xy 350.331146 -398.847558)
			(xy 350.281971 -398.845577) (xy 350.233752 -398.835733) (xy 350.187736 -398.818281) (xy 350.145115 -398.793674)
			(xy 350.106994 -398.762549) (xy 350.074359 -398.725712) (xy 350.048056 -398.684116) (xy 350.028765 -398.63884)
			(xy 350.016988 -398.591056) (xy 350.013028 -398.542002) (xy 349.42399 -398.542002) (xy 349.423495 -398.566609)
			(xy 349.4156 -398.615186) (xy 349.400016 -398.661867) (xy 349.377145 -398.705444) (xy 349.34758 -398.744788)
			(xy 349.312087 -398.77888) (xy 349.271584 -398.806836) (xy 349.227122 -398.827934) (xy 349.179851 -398.841626)
			(xy 349.130996 -398.847558) (xy 349.081821 -398.845577) (xy 349.033602 -398.835733) (xy 348.987586 -398.818281)
			(xy 348.944965 -398.793674) (xy 348.906844 -398.762549) (xy 348.874209 -398.725712) (xy 348.847906 -398.684116)
			(xy 348.828615 -398.63884) (xy 348.816838 -398.591056) (xy 348.812878 -398.542002) (xy 348.224094 -398.542002)
			(xy 348.223599 -398.566609) (xy 348.215704 -398.615186) (xy 348.20012 -398.661867) (xy 348.177249 -398.705444)
			(xy 348.147684 -398.744788) (xy 348.112191 -398.77888) (xy 348.071688 -398.806836) (xy 348.027226 -398.827934)
			(xy 347.979955 -398.841626) (xy 347.9311 -398.847558) (xy 347.881925 -398.845577) (xy 347.833706 -398.835733)
			(xy 347.78769 -398.818281) (xy 347.745069 -398.793674) (xy 347.706948 -398.762549) (xy 347.674313 -398.725712)
			(xy 347.64801 -398.684116) (xy 347.628719 -398.63884) (xy 347.616942 -398.591056) (xy 347.612982 -398.542002)
			(xy 347.024198 -398.542002) (xy 347.023703 -398.566609) (xy 347.015808 -398.615186) (xy 347.000224 -398.661867)
			(xy 346.977353 -398.705444) (xy 346.947788 -398.744788) (xy 346.912295 -398.77888) (xy 346.871792 -398.806836)
			(xy 346.82733 -398.827934) (xy 346.780059 -398.841626) (xy 346.731204 -398.847558) (xy 346.682029 -398.845577)
			(xy 346.63381 -398.835733) (xy 346.587794 -398.818281) (xy 346.545173 -398.793674) (xy 346.507052 -398.762549)
			(xy 346.474417 -398.725712) (xy 346.448114 -398.684116) (xy 346.428823 -398.63884) (xy 346.417046 -398.591056)
			(xy 346.413086 -398.542002) (xy 345.824048 -398.542002) (xy 345.823553 -398.566609) (xy 345.815658 -398.615186)
			(xy 345.800074 -398.661867) (xy 345.777203 -398.705444) (xy 345.747638 -398.744788) (xy 345.712145 -398.77888)
			(xy 345.671642 -398.806836) (xy 345.62718 -398.827934) (xy 345.579909 -398.841626) (xy 345.531054 -398.847558)
			(xy 345.481879 -398.845577) (xy 345.43366 -398.835733) (xy 345.387644 -398.818281) (xy 345.345023 -398.793674)
			(xy 345.306902 -398.762549) (xy 345.274267 -398.725712) (xy 345.247964 -398.684116) (xy 345.228673 -398.63884)
			(xy 345.216896 -398.591056) (xy 345.212936 -398.542002) (xy 344.624152 -398.542002) (xy 344.623657 -398.566609)
			(xy 344.615762 -398.615186) (xy 344.600178 -398.661867) (xy 344.577307 -398.705444) (xy 344.547742 -398.744788)
			(xy 344.512249 -398.77888) (xy 344.471746 -398.806836) (xy 344.427284 -398.827934) (xy 344.380013 -398.841626)
			(xy 344.331158 -398.847558) (xy 344.281983 -398.845577) (xy 344.233764 -398.835733) (xy 344.187748 -398.818281)
			(xy 344.145127 -398.793674) (xy 344.107006 -398.762549) (xy 344.074371 -398.725712) (xy 344.048068 -398.684116)
			(xy 344.028777 -398.63884) (xy 344.017 -398.591056) (xy 344.01304 -398.542002) (xy 343.424002 -398.542002)
			(xy 343.423507 -398.566609) (xy 343.415612 -398.615186) (xy 343.400028 -398.661867) (xy 343.377157 -398.705444)
			(xy 343.347592 -398.744788) (xy 343.312099 -398.77888) (xy 343.271596 -398.806836) (xy 343.227134 -398.827934)
			(xy 343.179863 -398.841626) (xy 343.131008 -398.847558) (xy 343.081833 -398.845577) (xy 343.033614 -398.835733)
			(xy 342.987598 -398.818281) (xy 342.944977 -398.793674) (xy 342.906856 -398.762549) (xy 342.874221 -398.725712)
			(xy 342.847918 -398.684116) (xy 342.828627 -398.63884) (xy 342.81685 -398.591056) (xy 342.81289 -398.542002)
			(xy 342.224106 -398.542002) (xy 342.223611 -398.566609) (xy 342.215716 -398.615186) (xy 342.200132 -398.661867)
			(xy 342.177261 -398.705444) (xy 342.147696 -398.744788) (xy 342.112203 -398.77888) (xy 342.0717 -398.806836)
			(xy 342.027238 -398.827934) (xy 341.979967 -398.841626) (xy 341.931112 -398.847558) (xy 341.881937 -398.845577)
			(xy 341.833718 -398.835733) (xy 341.787702 -398.818281) (xy 341.745081 -398.793674) (xy 341.70696 -398.762549)
			(xy 341.674325 -398.725712) (xy 341.648022 -398.684116) (xy 341.628731 -398.63884) (xy 341.616954 -398.591056)
			(xy 341.612994 -398.542002) (xy 341.02421 -398.542002) (xy 341.023715 -398.566609) (xy 341.01582 -398.615186)
			(xy 341.000236 -398.661867) (xy 340.977365 -398.705444) (xy 340.9478 -398.744788) (xy 340.912307 -398.77888)
			(xy 340.871804 -398.806836) (xy 340.827342 -398.827934) (xy 340.780071 -398.841626) (xy 340.731216 -398.847558)
			(xy 340.682041 -398.845577) (xy 340.633822 -398.835733) (xy 340.587806 -398.818281) (xy 340.545185 -398.793674)
			(xy 340.507064 -398.762549) (xy 340.474429 -398.725712) (xy 340.448126 -398.684116) (xy 340.428835 -398.63884)
			(xy 340.417058 -398.591056) (xy 340.413098 -398.542002) (xy 339.82406 -398.542002) (xy 339.823565 -398.566609)
			(xy 339.81567 -398.615186) (xy 339.800086 -398.661867) (xy 339.777215 -398.705444) (xy 339.74765 -398.744788)
			(xy 339.712157 -398.77888) (xy 339.671654 -398.806836) (xy 339.627192 -398.827934) (xy 339.579921 -398.841626)
			(xy 339.531066 -398.847558) (xy 339.481891 -398.845577) (xy 339.433672 -398.835733) (xy 339.387656 -398.818281)
			(xy 339.345035 -398.793674) (xy 339.306914 -398.762549) (xy 339.274279 -398.725712) (xy 339.247976 -398.684116)
			(xy 339.228685 -398.63884) (xy 339.216908 -398.591056) (xy 339.212948 -398.542002) (xy 338.624164 -398.542002)
			(xy 338.623669 -398.566609) (xy 338.615774 -398.615186) (xy 338.60019 -398.661867) (xy 338.577319 -398.705444)
			(xy 338.547754 -398.744788) (xy 338.512261 -398.77888) (xy 338.471758 -398.806836) (xy 338.427296 -398.827934)
			(xy 338.380025 -398.841626) (xy 338.33117 -398.847558) (xy 338.281995 -398.845577) (xy 338.233776 -398.835733)
			(xy 338.18776 -398.818281) (xy 338.145139 -398.793674) (xy 338.107018 -398.762549) (xy 338.074383 -398.725712)
			(xy 338.04808 -398.684116) (xy 338.028789 -398.63884) (xy 338.017012 -398.591056) (xy 338.013052 -398.542002)
			(xy 337.424014 -398.542002) (xy 337.423519 -398.566609) (xy 337.415624 -398.615186) (xy 337.40004 -398.661867)
			(xy 337.377169 -398.705444) (xy 337.347604 -398.744788) (xy 337.312111 -398.77888) (xy 337.271608 -398.806836)
			(xy 337.227146 -398.827934) (xy 337.179875 -398.841626) (xy 337.13102 -398.847558) (xy 337.081845 -398.845577)
			(xy 337.033626 -398.835733) (xy 336.98761 -398.818281) (xy 336.944989 -398.793674) (xy 336.906868 -398.762549)
			(xy 336.874233 -398.725712) (xy 336.84793 -398.684116) (xy 336.828639 -398.63884) (xy 336.816862 -398.591056)
			(xy 336.812902 -398.542002) (xy 336.223864 -398.542002) (xy 336.223369 -398.566609) (xy 336.215474 -398.615186)
			(xy 336.19989 -398.661867) (xy 336.177019 -398.705444) (xy 336.147454 -398.744788) (xy 336.111961 -398.77888)
			(xy 336.071458 -398.806836) (xy 336.026996 -398.827934) (xy 335.979725 -398.841626) (xy 335.93087 -398.847558)
			(xy 335.881695 -398.845577) (xy 335.833476 -398.835733) (xy 335.78746 -398.818281) (xy 335.744839 -398.793674)
			(xy 335.706718 -398.762549) (xy 335.674083 -398.725712) (xy 335.64778 -398.684116) (xy 335.628489 -398.63884)
			(xy 335.616712 -398.591056) (xy 335.612752 -398.542002) (xy 334.069343 -398.542002) (xy 334.068399 -398.548469)
			(xy 334.049322 -398.61226) (xy 334.021189 -398.672608) (xy 334.003396 -398.700752) (xy 333.998347 -398.709276)
			(xy 333.994526 -398.728693) (xy 333.998342 -398.748112) (xy 334.003396 -398.756632) (xy 334.021165 -398.784787)
			(xy 334.049261 -398.845144) (xy 334.068332 -398.90893) (xy 334.077977 -398.974804) (xy 334.07858 -399.008092)
			(xy 334.078138 -399.037392) (xy 334.070691 -399.095516) (xy 334.055867 -399.152208) (xy 334.045306 -399.179542)
			(xy 334.041242 -399.189194) (xy 334.04175 -399.20926) (xy 334.049623 -399.227119) (xy 355.897944 -399.227119)
			(xy 355.897944 -399.175145) (xy 355.906074 -399.12381) (xy 355.922135 -399.07438) (xy 355.945731 -399.02807)
			(xy 355.976281 -398.986022) (xy 356.013032 -398.949271) (xy 356.05508 -398.918721) (xy 356.10139 -398.895125)
			(xy 356.15082 -398.879064) (xy 356.202155 -398.870934) (xy 356.254129 -398.870934) (xy 356.305464 -398.879064)
			(xy 356.354894 -398.895125) (xy 356.401204 -398.918721) (xy 356.443252 -398.949271) (xy 356.480003 -398.986022)
			(xy 356.510553 -399.02807) (xy 356.534149 -399.07438) (xy 356.55021 -399.12381) (xy 356.55834 -399.175145)
			(xy 356.55885 -399.201132) (xy 356.55834 -399.227119) (xy 356.55021 -399.278454) (xy 356.534149 -399.327884)
			(xy 356.510553 -399.374194) (xy 356.480003 -399.416242) (xy 356.443252 -399.452993) (xy 356.401204 -399.483543)
			(xy 356.354894 -399.507139) (xy 356.305464 -399.5232) (xy 356.254129 -399.53133) (xy 356.202155 -399.53133)
			(xy 356.15082 -399.5232) (xy 356.10139 -399.507139) (xy 356.05508 -399.483543) (xy 356.013032 -399.452993)
			(xy 355.976281 -399.416242) (xy 355.945731 -399.374194) (xy 355.922135 -399.327884) (xy 355.906074 -399.278454)
			(xy 355.897944 -399.227119) (xy 334.049623 -399.227119) (xy 334.079596 -399.295112) (xy 334.094074 -399.309082)
			(xy 334.10398 -399.312638) (xy 334.127337 -399.321846) (xy 334.171184 -399.3463) (xy 334.210831 -399.377101)
			(xy 334.245367 -399.41354) (xy 334.273999 -399.45478) (xy 334.296068 -399.499875) (xy 334.311068 -399.547787)
			(xy 334.318653 -399.597415) (xy 334.319118 -399.622518) (xy 334.318608 -399.648505) (xy 334.310478 -399.69984)
			(xy 334.294417 -399.74927) (xy 334.270821 -399.79558) (xy 334.240271 -399.837628) (xy 334.20352 -399.874379)
			(xy 334.161472 -399.904929) (xy 334.115162 -399.928525) (xy 334.065732 -399.944586) (xy 334.014397 -399.952716)
			(xy 333.962423 -399.952716) (xy 333.911088 -399.944586) (xy 333.861658 -399.928525) (xy 333.815348 -399.904929)
			(xy 333.7733 -399.874379) (xy 333.736549 -399.837628) (xy 333.705999 -399.79558) (xy 333.682403 -399.74927)
			(xy 333.666342 -399.69984) (xy 333.658212 -399.648505) (xy 333.657702 -399.622518) (xy 333.657803 -399.611307)
			(xy 333.659329 -399.588936) (xy 333.66075 -399.577814) (xy 333.662274 -399.5674) (xy 333.65694 -399.547842)
			(xy 333.599282 -399.473928) (xy 333.581502 -399.464276) (xy 333.571088 -399.463006) (xy 333.540908 -399.459145)
			(xy 333.481833 -399.44459) (xy 333.425208 -399.422335) (xy 333.372032 -399.392771) (xy 333.323243 -399.356421)
			(xy 333.279703 -399.313925) (xy 333.242178 -399.266033) (xy 333.211333 -399.21359) (xy 333.187709 -399.157522)
			(xy 333.171725 -399.098818) (xy 333.163663 -399.038513) (xy 333.163164 -399.008092) (xy 330.34605 -399.008092)
			(xy 330.34605 -399.040096) (xy 330.3524 -399.057114) (xy 330.358496 -399.064226) (xy 330.376137 -399.085158)
			(xy 330.40586 -399.131125) (xy 330.4287 -399.180872) (xy 330.444187 -399.233375) (xy 330.452002 -399.287554)
			(xy 330.452476 -399.314924) (xy 330.452305 -399.331263) (xy 330.44951 -399.36382) (xy 330.446888 -399.379948)
			(xy 330.444856 -399.392394) (xy 330.452222 -399.416016) (xy 330.52893 -399.492216) (xy 330.552552 -399.499582)
			(xy 330.564744 -399.497296) (xy 330.586973 -399.493582) (xy 330.63187 -399.489636) (xy 330.654406 -399.489422)
			(xy 330.685101 -399.489901) (xy 330.746041 -399.497322) (xy 330.805647 -399.51202) (xy 330.863051 -399.53378)
			(xy 330.917422 -399.562288) (xy 330.94295 -399.579338) (xy 330.951702 -399.584809) (xy 330.971906 -399.588937)
			(xy 330.99211 -399.584809) (xy 331.000862 -399.579338) (xy 331.026388 -399.562281) (xy 331.08075 -399.533747)
			(xy 331.138153 -399.511972) (xy 331.197762 -399.497272) (xy 331.258709 -399.489863) (xy 331.289406 -399.489422)
			(xy 331.320101 -399.489901) (xy 331.381041 -399.497322) (xy 331.440647 -399.51202) (xy 331.498051 -399.53378)
			(xy 331.552422 -399.562288) (xy 331.57795 -399.579338) (xy 331.586702 -399.584809) (xy 331.606906 -399.588937)
			(xy 331.62711 -399.584809) (xy 331.635862 -399.579338) (xy 331.661388 -399.562281) (xy 331.71575 -399.533747)
			(xy 331.773153 -399.511972) (xy 331.832762 -399.497272) (xy 331.893709 -399.489863) (xy 331.924406 -399.489422)
			(xy 331.955137 -399.489868) (xy 332.016151 -399.497277) (xy 332.075828 -399.511987) (xy 332.133295 -399.533784)
			(xy 332.187717 -399.562348) (xy 332.238299 -399.597264) (xy 332.284303 -399.638023) (xy 332.325058 -399.68403)
			(xy 332.359971 -399.734614) (xy 332.388531 -399.789037) (xy 332.410323 -399.846507) (xy 332.425029 -399.906184)
			(xy 332.432434 -399.967199) (xy 332.432914 -399.99793) (xy 332.432434 -400.028625) (xy 332.42501 -400.089564)
			(xy 332.410311 -400.149169) (xy 332.38855 -400.206572) (xy 332.360042 -400.260942) (xy 332.342998 -400.286474)
			(xy 332.337532 -400.295226) (xy 332.333415 -400.315425) (xy 332.337552 -400.33562) (xy 332.342998 -400.344386)
			(xy 332.361286 -400.372834) (xy 332.368144 -400.384518) (xy 332.391258 -400.397472) (xy 332.505812 -400.397726)
			(xy 332.528672 -400.384518) (xy 332.535784 -400.372834) (xy 332.553064 -400.344952) (xy 332.593704 -400.293461)
			(xy 332.640629 -400.247624) (xy 332.693059 -400.208202) (xy 332.750124 -400.175851) (xy 332.810875 -400.151107)
			(xy 332.874304 -400.134382) (xy 332.939357 -400.125953) (xy 332.972156 -400.125438) (xy 333.002889 -400.125881)
			(xy 333.063907 -400.133286) (xy 333.123587 -400.147992) (xy 333.18106 -400.169785) (xy 333.235485 -400.198348)
			(xy 333.286071 -400.233263) (xy 333.332079 -400.274022) (xy 333.372838 -400.32003) (xy 333.407753 -400.370616)
			(xy 333.436316 -400.425042) (xy 333.458109 -400.482515) (xy 333.472815 -400.542195) (xy 333.480219 -400.603213)
			(xy 333.480664 -400.633946) (xy 333.480321 -400.659591) (xy 333.475108 -400.710617) (xy 333.473925 -400.71675)
			(xy 334.691736 -400.71675) (xy 334.692137 -400.693516) (xy 334.698636 -400.647506) (xy 334.711512 -400.602859)
			(xy 334.730512 -400.560454) (xy 334.755262 -400.521128) (xy 334.769968 -400.503136) (xy 334.776064 -400.496024)
			(xy 334.78216 -400.479514) (xy 334.78216 -400.395186) (xy 334.776064 -400.378676) (xy 334.769968 -400.371564)
			(xy 334.755285 -400.353555) (xy 334.730533 -400.314232) (xy 334.711527 -400.271832) (xy 334.698643 -400.227189)
			(xy 334.692133 -400.181182) (xy 334.691736 -400.15795) (xy 334.692246 -400.131963) (xy 334.700376 -400.080628)
			(xy 334.716437 -400.031198) (xy 334.740033 -399.984888) (xy 334.770583 -399.94284) (xy 334.807334 -399.906089)
			(xy 334.849382 -399.875539) (xy 334.895692 -399.851943) (xy 334.945122 -399.835882) (xy 334.996457 -399.827752)
			(xy 335.048431 -399.827752) (xy 335.099766 -399.835882) (xy 335.149196 -399.851943) (xy 335.195506 -399.875539)
			(xy 335.237554 -399.906089) (xy 335.274305 -399.94284) (xy 335.304855 -399.984888) (xy 335.328451 -400.031198)
			(xy 335.344512 -400.080628) (xy 335.352642 -400.131963) (xy 335.353152 -400.15795) (xy 335.352754 -400.181184)
			(xy 335.346255 -400.227194) (xy 335.333378 -400.271841) (xy 335.314377 -400.314246) (xy 335.289626 -400.353573)
			(xy 335.27492 -400.371564) (xy 335.268824 -400.378676) (xy 335.262728 -400.395186) (xy 335.262728 -400.479514)
			(xy 335.268824 -400.496024) (xy 335.27492 -400.503136) (xy 335.289616 -400.521135) (xy 335.314364 -400.560462)
			(xy 335.333365 -400.602865) (xy 335.346247 -400.647509) (xy 335.352755 -400.693517) (xy 335.353152 -400.71675)
			(xy 335.352642 -400.742737) (xy 335.344512 -400.794072) (xy 335.328451 -400.843502) (xy 335.304855 -400.889812)
			(xy 335.274305 -400.93186) (xy 335.237554 -400.968611) (xy 335.195506 -400.999161) (xy 335.149196 -401.022757)
			(xy 335.099766 -401.038818) (xy 335.048431 -401.046948) (xy 334.996457 -401.046948) (xy 334.945122 -401.038818)
			(xy 334.895692 -401.022757) (xy 334.849382 -400.999161) (xy 334.807334 -400.968611) (xy 334.770583 -400.93186)
			(xy 334.740033 -400.889812) (xy 334.716437 -400.843502) (xy 334.700376 -400.794072) (xy 334.692246 -400.742737)
			(xy 334.691736 -400.71675) (xy 333.473925 -400.71675) (xy 333.47025 -400.7358) (xy 333.468472 -400.745452)
			(xy 333.47152 -400.763486) (xy 333.51597 -400.838924) (xy 333.530448 -400.850354) (xy 333.539592 -400.853148)
			(xy 333.565112 -400.861624) (xy 333.613663 -400.884741) (xy 333.658491 -400.914439) (xy 333.698711 -400.950132)
			(xy 333.733526 -400.991113) (xy 333.762249 -401.036572) (xy 333.784311 -401.085611) (xy 333.799276 -401.13726)
			(xy 333.806849 -401.190498) (xy 333.807308 -401.217384) (xy 333.806846 -401.244638) (xy 333.799091 -401.29859)
			(xy 333.783736 -401.35089) (xy 333.761094 -401.400472) (xy 333.731627 -401.446327) (xy 333.695933 -401.487522)
			(xy 333.65474 -401.523217) (xy 333.608886 -401.552687) (xy 333.559305 -401.57533) (xy 333.507006 -401.590687)
			(xy 333.453054 -401.598445) (xy 333.4258 -401.598892) (xy 333.396849 -401.598355) (xy 333.33961 -401.589607)
			(xy 333.284351 -401.572312) (xy 333.232338 -401.546866) (xy 333.184767 -401.513855) (xy 333.14273 -401.474035)
			(xy 333.107191 -401.428321) (xy 333.078967 -401.377763) (xy 333.058705 -401.32352) (xy 333.046871 -401.26684)
			(xy 333.0448 -401.237958) (xy 333.044292 -401.228306) (xy 333.036672 -401.211288) (xy 332.974696 -401.14982)
			(xy 332.957932 -401.142454) (xy 332.94828 -401.141946) (xy 332.916959 -401.140015) (xy 332.855111 -401.129388)
			(xy 332.795042 -401.111225) (xy 332.737668 -401.085803) (xy 332.683861 -401.053509) (xy 332.634441 -401.014834)
			(xy 332.590159 -400.970368) (xy 332.551691 -400.920786) (xy 332.535276 -400.894042) (xy 332.528418 -400.882358)
			(xy 332.505304 -400.869404) (xy 332.39075 -400.86915) (xy 332.36789 -400.882358) (xy 332.360778 -400.894042)
			(xy 332.342998 -400.921474) (xy 332.337532 -400.930226) (xy 332.333415 -400.950425) (xy 332.337552 -400.97062)
			(xy 332.342998 -400.979386) (xy 332.360053 -401.004913) (xy 332.388582 -401.059275) (xy 332.410353 -401.116679)
			(xy 332.425049 -401.176288) (xy 332.432455 -401.237233) (xy 332.432914 -401.26793) (xy 332.432434 -401.298625)
			(xy 332.42501 -401.359564) (xy 332.410311 -401.419169) (xy 332.38855 -401.476572) (xy 332.360042 -401.530942)
			(xy 332.342998 -401.556474) (xy 332.337532 -401.565226) (xy 332.333415 -401.585425) (xy 332.337552 -401.60562)
			(xy 332.342998 -401.614386) (xy 332.360053 -401.639913) (xy 332.378382 -401.674838) (xy 335.962244 -401.674838)
			(xy 335.962244 -400.811238) (xy 335.962723 -400.784882) (xy 335.969986 -400.732674) (xy 335.984365 -400.681961)
			(xy 336.005586 -400.63371) (xy 336.033247 -400.588839) (xy 336.066819 -400.548202) (xy 336.085942 -400.53006)
			(xy 336.093054 -400.52371) (xy 336.101182 -400.506946) (xy 336.109564 -400.420332) (xy 336.104484 -400.402552)
			(xy 336.098896 -400.394678) (xy 336.084751 -400.374827) (xy 336.062291 -400.331571) (xy 336.046977 -400.285299)
			(xy 336.039197 -400.237184) (xy 336.038698 -400.212814) (xy 336.03922 -400.187559) (xy 336.047533 -400.137737)
			(xy 336.063934 -400.089963) (xy 336.087975 -400.04554) (xy 336.118999 -400.00568) (xy 336.156161 -399.97147)
			(xy 336.198447 -399.943844) (xy 336.244703 -399.923554) (xy 336.293668 -399.911154) (xy 336.344006 -399.906983)
			(xy 336.394344 -399.911154) (xy 336.443309 -399.923554) (xy 336.489565 -399.943844) (xy 336.531851 -399.97147)
			(xy 336.569013 -400.00568) (xy 336.600037 -400.04554) (xy 336.624078 -400.089963) (xy 336.640479 -400.137737)
			(xy 336.648792 -400.187559) (xy 336.649314 -400.212814) (xy 336.648843 -400.237187) (xy 336.641083 -400.28531)
			(xy 336.625763 -400.331586) (xy 336.603275 -400.374834) (xy 336.589116 -400.394678) (xy 336.583528 -400.402552)
			(xy 336.578448 -400.420332) (xy 336.58683 -400.506946) (xy 336.594958 -400.52371) (xy 336.60207 -400.53006)
			(xy 336.621208 -400.54819) (xy 336.654795 -400.588822) (xy 336.682465 -400.633693) (xy 336.703692 -400.681947)
			(xy 336.71807 -400.732665) (xy 336.725325 -400.78488) (xy 336.725768 -400.811238) (xy 336.725768 -401.674838)
			(xy 337.16214 -401.674838) (xy 337.16214 -400.811238) (xy 337.16262 -400.784882) (xy 337.169883 -400.732674)
			(xy 337.184262 -400.681962) (xy 337.205483 -400.633711) (xy 337.233143 -400.58884) (xy 337.266715 -400.548202)
			(xy 337.285838 -400.53006) (xy 337.29295 -400.523456) (xy 337.301332 -400.506946) (xy 337.30946 -400.420078)
			(xy 337.304634 -400.402298) (xy 337.298792 -400.394678) (xy 337.284687 -400.374809) (xy 337.262264 -400.331554)
			(xy 337.247007 -400.285284) (xy 337.239302 -400.237175) (xy 337.238848 -400.212814) (xy 337.23937 -400.187559)
			(xy 337.247683 -400.137737) (xy 337.264084 -400.089963) (xy 337.288125 -400.04554) (xy 337.319149 -400.00568)
			(xy 337.356311 -399.97147) (xy 337.398597 -399.943844) (xy 337.444853 -399.923554) (xy 337.493818 -399.911154)
			(xy 337.544156 -399.906983) (xy 337.594494 -399.911154) (xy 337.643459 -399.923554) (xy 337.689715 -399.943844)
			(xy 337.732001 -399.97147) (xy 337.769163 -400.00568) (xy 337.800187 -400.04554) (xy 337.824228 -400.089963)
			(xy 337.840629 -400.137737) (xy 337.848942 -400.187559) (xy 337.849464 -400.212814) (xy 337.848997 -400.237217)
			(xy 337.841238 -400.285401) (xy 337.825918 -400.331739) (xy 337.803427 -400.375053) (xy 337.789266 -400.394932)
			(xy 337.783678 -400.402552) (xy 337.778598 -400.420332) (xy 337.786726 -400.5072) (xy 337.795108 -400.52371)
			(xy 337.80222 -400.530314) (xy 337.821289 -400.548466) (xy 337.85478 -400.589089) (xy 337.882377 -400.633924)
			(xy 337.903558 -400.682122) (xy 337.917923 -400.732772) (xy 337.925199 -400.784915) (xy 337.925664 -400.811238)
			(xy 337.925664 -401.674838) (xy 338.362544 -401.674838) (xy 338.362544 -400.811238) (xy 338.36301 -400.784893)
			(xy 338.370257 -400.732705) (xy 338.384606 -400.682007) (xy 338.405784 -400.633761) (xy 338.433389 -400.588882)
			(xy 338.466898 -400.548221) (xy 338.485988 -400.53006) (xy 338.4931 -400.52371) (xy 338.501228 -400.506946)
			(xy 338.50961 -400.420332) (xy 338.50453 -400.402552) (xy 338.498942 -400.394678) (xy 338.484791 -400.374832)
			(xy 338.462334 -400.331573) (xy 338.447022 -400.2853) (xy 338.439242 -400.237184) (xy 338.438744 -400.212814)
			(xy 338.439266 -400.187559) (xy 338.447579 -400.137737) (xy 338.46398 -400.089963) (xy 338.488021 -400.04554)
			(xy 338.519045 -400.00568) (xy 338.556207 -399.97147) (xy 338.598493 -399.943844) (xy 338.644749 -399.923554)
			(xy 338.693714 -399.911154) (xy 338.744052 -399.906983) (xy 338.79439 -399.911154) (xy 338.843355 -399.923554)
			(xy 338.889611 -399.943844) (xy 338.931897 -399.97147) (xy 338.969059 -400.00568) (xy 339.000083 -400.04554)
			(xy 339.024124 -400.089963) (xy 339.040525 -400.137737) (xy 339.048838 -400.187559) (xy 339.04936 -400.212814)
			(xy 339.04888 -400.237186) (xy 339.041121 -400.285309) (xy 339.025804 -400.331585) (xy 339.003319 -400.374833)
			(xy 338.989162 -400.394678) (xy 338.983574 -400.402552) (xy 338.978494 -400.420332) (xy 338.986876 -400.506946)
			(xy 338.995004 -400.52371) (xy 339.002116 -400.53006) (xy 339.021212 -400.548217) (xy 339.054735 -400.588871)
			(xy 339.08235 -400.633748) (xy 339.103533 -400.681996) (xy 339.11788 -400.732698) (xy 339.12512 -400.784891)
			(xy 339.12556 -400.811238) (xy 339.12556 -401.674838) (xy 339.56244 -401.674838) (xy 339.56244 -400.811238)
			(xy 339.562907 -400.784893) (xy 339.570154 -400.732705) (xy 339.584503 -400.682007) (xy 339.60568 -400.633761)
			(xy 339.633285 -400.588882) (xy 339.666794 -400.548221) (xy 339.685884 -400.53006) (xy 339.692996 -400.52371)
			(xy 339.701124 -400.506946) (xy 339.709506 -400.420332) (xy 339.704426 -400.402552) (xy 339.698838 -400.394678)
			(xy 339.684686 -400.374832) (xy 339.66223 -400.331573) (xy 339.646918 -400.2853) (xy 339.639138 -400.237184)
			(xy 339.63864 -400.212814) (xy 339.639162 -400.187559) (xy 339.647475 -400.137737) (xy 339.663876 -400.089963)
			(xy 339.687917 -400.04554) (xy 339.718941 -400.00568) (xy 339.756103 -399.97147) (xy 339.798389 -399.943844)
			(xy 339.844645 -399.923554) (xy 339.89361 -399.911154) (xy 339.943948 -399.906983) (xy 339.994286 -399.911154)
			(xy 340.043251 -399.923554) (xy 340.089507 -399.943844) (xy 340.131793 -399.97147) (xy 340.168955 -400.00568)
			(xy 340.199979 -400.04554) (xy 340.22402 -400.089963) (xy 340.240421 -400.137737) (xy 340.248734 -400.187559)
			(xy 340.249256 -400.212814) (xy 340.248777 -400.237186) (xy 340.241018 -400.285309) (xy 340.225701 -400.331585)
			(xy 340.203215 -400.374833) (xy 340.189058 -400.394678) (xy 340.18347 -400.402552) (xy 340.17839 -400.420332)
			(xy 340.186772 -400.506946) (xy 340.1949 -400.52371) (xy 340.202012 -400.53006) (xy 340.221107 -400.548218)
			(xy 340.254631 -400.588871) (xy 340.282246 -400.633748) (xy 340.303428 -400.681996) (xy 340.317776 -400.732698)
			(xy 340.325016 -400.784891) (xy 340.325456 -400.811238) (xy 340.325456 -401.674838) (xy 340.762336 -401.674838)
			(xy 340.762336 -400.811238) (xy 340.762817 -400.784882) (xy 340.77008 -400.732674) (xy 340.784459 -400.681962)
			(xy 340.80568 -400.633711) (xy 340.83334 -400.58884) (xy 340.866912 -400.548202) (xy 340.886034 -400.53006)
			(xy 340.893146 -400.52371) (xy 340.901274 -400.506946) (xy 340.909656 -400.420332) (xy 340.904576 -400.402552)
			(xy 340.898988 -400.394678) (xy 340.884842 -400.374828) (xy 340.862383 -400.331571) (xy 340.847069 -400.285299)
			(xy 340.839289 -400.237184) (xy 340.83879 -400.212814) (xy 340.839312 -400.187559) (xy 340.847625 -400.137737)
			(xy 340.864026 -400.089963) (xy 340.888067 -400.04554) (xy 340.919091 -400.00568) (xy 340.956253 -399.97147)
			(xy 340.998539 -399.943844) (xy 341.044795 -399.923554) (xy 341.09376 -399.911154) (xy 341.144098 -399.906983)
			(xy 341.194436 -399.911154) (xy 341.243401 -399.923554) (xy 341.289657 -399.943844) (xy 341.331943 -399.97147)
			(xy 341.369105 -400.00568) (xy 341.400129 -400.04554) (xy 341.42417 -400.089963) (xy 341.440571 -400.137737)
			(xy 341.448884 -400.187559) (xy 341.449406 -400.212814) (xy 341.448936 -400.237187) (xy 341.441176 -400.285311)
			(xy 341.425856 -400.331586) (xy 341.403367 -400.374834) (xy 341.389208 -400.394678) (xy 341.38362 -400.402552)
			(xy 341.37854 -400.420332) (xy 341.386922 -400.506946) (xy 341.39505 -400.52371) (xy 341.402162 -400.53006)
			(xy 341.421298 -400.548192) (xy 341.454886 -400.588823) (xy 341.482556 -400.633693) (xy 341.503783 -400.681947)
			(xy 341.518162 -400.732665) (xy 341.525417 -400.78488) (xy 341.52586 -400.811238) (xy 341.52586 -401.674838)
			(xy 341.962232 -401.674838) (xy 341.962232 -400.811238) (xy 341.962714 -400.784883) (xy 341.969977 -400.732674)
			(xy 341.984356 -400.681962) (xy 342.005577 -400.633711) (xy 342.033236 -400.58884) (xy 342.066808 -400.548203)
			(xy 342.08593 -400.53006) (xy 342.093042 -400.52371) (xy 342.10117 -400.506946) (xy 342.109552 -400.420332)
			(xy 342.104472 -400.402552) (xy 342.098884 -400.394678) (xy 342.084738 -400.374828) (xy 342.062279 -400.331571)
			(xy 342.046965 -400.285299) (xy 342.039185 -400.237184) (xy 342.038686 -400.212814) (xy 342.039208 -400.187559)
			(xy 342.047521 -400.137737) (xy 342.063922 -400.089963) (xy 342.087963 -400.04554) (xy 342.118987 -400.00568)
			(xy 342.156149 -399.97147) (xy 342.198435 -399.943844) (xy 342.244691 -399.923554) (xy 342.293656 -399.911154)
			(xy 342.343994 -399.906983) (xy 342.394332 -399.911154) (xy 342.443297 -399.923554) (xy 342.489553 -399.943844)
			(xy 342.531839 -399.97147) (xy 342.569001 -400.00568) (xy 342.600025 -400.04554) (xy 342.624066 -400.089963)
			(xy 342.640467 -400.137737) (xy 342.64878 -400.187559) (xy 342.649302 -400.212814) (xy 342.648833 -400.237187)
			(xy 342.641073 -400.285311) (xy 342.625753 -400.331586) (xy 342.603263 -400.374834) (xy 342.589104 -400.394678)
			(xy 342.583516 -400.402552) (xy 342.578436 -400.420332) (xy 342.586818 -400.506946) (xy 342.594946 -400.52371)
			(xy 342.602058 -400.53006) (xy 342.621193 -400.548192) (xy 342.654781 -400.588824) (xy 342.682452 -400.633694)
			(xy 342.703679 -400.681947) (xy 342.718058 -400.732665) (xy 342.725313 -400.78488) (xy 342.725756 -400.811238)
			(xy 342.725756 -401.674838) (xy 343.162636 -401.674838) (xy 343.162636 -400.811238) (xy 343.163105 -400.784893)
			(xy 343.170352 -400.732705) (xy 343.1847 -400.682007) (xy 343.205877 -400.633761) (xy 343.233482 -400.588882)
			(xy 343.26699 -400.548221) (xy 343.28608 -400.53006) (xy 343.293192 -400.52371) (xy 343.30132 -400.506946)
			(xy 343.309702 -400.420332) (xy 343.304622 -400.402552) (xy 343.299034 -400.394678) (xy 343.284882 -400.374833)
			(xy 343.262425 -400.331573) (xy 343.247114 -400.2853) (xy 343.239334 -400.237184) (xy 343.238836 -400.212814)
			(xy 343.239358 -400.187559) (xy 343.247671 -400.137737) (xy 343.264072 -400.089963) (xy 343.288113 -400.04554)
			(xy 343.319137 -400.00568) (xy 343.356299 -399.97147) (xy 343.398585 -399.943844) (xy 343.444841 -399.923554)
			(xy 343.493806 -399.911154) (xy 343.544144 -399.906983) (xy 343.594482 -399.911154) (xy 343.643447 -399.923554)
			(xy 343.689703 -399.943844) (xy 343.731989 -399.97147) (xy 343.769151 -400.00568) (xy 343.800175 -400.04554)
			(xy 343.824216 -400.089963) (xy 343.840617 -400.137737) (xy 343.84893 -400.187559) (xy 343.849452 -400.212814)
			(xy 343.848973 -400.237186) (xy 343.841215 -400.285309) (xy 343.825897 -400.331585) (xy 343.803411 -400.374833)
			(xy 343.789254 -400.394678) (xy 343.783666 -400.402552) (xy 343.778586 -400.420332) (xy 343.786968 -400.506946)
			(xy 343.795096 -400.52371) (xy 343.802208 -400.53006) (xy 343.821303 -400.548218) (xy 343.854826 -400.588872)
			(xy 343.882442 -400.633749) (xy 343.903624 -400.681996) (xy 343.917972 -400.732698) (xy 343.925212 -400.784892)
			(xy 343.925652 -400.811238) (xy 343.925652 -401.674838) (xy 344.362532 -401.674838) (xy 344.362532 -400.811238)
			(xy 344.363002 -400.784894) (xy 344.370249 -400.732705) (xy 344.384597 -400.682007) (xy 344.405774 -400.633761)
			(xy 344.433378 -400.588882) (xy 344.466887 -400.548221) (xy 344.485976 -400.53006) (xy 344.493088 -400.52371)
			(xy 344.501216 -400.506946) (xy 344.509598 -400.420332) (xy 344.504518 -400.402552) (xy 344.49893 -400.394678)
			(xy 344.484777 -400.374833) (xy 344.462321 -400.331573) (xy 344.44701 -400.2853) (xy 344.43923 -400.237184)
			(xy 344.438732 -400.212814) (xy 344.439254 -400.187559) (xy 344.447567 -400.137737) (xy 344.463968 -400.089963)
			(xy 344.488009 -400.04554) (xy 344.519033 -400.00568) (xy 344.556195 -399.97147) (xy 344.598481 -399.943844)
			(xy 344.644737 -399.923554) (xy 344.693702 -399.911154) (xy 344.74404 -399.906983) (xy 344.794378 -399.911154)
			(xy 344.843343 -399.923554) (xy 344.889599 -399.943844) (xy 344.931885 -399.97147) (xy 344.969047 -400.00568)
			(xy 345.000071 -400.04554) (xy 345.024112 -400.089963) (xy 345.040513 -400.137737) (xy 345.048826 -400.187559)
			(xy 345.049348 -400.212814) (xy 345.04887 -400.237186) (xy 345.041111 -400.28531) (xy 345.025793 -400.331585)
			(xy 345.003307 -400.374833) (xy 344.98915 -400.394678) (xy 344.983562 -400.402552) (xy 344.978482 -400.420332)
			(xy 344.986864 -400.506946) (xy 344.994992 -400.52371) (xy 345.002104 -400.53006) (xy 345.021198 -400.548219)
			(xy 345.054722 -400.588873) (xy 345.082337 -400.633749) (xy 345.10352 -400.681997) (xy 345.117868 -400.732698)
			(xy 345.125108 -400.784892) (xy 345.125548 -400.811238) (xy 345.125548 -401.674838) (xy 345.562428 -401.674838)
			(xy 345.562428 -400.811238) (xy 345.562861 -400.784911) (xy 345.570111 -400.732757) (xy 345.584465 -400.682096)
			(xy 345.60565 -400.633891) (xy 345.633263 -400.589057) (xy 345.66678 -400.548447) (xy 345.685872 -400.530314)
			(xy 345.692984 -400.52371) (xy 345.701366 -400.5072) (xy 345.709494 -400.420332) (xy 345.704414 -400.402552)
			(xy 345.698826 -400.394932) (xy 345.684674 -400.375048) (xy 345.662185 -400.331735) (xy 345.646866 -400.285398)
			(xy 345.639106 -400.237216) (xy 345.638628 -400.212814) (xy 345.63915 -400.187559) (xy 345.647463 -400.137737)
			(xy 345.663864 -400.089963) (xy 345.687905 -400.04554) (xy 345.718929 -400.00568) (xy 345.756091 -399.97147)
			(xy 345.798377 -399.943844) (xy 345.844633 -399.923554) (xy 345.893598 -399.911154) (xy 345.943936 -399.906983)
			(xy 345.994274 -399.911154) (xy 346.043239 -399.923554) (xy 346.089495 -399.943844) (xy 346.131781 -399.97147)
			(xy 346.168943 -400.00568) (xy 346.199967 -400.04554) (xy 346.224008 -400.089963) (xy 346.240409 -400.137737)
			(xy 346.248722 -400.187559) (xy 346.249244 -400.212814) (xy 346.248748 -400.237172) (xy 346.241035 -400.285275)
			(xy 346.225792 -400.331545) (xy 346.203403 -400.374812) (xy 346.1893 -400.394678) (xy 346.183458 -400.402298)
			(xy 346.178632 -400.420078) (xy 346.18676 -400.506946) (xy 346.195142 -400.523456) (xy 346.202254 -400.53006)
			(xy 346.221389 -400.548193) (xy 346.254976 -400.588824) (xy 346.282648 -400.633694) (xy 346.303875 -400.681948)
			(xy 346.318253 -400.732665) (xy 346.325509 -400.78488) (xy 346.325952 -400.811238) (xy 346.325952 -401.674838)
			(xy 346.762324 -401.674838) (xy 346.762324 -400.811238) (xy 346.762809 -400.784883) (xy 346.770072 -400.732674)
			(xy 346.78445 -400.681963) (xy 346.80567 -400.633712) (xy 346.833329 -400.588841) (xy 346.8669 -400.548203)
			(xy 346.886022 -400.53006) (xy 346.893134 -400.52371) (xy 346.901262 -400.506946) (xy 346.909644 -400.420332)
			(xy 346.904564 -400.402552) (xy 346.898976 -400.394678) (xy 346.884829 -400.374829) (xy 346.86237 -400.331571)
			(xy 346.847057 -400.285299) (xy 346.839276 -400.237184) (xy 346.838778 -400.212814) (xy 346.8393 -400.187559)
			(xy 346.847613 -400.137737) (xy 346.864014 -400.089963) (xy 346.888055 -400.04554) (xy 346.919079 -400.00568)
			(xy 346.956241 -399.97147) (xy 346.998527 -399.943844) (xy 347.044783 -399.923554) (xy 347.093748 -399.911154)
			(xy 347.144086 -399.906983) (xy 347.194424 -399.911154) (xy 347.243389 -399.923554) (xy 347.289645 -399.943844)
			(xy 347.331931 -399.97147) (xy 347.369093 -400.00568) (xy 347.400117 -400.04554) (xy 347.424158 -400.089963)
			(xy 347.440559 -400.137737) (xy 347.448872 -400.187559) (xy 347.449394 -400.212814) (xy 347.448927 -400.237187)
			(xy 347.441166 -400.285311) (xy 347.425846 -400.331587) (xy 347.403355 -400.374834) (xy 347.389196 -400.394678)
			(xy 347.383608 -400.402552) (xy 347.378528 -400.420332) (xy 347.38691 -400.506946) (xy 347.395038 -400.52371)
			(xy 347.40215 -400.53006) (xy 347.421284 -400.548194) (xy 347.454872 -400.588825) (xy 347.482543 -400.633694)
			(xy 347.503771 -400.681948) (xy 347.518149 -400.732665) (xy 347.525405 -400.78488) (xy 347.525848 -400.811238)
			(xy 347.525848 -401.674838) (xy 347.962728 -401.674838) (xy 347.962728 -400.811238) (xy 347.963151 -400.784921)
			(xy 347.970376 -400.732785) (xy 347.984694 -400.682136) (xy 348.005834 -400.633934) (xy 348.033395 -400.589093)
			(xy 348.066855 -400.548463) (xy 348.085918 -400.530314) (xy 348.09303 -400.52371) (xy 348.101412 -400.5072)
			(xy 348.10954 -400.420332) (xy 348.10446 -400.402552) (xy 348.098872 -400.394932) (xy 348.084713 -400.375052)
			(xy 348.062227 -400.331737) (xy 348.04691 -400.285399) (xy 348.039152 -400.237216) (xy 348.038674 -400.212814)
			(xy 348.039196 -400.187559) (xy 348.047509 -400.137737) (xy 348.06391 -400.089963) (xy 348.087951 -400.04554)
			(xy 348.118975 -400.00568) (xy 348.156137 -399.97147) (xy 348.198423 -399.943844) (xy 348.244679 -399.923554)
			(xy 348.293644 -399.911154) (xy 348.343982 -399.906983) (xy 348.39432 -399.911154) (xy 348.443285 -399.923554)
			(xy 348.489541 -399.943844) (xy 348.531827 -399.97147) (xy 348.568989 -400.00568) (xy 348.600013 -400.04554)
			(xy 348.624054 -400.089963) (xy 348.640455 -400.137737) (xy 348.648768 -400.187559) (xy 348.64929 -400.212814)
			(xy 348.648804 -400.237173) (xy 348.64109 -400.285276) (xy 348.625844 -400.331546) (xy 348.603451 -400.374813)
			(xy 348.589346 -400.394678) (xy 348.583504 -400.402298) (xy 348.578678 -400.420078) (xy 348.586806 -400.506946)
			(xy 348.595188 -400.523456) (xy 348.6023 -400.53006) (xy 348.621413 -400.5482) (xy 348.654931 -400.58886)
			(xy 348.682542 -400.633741) (xy 348.703721 -400.681992) (xy 348.718066 -400.732696) (xy 348.725304 -400.784891)
			(xy 348.725744 -400.811238) (xy 348.725744 -401.674838) (xy 349.162624 -401.674838) (xy 349.162624 -400.811238)
			(xy 349.163064 -400.784892) (xy 349.170313 -400.732701) (xy 349.184665 -400.682002) (xy 349.205847 -400.633755)
			(xy 349.233459 -400.588877) (xy 349.266975 -400.548219) (xy 349.286068 -400.53006) (xy 349.29318 -400.52371)
			(xy 349.301308 -400.506946) (xy 349.30969 -400.420332) (xy 349.30461 -400.402552) (xy 349.299022 -400.394678)
			(xy 349.284868 -400.374834) (xy 349.262412 -400.331574) (xy 349.247101 -400.2853) (xy 349.239322 -400.237184)
			(xy 349.238824 -400.212814) (xy 349.239346 -400.187559) (xy 349.247659 -400.137737) (xy 349.26406 -400.089963)
			(xy 349.288101 -400.04554) (xy 349.319125 -400.00568) (xy 349.356287 -399.97147) (xy 349.398573 -399.943844)
			(xy 349.444829 -399.923554) (xy 349.493794 -399.911154) (xy 349.544132 -399.906983) (xy 349.59447 -399.911154)
			(xy 349.643435 -399.923554) (xy 349.689691 -399.943844) (xy 349.731977 -399.97147) (xy 349.769139 -400.00568)
			(xy 349.800163 -400.04554) (xy 349.824204 -400.089963) (xy 349.840605 -400.137737) (xy 349.848918 -400.187559)
			(xy 349.84944 -400.212814) (xy 349.848964 -400.237186) (xy 349.841205 -400.28531) (xy 349.825886 -400.331585)
			(xy 349.803399 -400.374833) (xy 349.789242 -400.394678) (xy 349.783654 -400.402552) (xy 349.778574 -400.420332)
			(xy 349.786956 -400.506946) (xy 349.795084 -400.52371) (xy 349.802196 -400.53006) (xy 349.821308 -400.548201)
			(xy 349.854827 -400.58886) (xy 349.882438 -400.633741) (xy 349.903617 -400.681992) (xy 349.917962 -400.732696)
			(xy 349.9252 -400.784891) (xy 349.92564 -400.811238) (xy 349.92564 -401.674838) (xy 350.36252 -401.674838)
			(xy 350.36252 -400.811238) (xy 350.362962 -400.784892) (xy 350.37021 -400.732702) (xy 350.384562 -400.682002)
			(xy 350.405744 -400.633756) (xy 350.433355 -400.588877) (xy 350.466871 -400.548219) (xy 350.485964 -400.53006)
			(xy 350.493076 -400.52371) (xy 350.501204 -400.506946) (xy 350.509586 -400.420332) (xy 350.504506 -400.402552)
			(xy 350.498918 -400.394678) (xy 350.484764 -400.374834) (xy 350.462308 -400.331574) (xy 350.446997 -400.2853)
			(xy 350.439218 -400.237184) (xy 350.43872 -400.212814) (xy 350.439242 -400.187559) (xy 350.447555 -400.137737)
			(xy 350.463956 -400.089963) (xy 350.487997 -400.04554) (xy 350.519021 -400.00568) (xy 350.556183 -399.97147)
			(xy 350.598469 -399.943844) (xy 350.644725 -399.923554) (xy 350.69369 -399.911154) (xy 350.744028 -399.906983)
			(xy 350.794366 -399.911154) (xy 350.843331 -399.923554) (xy 350.889587 -399.943844) (xy 350.931873 -399.97147)
			(xy 350.969035 -400.00568) (xy 351.000059 -400.04554) (xy 351.0241 -400.089963) (xy 351.040501 -400.137737)
			(xy 351.048814 -400.187559) (xy 351.049336 -400.212814) (xy 351.04886 -400.237186) (xy 351.041101 -400.28531)
			(xy 351.025783 -400.331585) (xy 351.003296 -400.374833) (xy 350.989138 -400.394678) (xy 350.98355 -400.402552)
			(xy 350.97847 -400.420332) (xy 350.986852 -400.506946) (xy 350.99498 -400.52371) (xy 351.002092 -400.53006)
			(xy 351.021203 -400.548201) (xy 351.054722 -400.588861) (xy 351.082333 -400.633742) (xy 351.103513 -400.681992)
			(xy 351.117858 -400.732696) (xy 351.125096 -400.784891) (xy 351.125536 -400.811238) (xy 351.125536 -401.674838)
			(xy 351.562416 -401.674838) (xy 351.562416 -400.811238) (xy 351.562859 -400.784892) (xy 351.570108 -400.732702)
			(xy 351.584459 -400.682002) (xy 351.605641 -400.633756) (xy 351.633252 -400.588878) (xy 351.666767 -400.548219)
			(xy 351.68586 -400.53006) (xy 351.692972 -400.52371) (xy 351.7011 -400.506946) (xy 351.709482 -400.420332)
			(xy 351.704402 -400.402552) (xy 351.698814 -400.394678) (xy 351.684659 -400.374834) (xy 351.662204 -400.331574)
			(xy 351.646893 -400.2853) (xy 351.639114 -400.237184) (xy 351.638616 -400.212814) (xy 351.639138 -400.187559)
			(xy 351.647451 -400.137737) (xy 351.663852 -400.089963) (xy 351.687893 -400.04554) (xy 351.718917 -400.00568)
			(xy 351.756079 -399.97147) (xy 351.798365 -399.943844) (xy 351.844621 -399.923554) (xy 351.893586 -399.911154)
			(xy 351.943924 -399.906983) (xy 351.994262 -399.911154) (xy 352.043227 -399.923554) (xy 352.089483 -399.943844)
			(xy 352.131769 -399.97147) (xy 352.168931 -400.00568) (xy 352.199955 -400.04554) (xy 352.223996 -400.089963)
			(xy 352.240397 -400.137737) (xy 352.24871 -400.187559) (xy 352.249232 -400.212814) (xy 352.248757 -400.237186)
			(xy 352.240998 -400.28531) (xy 352.225679 -400.331585) (xy 352.203192 -400.374833) (xy 352.189034 -400.394678)
			(xy 352.183446 -400.402552) (xy 352.178366 -400.420332) (xy 352.186748 -400.506946) (xy 352.194876 -400.52371)
			(xy 352.201988 -400.53006) (xy 352.221098 -400.548202) (xy 352.254617 -400.588861) (xy 352.282229 -400.633742)
			(xy 352.303408 -400.681992) (xy 352.317754 -400.732696) (xy 352.324992 -400.784891) (xy 352.325432 -400.811238)
			(xy 352.325432 -401.674838) (xy 352.762312 -401.674838) (xy 352.762312 -400.811238) (xy 352.762801 -400.784883)
			(xy 352.770063 -400.732675) (xy 352.784441 -400.681963) (xy 352.805661 -400.633713) (xy 352.833319 -400.588841)
			(xy 352.866889 -400.548203) (xy 352.88601 -400.53006) (xy 352.893122 -400.52371) (xy 352.90125 -400.506946)
			(xy 352.909632 -400.420332) (xy 352.904552 -400.402552) (xy 352.898964 -400.394678) (xy 352.884815 -400.37483)
			(xy 352.862357 -400.331572) (xy 352.847044 -400.285299) (xy 352.839264 -400.237184) (xy 352.838766 -400.212814)
			(xy 352.839288 -400.187559) (xy 352.847601 -400.137737) (xy 352.864002 -400.089963) (xy 352.888043 -400.04554)
			(xy 352.919067 -400.00568) (xy 352.956229 -399.97147) (xy 352.998515 -399.943844) (xy 353.044771 -399.923554)
			(xy 353.093736 -399.911154) (xy 353.144074 -399.906983) (xy 353.194412 -399.911154) (xy 353.243377 -399.923554)
			(xy 353.289633 -399.943844) (xy 353.331919 -399.97147) (xy 353.369081 -400.00568) (xy 353.400105 -400.04554)
			(xy 353.424146 -400.089963) (xy 353.440547 -400.137737) (xy 353.44886 -400.187559) (xy 353.449382 -400.212814)
			(xy 353.448917 -400.237187) (xy 353.441156 -400.285311) (xy 353.425835 -400.331587) (xy 353.403344 -400.374834)
			(xy 353.389184 -400.394678) (xy 353.383596 -400.402552) (xy 353.378516 -400.420332) (xy 353.386898 -400.506946)
			(xy 353.395026 -400.52371) (xy 353.402138 -400.53006) (xy 353.42127 -400.548196) (xy 353.454858 -400.588826)
			(xy 353.48253 -400.633695) (xy 353.503758 -400.681948) (xy 353.518137 -400.732666) (xy 353.525393 -400.78488)
			(xy 353.525836 -400.811238) (xy 353.525836 -401.674838) (xy 353.962208 -401.674838) (xy 353.962208 -400.811238)
			(xy 353.962666 -400.784881) (xy 353.96993 -400.732671) (xy 353.984312 -400.681957) (xy 354.005537 -400.633706)
			(xy 354.033202 -400.588836) (xy 354.06678 -400.548201) (xy 354.085906 -400.53006) (xy 354.093018 -400.52371)
			(xy 354.101146 -400.506946) (xy 354.109528 -400.420332) (xy 354.104448 -400.402552) (xy 354.09886 -400.394678)
			(xy 354.084711 -400.37483) (xy 354.062253 -400.331572) (xy 354.04694 -400.285299) (xy 354.03916 -400.237184)
			(xy 354.038662 -400.212814) (xy 354.039184 -400.187559) (xy 354.047497 -400.137737) (xy 354.063898 -400.089963)
			(xy 354.087939 -400.04554) (xy 354.118963 -400.00568) (xy 354.156125 -399.97147) (xy 354.198411 -399.943844)
			(xy 354.244667 -399.923554) (xy 354.293632 -399.911154) (xy 354.34397 -399.906983) (xy 354.394308 -399.911154)
			(xy 354.443273 -399.923554) (xy 354.489529 -399.943844) (xy 354.531815 -399.97147) (xy 354.568977 -400.00568)
			(xy 354.600001 -400.04554) (xy 354.624042 -400.089963) (xy 354.640443 -400.137737) (xy 354.648756 -400.187559)
			(xy 354.649278 -400.212814) (xy 354.648814 -400.237187) (xy 354.641053 -400.285311) (xy 354.625732 -400.331587)
			(xy 354.60324 -400.374834) (xy 354.58908 -400.394678) (xy 354.583492 -400.402552) (xy 354.578412 -400.420332)
			(xy 354.586794 -400.506946) (xy 354.594922 -400.52371) (xy 354.602034 -400.53006) (xy 354.621165 -400.548197)
			(xy 354.654754 -400.588827) (xy 354.682426 -400.633696) (xy 354.703654 -400.681949) (xy 354.718033 -400.732666)
			(xy 354.725289 -400.78488) (xy 354.725732 -400.811238) (xy 354.725732 -401.20833) (xy 355.91197 -401.20833)
			(xy 355.914576 -401.145297) (xy 355.924959 -401.083071) (xy 355.942959 -401.022606) (xy 355.9683 -400.964833)
			(xy 356.000593 -400.910637) (xy 356.039342 -400.860853) (xy 356.083951 -400.816243) (xy 356.133736 -400.777494)
			(xy 356.187931 -400.745201) (xy 356.245704 -400.71986) (xy 356.306169 -400.70186) (xy 356.368395 -400.691477)
			(xy 356.431428 -400.68887) (xy 356.4943 -400.694081) (xy 356.556044 -400.707029) (xy 356.615712 -400.727515)
			(xy 356.672388 -400.755224) (xy 356.725201 -400.78973) (xy 356.773341 -400.830505) (xy 356.816067 -400.876921)
			(xy 356.852723 -400.928266) (xy 356.882747 -400.98375) (xy 356.905677 -401.042522) (xy 356.921161 -401.10368)
			(xy 356.928962 -401.166282) (xy 356.929436 -401.197826) (xy 356.927658 -401.239228) (xy 356.926642 -401.25142)
			(xy 356.93604 -401.274026) (xy 357.01732 -401.343368) (xy 357.040942 -401.34921) (xy 357.05288 -401.346162)
			(xy 357.075022 -401.341164) (xy 357.120099 -401.335819) (xy 357.142796 -401.335494) (xy 357.170049 -401.335953)
			(xy 357.224001 -401.34371) (xy 357.276299 -401.359065) (xy 357.32588 -401.381708) (xy 357.371734 -401.411176)
			(xy 357.412928 -401.44687) (xy 357.448622 -401.488063) (xy 357.47809 -401.533916) (xy 357.500733 -401.583497)
			(xy 357.51609 -401.635795) (xy 357.523847 -401.689747) (xy 357.523847 -401.744253) (xy 357.51609 -401.798205)
			(xy 357.500733 -401.850503) (xy 357.47809 -401.900084) (xy 357.448622 -401.945937) (xy 357.412928 -401.98713)
			(xy 357.371734 -402.022824) (xy 357.32588 -402.052292) (xy 357.276299 -402.074935) (xy 357.254978 -402.081195)
			(xy 359.374942 -402.081195) (xy 359.374942 -402.017273) (xy 359.382953 -401.953855) (xy 359.39885 -401.891941)
			(xy 359.422382 -401.832508) (xy 359.453176 -401.776493) (xy 359.490749 -401.724778) (xy 359.534506 -401.678181)
			(xy 359.583759 -401.637436) (xy 359.63773 -401.603185) (xy 359.695569 -401.575968) (xy 359.756362 -401.556215)
			(xy 359.819152 -401.544237) (xy 359.882948 -401.540224) (xy 359.946744 -401.544237) (xy 360.009534 -401.556215)
			(xy 360.070327 -401.575968) (xy 360.128166 -401.603185) (xy 360.182137 -401.637436) (xy 360.23139 -401.678181)
			(xy 360.275147 -401.724778) (xy 360.31272 -401.776493) (xy 360.343514 -401.832508) (xy 360.367046 -401.891941)
			(xy 360.369868 -401.90293) (xy 361.068366 -401.90293) (xy 361.068829 -401.872233) (xy 361.076234 -401.811288)
			(xy 361.090929 -401.75168) (xy 361.1127 -401.694276) (xy 361.141228 -401.639913) (xy 361.158282 -401.614386)
			(xy 361.16373 -401.605621) (xy 361.167869 -401.585425) (xy 361.16375 -401.565225) (xy 361.158282 -401.556474)
			(xy 361.141247 -401.530936) (xy 361.112736 -401.476569) (xy 361.090972 -401.419167) (xy 361.076271 -401.359563)
			(xy 361.068847 -401.298624) (xy 361.068366 -401.26793) (xy 361.068829 -401.237233) (xy 361.076234 -401.176288)
			(xy 361.090929 -401.11668) (xy 361.1127 -401.059276) (xy 361.141228 -401.004913) (xy 361.158282 -400.979386)
			(xy 361.16373 -400.970621) (xy 361.167869 -400.950425) (xy 361.16375 -400.930225) (xy 361.158282 -400.921474)
			(xy 361.141247 -400.895936) (xy 361.112736 -400.841569) (xy 361.090972 -400.784167) (xy 361.076271 -400.724563)
			(xy 361.068847 -400.663624) (xy 361.068366 -400.63293) (xy 361.068829 -400.602233) (xy 361.076234 -400.541288)
			(xy 361.090929 -400.48168) (xy 361.1127 -400.424276) (xy 361.141228 -400.369913) (xy 361.158282 -400.344386)
			(xy 361.16373 -400.335621) (xy 361.167869 -400.315425) (xy 361.16375 -400.295225) (xy 361.158282 -400.286474)
			(xy 361.141247 -400.260936) (xy 361.112736 -400.206569) (xy 361.090972 -400.149167) (xy 361.076271 -400.089563)
			(xy 361.068847 -400.028624) (xy 361.068366 -399.99793) (xy 361.06881 -399.966878) (xy 361.076392 -399.905238)
			(xy 361.091422 -399.844979) (xy 361.113677 -399.786999) (xy 361.142825 -399.732159) (xy 361.178433 -399.681277)
			(xy 361.219972 -399.635108) (xy 361.266822 -399.59434) (xy 361.318288 -399.55958) (xy 361.345734 -399.545048)
			(xy 361.353906 -399.540356) (xy 361.36641 -399.526279) (xy 361.370118 -399.517616) (xy 361.38104 -399.488914)
			(xy 361.383963 -399.47999) (xy 361.383818 -399.461226) (xy 361.380786 -399.452338) (xy 361.36953 -399.422471)
			(xy 361.353707 -399.360635) (xy 361.345727 -399.297308) (xy 361.345226 -399.265394) (xy 361.345711 -399.234698)
			(xy 361.35311 -399.173753) (xy 361.367799 -399.114145) (xy 361.389564 -399.05674) (xy 361.418089 -399.002378)
			(xy 361.435142 -398.97685) (xy 361.440616 -398.9681) (xy 361.444739 -398.947895) (xy 361.440612 -398.927691)
			(xy 361.435142 -398.918938) (xy 361.418087 -398.893413) (xy 361.38958 -398.839042) (xy 361.367821 -398.781636)
			(xy 361.353124 -398.72203) (xy 361.345704 -398.661089) (xy 361.345226 -398.630394) (xy 361.345733 -398.599314)
			(xy 361.35331 -398.537617) (xy 361.368351 -398.477304) (xy 361.390632 -398.419274) (xy 361.41982 -398.364392)
			(xy 361.45548 -398.313478) (xy 361.49708 -398.267289) (xy 361.543999 -398.226516) (xy 361.569508 -398.208754)
			(xy 361.576789 -398.203375) (xy 361.587333 -398.188676) (xy 361.590082 -398.180052) (xy 361.59821 -398.150842)
			(xy 361.600158 -398.142188) (xy 361.598741 -398.124521) (xy 361.595416 -398.116298) (xy 361.584547 -398.091352)
			(xy 361.569261 -398.03913) (xy 361.561564 -397.985263) (xy 361.561126 -397.958056) (xy 361.561619 -397.930687)
			(xy 361.569429 -397.876508) (xy 361.584912 -397.824005) (xy 361.607748 -397.774258) (xy 361.637467 -397.72829)
			(xy 361.655106 -397.707358) (xy 361.661202 -397.700246) (xy 361.667552 -397.683228) (xy 361.667552 -397.597884)
			(xy 361.661202 -397.580866) (xy 361.655106 -397.573754) (xy 361.63748 -397.552812) (xy 361.607766 -397.506842)
			(xy 361.584927 -397.457097) (xy 361.569433 -397.404598) (xy 361.561602 -397.350424) (xy 361.561126 -397.323056)
			(xy 361.561537 -397.295802) (xy 361.5693 -397.24185) (xy 361.584663 -397.189552) (xy 361.607312 -397.139972)
			(xy 361.636786 -397.09412) (xy 361.672485 -397.05293) (xy 361.713683 -397.017239) (xy 361.759541 -396.987774)
			(xy 361.809125 -396.965136) (xy 361.861426 -396.949784) (xy 361.91538 -396.942031) (xy 361.942634 -396.941548)
			(xy 361.969394 -396.941998) (xy 362.02239 -396.949466) (xy 362.073823 -396.964265) (xy 362.122684 -396.986104)
			(xy 362.168014 -397.014556) (xy 362.18876 -397.031464) (xy 362.197904 -397.039338) (xy 362.221018 -397.044926)
			(xy 362.323634 -397.021812) (xy 362.341922 -397.006826) (xy 362.347002 -396.995904) (xy 362.358671 -396.971183)
			(xy 362.388071 -396.925097) (xy 362.423751 -396.88368) (xy 362.464978 -396.847782) (xy 362.510908 -396.818138)
			(xy 362.5606 -396.795356) (xy 362.613036 -396.779902) (xy 362.667141 -396.772093) (xy 362.694474 -396.771622)
			(xy 362.721844 -396.772098) (xy 362.776023 -396.779913) (xy 362.828526 -396.795399) (xy 362.878273 -396.818239)
			(xy 362.92424 -396.847962) (xy 362.945172 -396.865602) (xy 362.952284 -396.871698) (xy 362.969302 -396.878048)
			(xy 363.054646 -396.878048) (xy 363.071664 -396.871698) (xy 363.078776 -396.865602) (xy 363.099707 -396.847961)
			(xy 363.14568 -396.818249) (xy 363.195428 -396.795414) (xy 363.247929 -396.779923) (xy 363.302105 -396.772096)
			(xy 363.329474 -396.771622) (xy 363.35673 -396.772023) (xy 363.410688 -396.779778) (xy 363.462993 -396.795133)
			(xy 363.512581 -396.817776) (xy 363.558441 -396.847245) (xy 363.59964 -396.882942) (xy 363.635339 -396.924138)
			(xy 363.664812 -396.969996) (xy 363.687458 -397.019582) (xy 363.702817 -397.071886) (xy 363.710575 -397.125844)
			(xy 363.710575 -397.180356) (xy 363.702817 -397.234314) (xy 363.687458 -397.286618) (xy 363.664812 -397.336204)
			(xy 363.635339 -397.382062) (xy 363.59964 -397.423258) (xy 363.558441 -397.458955) (xy 363.512581 -397.488424)
			(xy 363.462993 -397.511067) (xy 363.410688 -397.526422) (xy 363.35673 -397.534177) (xy 363.329474 -397.534638)
			(xy 363.302102 -397.534202) (xy 363.247922 -397.526379) (xy 363.195417 -397.510884) (xy 363.145671 -397.488035)
			(xy 363.099706 -397.458303) (xy 363.078776 -397.440658) (xy 363.071664 -397.434562) (xy 363.054646 -397.428212)
			(xy 362.969302 -397.428212) (xy 362.952284 -397.434562) (xy 362.945172 -397.440658) (xy 362.924218 -397.45827)
			(xy 362.878252 -397.487988) (xy 362.82851 -397.510829) (xy 362.776014 -397.526327) (xy 362.721842 -397.534161)
			(xy 362.694474 -397.534638) (xy 362.667714 -397.534187) (xy 362.614718 -397.52672) (xy 362.563285 -397.511921)
			(xy 362.514424 -397.490082) (xy 362.469094 -397.46163) (xy 362.448348 -397.444722) (xy 362.439204 -397.436848)
			(xy 362.41609 -397.43126) (xy 362.313474 -397.454374) (xy 362.295186 -397.46936) (xy 362.290106 -397.480282)
			(xy 362.278162 -397.50547) (xy 362.248074 -397.552394) (xy 362.230162 -397.573754) (xy 362.224066 -397.580866)
			(xy 362.217716 -397.597884) (xy 362.217716 -397.683228) (xy 362.224066 -397.700246) (xy 362.230162 -397.707358)
			(xy 362.247789 -397.7283) (xy 362.277504 -397.774269) (xy 362.300343 -397.824014) (xy 362.315837 -397.876513)
			(xy 362.323667 -397.930687) (xy 362.324142 -397.958056) (xy 362.32371 -397.984418) (xy 362.316459 -398.036642)
			(xy 362.302087 -398.08737) (xy 362.28087 -398.135638) (xy 362.253211 -398.180525) (xy 362.236766 -398.201134)
			(xy 362.231422 -398.208178) (xy 362.225456 -398.224811) (xy 362.225082 -398.233646) (xy 362.225336 -398.264126)
			(xy 362.225772 -398.273161) (xy 362.232139 -398.290078) (xy 362.237782 -398.297146) (xy 362.262944 -398.327262)
			(xy 362.304666 -398.393725) (xy 362.32084 -398.42948) (xy 362.325158 -398.439132) (xy 362.340398 -398.45361)
			(xy 362.430314 -398.485868) (xy 362.451396 -398.484344) (xy 362.460794 -398.479518) (xy 362.487962 -398.465959)
			(xy 362.544828 -398.444668) (xy 362.603825 -398.430302) (xy 362.664114 -398.423066) (xy 362.694474 -398.422622)
			(xy 362.725171 -398.423073) (xy 362.786117 -398.43048) (xy 362.845726 -398.445177) (xy 362.90313 -398.46695)
			(xy 362.957491 -398.495482) (xy 362.983018 -398.512538) (xy 362.99177 -398.518009) (xy 363.011974 -398.522137)
			(xy 363.032178 -398.518009) (xy 363.04093 -398.512538) (xy 363.066464 -398.495496) (xy 363.120833 -398.466987)
			(xy 363.178236 -398.445225) (xy 363.23784 -398.430526) (xy 363.298779 -398.423102) (xy 363.329474 -398.422622)
			(xy 363.360207 -398.423062) (xy 363.421224 -398.430468) (xy 363.480904 -398.445176) (xy 363.538376 -398.46697)
			(xy 363.592801 -398.495534) (xy 363.643387 -398.53045) (xy 363.689394 -398.571209) (xy 363.730153 -398.617217)
			(xy 363.765068 -398.667802) (xy 363.793631 -398.722228) (xy 363.815425 -398.7797) (xy 363.830132 -398.83938)
			(xy 363.837538 -398.900397) (xy 363.837982 -398.93113) (xy 363.837418 -398.965316) (xy 363.82828 -399.033074)
			(xy 363.810146 -399.098997) (xy 363.783343 -399.161896) (xy 363.748355 -399.220637) (xy 363.705812 -399.274161)
			(xy 363.656481 -399.321501) (xy 363.629194 -399.342102) (xy 363.61751 -399.350484) (xy 363.606842 -399.376138)
			(xy 363.623352 -399.493232) (xy 363.641132 -399.514822) (xy 363.654594 -399.519648) (xy 363.686132 -399.531663)
			(xy 363.746002 -399.562811) (xy 363.801231 -399.601597) (xy 363.85085 -399.647342) (xy 363.893989 -399.699243)
			(xy 363.929891 -399.756389) (xy 363.944408 -399.786856) (xy 363.950758 -399.800572) (xy 363.97565 -399.81632)
			(xy 364.098078 -399.81632) (xy 364.12297 -399.800572) (xy 364.12932 -399.786856) (xy 364.142936 -399.758116)
			(xy 364.176307 -399.703978) (xy 364.21617 -399.654425) (xy 364.261904 -399.610233) (xy 364.287054 -399.590768)
			(xy 364.294161 -399.585011) (xy 364.304059 -399.569648) (xy 364.306358 -399.560796) (xy 364.312708 -399.531078)
			(xy 364.314234 -399.52219) (xy 364.311633 -399.504359) (xy 364.307628 -399.49628) (xy 364.293229 -399.468244)
			(xy 364.272843 -399.408609) (xy 364.262532 -399.346436) (xy 364.261908 -399.314924) (xy 364.262386 -399.287554)
			(xy 364.270201 -399.233376) (xy 364.285687 -399.180872) (xy 364.308526 -399.131125) (xy 364.338248 -399.085158)
			(xy 364.355888 -399.064226) (xy 364.361984 -399.057114) (xy 364.368334 -399.040096) (xy 364.368334 -398.954752)
			(xy 364.361984 -398.937734) (xy 364.355888 -398.930622) (xy 364.338244 -398.909694) (xy 364.308533 -398.86372)
			(xy 364.285698 -398.813971) (xy 364.270209 -398.76147) (xy 364.262381 -398.707293) (xy 364.261908 -398.679924)
			(xy 364.262394 -398.652673) (xy 364.27015 -398.598725) (xy 364.285505 -398.54643) (xy 364.308147 -398.496853)
			(xy 364.337613 -398.451003) (xy 364.373304 -398.409812) (xy 364.414495 -398.374121) (xy 364.460345 -398.344655)
			(xy 364.509922 -398.322013) (xy 364.562217 -398.306658) (xy 364.616165 -398.298902) (xy 364.670667 -398.298902)
			(xy 364.724615 -398.306658) (xy 364.77691 -398.322013) (xy 364.826487 -398.344655) (xy 364.872337 -398.374121)
			(xy 364.913528 -398.409812) (xy 364.949219 -398.451003) (xy 364.978685 -398.496853) (xy 365.001327 -398.54643)
			(xy 365.016682 -398.598725) (xy 365.024438 -398.652673) (xy 365.024924 -398.679924) (xy 365.024491 -398.707296)
			(xy 365.016668 -398.761477) (xy 365.001172 -398.813981) (xy 364.978323 -398.863727) (xy 364.94859 -398.909692)
			(xy 364.930944 -398.930622) (xy 364.924848 -398.937734) (xy 364.918498 -398.954752) (xy 364.918498 -399.008092)
			(xy 367.735612 -399.008092) (xy 367.736169 -398.9748) (xy 367.745789 -398.908915) (xy 367.764868 -398.845123)
			(xy 367.793002 -398.784776) (xy 367.810796 -398.756632) (xy 367.815859 -398.748116) (xy 367.819677 -398.728693)
			(xy 367.815854 -398.709272) (xy 367.810796 -398.700752) (xy 367.79302 -398.672601) (xy 367.764925 -398.612243)
			(xy 367.745857 -398.548455) (xy 367.736214 -398.48258) (xy 367.735612 -398.449292) (xy 367.736102 -398.419324)
			(xy 367.743925 -398.359902) (xy 367.759438 -398.302009) (xy 367.782374 -398.246636) (xy 367.812341 -398.19473)
			(xy 367.848828 -398.14718) (xy 367.891208 -398.1048) (xy 367.938758 -398.068313) (xy 367.990664 -398.038346)
			(xy 368.046037 -398.01541) (xy 368.10393 -397.999897) (xy 368.163352 -397.992074) (xy 368.223288 -397.992074)
			(xy 368.28271 -397.999897) (xy 368.340603 -398.01541) (xy 368.395976 -398.038346) (xy 368.447882 -398.068313)
			(xy 368.495432 -398.1048) (xy 368.537812 -398.14718) (xy 368.574299 -398.19473) (xy 368.604266 -398.246636)
			(xy 368.627202 -398.302009) (xy 368.642715 -398.359902) (xy 368.650538 -398.419324) (xy 368.651028 -398.449292)
			(xy 368.650458 -398.482584) (xy 368.641785 -398.542002) (xy 370.1852 -398.542002) (xy 370.18916 -398.492948)
			(xy 370.200937 -398.445164) (xy 370.220228 -398.399888) (xy 370.246531 -398.358292) (xy 370.279166 -398.321455)
			(xy 370.317287 -398.29033) (xy 370.359908 -398.265723) (xy 370.405924 -398.248271) (xy 370.454143 -398.238427)
			(xy 370.503318 -398.236446) (xy 370.552173 -398.242378) (xy 370.599444 -398.25607) (xy 370.643906 -398.277168)
			(xy 370.684409 -398.305124) (xy 370.719902 -398.339216) (xy 370.749467 -398.37856) (xy 370.772338 -398.422137)
			(xy 370.787922 -398.468818) (xy 370.795817 -398.517395) (xy 370.796312 -398.542002) (xy 371.38535 -398.542002)
			(xy 371.38931 -398.492948) (xy 371.401087 -398.445164) (xy 371.420378 -398.399888) (xy 371.446681 -398.358292)
			(xy 371.479316 -398.321455) (xy 371.517437 -398.29033) (xy 371.560058 -398.265723) (xy 371.606074 -398.248271)
			(xy 371.654293 -398.238427) (xy 371.703468 -398.236446) (xy 371.752323 -398.242378) (xy 371.799594 -398.25607)
			(xy 371.844056 -398.277168) (xy 371.884559 -398.305124) (xy 371.920052 -398.339216) (xy 371.949617 -398.37856)
			(xy 371.972488 -398.422137) (xy 371.988072 -398.468818) (xy 371.995967 -398.517395) (xy 371.996462 -398.542002)
			(xy 372.5855 -398.542002) (xy 372.58946 -398.492948) (xy 372.601237 -398.445164) (xy 372.620528 -398.399888)
			(xy 372.646831 -398.358292) (xy 372.679466 -398.321455) (xy 372.717587 -398.29033) (xy 372.760208 -398.265723)
			(xy 372.806224 -398.248271) (xy 372.854443 -398.238427) (xy 372.903618 -398.236446) (xy 372.952473 -398.242378)
			(xy 372.999744 -398.25607) (xy 373.044206 -398.277168) (xy 373.084709 -398.305124) (xy 373.120202 -398.339216)
			(xy 373.149767 -398.37856) (xy 373.172638 -398.422137) (xy 373.188222 -398.468818) (xy 373.196117 -398.517395)
			(xy 373.196612 -398.542002) (xy 373.785396 -398.542002) (xy 373.789356 -398.492948) (xy 373.801133 -398.445164)
			(xy 373.820424 -398.399888) (xy 373.846727 -398.358292) (xy 373.879362 -398.321455) (xy 373.917483 -398.29033)
			(xy 373.960104 -398.265723) (xy 374.00612 -398.248271) (xy 374.054339 -398.238427) (xy 374.103514 -398.236446)
			(xy 374.152369 -398.242378) (xy 374.19964 -398.25607) (xy 374.244102 -398.277168) (xy 374.284605 -398.305124)
			(xy 374.320098 -398.339216) (xy 374.349663 -398.37856) (xy 374.372534 -398.422137) (xy 374.388118 -398.468818)
			(xy 374.396013 -398.517395) (xy 374.396508 -398.542002) (xy 374.985546 -398.542002) (xy 374.989506 -398.492948)
			(xy 375.001283 -398.445164) (xy 375.020574 -398.399888) (xy 375.046877 -398.358292) (xy 375.079512 -398.321455)
			(xy 375.117633 -398.29033) (xy 375.160254 -398.265723) (xy 375.20627 -398.248271) (xy 375.254489 -398.238427)
			(xy 375.303664 -398.236446) (xy 375.352519 -398.242378) (xy 375.39979 -398.25607) (xy 375.444252 -398.277168)
			(xy 375.484755 -398.305124) (xy 375.520248 -398.339216) (xy 375.549813 -398.37856) (xy 375.572684 -398.422137)
			(xy 375.588268 -398.468818) (xy 375.596163 -398.517395) (xy 375.596658 -398.542002) (xy 376.185442 -398.542002)
			(xy 376.189402 -398.492948) (xy 376.201179 -398.445164) (xy 376.22047 -398.399888) (xy 376.246773 -398.358292)
			(xy 376.279408 -398.321455) (xy 376.317529 -398.29033) (xy 376.36015 -398.265723) (xy 376.406166 -398.248271)
			(xy 376.454385 -398.238427) (xy 376.50356 -398.236446) (xy 376.552415 -398.242378) (xy 376.599686 -398.25607)
			(xy 376.644148 -398.277168) (xy 376.684651 -398.305124) (xy 376.720144 -398.339216) (xy 376.749709 -398.37856)
			(xy 376.77258 -398.422137) (xy 376.788164 -398.468818) (xy 376.796059 -398.517395) (xy 376.796554 -398.542002)
			(xy 377.385338 -398.542002) (xy 377.389298 -398.492948) (xy 377.401075 -398.445164) (xy 377.420366 -398.399888)
			(xy 377.446669 -398.358292) (xy 377.479304 -398.321455) (xy 377.517425 -398.29033) (xy 377.560046 -398.265723)
			(xy 377.606062 -398.248271) (xy 377.654281 -398.238427) (xy 377.703456 -398.236446) (xy 377.752311 -398.242378)
			(xy 377.799582 -398.25607) (xy 377.844044 -398.277168) (xy 377.884547 -398.305124) (xy 377.92004 -398.339216)
			(xy 377.949605 -398.37856) (xy 377.972476 -398.422137) (xy 377.98806 -398.468818) (xy 377.995955 -398.517395)
			(xy 377.99645 -398.542002) (xy 378.585488 -398.542002) (xy 378.589448 -398.492948) (xy 378.601225 -398.445164)
			(xy 378.620516 -398.399888) (xy 378.646819 -398.358292) (xy 378.679454 -398.321455) (xy 378.717575 -398.29033)
			(xy 378.760196 -398.265723) (xy 378.806212 -398.248271) (xy 378.854431 -398.238427) (xy 378.903606 -398.236446)
			(xy 378.952461 -398.242378) (xy 378.999732 -398.25607) (xy 379.044194 -398.277168) (xy 379.084697 -398.305124)
			(xy 379.12019 -398.339216) (xy 379.149755 -398.37856) (xy 379.172626 -398.422137) (xy 379.18821 -398.468818)
			(xy 379.196105 -398.517395) (xy 379.1966 -398.542002) (xy 379.785384 -398.542002) (xy 379.789344 -398.492948)
			(xy 379.801121 -398.445164) (xy 379.820412 -398.399888) (xy 379.846715 -398.358292) (xy 379.87935 -398.321455)
			(xy 379.917471 -398.29033) (xy 379.960092 -398.265723) (xy 380.006108 -398.248271) (xy 380.054327 -398.238427)
			(xy 380.103502 -398.236446) (xy 380.152357 -398.242378) (xy 380.199628 -398.25607) (xy 380.24409 -398.277168)
			(xy 380.284593 -398.305124) (xy 380.320086 -398.339216) (xy 380.349651 -398.37856) (xy 380.372522 -398.422137)
			(xy 380.388106 -398.468818) (xy 380.396001 -398.517395) (xy 380.396496 -398.542002) (xy 380.985534 -398.542002)
			(xy 380.989494 -398.492948) (xy 381.001271 -398.445164) (xy 381.020562 -398.399888) (xy 381.046865 -398.358292)
			(xy 381.0795 -398.321455) (xy 381.117621 -398.29033) (xy 381.160242 -398.265723) (xy 381.206258 -398.248271)
			(xy 381.254477 -398.238427) (xy 381.303652 -398.236446) (xy 381.352507 -398.242378) (xy 381.399778 -398.25607)
			(xy 381.44424 -398.277168) (xy 381.484743 -398.305124) (xy 381.520236 -398.339216) (xy 381.549801 -398.37856)
			(xy 381.572672 -398.422137) (xy 381.588256 -398.468818) (xy 381.596151 -398.517395) (xy 381.596646 -398.542002)
			(xy 382.18543 -398.542002) (xy 382.18939 -398.492948) (xy 382.201167 -398.445164) (xy 382.220458 -398.399888)
			(xy 382.246761 -398.358292) (xy 382.279396 -398.321455) (xy 382.317517 -398.29033) (xy 382.360138 -398.265723)
			(xy 382.406154 -398.248271) (xy 382.454373 -398.238427) (xy 382.503548 -398.236446) (xy 382.552403 -398.242378)
			(xy 382.599674 -398.25607) (xy 382.644136 -398.277168) (xy 382.684639 -398.305124) (xy 382.720132 -398.339216)
			(xy 382.749697 -398.37856) (xy 382.772568 -398.422137) (xy 382.788152 -398.468818) (xy 382.796047 -398.517395)
			(xy 382.796542 -398.542002) (xy 383.385326 -398.542002) (xy 383.389286 -398.492948) (xy 383.401063 -398.445164)
			(xy 383.420354 -398.399888) (xy 383.446657 -398.358292) (xy 383.479292 -398.321455) (xy 383.517413 -398.29033)
			(xy 383.560034 -398.265723) (xy 383.60605 -398.248271) (xy 383.654269 -398.238427) (xy 383.703444 -398.236446)
			(xy 383.752299 -398.242378) (xy 383.79957 -398.25607) (xy 383.844032 -398.277168) (xy 383.884535 -398.305124)
			(xy 383.920028 -398.339216) (xy 383.949593 -398.37856) (xy 383.972464 -398.422137) (xy 383.988048 -398.468818)
			(xy 383.995943 -398.517395) (xy 383.996438 -398.542002) (xy 384.585476 -398.542002) (xy 384.589436 -398.492948)
			(xy 384.601213 -398.445164) (xy 384.620504 -398.399888) (xy 384.646807 -398.358292) (xy 384.679442 -398.321455)
			(xy 384.717563 -398.29033) (xy 384.760184 -398.265723) (xy 384.8062 -398.248271) (xy 384.854419 -398.238427)
			(xy 384.903594 -398.236446) (xy 384.952449 -398.242378) (xy 384.99972 -398.25607) (xy 385.044182 -398.277168)
			(xy 385.084685 -398.305124) (xy 385.120178 -398.339216) (xy 385.149743 -398.37856) (xy 385.172614 -398.422137)
			(xy 385.188198 -398.468818) (xy 385.196093 -398.517395) (xy 385.196588 -398.542002) (xy 385.785372 -398.542002)
			(xy 385.789332 -398.492948) (xy 385.801109 -398.445164) (xy 385.8204 -398.399888) (xy 385.846703 -398.358292)
			(xy 385.879338 -398.321455) (xy 385.917459 -398.29033) (xy 385.96008 -398.265723) (xy 386.006096 -398.248271)
			(xy 386.054315 -398.238427) (xy 386.10349 -398.236446) (xy 386.152345 -398.242378) (xy 386.199616 -398.25607)
			(xy 386.244078 -398.277168) (xy 386.284581 -398.305124) (xy 386.320074 -398.339216) (xy 386.349639 -398.37856)
			(xy 386.37251 -398.422137) (xy 386.388094 -398.468818) (xy 386.395989 -398.517395) (xy 386.396484 -398.542002)
			(xy 386.985522 -398.542002) (xy 386.989482 -398.492948) (xy 387.001259 -398.445164) (xy 387.02055 -398.399888)
			(xy 387.046853 -398.358292) (xy 387.079488 -398.321455) (xy 387.117609 -398.29033) (xy 387.16023 -398.265723)
			(xy 387.206246 -398.248271) (xy 387.254465 -398.238427) (xy 387.30364 -398.236446) (xy 387.352495 -398.242378)
			(xy 387.399766 -398.25607) (xy 387.444228 -398.277168) (xy 387.484731 -398.305124) (xy 387.520224 -398.339216)
			(xy 387.549789 -398.37856) (xy 387.57266 -398.422137) (xy 387.588244 -398.468818) (xy 387.596139 -398.517395)
			(xy 387.596634 -398.542002) (xy 388.185418 -398.542002) (xy 388.189378 -398.492948) (xy 388.201155 -398.445164)
			(xy 388.220446 -398.399888) (xy 388.246749 -398.358292) (xy 388.279384 -398.321455) (xy 388.317505 -398.29033)
			(xy 388.360126 -398.265723) (xy 388.406142 -398.248271) (xy 388.454361 -398.238427) (xy 388.503536 -398.236446)
			(xy 388.552391 -398.242378) (xy 388.599662 -398.25607) (xy 388.644124 -398.277168) (xy 388.684627 -398.305124)
			(xy 388.72012 -398.339216) (xy 388.749685 -398.37856) (xy 388.772556 -398.422137) (xy 388.78814 -398.468818)
			(xy 388.796035 -398.517395) (xy 388.79653 -398.542002) (xy 388.796035 -398.566609) (xy 388.795811 -398.567989)
			(xy 389.515098 -398.567989) (xy 389.515098 -398.516015) (xy 389.523228 -398.46468) (xy 389.539289 -398.41525)
			(xy 389.562885 -398.36894) (xy 389.593435 -398.326892) (xy 389.630186 -398.290141) (xy 389.672234 -398.259591)
			(xy 389.718544 -398.235995) (xy 389.767974 -398.219934) (xy 389.819309 -398.211804) (xy 389.871283 -398.211804)
			(xy 389.922618 -398.219934) (xy 389.972048 -398.235995) (xy 390.018358 -398.259591) (xy 390.060406 -398.290141)
			(xy 390.097157 -398.326892) (xy 390.127707 -398.36894) (xy 390.151303 -398.41525) (xy 390.167364 -398.46468)
			(xy 390.175494 -398.516015) (xy 390.176004 -398.542002) (xy 390.175494 -398.567989) (xy 390.167364 -398.619324)
			(xy 390.151303 -398.668754) (xy 390.127707 -398.715064) (xy 390.097157 -398.757112) (xy 390.060406 -398.793863)
			(xy 390.018358 -398.824413) (xy 389.972048 -398.848009) (xy 389.922618 -398.86407) (xy 389.871283 -398.8722)
			(xy 389.819309 -398.8722) (xy 389.767974 -398.86407) (xy 389.718544 -398.848009) (xy 389.672234 -398.824413)
			(xy 389.630186 -398.793863) (xy 389.593435 -398.757112) (xy 389.562885 -398.715064) (xy 389.539289 -398.668754)
			(xy 389.523228 -398.619324) (xy 389.515098 -398.567989) (xy 388.795811 -398.567989) (xy 388.78814 -398.615186)
			(xy 388.772556 -398.661867) (xy 388.749685 -398.705444) (xy 388.72012 -398.744788) (xy 388.684627 -398.77888)
			(xy 388.644124 -398.806836) (xy 388.599662 -398.827934) (xy 388.552391 -398.841626) (xy 388.503536 -398.847558)
			(xy 388.454361 -398.845577) (xy 388.406142 -398.835733) (xy 388.360126 -398.818281) (xy 388.317505 -398.793674)
			(xy 388.279384 -398.762549) (xy 388.246749 -398.725712) (xy 388.220446 -398.684116) (xy 388.201155 -398.63884)
			(xy 388.189378 -398.591056) (xy 388.185418 -398.542002) (xy 387.596634 -398.542002) (xy 387.596139 -398.566609)
			(xy 387.588244 -398.615186) (xy 387.57266 -398.661867) (xy 387.549789 -398.705444) (xy 387.520224 -398.744788)
			(xy 387.484731 -398.77888) (xy 387.444228 -398.806836) (xy 387.399766 -398.827934) (xy 387.352495 -398.841626)
			(xy 387.30364 -398.847558) (xy 387.254465 -398.845577) (xy 387.206246 -398.835733) (xy 387.16023 -398.818281)
			(xy 387.117609 -398.793674) (xy 387.079488 -398.762549) (xy 387.046853 -398.725712) (xy 387.02055 -398.684116)
			(xy 387.001259 -398.63884) (xy 386.989482 -398.591056) (xy 386.985522 -398.542002) (xy 386.396484 -398.542002)
			(xy 386.395989 -398.566609) (xy 386.388094 -398.615186) (xy 386.37251 -398.661867) (xy 386.349639 -398.705444)
			(xy 386.320074 -398.744788) (xy 386.284581 -398.77888) (xy 386.244078 -398.806836) (xy 386.199616 -398.827934)
			(xy 386.152345 -398.841626) (xy 386.10349 -398.847558) (xy 386.054315 -398.845577) (xy 386.006096 -398.835733)
			(xy 385.96008 -398.818281) (xy 385.917459 -398.793674) (xy 385.879338 -398.762549) (xy 385.846703 -398.725712)
			(xy 385.8204 -398.684116) (xy 385.801109 -398.63884) (xy 385.789332 -398.591056) (xy 385.785372 -398.542002)
			(xy 385.196588 -398.542002) (xy 385.196093 -398.566609) (xy 385.188198 -398.615186) (xy 385.172614 -398.661867)
			(xy 385.149743 -398.705444) (xy 385.120178 -398.744788) (xy 385.084685 -398.77888) (xy 385.044182 -398.806836)
			(xy 384.99972 -398.827934) (xy 384.952449 -398.841626) (xy 384.903594 -398.847558) (xy 384.854419 -398.845577)
			(xy 384.8062 -398.835733) (xy 384.760184 -398.818281) (xy 384.717563 -398.793674) (xy 384.679442 -398.762549)
			(xy 384.646807 -398.725712) (xy 384.620504 -398.684116) (xy 384.601213 -398.63884) (xy 384.589436 -398.591056)
			(xy 384.585476 -398.542002) (xy 383.996438 -398.542002) (xy 383.995943 -398.566609) (xy 383.988048 -398.615186)
			(xy 383.972464 -398.661867) (xy 383.949593 -398.705444) (xy 383.920028 -398.744788) (xy 383.884535 -398.77888)
			(xy 383.844032 -398.806836) (xy 383.79957 -398.827934) (xy 383.752299 -398.841626) (xy 383.703444 -398.847558)
			(xy 383.654269 -398.845577) (xy 383.60605 -398.835733) (xy 383.560034 -398.818281) (xy 383.517413 -398.793674)
			(xy 383.479292 -398.762549) (xy 383.446657 -398.725712) (xy 383.420354 -398.684116) (xy 383.401063 -398.63884)
			(xy 383.389286 -398.591056) (xy 383.385326 -398.542002) (xy 382.796542 -398.542002) (xy 382.796047 -398.566609)
			(xy 382.788152 -398.615186) (xy 382.772568 -398.661867) (xy 382.749697 -398.705444) (xy 382.720132 -398.744788)
			(xy 382.684639 -398.77888) (xy 382.644136 -398.806836) (xy 382.599674 -398.827934) (xy 382.552403 -398.841626)
			(xy 382.503548 -398.847558) (xy 382.454373 -398.845577) (xy 382.406154 -398.835733) (xy 382.360138 -398.818281)
			(xy 382.317517 -398.793674) (xy 382.279396 -398.762549) (xy 382.246761 -398.725712) (xy 382.220458 -398.684116)
			(xy 382.201167 -398.63884) (xy 382.18939 -398.591056) (xy 382.18543 -398.542002) (xy 381.596646 -398.542002)
			(xy 381.596151 -398.566609) (xy 381.588256 -398.615186) (xy 381.572672 -398.661867) (xy 381.549801 -398.705444)
			(xy 381.520236 -398.744788) (xy 381.484743 -398.77888) (xy 381.44424 -398.806836) (xy 381.399778 -398.827934)
			(xy 381.352507 -398.841626) (xy 381.303652 -398.847558) (xy 381.254477 -398.845577) (xy 381.206258 -398.835733)
			(xy 381.160242 -398.818281) (xy 381.117621 -398.793674) (xy 381.0795 -398.762549) (xy 381.046865 -398.725712)
			(xy 381.020562 -398.684116) (xy 381.001271 -398.63884) (xy 380.989494 -398.591056) (xy 380.985534 -398.542002)
			(xy 380.396496 -398.542002) (xy 380.396001 -398.566609) (xy 380.388106 -398.615186) (xy 380.372522 -398.661867)
			(xy 380.349651 -398.705444) (xy 380.320086 -398.744788) (xy 380.284593 -398.77888) (xy 380.24409 -398.806836)
			(xy 380.199628 -398.827934) (xy 380.152357 -398.841626) (xy 380.103502 -398.847558) (xy 380.054327 -398.845577)
			(xy 380.006108 -398.835733) (xy 379.960092 -398.818281) (xy 379.917471 -398.793674) (xy 379.87935 -398.762549)
			(xy 379.846715 -398.725712) (xy 379.820412 -398.684116) (xy 379.801121 -398.63884) (xy 379.789344 -398.591056)
			(xy 379.785384 -398.542002) (xy 379.1966 -398.542002) (xy 379.196105 -398.566609) (xy 379.18821 -398.615186)
			(xy 379.172626 -398.661867) (xy 379.149755 -398.705444) (xy 379.12019 -398.744788) (xy 379.084697 -398.77888)
			(xy 379.044194 -398.806836) (xy 378.999732 -398.827934) (xy 378.952461 -398.841626) (xy 378.903606 -398.847558)
			(xy 378.854431 -398.845577) (xy 378.806212 -398.835733) (xy 378.760196 -398.818281) (xy 378.717575 -398.793674)
			(xy 378.679454 -398.762549) (xy 378.646819 -398.725712) (xy 378.620516 -398.684116) (xy 378.601225 -398.63884)
			(xy 378.589448 -398.591056) (xy 378.585488 -398.542002) (xy 377.99645 -398.542002) (xy 377.995955 -398.566609)
			(xy 377.98806 -398.615186) (xy 377.972476 -398.661867) (xy 377.949605 -398.705444) (xy 377.92004 -398.744788)
			(xy 377.884547 -398.77888) (xy 377.844044 -398.806836) (xy 377.799582 -398.827934) (xy 377.752311 -398.841626)
			(xy 377.703456 -398.847558) (xy 377.654281 -398.845577) (xy 377.606062 -398.835733) (xy 377.560046 -398.818281)
			(xy 377.517425 -398.793674) (xy 377.479304 -398.762549) (xy 377.446669 -398.725712) (xy 377.420366 -398.684116)
			(xy 377.401075 -398.63884) (xy 377.389298 -398.591056) (xy 377.385338 -398.542002) (xy 376.796554 -398.542002)
			(xy 376.796059 -398.566609) (xy 376.788164 -398.615186) (xy 376.77258 -398.661867) (xy 376.749709 -398.705444)
			(xy 376.720144 -398.744788) (xy 376.684651 -398.77888) (xy 376.644148 -398.806836) (xy 376.599686 -398.827934)
			(xy 376.552415 -398.841626) (xy 376.50356 -398.847558) (xy 376.454385 -398.845577) (xy 376.406166 -398.835733)
			(xy 376.36015 -398.818281) (xy 376.317529 -398.793674) (xy 376.279408 -398.762549) (xy 376.246773 -398.725712)
			(xy 376.22047 -398.684116) (xy 376.201179 -398.63884) (xy 376.189402 -398.591056) (xy 376.185442 -398.542002)
			(xy 375.596658 -398.542002) (xy 375.596163 -398.566609) (xy 375.588268 -398.615186) (xy 375.572684 -398.661867)
			(xy 375.549813 -398.705444) (xy 375.520248 -398.744788) (xy 375.484755 -398.77888) (xy 375.444252 -398.806836)
			(xy 375.39979 -398.827934) (xy 375.352519 -398.841626) (xy 375.303664 -398.847558) (xy 375.254489 -398.845577)
			(xy 375.20627 -398.835733) (xy 375.160254 -398.818281) (xy 375.117633 -398.793674) (xy 375.079512 -398.762549)
			(xy 375.046877 -398.725712) (xy 375.020574 -398.684116) (xy 375.001283 -398.63884) (xy 374.989506 -398.591056)
			(xy 374.985546 -398.542002) (xy 374.396508 -398.542002) (xy 374.396013 -398.566609) (xy 374.388118 -398.615186)
			(xy 374.372534 -398.661867) (xy 374.349663 -398.705444) (xy 374.320098 -398.744788) (xy 374.284605 -398.77888)
			(xy 374.244102 -398.806836) (xy 374.19964 -398.827934) (xy 374.152369 -398.841626) (xy 374.103514 -398.847558)
			(xy 374.054339 -398.845577) (xy 374.00612 -398.835733) (xy 373.960104 -398.818281) (xy 373.917483 -398.793674)
			(xy 373.879362 -398.762549) (xy 373.846727 -398.725712) (xy 373.820424 -398.684116) (xy 373.801133 -398.63884)
			(xy 373.789356 -398.591056) (xy 373.785396 -398.542002) (xy 373.196612 -398.542002) (xy 373.196117 -398.566609)
			(xy 373.188222 -398.615186) (xy 373.172638 -398.661867) (xy 373.149767 -398.705444) (xy 373.120202 -398.744788)
			(xy 373.084709 -398.77888) (xy 373.044206 -398.806836) (xy 372.999744 -398.827934) (xy 372.952473 -398.841626)
			(xy 372.903618 -398.847558) (xy 372.854443 -398.845577) (xy 372.806224 -398.835733) (xy 372.760208 -398.818281)
			(xy 372.717587 -398.793674) (xy 372.679466 -398.762549) (xy 372.646831 -398.725712) (xy 372.620528 -398.684116)
			(xy 372.601237 -398.63884) (xy 372.58946 -398.591056) (xy 372.5855 -398.542002) (xy 371.996462 -398.542002)
			(xy 371.995967 -398.566609) (xy 371.988072 -398.615186) (xy 371.972488 -398.661867) (xy 371.949617 -398.705444)
			(xy 371.920052 -398.744788) (xy 371.884559 -398.77888) (xy 371.844056 -398.806836) (xy 371.799594 -398.827934)
			(xy 371.752323 -398.841626) (xy 371.703468 -398.847558) (xy 371.654293 -398.845577) (xy 371.606074 -398.835733)
			(xy 371.560058 -398.818281) (xy 371.517437 -398.793674) (xy 371.479316 -398.762549) (xy 371.446681 -398.725712)
			(xy 371.420378 -398.684116) (xy 371.401087 -398.63884) (xy 371.38931 -398.591056) (xy 371.38535 -398.542002)
			(xy 370.796312 -398.542002) (xy 370.795817 -398.566609) (xy 370.787922 -398.615186) (xy 370.772338 -398.661867)
			(xy 370.749467 -398.705444) (xy 370.719902 -398.744788) (xy 370.684409 -398.77888) (xy 370.643906 -398.806836)
			(xy 370.599444 -398.827934) (xy 370.552173 -398.841626) (xy 370.503318 -398.847558) (xy 370.454143 -398.845577)
			(xy 370.405924 -398.835733) (xy 370.359908 -398.818281) (xy 370.317287 -398.793674) (xy 370.279166 -398.762549)
			(xy 370.246531 -398.725712) (xy 370.220228 -398.684116) (xy 370.200937 -398.63884) (xy 370.18916 -398.591056)
			(xy 370.1852 -398.542002) (xy 368.641785 -398.542002) (xy 368.640841 -398.548468) (xy 368.621766 -398.612259)
			(xy 368.593636 -398.672608) (xy 368.575844 -398.700752) (xy 368.570799 -398.709277) (xy 368.566982 -398.728693)
			(xy 368.570794 -398.748111) (xy 368.575844 -398.756632) (xy 368.593618 -398.784784) (xy 368.621712 -398.845143)
			(xy 368.640781 -398.90893) (xy 368.650425 -398.974804) (xy 368.651028 -399.008092) (xy 368.650584 -399.037392)
			(xy 368.643137 -399.095515) (xy 368.628314 -399.152208) (xy 368.617754 -399.179542) (xy 368.61369 -399.189194)
			(xy 368.614198 -399.20926) (xy 368.652044 -399.295112) (xy 368.666522 -399.309082) (xy 368.676428 -399.312638)
			(xy 368.699796 -399.32182) (xy 368.743641 -399.34628) (xy 368.783286 -399.377086) (xy 368.81782 -399.413529)
			(xy 368.84645 -399.454773) (xy 368.868518 -399.49987) (xy 368.883516 -399.547784) (xy 368.891101 -399.597415)
			(xy 368.891566 -399.622518) (xy 368.891056 -399.648505) (xy 368.882926 -399.69984) (xy 368.866865 -399.74927)
			(xy 368.843269 -399.79558) (xy 368.812719 -399.837628) (xy 368.775968 -399.874379) (xy 368.73392 -399.904929)
			(xy 368.68761 -399.928525) (xy 368.63818 -399.944586) (xy 368.586845 -399.952716) (xy 368.534871 -399.952716)
			(xy 368.483536 -399.944586) (xy 368.434106 -399.928525) (xy 368.387796 -399.904929) (xy 368.345748 -399.874379)
			(xy 368.308997 -399.837628) (xy 368.278447 -399.79558) (xy 368.254851 -399.74927) (xy 368.23879 -399.69984)
			(xy 368.23066 -399.648505) (xy 368.23015 -399.622518) (xy 368.230252 -399.611307) (xy 368.231778 -399.588936)
			(xy 368.233198 -399.577814) (xy 368.234722 -399.5674) (xy 368.229388 -399.547842) (xy 368.17173 -399.473928)
			(xy 368.15395 -399.464276) (xy 368.143536 -399.463006) (xy 368.11335 -399.459187) (xy 368.054274 -399.444626)
			(xy 367.997649 -399.422365) (xy 367.944474 -399.392796) (xy 367.895686 -399.356441) (xy 367.852147 -399.31394)
			(xy 367.814624 -399.266045) (xy 367.783779 -399.213599) (xy 367.760156 -399.157528) (xy 367.744173 -399.098821)
			(xy 367.736111 -399.038514) (xy 367.735612 -399.008092) (xy 364.918498 -399.008092) (xy 364.918498 -399.040096)
			(xy 364.924848 -399.057114) (xy 364.930944 -399.064226) (xy 364.948569 -399.085169) (xy 364.978282 -399.13114)
			(xy 365.00112 -399.180884) (xy 365.016614 -399.233382) (xy 365.024447 -399.287556) (xy 365.024924 -399.314924)
			(xy 365.02475 -399.331262) (xy 365.02195 -399.363819) (xy 365.019336 -399.379948) (xy 365.017304 -399.392394)
			(xy 365.02467 -399.416016) (xy 365.101378 -399.492216) (xy 365.125 -399.499582) (xy 365.137192 -399.497296)
			(xy 365.159422 -399.493592) (xy 365.204319 -399.489645) (xy 365.226854 -399.489422) (xy 365.257551 -399.489883)
			(xy 365.318496 -399.497288) (xy 365.378105 -399.511982) (xy 365.435509 -399.533753) (xy 365.489871 -399.562283)
			(xy 365.515398 -399.579338) (xy 365.52415 -399.584809) (xy 365.544354 -399.588937) (xy 365.564558 -399.584809)
			(xy 365.57331 -399.579338) (xy 365.598849 -399.562305) (xy 365.653217 -399.533795) (xy 365.710618 -399.51203)
			(xy 365.770221 -399.497329) (xy 365.83116 -399.489903) (xy 365.861854 -399.489422) (xy 365.892551 -399.489883)
			(xy 365.953496 -399.497288) (xy 366.013105 -399.511982) (xy 366.070509 -399.533753) (xy 366.124871 -399.562283)
			(xy 366.150398 -399.579338) (xy 366.15915 -399.584809) (xy 366.179354 -399.588937) (xy 366.199558 -399.584809)
			(xy 366.20831 -399.579338) (xy 366.233849 -399.562305) (xy 366.288217 -399.533795) (xy 366.345618 -399.51203)
			(xy 366.405221 -399.497329) (xy 366.46616 -399.489903) (xy 366.496854 -399.489422) (xy 366.527586 -399.489881)
			(xy 366.588603 -399.497285) (xy 366.648283 -399.51199) (xy 366.705754 -399.533783) (xy 366.76018 -399.562344)
			(xy 366.810765 -399.597258) (xy 366.856773 -399.638016) (xy 366.897532 -399.684022) (xy 366.932448 -399.734607)
			(xy 366.961011 -399.789031) (xy 366.982805 -399.846502) (xy 366.997512 -399.906181) (xy 367.004918 -399.967198)
			(xy 367.005362 -399.99793) (xy 367.004891 -400.028626) (xy 366.99749 -400.089572) (xy 366.982797 -400.149181)
			(xy 366.961028 -400.206585) (xy 366.932501 -400.260947) (xy 366.915446 -400.286474) (xy 366.909953 -400.295213)
			(xy 366.905837 -400.315425) (xy 366.909972 -400.335632) (xy 366.915446 -400.344386) (xy 366.933734 -400.372834)
			(xy 366.940592 -400.384518) (xy 366.963706 -400.397472) (xy 367.07826 -400.397726) (xy 367.10112 -400.384518)
			(xy 367.108232 -400.372834) (xy 367.125506 -400.344949) (xy 367.166151 -400.293461) (xy 367.213078 -400.247627)
			(xy 367.26551 -400.208208) (xy 367.322574 -400.175857) (xy 367.383325 -400.151112) (xy 367.446753 -400.134384)
			(xy 367.511806 -400.12595) (xy 367.544604 -400.125438) (xy 367.575338 -400.125834) (xy 367.636358 -400.133244)
			(xy 367.696039 -400.147955) (xy 367.753512 -400.169754) (xy 367.807938 -400.198321) (xy 367.858524 -400.233241)
			(xy 367.904532 -400.274004) (xy 367.94529 -400.320015) (xy 367.980205 -400.370605) (xy 368.008767 -400.425034)
			(xy 368.030559 -400.482509) (xy 368.045265 -400.542192) (xy 368.052669 -400.603212) (xy 368.053112 -400.633946)
			(xy 368.052398 -400.671994) (xy 368.045643 -400.71675) (xy 369.264184 -400.71675) (xy 369.264574 -400.693516)
			(xy 369.271074 -400.647505) (xy 369.283952 -400.602857) (xy 369.302955 -400.560453) (xy 369.327709 -400.521127)
			(xy 369.342416 -400.503136) (xy 369.348512 -400.496024) (xy 369.354608 -400.479514) (xy 369.354608 -400.395186)
			(xy 369.348512 -400.378676) (xy 369.342416 -400.371564) (xy 369.327725 -400.353561) (xy 369.302976 -400.314235)
			(xy 369.283973 -400.271834) (xy 369.27109 -400.22719) (xy 369.264581 -400.181183) (xy 369.264184 -400.15795)
			(xy 369.264694 -400.131963) (xy 369.272824 -400.080628) (xy 369.288885 -400.031198) (xy 369.312481 -399.984888)
			(xy 369.343031 -399.94284) (xy 369.379782 -399.906089) (xy 369.42183 -399.875539) (xy 369.46814 -399.851943)
			(xy 369.51757 -399.835882) (xy 369.568905 -399.827752) (xy 369.620879 -399.827752) (xy 369.672214 -399.835882)
			(xy 369.721644 -399.851943) (xy 369.767954 -399.875539) (xy 369.810002 -399.906089) (xy 369.846753 -399.94284)
			(xy 369.877303 -399.984888) (xy 369.900899 -400.031198) (xy 369.91696 -400.080628) (xy 369.92509 -400.131963)
			(xy 369.9256 -400.15795) (xy 369.925213 -400.181184) (xy 369.918713 -400.227196) (xy 369.905835 -400.271843)
			(xy 369.88683 -400.314248) (xy 369.862076 -400.353573) (xy 369.847368 -400.371564) (xy 369.841272 -400.378676)
			(xy 369.835176 -400.395186) (xy 369.835176 -400.479514) (xy 369.841272 -400.496024) (xy 369.847368 -400.503136)
			(xy 369.862056 -400.521141) (xy 369.886807 -400.560466) (xy 369.905811 -400.602867) (xy 369.918694 -400.64751)
			(xy 369.925203 -400.693517) (xy 369.9256 -400.71675) (xy 369.92509 -400.742737) (xy 369.91696 -400.794072)
			(xy 369.900899 -400.843502) (xy 369.877303 -400.889812) (xy 369.846753 -400.93186) (xy 369.810002 -400.968611)
			(xy 369.767954 -400.999161) (xy 369.721644 -401.022757) (xy 369.672214 -401.038818) (xy 369.620879 -401.046948)
			(xy 369.568905 -401.046948) (xy 369.51757 -401.038818) (xy 369.46814 -401.022757) (xy 369.42183 -400.999161)
			(xy 369.379782 -400.968611) (xy 369.343031 -400.93186) (xy 369.312481 -400.889812) (xy 369.288885 -400.843502)
			(xy 369.272824 -400.794072) (xy 369.264694 -400.742737) (xy 369.264184 -400.71675) (xy 368.045643 -400.71675)
			(xy 368.041042 -400.747239) (xy 368.030506 -400.783806) (xy 368.027712 -400.792696) (xy 368.028728 -400.81073)
			(xy 368.063018 -400.888708) (xy 368.075718 -400.901662) (xy 368.0841 -400.905472) (xy 368.108192 -400.917426)
			(xy 368.15303 -400.947125) (xy 368.193255 -400.982824) (xy 368.228071 -401.023816) (xy 368.256787 -401.06929)
			(xy 368.278835 -401.118345) (xy 368.293779 -401.170009) (xy 368.301322 -401.223259) (xy 368.301778 -401.25015)
			(xy 368.301292 -401.277401) (xy 368.293536 -401.331349) (xy 368.278181 -401.383644) (xy 368.255539 -401.433221)
			(xy 368.226073 -401.479071) (xy 368.190382 -401.520262) (xy 368.149191 -401.555953) (xy 368.103341 -401.585419)
			(xy 368.053764 -401.608061) (xy 368.001469 -401.623416) (xy 367.947521 -401.631172) (xy 367.893019 -401.631172)
			(xy 367.839071 -401.623416) (xy 367.786776 -401.608061) (xy 367.737199 -401.585419) (xy 367.691349 -401.555953)
			(xy 367.650158 -401.520262) (xy 367.614467 -401.479071) (xy 367.585001 -401.433221) (xy 367.562359 -401.383644)
			(xy 367.547004 -401.331349) (xy 367.539248 -401.277401) (xy 367.538762 -401.25015) (xy 367.539016 -401.237958)
			(xy 367.53927 -401.22856) (xy 367.533428 -401.211542) (xy 367.480088 -401.145248) (xy 367.46434 -401.136104)
			(xy 367.455196 -401.13458) (xy 367.424627 -401.128635) (xy 367.365128 -401.110242) (xy 367.308318 -401.084728)
			(xy 367.255043 -401.052474) (xy 367.206101 -401.013963) (xy 367.162223 -400.96977) (xy 367.124063 -400.920554)
			(xy 367.107724 -400.894042) (xy 367.100866 -400.882358) (xy 367.077752 -400.869404) (xy 366.963198 -400.86915)
			(xy 366.940338 -400.882358) (xy 366.933226 -400.894042) (xy 366.915446 -400.921474) (xy 366.909953 -400.930213)
			(xy 366.905837 -400.950425) (xy 366.909972 -400.970632) (xy 366.915446 -400.979386) (xy 366.932467 -401.004933)
			(xy 366.96098 -401.059298) (xy 366.982746 -401.116698) (xy 366.997451 -401.176299) (xy 367.004879 -401.237236)
			(xy 367.005362 -401.26793) (xy 367.004891 -401.298626) (xy 366.99749 -401.359572) (xy 366.982797 -401.419181)
			(xy 366.961028 -401.476585) (xy 366.932501 -401.530947) (xy 366.915446 -401.556474) (xy 366.909953 -401.565213)
			(xy 366.905837 -401.585425) (xy 366.909972 -401.605632) (xy 366.915446 -401.614386) (xy 366.932467 -401.639933)
			(xy 366.950774 -401.674838) (xy 370.534692 -401.674838) (xy 370.534692 -400.811238) (xy 370.535155 -400.784882)
			(xy 370.542419 -400.732672) (xy 370.5568 -400.681958) (xy 370.578025 -400.633707) (xy 370.605689 -400.588837)
			(xy 370.639265 -400.548201) (xy 370.65839 -400.53006) (xy 370.665502 -400.52371) (xy 370.67363 -400.506946)
			(xy 370.682012 -400.420332) (xy 370.676932 -400.402552) (xy 370.671344 -400.394678) (xy 370.657193 -400.374832)
			(xy 370.634736 -400.331573) (xy 370.619424 -400.2853) (xy 370.611644 -400.237184) (xy 370.611146 -400.212814)
			(xy 370.611668 -400.187559) (xy 370.619981 -400.137737) (xy 370.636382 -400.089963) (xy 370.660423 -400.04554)
			(xy 370.691447 -400.00568) (xy 370.728609 -399.97147) (xy 370.770895 -399.943844) (xy 370.817151 -399.923554)
			(xy 370.866116 -399.911154) (xy 370.916454 -399.906983) (xy 370.966792 -399.911154) (xy 371.015757 -399.923554)
			(xy 371.062013 -399.943844) (xy 371.104299 -399.97147) (xy 371.141461 -400.00568) (xy 371.172485 -400.04554)
			(xy 371.196526 -400.089963) (xy 371.212927 -400.137737) (xy 371.22124 -400.187559) (xy 371.221762 -400.212814)
			(xy 371.221281 -400.237186) (xy 371.213523 -400.285309) (xy 371.198206 -400.331585) (xy 371.175721 -400.374833)
			(xy 371.161564 -400.394678) (xy 371.155976 -400.402552) (xy 371.150896 -400.420332) (xy 371.159278 -400.506946)
			(xy 371.167406 -400.52371) (xy 371.174518 -400.53006) (xy 371.193646 -400.5482) (xy 371.227236 -400.588829)
			(xy 371.254909 -400.633697) (xy 371.276137 -400.681949) (xy 371.290517 -400.732666) (xy 371.297773 -400.78488)
			(xy 371.298216 -400.811238) (xy 371.298216 -401.674838) (xy 371.734588 -401.674838) (xy 371.734588 -400.811238)
			(xy 371.735052 -400.784882) (xy 371.742316 -400.732672) (xy 371.756697 -400.681959) (xy 371.777921 -400.633708)
			(xy 371.805585 -400.588837) (xy 371.839161 -400.548201) (xy 371.858286 -400.53006) (xy 371.865398 -400.523456)
			(xy 371.87378 -400.506946) (xy 371.881908 -400.420078) (xy 371.877082 -400.402298) (xy 371.87124 -400.394678)
			(xy 371.857129 -400.374814) (xy 371.834709 -400.331557) (xy 371.819453 -400.285285) (xy 371.81175 -400.237175)
			(xy 371.811296 -400.212814) (xy 371.811818 -400.187559) (xy 371.820131 -400.137737) (xy 371.836532 -400.089963)
			(xy 371.860573 -400.04554) (xy 371.891597 -400.00568) (xy 371.928759 -399.97147) (xy 371.971045 -399.943844)
			(xy 372.017301 -399.923554) (xy 372.066266 -399.911154) (xy 372.116604 -399.906983) (xy 372.166942 -399.911154)
			(xy 372.215907 -399.923554) (xy 372.262163 -399.943844) (xy 372.304449 -399.97147) (xy 372.341611 -400.00568)
			(xy 372.372635 -400.04554) (xy 372.396676 -400.089963) (xy 372.413077 -400.137737) (xy 372.42139 -400.187559)
			(xy 372.421912 -400.212814) (xy 372.421455 -400.237217) (xy 372.413694 -400.285402) (xy 372.398372 -400.331741)
			(xy 372.375878 -400.375054) (xy 372.361714 -400.394932) (xy 372.356126 -400.402552) (xy 372.351046 -400.420332)
			(xy 372.359174 -400.5072) (xy 372.367556 -400.52371) (xy 372.374668 -400.530314) (xy 372.393727 -400.548477)
			(xy 372.42722 -400.589096) (xy 372.45482 -400.633928) (xy 372.476004 -400.682125) (xy 372.49037 -400.732774)
			(xy 372.497647 -400.784915) (xy 372.498112 -400.811238) (xy 372.498112 -401.674838) (xy 372.934992 -401.674838)
			(xy 372.934992 -400.811238) (xy 372.935443 -400.784893) (xy 372.942691 -400.732703) (xy 372.957041 -400.682004)
			(xy 372.978222 -400.633757) (xy 373.005831 -400.588879) (xy 373.039344 -400.54822) (xy 373.058436 -400.53006)
			(xy 373.065548 -400.52371) (xy 373.073676 -400.506946) (xy 373.082058 -400.420332) (xy 373.076978 -400.402552)
			(xy 373.07139 -400.394678) (xy 373.057245 -400.374828) (xy 373.034785 -400.331571) (xy 373.019471 -400.285299)
			(xy 373.011691 -400.237184) (xy 373.011192 -400.212814) (xy 373.011714 -400.187559) (xy 373.020027 -400.137737)
			(xy 373.036428 -400.089963) (xy 373.060469 -400.04554) (xy 373.091493 -400.00568) (xy 373.128655 -399.97147)
			(xy 373.170941 -399.943844) (xy 373.217197 -399.923554) (xy 373.266162 -399.911154) (xy 373.3165 -399.906983)
			(xy 373.366838 -399.911154) (xy 373.415803 -399.923554) (xy 373.462059 -399.943844) (xy 373.504345 -399.97147)
			(xy 373.541507 -400.00568) (xy 373.572531 -400.04554) (xy 373.596572 -400.089963) (xy 373.612973 -400.137737)
			(xy 373.621286 -400.187559) (xy 373.621808 -400.212814) (xy 373.621338 -400.237187) (xy 373.613578 -400.285311)
			(xy 373.598258 -400.331586) (xy 373.575769 -400.374834) (xy 373.56161 -400.394678) (xy 373.556022 -400.402552)
			(xy 373.550942 -400.420332) (xy 373.559324 -400.506946) (xy 373.567452 -400.52371) (xy 373.574564 -400.53006)
			(xy 373.59367 -400.548207) (xy 373.62719 -400.588864) (xy 373.654803 -400.633744) (xy 373.675983 -400.681994)
			(xy 373.690329 -400.732697) (xy 373.697568 -400.784891) (xy 373.698008 -400.811238) (xy 373.698008 -401.674838)
			(xy 374.134888 -401.674838) (xy 374.134888 -400.811238) (xy 374.13534 -400.784893) (xy 374.142588 -400.732703)
			(xy 374.156938 -400.682004) (xy 374.178119 -400.633758) (xy 374.205727 -400.588879) (xy 374.23924 -400.54822)
			(xy 374.258332 -400.53006) (xy 374.265444 -400.52371) (xy 374.273572 -400.506946) (xy 374.281954 -400.420332)
			(xy 374.276874 -400.402552) (xy 374.271286 -400.394678) (xy 374.25714 -400.374828) (xy 374.234681 -400.331571)
			(xy 374.219367 -400.285299) (xy 374.211587 -400.237184) (xy 374.211088 -400.212814) (xy 374.21161 -400.187559)
			(xy 374.219923 -400.137737) (xy 374.236324 -400.089963) (xy 374.260365 -400.04554) (xy 374.291389 -400.00568)
			(xy 374.328551 -399.97147) (xy 374.370837 -399.943844) (xy 374.417093 -399.923554) (xy 374.466058 -399.911154)
			(xy 374.516396 -399.906983) (xy 374.566734 -399.911154) (xy 374.615699 -399.923554) (xy 374.661955 -399.943844)
			(xy 374.704241 -399.97147) (xy 374.741403 -400.00568) (xy 374.772427 -400.04554) (xy 374.796468 -400.089963)
			(xy 374.812869 -400.137737) (xy 374.821182 -400.187559) (xy 374.821704 -400.212814) (xy 374.821235 -400.237187)
			(xy 374.813475 -400.285311) (xy 374.798155 -400.331586) (xy 374.775665 -400.374834) (xy 374.761506 -400.394678)
			(xy 374.755918 -400.402552) (xy 374.750838 -400.420332) (xy 374.75922 -400.506946) (xy 374.767348 -400.52371)
			(xy 374.77446 -400.53006) (xy 374.793565 -400.548208) (xy 374.827086 -400.588865) (xy 374.854698 -400.633744)
			(xy 374.875879 -400.681994) (xy 374.890225 -400.732697) (xy 374.897464 -400.784891) (xy 374.897904 -400.811238)
			(xy 374.897904 -401.674838) (xy 375.334784 -401.674838) (xy 375.334784 -400.811238) (xy 375.33525 -400.784882)
			(xy 375.342513 -400.732672) (xy 375.356894 -400.681959) (xy 375.378118 -400.633708) (xy 375.405782 -400.588837)
			(xy 375.439357 -400.548201) (xy 375.458482 -400.53006) (xy 375.465594 -400.52371) (xy 375.473722 -400.506946)
			(xy 375.482104 -400.420332) (xy 375.477024 -400.402552) (xy 375.471436 -400.394678) (xy 375.457284 -400.374833)
			(xy 375.434827 -400.331573) (xy 375.419516 -400.2853) (xy 375.411736 -400.237184) (xy 375.411238 -400.212814)
			(xy 375.41176 -400.187559) (xy 375.420073 -400.137737) (xy 375.436474 -400.089963) (xy 375.460515 -400.04554)
			(xy 375.491539 -400.00568) (xy 375.528701 -399.97147) (xy 375.570987 -399.943844) (xy 375.617243 -399.923554)
			(xy 375.666208 -399.911154) (xy 375.716546 -399.906983) (xy 375.766884 -399.911154) (xy 375.815849 -399.923554)
			(xy 375.862105 -399.943844) (xy 375.904391 -399.97147) (xy 375.941553 -400.00568) (xy 375.972577 -400.04554)
			(xy 375.996618 -400.089963) (xy 376.013019 -400.137737) (xy 376.021332 -400.187559) (xy 376.021854 -400.212814)
			(xy 376.021375 -400.237186) (xy 376.013616 -400.285309) (xy 375.998299 -400.331585) (xy 375.975813 -400.374833)
			(xy 375.961656 -400.394678) (xy 375.956068 -400.402552) (xy 375.950988 -400.420332) (xy 375.95937 -400.506946)
			(xy 375.967498 -400.52371) (xy 375.97461 -400.53006) (xy 375.993736 -400.548202) (xy 376.027326 -400.58883)
			(xy 376.055 -400.633698) (xy 376.076229 -400.68195) (xy 376.090609 -400.732666) (xy 376.097865 -400.78488)
			(xy 376.098308 -400.811238) (xy 376.098308 -401.674838) (xy 376.53468 -401.674838) (xy 376.53468 -400.811238)
			(xy 376.535147 -400.784882) (xy 376.542411 -400.732672) (xy 376.556791 -400.681959) (xy 376.578015 -400.633708)
			(xy 376.605678 -400.588837) (xy 376.639254 -400.548201) (xy 376.658378 -400.53006) (xy 376.66549 -400.52371)
			(xy 376.673618 -400.506946) (xy 376.682 -400.420332) (xy 376.67692 -400.402552) (xy 376.671332 -400.394678)
			(xy 376.657179 -400.374833) (xy 376.634723 -400.331573) (xy 376.619412 -400.2853) (xy 376.611632 -400.237184)
			(xy 376.611134 -400.212814) (xy 376.611656 -400.187559) (xy 376.619969 -400.137737) (xy 376.63637 -400.089963)
			(xy 376.660411 -400.04554) (xy 376.691435 -400.00568) (xy 376.728597 -399.97147) (xy 376.770883 -399.943844)
			(xy 376.817139 -399.923554) (xy 376.866104 -399.911154) (xy 376.916442 -399.906983) (xy 376.96678 -399.911154)
			(xy 377.015745 -399.923554) (xy 377.062001 -399.943844) (xy 377.104287 -399.97147) (xy 377.141449 -400.00568)
			(xy 377.172473 -400.04554) (xy 377.196514 -400.089963) (xy 377.212915 -400.137737) (xy 377.221228 -400.187559)
			(xy 377.22175 -400.212814) (xy 377.221272 -400.237186) (xy 377.213513 -400.28531) (xy 377.198195 -400.331585)
			(xy 377.175709 -400.374833) (xy 377.161552 -400.394678) (xy 377.155964 -400.402552) (xy 377.150884 -400.420332)
			(xy 377.159266 -400.506946) (xy 377.167394 -400.52371) (xy 377.174506 -400.53006) (xy 377.193632 -400.548203)
			(xy 377.227222 -400.58883) (xy 377.254896 -400.633698) (xy 377.276125 -400.68195) (xy 377.290505 -400.732666)
			(xy 377.297761 -400.78488) (xy 377.298204 -400.811238) (xy 377.298204 -401.674838) (xy 377.735084 -401.674838)
			(xy 377.735084 -400.811238) (xy 377.735537 -400.784893) (xy 377.742785 -400.732703) (xy 377.757135 -400.682004)
			(xy 377.778316 -400.633758) (xy 377.805924 -400.588879) (xy 377.839436 -400.54822) (xy 377.858528 -400.53006)
			(xy 377.86564 -400.52371) (xy 377.873768 -400.506946) (xy 377.88215 -400.420332) (xy 377.87707 -400.402552)
			(xy 377.871482 -400.394678) (xy 377.857336 -400.374829) (xy 377.834876 -400.331571) (xy 377.819563 -400.285299)
			(xy 377.811782 -400.237184) (xy 377.811284 -400.212814) (xy 377.811806 -400.187559) (xy 377.820119 -400.137737)
			(xy 377.83652 -400.089963) (xy 377.860561 -400.04554) (xy 377.891585 -400.00568) (xy 377.928747 -399.97147)
			(xy 377.971033 -399.943844) (xy 378.017289 -399.923554) (xy 378.066254 -399.911154) (xy 378.116592 -399.906983)
			(xy 378.16693 -399.911154) (xy 378.215895 -399.923554) (xy 378.262151 -399.943844) (xy 378.304437 -399.97147)
			(xy 378.341599 -400.00568) (xy 378.372623 -400.04554) (xy 378.396664 -400.089963) (xy 378.413065 -400.137737)
			(xy 378.421378 -400.187559) (xy 378.4219 -400.212814) (xy 378.421431 -400.237187) (xy 378.413671 -400.285311)
			(xy 378.398351 -400.331586) (xy 378.375861 -400.374834) (xy 378.361702 -400.394678) (xy 378.356114 -400.402552)
			(xy 378.351034 -400.420332) (xy 378.359416 -400.506946) (xy 378.367544 -400.52371) (xy 378.374656 -400.53006)
			(xy 378.39376 -400.548209) (xy 378.427281 -400.588865) (xy 378.454894 -400.633745) (xy 378.476075 -400.681994)
			(xy 378.490421 -400.732697) (xy 378.49766 -400.784891) (xy 378.4981 -400.811238) (xy 378.4981 -401.674838)
			(xy 378.93498 -401.674838) (xy 378.93498 -400.811238) (xy 378.935434 -400.784893) (xy 378.942682 -400.732703)
			(xy 378.957032 -400.682004) (xy 378.978212 -400.633758) (xy 379.00582 -400.58888) (xy 379.039332 -400.54822)
			(xy 379.058424 -400.53006) (xy 379.065536 -400.52371) (xy 379.073664 -400.506946) (xy 379.082046 -400.420332)
			(xy 379.076966 -400.402552) (xy 379.071378 -400.394678) (xy 379.057231 -400.374829) (xy 379.034772 -400.331571)
			(xy 379.019459 -400.285299) (xy 379.011678 -400.237184) (xy 379.01118 -400.212814) (xy 379.011702 -400.187559)
			(xy 379.020015 -400.137737) (xy 379.036416 -400.089963) (xy 379.060457 -400.04554) (xy 379.091481 -400.00568)
			(xy 379.128643 -399.97147) (xy 379.170929 -399.943844) (xy 379.217185 -399.923554) (xy 379.26615 -399.911154)
			(xy 379.316488 -399.906983) (xy 379.366826 -399.911154) (xy 379.415791 -399.923554) (xy 379.462047 -399.943844)
			(xy 379.504333 -399.97147) (xy 379.541495 -400.00568) (xy 379.572519 -400.04554) (xy 379.59656 -400.089963)
			(xy 379.612961 -400.137737) (xy 379.621274 -400.187559) (xy 379.621796 -400.212814) (xy 379.621328 -400.237187)
			(xy 379.613568 -400.285311) (xy 379.598247 -400.331587) (xy 379.575757 -400.374834) (xy 379.561598 -400.394678)
			(xy 379.55601 -400.402552) (xy 379.55093 -400.420332) (xy 379.559312 -400.506946) (xy 379.56744 -400.52371)
			(xy 379.574552 -400.53006) (xy 379.593655 -400.548209) (xy 379.627177 -400.588866) (xy 379.65479 -400.633745)
			(xy 379.675971 -400.681994) (xy 379.690317 -400.732697) (xy 379.697556 -400.784891) (xy 379.697996 -400.811238)
			(xy 379.697996 -401.674838) (xy 380.134876 -401.674838) (xy 380.134876 -400.811238) (xy 380.135294 -400.78491)
			(xy 380.142545 -400.732755) (xy 380.156901 -400.682094) (xy 380.178088 -400.633888) (xy 380.205705 -400.589055)
			(xy 380.239226 -400.548446) (xy 380.25832 -400.530314) (xy 380.265432 -400.52371) (xy 380.273814 -400.5072)
			(xy 380.281942 -400.420332) (xy 380.276862 -400.402552) (xy 380.271274 -400.394932) (xy 380.257115 -400.375052)
			(xy 380.234629 -400.331737) (xy 380.219312 -400.285399) (xy 380.211554 -400.237216) (xy 380.211076 -400.212814)
			(xy 380.211598 -400.187559) (xy 380.219911 -400.137737) (xy 380.236312 -400.089963) (xy 380.260353 -400.04554)
			(xy 380.291377 -400.00568) (xy 380.328539 -399.97147) (xy 380.370825 -399.943844) (xy 380.417081 -399.923554)
			(xy 380.466046 -399.911154) (xy 380.516384 -399.906983) (xy 380.566722 -399.911154) (xy 380.615687 -399.923554)
			(xy 380.661943 -399.943844) (xy 380.704229 -399.97147) (xy 380.741391 -400.00568) (xy 380.772415 -400.04554)
			(xy 380.796456 -400.089963) (xy 380.812857 -400.137737) (xy 380.82117 -400.187559) (xy 380.821692 -400.212814)
			(xy 380.821205 -400.237173) (xy 380.813491 -400.285276) (xy 380.798245 -400.331546) (xy 380.775853 -400.374813)
			(xy 380.761748 -400.394678) (xy 380.755906 -400.402298) (xy 380.75108 -400.420078) (xy 380.759208 -400.506946)
			(xy 380.76759 -400.523456) (xy 380.774702 -400.53006) (xy 380.793827 -400.548203) (xy 380.827417 -400.588831)
			(xy 380.855091 -400.633698) (xy 380.876321 -400.68195) (xy 380.890701 -400.732667) (xy 380.897957 -400.78488)
			(xy 380.8984 -400.811238) (xy 380.8984 -401.674838) (xy 381.334772 -401.674838) (xy 381.334772 -400.811238)
			(xy 381.335242 -400.784882) (xy 381.342505 -400.732672) (xy 381.356885 -400.68196) (xy 381.378109 -400.633709)
			(xy 381.405771 -400.588838) (xy 381.439346 -400.548202) (xy 381.45847 -400.53006) (xy 381.465582 -400.52371)
			(xy 381.47371 -400.506946) (xy 381.482092 -400.420332) (xy 381.477012 -400.402552) (xy 381.471424 -400.394678)
			(xy 381.45727 -400.374834) (xy 381.434815 -400.331574) (xy 381.419503 -400.2853) (xy 381.411724 -400.237184)
			(xy 381.411226 -400.212814) (xy 381.411748 -400.187559) (xy 381.420061 -400.137737) (xy 381.436462 -400.089963)
			(xy 381.460503 -400.04554) (xy 381.491527 -400.00568) (xy 381.528689 -399.97147) (xy 381.570975 -399.943844)
			(xy 381.617231 -399.923554) (xy 381.666196 -399.911154) (xy 381.716534 -399.906983) (xy 381.766872 -399.911154)
			(xy 381.815837 -399.923554) (xy 381.862093 -399.943844) (xy 381.904379 -399.97147) (xy 381.941541 -400.00568)
			(xy 381.972565 -400.04554) (xy 381.996606 -400.089963) (xy 382.013007 -400.137737) (xy 382.02132 -400.187559)
			(xy 382.021842 -400.212814) (xy 382.021365 -400.237186) (xy 382.013606 -400.28531) (xy 381.998288 -400.331585)
			(xy 381.975801 -400.374833) (xy 381.961644 -400.394678) (xy 381.956056 -400.402552) (xy 381.950976 -400.420332)
			(xy 381.959358 -400.506946) (xy 381.967486 -400.52371) (xy 381.974598 -400.53006) (xy 381.993722 -400.548204)
			(xy 382.027313 -400.588831) (xy 382.054987 -400.633699) (xy 382.076216 -400.68195) (xy 382.090597 -400.732667)
			(xy 382.097853 -400.78488) (xy 382.098296 -400.811238) (xy 382.098296 -401.674838) (xy 382.535176 -401.674838)
			(xy 382.535176 -400.811238) (xy 382.535616 -400.784922) (xy 382.54284 -400.732787) (xy 382.557156 -400.682139)
			(xy 382.578293 -400.633937) (xy 382.60585 -400.589096) (xy 382.639305 -400.548464) (xy 382.658366 -400.530314)
			(xy 382.665478 -400.52371) (xy 382.67386 -400.5072) (xy 382.681988 -400.420332) (xy 382.676908 -400.402552)
			(xy 382.67132 -400.394932) (xy 382.657167 -400.375048) (xy 382.634678 -400.331735) (xy 382.619359 -400.285398)
			(xy 382.6116 -400.237216) (xy 382.611122 -400.212814) (xy 382.611644 -400.187559) (xy 382.619957 -400.137737)
			(xy 382.636358 -400.089963) (xy 382.660399 -400.04554) (xy 382.691423 -400.00568) (xy 382.728585 -399.97147)
			(xy 382.770871 -399.943844) (xy 382.817127 -399.923554) (xy 382.866092 -399.911154) (xy 382.91643 -399.906983)
			(xy 382.966768 -399.911154) (xy 383.015733 -399.923554) (xy 383.061989 -399.943844) (xy 383.104275 -399.97147)
			(xy 383.141437 -400.00568) (xy 383.172461 -400.04554) (xy 383.196502 -400.089963) (xy 383.212903 -400.137737)
			(xy 383.221216 -400.187559) (xy 383.221738 -400.212814) (xy 383.221243 -400.237172) (xy 383.21353 -400.285275)
			(xy 383.198287 -400.331545) (xy 383.175898 -400.374812) (xy 383.161794 -400.394678) (xy 383.155952 -400.402298)
			(xy 383.151126 -400.420078) (xy 383.159254 -400.506946) (xy 383.167636 -400.523456) (xy 383.174748 -400.53006)
			(xy 383.193851 -400.54821) (xy 383.227372 -400.588866) (xy 383.254985 -400.633745) (xy 383.276167 -400.681994)
			(xy 383.290513 -400.732697) (xy 383.297752 -400.784891) (xy 383.298192 -400.811238) (xy 383.298192 -401.674838)
			(xy 383.735072 -401.674838) (xy 383.735072 -400.811238) (xy 383.735529 -400.784893) (xy 383.742777 -400.732704)
			(xy 383.757127 -400.682005) (xy 383.778306 -400.633759) (xy 383.805913 -400.58888) (xy 383.839425 -400.54822)
			(xy 383.858516 -400.53006) (xy 383.865628 -400.52371) (xy 383.873756 -400.506946) (xy 383.882138 -400.420332)
			(xy 383.877058 -400.402552) (xy 383.87147 -400.394678) (xy 383.857322 -400.37483) (xy 383.834864 -400.331572)
			(xy 383.819551 -400.285299) (xy 383.81177 -400.237184) (xy 383.811272 -400.212814) (xy 383.811794 -400.187559)
			(xy 383.820107 -400.137737) (xy 383.836508 -400.089963) (xy 383.860549 -400.04554) (xy 383.891573 -400.00568)
			(xy 383.928735 -399.97147) (xy 383.971021 -399.943844) (xy 384.017277 -399.923554) (xy 384.066242 -399.911154)
			(xy 384.11658 -399.906983) (xy 384.166918 -399.911154) (xy 384.215883 -399.923554) (xy 384.262139 -399.943844)
			(xy 384.304425 -399.97147) (xy 384.341587 -400.00568) (xy 384.372611 -400.04554) (xy 384.396652 -400.089963)
			(xy 384.413053 -400.137737) (xy 384.421366 -400.187559) (xy 384.421888 -400.212814) (xy 384.421422 -400.237187)
			(xy 384.413661 -400.285311) (xy 384.39834 -400.331587) (xy 384.37585 -400.374834) (xy 384.36169 -400.394678)
			(xy 384.356102 -400.402552) (xy 384.351022 -400.420332) (xy 384.359404 -400.506946) (xy 384.367532 -400.52371)
			(xy 384.374644 -400.53006) (xy 384.393746 -400.548211) (xy 384.427267 -400.588867) (xy 384.454881 -400.633746)
			(xy 384.476062 -400.681995) (xy 384.490409 -400.732697) (xy 384.497648 -400.784891) (xy 384.498088 -400.811238)
			(xy 384.498088 -401.674838) (xy 384.934968 -401.674838) (xy 384.934968 -400.811238) (xy 384.935426 -400.784893)
			(xy 384.942674 -400.732704) (xy 384.957024 -400.682005) (xy 384.978203 -400.633759) (xy 385.00581 -400.58888)
			(xy 385.039321 -400.54822) (xy 385.058412 -400.53006) (xy 385.065524 -400.52371) (xy 385.073652 -400.506946)
			(xy 385.082034 -400.420332) (xy 385.076954 -400.402552) (xy 385.071366 -400.394678) (xy 385.057218 -400.37483)
			(xy 385.034759 -400.331572) (xy 385.019446 -400.285299) (xy 385.011666 -400.237184) (xy 385.011168 -400.212814)
			(xy 385.01169 -400.187559) (xy 385.020003 -400.137737) (xy 385.036404 -400.089963) (xy 385.060445 -400.04554)
			(xy 385.091469 -400.00568) (xy 385.128631 -399.97147) (xy 385.170917 -399.943844) (xy 385.217173 -399.923554)
			(xy 385.266138 -399.911154) (xy 385.316476 -399.906983) (xy 385.366814 -399.911154) (xy 385.415779 -399.923554)
			(xy 385.462035 -399.943844) (xy 385.504321 -399.97147) (xy 385.541483 -400.00568) (xy 385.572507 -400.04554)
			(xy 385.596548 -400.089963) (xy 385.612949 -400.137737) (xy 385.621262 -400.187559) (xy 385.621784 -400.212814)
			(xy 385.621319 -400.237187) (xy 385.613558 -400.285311) (xy 385.598237 -400.331587) (xy 385.575746 -400.374834)
			(xy 385.561586 -400.394678) (xy 385.555998 -400.402552) (xy 385.550918 -400.420332) (xy 385.5593 -400.506946)
			(xy 385.567428 -400.52371) (xy 385.57454 -400.53006) (xy 385.593641 -400.548212) (xy 385.627163 -400.588867)
			(xy 385.654777 -400.633746) (xy 385.675958 -400.681995) (xy 385.690305 -400.732697) (xy 385.697544 -400.784891)
			(xy 385.697984 -400.811238) (xy 385.697984 -401.674838) (xy 386.134864 -401.674838) (xy 386.134864 -400.811238)
			(xy 386.135324 -400.784893) (xy 386.142571 -400.732704) (xy 386.156921 -400.682005) (xy 386.1781 -400.633759)
			(xy 386.205706 -400.588881) (xy 386.239217 -400.54822) (xy 386.258308 -400.53006) (xy 386.26542 -400.52371)
			(xy 386.273548 -400.506946) (xy 386.28193 -400.420332) (xy 386.27685 -400.402552) (xy 386.271262 -400.394678)
			(xy 386.257113 -400.37483) (xy 386.234655 -400.331572) (xy 386.219342 -400.285299) (xy 386.211562 -400.237184)
			(xy 386.211064 -400.212814) (xy 386.211586 -400.187559) (xy 386.219899 -400.137737) (xy 386.2363 -400.089963)
			(xy 386.260341 -400.04554) (xy 386.291365 -400.00568) (xy 386.328527 -399.97147) (xy 386.370813 -399.943844)
			(xy 386.417069 -399.923554) (xy 386.466034 -399.911154) (xy 386.516372 -399.906983) (xy 386.56671 -399.911154)
			(xy 386.615675 -399.923554) (xy 386.661931 -399.943844) (xy 386.704217 -399.97147) (xy 386.741379 -400.00568)
			(xy 386.772403 -400.04554) (xy 386.796444 -400.089963) (xy 386.812845 -400.137737) (xy 386.821158 -400.187559)
			(xy 386.82168 -400.212814) (xy 386.821215 -400.237187) (xy 386.813455 -400.285311) (xy 386.798133 -400.331587)
			(xy 386.775642 -400.374834) (xy 386.761482 -400.394678) (xy 386.755894 -400.402552) (xy 386.750814 -400.420332)
			(xy 386.759196 -400.506946) (xy 386.767324 -400.52371) (xy 386.774436 -400.53006) (xy 386.793536 -400.548213)
			(xy 386.827058 -400.588868) (xy 386.854672 -400.633746) (xy 386.875854 -400.681995) (xy 386.890201 -400.732698)
			(xy 386.89744 -400.784891) (xy 386.89788 -400.811238) (xy 386.89788 -401.674838) (xy 387.33476 -401.674838)
			(xy 387.33476 -400.811238) (xy 387.335233 -400.784882) (xy 387.342497 -400.732673) (xy 387.356877 -400.68196)
			(xy 387.378099 -400.633709) (xy 387.405761 -400.588839) (xy 387.439335 -400.548202) (xy 387.458458 -400.53006)
			(xy 387.46557 -400.52371) (xy 387.473698 -400.506946) (xy 387.48208 -400.420332) (xy 387.477 -400.402552)
			(xy 387.471412 -400.394678) (xy 387.457257 -400.374835) (xy 387.434802 -400.331574) (xy 387.419491 -400.2853)
			(xy 387.411712 -400.237184) (xy 387.411214 -400.212814) (xy 387.411736 -400.187559) (xy 387.420049 -400.137737)
			(xy 387.43645 -400.089963) (xy 387.460491 -400.04554) (xy 387.491515 -400.00568) (xy 387.528677 -399.97147)
			(xy 387.570963 -399.943844) (xy 387.617219 -399.923554) (xy 387.666184 -399.911154) (xy 387.716522 -399.906983)
			(xy 387.76686 -399.911154) (xy 387.815825 -399.923554) (xy 387.862081 -399.943844) (xy 387.904367 -399.97147)
			(xy 387.941529 -400.00568) (xy 387.972553 -400.04554) (xy 387.996594 -400.089963) (xy 388.012995 -400.137737)
			(xy 388.021308 -400.187559) (xy 388.02183 -400.212814) (xy 388.021356 -400.237187) (xy 388.013596 -400.28531)
			(xy 387.998278 -400.331586) (xy 387.97579 -400.374834) (xy 387.961632 -400.394678) (xy 387.956044 -400.402552)
			(xy 387.950964 -400.420332) (xy 387.959346 -400.506946) (xy 387.967474 -400.52371) (xy 387.974586 -400.53006)
			(xy 387.993727 -400.548187) (xy 388.027313 -400.58882) (xy 388.054982 -400.633691) (xy 388.076208 -400.681946)
			(xy 388.090586 -400.732664) (xy 388.097841 -400.78488) (xy 388.098284 -400.811238) (xy 388.098284 -401.674838)
			(xy 388.534656 -401.674838) (xy 388.534656 -400.811238) (xy 388.535131 -400.784882) (xy 388.542394 -400.732673)
			(xy 388.556774 -400.681961) (xy 388.577996 -400.63371) (xy 388.605657 -400.588839) (xy 388.639231 -400.548202)
			(xy 388.658354 -400.53006) (xy 388.665466 -400.52371) (xy 388.673594 -400.506946) (xy 388.681976 -400.420332)
			(xy 388.676896 -400.402552) (xy 388.671308 -400.394678) (xy 388.657165 -400.374826) (xy 388.634704 -400.33157)
			(xy 388.619389 -400.285298) (xy 388.611609 -400.237184) (xy 388.61111 -400.212814) (xy 388.611632 -400.187559)
			(xy 388.619945 -400.137737) (xy 388.636346 -400.089963) (xy 388.660387 -400.04554) (xy 388.691411 -400.00568)
			(xy 388.728573 -399.97147) (xy 388.770859 -399.943844) (xy 388.817115 -399.923554) (xy 388.86608 -399.911154)
			(xy 388.916418 -399.906983) (xy 388.966756 -399.911154) (xy 389.015721 -399.923554) (xy 389.061977 -399.943844)
			(xy 389.104263 -399.97147) (xy 389.141425 -400.00568) (xy 389.172449 -400.04554) (xy 389.19649 -400.089963)
			(xy 389.212891 -400.137737) (xy 389.221204 -400.187559) (xy 389.221726 -400.212814) (xy 389.221252 -400.237187)
			(xy 389.213493 -400.28531) (xy 389.198174 -400.331586) (xy 389.175686 -400.374834) (xy 389.161528 -400.394678)
			(xy 389.15594 -400.402552) (xy 389.15086 -400.420332) (xy 389.159242 -400.506946) (xy 389.16737 -400.52371)
			(xy 389.174482 -400.53006) (xy 389.193622 -400.548188) (xy 389.227208 -400.58882) (xy 389.254878 -400.633692)
			(xy 389.276104 -400.681946) (xy 389.290482 -400.732664) (xy 389.297737 -400.78488) (xy 389.29818 -400.811238)
			(xy 389.29818 -401.208294) (xy 390.484522 -401.208294) (xy 390.487132 -401.145269) (xy 390.497517 -401.083051)
			(xy 390.515519 -401.022595) (xy 390.54086 -400.96483) (xy 390.573152 -400.910643) (xy 390.611899 -400.860867)
			(xy 390.656504 -400.816265) (xy 390.706285 -400.777524) (xy 390.760475 -400.745237) (xy 390.818242 -400.719902)
			(xy 390.8787 -400.701906) (xy 390.940919 -400.691526) (xy 391.003945 -400.688923) (xy 391.066808 -400.694135)
			(xy 391.128544 -400.707083) (xy 391.188204 -400.727568) (xy 391.244873 -400.755275) (xy 391.297679 -400.789778)
			(xy 391.345811 -400.830549) (xy 391.388531 -400.87696) (xy 391.425183 -400.928298) (xy 391.455202 -400.983776)
			(xy 391.478129 -401.042542) (xy 391.493611 -401.103691) (xy 391.50141 -401.166286) (xy 391.501884 -401.197826)
			(xy 391.500106 -401.239228) (xy 391.49909 -401.25142) (xy 391.508488 -401.274026) (xy 391.589768 -401.343368)
			(xy 391.61339 -401.34921) (xy 391.625328 -401.346162) (xy 391.647472 -401.341173) (xy 391.692548 -401.335822)
			(xy 391.715244 -401.335494) (xy 391.742493 -401.335979) (xy 391.796437 -401.34374) (xy 391.848726 -401.359099)
			(xy 391.898298 -401.381743) (xy 391.944143 -401.411211) (xy 391.985329 -401.446903) (xy 392.021016 -401.488092)
			(xy 392.050478 -401.53394) (xy 392.073116 -401.583515) (xy 392.088469 -401.635806) (xy 392.096224 -401.689751)
			(xy 392.096224 -401.744249) (xy 392.088469 -401.798194) (xy 392.073116 -401.850485) (xy 392.050478 -401.90006)
			(xy 392.021016 -401.945908) (xy 391.985329 -401.987097) (xy 391.944143 -402.022789) (xy 391.898298 -402.052257)
			(xy 391.848726 -402.074901) (xy 391.796437 -402.09026) (xy 391.742493 -402.098021) (xy 391.715244 -402.09851)
			(xy 391.686914 -402.098022) (xy 391.63088 -402.089608) (xy 391.576707 -402.073001) (xy 391.525584 -402.048568)
			(xy 391.478635 -402.016844) (xy 391.436893 -401.978529) (xy 391.401274 -401.934462) (xy 391.372561 -401.885615)
			(xy 391.351386 -401.833058) (xy 391.338214 -401.777949) (xy 391.33526 -401.749768) (xy 391.33399 -401.737576)
			(xy 391.321036 -401.716748) (xy 391.229596 -401.661884) (xy 391.205212 -401.66036) (xy 391.193782 -401.665186)
			(xy 391.161998 -401.678215) (xy 391.095791 -401.69653) (xy 391.027723 -401.705771) (xy 390.993376 -401.706334)
			(xy 390.961836 -401.705807) (xy 390.899242 -401.698002) (xy 390.838094 -401.682514) (xy 390.779331 -401.659581)
			(xy 390.723856 -401.629556) (xy 390.672521 -401.5929) (xy 390.626114 -401.550175) (xy 390.585348 -401.502039)
			(xy 390.55085 -401.449229) (xy 390.523148 -401.392558) (xy 390.50267 -401.332896) (xy 390.489728 -401.271158)
			(xy 390.484522 -401.208294) (xy 389.29818 -401.208294) (xy 389.29818 -401.461986) (xy 389.298587 -401.470959)
			(xy 389.304815 -401.487792) (xy 389.316448 -401.50146) (xy 389.324088 -401.506182) (xy 389.413496 -401.55622)
			(xy 389.441182 -401.555712) (xy 389.452866 -401.548346) (xy 389.475529 -401.534906) (xy 389.523781 -401.513738)
			(xy 389.574482 -401.499396) (xy 389.626673 -401.49215) (xy 389.653018 -401.491704) (xy 389.680269 -401.492167)
			(xy 389.734217 -401.499926) (xy 389.786511 -401.515283) (xy 389.836087 -401.537926) (xy 389.881937 -401.567394)
			(xy 389.923126 -401.603086) (xy 389.958817 -401.644277) (xy 389.988283 -401.690128) (xy 390.010923 -401.739706)
			(xy 390.026278 -401.792001) (xy 390.034034 -401.845949) (xy 390.034034 -401.900451) (xy 390.026278 -401.954399)
			(xy 390.010923 -402.006694) (xy 389.988283 -402.056272) (xy 389.958817 -402.102123) (xy 389.923126 -402.143314)
			(xy 389.881937 -402.179006) (xy 389.836087 -402.208474) (xy 389.786511 -402.231117) (xy 389.734217 -402.246474)
			(xy 389.680269 -402.254233) (xy 389.653018 -402.25472) (xy 389.626064 -402.254204) (xy 389.572694 -402.246605)
			(xy 389.520925 -402.231571) (xy 389.471787 -402.209399) (xy 389.426259 -402.180533) (xy 389.385248 -402.145545)
			(xy 389.349568 -402.105134) (xy 389.319932 -402.060104) (xy 389.296928 -402.01135) (xy 389.288528 -401.985734)
			(xy 389.285666 -401.977666) (xy 389.275516 -401.963896) (xy 389.261394 -401.954244) (xy 389.253222 -401.951698)
			(xy 389.194802 -401.93595) (xy 389.18515 -401.945856) (xy 389.178546 -401.95246) (xy 389.170926 -401.969224)
			(xy 389.165592 -402.05533) (xy 389.170926 -402.07311) (xy 389.176768 -402.080476) (xy 389.193276 -402.102464)
			(xy 389.21955 -402.150757) (xy 389.237481 -402.202729) (xy 389.246577 -402.256949) (xy 389.247126 -402.284438)
			(xy 389.246616 -402.310425) (xy 389.238486 -402.36176) (xy 389.222425 -402.41119) (xy 389.198829 -402.4575)
			(xy 389.168279 -402.499548) (xy 389.131528 -402.536299) (xy 389.08948 -402.566849) (xy 389.04317 -402.590445)
			(xy 388.99374 -402.606506) (xy 388.942405 -402.614636) (xy 388.890431 -402.614636) (xy 388.839096 -402.606506)
			(xy 388.789666 -402.590445) (xy 388.743356 -402.566849) (xy 388.701308 -402.536299) (xy 388.664557 -402.499548)
			(xy 388.634007 -402.4575) (xy 388.610411 -402.41119) (xy 388.59435 -402.36176) (xy 388.58622 -402.310425)
			(xy 388.58571 -402.284438) (xy 388.586261 -402.256947) (xy 388.595337 -402.202721) (xy 388.613262 -402.150745)
			(xy 388.639543 -402.102452) (xy 388.656068 -402.080476) (xy 388.66191 -402.07311) (xy 388.667244 -402.05533)
			(xy 388.66191 -401.969224) (xy 388.65429 -401.95246) (xy 388.647686 -401.945856) (xy 388.626644 -401.92424)
			(xy 388.590998 -401.875576) (xy 388.563458 -401.821907) (xy 388.54471 -401.764571) (xy 388.535223 -401.704999)
			(xy 388.534656 -401.674838) (xy 388.098284 -401.674838) (xy 388.097874 -401.701013) (xy 388.090676 -401.752866)
			(xy 388.076462 -401.80325) (xy 388.055498 -401.851219) (xy 388.028176 -401.895875) (xy 387.995011 -401.936379)
			(xy 387.97611 -401.954492) (xy 387.968744 -401.96135) (xy 387.960616 -401.978876) (xy 387.955282 -402.069046)
			(xy 387.961378 -402.087334) (xy 387.967982 -402.094954) (xy 387.982879 -402.113001) (xy 388.007945 -402.152517)
			(xy 388.027193 -402.195171) (xy 388.040241 -402.24011) (xy 388.046828 -402.28644) (xy 388.04723 -402.309838)
			(xy 388.04672 -402.335825) (xy 388.03859 -402.38716) (xy 388.022529 -402.43659) (xy 387.998933 -402.4829)
			(xy 387.968383 -402.524948) (xy 387.931632 -402.561699) (xy 387.889584 -402.592249) (xy 387.843274 -402.615845)
			(xy 387.793844 -402.631906) (xy 387.742509 -402.640036) (xy 387.690535 -402.640036) (xy 387.6392 -402.631906)
			(xy 387.58977 -402.615845) (xy 387.54346 -402.592249) (xy 387.501412 -402.561699) (xy 387.464661 -402.524948)
			(xy 387.434111 -402.4829) (xy 387.410515 -402.43659) (xy 387.394454 -402.38716) (xy 387.386324 -402.335825)
			(xy 387.385814 -402.309838) (xy 387.386247 -402.286442) (xy 387.392833 -402.240116) (xy 387.405878 -402.195179)
			(xy 387.425122 -402.152528) (xy 387.450182 -402.113012) (xy 387.465062 -402.094954) (xy 387.471666 -402.087334)
			(xy 387.477762 -402.069046) (xy 387.472428 -401.978876) (xy 387.4643 -401.96135) (xy 387.456934 -401.954492)
			(xy 387.438025 -401.936389) (xy 387.404865 -401.895881) (xy 387.377552 -401.851223) (xy 387.356597 -401.803251)
			(xy 387.342393 -401.752866) (xy 387.335208 -401.701012) (xy 387.33476 -401.674838) (xy 386.89788 -401.674838)
			(xy 386.897414 -401.701001) (xy 386.890264 -401.752836) (xy 386.876103 -401.80321) (xy 386.855196 -401.851178)
			(xy 386.827935 -401.895842) (xy 386.794831 -401.936365) (xy 386.77596 -401.954492) (xy 386.768594 -401.96135)
			(xy 386.760466 -401.978876) (xy 386.755132 -402.069046) (xy 386.761228 -402.087334) (xy 386.767832 -402.094954)
			(xy 386.782737 -402.112994) (xy 386.807799 -402.152513) (xy 386.827046 -402.195169) (xy 386.840092 -402.240109)
			(xy 386.846678 -402.28644) (xy 386.84708 -402.309838) (xy 386.84657 -402.335825) (xy 386.83844 -402.38716)
			(xy 386.822379 -402.43659) (xy 386.798783 -402.4829) (xy 386.768233 -402.524948) (xy 386.731482 -402.561699)
			(xy 386.689434 -402.592249) (xy 386.643124 -402.615845) (xy 386.593694 -402.631906) (xy 386.542359 -402.640036)
			(xy 386.490385 -402.640036) (xy 386.43905 -402.631906) (xy 386.38962 -402.615845) (xy 386.34331 -402.592249)
			(xy 386.301262 -402.561699) (xy 386.264511 -402.524948) (xy 386.233961 -402.4829) (xy 386.210365 -402.43659)
			(xy 386.194304 -402.38716) (xy 386.186174 -402.335825) (xy 386.185664 -402.309838) (xy 386.186085 -402.286441)
			(xy 386.192672 -402.240114) (xy 386.205719 -402.195177) (xy 386.224966 -402.152526) (xy 386.25003 -402.113012)
			(xy 386.264912 -402.094954) (xy 386.271516 -402.087334) (xy 386.277612 -402.069046) (xy 386.272278 -401.978876)
			(xy 386.26415 -401.96135) (xy 386.256784 -401.954492) (xy 386.237887 -401.936389) (xy 386.20477 -401.895867)
			(xy 386.177502 -401.851201) (xy 386.156592 -401.803228) (xy 386.142433 -401.752847) (xy 386.135291 -401.701004)
			(xy 386.134864 -401.674838) (xy 385.697984 -401.674838) (xy 385.697464 -401.703743) (xy 385.688758 -401.760895)
			(xy 385.671534 -401.81608) (xy 385.646188 -401.868038) (xy 385.613298 -401.91558) (xy 385.593844 -401.936966)
			(xy 385.587748 -401.94357) (xy 385.580636 -401.959572) (xy 385.575048 -402.041868) (xy 385.579874 -402.058886)
			(xy 385.584954 -402.065998) (xy 385.599591 -402.087228) (xy 385.622844 -402.133249) (xy 385.63867 -402.182322)
			(xy 385.646685 -402.233257) (xy 385.647184 -402.259038) (xy 385.646674 -402.285025) (xy 385.638544 -402.33636)
			(xy 385.622483 -402.38579) (xy 385.598887 -402.4321) (xy 385.568337 -402.474148) (xy 385.531586 -402.510899)
			(xy 385.489538 -402.541449) (xy 385.443228 -402.565045) (xy 385.393798 -402.581106) (xy 385.342463 -402.589236)
			(xy 385.290489 -402.589236) (xy 385.239154 -402.581106) (xy 385.189724 -402.565045) (xy 385.143414 -402.541449)
			(xy 385.101366 -402.510899) (xy 385.064615 -402.474148) (xy 385.034065 -402.4321) (xy 385.010469 -402.38579)
			(xy 384.994408 -402.33636) (xy 384.986278 -402.285025) (xy 384.985768 -402.259038) (xy 384.986247 -402.233255)
			(xy 384.994253 -402.182314) (xy 385.010078 -402.133236) (xy 385.033337 -402.087213) (xy 385.047998 -402.065998)
			(xy 385.053078 -402.058886) (xy 385.057904 -402.041868) (xy 385.052316 -401.959572) (xy 385.045204 -401.94357)
			(xy 385.039108 -401.936966) (xy 385.019626 -401.915602) (xy 384.986718 -401.868065) (xy 384.961366 -401.816103)
			(xy 384.944154 -401.760908) (xy 384.935476 -401.703747) (xy 384.934968 -401.674838) (xy 384.498088 -401.674838)
			(xy 384.497619 -401.701001) (xy 384.490469 -401.752836) (xy 384.476308 -401.803209) (xy 384.455402 -401.851177)
			(xy 384.428142 -401.895841) (xy 384.395038 -401.936365) (xy 384.376168 -401.954492) (xy 384.368802 -401.96135)
			(xy 384.360674 -401.978876) (xy 384.35534 -402.069046) (xy 384.361436 -402.087334) (xy 384.36804 -402.094954)
			(xy 384.382946 -402.112993) (xy 384.408008 -402.152513) (xy 384.427254 -402.195168) (xy 384.4403 -402.240109)
			(xy 384.446886 -402.28644) (xy 384.447288 -402.309838) (xy 384.446778 -402.335825) (xy 384.438648 -402.38716)
			(xy 384.422587 -402.43659) (xy 384.398991 -402.4829) (xy 384.368441 -402.524948) (xy 384.33169 -402.561699)
			(xy 384.289642 -402.592249) (xy 384.243332 -402.615845) (xy 384.193902 -402.631906) (xy 384.142567 -402.640036)
			(xy 384.090593 -402.640036) (xy 384.039258 -402.631906) (xy 383.989828 -402.615845) (xy 383.943518 -402.592249)
			(xy 383.90147 -402.561699) (xy 383.864719 -402.524948) (xy 383.834169 -402.4829) (xy 383.810573 -402.43659)
			(xy 383.794512 -402.38716) (xy 383.786382 -402.335825) (xy 383.785872 -402.309838) (xy 383.786292 -402.286441)
			(xy 383.792878 -402.240114) (xy 383.805925 -402.195177) (xy 383.825173 -402.152526) (xy 383.850237 -402.113011)
			(xy 383.86512 -402.094954) (xy 383.871724 -402.087334) (xy 383.87782 -402.069046) (xy 383.872486 -401.978876)
			(xy 383.864358 -401.96135) (xy 383.856992 -401.954492) (xy 383.838096 -401.936387) (xy 383.804979 -401.895866)
			(xy 383.77771 -401.8512) (xy 383.7568 -401.803227) (xy 383.742641 -401.752847) (xy 383.735499 -401.701004)
			(xy 383.735072 -401.674838) (xy 383.298192 -401.674838) (xy 383.297722 -401.701001) (xy 383.290572 -401.752836)
			(xy 383.276411 -401.803209) (xy 383.255505 -401.851177) (xy 383.228245 -401.895841) (xy 383.195142 -401.936365)
			(xy 383.176272 -401.954492) (xy 383.168906 -401.96135) (xy 383.160778 -401.978876) (xy 383.155444 -402.069046)
			(xy 383.16154 -402.087334) (xy 383.168144 -402.094954) (xy 383.183051 -402.112993) (xy 383.208113 -402.152513)
			(xy 383.227358 -402.195168) (xy 383.240404 -402.240109) (xy 383.24699 -402.28644) (xy 383.247392 -402.309838)
			(xy 383.246882 -402.335825) (xy 383.238752 -402.38716) (xy 383.222691 -402.43659) (xy 383.199095 -402.4829)
			(xy 383.168545 -402.524948) (xy 383.131794 -402.561699) (xy 383.089746 -402.592249) (xy 383.043436 -402.615845)
			(xy 382.994006 -402.631906) (xy 382.942671 -402.640036) (xy 382.890697 -402.640036) (xy 382.839362 -402.631906)
			(xy 382.789932 -402.615845) (xy 382.743622 -402.592249) (xy 382.701574 -402.561699) (xy 382.664823 -402.524948)
			(xy 382.634273 -402.4829) (xy 382.610677 -402.43659) (xy 382.594616 -402.38716) (xy 382.586486 -402.335825)
			(xy 382.585976 -402.309838) (xy 382.586395 -402.286441) (xy 382.592981 -402.240114) (xy 382.606029 -402.195177)
			(xy 382.625277 -402.152526) (xy 382.650341 -402.113011) (xy 382.665224 -402.094954) (xy 382.671828 -402.087334)
			(xy 382.677924 -402.069046) (xy 382.67259 -401.978876) (xy 382.664462 -401.96135) (xy 382.657096 -401.954492)
			(xy 382.638201 -401.936387) (xy 382.605084 -401.895866) (xy 382.577815 -401.8512) (xy 382.556904 -401.803227)
			(xy 382.542745 -401.752847) (xy 382.535603 -401.701004) (xy 382.535176 -401.674838) (xy 382.098296 -401.674838)
			(xy 382.097882 -401.701013) (xy 382.090684 -401.752866) (xy 382.076471 -401.803249) (xy 382.055507 -401.851218)
			(xy 382.028187 -401.895874) (xy 381.995022 -401.936379) (xy 381.976122 -401.954492) (xy 381.968756 -401.96135)
			(xy 381.960628 -401.978876) (xy 381.955294 -402.069046) (xy 381.96139 -402.087334) (xy 381.967994 -402.094954)
			(xy 381.982893 -402.112999) (xy 382.007958 -402.152516) (xy 382.027206 -402.19517) (xy 382.040253 -402.24011)
			(xy 382.04684 -402.28644) (xy 382.047242 -402.309838) (xy 382.046732 -402.335825) (xy 382.038602 -402.38716)
			(xy 382.022541 -402.43659) (xy 381.998945 -402.4829) (xy 381.968395 -402.524948) (xy 381.931644 -402.561699)
			(xy 381.889596 -402.592249) (xy 381.843286 -402.615845) (xy 381.793856 -402.631906) (xy 381.742521 -402.640036)
			(xy 381.690547 -402.640036) (xy 381.639212 -402.631906) (xy 381.589782 -402.615845) (xy 381.543472 -402.592249)
			(xy 381.501424 -402.561699) (xy 381.464673 -402.524948) (xy 381.434123 -402.4829) (xy 381.410527 -402.43659)
			(xy 381.394466 -402.38716) (xy 381.386336 -402.335825) (xy 381.385826 -402.309838) (xy 381.386256 -402.286442)
			(xy 381.392842 -402.240116) (xy 381.405887 -402.195179) (xy 381.425132 -402.152528) (xy 381.450193 -402.113012)
			(xy 381.465074 -402.094954) (xy 381.471678 -402.087334) (xy 381.477774 -402.069046) (xy 381.47244 -401.978876)
			(xy 381.464312 -401.96135) (xy 381.456946 -401.954492) (xy 381.438039 -401.936386) (xy 381.404879 -401.89588)
			(xy 381.377565 -401.851222) (xy 381.356609 -401.80325) (xy 381.342405 -401.752865) (xy 381.33522 -401.701012)
			(xy 381.334772 -401.674838) (xy 380.8984 -401.674838) (xy 380.897985 -401.701013) (xy 380.890787 -401.752865)
			(xy 380.876574 -401.803249) (xy 380.85561 -401.851218) (xy 380.82829 -401.895874) (xy 380.795126 -401.936379)
			(xy 380.776226 -401.954492) (xy 380.76886 -401.96135) (xy 380.760732 -401.978876) (xy 380.755398 -402.069046)
			(xy 380.761494 -402.087334) (xy 380.768098 -402.094954) (xy 380.782998 -402.112999) (xy 380.808062 -402.152516)
			(xy 380.82731 -402.19517) (xy 380.840357 -402.24011) (xy 380.846944 -402.28644) (xy 380.847346 -402.309838)
			(xy 380.846836 -402.335825) (xy 380.838706 -402.38716) (xy 380.822645 -402.43659) (xy 380.799049 -402.4829)
			(xy 380.768499 -402.524948) (xy 380.731748 -402.561699) (xy 380.6897 -402.592249) (xy 380.64339 -402.615845)
			(xy 380.59396 -402.631906) (xy 380.542625 -402.640036) (xy 380.490651 -402.640036) (xy 380.439316 -402.631906)
			(xy 380.389886 -402.615845) (xy 380.343576 -402.592249) (xy 380.301528 -402.561699) (xy 380.264777 -402.524948)
			(xy 380.234227 -402.4829) (xy 380.210631 -402.43659) (xy 380.19457 -402.38716) (xy 380.18644 -402.335825)
			(xy 380.18593 -402.309838) (xy 380.18636 -402.286442) (xy 380.192945 -402.240115) (xy 380.205991 -402.195179)
			(xy 380.225236 -402.152527) (xy 380.250297 -402.113012) (xy 380.265178 -402.094954) (xy 380.271782 -402.087334)
			(xy 380.277878 -402.069046) (xy 380.272544 -401.978876) (xy 380.264416 -401.96135) (xy 380.25705 -401.954492)
			(xy 380.238144 -401.936385) (xy 380.204984 -401.895879) (xy 380.177669 -401.851221) (xy 380.156713 -401.80325)
			(xy 380.142509 -401.752865) (xy 380.135324 -401.701012) (xy 380.134876 -401.674838) (xy 379.697996 -401.674838)
			(xy 379.697454 -401.704988) (xy 379.687996 -401.76454) (xy 379.669291 -401.821865) (xy 379.641803 -401.875534)
			(xy 379.606217 -401.924213) (xy 379.58522 -401.945856) (xy 379.578616 -401.95246) (xy 379.570996 -401.969224)
			(xy 379.565662 -402.05533) (xy 379.570996 -402.07311) (xy 379.576838 -402.080476) (xy 379.593342 -402.102467)
			(xy 379.619618 -402.150759) (xy 379.63755 -402.202729) (xy 379.646647 -402.256949) (xy 379.647196 -402.284438)
			(xy 379.646686 -402.310425) (xy 379.638556 -402.36176) (xy 379.622495 -402.41119) (xy 379.598899 -402.4575)
			(xy 379.568349 -402.499548) (xy 379.531598 -402.536299) (xy 379.48955 -402.566849) (xy 379.44324 -402.590445)
			(xy 379.39381 -402.606506) (xy 379.342475 -402.614636) (xy 379.290501 -402.614636) (xy 379.239166 -402.606506)
			(xy 379.189736 -402.590445) (xy 379.143426 -402.566849) (xy 379.101378 -402.536299) (xy 379.064627 -402.499548)
			(xy 379.034077 -402.4575) (xy 379.010481 -402.41119) (xy 378.99442 -402.36176) (xy 378.98629 -402.310425)
			(xy 378.98578 -402.284438) (xy 378.986337 -402.256948) (xy 378.995412 -402.202722) (xy 379.013336 -402.150746)
			(xy 379.039614 -402.102452) (xy 379.056138 -402.080476) (xy 379.06198 -402.07311) (xy 379.067314 -402.05533)
			(xy 379.06198 -401.969224) (xy 379.05436 -401.95246) (xy 379.047756 -401.945856) (xy 379.026771 -401.924201)
			(xy 378.991175 -401.875531) (xy 378.963683 -401.821865) (xy 378.944979 -401.764541) (xy 378.935531 -401.704987)
			(xy 378.93498 -401.674838) (xy 378.4981 -401.674838) (xy 378.497576 -401.703743) (xy 378.48887 -401.760894)
			(xy 378.471647 -401.816079) (xy 378.446302 -401.868037) (xy 378.413413 -401.91558) (xy 378.39396 -401.936966)
			(xy 378.387864 -401.94357) (xy 378.380752 -401.959572) (xy 378.375164 -402.041868) (xy 378.37999 -402.058886)
			(xy 378.38507 -402.065998) (xy 378.399709 -402.087226) (xy 378.422961 -402.133248) (xy 378.438786 -402.182322)
			(xy 378.446801 -402.233257) (xy 378.4473 -402.259038) (xy 378.44679 -402.285025) (xy 378.43866 -402.33636)
			(xy 378.422599 -402.38579) (xy 378.399003 -402.4321) (xy 378.368453 -402.474148) (xy 378.331702 -402.510899)
			(xy 378.289654 -402.541449) (xy 378.243344 -402.565045) (xy 378.193914 -402.581106) (xy 378.142579 -402.589236)
			(xy 378.090605 -402.589236) (xy 378.03927 -402.581106) (xy 377.98984 -402.565045) (xy 377.94353 -402.541449)
			(xy 377.901482 -402.510899) (xy 377.864731 -402.474148) (xy 377.834181 -402.4321) (xy 377.810585 -402.38579)
			(xy 377.794524 -402.33636) (xy 377.786394 -402.285025) (xy 377.785884 -402.259038) (xy 377.78636 -402.233255)
			(xy 377.794367 -402.182313) (xy 377.810192 -402.133235) (xy 377.833452 -402.087212) (xy 377.848114 -402.065998)
			(xy 377.853194 -402.058886) (xy 377.85802 -402.041868) (xy 377.852432 -401.959572) (xy 377.84532 -401.94357)
			(xy 377.839224 -401.936966) (xy 377.819745 -401.9156) (xy 377.786835 -401.868064) (xy 377.761483 -401.816102)
			(xy 377.74427 -401.760908) (xy 377.735592 -401.703747) (xy 377.735084 -401.674838) (xy 377.298204 -401.674838)
			(xy 377.297788 -401.701013) (xy 377.29059 -401.752865) (xy 377.276377 -401.803248) (xy 377.255414 -401.851218)
			(xy 377.228094 -401.895874) (xy 377.19493 -401.936379) (xy 377.17603 -401.954492) (xy 377.168664 -401.96135)
			(xy 377.160536 -401.978876) (xy 377.155202 -402.069046) (xy 377.161298 -402.087334) (xy 377.167902 -402.094954)
			(xy 377.182802 -402.112998) (xy 377.207867 -402.152516) (xy 377.227114 -402.19517) (xy 377.240161 -402.24011)
			(xy 377.246748 -402.28644) (xy 377.24715 -402.309838) (xy 377.24664 -402.335825) (xy 377.23851 -402.38716)
			(xy 377.222449 -402.43659) (xy 377.198853 -402.4829) (xy 377.168303 -402.524948) (xy 377.131552 -402.561699)
			(xy 377.089504 -402.592249) (xy 377.043194 -402.615845) (xy 376.993764 -402.631906) (xy 376.942429 -402.640036)
			(xy 376.890455 -402.640036) (xy 376.83912 -402.631906) (xy 376.78969 -402.615845) (xy 376.74338 -402.592249)
			(xy 376.701332 -402.561699) (xy 376.664581 -402.524948) (xy 376.634031 -402.4829) (xy 376.610435 -402.43659)
			(xy 376.594374 -402.38716) (xy 376.586244 -402.335825) (xy 376.585734 -402.309838) (xy 376.586163 -402.286442)
			(xy 376.592748 -402.240115) (xy 376.605794 -402.195178) (xy 376.62504 -402.152527) (xy 376.650101 -402.113012)
			(xy 376.664982 -402.094954) (xy 376.671586 -402.087334) (xy 376.677682 -402.069046) (xy 376.672348 -401.978876)
			(xy 376.66422 -401.96135) (xy 376.656854 -401.954492) (xy 376.637949 -401.936385) (xy 376.604788 -401.895879)
			(xy 376.577473 -401.851221) (xy 376.556518 -401.80325) (xy 376.542313 -401.752865) (xy 376.535128 -401.701012)
			(xy 376.53468 -401.674838) (xy 376.098308 -401.674838) (xy 376.09789 -401.701012) (xy 376.090693 -401.752865)
			(xy 376.07648 -401.803248) (xy 376.055517 -401.851217) (xy 376.028197 -401.895873) (xy 375.995034 -401.936378)
			(xy 375.976134 -401.954492) (xy 375.968768 -401.96135) (xy 375.96064 -401.978876) (xy 375.955306 -402.069046)
			(xy 375.961402 -402.087334) (xy 375.968006 -402.094954) (xy 375.982907 -402.112998) (xy 376.007971 -402.152515)
			(xy 376.027218 -402.19517) (xy 376.040266 -402.24011) (xy 376.046852 -402.28644) (xy 376.047254 -402.309838)
			(xy 376.046744 -402.335825) (xy 376.038614 -402.38716) (xy 376.022553 -402.43659) (xy 375.998957 -402.4829)
			(xy 375.968407 -402.524948) (xy 375.931656 -402.561699) (xy 375.889608 -402.592249) (xy 375.843298 -402.615845)
			(xy 375.793868 -402.631906) (xy 375.742533 -402.640036) (xy 375.690559 -402.640036) (xy 375.639224 -402.631906)
			(xy 375.589794 -402.615845) (xy 375.543484 -402.592249) (xy 375.501436 -402.561699) (xy 375.464685 -402.524948)
			(xy 375.434135 -402.4829) (xy 375.410539 -402.43659) (xy 375.394478 -402.38716) (xy 375.386348 -402.335825)
			(xy 375.385838 -402.309838) (xy 375.386266 -402.286442) (xy 375.392852 -402.240115) (xy 375.405897 -402.195178)
			(xy 375.425143 -402.152527) (xy 375.450205 -402.113012) (xy 375.465086 -402.094954) (xy 375.47169 -402.087334)
			(xy 375.477786 -402.069046) (xy 375.472452 -401.978876) (xy 375.464324 -401.96135) (xy 375.456958 -401.954492)
			(xy 375.438054 -401.936384) (xy 375.404893 -401.895878) (xy 375.377578 -401.851221) (xy 375.356622 -401.80325)
			(xy 375.342418 -401.752865) (xy 375.335232 -401.701012) (xy 375.334784 -401.674838) (xy 374.897904 -401.674838)
			(xy 374.897379 -401.703743) (xy 374.888673 -401.760894) (xy 374.87145 -401.816079) (xy 374.846105 -401.868037)
			(xy 374.813217 -401.91558) (xy 374.793764 -401.936966) (xy 374.787668 -401.94357) (xy 374.780556 -401.959572)
			(xy 374.774968 -402.041868) (xy 374.779794 -402.058886) (xy 374.784874 -402.065998) (xy 374.799513 -402.087226)
			(xy 374.822765 -402.133248) (xy 374.83859 -402.182321) (xy 374.846605 -402.233257) (xy 374.847104 -402.259038)
			(xy 374.846594 -402.285025) (xy 374.838464 -402.33636) (xy 374.822403 -402.38579) (xy 374.798807 -402.4321)
			(xy 374.768257 -402.474148) (xy 374.731506 -402.510899) (xy 374.689458 -402.541449) (xy 374.643148 -402.565045)
			(xy 374.593718 -402.581106) (xy 374.542383 -402.589236) (xy 374.490409 -402.589236) (xy 374.439074 -402.581106)
			(xy 374.389644 -402.565045) (xy 374.343334 -402.541449) (xy 374.301286 -402.510899) (xy 374.264535 -402.474148)
			(xy 374.233985 -402.4321) (xy 374.210389 -402.38579) (xy 374.194328 -402.33636) (xy 374.186198 -402.285025)
			(xy 374.185688 -402.259038) (xy 374.186163 -402.233255) (xy 374.19417 -402.182313) (xy 374.209996 -402.133235)
			(xy 374.233256 -402.087212) (xy 374.247918 -402.065998) (xy 374.252998 -402.058886) (xy 374.257824 -402.041868)
			(xy 374.252236 -401.959572) (xy 374.245124 -401.94357) (xy 374.239028 -401.936966) (xy 374.21955 -401.915599)
			(xy 374.18664 -401.868063) (xy 374.161287 -401.816102) (xy 374.144074 -401.760908) (xy 374.135396 -401.703747)
			(xy 374.134888 -401.674838) (xy 373.698008 -401.674838) (xy 373.697533 -401.701001) (xy 373.690383 -401.752835)
			(xy 373.676223 -401.803208) (xy 373.655318 -401.851176) (xy 373.628059 -401.89584) (xy 373.594958 -401.936364)
			(xy 373.576088 -401.954492) (xy 373.568722 -401.96135) (xy 373.560594 -401.978876) (xy 373.55526 -402.069046)
			(xy 373.561356 -402.087334) (xy 373.56796 -402.094954) (xy 373.582854 -402.113003) (xy 373.607921 -402.152519)
			(xy 373.62717 -402.195172) (xy 373.640219 -402.240111) (xy 373.646806 -402.28644) (xy 373.647208 -402.309838)
			(xy 373.646698 -402.335825) (xy 373.638568 -402.38716) (xy 373.622507 -402.43659) (xy 373.598911 -402.4829)
			(xy 373.568361 -402.524948) (xy 373.53161 -402.561699) (xy 373.489562 -402.592249) (xy 373.443252 -402.615845)
			(xy 373.393822 -402.631906) (xy 373.342487 -402.640036) (xy 373.290513 -402.640036) (xy 373.239178 -402.631906)
			(xy 373.189748 -402.615845) (xy 373.143438 -402.592249) (xy 373.10139 -402.561699) (xy 373.064639 -402.524948)
			(xy 373.034089 -402.4829) (xy 373.010493 -402.43659) (xy 372.994432 -402.38716) (xy 372.986302 -402.335825)
			(xy 372.985792 -402.309838) (xy 372.986231 -402.286442) (xy 372.992815 -402.240117) (xy 373.005859 -402.19518)
			(xy 373.025102 -402.152529) (xy 373.050161 -402.113013) (xy 373.06504 -402.094954) (xy 373.071644 -402.087334)
			(xy 373.07774 -402.069046) (xy 373.072406 -401.978876) (xy 373.064278 -401.96135) (xy 373.056912 -401.954492)
			(xy 373.03802 -401.936384) (xy 373.004902 -401.895864) (xy 372.977632 -401.851199) (xy 372.956721 -401.803226)
			(xy 372.942561 -401.752846) (xy 372.935419 -401.701004) (xy 372.934992 -401.674838) (xy 372.498112 -401.674838)
			(xy 372.497511 -401.704996) (xy 372.488016 -401.764561) (xy 372.469269 -401.821891) (xy 372.441736 -401.875557)
			(xy 372.406103 -401.924223) (xy 372.385082 -401.945856) (xy 372.378478 -401.95246) (xy 372.370858 -401.969224)
			(xy 372.365524 -402.05533) (xy 372.370858 -402.07311) (xy 372.3767 -402.080476) (xy 372.393212 -402.10246)
			(xy 372.419484 -402.150755) (xy 372.437415 -402.202728) (xy 372.44651 -402.256949) (xy 372.447058 -402.284438)
			(xy 372.446548 -402.310425) (xy 372.438418 -402.36176) (xy 372.422357 -402.41119) (xy 372.398761 -402.4575)
			(xy 372.368211 -402.499548) (xy 372.33146 -402.536299) (xy 372.289412 -402.566849) (xy 372.243102 -402.590445)
			(xy 372.193672 -402.606506) (xy 372.142337 -402.614636) (xy 372.090363 -402.614636) (xy 372.039028 -402.606506)
			(xy 371.989598 -402.590445) (xy 371.943288 -402.566849) (xy 371.90124 -402.536299) (xy 371.864489 -402.499548)
			(xy 371.833939 -402.4575) (xy 371.810343 -402.41119) (xy 371.794282 -402.36176) (xy 371.786152 -402.310425)
			(xy 371.785642 -402.284438) (xy 371.786207 -402.256948) (xy 371.795281 -402.202723) (xy 371.813203 -402.150747)
			(xy 371.839478 -402.102453) (xy 371.856 -402.080476) (xy 371.861842 -402.07311) (xy 371.867176 -402.05533)
			(xy 371.861842 -401.969224) (xy 371.854222 -401.95246) (xy 371.847618 -401.945856) (xy 371.826582 -401.924234)
			(xy 371.790934 -401.875572) (xy 371.763392 -401.821905) (xy 371.744644 -401.76457) (xy 371.735156 -401.704999)
			(xy 371.734588 -401.674838) (xy 371.298216 -401.674838) (xy 371.297614 -401.704996) (xy 371.288119 -401.764561)
			(xy 371.269372 -401.82189) (xy 371.241839 -401.875556) (xy 371.206207 -401.924223) (xy 371.185186 -401.945856)
			(xy 371.178582 -401.95246) (xy 371.170962 -401.969224) (xy 371.165628 -402.05533) (xy 371.170962 -402.07311)
			(xy 371.176804 -402.080476) (xy 371.193317 -402.10246) (xy 371.219589 -402.150755) (xy 371.237519 -402.202728)
			(xy 371.246614 -402.256949) (xy 371.247162 -402.284438) (xy 371.246652 -402.310425) (xy 371.238522 -402.36176)
			(xy 371.222461 -402.41119) (xy 371.198865 -402.4575) (xy 371.168315 -402.499548) (xy 371.131564 -402.536299)
			(xy 371.089516 -402.566849) (xy 371.043206 -402.590445) (xy 370.993776 -402.606506) (xy 370.942441 -402.614636)
			(xy 370.890467 -402.614636) (xy 370.839132 -402.606506) (xy 370.789702 -402.590445) (xy 370.743392 -402.566849)
			(xy 370.701344 -402.536299) (xy 370.664593 -402.499548) (xy 370.634043 -402.4575) (xy 370.610447 -402.41119)
			(xy 370.594386 -402.36176) (xy 370.586256 -402.310425) (xy 370.585746 -402.284438) (xy 370.58631 -402.256948)
			(xy 370.595385 -402.202723) (xy 370.613306 -402.150747) (xy 370.639582 -402.102453) (xy 370.656104 -402.080476)
			(xy 370.661946 -402.07311) (xy 370.66728 -402.05533) (xy 370.661946 -401.969224) (xy 370.654326 -401.95246)
			(xy 370.647722 -401.945856) (xy 370.626669 -401.92425) (xy 370.591027 -401.875582) (xy 370.56349 -401.82191)
			(xy 370.544745 -401.764573) (xy 370.535259 -401.705) (xy 370.534692 -401.674838) (xy 366.950774 -401.674838)
			(xy 366.96098 -401.694298) (xy 366.982746 -401.751698) (xy 366.997451 -401.811299) (xy 367.004879 -401.872236)
			(xy 367.005362 -401.90293) (xy 367.00499 -401.933665) (xy 366.997577 -401.994685) (xy 366.982863 -402.054367)
			(xy 366.961062 -402.11184) (xy 366.932492 -402.166266) (xy 366.89757 -402.216852) (xy 366.856805 -402.262859)
			(xy 366.810792 -402.303617) (xy 366.760201 -402.338532) (xy 366.705771 -402.367093) (xy 366.648294 -402.388886)
			(xy 366.58861 -402.403591) (xy 366.527589 -402.410995) (xy 366.496854 -402.411438) (xy 366.466158 -402.410962)
			(xy 366.405213 -402.40356) (xy 366.345605 -402.388868) (xy 366.288201 -402.3671) (xy 366.233838 -402.338575)
			(xy 366.20831 -402.321522) (xy 366.199558 -402.316051) (xy 366.179354 -402.311923) (xy 366.15915 -402.316051)
			(xy 366.150398 -402.321522) (xy 366.124853 -402.338547) (xy 366.070488 -402.36706) (xy 366.013088 -402.388826)
			(xy 365.953486 -402.403529) (xy 365.892548 -402.410956) (xy 365.861854 -402.411438) (xy 365.831158 -402.410962)
			(xy 365.770213 -402.40356) (xy 365.710605 -402.388868) (xy 365.653201 -402.3671) (xy 365.598838 -402.338575)
			(xy 365.57331 -402.321522) (xy 365.564558 -402.316051) (xy 365.544354 -402.311923) (xy 365.52415 -402.316051)
			(xy 365.515398 -402.321522) (xy 365.489853 -402.338547) (xy 365.435488 -402.36706) (xy 365.378088 -402.388826)
			(xy 365.318486 -402.403529) (xy 365.257548 -402.410956) (xy 365.226854 -402.411438) (xy 365.196158 -402.410962)
			(xy 365.135213 -402.40356) (xy 365.075605 -402.388868) (xy 365.018201 -402.3671) (xy 364.963838 -402.338575)
			(xy 364.93831 -402.321522) (xy 364.929558 -402.316051) (xy 364.909354 -402.311923) (xy 364.88915 -402.316051)
			(xy 364.880398 -402.321522) (xy 364.865158 -402.331682) (xy 364.856008 -402.338276) (xy 364.844054 -402.357368)
			(xy 364.841353 -402.379732) (xy 364.84433 -402.39061) (xy 364.852471 -402.41645) (xy 364.863897 -402.469411)
			(xy 364.869633 -402.523286) (xy 364.869984 -402.550376) (xy 364.86954 -402.581109) (xy 364.862133 -402.642126)
			(xy 364.847426 -402.701805) (xy 364.83521 -402.734018) (xy 369.305076 -402.734018) (xy 369.309147 -402.678396)
			(xy 369.321273 -402.623959) (xy 369.341196 -402.571868) (xy 369.368492 -402.523233) (xy 369.402578 -402.47909)
			(xy 369.442727 -402.440381) (xy 369.488085 -402.40793) (xy 369.537685 -402.382429) (xy 369.590469 -402.364422)
			(xy 369.645312 -402.354292) (xy 369.701046 -402.352255) (xy 369.756483 -402.358355) (xy 369.81044 -402.372461)
			(xy 369.861769 -402.394273) (xy 369.909375 -402.423327) (xy 369.952243 -402.459002) (xy 369.98946 -402.500539)
			(xy 370.020233 -402.547052) (xy 370.043905 -402.597549) (xy 370.059973 -402.650956) (xy 370.068093 -402.706132)
			(xy 370.068602 -402.734018) (xy 370.068093 -402.761904) (xy 370.059973 -402.81708) (xy 370.043905 -402.870487)
			(xy 370.020233 -402.920984) (xy 369.98946 -402.967497) (xy 369.952243 -403.009034) (xy 369.909375 -403.044709)
			(xy 369.861769 -403.073763) (xy 369.81044 -403.095575) (xy 369.756483 -403.109681) (xy 369.701046 -403.115781)
			(xy 369.645312 -403.113744) (xy 369.590469 -403.103614) (xy 369.537685 -403.085607) (xy 369.488085 -403.060106)
			(xy 369.442727 -403.027655) (xy 369.402578 -402.988946) (xy 369.368492 -402.944803) (xy 369.341196 -402.896168)
			(xy 369.321273 -402.844077) (xy 369.309147 -402.78964) (xy 369.305076 -402.734018) (xy 364.83521 -402.734018)
			(xy 364.825631 -402.759276) (xy 364.797068 -402.813702) (xy 364.762153 -402.864287) (xy 364.721394 -402.910294)
			(xy 364.675387 -402.951053) (xy 364.624802 -402.985968) (xy 364.570376 -403.014531) (xy 364.512905 -403.036326)
			(xy 364.453226 -403.051033) (xy 364.392209 -403.05844) (xy 364.361476 -403.058884) (xy 364.327889 -403.058373)
			(xy 364.261301 -403.049526) (xy 364.196458 -403.031989) (xy 364.134487 -403.006066) (xy 364.07647 -402.972211)
			(xy 364.023415 -402.931011) (xy 363.976246 -402.883185) (xy 363.955584 -402.8567) (xy 363.948632 -402.848368)
			(xy 363.929643 -402.837921) (xy 363.908036 -402.836223) (xy 363.897672 -402.839428) (xy 363.869935 -402.848993)
			(xy 363.812822 -402.862437) (xy 363.754543 -402.869222) (xy 363.725206 -402.869654) (xy 363.68536 -402.868922)
			(xy 363.606638 -402.856542) (xy 363.568488 -402.845016) (xy 363.558473 -402.84231) (xy 363.53784 -402.84426)
			(xy 363.519646 -402.854186) (xy 363.512862 -402.862034) (xy 363.49214 -402.887858) (xy 363.445112 -402.934464)
			(xy 363.392433 -402.974574) (xy 363.334995 -403.007508) (xy 363.273768 -403.03271) (xy 363.209789 -403.049753)
			(xy 363.144139 -403.05835) (xy 363.111034 -403.058884) (xy 363.080302 -403.05843) (xy 363.019285 -403.051025)
			(xy 362.959606 -403.036319) (xy 362.902134 -403.014525) (xy 362.847709 -402.985963) (xy 362.797124 -402.951048)
			(xy 362.751117 -402.91029) (xy 362.710358 -402.864284) (xy 362.675442 -402.813699) (xy 362.646879 -402.759275)
			(xy 362.625084 -402.701804) (xy 362.610377 -402.642125) (xy 362.60297 -402.581108) (xy 362.602526 -402.550376)
			(xy 362.603148 -402.513791) (xy 362.613603 -402.441371) (xy 362.623354 -402.406104) (xy 362.626127 -402.394907)
			(xy 362.622472 -402.372157) (xy 362.609269 -402.353273) (xy 362.599478 -402.347176) (xy 362.588923 -402.341202)
			(xy 362.568342 -402.328367) (xy 362.55833 -402.321522) (xy 362.549578 -402.316051) (xy 362.529374 -402.311923)
			(xy 362.50917 -402.316051) (xy 362.500418 -402.321522) (xy 362.474868 -402.338538) (xy 362.420504 -402.367052)
			(xy 362.363105 -402.38882) (xy 362.303504 -402.403526) (xy 362.242568 -402.410955) (xy 362.211874 -402.411438)
			(xy 362.181178 -402.410952) (xy 362.120234 -402.403552) (xy 362.060626 -402.388862) (xy 362.003221 -402.367097)
			(xy 361.948858 -402.338574) (xy 361.92333 -402.321522) (xy 361.914578 -402.316051) (xy 361.894374 -402.311923)
			(xy 361.87417 -402.316051) (xy 361.865418 -402.321522) (xy 361.839868 -402.338538) (xy 361.785504 -402.367052)
			(xy 361.728105 -402.38882) (xy 361.668504 -402.403526) (xy 361.607568 -402.410955) (xy 361.576874 -402.411438)
			(xy 361.546144 -402.410968) (xy 361.485131 -402.403558) (xy 361.425457 -402.388847) (xy 361.367991 -402.367051)
			(xy 361.31357 -402.338488) (xy 361.262989 -402.303574) (xy 361.216985 -402.262818) (xy 361.176229 -402.216814)
			(xy 361.141314 -402.166233) (xy 361.11275 -402.111813) (xy 361.090954 -402.054347) (xy 361.076243 -401.994673)
			(xy 361.068832 -401.93366) (xy 361.068366 -401.90293) (xy 360.369868 -401.90293) (xy 360.382943 -401.953855)
			(xy 360.390954 -402.017273) (xy 360.391456 -402.049234) (xy 360.390954 -402.081195) (xy 360.382943 -402.144613)
			(xy 360.367046 -402.206527) (xy 360.343514 -402.26596) (xy 360.31272 -402.321975) (xy 360.275147 -402.37369)
			(xy 360.23139 -402.420287) (xy 360.182137 -402.461032) (xy 360.128166 -402.495283) (xy 360.070327 -402.5225)
			(xy 360.009534 -402.542253) (xy 359.946744 -402.554231) (xy 359.882948 -402.558245) (xy 359.819152 -402.554231)
			(xy 359.756362 -402.542253) (xy 359.695569 -402.5225) (xy 359.63773 -402.495283) (xy 359.583759 -402.461032)
			(xy 359.534506 -402.420287) (xy 359.490749 -402.37369) (xy 359.453176 -402.321975) (xy 359.422382 -402.26596)
			(xy 359.39885 -402.206527) (xy 359.382953 -402.144613) (xy 359.374942 -402.081195) (xy 357.254978 -402.081195)
			(xy 357.224001 -402.09029) (xy 357.170049 -402.098047) (xy 357.142796 -402.09851) (xy 357.114467 -402.097974)
			(xy 357.058436 -402.089567) (xy 357.004263 -402.072967) (xy 356.953141 -402.04854) (xy 356.906192 -402.016823)
			(xy 356.864448 -401.978512) (xy 356.828829 -401.93445) (xy 356.800115 -401.885606) (xy 356.778939 -401.833054)
			(xy 356.765767 -401.777948) (xy 356.762812 -401.749768) (xy 356.761542 -401.737576) (xy 356.748588 -401.716748)
			(xy 356.657148 -401.661884) (xy 356.632764 -401.66036) (xy 356.621334 -401.665186) (xy 356.589544 -401.678198)
			(xy 356.52334 -401.69652) (xy 356.455274 -401.705767) (xy 356.420928 -401.706334) (xy 356.389384 -401.705862)
			(xy 356.326782 -401.698062) (xy 356.265624 -401.682578) (xy 356.206852 -401.659648) (xy 356.151367 -401.629624)
			(xy 356.100023 -401.592968) (xy 356.053606 -401.550242) (xy 356.012832 -401.502103) (xy 355.978325 -401.44929)
			(xy 355.950615 -401.392614) (xy 355.930129 -401.332946) (xy 355.917181 -401.271202) (xy 355.91197 -401.20833)
			(xy 354.725732 -401.20833) (xy 354.725732 -401.461986) (xy 354.726113 -401.470962) (xy 354.732349 -401.487799)
			(xy 354.743994 -401.501465) (xy 354.75164 -401.506182) (xy 354.841048 -401.55622) (xy 354.868734 -401.555712)
			(xy 354.880418 -401.548346) (xy 354.903092 -401.534925) (xy 354.95134 -401.513753) (xy 355.002038 -401.499405)
			(xy 355.054226 -401.492153) (xy 355.08057 -401.491704) (xy 355.107825 -401.492141) (xy 355.161781 -401.499895)
			(xy 355.214084 -401.515249) (xy 355.26367 -401.53789) (xy 355.309528 -401.567358) (xy 355.350726 -401.603053)
			(xy 355.386424 -401.644248) (xy 355.415896 -401.690104) (xy 355.438541 -401.739688) (xy 355.453899 -401.79199)
			(xy 355.461657 -401.845945) (xy 355.461657 -401.900455) (xy 355.453899 -401.95441) (xy 355.438541 -402.006712)
			(xy 355.415896 -402.056296) (xy 355.386424 -402.102152) (xy 355.350726 -402.143347) (xy 355.309528 -402.179042)
			(xy 355.26367 -402.20851) (xy 355.214084 -402.231151) (xy 355.161781 -402.246505) (xy 355.107825 -402.254259)
			(xy 355.08057 -402.25472) (xy 355.053615 -402.254247) (xy 355.000243 -402.246641) (xy 354.948473 -402.2316)
			(xy 354.899335 -402.209423) (xy 354.853807 -402.180551) (xy 354.812796 -402.145559) (xy 354.777117 -402.105143)
			(xy 354.747482 -402.060109) (xy 354.72448 -402.011352) (xy 354.71608 -401.985734) (xy 354.713246 -401.977654)
			(xy 354.703086 -401.963884) (xy 354.688951 -401.954238) (xy 354.680774 -401.951698) (xy 354.622354 -401.93595)
			(xy 354.612702 -401.945856) (xy 354.606098 -401.95246) (xy 354.598478 -401.969224) (xy 354.593144 -402.05533)
			(xy 354.598478 -402.07311) (xy 354.60432 -402.080476) (xy 354.620821 -402.102468) (xy 354.647098 -402.15076)
			(xy 354.665032 -402.20273) (xy 354.674129 -402.256949) (xy 354.674678 -402.284438) (xy 354.674168 -402.310425)
			(xy 354.666038 -402.36176) (xy 354.649977 -402.41119) (xy 354.626381 -402.4575) (xy 354.595831 -402.499548)
			(xy 354.55908 -402.536299) (xy 354.517032 -402.566849) (xy 354.470722 -402.590445) (xy 354.421292 -402.606506)
			(xy 354.369957 -402.614636) (xy 354.317983 -402.614636) (xy 354.266648 -402.606506) (xy 354.217218 -402.590445)
			(xy 354.170908 -402.566849) (xy 354.12886 -402.536299) (xy 354.092109 -402.499548) (xy 354.061559 -402.4575)
			(xy 354.037963 -402.41119) (xy 354.021902 -402.36176) (xy 354.013772 -402.310425) (xy 354.013262 -402.284438)
			(xy 354.013823 -402.256948) (xy 354.022898 -402.202723) (xy 354.04082 -402.150746) (xy 354.067097 -402.102453)
			(xy 354.08362 -402.080476) (xy 354.089462 -402.07311) (xy 354.094796 -402.05533) (xy 354.089462 -401.969224)
			(xy 354.081842 -401.95246) (xy 354.075238 -401.945856) (xy 354.054188 -401.924248) (xy 354.018545 -401.875581)
			(xy 353.991007 -401.82191) (xy 353.972261 -401.764573) (xy 353.962775 -401.705) (xy 353.962208 -401.674838)
			(xy 353.525836 -401.674838) (xy 353.525409 -401.701012) (xy 353.518213 -401.752864) (xy 353.504 -401.803247)
			(xy 353.483039 -401.851216) (xy 353.455722 -401.895872) (xy 353.422561 -401.936378) (xy 353.403662 -401.954492)
			(xy 353.396296 -401.96135) (xy 353.388168 -401.978876) (xy 353.382834 -402.069046) (xy 353.38893 -402.087334)
			(xy 353.395534 -402.094954) (xy 353.410439 -402.112994) (xy 353.435502 -402.152513) (xy 353.454748 -402.195169)
			(xy 353.467794 -402.240109) (xy 353.47438 -402.28644) (xy 353.474782 -402.309838) (xy 353.474272 -402.335825)
			(xy 353.466142 -402.38716) (xy 353.450081 -402.43659) (xy 353.426485 -402.4829) (xy 353.395935 -402.524948)
			(xy 353.359184 -402.561699) (xy 353.317136 -402.592249) (xy 353.270826 -402.615845) (xy 353.221396 -402.631906)
			(xy 353.170061 -402.640036) (xy 353.118087 -402.640036) (xy 353.066752 -402.631906) (xy 353.017322 -402.615845)
			(xy 352.971012 -402.592249) (xy 352.928964 -402.561699) (xy 352.892213 -402.524948) (xy 352.861663 -402.4829)
			(xy 352.838067 -402.43659) (xy 352.822006 -402.38716) (xy 352.813876 -402.335825) (xy 352.813366 -402.309838)
			(xy 352.813787 -402.286441) (xy 352.820374 -402.240114) (xy 352.833421 -402.195177) (xy 352.852668 -402.152526)
			(xy 352.877732 -402.113011) (xy 352.892614 -402.094954) (xy 352.899218 -402.087334) (xy 352.905314 -402.069046)
			(xy 352.89998 -401.978876) (xy 352.891852 -401.96135) (xy 352.884486 -401.954492) (xy 352.865587 -401.936378)
			(xy 352.832424 -401.895874) (xy 352.805108 -401.851218) (xy 352.784151 -401.803248) (xy 352.769946 -401.752864)
			(xy 352.76276 -401.701012) (xy 352.762312 -401.674838) (xy 352.325432 -401.674838) (xy 352.324981 -401.701002)
			(xy 352.31783 -401.752838) (xy 352.303667 -401.803213) (xy 352.282757 -401.851181) (xy 352.255493 -401.895844)
			(xy 352.222385 -401.936366) (xy 352.203512 -401.954492) (xy 352.196146 -401.96135) (xy 352.188018 -401.978876)
			(xy 352.182684 -402.069046) (xy 352.18878 -402.087334) (xy 352.195384 -402.094954) (xy 352.210282 -402.113)
			(xy 352.235347 -402.152517) (xy 352.254595 -402.195171) (xy 352.267643 -402.24011) (xy 352.27423 -402.28644)
			(xy 352.274632 -402.309838) (xy 352.274122 -402.335825) (xy 352.265992 -402.38716) (xy 352.249931 -402.43659)
			(xy 352.226335 -402.4829) (xy 352.195785 -402.524948) (xy 352.159034 -402.561699) (xy 352.116986 -402.592249)
			(xy 352.070676 -402.615845) (xy 352.021246 -402.631906) (xy 351.969911 -402.640036) (xy 351.917937 -402.640036)
			(xy 351.866602 -402.631906) (xy 351.817172 -402.615845) (xy 351.770862 -402.592249) (xy 351.728814 -402.561699)
			(xy 351.692063 -402.524948) (xy 351.661513 -402.4829) (xy 351.637917 -402.43659) (xy 351.621856 -402.38716)
			(xy 351.613726 -402.335825) (xy 351.613216 -402.309838) (xy 351.613649 -402.286442) (xy 351.620234 -402.240116)
			(xy 351.633279 -402.195179) (xy 351.652524 -402.152528) (xy 351.677584 -402.113012) (xy 351.692464 -402.094954)
			(xy 351.699068 -402.087334) (xy 351.705164 -402.069046) (xy 351.69983 -401.978876) (xy 351.691702 -401.96135)
			(xy 351.684336 -401.954492) (xy 351.665448 -401.936379) (xy 351.632329 -401.895861) (xy 351.605058 -401.851197)
			(xy 351.584146 -401.803225) (xy 351.569986 -401.752846) (xy 351.562843 -401.701004) (xy 351.562416 -401.674838)
			(xy 351.125536 -401.674838) (xy 351.125002 -401.703743) (xy 351.116297 -401.760893) (xy 351.099076 -401.816077)
			(xy 351.073733 -401.868035) (xy 351.040848 -401.915579) (xy 351.021396 -401.936966) (xy 351.0153 -401.94357)
			(xy 351.008188 -401.959572) (xy 351.0026 -402.041868) (xy 351.007426 -402.058886) (xy 351.012506 -402.065998)
			(xy 351.027149 -402.087223) (xy 351.050399 -402.133246) (xy 351.066223 -402.182321) (xy 351.074237 -402.233257)
			(xy 351.074736 -402.259038) (xy 351.074226 -402.285025) (xy 351.066096 -402.33636) (xy 351.050035 -402.38579)
			(xy 351.026439 -402.4321) (xy 350.995889 -402.474148) (xy 350.959138 -402.510899) (xy 350.91709 -402.541449)
			(xy 350.87078 -402.565045) (xy 350.82135 -402.581106) (xy 350.770015 -402.589236) (xy 350.718041 -402.589236)
			(xy 350.666706 -402.581106) (xy 350.617276 -402.565045) (xy 350.570966 -402.541449) (xy 350.528918 -402.510899)
			(xy 350.492167 -402.474148) (xy 350.461617 -402.4321) (xy 350.438021 -402.38579) (xy 350.42196 -402.33636)
			(xy 350.41383 -402.285025) (xy 350.41332 -402.259038) (xy 350.413789 -402.233254) (xy 350.421797 -402.182313)
			(xy 350.437624 -402.133234) (xy 350.460887 -402.087212) (xy 350.47555 -402.065998) (xy 350.48063 -402.058886)
			(xy 350.485456 -402.041868) (xy 350.479868 -401.959572) (xy 350.472756 -401.94357) (xy 350.46666 -401.936966)
			(xy 350.44717 -401.915609) (xy 350.414265 -401.868069) (xy 350.388916 -401.816106) (xy 350.371705 -401.760909)
			(xy 350.363028 -401.703747) (xy 350.36252 -401.674838) (xy 349.92564 -401.674838) (xy 349.925186 -401.701002)
			(xy 349.918035 -401.752838) (xy 349.903873 -401.803212) (xy 349.882964 -401.85118) (xy 349.8557 -401.895844)
			(xy 349.822593 -401.936366) (xy 349.80372 -401.954492) (xy 349.796354 -401.96135) (xy 349.788226 -401.978876)
			(xy 349.782892 -402.069046) (xy 349.788988 -402.087334) (xy 349.795592 -402.094954) (xy 349.810491 -402.112999)
			(xy 349.835556 -402.152516) (xy 349.854804 -402.19517) (xy 349.867851 -402.24011) (xy 349.874438 -402.28644)
			(xy 349.87484 -402.309838) (xy 349.87433 -402.335825) (xy 349.8662 -402.38716) (xy 349.850139 -402.43659)
			(xy 349.826543 -402.4829) (xy 349.795993 -402.524948) (xy 349.759242 -402.561699) (xy 349.717194 -402.592249)
			(xy 349.670884 -402.615845) (xy 349.621454 -402.631906) (xy 349.570119 -402.640036) (xy 349.518145 -402.640036)
			(xy 349.46681 -402.631906) (xy 349.41738 -402.615845) (xy 349.37107 -402.592249) (xy 349.329022 -402.561699)
			(xy 349.292271 -402.524948) (xy 349.261721 -402.4829) (xy 349.238125 -402.43659) (xy 349.222064 -402.38716)
			(xy 349.213934 -402.335825) (xy 349.213424 -402.309838) (xy 349.213855 -402.286442) (xy 349.220441 -402.240116)
			(xy 349.233486 -402.195179) (xy 349.252731 -402.152528) (xy 349.277791 -402.113012) (xy 349.292672 -402.094954)
			(xy 349.299276 -402.087334) (xy 349.305372 -402.069046) (xy 349.300038 -401.978876) (xy 349.29191 -401.96135)
			(xy 349.284544 -401.954492) (xy 349.265658 -401.936377) (xy 349.232538 -401.89586) (xy 349.205267 -401.851196)
			(xy 349.184354 -401.803225) (xy 349.170194 -401.752845) (xy 349.163051 -401.701004) (xy 349.162624 -401.674838)
			(xy 348.725744 -401.674838) (xy 348.725289 -401.701002) (xy 348.718138 -401.752838) (xy 348.703976 -401.803212)
			(xy 348.683067 -401.85118) (xy 348.655804 -401.895844) (xy 348.622696 -401.936366) (xy 348.603824 -401.954492)
			(xy 348.596458 -401.96135) (xy 348.58833 -401.978876) (xy 348.582996 -402.069046) (xy 348.589092 -402.087334)
			(xy 348.595696 -402.094954) (xy 348.610595 -402.112999) (xy 348.63566 -402.152516) (xy 348.654908 -402.19517)
			(xy 348.667955 -402.24011) (xy 348.674542 -402.28644) (xy 348.674944 -402.309838) (xy 348.674434 -402.335825)
			(xy 348.666304 -402.38716) (xy 348.650243 -402.43659) (xy 348.626647 -402.4829) (xy 348.596097 -402.524948)
			(xy 348.559346 -402.561699) (xy 348.517298 -402.592249) (xy 348.470988 -402.615845) (xy 348.421558 -402.631906)
			(xy 348.370223 -402.640036) (xy 348.318249 -402.640036) (xy 348.266914 -402.631906) (xy 348.217484 -402.615845)
			(xy 348.171174 -402.592249) (xy 348.129126 -402.561699) (xy 348.092375 -402.524948) (xy 348.061825 -402.4829)
			(xy 348.038229 -402.43659) (xy 348.022168 -402.38716) (xy 348.014038 -402.335825) (xy 348.013528 -402.309838)
			(xy 348.013958 -402.286442) (xy 348.020544 -402.240116) (xy 348.033589 -402.195179) (xy 348.052834 -402.152527)
			(xy 348.077895 -402.113012) (xy 348.092776 -402.094954) (xy 348.09938 -402.087334) (xy 348.105476 -402.069046)
			(xy 348.100142 -401.978876) (xy 348.092014 -401.96135) (xy 348.084648 -401.954492) (xy 348.065763 -401.936377)
			(xy 348.032643 -401.895859) (xy 348.005371 -401.851196) (xy 347.984459 -401.803224) (xy 347.970298 -401.752845)
			(xy 347.963155 -401.701004) (xy 347.962728 -401.674838) (xy 347.525848 -401.674838) (xy 347.525418 -401.701012)
			(xy 347.518221 -401.752863) (xy 347.504009 -401.803246) (xy 347.483049 -401.851215) (xy 347.455732 -401.895871)
			(xy 347.422572 -401.936377) (xy 347.403674 -401.954492) (xy 347.396308 -401.96135) (xy 347.38818 -401.978876)
			(xy 347.382846 -402.069046) (xy 347.388942 -402.087334) (xy 347.395546 -402.094954) (xy 347.410453 -402.112993)
			(xy 347.435515 -402.152512) (xy 347.45476 -402.195168) (xy 347.467806 -402.240109) (xy 347.474392 -402.28644)
			(xy 347.474794 -402.309838) (xy 347.474284 -402.335825) (xy 347.466154 -402.38716) (xy 347.450093 -402.43659)
			(xy 347.426497 -402.4829) (xy 347.395947 -402.524948) (xy 347.359196 -402.561699) (xy 347.317148 -402.592249)
			(xy 347.270838 -402.615845) (xy 347.221408 -402.631906) (xy 347.170073 -402.640036) (xy 347.118099 -402.640036)
			(xy 347.066764 -402.631906) (xy 347.017334 -402.615845) (xy 346.971024 -402.592249) (xy 346.928976 -402.561699)
			(xy 346.892225 -402.524948) (xy 346.861675 -402.4829) (xy 346.838079 -402.43659) (xy 346.822018 -402.38716)
			(xy 346.813888 -402.335825) (xy 346.813378 -402.309838) (xy 346.813796 -402.286441) (xy 346.820383 -402.240114)
			(xy 346.83343 -402.195177) (xy 346.852678 -402.152525) (xy 346.877743 -402.113011) (xy 346.892626 -402.094954)
			(xy 346.89923 -402.087334) (xy 346.905326 -402.069046) (xy 346.899992 -401.978876) (xy 346.891864 -401.96135)
			(xy 346.884498 -401.954492) (xy 346.865601 -401.936376) (xy 346.832438 -401.895873) (xy 346.805121 -401.851218)
			(xy 346.784164 -401.803248) (xy 346.769958 -401.752864) (xy 346.762772 -401.701012) (xy 346.762324 -401.674838)
			(xy 346.325952 -401.674838) (xy 346.32552 -401.701012) (xy 346.318324 -401.752863) (xy 346.304112 -401.803246)
			(xy 346.283152 -401.851215) (xy 346.255836 -401.895871) (xy 346.222676 -401.936377) (xy 346.203778 -401.954492)
			(xy 346.196412 -401.96135) (xy 346.188284 -401.978876) (xy 346.18295 -402.069046) (xy 346.189046 -402.087334)
			(xy 346.19565 -402.094954) (xy 346.210558 -402.112992) (xy 346.235619 -402.152512) (xy 346.254865 -402.195168)
			(xy 346.26791 -402.240109) (xy 346.274496 -402.28644) (xy 346.274898 -402.309838) (xy 346.274388 -402.335825)
			(xy 346.266258 -402.38716) (xy 346.250197 -402.43659) (xy 346.226601 -402.4829) (xy 346.196051 -402.524948)
			(xy 346.1593 -402.561699) (xy 346.117252 -402.592249) (xy 346.070942 -402.615845) (xy 346.021512 -402.631906)
			(xy 345.970177 -402.640036) (xy 345.918203 -402.640036) (xy 345.866868 -402.631906) (xy 345.817438 -402.615845)
			(xy 345.771128 -402.592249) (xy 345.72908 -402.561699) (xy 345.692329 -402.524948) (xy 345.661779 -402.4829)
			(xy 345.638183 -402.43659) (xy 345.622122 -402.38716) (xy 345.613992 -402.335825) (xy 345.613482 -402.309838)
			(xy 345.613923 -402.286442) (xy 345.620508 -402.240117) (xy 345.633551 -402.195181) (xy 345.652793 -402.152529)
			(xy 345.677851 -402.113013) (xy 345.69273 -402.094954) (xy 345.699334 -402.087334) (xy 345.70543 -402.069046)
			(xy 345.700096 -401.978876) (xy 345.691968 -401.96135) (xy 345.684602 -401.954492) (xy 345.665706 -401.936375)
			(xy 345.632543 -401.895872) (xy 345.605226 -401.851217) (xy 345.584268 -401.803248) (xy 345.570062 -401.752864)
			(xy 345.562876 -401.701012) (xy 345.562428 -401.674838) (xy 345.125548 -401.674838) (xy 345.124991 -401.704987)
			(xy 345.115535 -401.764538) (xy 345.096832 -401.821862) (xy 345.069348 -401.875532) (xy 345.033767 -401.924212)
			(xy 345.012772 -401.945856) (xy 345.006168 -401.95246) (xy 344.998548 -401.969224) (xy 344.993214 -402.05533)
			(xy 344.998548 -402.07311) (xy 345.00439 -402.080476) (xy 345.020901 -402.102461) (xy 345.047174 -402.150756)
			(xy 345.065104 -402.202728) (xy 345.0742 -402.256949) (xy 345.074748 -402.284438) (xy 345.074238 -402.310425)
			(xy 345.066108 -402.36176) (xy 345.050047 -402.41119) (xy 345.026451 -402.4575) (xy 344.995901 -402.499548)
			(xy 344.95915 -402.536299) (xy 344.917102 -402.566849) (xy 344.870792 -402.590445) (xy 344.821362 -402.606506)
			(xy 344.770027 -402.614636) (xy 344.718053 -402.614636) (xy 344.666718 -402.606506) (xy 344.617288 -402.590445)
			(xy 344.570978 -402.566849) (xy 344.52893 -402.536299) (xy 344.492179 -402.499548) (xy 344.461629 -402.4575)
			(xy 344.438033 -402.41119) (xy 344.421972 -402.36176) (xy 344.413842 -402.310425) (xy 344.413332 -402.284438)
			(xy 344.413878 -402.256947) (xy 344.422955 -402.20272) (xy 344.440882 -402.150744) (xy 344.467164 -402.102451)
			(xy 344.48369 -402.080476) (xy 344.489532 -402.07311) (xy 344.494866 -402.05533) (xy 344.489532 -401.969224)
			(xy 344.481912 -401.95246) (xy 344.475308 -401.945856) (xy 344.454314 -401.924209) (xy 344.418722 -401.875535)
			(xy 344.391232 -401.821867) (xy 344.37253 -401.764542) (xy 344.363082 -401.704988) (xy 344.362532 -401.674838)
			(xy 343.925652 -401.674838) (xy 343.925114 -401.703742) (xy 343.916409 -401.760892) (xy 343.899189 -401.816076)
			(xy 343.873847 -401.868034) (xy 343.840963 -401.915579) (xy 343.821512 -401.936966) (xy 343.815416 -401.94357)
			(xy 343.808304 -401.959572) (xy 343.802716 -402.041868) (xy 343.807542 -402.058886) (xy 343.812622 -402.065998)
			(xy 343.827255 -402.08723) (xy 343.85051 -402.13325) (xy 343.866337 -402.182322) (xy 343.874353 -402.233257)
			(xy 343.874852 -402.259038) (xy 343.874342 -402.285025) (xy 343.866212 -402.33636) (xy 343.850151 -402.38579)
			(xy 343.826555 -402.4321) (xy 343.796005 -402.474148) (xy 343.759254 -402.510899) (xy 343.717206 -402.541449)
			(xy 343.670896 -402.565045) (xy 343.621466 -402.581106) (xy 343.570131 -402.589236) (xy 343.518157 -402.589236)
			(xy 343.466822 -402.581106) (xy 343.417392 -402.565045) (xy 343.371082 -402.541449) (xy 343.329034 -402.510899)
			(xy 343.292283 -402.474148) (xy 343.261733 -402.4321) (xy 343.238137 -402.38579) (xy 343.222076 -402.33636)
			(xy 343.213946 -402.285025) (xy 343.213436 -402.259038) (xy 343.21392 -402.233255) (xy 343.221926 -402.182315)
			(xy 343.237749 -402.133237) (xy 343.261006 -402.087213) (xy 343.275666 -402.065998) (xy 343.280746 -402.058886)
			(xy 343.285572 -402.041868) (xy 343.279984 -401.959572) (xy 343.272872 -401.94357) (xy 343.266776 -401.936966)
			(xy 343.247289 -401.915607) (xy 343.214382 -401.868068) (xy 343.189033 -401.816105) (xy 343.171821 -401.760909)
			(xy 343.163144 -401.703747) (xy 343.162636 -401.674838) (xy 342.725756 -401.674838) (xy 342.725324 -401.701012)
			(xy 342.718127 -401.752863) (xy 342.703916 -401.803246) (xy 342.682956 -401.851215) (xy 342.65564 -401.895871)
			(xy 342.62248 -401.936378) (xy 342.603582 -401.954492) (xy 342.596216 -401.96135) (xy 342.588088 -401.978876)
			(xy 342.582754 -402.069046) (xy 342.58885 -402.087334) (xy 342.595454 -402.094954) (xy 342.610347 -402.113004)
			(xy 342.635414 -402.152519) (xy 342.654664 -402.195172) (xy 342.667713 -402.240111) (xy 342.6743 -402.28644)
			(xy 342.674702 -402.309838) (xy 342.674192 -402.335825) (xy 342.666062 -402.38716) (xy 342.650001 -402.43659)
			(xy 342.626405 -402.4829) (xy 342.595855 -402.524948) (xy 342.559104 -402.561699) (xy 342.517056 -402.592249)
			(xy 342.470746 -402.615845) (xy 342.421316 -402.631906) (xy 342.369981 -402.640036) (xy 342.318007 -402.640036)
			(xy 342.266672 -402.631906) (xy 342.217242 -402.615845) (xy 342.170932 -402.592249) (xy 342.128884 -402.561699)
			(xy 342.092133 -402.524948) (xy 342.061583 -402.4829) (xy 342.037987 -402.43659) (xy 342.021926 -402.38716)
			(xy 342.013796 -402.335825) (xy 342.013286 -402.309838) (xy 342.013726 -402.286442) (xy 342.020311 -402.240117)
			(xy 342.033354 -402.19518) (xy 342.052597 -402.152529) (xy 342.077655 -402.113013) (xy 342.092534 -402.094954)
			(xy 342.099138 -402.087334) (xy 342.105234 -402.069046) (xy 342.0999 -401.978876) (xy 342.091772 -401.96135)
			(xy 342.084406 -401.954492) (xy 342.065511 -401.936375) (xy 342.032347 -401.895872) (xy 342.00503 -401.851217)
			(xy 341.984072 -401.803247) (xy 341.969866 -401.752864) (xy 341.96268 -401.701012) (xy 341.962232 -401.674838)
			(xy 341.52586 -401.674838) (xy 341.525457 -401.701013) (xy 341.518259 -401.752867) (xy 341.504044 -401.803251)
			(xy 341.483078 -401.851221) (xy 341.455756 -401.895876) (xy 341.422588 -401.93638) (xy 341.403686 -401.954492)
			(xy 341.39632 -401.96135) (xy 341.388192 -401.978876) (xy 341.382858 -402.069046) (xy 341.388954 -402.087334)
			(xy 341.395558 -402.094954) (xy 341.410452 -402.113004) (xy 341.435518 -402.152519) (xy 341.454768 -402.195172)
			(xy 341.467817 -402.240111) (xy 341.474404 -402.28644) (xy 341.474806 -402.309838) (xy 341.474296 -402.335825)
			(xy 341.466166 -402.38716) (xy 341.450105 -402.43659) (xy 341.426509 -402.4829) (xy 341.395959 -402.524948)
			(xy 341.359208 -402.561699) (xy 341.31716 -402.592249) (xy 341.27085 -402.615845) (xy 341.22142 -402.631906)
			(xy 341.170085 -402.640036) (xy 341.118111 -402.640036) (xy 341.066776 -402.631906) (xy 341.017346 -402.615845)
			(xy 340.971036 -402.592249) (xy 340.928988 -402.561699) (xy 340.892237 -402.524948) (xy 340.861687 -402.4829)
			(xy 340.838091 -402.43659) (xy 340.82203 -402.38716) (xy 340.8139 -402.335825) (xy 340.81339 -402.309838)
			(xy 340.813829 -402.286442) (xy 340.820414 -402.240117) (xy 340.833458 -402.19518) (xy 340.852701 -402.152529)
			(xy 340.877759 -402.113013) (xy 340.892638 -402.094954) (xy 340.899242 -402.087334) (xy 340.905338 -402.069046)
			(xy 340.900004 -401.978876) (xy 340.891876 -401.96135) (xy 340.88451 -401.954492) (xy 340.865616 -401.936374)
			(xy 340.832452 -401.895871) (xy 340.805134 -401.851217) (xy 340.784176 -401.803247) (xy 340.76997 -401.752864)
			(xy 340.762784 -401.701012) (xy 340.762336 -401.674838) (xy 340.325456 -401.674838) (xy 340.324917 -401.703742)
			(xy 340.316212 -401.760892) (xy 340.298992 -401.816076) (xy 340.273651 -401.868034) (xy 340.240767 -401.915579)
			(xy 340.221316 -401.936966) (xy 340.21522 -401.94357) (xy 340.208108 -401.959572) (xy 340.20252 -402.041868)
			(xy 340.207346 -402.058886) (xy 340.212426 -402.065998) (xy 340.227059 -402.08723) (xy 340.250314 -402.13325)
			(xy 340.266141 -402.182322) (xy 340.274157 -402.233257) (xy 340.274656 -402.259038) (xy 340.274146 -402.285025)
			(xy 340.266016 -402.33636) (xy 340.249955 -402.38579) (xy 340.226359 -402.4321) (xy 340.195809 -402.474148)
			(xy 340.159058 -402.510899) (xy 340.11701 -402.541449) (xy 340.0707 -402.565045) (xy 340.02127 -402.581106)
			(xy 339.969935 -402.589236) (xy 339.917961 -402.589236) (xy 339.866626 -402.581106) (xy 339.817196 -402.565045)
			(xy 339.770886 -402.541449) (xy 339.728838 -402.510899) (xy 339.692087 -402.474148) (xy 339.661537 -402.4321)
			(xy 339.637941 -402.38579) (xy 339.62188 -402.33636) (xy 339.61375 -402.285025) (xy 339.61324 -402.259038)
			(xy 339.613723 -402.233255) (xy 339.621729 -402.182314) (xy 339.637553 -402.133236) (xy 339.660809 -402.087213)
			(xy 339.67547 -402.065998) (xy 339.68055 -402.058886) (xy 339.685376 -402.041868) (xy 339.679788 -401.959572)
			(xy 339.672676 -401.94357) (xy 339.66658 -401.936966) (xy 339.647094 -401.915606) (xy 339.614187 -401.868068)
			(xy 339.588837 -401.816105) (xy 339.571625 -401.760909) (xy 339.562948 -401.703747) (xy 339.56244 -401.674838)
			(xy 339.12556 -401.674838) (xy 339.1251 -401.701001) (xy 339.11795 -401.752837) (xy 339.103788 -401.803211)
			(xy 339.08288 -401.851179) (xy 339.055618 -401.895843) (xy 339.022512 -401.936366) (xy 339.00364 -401.954492)
			(xy 338.996274 -401.96135) (xy 338.988146 -401.978876) (xy 338.982812 -402.069046) (xy 338.988908 -402.087334)
			(xy 338.995512 -402.094954) (xy 339.010414 -402.112997) (xy 339.035478 -402.152515) (xy 339.054725 -402.195169)
			(xy 339.067772 -402.24011) (xy 339.074358 -402.28644) (xy 339.07476 -402.309838) (xy 339.07425 -402.335825)
			(xy 339.06612 -402.38716) (xy 339.050059 -402.43659) (xy 339.026463 -402.4829) (xy 338.995913 -402.524948)
			(xy 338.959162 -402.561699) (xy 338.917114 -402.592249) (xy 338.870804 -402.615845) (xy 338.821374 -402.631906)
			(xy 338.770039 -402.640036) (xy 338.718065 -402.640036) (xy 338.66673 -402.631906) (xy 338.6173 -402.615845)
			(xy 338.57099 -402.592249) (xy 338.528942 -402.561699) (xy 338.492191 -402.524948) (xy 338.461641 -402.4829)
			(xy 338.438045 -402.43659) (xy 338.421984 -402.38716) (xy 338.413854 -402.335825) (xy 338.413344 -402.309838)
			(xy 338.41377 -402.286442) (xy 338.420356 -402.240115) (xy 338.433402 -402.195178) (xy 338.452648 -402.152527)
			(xy 338.47771 -402.113012) (xy 338.492592 -402.094954) (xy 338.499196 -402.087334) (xy 338.505292 -402.069046)
			(xy 338.499958 -401.978876) (xy 338.49183 -401.96135) (xy 338.484464 -401.954492) (xy 338.465563 -401.936393)
			(xy 338.432448 -401.89587) (xy 338.40518 -401.851203) (xy 338.384271 -401.803229) (xy 338.370113 -401.752847)
			(xy 338.362971 -401.701004) (xy 338.362544 -401.674838) (xy 337.925664 -401.674838) (xy 337.925049 -401.704996)
			(xy 337.915555 -401.764559) (xy 337.89681 -401.821888) (xy 337.869281 -401.875554) (xy 337.833653 -401.924222)
			(xy 337.812634 -401.945856) (xy 337.80603 -401.95246) (xy 337.79841 -401.969224) (xy 337.793076 -402.05533)
			(xy 337.79841 -402.07311) (xy 337.804252 -402.080476) (xy 337.820758 -402.102465) (xy 337.847033 -402.150758)
			(xy 337.864965 -402.202729) (xy 337.874061 -402.256949) (xy 337.87461 -402.284438) (xy 337.8741 -402.310425)
			(xy 337.86597 -402.36176) (xy 337.849909 -402.41119) (xy 337.826313 -402.4575) (xy 337.795763 -402.499548)
			(xy 337.759012 -402.536299) (xy 337.716964 -402.566849) (xy 337.670654 -402.590445) (xy 337.621224 -402.606506)
			(xy 337.569889 -402.614636) (xy 337.517915 -402.614636) (xy 337.46658 -402.606506) (xy 337.41715 -402.590445)
			(xy 337.37084 -402.566849) (xy 337.328792 -402.536299) (xy 337.292041 -402.499548) (xy 337.261491 -402.4575)
			(xy 337.237895 -402.41119) (xy 337.221834 -402.36176) (xy 337.213704 -402.310425) (xy 337.213194 -402.284438)
			(xy 337.213748 -402.256948) (xy 337.222824 -402.202722) (xy 337.240748 -402.150745) (xy 337.267027 -402.102452)
			(xy 337.283552 -402.080476) (xy 337.289394 -402.07311) (xy 337.294728 -402.05533) (xy 337.289394 -401.969224)
			(xy 337.281774 -401.95246) (xy 337.27517 -401.945856) (xy 337.254126 -401.924242) (xy 337.21848 -401.875577)
			(xy 337.190941 -401.821908) (xy 337.172194 -401.764572) (xy 337.162707 -401.705) (xy 337.16214 -401.674838)
			(xy 336.725768 -401.674838) (xy 336.725152 -401.704996) (xy 336.715658 -401.764559) (xy 336.696913 -401.821888)
			(xy 336.669384 -401.875554) (xy 336.633756 -401.924222) (xy 336.612738 -401.945856) (xy 336.606134 -401.95246)
			(xy 336.598514 -401.969224) (xy 336.59318 -402.05533) (xy 336.598514 -402.07311) (xy 336.604356 -402.080476)
			(xy 336.620862 -402.102465) (xy 336.647137 -402.150758) (xy 336.665069 -402.202729) (xy 336.674165 -402.256949)
			(xy 336.674714 -402.284438) (xy 336.674204 -402.310425) (xy 336.666074 -402.36176) (xy 336.650013 -402.41119)
			(xy 336.626417 -402.4575) (xy 336.595867 -402.499548) (xy 336.559116 -402.536299) (xy 336.517068 -402.566849)
			(xy 336.470758 -402.590445) (xy 336.421328 -402.606506) (xy 336.369993 -402.614636) (xy 336.318019 -402.614636)
			(xy 336.266684 -402.606506) (xy 336.217254 -402.590445) (xy 336.170944 -402.566849) (xy 336.128896 -402.536299)
			(xy 336.092145 -402.499548) (xy 336.061595 -402.4575) (xy 336.037999 -402.41119) (xy 336.021938 -402.36176)
			(xy 336.013808 -402.310425) (xy 336.013298 -402.284438) (xy 336.013851 -402.256948) (xy 336.022927 -402.202722)
			(xy 336.040852 -402.150745) (xy 336.067131 -402.102452) (xy 336.083656 -402.080476) (xy 336.089498 -402.07311)
			(xy 336.094832 -402.05533) (xy 336.089498 -401.969224) (xy 336.081878 -401.95246) (xy 336.075274 -401.945856)
			(xy 336.05423 -401.924242) (xy 336.018585 -401.875577) (xy 335.991045 -401.821908) (xy 335.972298 -401.764572)
			(xy 335.962811 -401.705) (xy 335.962244 -401.674838) (xy 332.378382 -401.674838) (xy 332.388582 -401.694275)
			(xy 332.410353 -401.751679) (xy 332.425049 -401.811288) (xy 332.432455 -401.872233) (xy 332.432914 -401.90293)
			(xy 332.432448 -401.93366) (xy 332.425037 -401.994671) (xy 332.410326 -402.054345) (xy 332.388529 -402.11181)
			(xy 332.359965 -402.166229) (xy 332.32505 -402.216808) (xy 332.284294 -402.262811) (xy 332.238289 -402.303565)
			(xy 332.187708 -402.338478) (xy 332.133288 -402.367039) (xy 332.075822 -402.388833) (xy 332.016148 -402.403541)
			(xy 331.955136 -402.41095) (xy 331.924406 -402.411438) (xy 331.893711 -402.41096) (xy 331.83277 -402.403539)
			(xy 331.773165 -402.388842) (xy 331.71576 -402.367081) (xy 331.66139 -402.338573) (xy 331.635862 -402.321522)
			(xy 331.62711 -402.316051) (xy 331.606906 -402.311923) (xy 331.586702 -402.316051) (xy 331.57795 -402.321522)
			(xy 331.552422 -402.338573) (xy 331.498058 -402.367094) (xy 331.440654 -402.388857) (xy 331.381045 -402.403544)
			(xy 331.320102 -402.410942) (xy 331.289406 -402.411438) (xy 331.258711 -402.41096) (xy 331.19777 -402.403539)
			(xy 331.138165 -402.388842) (xy 331.08076 -402.367081) (xy 331.02639 -402.338573) (xy 331.000862 -402.321522)
			(xy 330.99211 -402.316051) (xy 330.971906 -402.311923) (xy 330.951702 -402.316051) (xy 330.94295 -402.321522)
			(xy 330.917422 -402.338573) (xy 330.863058 -402.367094) (xy 330.805654 -402.388857) (xy 330.746045 -402.403544)
			(xy 330.685102 -402.410942) (xy 330.654406 -402.411438) (xy 330.623711 -402.41096) (xy 330.56277 -402.403539)
			(xy 330.503165 -402.388842) (xy 330.44576 -402.367081) (xy 330.39139 -402.338573) (xy 330.365862 -402.321522)
			(xy 330.35711 -402.316051) (xy 330.336906 -402.311923) (xy 330.316702 -402.316051) (xy 330.30795 -402.321522)
			(xy 330.29271 -402.331682) (xy 330.283507 -402.33824) (xy 330.271479 -402.357335) (xy 330.268795 -402.379743)
			(xy 330.271882 -402.39061) (xy 330.280048 -402.416443) (xy 330.291474 -402.469406) (xy 330.297199 -402.523285)
			(xy 330.297536 -402.550376) (xy 330.297073 -402.581109) (xy 330.289667 -402.642126) (xy 330.274961 -402.701806)
			(xy 330.262746 -402.734018) (xy 334.732628 -402.734018) (xy 334.736699 -402.678396) (xy 334.748825 -402.623959)
			(xy 334.768748 -402.571868) (xy 334.796044 -402.523233) (xy 334.83013 -402.47909) (xy 334.870279 -402.440381)
			(xy 334.915637 -402.40793) (xy 334.965237 -402.382429) (xy 335.018021 -402.364422) (xy 335.072864 -402.354292)
			(xy 335.128598 -402.352255) (xy 335.184035 -402.358355) (xy 335.237992 -402.372461) (xy 335.289321 -402.394273)
			(xy 335.336927 -402.423327) (xy 335.379795 -402.459002) (xy 335.417012 -402.500539) (xy 335.447785 -402.547052)
			(xy 335.471457 -402.597549) (xy 335.487525 -402.650956) (xy 335.495645 -402.706132) (xy 335.496154 -402.734018)
			(xy 335.495645 -402.761904) (xy 335.487525 -402.81708) (xy 335.471457 -402.870487) (xy 335.447785 -402.920984)
			(xy 335.417012 -402.967497) (xy 335.379795 -403.009034) (xy 335.336927 -403.044709) (xy 335.289321 -403.073763)
			(xy 335.237992 -403.095575) (xy 335.184035 -403.109681) (xy 335.128998 -403.115737) (xy 358.606338 -403.115737)
			(xy 358.606338 -403.051815) (xy 358.614349 -402.988397) (xy 358.630246 -402.926483) (xy 358.653778 -402.86705)
			(xy 358.684572 -402.811035) (xy 358.722145 -402.75932) (xy 358.765902 -402.712723) (xy 358.815155 -402.671978)
			(xy 358.869126 -402.637727) (xy 358.926965 -402.61051) (xy 358.987758 -402.590757) (xy 359.050548 -402.578779)
			(xy 359.114344 -402.574766) (xy 359.17814 -402.578779) (xy 359.24093 -402.590757) (xy 359.301723 -402.61051)
			(xy 359.359562 -402.637727) (xy 359.413533 -402.671978) (xy 359.462786 -402.712723) (xy 359.506543 -402.75932)
			(xy 359.544116 -402.811035) (xy 359.57491 -402.86705) (xy 359.598442 -402.926483) (xy 359.614339 -402.988397)
			(xy 359.62235 -403.051815) (xy 359.622852 -403.083776) (xy 359.62235 -403.115737) (xy 359.614339 -403.179155)
			(xy 359.598442 -403.241069) (xy 359.57491 -403.300502) (xy 359.544116 -403.356517) (xy 359.506543 -403.408232)
			(xy 359.462786 -403.454829) (xy 359.413533 -403.495574) (xy 359.359562 -403.529825) (xy 359.301723 -403.557042)
			(xy 359.24093 -403.576795) (xy 359.17814 -403.588773) (xy 359.114344 -403.592787) (xy 359.050548 -403.588773)
			(xy 358.987758 -403.576795) (xy 358.926965 -403.557042) (xy 358.869126 -403.529825) (xy 358.815155 -403.495574)
			(xy 358.765902 -403.454829) (xy 358.722145 -403.408232) (xy 358.684572 -403.356517) (xy 358.653778 -403.300502)
			(xy 358.630246 -403.241069) (xy 358.614349 -403.179155) (xy 358.606338 -403.115737) (xy 335.128998 -403.115737)
			(xy 335.128598 -403.115781) (xy 335.072864 -403.113744) (xy 335.018021 -403.103614) (xy 334.965237 -403.085607)
			(xy 334.915637 -403.060106) (xy 334.870279 -403.027655) (xy 334.83013 -402.988946) (xy 334.796044 -402.944803)
			(xy 334.768748 -402.896168) (xy 334.748825 -402.844077) (xy 334.736699 -402.78964) (xy 334.732628 -402.734018)
			(xy 330.262746 -402.734018) (xy 330.253168 -402.759277) (xy 330.224606 -402.813703) (xy 330.189693 -402.86429)
			(xy 330.148936 -402.910299) (xy 330.102931 -402.951061) (xy 330.052348 -402.985979) (xy 329.997925 -403.014546)
			(xy 329.940455 -403.036345) (xy 329.880777 -403.051058) (xy 329.819761 -403.05847) (xy 329.789028 -403.058884)
			(xy 329.78217 -403.058884) (xy 329.77201 -403.05863) (xy 329.753214 -403.06625) (xy 329.69454 -403.124162)
			(xy 329.687583 -403.131584) (xy 329.679705 -403.150321) (xy 329.6793 -403.160484) (xy 329.6793 -404.607987)
			(xy 359.33608 -404.607987) (xy 359.33608 -404.544065) (xy 359.344091 -404.480647) (xy 359.359988 -404.418733)
			(xy 359.38352 -404.3593) (xy 359.414314 -404.303285) (xy 359.451887 -404.25157) (xy 359.495644 -404.204973)
			(xy 359.544897 -404.164228) (xy 359.598868 -404.129977) (xy 359.656707 -404.10276) (xy 359.7175 -404.083007)
			(xy 359.78029 -404.071029) (xy 359.844086 -404.067016) (xy 359.907882 -404.071029) (xy 359.970672 -404.083007)
			(xy 360.031465 -404.10276) (xy 360.089304 -404.129977) (xy 360.143275 -404.164228) (xy 360.192528 -404.204973)
			(xy 360.236285 -404.25157) (xy 360.273858 -404.303285) (xy 360.304652 -404.3593) (xy 360.328184 -404.418733)
			(xy 360.344081 -404.480647) (xy 360.352092 -404.544065) (xy 360.352594 -404.576026) (xy 360.352092 -404.607987)
			(xy 360.344081 -404.671405) (xy 360.328184 -404.733319) (xy 360.304652 -404.792752) (xy 360.273858 -404.848767)
			(xy 360.236285 -404.900482) (xy 360.192528 -404.947079) (xy 360.143275 -404.987824) (xy 360.089304 -405.022075)
			(xy 360.031465 -405.049292) (xy 359.970672 -405.069045) (xy 359.907882 -405.081023) (xy 359.844086 -405.085037)
			(xy 359.78029 -405.081023) (xy 359.7175 -405.069045) (xy 359.656707 -405.049292) (xy 359.598868 -405.022075)
			(xy 359.544897 -404.987824) (xy 359.495644 -404.947079) (xy 359.451887 -404.900482) (xy 359.414314 -404.848767)
			(xy 359.38352 -404.792752) (xy 359.359988 -404.733319) (xy 359.344091 -404.671405) (xy 359.33608 -404.607987)
			(xy 329.6793 -404.607987) (xy 329.6793 -405.52243) (xy 364.256318 -405.52243) (xy 364.260389 -405.466808)
			(xy 364.272515 -405.412371) (xy 364.292438 -405.36028) (xy 364.319734 -405.311645) (xy 364.35382 -405.267502)
			(xy 364.393969 -405.228793) (xy 364.439327 -405.196342) (xy 364.488927 -405.170841) (xy 364.541711 -405.152834)
			(xy 364.596554 -405.142704) (xy 364.652288 -405.140667) (xy 364.707725 -405.146767) (xy 364.761682 -405.160873)
			(xy 364.813011 -405.182685) (xy 364.860617 -405.211739) (xy 364.903485 -405.247414) (xy 364.940702 -405.288951)
			(xy 364.971475 -405.335464) (xy 364.995147 -405.385961) (xy 365.011215 -405.439368) (xy 365.019335 -405.494544)
			(xy 365.019844 -405.52243) (xy 365.019335 -405.550316) (xy 365.011215 -405.605492) (xy 364.995147 -405.658899)
			(xy 364.971475 -405.709396) (xy 364.940702 -405.755909) (xy 364.903485 -405.797446) (xy 364.860617 -405.833121)
			(xy 364.813011 -405.862175) (xy 364.761682 -405.883987) (xy 364.707725 -405.898093) (xy 364.652288 -405.904193)
			(xy 364.596554 -405.902156) (xy 364.541711 -405.892026) (xy 364.488927 -405.874019) (xy 364.439327 -405.848518)
			(xy 364.393969 -405.816067) (xy 364.35382 -405.777358) (xy 364.319734 -405.733215) (xy 364.292438 -405.68458)
			(xy 364.272515 -405.632489) (xy 364.260389 -405.578052) (xy 364.256318 -405.52243) (xy 329.6793 -405.52243)
			(xy 329.6793 -405.670258) (xy 329.679734 -405.680323) (xy 329.687463 -405.698913) (xy 329.694286 -405.706326)
			(xy 331.416914 -407.428954) (xy 331.424311 -407.435803) (xy 331.44291 -407.44354) (xy 331.452982 -407.44394)
		)
		(stroke
			(width 0)
			(type solid)
		)
		(fill yes)
		(layer "In11.Cu")
		(net "P1V8_CPU0_RT_1D")
	)
	(gr_line
		(start 15.533878 -17.61236)
		(end 15.824708 -17.90319)
		(stroke
			(width 0.07112)
			(type default)
		)
		(layer "In11.Cu")
	)
	(gr_line
		(start 16.397478 -17.61236)
		(end 16.106648 -17.90319)
		(stroke
			(width 0.07112)
			(type default)
		)
		(layer "In11.Cu")
	)
	(gr_line
		(start 18.326862 -19.137122)
		(end 18.617692 -19.427952)
		(stroke
			(width 0.07112)
			(type default)
		)
		(layer "In11.Cu")
	)
	(gr_line
		(start 19.190462 -19.137122)
		(end 18.899632 -19.427952)
		(stroke
			(width 0.07112)
			(type default)
		)
		(layer "In11.Cu")
	)
	(gr_line
		(start 21.121878 -17.61236)
		(end 21.412708 -17.90319)
		(stroke
			(width 0.07112)
			(type default)
		)
		(layer "In11.Cu")
	)
	(gr_line
		(start 21.985478 -17.61236)
		(end 21.694648 -17.90319)
		(stroke
			(width 0.07112)
			(type default)
		)
		(layer "In11.Cu")
	)
	(gr_line
		(start 23.915878 -19.13636)
		(end 24.206708 -19.42719)
		(stroke
			(width 0.07112)
			(type default)
		)
		(layer "In11.Cu")
	)
	(gr_line
		(start 24.779478 -19.13636)
		(end 24.488648 -19.42719)
		(stroke
			(width 0.07112)
			(type default)
		)
		(layer "In11.Cu")
	)
	(gr_line
		(start 26.709878 -17.61236)
		(end 27.000708 -17.90319)
		(stroke
			(width 0.07112)
			(type default)
		)
		(layer "In11.Cu")
	)
	(gr_line
		(start 27.573478 -17.61236)
		(end 27.282648 -17.90319)
		(stroke
			(width 0.07112)
			(type default)
		)
		(layer "In11.Cu")
	)
	(gr_line
		(start 29.503878 -19.13636)
		(end 29.794708 -19.42719)
		(stroke
			(width 0.07112)
			(type default)
		)
		(layer "In11.Cu")
	)
	(gr_line
		(start 30.367478 -19.13636)
		(end 30.076648 -19.42719)
		(stroke
			(width 0.07112)
			(type default)
		)
		(layer "In11.Cu")
	)
	(gr_line
		(start 32.296862 -17.613122)
		(end 32.587692 -17.903952)
		(stroke
			(width 0.07112)
			(type default)
		)
		(layer "In11.Cu")
	)
	(gr_line
		(start 33.160462 -17.613122)
		(end 32.869632 -17.903952)
		(stroke
			(width 0.07112)
			(type default)
		)
		(layer "In11.Cu")
	)
	(gr_line
		(start 35.091878 -19.13636)
		(end 35.382708 -19.42719)
		(stroke
			(width 0.07112)
			(type default)
		)
		(layer "In11.Cu")
	)
	(gr_line
		(start 35.955478 -19.13636)
		(end 35.664648 -19.42719)
		(stroke
			(width 0.07112)
			(type default)
		)
		(layer "In11.Cu")
	)
	(gr_line
		(start 37.884862 -17.613122)
		(end 38.175692 -17.903952)
		(stroke
			(width 0.07112)
			(type default)
		)
		(layer "In11.Cu")
	)
	(gr_line
		(start 38.748462 -17.613122)
		(end 38.457632 -17.903952)
		(stroke
			(width 0.07112)
			(type default)
		)
		(layer "In11.Cu")
	)
	(gr_line
		(start 40.985694 -19.13636)
		(end 41.276524 -19.42719)
		(stroke
			(width 0.07112)
			(type default)
		)
		(layer "In11.Cu")
	)
	(gr_line
		(start 41.849294 -19.13636)
		(end 41.558464 -19.42719)
		(stroke
			(width 0.07112)
			(type default)
		)
		(layer "In11.Cu")
	)
	(gr_line
		(start 43.779694 -17.61236)
		(end 44.070524 -17.90319)
		(stroke
			(width 0.07112)
			(type default)
		)
		(layer "In11.Cu")
	)
	(gr_line
		(start 44.643294 -17.61236)
		(end 44.352464 -17.90319)
		(stroke
			(width 0.07112)
			(type default)
		)
		(layer "In11.Cu")
	)
	(gr_line
		(start 46.572678 -19.137122)
		(end 46.863508 -19.427952)
		(stroke
			(width 0.07112)
			(type default)
		)
		(layer "In11.Cu")
	)
	(gr_line
		(start 47.436278 -19.137122)
		(end 47.145448 -19.427952)
		(stroke
			(width 0.07112)
			(type default)
		)
		(layer "In11.Cu")
	)
	(gr_line
		(start 47.794164 -412.570168)
		(end 48.084994 -412.860998)
		(stroke
			(width 0.07112)
			(type default)
		)
		(layer "In11.Cu")
	)
	(gr_line
		(start 48.657764 -412.570168)
		(end 48.366934 -412.860998)
		(stroke
			(width 0.07112)
			(type default)
		)
		(layer "In11.Cu")
	)
	(gr_line
		(start 49.367694 -17.61236)
		(end 49.658524 -17.90319)
		(stroke
			(width 0.07112)
			(type default)
		)
		(layer "In11.Cu")
	)
	(gr_line
		(start 49.616614 -406.71369)
		(end 49.325784 -407.00452)
		(stroke
			(width 0.07112)
			(type default)
		)
		(layer "In11.Cu")
	)
	(gr_line
		(start 49.898554 -406.71369)
		(end 50.189384 -407.00452)
		(stroke
			(width 0.07112)
			(type default)
		)
		(layer "In11.Cu")
	)
	(gr_line
		(start 49.91354 -415.678366)
		(end 50.561494 -415.946844)
		(stroke
			(width 0.07112)
			(type default)
		)
		(layer "In11.Cu")
	)
	(gr_line
		(start 50.02276 -415.417)
		(end 50.20056 -415.34334)
		(stroke
			(width 0.07112)
			(type default)
		)
		(layer "In11.Cu")
	)
	(gr_line
		(start 50.20056 -415.34334)
		(end 50.595022 -415.506662)
		(stroke
			(width 0.07112)
			(type default)
		)
		(layer "In11.Cu")
	)
	(gr_line
		(start 50.231294 -17.61236)
		(end 49.940464 -17.90319)
		(stroke
			(width 0.07112)
			(type default)
		)
		(layer "In11.Cu")
	)
	(gr_line
		(start 50.595022 -415.506662)
		(end 50.668682 -415.684716)
		(stroke
			(width 0.07112)
			(type default)
		)
		(layer "In11.Cu")
	)
	(gr_line
		(start 50.857404 -412.570168)
		(end 51.148234 -412.860998)
		(stroke
			(width 0.07112)
			(type default)
		)
		(layer "In11.Cu")
	)
	(gr_line
		(start 51.016154 -416.135058)
		(end 51.664108 -416.403536)
		(stroke
			(width 0.07112)
			(type default)
		)
		(layer "In11.Cu")
	)
	(gr_line
		(start 51.125628 -415.873946)
		(end 51.303428 -415.800286)
		(stroke
			(width 0.07112)
			(type default)
		)
		(layer "In11.Cu")
	)
	(gr_line
		(start 51.303428 -415.800286)
		(end 51.69789 -415.963608)
		(stroke
			(width 0.07112)
			(type default)
		)
		(layer "In11.Cu")
	)
	(gr_line
		(start 51.69789 -415.963608)
		(end 51.771296 -416.141408)
		(stroke
			(width 0.07112)
			(type default)
		)
		(layer "In11.Cu")
	)
	(gr_line
		(start 51.721004 -412.570168)
		(end 51.430174 -412.860998)
		(stroke
			(width 0.07112)
			(type default)
		)
		(layer "In11.Cu")
	)
	(gr_line
		(start 51.807618 -414.604454)
		(end 52.390802 -414.994344)
		(stroke
			(width 0.07112)
			(type default)
		)
		(layer "In11.Cu")
	)
	(gr_line
		(start 51.96586 -414.369758)
		(end 52.154582 -414.332166)
		(stroke
			(width 0.07112)
			(type default)
		)
		(layer "In11.Cu")
	)
	(gr_line
		(start 52.087526 -416.578796)
		(end 52.735734 -416.847274)
		(stroke
			(width 0.07112)
			(type default)
		)
		(layer "In11.Cu")
	)
	(gr_line
		(start 52.154582 -414.332166)
		(end 52.509674 -414.569656)
		(stroke
			(width 0.07112)
			(type default)
		)
		(layer "In11.Cu")
	)
	(gr_line
		(start 52.19573 -19.13636)
		(end 52.48656 -19.42719)
		(stroke
			(width 0.07112)
			(type default)
		)
		(layer "In11.Cu")
	)
	(gr_line
		(start 52.197 -416.317684)
		(end 52.374546 -416.244024)
		(stroke
			(width 0.07112)
			(type default)
		)
		(layer "In11.Cu")
	)
	(gr_line
		(start 52.374546 -416.244024)
		(end 52.769008 -416.407346)
		(stroke
			(width 0.07112)
			(type default)
		)
		(layer "In11.Cu")
	)
	(gr_line
		(start 52.509674 -414.569656)
		(end 52.547266 -414.758124)
		(stroke
			(width 0.07112)
			(type default)
		)
		(layer "In11.Cu")
	)
	(gr_line
		(start 52.575968 -415.118042)
		(end 52.745386 -415.231326)
		(stroke
			(width 0.07112)
			(type default)
		)
		(layer "In11.Cu")
	)
	(gr_line
		(start 52.679854 -406.71369)
		(end 52.389024 -407.00452)
		(stroke
			(width 0.07112)
			(type default)
		)
		(layer "In11.Cu")
	)
	(gr_line
		(start 52.732432 -414.8836)
		(end 52.902104 -414.996884)
		(stroke
			(width 0.07112)
			(type default)
		)
		(layer "In11.Cu")
	)
	(gr_line
		(start 52.745386 -415.231326)
		(end 53.32857 -415.620962)
		(stroke
			(width 0.07112)
			(type default)
		)
		(layer "In11.Cu")
	)
	(gr_line
		(start 52.769008 -416.407346)
		(end 52.842922 -416.585146)
		(stroke
			(width 0.07112)
			(type default)
		)
		(layer "In11.Cu")
	)
	(gr_line
		(start 52.903882 -414.99663)
		(end 53.09235 -414.959038)
		(stroke
			(width 0.07112)
			(type default)
		)
		(layer "In11.Cu")
	)
	(gr_line
		(start 52.961794 -406.71369)
		(end 53.252624 -407.00452)
		(stroke
			(width 0.07112)
			(type default)
		)
		(layer "In11.Cu")
	)
	(gr_line
		(start 53.05933 -19.13636)
		(end 52.7685 -19.42719)
		(stroke
			(width 0.07112)
			(type default)
		)
		(layer "In11.Cu")
	)
	(gr_line
		(start 53.09235 -414.959038)
		(end 53.447442 -415.196274)
		(stroke
			(width 0.07112)
			(type default)
		)
		(layer "In11.Cu")
	)
	(gr_line
		(start 53.129688 -417.010596)
		(end 53.453538 -417.144708)
		(stroke
			(width 0.07112)
			(type default)
		)
		(layer "In11.Cu")
	)
	(gr_line
		(start 53.238908 -416.74923)
		(end 53.416708 -416.67557)
		(stroke
			(width 0.07112)
			(type default)
		)
		(layer "In11.Cu")
	)
	(gr_line
		(start 53.416708 -416.67557)
		(end 53.81117 -416.838892)
		(stroke
			(width 0.07112)
			(type default)
		)
		(layer "In11.Cu")
	)
	(gr_line
		(start 53.447442 -415.196274)
		(end 53.485034 -415.384996)
		(stroke
			(width 0.07112)
			(type default)
		)
		(layer "In11.Cu")
	)
	(gr_line
		(start 53.453538 -417.144708)
		(end 53.777388 -417.27882)
		(stroke
			(width 0.07112)
			(type default)
		)
		(layer "In11.Cu")
	)
	(gr_line
		(start 53.777388 -417.27882)
		(end 53.777642 -417.279074)
		(stroke
			(width 0.07112)
			(type default)
		)
		(layer "In11.Cu")
	)
	(gr_line
		(start 53.81117 -416.838892)
		(end 53.884576 -417.016692)
		(stroke
			(width 0.07112)
			(type default)
		)
		(layer "In11.Cu")
	)
	(gr_line
		(start 53.920644 -412.570168)
		(end 54.211474 -412.860998)
		(stroke
			(width 0.07112)
			(type default)
		)
		(layer "In11.Cu")
	)
	(gr_line
		(start 54.040532 -400.922236)
		(end 54.040786 -400.922744)
		(stroke
			(width 0.07112)
			(type default)
		)
		(layer "In11.Cu")
	)
	(gr_line
		(start 54.101238 -417.413186)
		(end 54.101492 -417.41344)
		(stroke
			(width 0.07112)
			(type default)
		)
		(layer "In11.Cu")
	)
	(gr_line
		(start 54.154324 -55.54218)
		(end 54.173628 -55.56758)
		(stroke
			(width 0.07112)
			(type default)
		)
		(layer "In11.Cu")
	)
	(gr_line
		(start 54.173628 -55.56758)
		(end 54.180486 -55.573422)
		(stroke
			(width 0.07112)
			(type default)
		)
		(layer "In11.Cu")
	)
	(gr_line
		(start 54.180994 -55.573676)
		(end 54.190138 -55.58155)
		(stroke
			(width 0.07112)
			(type default)
		)
		(layer "In11.Cu")
	)
	(gr_line
		(start 54.190138 -55.58155)
		(end 54.194456 -55.58536)
		(stroke
			(width 0.07112)
			(type default)
		)
		(layer "In11.Cu")
	)
	(gr_line
		(start 54.194456 -55.58536)
		(end 54.194964 -55.585614)
		(stroke
			(width 0.07112)
			(type default)
		)
		(layer "In11.Cu")
	)
	(gr_line
		(start 54.194964 -55.585614)
		(end 54.195726 -55.586376)
		(stroke
			(width 0.07112)
			(type default)
		)
		(layer "In11.Cu")
	)
	(gr_line
		(start 54.195726 -55.586376)
		(end 54.196742 -55.587138)
		(stroke
			(width 0.07112)
			(type default)
		)
		(layer "In11.Cu")
	)
	(gr_line
		(start 54.196742 -55.587138)
		(end 54.197504 -55.5879)
		(stroke
			(width 0.07112)
			(type default)
		)
		(layer "In11.Cu")
	)
	(gr_line
		(start 54.288182 -401.287742)
		(end 54.119272 -401.19427)
		(stroke
			(width 0.07112)
			(type default)
		)
		(layer "In11.Cu")
	)
	(gr_line
		(start 54.383178 -55.375048)
		(end 54.38394 -55.37581)
		(stroke
			(width 0.07112)
			(type default)
		)
		(layer "In11.Cu")
	)
	(gr_line
		(start 54.38394 -55.37581)
		(end 54.385972 -55.378096)
		(stroke
			(width 0.07112)
			(type default)
		)
		(layer "In11.Cu")
	)
	(gr_line
		(start 54.698646 -401.17014)
		(end 54.288182 -401.287742)
		(stroke
			(width 0.07112)
			(type default)
		)
		(layer "In11.Cu")
	)
	(gr_line
		(start 54.714648 -400.728688)
		(end 54.040532 -400.922236)
		(stroke
			(width 0.07112)
			(type default)
		)
		(layer "In11.Cu")
	)
	(gr_line
		(start 54.784244 -412.570168)
		(end 54.493414 -412.860998)
		(stroke
			(width 0.07112)
			(type default)
		)
		(layer "In11.Cu")
	)
	(gr_line
		(start 54.792118 -401.00123)
		(end 54.698646 -401.17014)
		(stroke
			(width 0.07112)
			(type default)
		)
		(layer "In11.Cu")
	)
	(gr_line
		(start 54.988714 -17.613122)
		(end 55.279544 -17.903952)
		(stroke
			(width 0.07112)
			(type default)
		)
		(layer "In11.Cu")
	)
	(gr_line
		(start 55.294276 -414.757362)
		(end 55.94223 -415.02584)
		(stroke
			(width 0.07112)
			(type default)
		)
		(layer "In11.Cu")
	)
	(gr_line
		(start 55.372254 -400.976592)
		(end 55.203344 -400.88312)
		(stroke
			(width 0.07112)
			(type default)
		)
		(layer "In11.Cu")
	)
	(gr_line
		(start 55.403496 -414.49625)
		(end 55.581296 -414.42259)
		(stroke
			(width 0.07112)
			(type default)
		)
		(layer "In11.Cu")
	)
	(gr_line
		(start 55.579264 -402.092922)
		(end 55.409592 -402.00199)
		(stroke
			(width 0.07112)
			(type default)
		)
		(layer "In11.Cu")
	)
	(gr_line
		(start 55.581296 -414.42259)
		(end 55.975758 -414.585912)
		(stroke
			(width 0.07112)
			(type default)
		)
		(layer "In11.Cu")
	)
	(gr_line
		(start 55.743094 -406.71369)
		(end 55.452264 -407.00452)
		(stroke
			(width 0.07112)
			(type default)
		)
		(layer "In11.Cu")
	)
	(gr_line
		(start 55.782718 -400.858736)
		(end 55.372254 -400.976592)
		(stroke
			(width 0.07112)
			(type default)
		)
		(layer "In11.Cu")
	)
	(gr_line
		(start 55.798974 -400.417538)
		(end 55.124604 -400.611086)
		(stroke
			(width 0.07112)
			(type default)
		)
		(layer "In11.Cu")
	)
	(gr_line
		(start 55.852314 -17.613122)
		(end 55.561484 -17.903952)
		(stroke
			(width 0.07112)
			(type default)
		)
		(layer "In11.Cu")
	)
	(gr_line
		(start 55.87619 -400.689826)
		(end 55.782718 -400.858736)
		(stroke
			(width 0.07112)
			(type default)
		)
		(layer "In11.Cu")
	)
	(gr_line
		(start 55.975758 -414.585912)
		(end 56.049672 -414.763712)
		(stroke
			(width 0.07112)
			(type default)
		)
		(layer "In11.Cu")
	)
	(gr_line
		(start 55.98795 -401.969478)
		(end 55.579264 -402.092922)
		(stroke
			(width 0.07112)
			(type default)
		)
		(layer "In11.Cu")
	)
	(gr_line
		(start 55.997856 -401.52828)
		(end 55.326534 -401.731226)
		(stroke
			(width 0.07112)
			(type default)
		)
		(layer "In11.Cu")
	)
	(gr_line
		(start 56.025034 -406.71369)
		(end 56.315864 -407.00452)
		(stroke
			(width 0.07112)
			(type default)
		)
		(layer "In11.Cu")
	)
	(gr_line
		(start 56.078628 -401.799806)
		(end 55.98795 -401.969478)
		(stroke
			(width 0.07112)
			(type default)
		)
		(layer "In11.Cu")
	)
	(gr_line
		(start 56.348122 -415.193988)
		(end 56.996076 -415.462466)
		(stroke
			(width 0.07112)
			(type default)
		)
		(layer "In11.Cu")
	)
	(gr_line
		(start 56.456326 -400.665188)
		(end 56.28767 -400.571716)
		(stroke
			(width 0.07112)
			(type default)
		)
		(layer "In11.Cu")
	)
	(gr_line
		(start 56.457596 -414.932876)
		(end 56.635396 -414.858962)
		(stroke
			(width 0.07112)
			(type default)
		)
		(layer "In11.Cu")
	)
	(gr_line
		(start 56.635396 -414.858962)
		(end 57.029858 -415.022284)
		(stroke
			(width 0.07112)
			(type default)
		)
		(layer "In11.Cu")
	)
	(gr_line
		(start 56.659018 -401.766532)
		(end 56.489346 -401.6756)
		(stroke
			(width 0.07112)
			(type default)
		)
		(layer "In11.Cu")
	)
	(gr_line
		(start 56.86679 -400.547332)
		(end 56.456326 -400.665188)
		(stroke
			(width 0.07112)
			(type default)
		)
		(layer "In11.Cu")
	)
	(gr_line
		(start 56.883046 -400.106134)
		(end 56.208676 -400.299682)
		(stroke
			(width 0.07112)
			(type default)
		)
		(layer "In11.Cu")
	)
	(gr_line
		(start 56.960008 -400.378676)
		(end 56.86679 -400.547332)
		(stroke
			(width 0.07112)
			(type default)
		)
		(layer "In11.Cu")
	)
	(gr_line
		(start 56.983884 -412.570168)
		(end 57.274714 -412.860998)
		(stroke
			(width 0.07112)
			(type default)
		)
		(layer "In11.Cu")
	)
	(gr_line
		(start 57.029858 -415.022284)
		(end 57.103264 -415.200338)
		(stroke
			(width 0.07112)
			(type default)
		)
		(layer "In11.Cu")
	)
	(gr_line
		(start 57.067704 -401.643088)
		(end 56.659018 -401.766532)
		(stroke
			(width 0.07112)
			(type default)
		)
		(layer "In11.Cu")
	)
	(gr_line
		(start 57.07761 -401.20189)
		(end 56.406288 -401.404836)
		(stroke
			(width 0.07112)
			(type default)
		)
		(layer "In11.Cu")
	)
	(gr_line
		(start 57.158382 -401.473416)
		(end 57.067704 -401.643088)
		(stroke
			(width 0.07112)
			(type default)
		)
		(layer "In11.Cu")
	)
	(gr_line
		(start 57.520078 -402.222208)
		(end 57.520332 -402.222462)
		(stroke
			(width 0.07112)
			(type default)
		)
		(layer "In11.Cu")
	)
	(gr_line
		(start 57.625488 -13.155676)
		(end 57.334658 -12.864846)
		(stroke
			(width 0.07112)
			(type default)
		)
		(layer "In11.Cu")
	)
	(gr_line
		(start 57.626504 -7.015988)
		(end 57.335674 -6.725158)
		(stroke
			(width 0.07112)
			(type default)
		)
		(layer "In11.Cu")
	)
	(gr_line
		(start 57.738518 -401.440142)
		(end 57.5691 -401.34921)
		(stroke
			(width 0.07112)
			(type default)
		)
		(layer "In11.Cu")
	)
	(gr_line
		(start 57.78373 -19.13636)
		(end 58.07456 -19.42719)
		(stroke
			(width 0.07112)
			(type default)
		)
		(layer "In11.Cu")
	)
	(gr_line
		(start 57.785254 -402.575014)
		(end 57.61228 -402.489924)
		(stroke
			(width 0.07112)
			(type default)
		)
		(layer "In11.Cu")
	)
	(gr_line
		(start 57.847484 -412.570168)
		(end 57.556654 -412.860998)
		(stroke
			(width 0.07112)
			(type default)
		)
		(layer "In11.Cu")
	)
	(gr_line
		(start 57.907428 -13.155676)
		(end 58.198258 -12.864846)
		(stroke
			(width 0.07112)
			(type default)
		)
		(layer "In11.Cu")
	)
	(gr_line
		(start 58.147204 -401.316698)
		(end 57.738518 -401.440142)
		(stroke
			(width 0.07112)
			(type default)
		)
		(layer "In11.Cu")
	)
	(gr_line
		(start 58.157364 -400.8755)
		(end 57.486042 -401.078446)
		(stroke
			(width 0.07112)
			(type default)
		)
		(layer "In11.Cu")
	)
	(gr_line
		(start 58.18378 -401.99564)
		(end 57.520078 -402.222208)
		(stroke
			(width 0.07112)
			(type default)
		)
		(layer "In11.Cu")
	)
	(gr_line
		(start 58.189368 -402.437092)
		(end 57.785254 -402.575014)
		(stroke
			(width 0.07112)
			(type default)
		)
		(layer "In11.Cu")
	)
	(gr_line
		(start 58.199274 -6.725158)
		(end 57.908444 -7.015988)
		(stroke
			(width 0.07112)
			(type default)
		)
		(layer "In11.Cu")
	)
	(gr_line
		(start 58.238136 -401.147026)
		(end 58.147204 -401.316698)
		(stroke
			(width 0.07112)
			(type default)
		)
		(layer "In11.Cu")
	)
	(gr_line
		(start 58.27268 -415.84499)
		(end 58.948574 -416.031934)
		(stroke
			(width 0.07112)
			(type default)
		)
		(layer "In11.Cu")
	)
	(gr_line
		(start 58.274204 -402.263864)
		(end 58.189368 -402.437092)
		(stroke
			(width 0.07112)
			(type default)
		)
		(layer "In11.Cu")
	)
	(gr_line
		(start 58.349388 -415.572448)
		(end 58.51652 -415.477452)
		(stroke
			(width 0.07112)
			(type default)
		)
		(layer "In11.Cu")
	)
	(gr_line
		(start 58.499248 -430.125632)
		(end 58.52287 -430.125632)
		(stroke
			(width 0.07112)
			(type default)
		)
		(layer "In11.Cu")
	)
	(gr_line
		(start 58.500518 -430.408842)
		(end 58.64987 -430.558194)
		(stroke
			(width 0.07112)
			(type default)
		)
		(layer "In11.Cu")
	)
	(gr_line
		(start 58.51652 -415.477452)
		(end 58.928 -415.591244)
		(stroke
			(width 0.07112)
			(type default)
		)
		(layer "In11.Cu")
	)
	(gr_line
		(start 58.52287 -430.125632)
		(end 58.64987 -429.998632)
		(stroke
			(width 0.07112)
			(type default)
		)
		(layer "In11.Cu")
	)
	(gr_line
		(start 58.58637 -414.69945)
		(end 59.257438 -414.902904)
		(stroke
			(width 0.07112)
			(type default)
		)
		(layer "In11.Cu")
	)
	(gr_line
		(start 58.64733 -19.13636)
		(end 58.3565 -19.42719)
		(stroke
			(width 0.07112)
			(type default)
		)
		(layer "In11.Cu")
	)
	(gr_line
		(start 58.64987 -430.558194)
		(end 58.64987 -430.889918)
		(stroke
			(width 0.07112)
			(type default)
		)
		(layer "In11.Cu")
	)
	(gr_line
		(start 58.64987 -429.998632)
		(end 58.64987 -429.689768)
		(stroke
			(width 0.07112)
			(type default)
		)
		(layer "In11.Cu")
	)
	(gr_line
		(start 58.669428 -414.428686)
		(end 58.839354 -414.337754)
		(stroke
			(width 0.07112)
			(type default)
		)
		(layer "In11.Cu")
	)
	(gr_line
		(start 58.806334 -406.71369)
		(end 58.515504 -407.00452)
		(stroke
			(width 0.07112)
			(type default)
		)
		(layer "In11.Cu")
	)
	(gr_line
		(start 58.839354 -414.337754)
		(end 59.247786 -414.461706)
		(stroke
			(width 0.07112)
			(type default)
		)
		(layer "In11.Cu")
	)
	(gr_line
		(start 58.852562 -402.210524)
		(end 58.679842 -402.125434)
		(stroke
			(width 0.07112)
			(type default)
		)
		(layer "In11.Cu")
	)
	(gr_line
		(start 58.928 -415.591244)
		(end 59.022742 -415.75863)
		(stroke
			(width 0.07112)
			(type default)
		)
		(layer "In11.Cu")
	)
	(gr_line
		(start 58.948574 -416.031934)
		(end 58.948574 -416.032188)
		(stroke
			(width 0.07112)
			(type default)
		)
		(layer "In11.Cu")
	)
	(gr_line
		(start 59.088274 -406.71369)
		(end 59.379104 -407.00452)
		(stroke
			(width 0.07112)
			(type default)
		)
		(layer "In11.Cu")
	)
	(gr_line
		(start 59.247786 -414.461706)
		(end 59.338464 -414.631632)
		(stroke
			(width 0.07112)
			(type default)
		)
		(layer "In11.Cu")
	)
	(gr_line
		(start 59.251088 -401.63115)
		(end 58.587386 -401.857718)
		(stroke
			(width 0.07112)
			(type default)
		)
		(layer "In11.Cu")
	)
	(gr_line
		(start 59.256676 -402.072602)
		(end 58.852562 -402.210524)
		(stroke
			(width 0.07112)
			(type default)
		)
		(layer "In11.Cu")
	)
	(gr_line
		(start 59.341512 -401.899628)
		(end 59.256676 -402.072602)
		(stroke
			(width 0.07112)
			(type default)
		)
		(layer "In11.Cu")
	)
	(gr_line
		(start 59.513978 -416.188652)
		(end 60.189872 -416.375596)
		(stroke
			(width 0.07112)
			(type default)
		)
		(layer "In11.Cu")
	)
	(gr_line
		(start 59.590432 -415.915856)
		(end 59.757818 -415.821114)
		(stroke
			(width 0.07112)
			(type default)
		)
		(layer "In11.Cu")
	)
	(gr_line
		(start 59.757818 -415.821114)
		(end 60.169298 -415.934652)
		(stroke
			(width 0.07112)
			(type default)
		)
		(layer "In11.Cu")
	)
	(gr_line
		(start 59.920124 -401.84578)
		(end 59.74715 -401.760944)
		(stroke
			(width 0.07112)
			(type default)
		)
		(layer "In11.Cu")
	)
	(gr_line
		(start 60.047124 -412.570168)
		(end 60.337954 -412.860998)
		(stroke
			(width 0.07112)
			(type default)
		)
		(layer "In11.Cu")
	)
	(gr_line
		(start 60.169298 -415.934652)
		(end 60.264294 -416.102292)
		(stroke
			(width 0.07112)
			(type default)
		)
		(layer "In11.Cu")
	)
	(gr_line
		(start 60.301124 -402.931376)
		(end 60.13069 -402.88083)
		(stroke
			(width 0.07112)
			(type default)
		)
		(layer "In11.Cu")
	)
	(gr_line
		(start 60.318396 -401.26666)
		(end 59.654694 -401.493228)
		(stroke
			(width 0.07112)
			(type default)
		)
		(layer "In11.Cu")
	)
	(gr_line
		(start 60.324238 -401.707858)
		(end 59.920124 -401.84578)
		(stroke
			(width 0.07112)
			(type default)
		)
		(layer "In11.Cu")
	)
	(gr_line
		(start 60.40882 -401.535138)
		(end 60.324238 -401.707858)
		(stroke
			(width 0.07112)
			(type default)
		)
		(layer "In11.Cu")
	)
	(gr_line
		(start 60.506356 -415.32429)
		(end 61.154056 -415.592768)
		(stroke
			(width 0.07112)
			(type default)
		)
		(layer "In11.Cu")
	)
	(gr_line
		(start 60.522612 -431.430938)
		(end 60.649866 -431.558192)
		(stroke
			(width 0.07112)
			(type default)
		)
		(layer "In11.Cu")
	)
	(gr_line
		(start 60.522612 -431.148744)
		(end 60.649866 -431.02149)
		(stroke
			(width 0.07112)
			(type default)
		)
		(layer "In11.Cu")
	)
	(gr_line
		(start 60.611258 -402.2979)
		(end 59.9948 -402.632164)
		(stroke
			(width 0.07112)
			(type default)
		)
		(layer "In11.Cu")
	)
	(gr_line
		(start 60.61583 -415.063178)
		(end 60.793376 -414.989264)
		(stroke
			(width 0.07112)
			(type default)
		)
		(layer "In11.Cu")
	)
	(gr_line
		(start 60.649866 -431.558192)
		(end 60.649866 -431.889916)
		(stroke
			(width 0.07112)
			(type default)
		)
		(layer "In11.Cu")
	)
	(gr_line
		(start 60.649866 -431.02149)
		(end 60.649866 -430.689766)
		(stroke
			(width 0.07112)
			(type default)
		)
		(layer "In11.Cu")
	)
	(gr_line
		(start 60.677552 -414.104582)
		(end 61.05525 -414.294574)
		(stroke
			(width 0.07112)
			(type default)
		)
		(layer "In11.Cu")
	)
	(gr_line
		(start 60.69457 -402.718016)
		(end 60.301124 -402.931376)
		(stroke
			(width 0.07112)
			(type default)
		)
		(layer "In11.Cu")
	)
	(gr_line
		(start 60.745116 -402.547328)
		(end 60.69457 -402.718016)
		(stroke
			(width 0.07112)
			(type default)
		)
		(layer "In11.Cu")
	)
	(gr_line
		(start 60.793376 -414.989264)
		(end 61.187838 -415.15284)
		(stroke
			(width 0.07112)
			(type default)
		)
		(layer "In11.Cu")
	)
	(gr_line
		(start 60.804298 -413.852614)
		(end 61.181996 -414.04286)
		(stroke
			(width 0.07112)
			(type default)
		)
		(layer "In11.Cu")
	)
	(gr_line
		(start 60.910724 -412.570168)
		(end 60.619894 -412.860998)
		(stroke
			(width 0.07112)
			(type default)
		)
		(layer "In11.Cu")
	)
	(gr_line
		(start 61.05525 -414.294574)
		(end 61.681868 -414.610042)
		(stroke
			(width 0.07112)
			(type default)
		)
		(layer "In11.Cu")
	)
	(gr_line
		(start 61.183774 -414.042352)
		(end 61.366146 -413.9819)
		(stroke
			(width 0.07112)
			(type default)
		)
		(layer "In11.Cu")
	)
	(gr_line
		(start 61.187838 -415.15284)
		(end 61.261244 -415.33064)
		(stroke
			(width 0.07112)
			(type default)
		)
		(layer "In11.Cu")
	)
	(gr_line
		(start 61.366146 -413.9819)
		(end 61.747654 -414.17367)
		(stroke
			(width 0.07112)
			(type default)
		)
		(layer "In11.Cu")
	)
	(gr_line
		(start 61.747654 -414.17367)
		(end 61.808106 -414.35655)
		(stroke
			(width 0.07112)
			(type default)
		)
		(layer "In11.Cu")
	)
	(gr_line
		(start 61.869574 -406.71369)
		(end 61.578744 -407.00452)
		(stroke
			(width 0.07112)
			(type default)
		)
		(layer "In11.Cu")
	)
	(gr_line
		(start 62.062868 -414.801812)
		(end 62.689486 -415.117026)
		(stroke
			(width 0.07112)
			(type default)
		)
		(layer "In11.Cu")
	)
	(gr_line
		(start 62.151514 -406.71369)
		(end 62.442344 -407.00452)
		(stroke
			(width 0.07112)
			(type default)
		)
		(layer "In11.Cu")
	)
	(gr_line
		(start 62.191392 -414.549336)
		(end 62.373764 -414.488884)
		(stroke
			(width 0.07112)
			(type default)
		)
		(layer "In11.Cu")
	)
	(gr_line
		(start 62.373764 -414.488884)
		(end 62.755272 -414.680654)
		(stroke
			(width 0.07112)
			(type default)
		)
		(layer "In11.Cu")
	)
	(gr_line
		(start 62.49924 -430.125632)
		(end 62.522862 -430.125632)
		(stroke
			(width 0.07112)
			(type default)
		)
		(layer "In11.Cu")
	)
	(gr_line
		(start 62.50051 -430.408842)
		(end 62.649862 -430.558194)
		(stroke
			(width 0.07112)
			(type default)
		)
		(layer "In11.Cu")
	)
	(gr_line
		(start 62.522862 -430.125632)
		(end 62.649862 -429.998632)
		(stroke
			(width 0.07112)
			(type default)
		)
		(layer "In11.Cu")
	)
	(gr_line
		(start 62.649862 -430.558194)
		(end 62.649862 -430.889918)
		(stroke
			(width 0.07112)
			(type default)
		)
		(layer "In11.Cu")
	)
	(gr_line
		(start 62.649862 -429.998632)
		(end 62.649862 -429.689768)
		(stroke
			(width 0.07112)
			(type default)
		)
		(layer "In11.Cu")
	)
	(gr_line
		(start 62.755272 -414.680654)
		(end 62.815724 -414.863534)
		(stroke
			(width 0.07112)
			(type default)
		)
		(layer "In11.Cu")
	)
	(gr_line
		(start 62.790578 -401.857972)
		(end 62.630304 -401.772374)
		(stroke
			(width 0.07112)
			(type default)
		)
		(layer "In11.Cu")
	)
	(gr_line
		(start 62.812168 -402.61032)
		(end 62.812422 -402.610574)
		(stroke
			(width 0.07112)
			(type default)
		)
		(layer "In11.Cu")
	)
	(gr_line
		(start 63.072518 -402.966682)
		(end 62.90056 -402.879306)
		(stroke
			(width 0.07112)
			(type default)
		)
		(layer "In11.Cu")
	)
	(gr_line
		(start 63.110364 -412.570168)
		(end 63.353696 -412.8135)
		(stroke
			(width 0.07112)
			(type default)
		)
		(layer "In11.Cu")
	)
	(gr_line
		(start 63.213742 -401.73021)
		(end 62.790578 -401.857972)
		(stroke
			(width 0.07112)
			(type default)
		)
		(layer "In11.Cu")
	)
	(gr_line
		(start 63.218568 -401.298156)
		(end 62.547246 -401.50161)
		(stroke
			(width 0.07112)
			(type default)
		)
		(layer "In11.Cu")
	)
	(gr_line
		(start 63.299594 -401.569428)
		(end 63.213742 -401.73021)
		(stroke
			(width 0.07112)
			(type default)
		)
		(layer "In11.Cu")
	)
	(gr_arc
		(start 63.400178 -412.910782)
		(mid 63.385293 -412.858148)
		(end 63.353696 -412.8135)
		(stroke
			(width 0.07112)
			(type default)
		)
		(layer "In11.Cu")
	)
	(gr_line
		(start 63.47841 -402.834856)
		(end 63.072518 -402.966682)
		(stroke
			(width 0.07112)
			(type default)
		)
		(layer "In11.Cu")
	)
	(gr_line
		(start 63.479426 -402.393404)
		(end 62.812168 -402.61032)
		(stroke
			(width 0.07112)
			(type default)
		)
		(layer "In11.Cu")
	)
	(gr_line
		(start 63.565786 -402.662898)
		(end 63.47841 -402.834856)
		(stroke
			(width 0.07112)
			(type default)
		)
		(layer "In11.Cu")
	)
	(gr_line
		(start 63.633604 -415.689542)
		(end 64.17564 -416.13455)
		(stroke
			(width 0.07112)
			(type default)
		)
		(layer "In11.Cu")
	)
	(gr_arc
		(start 63.730632 -412.8135)
		(mid 63.699076 -412.858169)
		(end 63.68415 -412.910782)
		(stroke
			(width 0.07112)
			(type default)
		)
		(layer "In11.Cu")
	)
	(gr_line
		(start 63.81242 -415.471102)
		(end 63.81242 -415.471356)
		(stroke
			(width 0.07112)
			(type default)
		)
		(layer "In11.Cu")
	)
	(gr_line
		(start 63.813944 -415.471102)
		(end 64.00546 -415.452306)
		(stroke
			(width 0.07112)
			(type default)
		)
		(layer "In11.Cu")
	)
	(gr_line
		(start 63.871348 -401.531836)
		(end 63.70955 -401.445222)
		(stroke
			(width 0.07112)
			(type default)
		)
		(layer "In11.Cu")
	)
	(gr_line
		(start 63.884048 -414.391348)
		(end 64.42583 -414.83661)
		(stroke
			(width 0.07112)
			(type default)
		)
		(layer "In11.Cu")
	)
	(gr_line
		(start 63.973964 -412.570168)
		(end 63.730632 -412.8135)
		(stroke
			(width 0.07112)
			(type default)
		)
		(layer "In11.Cu")
	)
	(gr_line
		(start 64.00546 -415.452306)
		(end 64.33566 -415.723324)
		(stroke
			(width 0.07112)
			(type default)
		)
		(layer "In11.Cu")
	)
	(gr_line
		(start 64.064896 -414.173162)
		(end 64.256158 -414.15462)
		(stroke
			(width 0.07112)
			(type default)
		)
		(layer "In11.Cu")
	)
	(gr_line
		(start 64.08039 -22.650958)
		(end 64.08039 -22.226778)
		(stroke
			(width 0.07112)
			(type default)
		)
		(layer "In11.Cu")
	)
	(gr_line
		(start 64.08039 -22.226778)
		(end 64.21628 -22.090888)
		(stroke
			(width 0.07112)
			(type default)
		)
		(layer "In11.Cu")
	)
	(gr_line
		(start 64.08039 -21.528278)
		(end 64.08039 -21.104098)
		(stroke
			(width 0.07112)
			(type default)
		)
		(layer "In11.Cu")
	)
	(gr_line
		(start 64.08039 -21.104098)
		(end 64.21628 -20.968208)
		(stroke
			(width 0.07112)
			(type default)
		)
		(layer "In11.Cu")
	)
	(gr_line
		(start 64.08039 -20.405598)
		(end 64.08039 -19.981418)
		(stroke
			(width 0.07112)
			(type default)
		)
		(layer "In11.Cu")
	)
	(gr_line
		(start 64.08039 -19.981418)
		(end 64.21628 -19.845528)
		(stroke
			(width 0.07112)
			(type default)
		)
		(layer "In11.Cu")
	)
	(gr_line
		(start 64.14516 -402.617686)
		(end 63.973456 -402.530564)
		(stroke
			(width 0.07112)
			(type default)
		)
		(layer "In11.Cu")
	)
	(gr_line
		(start 64.21628 -22.786848)
		(end 64.08039 -22.650958)
		(stroke
			(width 0.07112)
			(type default)
		)
		(layer "In11.Cu")
	)
	(gr_line
		(start 64.21628 -21.664168)
		(end 64.08039 -21.528278)
		(stroke
			(width 0.07112)
			(type default)
		)
		(layer "In11.Cu")
	)
	(gr_line
		(start 64.21628 -20.541488)
		(end 64.08039 -20.405598)
		(stroke
			(width 0.07112)
			(type default)
		)
		(layer "In11.Cu")
	)
	(gr_line
		(start 64.256158 -414.15462)
		(end 64.586104 -414.425638)
		(stroke
			(width 0.07112)
			(type default)
		)
		(layer "In11.Cu")
	)
	(gr_line
		(start 64.29248 -401.404328)
		(end 63.871348 -401.531836)
		(stroke
			(width 0.07112)
			(type default)
		)
		(layer "In11.Cu")
	)
	(gr_line
		(start 64.298322 -400.971004)
		(end 63.626746 -401.174458)
		(stroke
			(width 0.07112)
			(type default)
		)
		(layer "In11.Cu")
	)
	(gr_line
		(start 64.33566 -415.723324)
		(end 64.354456 -415.91484)
		(stroke
			(width 0.07112)
			(type default)
		)
		(layer "In11.Cu")
	)
	(gr_line
		(start 64.379094 -401.24253)
		(end 64.29248 -401.404328)
		(stroke
			(width 0.07112)
			(type default)
		)
		(layer "In11.Cu")
	)
	(gr_line
		(start 64.49949 -22.089618)
		(end 64.49949 -22.788118)
		(stroke
			(width 0.07112)
			(type default)
		)
		(layer "In11.Cu")
	)
	(gr_line
		(start 64.49949 -20.966938)
		(end 64.49949 -21.665438)
		(stroke
			(width 0.07112)
			(type default)
		)
		(layer "In11.Cu")
	)
	(gr_line
		(start 64.49949 -19.844258)
		(end 64.49949 -20.542758)
		(stroke
			(width 0.07112)
			(type default)
		)
		(layer "In11.Cu")
	)
	(gr_line
		(start 64.505332 -416.40506)
		(end 65.047622 -416.850068)
		(stroke
			(width 0.07112)
			(type default)
		)
		(layer "In11.Cu")
	)
	(gr_line
		(start 64.522604 -431.430938)
		(end 64.649858 -431.558192)
		(stroke
			(width 0.07112)
			(type default)
		)
		(layer "In11.Cu")
	)
	(gr_line
		(start 64.522604 -431.148744)
		(end 64.649858 -431.02149)
		(stroke
			(width 0.07112)
			(type default)
		)
		(layer "In11.Cu")
	)
	(gr_line
		(start 64.551052 -402.48586)
		(end 64.14516 -402.617686)
		(stroke
			(width 0.07112)
			(type default)
		)
		(layer "In11.Cu")
	)
	(gr_line
		(start 64.552068 -402.044408)
		(end 63.885064 -402.261324)
		(stroke
			(width 0.07112)
			(type default)
		)
		(layer "In11.Cu")
	)
	(gr_line
		(start 64.586104 -414.425638)
		(end 64.604646 -414.6169)
		(stroke
			(width 0.07112)
			(type default)
		)
		(layer "In11.Cu")
	)
	(gr_line
		(start 64.638428 -402.314156)
		(end 64.551052 -402.48586)
		(stroke
			(width 0.07112)
			(type default)
		)
		(layer "In11.Cu")
	)
	(gr_line
		(start 64.649858 -431.558192)
		(end 64.649858 -431.889916)
		(stroke
			(width 0.07112)
			(type default)
		)
		(layer "In11.Cu")
	)
	(gr_line
		(start 64.649858 -431.02149)
		(end 64.649858 -430.689766)
		(stroke
			(width 0.07112)
			(type default)
		)
		(layer "In11.Cu")
	)
	(gr_line
		(start 64.685926 -416.18662)
		(end 64.877442 -416.167824)
		(stroke
			(width 0.07112)
			(type default)
		)
		(layer "In11.Cu")
	)
	(gr_line
		(start 64.755522 -415.107374)
		(end 65.297304 -415.552636)
		(stroke
			(width 0.07112)
			(type default)
		)
		(layer "In11.Cu")
	)
	(gr_line
		(start 64.877442 -416.167824)
		(end 65.207642 -416.438842)
		(stroke
			(width 0.07112)
			(type default)
		)
		(layer "In11.Cu")
	)
	(gr_line
		(start 64.932814 -406.71369)
		(end 64.641984 -407.00452)
		(stroke
			(width 0.07112)
			(type default)
		)
		(layer "In11.Cu")
	)
	(gr_line
		(start 64.936116 -414.889188)
		(end 65.127632 -414.870646)
		(stroke
			(width 0.07112)
			(type default)
		)
		(layer "In11.Cu")
	)
	(gr_line
		(start 64.94653 -401.202398)
		(end 64.789304 -401.118324)
		(stroke
			(width 0.07112)
			(type default)
		)
		(layer "In11.Cu")
	)
	(gr_line
		(start 65.127632 -414.870646)
		(end 65.457578 -415.141664)
		(stroke
			(width 0.07112)
			(type default)
		)
		(layer "In11.Cu")
	)
	(gr_line
		(start 65.207642 -416.438842)
		(end 65.226438 -416.630612)
		(stroke
			(width 0.07112)
			(type default)
		)
		(layer "In11.Cu")
	)
	(gr_line
		(start 65.214754 -406.71369)
		(end 65.505584 -407.00452)
		(stroke
			(width 0.07112)
			(type default)
		)
		(layer "In11.Cu")
	)
	(gr_line
		(start 65.217802 -402.268944)
		(end 65.046352 -402.181568)
		(stroke
			(width 0.07112)
			(type default)
		)
		(layer "In11.Cu")
	)
	(gr_line
		(start 65.374266 -401.072858)
		(end 64.94653 -401.202398)
		(stroke
			(width 0.07112)
			(type default)
		)
		(layer "In11.Cu")
	)
	(gr_line
		(start 65.377568 -400.644106)
		(end 64.706246 -400.84756)
		(stroke
			(width 0.07112)
			(type default)
		)
		(layer "In11.Cu")
	)
	(gr_line
		(start 65.457578 -415.141664)
		(end 65.47612 -415.33318)
		(stroke
			(width 0.07112)
			(type default)
		)
		(layer "In11.Cu")
	)
	(gr_line
		(start 65.458594 -400.915378)
		(end 65.374266 -401.072858)
		(stroke
			(width 0.07112)
			(type default)
		)
		(layer "In11.Cu")
	)
	(gr_line
		(start 65.512696 -401.731988)
		(end 64.957706 -401.912582)
		(stroke
			(width 0.07112)
			(type default)
		)
		(layer "In11.Cu")
	)
	(gr_line
		(start 65.51295 -401.732496)
		(end 65.512696 -401.731988)
		(stroke
			(width 0.07112)
			(type default)
		)
		(layer "In11.Cu")
	)
	(gr_line
		(start 65.623694 -402.136864)
		(end 65.217802 -402.268944)
		(stroke
			(width 0.07112)
			(type default)
		)
		(layer "In11.Cu")
	)
	(gr_line
		(start 65.624202 -401.696428)
		(end 65.51295 -401.732496)
		(stroke
			(width 0.07112)
			(type default)
		)
		(layer "In11.Cu")
	)
	(gr_line
		(start 65.710562 -401.965922)
		(end 65.623694 -402.136864)
		(stroke
			(width 0.07112)
			(type default)
		)
		(layer "In11.Cu")
	)
	(gr_line
		(start 66.173604 -412.570168)
		(end 66.464434 -412.860998)
		(stroke
			(width 0.07112)
			(type default)
		)
		(layer "In11.Cu")
	)
	(gr_line
		(start 66.499232 -430.125632)
		(end 66.522854 -430.125632)
		(stroke
			(width 0.07112)
			(type default)
		)
		(layer "In11.Cu")
	)
	(gr_line
		(start 66.500502 -430.408842)
		(end 66.649854 -430.558194)
		(stroke
			(width 0.07112)
			(type default)
		)
		(layer "In11.Cu")
	)
	(gr_line
		(start 66.522854 -430.125632)
		(end 66.649854 -429.998632)
		(stroke
			(width 0.07112)
			(type default)
		)
		(layer "In11.Cu")
	)
	(gr_line
		(start 66.57467 -402.914358)
		(end 66.402966 -402.825458)
		(stroke
			(width 0.07112)
			(type default)
		)
		(layer "In11.Cu")
	)
	(gr_line
		(start 66.649854 -430.558194)
		(end 66.649854 -430.889918)
		(stroke
			(width 0.07112)
			(type default)
		)
		(layer "In11.Cu")
	)
	(gr_line
		(start 66.649854 -429.998632)
		(end 66.649854 -429.689768)
		(stroke
			(width 0.07112)
			(type default)
		)
		(layer "In11.Cu")
	)
	(gr_line
		(start 66.82359 -414.102804)
		(end 66.902076 -414.189418)
		(stroke
			(width 0.07112)
			(type default)
		)
		(layer "In11.Cu")
	)
	(gr_line
		(start 66.902076 -414.189418)
		(end 66.90233 -414.189672)
		(stroke
			(width 0.07112)
			(type default)
		)
		(layer "In11.Cu")
	)
	(gr_line
		(start 66.90233 -414.189672)
		(end 67.29476 -414.622488)
		(stroke
			(width 0.07112)
			(type default)
		)
		(layer "In11.Cu")
	)
	(gr_line
		(start 66.981578 -402.78558)
		(end 66.57467 -402.914358)
		(stroke
			(width 0.07112)
			(type default)
		)
		(layer "In11.Cu")
	)
	(gr_line
		(start 66.985642 -402.34362)
		(end 66.315844 -402.555964)
		(stroke
			(width 0.07112)
			(type default)
		)
		(layer "In11.Cu")
	)
	(gr_line
		(start 67.03441 -413.91332)
		(end 67.226688 -413.922972)
		(stroke
			(width 0.07112)
			(type default)
		)
		(layer "In11.Cu")
	)
	(gr_line
		(start 67.037204 -412.570168)
		(end 66.746374 -412.860998)
		(stroke
			(width 0.07112)
			(type default)
		)
		(layer "In11.Cu")
	)
	(gr_line
		(start 67.070732 -402.613876)
		(end 66.981578 -402.78558)
		(stroke
			(width 0.07112)
			(type default)
		)
		(layer "In11.Cu")
	)
	(gr_line
		(start 67.226688 -413.922972)
		(end 67.513454 -414.239202)
		(stroke
			(width 0.07112)
			(type default)
		)
		(layer "In11.Cu")
	)
	(gr_line
		(start 67.513454 -414.239202)
		(end 67.503802 -414.431734)
		(stroke
			(width 0.07112)
			(type default)
		)
		(layer "In11.Cu")
	)
	(gr_line
		(start 67.581272 -414.938718)
		(end 68.052188 -415.458148)
		(stroke
			(width 0.07112)
			(type default)
		)
		(layer "In11.Cu")
	)
	(gr_line
		(start 67.668648 -402.57349)
		(end 67.489832 -402.48078)
		(stroke
			(width 0.07112)
			(type default)
		)
		(layer "In11.Cu")
	)
	(gr_line
		(start 67.777868 -417.225988)
		(end 67.80022 -417.244276)
		(stroke
			(width 0.07112)
			(type default)
		)
		(layer "In11.Cu")
	)
	(gr_line
		(start 67.791584 -414.74898)
		(end 67.984116 -414.758632)
		(stroke
			(width 0.07112)
			(type default)
		)
		(layer "In11.Cu")
	)
	(gr_line
		(start 67.80022 -417.244276)
		(end 67.818 -417.265866)
		(stroke
			(width 0.07112)
			(type default)
		)
		(layer "In11.Cu")
	)
	(gr_line
		(start 67.971924 -402.030946)
		(end 67.40398 -402.211032)
		(stroke
			(width 0.07112)
			(type default)
		)
		(layer "In11.Cu")
	)
	(gr_line
		(start 67.972178 -402.0312)
		(end 67.971924 -402.030946)
		(stroke
			(width 0.07112)
			(type default)
		)
		(layer "In11.Cu")
	)
	(gr_line
		(start 67.984116 -414.758632)
		(end 68.270882 -415.074862)
		(stroke
			(width 0.07112)
			(type default)
		)
		(layer "In11.Cu")
	)
	(gr_line
		(start 67.996054 -406.71369)
		(end 67.705224 -407.00452)
		(stroke
			(width 0.07112)
			(type default)
		)
		(layer "In11.Cu")
	)
	(gr_line
		(start 68.075556 -402.444712)
		(end 67.668648 -402.57349)
		(stroke
			(width 0.07112)
			(type default)
		)
		(layer "In11.Cu")
	)
	(gr_line
		(start 68.083684 -401.995894)
		(end 67.972178 -402.0312)
		(stroke
			(width 0.07112)
			(type default)
		)
		(layer "In11.Cu")
	)
	(gr_line
		(start 68.168012 -402.26615)
		(end 68.075556 -402.444712)
		(stroke
			(width 0.07112)
			(type default)
		)
		(layer "In11.Cu")
	)
	(gr_line
		(start 68.270882 -415.074862)
		(end 68.26123 -415.267394)
		(stroke
			(width 0.07112)
			(type default)
		)
		(layer "In11.Cu")
	)
	(gr_line
		(start 68.277994 -406.71369)
		(end 68.568824 -407.00452)
		(stroke
			(width 0.07112)
			(type default)
		)
		(layer "In11.Cu")
	)
	(gr_line
		(start 68.3387 -415.774378)
		(end 68.809362 -416.293808)
		(stroke
			(width 0.07112)
			(type default)
		)
		(layer "In11.Cu")
	)
	(gr_line
		(start 68.509134 -401.86102)
		(end 68.503546 -401.862798)
		(stroke
			(width 0.07112)
			(type default)
		)
		(layer "In11.Cu")
	)
	(gr_line
		(start 68.509134 -401.860766)
		(end 68.509134 -401.86102)
		(stroke
			(width 0.07112)
			(type default)
		)
		(layer "In11.Cu")
	)
	(gr_line
		(start 68.522596 -431.430938)
		(end 68.64985 -431.558192)
		(stroke
			(width 0.07112)
			(type default)
		)
		(layer "In11.Cu")
	)
	(gr_line
		(start 68.522596 -431.148744)
		(end 68.64985 -431.02149)
		(stroke
			(width 0.07112)
			(type default)
		)
		(layer "In11.Cu")
	)
	(gr_line
		(start 68.549012 -415.58464)
		(end 68.741544 -415.594292)
		(stroke
			(width 0.07112)
			(type default)
		)
		(layer "In11.Cu")
	)
	(gr_line
		(start 68.59778 -403.271228)
		(end 68.597272 -403.271482)
		(stroke
			(width 0.07112)
			(type default)
		)
		(layer "In11.Cu")
	)
	(gr_line
		(start 68.64985 -431.558192)
		(end 68.64985 -431.889916)
		(stroke
			(width 0.07112)
			(type default)
		)
		(layer "In11.Cu")
	)
	(gr_line
		(start 68.64985 -431.02149)
		(end 68.64985 -430.689766)
		(stroke
			(width 0.07112)
			(type default)
		)
		(layer "In11.Cu")
	)
	(gr_line
		(start 68.741544 -415.594292)
		(end 69.02831 -415.910522)
		(stroke
			(width 0.07112)
			(type default)
		)
		(layer "In11.Cu")
	)
	(gr_line
		(start 68.753228 -402.216874)
		(end 68.59016 -402.132546)
		(stroke
			(width 0.07112)
			(type default)
		)
		(layer "In11.Cu")
	)
	(gr_line
		(start 69.02831 -415.910522)
		(end 69.018658 -416.103054)
		(stroke
			(width 0.07112)
			(type default)
		)
		(layer "In11.Cu")
	)
	(gr_line
		(start 69.108828 -403.242526)
		(end 68.936108 -403.15769)
		(stroke
			(width 0.07112)
			(type default)
		)
		(layer "In11.Cu")
	)
	(gr_line
		(start 69.134228 -416.852354)
		(end 69.38645 -417.506658)
		(stroke
			(width 0.07112)
			(type default)
		)
		(layer "In11.Cu")
	)
	(gr_line
		(start 69.160136 -402.088096)
		(end 68.753228 -402.216874)
		(stroke
			(width 0.07112)
			(type default)
		)
		(layer "In11.Cu")
	)
	(gr_line
		(start 69.16039 -401.654264)
		(end 68.509134 -401.860766)
		(stroke
			(width 0.07112)
			(type default)
		)
		(layer "In11.Cu")
	)
	(gr_line
		(start 69.236844 -412.570168)
		(end 69.527674 -412.860998)
		(stroke
			(width 0.07112)
			(type default)
		)
		(layer "In11.Cu")
	)
	(gr_line
		(start 69.244972 -401.92452)
		(end 69.160136 -402.088096)
		(stroke
			(width 0.07112)
			(type default)
		)
		(layer "In11.Cu")
	)
	(gr_line
		(start 69.38645 -417.506658)
		(end 69.386704 -417.506658)
		(stroke
			(width 0.07112)
			(type default)
		)
		(layer "In11.Cu")
	)
	(gr_line
		(start 69.398896 -416.75177)
		(end 69.574918 -416.829748)
		(stroke
			(width 0.07112)
			(type default)
		)
		(layer "In11.Cu")
	)
	(gr_line
		(start 69.508116 -402.664168)
		(end 68.84416 -402.88972)
		(stroke
			(width 0.07112)
			(type default)
		)
		(layer "In11.Cu")
	)
	(gr_line
		(start 69.513196 -403.105366)
		(end 69.108828 -403.242526)
		(stroke
			(width 0.07112)
			(type default)
		)
		(layer "In11.Cu")
	)
	(gr_line
		(start 69.574918 -416.829748)
		(end 69.728334 -417.22802)
		(stroke
			(width 0.07112)
			(type default)
		)
		(layer "In11.Cu")
	)
	(gr_line
		(start 69.598032 -402.932646)
		(end 69.513196 -403.105366)
		(stroke
			(width 0.07112)
			(type default)
		)
		(layer "In11.Cu")
	)
	(gr_line
		(start 69.687694 -418.709094)
		(end 69.687948 -418.70884)
		(stroke
			(width 0.07112)
			(type default)
		)
		(layer "In11.Cu")
	)
	(gr_line
		(start 69.728334 -417.22802)
		(end 69.650356 -417.404042)
		(stroke
			(width 0.07112)
			(type default)
		)
		(layer "In11.Cu")
	)
	(gr_line
		(start 70.100444 -412.570168)
		(end 69.809614 -412.860998)
		(stroke
			(width 0.07112)
			(type default)
		)
		(layer "In11.Cu")
	)
	(gr_line
		(start 70.176644 -402.87956)
		(end 70.003924 -402.794724)
		(stroke
			(width 0.07112)
			(type default)
		)
		(layer "In11.Cu")
	)
	(gr_line
		(start 70.219316 -414.945322)
		(end 70.608952 -415.528252)
		(stroke
			(width 0.07112)
			(type default)
		)
		(layer "In11.Cu")
	)
	(gr_line
		(start 70.455282 -414.788604)
		(end 70.644258 -414.826196)
		(stroke
			(width 0.07112)
			(type default)
		)
		(layer "In11.Cu")
	)
	(gr_line
		(start 70.499224 -430.125632)
		(end 70.522846 -430.125632)
		(stroke
			(width 0.07112)
			(type default)
		)
		(layer "In11.Cu")
	)
	(gr_line
		(start 70.500494 -430.408842)
		(end 70.649846 -430.558194)
		(stroke
			(width 0.07112)
			(type default)
		)
		(layer "In11.Cu")
	)
	(gr_line
		(start 70.522846 -430.125632)
		(end 70.649846 -429.998632)
		(stroke
			(width 0.07112)
			(type default)
		)
		(layer "In11.Cu")
	)
	(gr_line
		(start 70.575932 -402.301202)
		(end 69.911976 -402.526754)
		(stroke
			(width 0.07112)
			(type default)
		)
		(layer "In11.Cu")
	)
	(gr_line
		(start 70.581012 -402.7424)
		(end 70.176644 -402.87956)
		(stroke
			(width 0.07112)
			(type default)
		)
		(layer "In11.Cu")
	)
	(gr_line
		(start 70.644258 -414.826196)
		(end 70.881494 -415.181288)
		(stroke
			(width 0.07112)
			(type default)
		)
		(layer "In11.Cu")
	)
	(gr_line
		(start 70.649846 -430.558194)
		(end 70.649846 -430.889918)
		(stroke
			(width 0.07112)
			(type default)
		)
		(layer "In11.Cu")
	)
	(gr_line
		(start 70.649846 -429.998632)
		(end 70.649846 -429.689768)
		(stroke
			(width 0.07112)
			(type default)
		)
		(layer "In11.Cu")
	)
	(gr_line
		(start 70.665848 -402.56968)
		(end 70.581012 -402.7424)
		(stroke
			(width 0.07112)
			(type default)
		)
		(layer "In11.Cu")
	)
	(gr_line
		(start 70.845934 -415.882836)
		(end 71.235824 -416.46602)
		(stroke
			(width 0.07112)
			(type default)
		)
		(layer "In11.Cu")
	)
	(gr_line
		(start 70.881494 -415.181288)
		(end 70.843902 -415.370264)
		(stroke
			(width 0.07112)
			(type default)
		)
		(layer "In11.Cu")
	)
	(gr_line
		(start 71.059294 -406.71369)
		(end 70.768464 -407.00452)
		(stroke
			(width 0.07112)
			(type default)
		)
		(layer "In11.Cu")
	)
	(gr_line
		(start 71.082154 -415.726372)
		(end 71.270876 -415.763964)
		(stroke
			(width 0.07112)
			(type default)
		)
		(layer "In11.Cu")
	)
	(gr_line
		(start 71.24446 -402.516594)
		(end 71.07174 -402.431758)
		(stroke
			(width 0.07112)
			(type default)
		)
		(layer "In11.Cu")
	)
	(gr_line
		(start 71.270876 -415.763964)
		(end 71.508112 -416.119056)
		(stroke
			(width 0.07112)
			(type default)
		)
		(layer "In11.Cu")
	)
	(gr_line
		(start 71.341234 -406.71369)
		(end 71.632064 -407.00452)
		(stroke
			(width 0.07112)
			(type default)
		)
		(layer "In11.Cu")
	)
	(gr_line
		(start 71.508112 -416.119056)
		(end 71.47052 -416.307778)
		(stroke
			(width 0.07112)
			(type default)
		)
		(layer "In11.Cu")
	)
	(gr_line
		(start 71.620634 -13.155676)
		(end 71.329804 -12.864846)
		(stroke
			(width 0.07112)
			(type default)
		)
		(layer "In11.Cu")
	)
	(gr_line
		(start 71.621142 -6.87832)
		(end 71.330312 -6.58749)
		(stroke
			(width 0.07112)
			(type default)
		)
		(layer "In11.Cu")
	)
	(gr_line
		(start 71.643748 -401.938236)
		(end 70.979792 -402.163788)
		(stroke
			(width 0.07112)
			(type default)
		)
		(layer "In11.Cu")
	)
	(gr_line
		(start 71.648828 -402.379434)
		(end 71.24446 -402.516594)
		(stroke
			(width 0.07112)
			(type default)
		)
		(layer "In11.Cu")
	)
	(gr_line
		(start 71.733664 -402.206714)
		(end 71.648828 -402.379434)
		(stroke
			(width 0.07112)
			(type default)
		)
		(layer "In11.Cu")
	)
	(gr_line
		(start 72.193404 -12.864846)
		(end 71.902574 -13.155676)
		(stroke
			(width 0.07112)
			(type default)
		)
		(layer "In11.Cu")
	)
	(gr_line
		(start 72.193912 -6.58749)
		(end 71.903082 -6.87832)
		(stroke
			(width 0.07112)
			(type default)
		)
		(layer "In11.Cu")
	)
	(gr_line
		(start 72.300084 -412.570168)
		(end 72.590914 -412.860998)
		(stroke
			(width 0.07112)
			(type default)
		)
		(layer "In11.Cu")
	)
	(gr_line
		(start 72.522588 -431.430938)
		(end 72.649842 -431.558192)
		(stroke
			(width 0.07112)
			(type default)
		)
		(layer "In11.Cu")
	)
	(gr_line
		(start 72.522588 -431.148744)
		(end 72.649842 -431.02149)
		(stroke
			(width 0.07112)
			(type default)
		)
		(layer "In11.Cu")
	)
	(gr_line
		(start 72.579992 -403.18944)
		(end 72.404478 -403.110192)
		(stroke
			(width 0.07112)
			(type default)
		)
		(layer "In11.Cu")
	)
	(gr_line
		(start 72.649842 -431.558192)
		(end 72.649842 -431.889916)
		(stroke
			(width 0.07112)
			(type default)
		)
		(layer "In11.Cu")
	)
	(gr_line
		(start 72.649842 -431.02149)
		(end 72.649842 -430.689766)
		(stroke
			(width 0.07112)
			(type default)
		)
		(layer "In11.Cu")
	)
	(gr_line
		(start 72.877934 -414.335722)
		(end 73.146158 -414.983676)
		(stroke
			(width 0.07112)
			(type default)
		)
		(layer "In11.Cu")
	)
	(gr_line
		(start 72.959722 -402.597874)
		(end 72.30364 -402.845524)
		(stroke
			(width 0.07112)
			(type default)
		)
		(layer "In11.Cu")
	)
	(gr_line
		(start 72.970644 -413.822896)
		(end 73.138284 -414.227772)
		(stroke
			(width 0.07112)
			(type default)
		)
		(layer "In11.Cu")
	)
	(gr_line
		(start 72.979534 -403.038564)
		(end 72.579992 -403.18944)
		(stroke
			(width 0.07112)
			(type default)
		)
		(layer "In11.Cu")
	)
	(gr_line
		(start 73.058528 -402.86305)
		(end 72.979534 -403.038564)
		(stroke
			(width 0.07112)
			(type default)
		)
		(layer "In11.Cu")
	)
	(gr_line
		(start 73.140062 -414.228534)
		(end 73.317862 -414.30194)
		(stroke
			(width 0.07112)
			(type default)
		)
		(layer "In11.Cu")
	)
	(gr_line
		(start 73.163684 -412.570168)
		(end 72.872854 -412.860998)
		(stroke
			(width 0.07112)
			(type default)
		)
		(layer "In11.Cu")
	)
	(gr_line
		(start 73.30948 -415.377884)
		(end 73.565258 -415.995358)
		(stroke
			(width 0.07112)
			(type default)
		)
		(layer "In11.Cu")
	)
	(gr_line
		(start 73.317862 -414.30194)
		(end 73.481184 -414.696656)
		(stroke
			(width 0.07112)
			(type default)
		)
		(layer "In11.Cu")
	)
	(gr_line
		(start 73.481184 -414.696656)
		(end 73.407524 -414.874456)
		(stroke
			(width 0.07112)
			(type default)
		)
		(layer "In11.Cu")
	)
	(gr_line
		(start 73.571608 -415.270442)
		(end 73.749662 -415.344102)
		(stroke
			(width 0.07112)
			(type default)
		)
		(layer "In11.Cu")
	)
	(gr_line
		(start 73.635108 -402.79066)
		(end 73.459848 -402.711666)
		(stroke
			(width 0.07112)
			(type default)
		)
		(layer "In11.Cu")
	)
	(gr_line
		(start 73.749662 -415.344102)
		(end 73.912984 -415.738564)
		(stroke
			(width 0.07112)
			(type default)
		)
		(layer "In11.Cu")
	)
	(gr_line
		(start 73.838562 -415.917888)
		(end 73.84415 -415.94532)
		(stroke
			(width 0.07112)
			(type default)
		)
		(layer "In11.Cu")
	)
	(gr_line
		(start 73.912984 -415.738564)
		(end 73.838562 -415.917888)
		(stroke
			(width 0.07112)
			(type default)
		)
		(layer "In11.Cu")
	)
	(gr_line
		(start 73.935336 -418.252402)
		(end 74.003916 -418.949886)
		(stroke
			(width 0.07112)
			(type default)
		)
		(layer "In11.Cu")
	)
	(gr_line
		(start 74.014838 -402.199094)
		(end 73.358756 -402.446998)
		(stroke
			(width 0.07112)
			(type default)
		)
		(layer "In11.Cu")
	)
	(gr_line
		(start 74.03465 -402.640038)
		(end 73.635108 -402.79066)
		(stroke
			(width 0.07112)
			(type default)
		)
		(layer "In11.Cu")
	)
	(gr_line
		(start 74.063606 -419.555676)
		(end 74.132186 -420.253922)
		(stroke
			(width 0.07112)
			(type default)
		)
		(layer "In11.Cu")
	)
	(gr_line
		(start 74.113644 -402.464524)
		(end 74.03465 -402.640038)
		(stroke
			(width 0.07112)
			(type default)
		)
		(layer "In11.Cu")
	)
	(gr_line
		(start 74.122534 -406.71369)
		(end 73.831704 -407.00452)
		(stroke
			(width 0.07112)
			(type default)
		)
		(layer "In11.Cu")
	)
	(gr_line
		(start 74.217276 -418.225732)
		(end 74.36612 -418.347652)
		(stroke
			(width 0.07112)
			(type default)
		)
		(layer "In11.Cu")
	)
	(gr_line
		(start 74.345546 -419.52926)
		(end 74.49439 -419.65118)
		(stroke
			(width 0.07112)
			(type default)
		)
		(layer "In11.Cu")
	)
	(gr_line
		(start 74.36612 -418.347652)
		(end 74.40803 -418.772594)
		(stroke
			(width 0.07112)
			(type default)
		)
		(layer "In11.Cu")
	)
	(gr_line
		(start 74.404474 -406.71369)
		(end 74.695304 -407.00452)
		(stroke
			(width 0.07112)
			(type default)
		)
		(layer "In11.Cu")
	)
	(gr_line
		(start 74.40803 -418.772594)
		(end 74.285856 -418.921438)
		(stroke
			(width 0.07112)
			(type default)
		)
		(layer "In11.Cu")
	)
	(gr_line
		(start 74.49439 -419.65118)
		(end 74.5363 -420.076122)
		(stroke
			(width 0.07112)
			(type default)
		)
		(layer "In11.Cu")
	)
	(gr_line
		(start 74.5363 -420.076122)
		(end 74.414126 -420.22522)
		(stroke
			(width 0.07112)
			(type default)
		)
		(layer "In11.Cu")
	)
	(gr_line
		(start 74.690224 -402.392134)
		(end 74.51471 -402.312886)
		(stroke
			(width 0.07112)
			(type default)
		)
		(layer "In11.Cu")
	)
	(gr_line
		(start 75.052936 -402.963634)
		(end 75.052936 -402.963888)
		(stroke
			(width 0.07112)
			(type default)
		)
		(layer "In11.Cu")
	)
	(gr_line
		(start 75.069954 -401.800568)
		(end 74.413872 -402.048472)
		(stroke
			(width 0.07112)
			(type default)
		)
		(layer "In11.Cu")
	)
	(gr_line
		(start 75.089766 -402.241512)
		(end 74.690224 -402.392134)
		(stroke
			(width 0.07112)
			(type default)
		)
		(layer "In11.Cu")
	)
	(gr_line
		(start 75.113388 -399.68678)
		(end 75.113642 -399.68678)
		(stroke
			(width 0.07112)
			(type default)
		)
		(layer "In11.Cu")
	)
	(gr_line
		(start 75.16876 -402.065998)
		(end 75.089766 -402.241512)
		(stroke
			(width 0.07112)
			(type default)
		)
		(layer "In11.Cu")
	)
	(gr_line
		(start 75.21194 -399.951194)
		(end 75.20432 -399.953734)
		(stroke
			(width 0.07112)
			(type default)
		)
		(layer "In11.Cu")
	)
	(gr_line
		(start 75.219052 -399.9484)
		(end 75.21194 -399.951194)
		(stroke
			(width 0.07112)
			(type default)
		)
		(layer "In11.Cu")
	)
	(gr_line
		(start 75.339956 -403.29866)
		(end 75.162156 -403.225)
		(stroke
			(width 0.07112)
			(type default)
		)
		(layer "In11.Cu")
	)
	(gr_line
		(start 75.363324 -412.570168)
		(end 75.654154 -412.860998)
		(stroke
			(width 0.07112)
			(type default)
		)
		(layer "In11.Cu")
	)
	(gr_line
		(start 75.499468 -430.125632)
		(end 75.52309 -430.125632)
		(stroke
			(width 0.07112)
			(type default)
		)
		(layer "In11.Cu")
	)
	(gr_line
		(start 75.500738 -430.408842)
		(end 75.65009 -430.558194)
		(stroke
			(width 0.07112)
			(type default)
		)
		(layer "In11.Cu")
	)
	(gr_line
		(start 75.52309 -430.125632)
		(end 75.65009 -429.998632)
		(stroke
			(width 0.07112)
			(type default)
		)
		(layer "In11.Cu")
	)
	(gr_line
		(start 75.65009 -430.558194)
		(end 75.65009 -430.889918)
		(stroke
			(width 0.07112)
			(type default)
		)
		(layer "In11.Cu")
	)
	(gr_line
		(start 75.65009 -429.998632)
		(end 75.65009 -429.689768)
		(stroke
			(width 0.07112)
			(type default)
		)
		(layer "In11.Cu")
	)
	(gr_line
		(start 75.65898 -414.839658)
		(end 75.697334 -415.228532)
		(stroke
			(width 0.07112)
			(type default)
		)
		(layer "In11.Cu")
	)
	(gr_line
		(start 75.697334 -415.228532)
		(end 75.765914 -415.926778)
		(stroke
			(width 0.07112)
			(type default)
		)
		(layer "In11.Cu")
	)
	(gr_line
		(start 75.701144 -402.695156)
		(end 75.052936 -402.963634)
		(stroke
			(width 0.07112)
			(type default)
		)
		(layer "In11.Cu")
	)
	(gr_line
		(start 75.70597 -400.557492)
		(end 75.705716 -400.557492)
		(stroke
			(width 0.07112)
			(type default)
		)
		(layer "In11.Cu")
	)
	(gr_line
		(start 75.734418 -403.135338)
		(end 75.339956 -403.29866)
		(stroke
			(width 0.07112)
			(type default)
		)
		(layer "In11.Cu")
	)
	(gr_line
		(start 75.752198 -367.390934)
		(end 75.752198 -367.39068)
		(stroke
			(width 0.07112)
			(type default)
		)
		(layer "In11.Cu")
	)
	(gr_line
		(start 75.800966 -400.823176)
		(end 75.796648 -400.8247)
		(stroke
			(width 0.07112)
			(type default)
		)
		(layer "In11.Cu")
	)
	(gr_line
		(start 75.805284 -400.821652)
		(end 75.800966 -400.823176)
		(stroke
			(width 0.07112)
			(type default)
		)
		(layer "In11.Cu")
	)
	(gr_line
		(start 75.808078 -402.957284)
		(end 75.734418 -403.135338)
		(stroke
			(width 0.07112)
			(type default)
		)
		(layer "In11.Cu")
	)
	(gr_line
		(start 75.81265 -416.39998)
		(end 75.88123 -417.096448)
		(stroke
			(width 0.07112)
			(type default)
		)
		(layer "In11.Cu")
	)
	(gr_line
		(start 75.88123 -417.096448)
		(end 75.881484 -417.097718)
		(stroke
			(width 0.07112)
			(type default)
		)
		(layer "In11.Cu")
	)
	(gr_line
		(start 75.881484 -417.097972)
		(end 75.881484 -417.097718)
		(stroke
			(width 0.07112)
			(type default)
		)
		(layer "In11.Cu")
	)
	(gr_line
		(start 75.93965 -414.812226)
		(end 75.97775 -415.2011)
		(stroke
			(width 0.07112)
			(type default)
		)
		(layer "In11.Cu")
	)
	(gr_line
		(start 75.979274 -415.20237)
		(end 76.128118 -415.32429)
		(stroke
			(width 0.07112)
			(type default)
		)
		(layer "In11.Cu")
	)
	(gr_line
		(start 76.09459 -416.37331)
		(end 76.243434 -416.49523)
		(stroke
			(width 0.07112)
			(type default)
		)
		(layer "In11.Cu")
	)
	(gr_line
		(start 76.128118 -415.32429)
		(end 76.169774 -415.749232)
		(stroke
			(width 0.07112)
			(type default)
		)
		(layer "In11.Cu")
	)
	(gr_line
		(start 76.169774 -415.749232)
		(end 76.047854 -415.897822)
		(stroke
			(width 0.07112)
			(type default)
		)
		(layer "In11.Cu")
	)
	(gr_line
		(start 76.226924 -412.570168)
		(end 75.936094 -412.860998)
		(stroke
			(width 0.07112)
			(type default)
		)
		(layer "In11.Cu")
	)
	(gr_line
		(start 76.243434 -416.49523)
		(end 76.285344 -416.920172)
		(stroke
			(width 0.07112)
			(type default)
		)
		(layer "In11.Cu")
	)
	(gr_line
		(start 76.285344 -416.920172)
		(end 76.162154 -417.070032)
		(stroke
			(width 0.07112)
			(type default)
		)
		(layer "In11.Cu")
	)
	(gr_line
		(start 76.382118 -402.86686)
		(end 76.204318 -402.7932)
		(stroke
			(width 0.07112)
			(type default)
		)
		(layer "In11.Cu")
	)
	(gr_line
		(start 76.743052 -402.26361)
		(end 76.095098 -402.531834)
		(stroke
			(width 0.07112)
			(type default)
		)
		(layer "In11.Cu")
	)
	(gr_line
		(start 76.77658 -402.703538)
		(end 76.382118 -402.86686)
		(stroke
			(width 0.07112)
			(type default)
		)
		(layer "In11.Cu")
	)
	(gr_line
		(start 76.850494 -402.525738)
		(end 76.77658 -402.703538)
		(stroke
			(width 0.07112)
			(type default)
		)
		(layer "In11.Cu")
	)
	(gr_line
		(start 76.964794 -421.253158)
		(end 76.969112 -421.275002)
		(stroke
			(width 0.07112)
			(type default)
		)
		(layer "In11.Cu")
	)
	(gr_arc
		(start 76.970128 -421.30472)
		(mid 76.969895 -421.289852)
		(end 76.969112 -421.275002)
		(stroke
			(width 0.07112)
			(type default)
		)
		(layer "In11.Cu")
	)
	(gr_line
		(start 76.970128 -421.30472)
		(end 76.970128 -421.308022)
		(stroke
			(width 0.07112)
			(type default)
		)
		(layer "In11.Cu")
	)
	(gr_line
		(start 77.185774 -406.71369)
		(end 76.894944 -407.00452)
		(stroke
			(width 0.07112)
			(type default)
		)
		(layer "In11.Cu")
	)
	(gr_line
		(start 77.196696 -377.040394)
		(end 77.19695 -377.040394)
		(stroke
			(width 0.07112)
			(type default)
		)
		(layer "In11.Cu")
	)
	(gr_line
		(start 77.399134 -376.844052)
		(end 77.399388 -376.844052)
		(stroke
			(width 0.07112)
			(type default)
		)
		(layer "In11.Cu")
	)
	(gr_line
		(start 77.42428 -402.435314)
		(end 77.24648 -402.361654)
		(stroke
			(width 0.07112)
			(type default)
		)
		(layer "In11.Cu")
	)
	(gr_line
		(start 77.467714 -406.71369)
		(end 77.758544 -407.00452)
		(stroke
			(width 0.07112)
			(type default)
		)
		(layer "In11.Cu")
	)
	(gr_line
		(start 77.522832 -431.430938)
		(end 77.650086 -431.558192)
		(stroke
			(width 0.07112)
			(type default)
		)
		(layer "In11.Cu")
	)
	(gr_line
		(start 77.522832 -431.148744)
		(end 77.650086 -431.02149)
		(stroke
			(width 0.07112)
			(type default)
		)
		(layer "In11.Cu")
	)
	(gr_line
		(start 77.650086 -431.558192)
		(end 77.650086 -431.889916)
		(stroke
			(width 0.07112)
			(type default)
		)
		(layer "In11.Cu")
	)
	(gr_line
		(start 77.650086 -431.02149)
		(end 77.650086 -430.689766)
		(stroke
			(width 0.07112)
			(type default)
		)
		(layer "In11.Cu")
	)
	(gr_line
		(start 77.785214 -401.832064)
		(end 77.13726 -402.100288)
		(stroke
			(width 0.07112)
			(type default)
		)
		(layer "In11.Cu")
	)
	(gr_line
		(start 77.818742 -402.271992)
		(end 77.42428 -402.435314)
		(stroke
			(width 0.07112)
			(type default)
		)
		(layer "In11.Cu")
	)
	(gr_line
		(start 77.892656 -402.093938)
		(end 77.818742 -402.271992)
		(stroke
			(width 0.07112)
			(type default)
		)
		(layer "In11.Cu")
	)
	(gr_line
		(start 78.354174 -372.970298)
		(end 78.354428 -372.970298)
		(stroke
			(width 0.07112)
			(type default)
		)
		(layer "In11.Cu")
	)
	(gr_line
		(start 78.35646 -379.995176)
		(end 78.35646 -379.802898)
		(stroke
			(width 0.07112)
			(type default)
		)
		(layer "In11.Cu")
	)
	(gr_line
		(start 78.426564 -412.570168)
		(end 78.717394 -412.860998)
		(stroke
			(width 0.07112)
			(type default)
		)
		(layer "In11.Cu")
	)
	(gr_line
		(start 78.617064 -375.449084)
		(end 78.602078 -375.415302)
		(stroke
			(width 0.07112)
			(type default)
		)
		(layer "In11.Cu")
	)
	(gr_arc
		(start 78.617064 -375.449084)
		(mid 78.619212 -375.453788)
		(end 78.621382 -375.458482)
		(stroke
			(width 0.07112)
			(type default)
		)
		(layer "In11.Cu")
	)
	(gr_line
		(start 78.652624 -375.492518)
		(end 78.621382 -375.458482)
		(stroke
			(width 0.07112)
			(type default)
		)
		(layer "In11.Cu")
	)
	(gr_line
		(start 78.658466 -380.297182)
		(end 78.35646 -379.995176)
		(stroke
			(width 0.07112)
			(type default)
		)
		(layer "In11.Cu")
	)
	(gr_line
		(start 78.71968 -414.07334)
		(end 78.73873 -414.458658)
		(stroke
			(width 0.07112)
			(type default)
		)
		(layer "In11.Cu")
	)
	(gr_line
		(start 78.73873 -414.458658)
		(end 78.77302 -415.15919)
		(stroke
			(width 0.07112)
			(type default)
		)
		(layer "In11.Cu")
	)
	(gr_line
		(start 78.781402 -415.328862)
		(end 78.794102 -415.585148)
		(stroke
			(width 0.07112)
			(type default)
		)
		(layer "In11.Cu")
	)
	(gr_line
		(start 78.794102 -415.585148)
		(end 78.828392 -416.28568)
		(stroke
			(width 0.07112)
			(type default)
		)
		(layer "In11.Cu")
	)
	(gr_line
		(start 78.83525 -416.425888)
		(end 78.849474 -416.713924)
		(stroke
			(width 0.07112)
			(type default)
		)
		(layer "In11.Cu")
	)
	(gr_line
		(start 78.849474 -416.713924)
		(end 78.883764 -417.414202)
		(stroke
			(width 0.07112)
			(type default)
		)
		(layer "In11.Cu")
	)
	(gr_line
		(start 78.850744 -380.297182)
		(end 78.658466 -380.297182)
		(stroke
			(width 0.07112)
			(type default)
		)
		(layer "In11.Cu")
	)
	(gr_line
		(start 78.91272 -418.000434)
		(end 78.94701 -418.700712)
		(stroke
			(width 0.07112)
			(type default)
		)
		(layer "In11.Cu")
	)
	(gr_line
		(start 78.963266 -402.948394)
		(end 78.778862 -402.892514)
		(stroke
			(width 0.07112)
			(type default)
		)
		(layer "In11.Cu")
	)
	(gr_line
		(start 79.001366 -414.059624)
		(end 79.020162 -414.444942)
		(stroke
			(width 0.07112)
			(type default)
		)
		(layer "In11.Cu")
	)
	(gr_line
		(start 79.021686 -414.446212)
		(end 79.16418 -414.575244)
		(stroke
			(width 0.07112)
			(type default)
		)
		(layer "In11.Cu")
	)
	(gr_line
		(start 79.051912 -380.097792)
		(end 78.55585 -379.60173)
		(stroke
			(width 0.07112)
			(type default)
		)
		(layer "In11.Cu")
	)
	(gr_line
		(start 79.063088 -415.315146)
		(end 79.075534 -415.571432)
		(stroke
			(width 0.07112)
			(type default)
		)
		(layer "In11.Cu")
	)
	(gr_line
		(start 79.076804 -415.572702)
		(end 79.219552 -415.701734)
		(stroke
			(width 0.07112)
			(type default)
		)
		(layer "In11.Cu")
	)
	(gr_line
		(start 79.116936 -416.412172)
		(end 79.130906 -416.700208)
		(stroke
			(width 0.07112)
			(type default)
		)
		(layer "In11.Cu")
	)
	(gr_line
		(start 79.13243 -416.701478)
		(end 79.274924 -416.83051)
		(stroke
			(width 0.07112)
			(type default)
		)
		(layer "In11.Cu")
	)
	(gr_line
		(start 79.15402 -380.792736)
		(end 79.15402 -380.600458)
		(stroke
			(width 0.07112)
			(type default)
		)
		(layer "In11.Cu")
	)
	(gr_line
		(start 79.16418 -414.575244)
		(end 79.185008 -415.00171)
		(stroke
			(width 0.07112)
			(type default)
		)
		(layer "In11.Cu")
	)
	(gr_line
		(start 79.185008 -415.00171)
		(end 79.055976 -415.144204)
		(stroke
			(width 0.07112)
			(type default)
		)
		(layer "In11.Cu")
	)
	(gr_line
		(start 79.195676 -417.987734)
		(end 79.338424 -418.116766)
		(stroke
			(width 0.07112)
			(type default)
		)
		(layer "In11.Cu")
	)
	(gr_line
		(start 79.202534 -373.679212)
		(end 79.20228 -373.677434)
		(stroke
			(width 0.07112)
			(type default)
		)
		(layer "In11.Cu")
	)
	(gr_line
		(start 79.219552 -415.701734)
		(end 79.24038 -416.1282)
		(stroke
			(width 0.07112)
			(type default)
		)
		(layer "In11.Cu")
	)
	(gr_line
		(start 79.24038 -416.1282)
		(end 79.111094 -416.270694)
		(stroke
			(width 0.07112)
			(type default)
		)
		(layer "In11.Cu")
	)
	(gr_line
		(start 79.262986 -402.312632)
		(end 78.644496 -402.64334)
		(stroke
			(width 0.07112)
			(type default)
		)
		(layer "In11.Cu")
	)
	(gr_line
		(start 79.274924 -416.83051)
		(end 79.296006 -417.256976)
		(stroke
			(width 0.07112)
			(type default)
		)
		(layer "In11.Cu")
	)
	(gr_line
		(start 79.290164 -412.570168)
		(end 78.999334 -412.860998)
		(stroke
			(width 0.07112)
			(type default)
		)
		(layer "In11.Cu")
	)
	(gr_line
		(start 79.296006 -417.256976)
		(end 79.16672 -417.39947)
		(stroke
			(width 0.07112)
			(type default)
		)
		(layer "In11.Cu")
	)
	(gr_line
		(start 79.338424 -418.116766)
		(end 79.359252 -418.543232)
		(stroke
			(width 0.07112)
			(type default)
		)
		(layer "In11.Cu")
	)
	(gr_line
		(start 79.339694 -402.747226)
		(end 78.963266 -402.948394)
		(stroke
			(width 0.07112)
			(type default)
		)
		(layer "In11.Cu")
	)
	(gr_line
		(start 79.359252 -418.543232)
		(end 79.229966 -418.68598)
		(stroke
			(width 0.07112)
			(type default)
		)
		(layer "In11.Cu")
	)
	(gr_line
		(start 79.395574 -402.562822)
		(end 79.339694 -402.747226)
		(stroke
			(width 0.07112)
			(type default)
		)
		(layer "In11.Cu")
	)
	(gr_line
		(start 79.456026 -381.094742)
		(end 79.15402 -380.792736)
		(stroke
			(width 0.07112)
			(type default)
		)
		(layer "In11.Cu")
	)
	(gr_line
		(start 79.49946 -430.125632)
		(end 79.523082 -430.125632)
		(stroke
			(width 0.07112)
			(type default)
		)
		(layer "In11.Cu")
	)
	(gr_line
		(start 79.50073 -430.408842)
		(end 79.650082 -430.558194)
		(stroke
			(width 0.07112)
			(type default)
		)
		(layer "In11.Cu")
	)
	(gr_line
		(start 79.523082 -430.125632)
		(end 79.650082 -429.998632)
		(stroke
			(width 0.07112)
			(type default)
		)
		(layer "In11.Cu")
	)
	(gr_line
		(start 79.648304 -381.094742)
		(end 79.456026 -381.094742)
		(stroke
			(width 0.07112)
			(type default)
		)
		(layer "In11.Cu")
	)
	(gr_line
		(start 79.650082 -430.558194)
		(end 79.650082 -430.889918)
		(stroke
			(width 0.07112)
			(type default)
		)
		(layer "In11.Cu")
	)
	(gr_line
		(start 79.650082 -429.998632)
		(end 79.650082 -429.689768)
		(stroke
			(width 0.07112)
			(type default)
		)
		(layer "In11.Cu")
	)
	(gr_line
		(start 79.849472 -380.895352)
		(end 79.35341 -380.39929)
		(stroke
			(width 0.07112)
			(type default)
		)
		(layer "In11.Cu")
	)
	(gr_line
		(start 79.95158 -381.590296)
		(end 79.95158 -381.398018)
		(stroke
			(width 0.07112)
			(type default)
		)
		(layer "In11.Cu")
	)
	(gr_line
		(start 80.024732 -368.54003)
		(end 80.271366 -368.191288)
		(stroke
			(width 0.07112)
			(type default)
		)
		(layer "In11.Cu")
	)
	(gr_line
		(start 80.057244 -368.729768)
		(end 80.024732 -368.54003)
		(stroke
			(width 0.07112)
			(type default)
		)
		(layer "In11.Cu")
	)
	(gr_line
		(start 80.249014 -406.71369)
		(end 79.958184 -407.00452)
		(stroke
			(width 0.07112)
			(type default)
		)
		(layer "In11.Cu")
	)
	(gr_line
		(start 80.253586 -381.892302)
		(end 79.95158 -381.590296)
		(stroke
			(width 0.07112)
			(type default)
		)
		(layer "In11.Cu")
	)
	(gr_line
		(start 80.271366 -368.191288)
		(end 80.461104 -368.158776)
		(stroke
			(width 0.07112)
			(type default)
		)
		(layer "In11.Cu")
	)
	(gr_line
		(start 80.28813 -368.894106)
		(end 80.693006 -368.321336)
		(stroke
			(width 0.07112)
			(type default)
		)
		(layer "In11.Cu")
	)
	(gr_line
		(start 80.319118 -388.774432)
		(end 80.364584 -388.819898)
		(stroke
			(width 0.07112)
			(type default)
		)
		(layer "In11.Cu")
	)
	(gr_line
		(start 80.319118 -385.31038)
		(end 80.672432 -385.405376)
		(stroke
			(width 0.07112)
			(type default)
		)
		(layer "In11.Cu")
	)
	(gr_line
		(start 80.364584 -388.999984)
		(end 80.219296 -389.145272)
		(stroke
			(width 0.07112)
			(type default)
		)
		(layer "In11.Cu")
	)
	(gr_line
		(start 80.364584 -388.819898)
		(end 80.364584 -388.999984)
		(stroke
			(width 0.07112)
			(type default)
		)
		(layer "In11.Cu")
	)
	(gr_line
		(start 80.445864 -381.892302)
		(end 80.253586 -381.892302)
		(stroke
			(width 0.07112)
			(type default)
		)
		(layer "In11.Cu")
	)
	(gr_line
		(start 80.515206 -365.355632)
		(end 80.563466 -365.169196)
		(stroke
			(width 0.07112)
			(type default)
		)
		(layer "In11.Cu")
	)
	(gr_line
		(start 80.530954 -406.71369)
		(end 80.821784 -407.00452)
		(stroke
			(width 0.07112)
			(type default)
		)
		(layer "In11.Cu")
	)
	(gr_line
		(start 80.563466 -365.169196)
		(end 80.931766 -364.953042)
		(stroke
			(width 0.07112)
			(type default)
		)
		(layer "In11.Cu")
	)
	(gr_line
		(start 80.596486 -389.344662)
		(end 80.420464 -389.344662)
		(stroke
			(width 0.07112)
			(type default)
		)
		(layer "In11.Cu")
	)
	(gr_line
		(start 80.647032 -381.692912)
		(end 80.15097 -381.19685)
		(stroke
			(width 0.07112)
			(type default)
		)
		(layer "In11.Cu")
	)
	(gr_line
		(start 80.657446 -365.600488)
		(end 81.262474 -365.245396)
		(stroke
			(width 0.07112)
			(type default)
		)
		(layer "In11.Cu")
	)
	(gr_line
		(start 80.672432 -385.405376)
		(end 80.67294 -385.404868)
		(stroke
			(width 0.07112)
			(type default)
		)
		(layer "In11.Cu")
	)
	(gr_line
		(start 80.675734 -367.619026)
		(end 80.922368 -367.270284)
		(stroke
			(width 0.07112)
			(type default)
		)
		(layer "In11.Cu")
	)
	(gr_line
		(start 80.708246 -367.809018)
		(end 80.675734 -367.619026)
		(stroke
			(width 0.07112)
			(type default)
		)
		(layer "In11.Cu")
	)
	(gr_line
		(start 80.719168 -389.467344)
		(end 80.596486 -389.344662)
		(stroke
			(width 0.07112)
			(type default)
		)
		(layer "In11.Cu")
	)
	(gr_line
		(start 80.719168 -386.003292)
		(end 80.81391 -385.649724)
		(stroke
			(width 0.07112)
			(type default)
		)
		(layer "In11.Cu")
	)
	(gr_line
		(start 80.922368 -367.270284)
		(end 81.11236 -367.237772)
		(stroke
			(width 0.07112)
			(type default)
		)
		(layer "In11.Cu")
	)
	(gr_line
		(start 80.931766 -364.953042)
		(end 81.118202 -365.001556)
		(stroke
			(width 0.07112)
			(type default)
		)
		(layer "In11.Cu")
	)
	(gr_line
		(start 80.935576 -385.579112)
		(end 80.988408 -385.548632)
		(stroke
			(width 0.07112)
			(type default)
		)
		(layer "In11.Cu")
	)
	(gr_line
		(start 80.939132 -367.973356)
		(end 81.344008 -367.400332)
		(stroke
			(width 0.07112)
			(type default)
		)
		(layer "In11.Cu")
	)
	(gr_line
		(start 80.988408 -385.548632)
		(end 81.076546 -385.460494)
		(stroke
			(width 0.07112)
			(type default)
		)
		(layer "In11.Cu")
	)
	(gr_line
		(start 81.076546 -385.460494)
		(end 81.076546 -385.334764)
		(stroke
			(width 0.07112)
			(type default)
		)
		(layer "In11.Cu")
	)
	(gr_line
		(start 81.32699 -366.698022)
		(end 81.573624 -366.34928)
		(stroke
			(width 0.07112)
			(type default)
		)
		(layer "In11.Cu")
	)
	(gr_line
		(start 81.359502 -366.888014)
		(end 81.32699 -366.698022)
		(stroke
			(width 0.07112)
			(type default)
		)
		(layer "In11.Cu")
	)
	(gr_line
		(start 81.480914 -401.876006)
		(end 81.307432 -401.793202)
		(stroke
			(width 0.07112)
			(type default)
		)
		(layer "In11.Cu")
	)
	(gr_line
		(start 81.48193 -397.420846)
		(end 81.471008 -397.425418)
		(stroke
			(width 0.07112)
			(type default)
		)
		(layer "In11.Cu")
	)
	(gr_line
		(start 81.487518 -364.78464)
		(end 81.536286 -364.59795)
		(stroke
			(width 0.07112)
			(type default)
		)
		(layer "In11.Cu")
	)
	(gr_line
		(start 81.48955 -402.865082)
		(end 81.48955 -402.86559)
		(stroke
			(width 0.07112)
			(type default)
		)
		(layer "In11.Cu")
	)
	(gr_line
		(start 81.489804 -412.570168)
		(end 81.780634 -412.860998)
		(stroke
			(width 0.07112)
			(type default)
		)
		(layer "In11.Cu")
	)
	(gr_line
		(start 81.513172 -431.139346)
		(end 81.532222 -431.139346)
		(stroke
			(width 0.07112)
			(type default)
		)
		(layer "In11.Cu")
	)
	(gr_line
		(start 81.514188 -416.713162)
		(end 81.445608 -417.411916)
		(stroke
			(width 0.07112)
			(type default)
		)
		(layer "In11.Cu")
	)
	(gr_line
		(start 81.514442 -431.422556)
		(end 81.650078 -431.558192)
		(stroke
			(width 0.07112)
			(type default)
		)
		(layer "In11.Cu")
	)
	(gr_line
		(start 81.519014 -388.774432)
		(end 81.571338 -388.826756)
		(stroke
			(width 0.07112)
			(type default)
		)
		(layer "In11.Cu")
	)
	(gr_line
		(start 81.519014 -385.31038)
		(end 81.872328 -385.405376)
		(stroke
			(width 0.07112)
			(type default)
		)
		(layer "In11.Cu")
	)
	(gr_line
		(start 81.532222 -431.139346)
		(end 81.650078 -431.02149)
		(stroke
			(width 0.07112)
			(type default)
		)
		(layer "In11.Cu")
	)
	(gr_line
		(start 81.536286 -364.59795)
		(end 81.904332 -364.381796)
		(stroke
			(width 0.07112)
			(type default)
		)
		(layer "In11.Cu")
	)
	(gr_line
		(start 81.571338 -389.006588)
		(end 81.42478 -389.153146)
		(stroke
			(width 0.07112)
			(type default)
		)
		(layer "In11.Cu")
	)
	(gr_line
		(start 81.571338 -388.826756)
		(end 81.571338 -389.006588)
		(stroke
			(width 0.07112)
			(type default)
		)
		(layer "In11.Cu")
	)
	(gr_line
		(start 81.573624 -366.34928)
		(end 81.763362 -366.316768)
		(stroke
			(width 0.07112)
			(type default)
		)
		(layer "In11.Cu")
	)
	(gr_line
		(start 81.590388 -367.052098)
		(end 81.995264 -366.479328)
		(stroke
			(width 0.07112)
			(type default)
		)
		(layer "In11.Cu")
	)
	(gr_line
		(start 81.601818 -397.67764)
		(end 81.592928 -397.681196)
		(stroke
			(width 0.07112)
			(type default)
		)
		(layer "In11.Cu")
	)
	(gr_line
		(start 81.630266 -365.029496)
		(end 82.235294 -364.67415)
		(stroke
			(width 0.07112)
			(type default)
		)
		(layer "In11.Cu")
	)
	(gr_line
		(start 81.650078 -431.558192)
		(end 81.650078 -431.889916)
		(stroke
			(width 0.07112)
			(type default)
		)
		(layer "In11.Cu")
	)
	(gr_line
		(start 81.650078 -431.02149)
		(end 81.650078 -430.689766)
		(stroke
			(width 0.07112)
			(type default)
		)
		(layer "In11.Cu")
	)
	(gr_line
		(start 81.677764 -415.051494)
		(end 81.609184 -415.749232)
		(stroke
			(width 0.07112)
			(type default)
		)
		(layer "In11.Cu")
	)
	(gr_line
		(start 81.680812 -384.416046)
		(end 81.682336 -384.234944)
		(stroke
			(width 0.07112)
			(type default)
		)
		(layer "In11.Cu")
	)
	(gr_line
		(start 81.682336 -384.234944)
		(end 81.809082 -384.108198)
		(stroke
			(width 0.07112)
			(type default)
		)
		(layer "In11.Cu")
	)
	(gr_line
		(start 81.726532 -417.438586)
		(end 81.726278 -417.438586)
		(stroke
			(width 0.07112)
			(type default)
		)
		(layer "In11.Cu")
	)
	(gr_line
		(start 81.78038 -414.0073)
		(end 81.780634 -414.007046)
		(stroke
			(width 0.07112)
			(type default)
		)
		(layer "In11.Cu")
	)
	(gr_line
		(start 81.796128 -416.742118)
		(end 81.918302 -416.890708)
		(stroke
			(width 0.07112)
			(type default)
		)
		(layer "In11.Cu")
	)
	(gr_line
		(start 81.797652 -403.181058)
		(end 81.615026 -403.118828)
		(stroke
			(width 0.07112)
			(type default)
		)
		(layer "In11.Cu")
	)
	(gr_line
		(start 81.804256 -389.352536)
		(end 81.625948 -389.352536)
		(stroke
			(width 0.07112)
			(type default)
		)
		(layer "In11.Cu")
	)
	(gr_line
		(start 81.872328 -385.405376)
		(end 81.872836 -385.404868)
		(stroke
			(width 0.07112)
			(type default)
		)
		(layer "In11.Cu")
	)
	(gr_line
		(start 81.87309 -401.292568)
		(end 81.211928 -401.526502)
		(stroke
			(width 0.07112)
			(type default)
		)
		(layer "In11.Cu")
	)
	(gr_line
		(start 81.876392 -417.31565)
		(end 81.727802 -417.437316)
		(stroke
			(width 0.07112)
			(type default)
		)
		(layer "In11.Cu")
	)
	(gr_line
		(start 81.883504 -401.733766)
		(end 81.480914 -401.876006)
		(stroke
			(width 0.07112)
			(type default)
		)
		(layer "In11.Cu")
	)
	(gr_line
		(start 81.904332 -364.381796)
		(end 82.090768 -364.430564)
		(stroke
			(width 0.07112)
			(type default)
		)
		(layer "In11.Cu")
	)
	(gr_line
		(start 81.918302 -416.890708)
		(end 81.876392 -417.31565)
		(stroke
			(width 0.07112)
			(type default)
		)
		(layer "In11.Cu")
	)
	(gr_line
		(start 81.919064 -389.467344)
		(end 81.804256 -389.352536)
		(stroke
			(width 0.07112)
			(type default)
		)
		(layer "In11.Cu")
	)
	(gr_line
		(start 81.919064 -386.003292)
		(end 82.013806 -385.649724)
		(stroke
			(width 0.07112)
			(type default)
		)
		(layer "In11.Cu")
	)
	(gr_line
		(start 81.95945 -415.080196)
		(end 82.081624 -415.22904)
		(stroke
			(width 0.07112)
			(type default)
		)
		(layer "In11.Cu")
	)
	(gr_line
		(start 81.966308 -401.56003)
		(end 81.883504 -401.733766)
		(stroke
			(width 0.07112)
			(type default)
		)
		(layer "In11.Cu")
	)
	(gr_arc
		(start 82.017616 -384.300222)
		(mid 81.98142 -384.360699)
		(end 81.964022 -384.429)
		(stroke
			(width 0.07112)
			(type default)
		)
		(layer "In11.Cu")
	)
	(gr_line
		(start 82.039968 -415.653982)
		(end 81.891124 -415.775902)
		(stroke
			(width 0.07112)
			(type default)
		)
		(layer "In11.Cu")
	)
	(gr_line
		(start 82.062574 -414.02127)
		(end 82.061304 -414.034986)
		(stroke
			(width 0.07112)
			(type default)
		)
		(layer "In11.Cu")
	)
	(gr_line
		(start 82.062574 -414.007046)
		(end 82.062574 -414.02127)
		(stroke
			(width 0.07112)
			(type default)
		)
		(layer "In11.Cu")
	)
	(gr_line
		(start 82.081624 -415.22904)
		(end 82.039968 -415.653982)
		(stroke
			(width 0.07112)
			(type default)
		)
		(layer "In11.Cu")
	)
	(gr_line
		(start 82.118962 -402.555964)
		(end 81.48955 -402.865082)
		(stroke
			(width 0.07112)
			(type default)
		)
		(layer "In11.Cu")
	)
	(gr_line
		(start 82.135472 -385.579112)
		(end 82.188304 -385.548632)
		(stroke
			(width 0.07112)
			(type default)
		)
		(layer "In11.Cu")
	)
	(gr_line
		(start 82.180938 -402.993098)
		(end 81.797652 -403.181058)
		(stroke
			(width 0.07112)
			(type default)
		)
		(layer "In11.Cu")
	)
	(gr_line
		(start 82.188304 -385.548632)
		(end 82.276442 -385.460494)
		(stroke
			(width 0.07112)
			(type default)
		)
		(layer "In11.Cu")
	)
	(gr_line
		(start 82.242914 -402.810472)
		(end 82.180938 -402.993098)
		(stroke
			(width 0.07112)
			(type default)
		)
		(layer "In11.Cu")
	)
	(gr_line
		(start 82.276442 -385.460494)
		(end 82.276442 -385.334764)
		(stroke
			(width 0.07112)
			(type default)
		)
		(layer "In11.Cu")
	)
	(gr_line
		(start 82.353404 -412.570168)
		(end 82.062574 -412.860998)
		(stroke
			(width 0.07112)
			(type default)
		)
		(layer "In11.Cu")
	)
	(gr_line
		(start 82.719164 -388.774432)
		(end 82.770472 -388.82574)
		(stroke
			(width 0.07112)
			(type default)
		)
		(layer "In11.Cu")
	)
	(gr_line
		(start 82.719164 -385.31038)
		(end 83.072224 -385.405376)
		(stroke
			(width 0.07112)
			(type default)
		)
		(layer "In11.Cu")
	)
	(gr_line
		(start 82.770472 -389.035544)
		(end 82.653886 -389.15213)
		(stroke
			(width 0.07112)
			(type default)
		)
		(layer "In11.Cu")
	)
	(gr_line
		(start 82.770472 -388.82574)
		(end 82.770472 -389.035544)
		(stroke
			(width 0.07112)
			(type default)
		)
		(layer "In11.Cu")
	)
	(gr_line
		(start 82.809842 -402.683726)
		(end 82.62747 -402.62175)
		(stroke
			(width 0.07112)
			(type default)
		)
		(layer "In11.Cu")
	)
	(gr_line
		(start 83.003136 -389.35152)
		(end 82.855054 -389.35152)
		(stroke
			(width 0.07112)
			(type default)
		)
		(layer "In11.Cu")
	)
	(gr_line
		(start 83.072224 -385.405376)
		(end 83.072732 -385.404868)
		(stroke
			(width 0.07112)
			(type default)
		)
		(layer "In11.Cu")
	)
	(gr_line
		(start 83.11896 -389.467344)
		(end 83.003136 -389.35152)
		(stroke
			(width 0.07112)
			(type default)
		)
		(layer "In11.Cu")
	)
	(gr_line
		(start 83.11896 -386.003292)
		(end 83.213702 -385.649724)
		(stroke
			(width 0.07112)
			(type default)
		)
		(layer "In11.Cu")
	)
	(gr_line
		(start 83.131406 -402.058632)
		(end 82.50174 -402.36775)
		(stroke
			(width 0.07112)
			(type default)
		)
		(layer "In11.Cu")
	)
	(gr_line
		(start 83.193128 -402.495766)
		(end 82.809842 -402.683726)
		(stroke
			(width 0.07112)
			(type default)
		)
		(layer "In11.Cu")
	)
	(gr_line
		(start 83.255358 -402.31314)
		(end 83.193128 -402.495766)
		(stroke
			(width 0.07112)
			(type default)
		)
		(layer "In11.Cu")
	)
	(gr_line
		(start 83.312254 -406.71369)
		(end 83.021424 -407.00452)
		(stroke
			(width 0.07112)
			(type default)
		)
		(layer "In11.Cu")
	)
	(gr_line
		(start 83.335368 -385.579112)
		(end 83.3882 -385.548632)
		(stroke
			(width 0.07112)
			(type default)
		)
		(layer "In11.Cu")
	)
	(gr_line
		(start 83.3882 -385.548632)
		(end 83.476338 -385.460494)
		(stroke
			(width 0.07112)
			(type default)
		)
		(layer "In11.Cu")
	)
	(gr_line
		(start 83.476338 -385.460494)
		(end 83.476338 -385.334764)
		(stroke
			(width 0.07112)
			(type default)
		)
		(layer "In11.Cu")
	)
	(gr_line
		(start 83.499452 -430.125632)
		(end 83.523074 -430.125632)
		(stroke
			(width 0.07112)
			(type default)
		)
		(layer "In11.Cu")
	)
	(gr_line
		(start 83.500722 -430.408842)
		(end 83.650074 -430.558194)
		(stroke
			(width 0.07112)
			(type default)
		)
		(layer "In11.Cu")
	)
	(gr_arc
		(start 83.515962 -367.457736)
		(mid 83.508065 -367.463675)
		(end 83.500214 -367.469674)
		(stroke
			(width 0.07112)
			(type default)
		)
		(layer "In11.Cu")
	)
	(gr_line
		(start 83.515962 -367.457736)
		(end 83.516978 -367.456974)
		(stroke
			(width 0.07112)
			(type default)
		)
		(layer "In11.Cu")
	)
	(gr_line
		(start 83.516978 -367.456974)
		(end 83.533234 -367.44783)
		(stroke
			(width 0.07112)
			(type default)
		)
		(layer "In11.Cu")
	)
	(gr_line
		(start 83.523074 -430.125632)
		(end 83.650074 -429.998632)
		(stroke
			(width 0.07112)
			(type default)
		)
		(layer "In11.Cu")
	)
	(gr_line
		(start 83.594194 -406.71369)
		(end 83.885024 -407.00452)
		(stroke
			(width 0.07112)
			(type default)
		)
		(layer "In11.Cu")
	)
	(gr_line
		(start 83.650074 -430.558194)
		(end 83.650074 -430.889918)
		(stroke
			(width 0.07112)
			(type default)
		)
		(layer "In11.Cu")
	)
	(gr_line
		(start 83.650074 -429.998632)
		(end 83.650074 -429.689768)
		(stroke
			(width 0.07112)
			(type default)
		)
		(layer "In11.Cu")
	)
	(gr_line
		(start 83.8454 -418.19449)
		(end 83.69173 -418.878766)
		(stroke
			(width 0.07112)
			(type default)
		)
		(layer "In11.Cu")
	)
	(gr_line
		(start 83.91906 -388.774432)
		(end 83.971384 -388.826756)
		(stroke
			(width 0.07112)
			(type default)
		)
		(layer "In11.Cu")
	)
	(gr_line
		(start 83.91906 -385.31038)
		(end 84.272374 -385.405376)
		(stroke
			(width 0.07112)
			(type default)
		)
		(layer "In11.Cu")
	)
	(gr_line
		(start 83.94954 -365.918242)
		(end 84.001864 -365.732822)
		(stroke
			(width 0.07112)
			(type default)
		)
		(layer "In11.Cu")
	)
	(gr_line
		(start 83.971384 -389.006588)
		(end 83.824826 -389.153146)
		(stroke
			(width 0.07112)
			(type default)
		)
		(layer "In11.Cu")
	)
	(gr_line
		(start 83.971384 -388.826756)
		(end 83.971384 -389.006588)
		(stroke
			(width 0.07112)
			(type default)
		)
		(layer "In11.Cu")
	)
	(gr_line
		(start 84.001864 -365.732822)
		(end 84.374482 -365.524542)
		(stroke
			(width 0.07112)
			(type default)
		)
		(layer "In11.Cu")
	)
	(gr_line
		(start 84.086954 -366.165892)
		(end 84.69884 -365.823246)
		(stroke
			(width 0.07112)
			(type default)
		)
		(layer "In11.Cu")
	)
	(gr_line
		(start 84.121244 -418.257736)
		(end 84.224368 -418.420042)
		(stroke
			(width 0.07112)
			(type default)
		)
		(layer "In11.Cu")
	)
	(gr_line
		(start 84.130896 -418.836856)
		(end 83.968082 -418.939726)
		(stroke
			(width 0.07112)
			(type default)
		)
		(layer "In11.Cu")
	)
	(gr_line
		(start 84.184744 -416.68319)
		(end 84.03209 -417.362386)
		(stroke
			(width 0.07112)
			(type default)
		)
		(layer "In11.Cu")
	)
	(gr_line
		(start 84.184998 -416.682682)
		(end 84.184744 -416.68319)
		(stroke
			(width 0.07112)
			(type default)
		)
		(layer "In11.Cu")
	)
	(gr_line
		(start 84.204302 -389.352536)
		(end 84.025994 -389.352536)
		(stroke
			(width 0.07112)
			(type default)
		)
		(layer "In11.Cu")
	)
	(gr_line
		(start 84.224368 -418.420042)
		(end 84.130896 -418.836856)
		(stroke
			(width 0.07112)
			(type default)
		)
		(layer "In11.Cu")
	)
	(gr_line
		(start 84.272374 -385.405376)
		(end 84.272882 -385.404868)
		(stroke
			(width 0.07112)
			(type default)
		)
		(layer "In11.Cu")
	)
	(gr_arc
		(start 84.295488 -390.175496)
		(mid 84.295488 -390.175877)
		(end 84.295488 -390.176258)
		(stroke
			(width 0.07112)
			(type default)
		)
		(layer "In11.Cu")
	)
	(gr_line
		(start 84.305902 -417.430712)
		(end 84.305648 -417.431728)
		(stroke
			(width 0.07112)
			(type default)
		)
		(layer "In11.Cu")
	)
	(gr_line
		(start 84.30641 -417.430458)
		(end 84.305902 -417.430712)
		(stroke
			(width 0.07112)
			(type default)
		)
		(layer "In11.Cu")
	)
	(gr_line
		(start 84.31911 -389.467344)
		(end 84.204302 -389.352536)
		(stroke
			(width 0.07112)
			(type default)
		)
		(layer "In11.Cu")
	)
	(gr_line
		(start 84.31911 -386.003292)
		(end 84.413852 -385.649724)
		(stroke
			(width 0.07112)
			(type default)
		)
		(layer "In11.Cu")
	)
	(gr_line
		(start 84.356448 -415.918396)
		(end 84.356194 -415.919412)
		(stroke
			(width 0.07112)
			(type default)
		)
		(layer "In11.Cu")
	)
	(gr_line
		(start 84.374482 -365.524542)
		(end 84.559648 -365.576612)
		(stroke
			(width 0.07112)
			(type default)
		)
		(layer "In11.Cu")
	)
	(gr_line
		(start 84.460334 -416.744404)
		(end 84.46008 -416.745166)
		(stroke
			(width 0.07112)
			(type default)
		)
		(layer "In11.Cu")
	)
	(gr_line
		(start 84.460588 -416.747452)
		(end 84.563458 -416.910266)
		(stroke
			(width 0.07112)
			(type default)
		)
		(layer "In11.Cu")
	)
	(gr_line
		(start 84.469986 -417.326826)
		(end 84.307426 -417.429696)
		(stroke
			(width 0.07112)
			(type default)
		)
		(layer "In11.Cu")
	)
	(gr_line
		(start 84.509864 -415.23539)
		(end 84.356448 -415.918396)
		(stroke
			(width 0.07112)
			(type default)
		)
		(layer "In11.Cu")
	)
	(gr_line
		(start 84.510118 -415.234882)
		(end 84.509864 -415.23539)
		(stroke
			(width 0.07112)
			(type default)
		)
		(layer "In11.Cu")
	)
	(gr_line
		(start 84.535518 -385.579112)
		(end 84.58835 -385.548632)
		(stroke
			(width 0.07112)
			(type default)
		)
		(layer "In11.Cu")
	)
	(gr_line
		(start 84.553044 -412.570168)
		(end 84.843874 -412.860998)
		(stroke
			(width 0.07112)
			(type default)
		)
		(layer "In11.Cu")
	)
	(gr_line
		(start 84.563458 -416.910266)
		(end 84.469986 -417.326826)
		(stroke
			(width 0.07112)
			(type default)
		)
		(layer "In11.Cu")
	)
	(gr_line
		(start 84.58835 -385.548632)
		(end 84.676488 -385.460494)
		(stroke
			(width 0.07112)
			(type default)
		)
		(layer "In11.Cu")
	)
	(gr_line
		(start 84.604606 -414.812988)
		(end 84.603336 -414.819592)
		(stroke
			(width 0.07112)
			(type default)
		)
		(layer "In11.Cu")
	)
	(gr_line
		(start 84.632292 -415.980372)
		(end 84.63153 -415.98088)
		(stroke
			(width 0.07112)
			(type default)
		)
		(layer "In11.Cu")
	)
	(gr_line
		(start 84.66836 -381.829564)
		(end 84.66836 -381.829056)
		(stroke
			(width 0.07112)
			(type default)
		)
		(layer "In11.Cu")
	)
	(gr_line
		(start 84.676488 -385.460494)
		(end 84.676488 -385.334764)
		(stroke
			(width 0.07112)
			(type default)
		)
		(layer "In11.Cu")
	)
	(gr_line
		(start 84.757006 -414.1343)
		(end 84.60486 -414.811972)
		(stroke
			(width 0.07112)
			(type default)
		)
		(layer "In11.Cu")
	)
	(gr_line
		(start 84.7852 -415.296604)
		(end 84.785708 -415.297366)
		(stroke
			(width 0.07112)
			(type default)
		)
		(layer "In11.Cu")
	)
	(gr_line
		(start 84.785962 -415.297874)
		(end 84.889086 -415.460434)
		(stroke
			(width 0.07112)
			(type default)
		)
		(layer "In11.Cu")
	)
	(gr_line
		(start 84.795614 -415.876994)
		(end 84.6328 -415.980118)
		(stroke
			(width 0.07112)
			(type default)
		)
		(layer "In11.Cu")
	)
	(gr_line
		(start 84.83727 -413.776414)
		(end 84.83727 -413.776668)
		(stroke
			(width 0.07112)
			(type default)
		)
		(layer "In11.Cu")
	)
	(gr_line
		(start 84.889086 -415.460434)
		(end 84.795614 -415.876994)
		(stroke
			(width 0.07112)
			(type default)
		)
		(layer "In11.Cu")
	)
	(gr_line
		(start 84.93379 -365.367316)
		(end 84.986114 -365.181896)
		(stroke
			(width 0.07112)
			(type default)
		)
		(layer "In11.Cu")
	)
	(gr_line
		(start 84.936838 -399.02003)
		(end 84.937092 -399.02003)
		(stroke
			(width 0.07112)
			(type default)
		)
		(layer "In11.Cu")
	)
	(gr_line
		(start 84.957666 -366.635538)
		(end 85.008466 -366.449864)
		(stroke
			(width 0.07112)
			(type default)
		)
		(layer "In11.Cu")
	)
	(gr_line
		(start 84.970366 -424.931586)
		(end 84.970112 -424.931332)
		(stroke
			(width 0.07112)
			(type default)
		)
		(layer "In11.Cu")
	)
	(gr_line
		(start 84.986114 -365.181896)
		(end 85.358732 -364.973362)
		(stroke
			(width 0.07112)
			(type default)
		)
		(layer "In11.Cu")
	)
	(gr_line
		(start 85.008466 -366.449864)
		(end 85.37956 -366.23879)
		(stroke
			(width 0.07112)
			(type default)
		)
		(layer "In11.Cu")
	)
	(gr_line
		(start 85.033104 -414.197292)
		(end 85.136228 -414.359852)
		(stroke
			(width 0.07112)
			(type default)
		)
		(layer "In11.Cu")
	)
	(gr_line
		(start 85.042756 -414.776412)
		(end 84.879942 -414.879536)
		(stroke
			(width 0.07112)
			(type default)
		)
		(layer "In11.Cu")
	)
	(gr_line
		(start 85.07095 -365.614966)
		(end 85.68309 -365.27232)
		(stroke
			(width 0.07112)
			(type default)
		)
		(layer "In11.Cu")
	)
	(gr_line
		(start 85.096604 -366.882426)
		(end 85.70595 -366.535462)
		(stroke
			(width 0.07112)
			(type default)
		)
		(layer "In11.Cu")
	)
	(gr_line
		(start 85.118956 -388.774432)
		(end 85.143594 -388.79907)
		(stroke
			(width 0.07112)
			(type default)
		)
		(layer "In11.Cu")
	)
	(gr_line
		(start 85.118956 -385.31038)
		(end 85.47227 -385.405376)
		(stroke
			(width 0.07112)
			(type default)
		)
		(layer "In11.Cu")
	)
	(gr_line
		(start 85.125814 -413.719518)
		(end 85.125814 -413.720534)
		(stroke
			(width 0.07112)
			(type default)
		)
		(layer "In11.Cu")
	)
	(gr_line
		(start 85.136228 -414.359852)
		(end 85.042756 -414.776412)
		(stroke
			(width 0.07112)
			(type default)
		)
		(layer "In11.Cu")
	)
	(gr_line
		(start 85.143594 -388.978902)
		(end 84.96935 -389.153146)
		(stroke
			(width 0.07112)
			(type default)
		)
		(layer "In11.Cu")
	)
	(gr_line
		(start 85.143594 -388.79907)
		(end 85.143594 -388.978902)
		(stroke
			(width 0.07112)
			(type default)
		)
		(layer "In11.Cu")
	)
	(gr_line
		(start 85.238336 -378.114052)
		(end 85.320378 -377.939808)
		(stroke
			(width 0.07112)
			(type default)
		)
		(layer "In11.Cu")
	)
	(gr_line
		(start 85.358732 -364.973362)
		(end 85.543898 -365.025686)
		(stroke
			(width 0.07112)
			(type default)
		)
		(layer "In11.Cu")
	)
	(gr_line
		(start 85.37956 -366.23879)
		(end 85.56498 -366.289844)
		(stroke
			(width 0.07112)
			(type default)
		)
		(layer "In11.Cu")
	)
	(gr_line
		(start 85.382608 -378.51588)
		(end 85.238336 -378.114052)
		(stroke
			(width 0.07112)
			(type default)
		)
		(layer "In11.Cu")
	)
	(gr_line
		(start 85.404198 -389.352536)
		(end 85.170518 -389.352536)
		(stroke
			(width 0.07112)
			(type default)
		)
		(layer "In11.Cu")
	)
	(gr_line
		(start 85.416644 -412.570168)
		(end 85.125814 -412.860998)
		(stroke
			(width 0.07112)
			(type default)
		)
		(layer "In11.Cu")
	)
	(gr_line
		(start 85.47227 -385.405376)
		(end 85.472778 -385.404868)
		(stroke
			(width 0.07112)
			(type default)
		)
		(layer "In11.Cu")
	)
	(gr_line
		(start 85.519006 -389.467344)
		(end 85.404198 -389.352536)
		(stroke
			(width 0.07112)
			(type default)
		)
		(layer "In11.Cu")
	)
	(gr_line
		(start 85.519006 -386.003292)
		(end 85.613748 -385.649724)
		(stroke
			(width 0.07112)
			(type default)
		)
		(layer "In11.Cu")
	)
	(gr_line
		(start 85.522816 -431.430938)
		(end 85.65007 -431.558192)
		(stroke
			(width 0.07112)
			(type default)
		)
		(layer "In11.Cu")
	)
	(gr_line
		(start 85.522816 -431.148744)
		(end 85.65007 -431.02149)
		(stroke
			(width 0.07112)
			(type default)
		)
		(layer "In11.Cu")
	)
	(gr_line
		(start 85.556852 -378.597668)
		(end 85.382608 -378.51588)
		(stroke
			(width 0.07112)
			(type default)
		)
		(layer "In11.Cu")
	)
	(gr_line
		(start 85.558122 -378.59843)
		(end 85.558376 -378.59843)
		(stroke
			(width 0.07112)
			(type default)
		)
		(layer "In11.Cu")
	)
	(gr_line
		(start 85.558376 -378.59843)
		(end 85.557868 -378.598176)
		(stroke
			(width 0.07112)
			(type default)
		)
		(layer "In11.Cu")
	)
	(gr_line
		(start 85.5599 -378.603764)
		(end 85.558122 -378.59843)
		(stroke
			(width 0.07112)
			(type default)
		)
		(layer "In11.Cu")
	)
	(gr_line
		(start 85.58657 -377.842526)
		(end 85.584538 -377.836684)
		(stroke
			(width 0.07112)
			(type default)
		)
		(layer "In11.Cu")
	)
	(gr_line
		(start 85.61959 -379.175518)
		(end 85.701632 -379.001528)
		(stroke
			(width 0.07112)
			(type default)
		)
		(layer "In11.Cu")
	)
	(gr_line
		(start 85.65007 -431.558192)
		(end 85.65007 -431.889916)
		(stroke
			(width 0.07112)
			(type default)
		)
		(layer "In11.Cu")
	)
	(gr_line
		(start 85.65007 -431.02149)
		(end 85.65007 -430.689766)
		(stroke
			(width 0.07112)
			(type default)
		)
		(layer "In11.Cu")
	)
	(gr_line
		(start 85.702394 -379.000004)
		(end 85.702394 -378.99975)
		(stroke
			(width 0.07112)
			(type default)
		)
		(layer "In11.Cu")
	)
	(gr_line
		(start 85.702394 -378.99975)
		(end 85.68309 -378.946156)
		(stroke
			(width 0.07112)
			(type default)
		)
		(layer "In11.Cu")
	)
	(gr_line
		(start 85.713824 -371.90045)
		(end 85.960204 -371.551962)
		(stroke
			(width 0.07112)
			(type default)
		)
		(layer "In11.Cu")
	)
	(gr_line
		(start 85.735414 -385.579112)
		(end 85.788246 -385.548632)
		(stroke
			(width 0.07112)
			(type default)
		)
		(layer "In11.Cu")
	)
	(gr_line
		(start 85.746336 -372.090188)
		(end 85.713824 -371.90045)
		(stroke
			(width 0.07112)
			(type default)
		)
		(layer "In11.Cu")
	)
	(gr_line
		(start 85.763862 -379.577346)
		(end 85.61959 -379.175518)
		(stroke
			(width 0.07112)
			(type default)
		)
		(layer "In11.Cu")
	)
	(gr_line
		(start 85.788246 -385.548632)
		(end 85.876384 -385.460494)
		(stroke
			(width 0.07112)
			(type default)
		)
		(layer "In11.Cu")
	)
	(gr_line
		(start 85.823552 -378.502672)
		(end 85.588856 -377.849384)
		(stroke
			(width 0.07112)
			(type default)
		)
		(layer "In11.Cu")
	)
	(gr_line
		(start 85.82533 -378.50826)
		(end 85.823552 -378.502672)
		(stroke
			(width 0.07112)
			(type default)
		)
		(layer "In11.Cu")
	)
	(gr_line
		(start 85.868256 -381.704342)
		(end 85.868256 -381.703834)
		(stroke
			(width 0.07112)
			(type default)
		)
		(layer "In11.Cu")
	)
	(gr_line
		(start 85.876384 -385.460494)
		(end 85.876384 -385.334764)
		(stroke
			(width 0.07112)
			(type default)
		)
		(layer "In11.Cu")
	)
	(gr_line
		(start 85.91804 -364.81639)
		(end 85.970364 -364.63097)
		(stroke
			(width 0.07112)
			(type default)
		)
		(layer "In11.Cu")
	)
	(gr_line
		(start 85.937852 -379.659134)
		(end 85.763862 -379.577346)
		(stroke
			(width 0.07112)
			(type default)
		)
		(layer "In11.Cu")
	)
	(gr_line
		(start 85.937852 -366.077754)
		(end 85.988652 -365.89208)
		(stroke
			(width 0.07112)
			(type default)
		)
		(layer "In11.Cu")
	)
	(gr_line
		(start 85.939376 -379.659896)
		(end 85.93963 -379.659896)
		(stroke
			(width 0.07112)
			(type default)
		)
		(layer "In11.Cu")
	)
	(gr_line
		(start 85.960204 -371.551962)
		(end 86.149942 -371.519196)
		(stroke
			(width 0.07112)
			(type default)
		)
		(layer "In11.Cu")
	)
	(gr_line
		(start 85.96757 -378.904246)
		(end 85.948266 -378.850652)
		(stroke
			(width 0.07112)
			(type default)
		)
		(layer "In11.Cu")
	)
	(gr_line
		(start 85.970364 -364.63097)
		(end 86.342982 -364.422436)
		(stroke
			(width 0.07112)
			(type default)
		)
		(layer "In11.Cu")
	)
	(gr_line
		(start 85.976968 -372.254526)
		(end 86.381844 -371.681756)
		(stroke
			(width 0.07112)
			(type default)
		)
		(layer "In11.Cu")
	)
	(gr_line
		(start 85.988652 -365.89208)
		(end 86.359746 -365.680752)
		(stroke
			(width 0.07112)
			(type default)
		)
		(layer "In11.Cu")
	)
	(gr_line
		(start 86.000844 -380.236984)
		(end 86.082886 -380.062994)
		(stroke
			(width 0.07112)
			(type default)
		)
		(layer "In11.Cu")
	)
	(gr_line
		(start 86.0552 -365.06404)
		(end 86.66734 -364.721394)
		(stroke
			(width 0.07112)
			(type default)
		)
		(layer "In11.Cu")
	)
	(gr_line
		(start 86.07679 -366.324388)
		(end 86.686136 -365.977424)
		(stroke
			(width 0.07112)
			(type default)
		)
		(layer "In11.Cu")
	)
	(gr_line
		(start 86.083648 -380.06147)
		(end 86.083648 -380.061216)
		(stroke
			(width 0.07112)
			(type default)
		)
		(layer "In11.Cu")
	)
	(gr_line
		(start 86.083648 -380.061216)
		(end 86.040976 -379.942852)
		(stroke
			(width 0.07112)
			(type default)
		)
		(layer "In11.Cu")
	)
	(gr_line
		(start 86.145116 -380.638812)
		(end 86.000844 -380.236984)
		(stroke
			(width 0.07112)
			(type default)
		)
		(layer "In11.Cu")
	)
	(gr_line
		(start 86.204806 -379.564392)
		(end 85.96757 -378.904246)
		(stroke
			(width 0.07112)
			(type default)
		)
		(layer "In11.Cu")
	)
	(gr_line
		(start 86.319106 -388.774432)
		(end 86.37143 -388.826756)
		(stroke
			(width 0.07112)
			(type default)
		)
		(layer "In11.Cu")
	)
	(gr_line
		(start 86.319106 -385.31038)
		(end 86.67242 -385.405376)
		(stroke
			(width 0.07112)
			(type default)
		)
		(layer "In11.Cu")
	)
	(gr_line
		(start 86.319106 -380.720854)
		(end 86.145116 -380.638812)
		(stroke
			(width 0.07112)
			(type default)
		)
		(layer "In11.Cu")
	)
	(gr_line
		(start 86.32063 -380.721616)
		(end 86.320884 -380.721616)
		(stroke
			(width 0.07112)
			(type default)
		)
		(layer "In11.Cu")
	)
	(gr_line
		(start 86.320884 -380.72187)
		(end 86.32063 -380.721616)
		(stroke
			(width 0.07112)
			(type default)
		)
		(layer "In11.Cu")
	)
	(gr_line
		(start 86.342982 -364.422436)
		(end 86.528148 -364.47476)
		(stroke
			(width 0.07112)
			(type default)
		)
		(layer "In11.Cu")
	)
	(gr_line
		(start 86.359746 -365.680752)
		(end 86.545166 -365.731806)
		(stroke
			(width 0.07112)
			(type default)
		)
		(layer "In11.Cu")
	)
	(gr_line
		(start 86.364826 -370.979446)
		(end 86.61146 -370.630704)
		(stroke
			(width 0.07112)
			(type default)
		)
		(layer "In11.Cu")
	)
	(gr_line
		(start 86.37143 -389.006588)
		(end 86.224872 -389.153146)
		(stroke
			(width 0.07112)
			(type default)
		)
		(layer "In11.Cu")
	)
	(gr_line
		(start 86.37143 -388.826756)
		(end 86.37143 -389.006588)
		(stroke
			(width 0.07112)
			(type default)
		)
		(layer "In11.Cu")
	)
	(gr_line
		(start 86.375494 -406.71369)
		(end 86.084664 -407.00452)
		(stroke
			(width 0.07112)
			(type default)
		)
		(layer "In11.Cu")
	)
	(gr_line
		(start 86.397338 -371.169184)
		(end 86.364826 -370.979446)
		(stroke
			(width 0.07112)
			(type default)
		)
		(layer "In11.Cu")
	)
	(gr_line
		(start 86.586314 -380.62662)
		(end 86.348824 -379.965966)
		(stroke
			(width 0.07112)
			(type default)
		)
		(layer "In11.Cu")
	)
	(gr_line
		(start 86.604348 -389.352536)
		(end 86.42604 -389.352536)
		(stroke
			(width 0.07112)
			(type default)
		)
		(layer "In11.Cu")
	)
	(gr_line
		(start 86.61146 -370.630704)
		(end 86.800944 -370.598192)
		(stroke
			(width 0.07112)
			(type default)
		)
		(layer "In11.Cu")
	)
	(gr_line
		(start 86.62797 -371.333522)
		(end 87.032846 -370.760752)
		(stroke
			(width 0.07112)
			(type default)
		)
		(layer "In11.Cu")
	)
	(gr_line
		(start 86.657434 -406.71369)
		(end 86.948264 -407.00452)
		(stroke
			(width 0.07112)
			(type default)
		)
		(layer "In11.Cu")
	)
	(gr_line
		(start 86.67242 -385.405376)
		(end 86.672928 -385.404868)
		(stroke
			(width 0.07112)
			(type default)
		)
		(layer "In11.Cu")
	)
	(gr_line
		(start 86.700106 -372.697756)
		(end 86.809834 -372.540784)
		(stroke
			(width 0.07112)
			(type default)
		)
		(layer "In11.Cu")
	)
	(gr_line
		(start 86.719156 -389.467344)
		(end 86.604348 -389.352536)
		(stroke
			(width 0.07112)
			(type default)
		)
		(layer "In11.Cu")
	)
	(gr_line
		(start 86.719156 -386.003292)
		(end 86.813898 -385.649724)
		(stroke
			(width 0.07112)
			(type default)
		)
		(layer "In11.Cu")
	)
	(gr_line
		(start 86.775798 -372.349776)
		(end 87.0204 -371.999764)
		(stroke
			(width 0.07112)
			(type default)
		)
		(layer "In11.Cu")
	)
	(gr_line
		(start 86.80958 -372.539006)
		(end 86.775798 -372.349776)
		(stroke
			(width 0.07112)
			(type default)
		)
		(layer "In11.Cu")
	)
	(gr_line
		(start 86.918038 -365.519716)
		(end 86.968838 -365.334042)
		(stroke
			(width 0.07112)
			(type default)
		)
		(layer "In11.Cu")
	)
	(gr_line
		(start 86.931246 -372.8593)
		(end 87.040974 -372.702328)
		(stroke
			(width 0.07112)
			(type default)
		)
		(layer "In11.Cu")
	)
	(gr_line
		(start 86.935564 -385.579112)
		(end 86.988396 -385.548632)
		(stroke
			(width 0.07112)
			(type default)
		)
		(layer "In11.Cu")
	)
	(gr_line
		(start 86.968838 -365.334042)
		(end 87.339932 -365.122714)
		(stroke
			(width 0.07112)
			(type default)
		)
		(layer "In11.Cu")
	)
	(gr_line
		(start 86.988396 -385.548632)
		(end 87.076534 -385.460494)
		(stroke
			(width 0.07112)
			(type default)
		)
		(layer "In11.Cu")
	)
	(gr_line
		(start 87.015828 -370.058442)
		(end 87.262462 -369.7097)
		(stroke
			(width 0.07112)
			(type default)
		)
		(layer "In11.Cu")
	)
	(gr_line
		(start 87.0204 -371.999764)
		(end 87.20963 -371.965982)
		(stroke
			(width 0.07112)
			(type default)
		)
		(layer "In11.Cu")
	)
	(gr_line
		(start 87.040974 -372.702328)
		(end 87.442548 -372.127018)
		(stroke
			(width 0.07112)
			(type default)
		)
		(layer "In11.Cu")
	)
	(gr_line
		(start 87.04834 -370.24818)
		(end 87.015828 -370.058442)
		(stroke
			(width 0.07112)
			(type default)
		)
		(layer "In11.Cu")
	)
	(gr_line
		(start 87.056976 -365.76635)
		(end 87.666576 -365.419386)
		(stroke
			(width 0.07112)
			(type default)
		)
		(layer "In11.Cu")
	)
	(gr_line
		(start 87.076534 -385.460494)
		(end 87.076534 -385.334764)
		(stroke
			(width 0.07112)
			(type default)
		)
		(layer "In11.Cu")
	)
	(gr_line
		(start 87.103204 -416.810444)
		(end 87.10295 -416.810952)
		(stroke
			(width 0.07112)
			(type default)
		)
		(layer "In11.Cu")
	)
	(gr_line
		(start 87.262462 -369.7097)
		(end 87.451946 -369.677188)
		(stroke
			(width 0.07112)
			(type default)
		)
		(layer "In11.Cu")
	)
	(gr_line
		(start 87.267542 -416.241484)
		(end 87.272622 -416.25139)
		(stroke
			(width 0.07112)
			(type default)
		)
		(layer "In11.Cu")
	)
	(gr_line
		(start 87.272622 -416.25139)
		(end 87.103204 -416.810444)
		(stroke
			(width 0.07112)
			(type default)
		)
		(layer "In11.Cu")
	)
	(gr_line
		(start 87.278972 -370.412518)
		(end 87.683848 -369.839748)
		(stroke
			(width 0.07112)
			(type default)
		)
		(layer "In11.Cu")
	)
	(gr_line
		(start 87.301324 -416.129724)
		(end 87.267542 -416.241484)
		(stroke
			(width 0.07112)
			(type default)
		)
		(layer "In11.Cu")
	)
	(gr_line
		(start 87.339932 -365.122714)
		(end 87.525606 -365.173768)
		(stroke
			(width 0.07112)
			(type default)
		)
		(layer "In11.Cu")
	)
	(gr_line
		(start 87.372952 -416.892486)
		(end 87.372698 -416.892994)
		(stroke
			(width 0.07112)
			(type default)
		)
		(layer "In11.Cu")
	)
	(gr_line
		(start 87.42172 -371.424962)
		(end 87.666322 -371.07495)
		(stroke
			(width 0.07112)
			(type default)
		)
		(layer "In11.Cu")
	)
	(gr_line
		(start 87.455248 -371.614446)
		(end 87.42172 -371.424962)
		(stroke
			(width 0.07112)
			(type default)
		)
		(layer "In11.Cu")
	)
	(gr_line
		(start 87.499444 -430.125632)
		(end 87.523066 -430.125632)
		(stroke
			(width 0.07112)
			(type default)
		)
		(layer "In11.Cu")
	)
	(gr_line
		(start 87.500714 -430.408842)
		(end 87.650066 -430.558194)
		(stroke
			(width 0.07112)
			(type default)
		)
		(layer "In11.Cu")
	)
	(gr_line
		(start 87.519002 -388.774432)
		(end 87.571326 -388.826756)
		(stroke
			(width 0.07112)
			(type default)
		)
		(layer "In11.Cu")
	)
	(gr_line
		(start 87.519002 -385.31038)
		(end 87.872316 -385.405376)
		(stroke
			(width 0.07112)
			(type default)
		)
		(layer "In11.Cu")
	)
	(gr_line
		(start 87.523066 -430.125632)
		(end 87.650066 -429.998632)
		(stroke
			(width 0.07112)
			(type default)
		)
		(layer "In11.Cu")
	)
	(gr_line
		(start 87.544148 -416.801046)
		(end 87.374476 -416.891724)
		(stroke
			(width 0.07112)
			(type default)
		)
		(layer "In11.Cu")
	)
	(gr_line
		(start 87.571326 -389.006588)
		(end 87.424768 -389.153146)
		(stroke
			(width 0.07112)
			(type default)
		)
		(layer "In11.Cu")
	)
	(gr_line
		(start 87.571326 -388.826756)
		(end 87.571326 -389.006588)
		(stroke
			(width 0.07112)
			(type default)
		)
		(layer "In11.Cu")
	)
	(gr_line
		(start 87.572088 -416.213036)
		(end 87.6681 -416.392614)
		(stroke
			(width 0.07112)
			(type default)
		)
		(layer "In11.Cu")
	)
	(gr_line
		(start 87.580216 -403.300438)
		(end 87.389716 -403.272498)
		(stroke
			(width 0.07112)
			(type default)
		)
		(layer "In11.Cu")
	)
	(gr_line
		(start 87.591646 -415.172398)
		(end 87.55761 -415.284412)
		(stroke
			(width 0.07112)
			(type default)
		)
		(layer "In11.Cu")
	)
	(gr_line
		(start 87.601552 -415.167064)
		(end 87.591646 -415.172398)
		(stroke
			(width 0.07112)
			(type default)
		)
		(layer "In11.Cu")
	)
	(gr_line
		(start 87.616284 -412.570168)
		(end 87.907114 -412.860998)
		(stroke
			(width 0.07112)
			(type default)
		)
		(layer "In11.Cu")
	)
	(gr_line
		(start 87.650066 -430.558194)
		(end 87.650066 -430.889918)
		(stroke
			(width 0.07112)
			(type default)
		)
		(layer "In11.Cu")
	)
	(gr_line
		(start 87.650066 -429.998632)
		(end 87.650066 -429.689768)
		(stroke
			(width 0.07112)
			(type default)
		)
		(layer "In11.Cu")
	)
	(gr_line
		(start 87.666322 -371.07495)
		(end 87.855552 -371.041168)
		(stroke
			(width 0.07112)
			(type default)
		)
		(layer "In11.Cu")
	)
	(gr_line
		(start 87.6681 -416.392614)
		(end 87.544148 -416.801046)
		(stroke
			(width 0.07112)
			(type default)
		)
		(layer "In11.Cu")
	)
	(gr_line
		(start 87.686896 -371.777514)
		(end 88.08847 -371.202204)
		(stroke
			(width 0.07112)
			(type default)
		)
		(layer "In11.Cu")
	)
	(gr_line
		(start 87.771478 -414.607502)
		(end 87.601552 -415.167064)
		(stroke
			(width 0.07112)
			(type default)
		)
		(layer "In11.Cu")
	)
	(gr_line
		(start 87.772494 -414.604454)
		(end 87.771478 -414.607502)
		(stroke
			(width 0.07112)
			(type default)
		)
		(layer "In11.Cu")
	)
	(gr_line
		(start 87.78367 -402.627592)
		(end 87.220298 -403.045422)
		(stroke
			(width 0.07112)
			(type default)
		)
		(layer "In11.Cu")
	)
	(gr_line
		(start 87.804244 -389.352536)
		(end 87.625936 -389.352536)
		(stroke
			(width 0.07112)
			(type default)
		)
		(layer "In11.Cu")
	)
	(gr_line
		(start 87.810594 -402.60778)
		(end 87.78367 -402.627592)
		(stroke
			(width 0.07112)
			(type default)
		)
		(layer "In11.Cu")
	)
	(gr_line
		(start 87.872316 -385.405376)
		(end 87.872824 -385.404868)
		(stroke
			(width 0.07112)
			(type default)
		)
		(layer "In11.Cu")
	)
	(gr_line
		(start 87.919052 -389.467344)
		(end 87.804244 -389.352536)
		(stroke
			(width 0.07112)
			(type default)
		)
		(layer "In11.Cu")
	)
	(gr_line
		(start 87.919052 -386.003292)
		(end 88.013794 -385.649724)
		(stroke
			(width 0.07112)
			(type default)
		)
		(layer "In11.Cu")
	)
	(gr_line
		(start 87.923116 -403.046184)
		(end 87.580216 -403.300438)
		(stroke
			(width 0.07112)
			(type default)
		)
		(layer "In11.Cu")
	)
	(gr_line
		(start 87.95131 -402.855938)
		(end 87.923116 -403.046184)
		(stroke
			(width 0.07112)
			(type default)
		)
		(layer "In11.Cu")
	)
	(gr_line
		(start 87.978488 -402.834094)
		(end 87.951564 -402.85416)
		(stroke
			(width 0.07112)
			(type default)
		)
		(layer "In11.Cu")
	)
	(gr_line
		(start 88.008968 -415.269426)
		(end 87.829136 -415.365438)
		(stroke
			(width 0.07112)
			(type default)
		)
		(layer "In11.Cu")
	)
	(gr_line
		(start 88.041988 -414.691068)
		(end 88.13292 -414.860994)
		(stroke
			(width 0.07112)
			(type default)
		)
		(layer "In11.Cu")
	)
	(gr_line
		(start 88.04275 -414.686242)
		(end 88.04148 -414.689798)
		(stroke
			(width 0.07112)
			(type default)
		)
		(layer "In11.Cu")
	)
	(gr_line
		(start 88.067642 -370.500148)
		(end 88.312244 -370.150136)
		(stroke
			(width 0.07112)
			(type default)
		)
		(layer "In11.Cu")
	)
	(gr_line
		(start 88.10117 -370.689632)
		(end 88.067642 -370.500148)
		(stroke
			(width 0.07112)
			(type default)
		)
		(layer "In11.Cu")
	)
	(gr_line
		(start 88.13292 -414.860994)
		(end 88.008968 -415.269426)
		(stroke
			(width 0.07112)
			(type default)
		)
		(layer "In11.Cu")
	)
	(gr_line
		(start 88.13546 -385.579112)
		(end 88.188292 -385.548632)
		(stroke
			(width 0.07112)
			(type default)
		)
		(layer "In11.Cu")
	)
	(gr_line
		(start 88.188292 -385.548632)
		(end 88.27643 -385.460494)
		(stroke
			(width 0.07112)
			(type default)
		)
		(layer "In11.Cu")
	)
	(gr_line
		(start 88.27643 -385.460494)
		(end 88.27643 -385.334764)
		(stroke
			(width 0.07112)
			(type default)
		)
		(layer "In11.Cu")
	)
	(gr_line
		(start 88.312244 -370.150136)
		(end 88.501474 -370.116354)
		(stroke
			(width 0.07112)
			(type default)
		)
		(layer "In11.Cu")
	)
	(gr_line
		(start 88.332818 -370.8527)
		(end 88.734392 -370.277644)
		(stroke
			(width 0.07112)
			(type default)
		)
		(layer "In11.Cu")
	)
	(gr_line
		(start 88.479884 -412.570168)
		(end 88.189054 -412.860998)
		(stroke
			(width 0.07112)
			(type default)
		)
		(layer "In11.Cu")
	)
	(gr_line
		(start 88.48598 -402.628608)
		(end 88.295734 -402.600414)
		(stroke
			(width 0.07112)
			(type default)
		)
		(layer "In11.Cu")
	)
	(gr_line
		(start 88.490044 -419.926262)
		(end 88.202008 -420.56558)
		(stroke
			(width 0.07112)
			(type default)
		)
		(layer "In11.Cu")
	)
	(gr_line
		(start 88.593676 -402.026882)
		(end 88.126316 -402.373592)
		(stroke
			(width 0.07112)
			(type default)
		)
		(layer "In11.Cu")
	)
	(gr_line
		(start 88.595962 -402.02739)
		(end 88.593676 -402.026882)
		(stroke
			(width 0.07112)
			(type default)
		)
		(layer "In11.Cu")
	)
	(gr_line
		(start 88.640666 -420.612824)
		(end 88.46058 -420.680896)
		(stroke
			(width 0.07112)
			(type default)
		)
		(layer "In11.Cu")
	)
	(gr_line
		(start 88.688672 -401.958556)
		(end 88.595962 -402.02739)
		(stroke
			(width 0.07112)
			(type default)
		)
		(layer "In11.Cu")
	)
	(gr_line
		(start 88.719152 -388.774432)
		(end 88.771476 -388.826756)
		(stroke
			(width 0.07112)
			(type default)
		)
		(layer "In11.Cu")
	)
	(gr_line
		(start 88.719152 -385.31038)
		(end 89.072212 -385.405376)
		(stroke
			(width 0.07112)
			(type default)
		)
		(layer "In11.Cu")
	)
	(gr_line
		(start 88.747854 -420.043356)
		(end 88.815926 -420.223442)
		(stroke
			(width 0.07112)
			(type default)
		)
		(layer "In11.Cu")
	)
	(gr_line
		(start 88.771476 -389.006588)
		(end 88.624918 -389.153146)
		(stroke
			(width 0.07112)
			(type default)
		)
		(layer "In11.Cu")
	)
	(gr_line
		(start 88.771476 -388.826756)
		(end 88.771476 -389.006588)
		(stroke
			(width 0.07112)
			(type default)
		)
		(layer "In11.Cu")
	)
	(gr_line
		(start 88.815926 -420.223442)
		(end 88.640666 -420.612824)
		(stroke
			(width 0.07112)
			(type default)
		)
		(layer "In11.Cu")
	)
	(gr_line
		(start 88.829134 -402.3741)
		(end 88.48598 -402.628608)
		(stroke
			(width 0.07112)
			(type default)
		)
		(layer "In11.Cu")
	)
	(gr_line
		(start 88.856566 -402.186648)
		(end 88.829134 -402.3741)
		(stroke
			(width 0.07112)
			(type default)
		)
		(layer "In11.Cu")
	)
	(gr_line
		(start 89.00414 -389.352536)
		(end 88.826086 -389.352536)
		(stroke
			(width 0.07112)
			(type default)
		)
		(layer "In11.Cu")
	)
	(gr_line
		(start 89.072212 -385.405376)
		(end 89.07272 -385.404868)
		(stroke
			(width 0.07112)
			(type default)
		)
		(layer "In11.Cu")
	)
	(gr_line
		(start 89.118948 -389.467344)
		(end 89.00414 -389.352536)
		(stroke
			(width 0.07112)
			(type default)
		)
		(layer "In11.Cu")
	)
	(gr_line
		(start 89.118948 -386.003292)
		(end 89.21369 -385.649724)
		(stroke
			(width 0.07112)
			(type default)
		)
		(layer "In11.Cu")
	)
	(gr_line
		(start 89.335356 -385.579112)
		(end 89.388188 -385.548632)
		(stroke
			(width 0.07112)
			(type default)
		)
		(layer "In11.Cu")
	)
	(gr_line
		(start 89.374726 -417.868608)
		(end 89.370154 -417.880292)
		(stroke
			(width 0.07112)
			(type default)
		)
		(layer "In11.Cu")
	)
	(gr_line
		(start 89.38133 -417.851336)
		(end 89.376758 -417.86302)
		(stroke
			(width 0.07112)
			(type default)
		)
		(layer "In11.Cu")
	)
	(gr_line
		(start 89.381838 -417.850574)
		(end 89.38133 -417.851336)
		(stroke
			(width 0.07112)
			(type default)
		)
		(layer "In11.Cu")
	)
	(gr_line
		(start 89.382092 -417.849812)
		(end 89.381838 -417.850574)
		(stroke
			(width 0.07112)
			(type default)
		)
		(layer "In11.Cu")
	)
	(gr_line
		(start 89.388188 -385.548632)
		(end 89.476326 -385.460494)
		(stroke
			(width 0.07112)
			(type default)
		)
		(layer "In11.Cu")
	)
	(gr_line
		(start 89.438734 -406.71369)
		(end 89.147904 -407.00452)
		(stroke
			(width 0.07112)
			(type default)
		)
		(layer "In11.Cu")
	)
	(gr_line
		(start 89.468198 -382.441958)
		(end 89.468198 -382.44272)
		(stroke
			(width 0.07112)
			(type default)
		)
		(layer "In11.Cu")
	)
	(gr_line
		(start 89.476326 -385.460494)
		(end 89.476326 -385.334764)
		(stroke
			(width 0.07112)
			(type default)
		)
		(layer "In11.Cu")
	)
	(gr_arc
		(start 89.479882 -401.722844)
		(mid 89.479501 -401.723225)
		(end 89.47912 -401.723606)
		(stroke
			(width 0.07112)
			(type default)
		)
		(layer "In11.Cu")
	)
	(gr_line
		(start 89.522808 -431.430938)
		(end 89.650062 -431.558192)
		(stroke
			(width 0.07112)
			(type default)
		)
		(layer "In11.Cu")
	)
	(gr_line
		(start 89.522808 -431.148744)
		(end 89.650062 -431.02149)
		(stroke
			(width 0.07112)
			(type default)
		)
		(layer "In11.Cu")
	)
	(gr_line
		(start 89.634314 -417.196016)
		(end 89.382092 -417.849812)
		(stroke
			(width 0.07112)
			(type default)
		)
		(layer "In11.Cu")
	)
	(gr_line
		(start 89.637616 -417.975542)
		(end 89.636092 -417.977828)
		(stroke
			(width 0.07112)
			(type default)
		)
		(layer "In11.Cu")
	)
	(gr_line
		(start 89.641426 -417.964112)
		(end 89.637616 -417.975542)
		(stroke
			(width 0.07112)
			(type default)
		)
		(layer "In11.Cu")
	)
	(gr_line
		(start 89.64549 -417.951666)
		(end 89.644982 -417.952936)
		(stroke
			(width 0.07112)
			(type default)
		)
		(layer "In11.Cu")
	)
	(gr_line
		(start 89.650062 -431.558192)
		(end 89.650062 -431.889916)
		(stroke
			(width 0.07112)
			(type default)
		)
		(layer "In11.Cu")
	)
	(gr_line
		(start 89.650062 -431.02149)
		(end 89.650062 -430.689766)
		(stroke
			(width 0.07112)
			(type default)
		)
		(layer "In11.Cu")
	)
	(gr_line
		(start 89.720674 -406.71369)
		(end 90.011504 -407.00452)
		(stroke
			(width 0.07112)
			(type default)
		)
		(layer "In11.Cu")
	)
	(gr_line
		(start 89.78773 -416.798252)
		(end 89.72423 -416.963098)
		(stroke
			(width 0.07112)
			(type default)
		)
		(layer "In11.Cu")
	)
	(gr_line
		(start 89.787984 -416.79749)
		(end 89.78773 -416.798252)
		(stroke
			(width 0.07112)
			(type default)
		)
		(layer "In11.Cu")
	)
	(gr_line
		(start 89.822528 -417.87318)
		(end 89.646506 -417.951158)
		(stroke
			(width 0.07112)
			(type default)
		)
		(layer "In11.Cu")
	)
	(gr_line
		(start 89.89822 -417.298886)
		(end 89.975944 -417.474654)
		(stroke
			(width 0.07112)
			(type default)
		)
		(layer "In11.Cu")
	)
	(gr_line
		(start 89.919048 -388.774432)
		(end 89.971372 -388.826756)
		(stroke
			(width 0.07112)
			(type default)
		)
		(layer "In11.Cu")
	)
	(gr_line
		(start 89.919048 -385.31038)
		(end 90.272362 -385.405376)
		(stroke
			(width 0.07112)
			(type default)
		)
		(layer "In11.Cu")
	)
	(gr_line
		(start 89.971372 -389.006588)
		(end 89.824814 -389.153146)
		(stroke
			(width 0.07112)
			(type default)
		)
		(layer "In11.Cu")
	)
	(gr_line
		(start 89.971372 -388.826756)
		(end 89.971372 -389.006588)
		(stroke
			(width 0.07112)
			(type default)
		)
		(layer "In11.Cu")
	)
	(gr_line
		(start 89.975944 -417.474654)
		(end 89.822528 -417.87318)
		(stroke
			(width 0.07112)
			(type default)
		)
		(layer "In11.Cu")
	)
	(gr_line
		(start 90.040206 -416.143694)
		(end 89.787984 -416.79749)
		(stroke
			(width 0.07112)
			(type default)
		)
		(layer "In11.Cu")
	)
	(gr_line
		(start 90.04173 -399.026126)
		(end 89.849452 -399.026126)
		(stroke
			(width 0.07112)
			(type default)
		)
		(layer "In11.Cu")
	)
	(gr_line
		(start 90.051382 -416.89909)
		(end 90.050874 -416.899344)
		(stroke
			(width 0.07112)
			(type default)
		)
		(layer "In11.Cu")
	)
	(gr_line
		(start 90.1446 -398.330674)
		(end 89.648538 -398.826736)
		(stroke
			(width 0.07112)
			(type default)
		)
		(layer "In11.Cu")
	)
	(gr_line
		(start 90.193876 -415.745676)
		(end 90.084148 -416.029648)
		(stroke
			(width 0.07112)
			(type default)
		)
		(layer "In11.Cu")
	)
	(gr_line
		(start 90.20429 -389.352536)
		(end 90.025982 -389.352536)
		(stroke
			(width 0.07112)
			(type default)
		)
		(layer "In11.Cu")
	)
	(gr_line
		(start 90.22842 -416.820858)
		(end 90.052652 -416.898582)
		(stroke
			(width 0.07112)
			(type default)
		)
		(layer "In11.Cu")
	)
	(gr_line
		(start 90.272362 -385.405376)
		(end 90.27287 -385.404868)
		(stroke
			(width 0.07112)
			(type default)
		)
		(layer "In11.Cu")
	)
	(gr_line
		(start 90.292936 -381.094996)
		(end 90.311986 -380.66853)
		(stroke
			(width 0.07112)
			(type default)
		)
		(layer "In11.Cu")
	)
	(gr_line
		(start 90.304112 -416.246564)
		(end 90.381836 -416.422332)
		(stroke
			(width 0.07112)
			(type default)
		)
		(layer "In11.Cu")
	)
	(gr_line
		(start 90.311986 -380.66853)
		(end 90.454226 -380.53899)
		(stroke
			(width 0.07112)
			(type default)
		)
		(layer "In11.Cu")
	)
	(gr_line
		(start 90.319098 -389.467344)
		(end 90.20429 -389.352536)
		(stroke
			(width 0.07112)
			(type default)
		)
		(layer "In11.Cu")
	)
	(gr_line
		(start 90.319098 -386.003292)
		(end 90.41384 -385.649724)
		(stroke
			(width 0.07112)
			(type default)
		)
		(layer "In11.Cu")
	)
	(gr_line
		(start 90.343736 -398.72412)
		(end 90.04173 -399.026126)
		(stroke
			(width 0.07112)
			(type default)
		)
		(layer "In11.Cu")
	)
	(gr_line
		(start 90.343736 -379.968252)
		(end 90.362786 -379.541786)
		(stroke
			(width 0.07112)
			(type default)
		)
		(layer "In11.Cu")
	)
	(gr_line
		(start 90.34399 -398.531588)
		(end 90.343736 -398.72412)
		(stroke
			(width 0.07112)
			(type default)
		)
		(layer "In11.Cu")
	)
	(gr_line
		(start 90.362786 -379.541786)
		(end 90.504772 -379.412246)
		(stroke
			(width 0.07112)
			(type default)
		)
		(layer "In11.Cu")
	)
	(gr_line
		(start 90.381836 -416.422332)
		(end 90.22842 -416.820858)
		(stroke
			(width 0.07112)
			(type default)
		)
		(layer "In11.Cu")
	)
	(gr_line
		(start 90.394536 -378.841508)
		(end 90.413586 -378.415042)
		(stroke
			(width 0.07112)
			(type default)
		)
		(layer "In11.Cu")
	)
	(gr_line
		(start 90.413586 -378.415042)
		(end 90.555572 -378.285756)
		(stroke
			(width 0.07112)
			(type default)
		)
		(layer "In11.Cu")
	)
	(gr_line
		(start 90.42273 -381.236982)
		(end 90.292936 -381.094996)
		(stroke
			(width 0.07112)
			(type default)
		)
		(layer "In11.Cu")
	)
	(gr_line
		(start 90.441526 -415.103564)
		(end 90.193876 -415.745676)
		(stroke
			(width 0.07112)
			(type default)
		)
		(layer "In11.Cu")
	)
	(gr_line
		(start 90.44178 -394.314426)
		(end 90.44178 -395.015466)
		(stroke
			(width 0.07112)
			(type default)
		)
		(layer "In11.Cu")
	)
	(gr_line
		(start 90.446606 -415.090356)
		(end 90.446098 -415.091626)
		(stroke
			(width 0.07112)
			(type default)
		)
		(layer "In11.Cu")
	)
	(gr_line
		(start 90.446606 -415.089848)
		(end 90.446606 -415.090356)
		(stroke
			(width 0.07112)
			(type default)
		)
		(layer "In11.Cu")
	)
	(gr_line
		(start 90.446606 -415.08934)
		(end 90.44686 -415.08934)
		(stroke
			(width 0.07112)
			(type default)
		)
		(layer "In11.Cu")
	)
	(gr_line
		(start 90.455496 -380.53772)
		(end 90.455242 -380.53772)
		(stroke
			(width 0.07112)
			(type default)
		)
		(layer "In11.Cu")
	)
	(gr_line
		(start 90.456766 -415.847022)
		(end 90.347292 -416.130994)
		(stroke
			(width 0.07112)
			(type default)
		)
		(layer "In11.Cu")
	)
	(gr_line
		(start 90.47353 -380.110238)
		(end 90.343736 -379.968252)
		(stroke
			(width 0.07112)
			(type default)
		)
		(layer "In11.Cu")
	)
	(gr_line
		(start 90.506296 -379.410976)
		(end 90.506042 -379.410976)
		(stroke
			(width 0.07112)
			(type default)
		)
		(layer "In11.Cu")
	)
	(gr_line
		(start 90.524076 -378.983494)
		(end 90.394536 -378.841508)
		(stroke
			(width 0.07112)
			(type default)
		)
		(layer "In11.Cu")
	)
	(gr_line
		(start 90.525092 -378.984764)
		(end 90.525346 -378.984764)
		(stroke
			(width 0.07112)
			(type default)
		)
		(layer "In11.Cu")
	)
	(gr_line
		(start 90.535506 -385.579112)
		(end 90.588338 -385.548632)
		(stroke
			(width 0.07112)
			(type default)
		)
		(layer "In11.Cu")
	)
	(gr_line
		(start 90.556588 -378.284232)
		(end 90.556842 -378.283978)
		(stroke
			(width 0.07112)
			(type default)
		)
		(layer "In11.Cu")
	)
	(gr_line
		(start 90.557096 -378.284232)
		(end 90.556588 -378.284232)
		(stroke
			(width 0.07112)
			(type default)
		)
		(layer "In11.Cu")
	)
	(gr_line
		(start 90.588338 -385.548632)
		(end 90.676476 -385.460494)
		(stroke
			(width 0.07112)
			(type default)
		)
		(layer "In11.Cu")
	)
	(gr_line
		(start 90.634312 -415.768536)
		(end 90.458544 -415.84626)
		(stroke
			(width 0.07112)
			(type default)
		)
		(layer "In11.Cu")
	)
	(gr_line
		(start 90.676476 -385.460494)
		(end 90.676476 -385.334764)
		(stroke
			(width 0.07112)
			(type default)
		)
		(layer "In11.Cu")
	)
	(gr_line
		(start 90.679524 -412.570168)
		(end 90.970354 -412.860998)
		(stroke
			(width 0.07112)
			(type default)
		)
		(layer "In11.Cu")
	)
	(gr_line
		(start 90.705686 -381.250952)
		(end 90.737182 -380.548642)
		(stroke
			(width 0.07112)
			(type default)
		)
		(layer "In11.Cu")
	)
	(gr_line
		(start 90.709242 -415.192718)
		(end 90.709496 -415.193226)
		(stroke
			(width 0.07112)
			(type default)
		)
		(layer "In11.Cu")
	)
	(gr_line
		(start 90.709496 -415.191956)
		(end 90.709242 -415.192718)
		(stroke
			(width 0.07112)
			(type default)
		)
		(layer "In11.Cu")
	)
	(gr_line
		(start 90.70975 -415.19094)
		(end 90.709496 -415.191956)
		(stroke
			(width 0.07112)
			(type default)
		)
		(layer "In11.Cu")
	)
	(gr_line
		(start 90.710004 -415.194496)
		(end 90.787982 -415.37001)
		(stroke
			(width 0.07112)
			(type default)
		)
		(layer "In11.Cu")
	)
	(gr_line
		(start 90.72499 -394.315696)
		(end 90.86088 -394.451586)
		(stroke
			(width 0.07112)
			(type default)
		)
		(layer "In11.Cu")
	)
	(gr_line
		(start 90.756232 -380.124208)
		(end 90.787728 -379.423676)
		(stroke
			(width 0.07112)
			(type default)
		)
		(layer "In11.Cu")
	)
	(gr_line
		(start 90.787982 -415.37001)
		(end 90.634312 -415.768536)
		(stroke
			(width 0.07112)
			(type default)
		)
		(layer "In11.Cu")
	)
	(gr_line
		(start 90.807032 -378.997464)
		(end 90.838528 -378.296678)
		(stroke
			(width 0.07112)
			(type default)
		)
		(layer "In11.Cu")
	)
	(gr_line
		(start 90.839544 -398.228566)
		(end 90.647012 -398.228566)
		(stroke
			(width 0.07112)
			(type default)
		)
		(layer "In11.Cu")
	)
	(gr_line
		(start 90.86088 -394.878306)
		(end 90.72499 -395.014196)
		(stroke
			(width 0.07112)
			(type default)
		)
		(layer "In11.Cu")
	)
	(gr_line
		(start 90.86088 -394.451586)
		(end 90.86088 -394.878306)
		(stroke
			(width 0.07112)
			(type default)
		)
		(layer "In11.Cu")
	)
	(gr_line
		(start 90.94216 -397.533114)
		(end 90.446098 -398.029176)
		(stroke
			(width 0.07112)
			(type default)
		)
		(layer "In11.Cu")
	)
	(gr_line
		(start 90.970354 -413.561276)
		(end 90.9701 -413.561022)
		(stroke
			(width 0.07112)
			(type default)
		)
		(layer "In11.Cu")
	)
	(gr_line
		(start 91.118944 -388.774432)
		(end 91.171268 -388.826756)
		(stroke
			(width 0.07112)
			(type default)
		)
		(layer "In11.Cu")
	)
	(gr_line
		(start 91.118944 -385.31038)
		(end 91.472258 -385.405376)
		(stroke
			(width 0.07112)
			(type default)
		)
		(layer "In11.Cu")
	)
	(gr_line
		(start 91.141296 -397.92656)
		(end 90.839544 -398.228566)
		(stroke
			(width 0.07112)
			(type default)
		)
		(layer "In11.Cu")
	)
	(gr_line
		(start 91.14155 -397.734282)
		(end 91.141296 -397.92656)
		(stroke
			(width 0.07112)
			(type default)
		)
		(layer "In11.Cu")
	)
	(gr_line
		(start 91.171268 -389.006588)
		(end 91.02471 -389.153146)
		(stroke
			(width 0.07112)
			(type default)
		)
		(layer "In11.Cu")
	)
	(gr_line
		(start 91.171268 -388.826756)
		(end 91.171268 -389.006588)
		(stroke
			(width 0.07112)
			(type default)
		)
		(layer "In11.Cu")
	)
	(gr_line
		(start 91.273122 -401.487894)
		(end 91.273376 -401.48891)
		(stroke
			(width 0.07112)
			(type default)
		)
		(layer "In11.Cu")
	)
	(gr_line
		(start 91.273376 -401.48891)
		(end 90.924888 -401.958048)
		(stroke
			(width 0.07112)
			(type default)
		)
		(layer "In11.Cu")
	)
	(gr_line
		(start 91.342972 -401.393914)
		(end 91.273122 -401.487894)
		(stroke
			(width 0.07112)
			(type default)
		)
		(layer "In11.Cu")
	)
	(gr_line
		(start 91.343226 -402.098002)
		(end 91.15298 -402.125942)
		(stroke
			(width 0.07112)
			(type default)
		)
		(layer "In11.Cu")
	)
	(gr_line
		(start 91.404186 -389.352536)
		(end 91.225878 -389.352536)
		(stroke
			(width 0.07112)
			(type default)
		)
		(layer "In11.Cu")
	)
	(gr_line
		(start 91.470226 -381.010922)
		(end 91.476322 -380.583948)
		(stroke
			(width 0.07112)
			(type default)
		)
		(layer "In11.Cu")
	)
	(gr_line
		(start 91.472258 -385.405376)
		(end 91.472766 -385.404868)
		(stroke
			(width 0.07112)
			(type default)
		)
		(layer "In11.Cu")
	)
	(gr_line
		(start 91.476322 -380.583948)
		(end 91.614498 -380.450344)
		(stroke
			(width 0.07112)
			(type default)
		)
		(layer "In11.Cu")
	)
	(gr_line
		(start 91.48699 -379.883416)
		(end 91.493086 -379.456442)
		(stroke
			(width 0.07112)
			(type default)
		)
		(layer "In11.Cu")
	)
	(gr_line
		(start 91.493086 -379.456442)
		(end 91.631262 -379.322584)
		(stroke
			(width 0.07112)
			(type default)
		)
		(layer "In11.Cu")
	)
	(gr_line
		(start 91.5035 -378.755656)
		(end 91.50985 -378.328682)
		(stroke
			(width 0.07112)
			(type default)
		)
		(layer "In11.Cu")
	)
	(gr_line
		(start 91.50985 -378.328682)
		(end 91.648026 -378.194824)
		(stroke
			(width 0.07112)
			(type default)
		)
		(layer "In11.Cu")
	)
	(gr_line
		(start 91.518994 -389.467344)
		(end 91.404186 -389.352536)
		(stroke
			(width 0.07112)
			(type default)
		)
		(layer "In11.Cu")
	)
	(gr_line
		(start 91.518994 -386.003292)
		(end 91.613736 -385.649724)
		(stroke
			(width 0.07112)
			(type default)
		)
		(layer "In11.Cu")
	)
	(gr_line
		(start 91.543124 -412.570168)
		(end 91.252294 -412.860998)
		(stroke
			(width 0.07112)
			(type default)
		)
		(layer "In11.Cu")
	)
	(gr_line
		(start 91.56954 -401.56384)
		(end 91.597988 -401.755102)
		(stroke
			(width 0.07112)
			(type default)
		)
		(layer "In11.Cu")
	)
	(gr_line
		(start 91.582494 -394.504418)
		(end 91.582494 -395.205458)
		(stroke
			(width 0.07112)
			(type default)
		)
		(layer "In11.Cu")
	)
	(gr_line
		(start 91.597988 -401.755102)
		(end 91.343226 -402.098002)
		(stroke
			(width 0.07112)
			(type default)
		)
		(layer "In11.Cu")
	)
	(gr_line
		(start 91.604084 -381.149098)
		(end 91.470226 -381.010922)
		(stroke
			(width 0.07112)
			(type default)
		)
		(layer "In11.Cu")
	)
	(gr_line
		(start 91.615768 -380.449074)
		(end 91.616022 -380.43866)
		(stroke
			(width 0.07112)
			(type default)
		)
		(layer "In11.Cu")
	)
	(gr_line
		(start 91.620848 -380.021592)
		(end 91.48699 -379.883416)
		(stroke
			(width 0.07112)
			(type default)
		)
		(layer "In11.Cu")
	)
	(gr_line
		(start 91.632532 -379.321314)
		(end 91.63304 -379.277372)
		(stroke
			(width 0.07112)
			(type default)
		)
		(layer "In11.Cu")
	)
	(gr_line
		(start 91.63685 -397.431006)
		(end 91.444826 -397.431006)
		(stroke
			(width 0.07112)
			(type default)
		)
		(layer "In11.Cu")
	)
	(gr_line
		(start 91.637612 -378.893832)
		(end 91.5035 -378.755656)
		(stroke
			(width 0.07112)
			(type default)
		)
		(layer "In11.Cu")
	)
	(gr_line
		(start 91.649296 -378.193554)
		(end 91.649042 -378.193554)
		(stroke
			(width 0.07112)
			(type default)
		)
		(layer "In11.Cu")
	)
	(gr_line
		(start 91.665806 -400.959066)
		(end 91.59621 -401.052538)
		(stroke
			(width 0.07112)
			(type default)
		)
		(layer "In11.Cu")
	)
	(gr_line
		(start 91.66606 -400.958812)
		(end 91.665806 -400.959066)
		(stroke
			(width 0.07112)
			(type default)
		)
		(layer "In11.Cu")
	)
	(gr_line
		(start 91.667076 -400.958812)
		(end 91.66606 -400.958812)
		(stroke
			(width 0.07112)
			(type default)
		)
		(layer "In11.Cu")
	)
	(gr_line
		(start 91.735402 -385.579112)
		(end 91.788234 -385.548632)
		(stroke
			(width 0.07112)
			(type default)
		)
		(layer "In11.Cu")
	)
	(gr_line
		(start 91.739466 -396.735808)
		(end 91.243658 -397.231616)
		(stroke
			(width 0.07112)
			(type default)
		)
		(layer "In11.Cu")
	)
	(gr_line
		(start 91.788234 -385.548632)
		(end 91.876372 -385.460494)
		(stroke
			(width 0.07112)
			(type default)
		)
		(layer "In11.Cu")
	)
	(gr_line
		(start 91.865704 -394.505688)
		(end 92.001594 -394.641578)
		(stroke
			(width 0.07112)
			(type default)
		)
		(layer "In11.Cu")
	)
	(gr_line
		(start 91.876372 -385.460494)
		(end 91.876372 -385.334764)
		(stroke
			(width 0.07112)
			(type default)
		)
		(layer "In11.Cu")
	)
	(gr_line
		(start 91.887294 -381.154178)
		(end 91.897708 -380.453138)
		(stroke
			(width 0.07112)
			(type default)
		)
		(layer "In11.Cu")
	)
	(gr_line
		(start 91.897708 -380.453138)
		(end 91.897708 -380.442724)
		(stroke
			(width 0.07112)
			(type default)
		)
		(layer "In11.Cu")
	)
	(gr_line
		(start 91.904058 -380.026672)
		(end 91.914472 -379.325378)
		(stroke
			(width 0.07112)
			(type default)
		)
		(layer "In11.Cu")
	)
	(gr_line
		(start 91.914472 -379.325378)
		(end 91.91498 -379.281436)
		(stroke
			(width 0.07112)
			(type default)
		)
		(layer "In11.Cu")
	)
	(gr_line
		(start 91.920822 -378.898912)
		(end 91.930982 -378.208286)
		(stroke
			(width 0.07112)
			(type default)
		)
		(layer "In11.Cu")
	)
	(gr_line
		(start 91.930982 -378.20346)
		(end 91.931236 -378.192792)
		(stroke
			(width 0.07112)
			(type default)
		)
		(layer "In11.Cu")
	)
	(gr_line
		(start 91.938856 -397.129)
		(end 91.63685 -397.431006)
		(stroke
			(width 0.07112)
			(type default)
		)
		(layer "In11.Cu")
	)
	(gr_line
		(start 91.938856 -396.936976)
		(end 91.938856 -397.129)
		(stroke
			(width 0.07112)
			(type default)
		)
		(layer "In11.Cu")
	)
	(gr_line
		(start 92.001594 -395.068298)
		(end 91.865704 -395.204188)
		(stroke
			(width 0.07112)
			(type default)
		)
		(layer "In11.Cu")
	)
	(gr_line
		(start 92.001594 -394.641578)
		(end 92.001594 -395.068298)
		(stroke
			(width 0.07112)
			(type default)
		)
		(layer "In11.Cu")
	)
	(gr_line
		(start 92.015818 -401.192238)
		(end 91.824302 -401.220686)
		(stroke
			(width 0.07112)
			(type default)
		)
		(layer "In11.Cu")
	)
	(gr_line
		(start 92.015818 -400.48942)
		(end 91.667076 -400.958812)
		(stroke
			(width 0.07112)
			(type default)
		)
		(layer "In11.Cu")
	)
	(gr_line
		(start 92.242386 -400.659346)
		(end 92.270326 -400.849592)
		(stroke
			(width 0.07112)
			(type default)
		)
		(layer "In11.Cu")
	)
	(gr_line
		(start 92.270326 -400.849592)
		(end 92.015818 -401.192238)
		(stroke
			(width 0.07112)
			(type default)
		)
		(layer "In11.Cu")
	)
	(gr_line
		(start 92.319094 -388.774432)
		(end 92.371418 -388.826756)
		(stroke
			(width 0.07112)
			(type default)
		)
		(layer "In11.Cu")
	)
	(gr_line
		(start 92.319094 -385.31038)
		(end 92.672408 -385.405376)
		(stroke
			(width 0.07112)
			(type default)
		)
		(layer "In11.Cu")
	)
	(gr_line
		(start 92.371418 -389.006588)
		(end 92.22486 -389.153146)
		(stroke
			(width 0.07112)
			(type default)
		)
		(layer "In11.Cu")
	)
	(gr_line
		(start 92.371418 -388.826756)
		(end 92.371418 -389.006588)
		(stroke
			(width 0.07112)
			(type default)
		)
		(layer "In11.Cu")
	)
	(gr_line
		(start 92.501974 -406.71369)
		(end 92.211144 -407.00452)
		(stroke
			(width 0.07112)
			(type default)
		)
		(layer "In11.Cu")
	)
	(gr_line
		(start 92.604336 -389.352536)
		(end 92.426028 -389.352536)
		(stroke
			(width 0.07112)
			(type default)
		)
		(layer "In11.Cu")
	)
	(gr_line
		(start 92.649294 -381.09906)
		(end 92.649294 -380.67234)
		(stroke
			(width 0.07112)
			(type default)
		)
		(layer "In11.Cu")
	)
	(gr_line
		(start 92.649294 -380.67234)
		(end 92.785184 -380.53645)
		(stroke
			(width 0.07112)
			(type default)
		)
		(layer "In11.Cu")
	)
	(gr_line
		(start 92.649294 -379.9713)
		(end 92.649294 -379.54458)
		(stroke
			(width 0.07112)
			(type default)
		)
		(layer "In11.Cu")
	)
	(gr_line
		(start 92.649294 -379.54458)
		(end 92.785184 -379.40869)
		(stroke
			(width 0.07112)
			(type default)
		)
		(layer "In11.Cu")
	)
	(gr_line
		(start 92.649294 -378.84354)
		(end 92.649294 -378.41682)
		(stroke
			(width 0.07112)
			(type default)
		)
		(layer "In11.Cu")
	)
	(gr_line
		(start 92.649294 -378.41682)
		(end 92.785184 -378.28093)
		(stroke
			(width 0.07112)
			(type default)
		)
		(layer "In11.Cu")
	)
	(gr_line
		(start 92.672408 -385.405376)
		(end 92.672916 -385.404868)
		(stroke
			(width 0.07112)
			(type default)
		)
		(layer "In11.Cu")
	)
	(gr_line
		(start 92.68841 -400.286728)
		(end 92.498164 -400.314922)
		(stroke
			(width 0.07112)
			(type default)
		)
		(layer "In11.Cu")
	)
	(gr_line
		(start 92.68841 -399.58391)
		(end 92.270072 -400.147028)
		(stroke
			(width 0.07112)
			(type default)
		)
		(layer "In11.Cu")
	)
	(gr_line
		(start 92.719144 -389.467344)
		(end 92.604336 -389.352536)
		(stroke
			(width 0.07112)
			(type default)
		)
		(layer "In11.Cu")
	)
	(gr_line
		(start 92.719144 -386.003292)
		(end 92.813886 -385.649724)
		(stroke
			(width 0.07112)
			(type default)
		)
		(layer "In11.Cu")
	)
	(gr_line
		(start 92.783914 -406.71369)
		(end 93.074744 -407.00452)
		(stroke
			(width 0.07112)
			(type default)
		)
		(layer "In11.Cu")
	)
	(gr_line
		(start 92.785184 -381.23495)
		(end 92.649294 -381.09906)
		(stroke
			(width 0.07112)
			(type default)
		)
		(layer "In11.Cu")
	)
	(gr_line
		(start 92.785184 -380.10719)
		(end 92.649294 -379.9713)
		(stroke
			(width 0.07112)
			(type default)
		)
		(layer "In11.Cu")
	)
	(gr_line
		(start 92.785184 -378.97943)
		(end 92.649294 -378.84354)
		(stroke
			(width 0.07112)
			(type default)
		)
		(layer "In11.Cu")
	)
	(gr_line
		(start 92.914978 -399.753836)
		(end 92.942918 -399.944082)
		(stroke
			(width 0.07112)
			(type default)
		)
		(layer "In11.Cu")
	)
	(gr_line
		(start 92.935552 -385.579112)
		(end 92.988384 -385.548632)
		(stroke
			(width 0.07112)
			(type default)
		)
		(layer "In11.Cu")
	)
	(gr_line
		(start 92.942918 -399.944082)
		(end 92.68841 -400.286728)
		(stroke
			(width 0.07112)
			(type default)
		)
		(layer "In11.Cu")
	)
	(gr_line
		(start 92.988384 -385.548632)
		(end 93.076522 -385.460494)
		(stroke
			(width 0.07112)
			(type default)
		)
		(layer "In11.Cu")
	)
	(gr_line
		(start 93.068394 -381.23622)
		(end 93.068394 -380.53518)
		(stroke
			(width 0.07112)
			(type default)
		)
		(layer "In11.Cu")
	)
	(gr_line
		(start 93.068394 -380.10846)
		(end 93.068394 -379.40742)
		(stroke
			(width 0.07112)
			(type default)
		)
		(layer "In11.Cu")
	)
	(gr_line
		(start 93.068394 -378.9807)
		(end 93.068394 -378.27966)
		(stroke
			(width 0.07112)
			(type default)
		)
		(layer "In11.Cu")
	)
	(gr_line
		(start 93.076522 -385.460494)
		(end 93.076522 -385.334764)
		(stroke
			(width 0.07112)
			(type default)
		)
		(layer "In11.Cu")
	)
	(gr_line
		(start 93.11259 -416.384994)
		(end 92.81287 -417.018978)
		(stroke
			(width 0.07112)
			(type default)
		)
		(layer "In11.Cu")
	)
	(gr_line
		(start 93.250766 -417.07435)
		(end 93.069156 -417.13912)
		(stroke
			(width 0.07112)
			(type default)
		)
		(layer "In11.Cu")
	)
	(gr_line
		(start 93.368368 -416.506914)
		(end 93.433138 -416.68827)
		(stroke
			(width 0.07112)
			(type default)
		)
		(layer "In11.Cu")
	)
	(gr_line
		(start 93.427804 -398.587976)
		(end 93.428058 -398.587976)
		(stroke
			(width 0.07112)
			(type default)
		)
		(layer "In11.Cu")
	)
	(gr_line
		(start 93.433138 -416.68827)
		(end 93.250766 -417.07435)
		(stroke
			(width 0.07112)
			(type default)
		)
		(layer "In11.Cu")
	)
	(gr_line
		(start 93.51899 -388.774432)
		(end 93.571314 -388.826756)
		(stroke
			(width 0.07112)
			(type default)
		)
		(layer "In11.Cu")
	)
	(gr_line
		(start 93.51899 -385.31038)
		(end 93.872304 -385.405376)
		(stroke
			(width 0.07112)
			(type default)
		)
		(layer "In11.Cu")
	)
	(gr_line
		(start 93.571314 -389.006588)
		(end 93.424756 -389.153146)
		(stroke
			(width 0.07112)
			(type default)
		)
		(layer "In11.Cu")
	)
	(gr_line
		(start 93.571314 -388.826756)
		(end 93.571314 -389.006588)
		(stroke
			(width 0.07112)
			(type default)
		)
		(layer "In11.Cu")
	)
	(gr_line
		(start 93.742764 -412.570168)
		(end 94.033594 -412.860998)
		(stroke
			(width 0.07112)
			(type default)
		)
		(layer "In11.Cu")
	)
	(gr_line
		(start 93.804232 -389.352536)
		(end 93.625924 -389.352536)
		(stroke
			(width 0.07112)
			(type default)
		)
		(layer "In11.Cu")
	)
	(gr_line
		(start 93.833442 -414.405064)
		(end 93.629734 -415.076386)
		(stroke
			(width 0.07112)
			(type default)
		)
		(layer "In11.Cu")
	)
	(gr_line
		(start 93.872304 -385.405376)
		(end 93.872812 -385.404868)
		(stroke
			(width 0.07112)
			(type default)
		)
		(layer "In11.Cu")
	)
	(gr_line
		(start 93.91904 -389.467344)
		(end 93.804232 -389.352536)
		(stroke
			(width 0.07112)
			(type default)
		)
		(layer "In11.Cu")
	)
	(gr_line
		(start 93.91904 -386.003292)
		(end 94.013782 -385.649724)
		(stroke
			(width 0.07112)
			(type default)
		)
		(layer "In11.Cu")
	)
	(gr_line
		(start 94.033594 -413.70377)
		(end 94.03334 -413.70377)
		(stroke
			(width 0.07112)
			(type default)
		)
		(layer "In11.Cu")
	)
	(gr_line
		(start 94.048326 -394.317474)
		(end 94.048326 -395.018514)
		(stroke
			(width 0.07112)
			(type default)
		)
		(layer "In11.Cu")
	)
	(gr_line
		(start 94.070932 -415.066734)
		(end 93.90126 -415.157412)
		(stroke
			(width 0.07112)
			(type default)
		)
		(layer "In11.Cu")
	)
	(gr_line
		(start 94.104206 -414.488122)
		(end 94.194884 -414.658048)
		(stroke
			(width 0.07112)
			(type default)
		)
		(layer "In11.Cu")
	)
	(gr_line
		(start 94.135448 -385.579112)
		(end 94.18828 -385.548632)
		(stroke
			(width 0.07112)
			(type default)
		)
		(layer "In11.Cu")
	)
	(gr_line
		(start 94.18828 -385.548632)
		(end 94.276418 -385.460494)
		(stroke
			(width 0.07112)
			(type default)
		)
		(layer "In11.Cu")
	)
	(gr_line
		(start 94.194884 -414.658048)
		(end 94.070932 -415.066734)
		(stroke
			(width 0.07112)
			(type default)
		)
		(layer "In11.Cu")
	)
	(gr_line
		(start 94.276418 -385.460494)
		(end 94.276418 -385.334764)
		(stroke
			(width 0.07112)
			(type default)
		)
		(layer "In11.Cu")
	)
	(gr_line
		(start 94.291658 -413.866584)
		(end 94.291404 -413.867092)
		(stroke
			(width 0.07112)
			(type default)
		)
		(layer "In11.Cu")
	)
	(gr_line
		(start 94.331536 -394.318744)
		(end 94.467426 -394.454634)
		(stroke
			(width 0.07112)
			(type default)
		)
		(layer "In11.Cu")
	)
	(gr_line
		(start 94.378018 -380.62281)
		(end 94.556834 -380.235206)
		(stroke
			(width 0.07112)
			(type default)
		)
		(layer "In11.Cu")
	)
	(gr_line
		(start 94.415102 -400.169126)
		(end 94.365318 -400.274536)
		(stroke
			(width 0.07112)
			(type default)
		)
		(layer "In11.Cu")
	)
	(gr_line
		(start 94.417896 -400.16811)
		(end 94.415102 -400.169126)
		(stroke
			(width 0.07112)
			(type default)
		)
		(layer "In11.Cu")
	)
	(gr_line
		(start 94.444566 -380.80315)
		(end 94.378018 -380.62281)
		(stroke
			(width 0.07112)
			(type default)
		)
		(layer "In11.Cu")
	)
	(gr_line
		(start 94.467426 -394.881354)
		(end 94.331536 -395.017244)
		(stroke
			(width 0.07112)
			(type default)
		)
		(layer "In11.Cu")
	)
	(gr_line
		(start 94.467426 -394.454634)
		(end 94.467426 -394.881354)
		(stroke
			(width 0.07112)
			(type default)
		)
		(layer "In11.Cu")
	)
	(gr_line
		(start 94.556834 -380.235206)
		(end 94.737428 -380.168912)
		(stroke
			(width 0.07112)
			(type default)
		)
		(layer "In11.Cu")
	)
	(gr_line
		(start 94.606364 -412.570168)
		(end 94.315534 -412.860998)
		(stroke
			(width 0.07112)
			(type default)
		)
		(layer "In11.Cu")
	)
	(gr_line
		(start 94.667832 -399.639536)
		(end 94.417896 -400.16811)
		(stroke
			(width 0.07112)
			(type default)
		)
		(layer "In11.Cu")
	)
	(gr_line
		(start 94.701106 -380.923292)
		(end 94.995238 -380.286006)
		(stroke
			(width 0.07112)
			(type default)
		)
		(layer "In11.Cu")
	)
	(gr_line
		(start 94.71914 -388.774432)
		(end 94.771464 -388.826756)
		(stroke
			(width 0.07112)
			(type default)
		)
		(layer "In11.Cu")
	)
	(gr_line
		(start 94.71914 -385.31038)
		(end 95.0722 -385.405376)
		(stroke
			(width 0.07112)
			(type default)
		)
		(layer "In11.Cu")
	)
	(gr_line
		(start 94.739206 -380.16815)
		(end 94.739206 -380.167896)
		(stroke
			(width 0.07112)
			(type default)
		)
		(layer "In11.Cu")
	)
	(gr_line
		(start 94.771464 -389.006588)
		(end 94.624906 -389.153146)
		(stroke
			(width 0.07112)
			(type default)
		)
		(layer "In11.Cu")
	)
	(gr_line
		(start 94.771464 -388.826756)
		(end 94.771464 -389.006588)
		(stroke
			(width 0.07112)
			(type default)
		)
		(layer "In11.Cu")
	)
	(gr_line
		(start 94.805754 -400.328638)
		(end 94.621858 -400.394678)
		(stroke
			(width 0.07112)
			(type default)
		)
		(layer "In11.Cu")
	)
	(gr_line
		(start 94.850966 -379.598936)
		(end 95.029782 -379.211078)
		(stroke
			(width 0.07112)
			(type default)
		)
		(layer "In11.Cu")
	)
	(gr_line
		(start 94.917514 -379.779022)
		(end 94.850966 -379.598936)
		(stroke
			(width 0.07112)
			(type default)
		)
		(layer "In11.Cu")
	)
	(gr_line
		(start 94.917768 -379.7808)
		(end 94.918022 -379.7808)
		(stroke
			(width 0.07112)
			(type default)
		)
		(layer "In11.Cu")
	)
	(gr_line
		(start 94.923356 -399.761456)
		(end 94.988126 -399.942558)
		(stroke
			(width 0.07112)
			(type default)
		)
		(layer "In11.Cu")
	)
	(gr_line
		(start 94.988126 -399.942558)
		(end 94.805754 -400.328638)
		(stroke
			(width 0.07112)
			(type default)
		)
		(layer "In11.Cu")
	)
	(gr_line
		(start 95.004128 -389.352536)
		(end 94.826074 -389.352536)
		(stroke
			(width 0.07112)
			(type default)
		)
		(layer "In11.Cu")
	)
	(gr_line
		(start 95.029782 -379.211078)
		(end 95.210122 -379.145038)
		(stroke
			(width 0.07112)
			(type default)
		)
		(layer "In11.Cu")
	)
	(gr_line
		(start 95.0722 -385.405376)
		(end 95.072708 -385.404868)
		(stroke
			(width 0.07112)
			(type default)
		)
		(layer "In11.Cu")
	)
	(gr_line
		(start 95.118936 -389.467344)
		(end 95.004128 -389.352536)
		(stroke
			(width 0.07112)
			(type default)
		)
		(layer "In11.Cu")
	)
	(gr_line
		(start 95.118936 -386.003292)
		(end 95.213678 -385.649724)
		(stroke
			(width 0.07112)
			(type default)
		)
		(layer "In11.Cu")
	)
	(gr_line
		(start 95.125032 -221.083378)
		(end 95.170752 -221.129098)
		(stroke
			(width 0.05715)
			(type default)
		)
		(layer "In11.Cu")
	)
	(gr_line
		(start 95.125032 -221.05493)
		(end 95.125032 -221.083378)
		(stroke
			(width 0.05715)
			(type default)
		)
		(layer "In11.Cu")
	)
	(gr_line
		(start 95.149924 -398.619726)
		(end 94.84995 -399.253964)
		(stroke
			(width 0.07112)
			(type default)
		)
		(layer "In11.Cu")
	)
	(gr_line
		(start 95.174054 -379.89891)
		(end 95.467932 -379.262386)
		(stroke
			(width 0.07112)
			(type default)
		)
		(layer "In11.Cu")
	)
	(gr_line
		(start 95.212154 -379.144276)
		(end 95.2119 -379.144276)
		(stroke
			(width 0.07112)
			(type default)
		)
		(layer "In11.Cu")
	)
	(gr_line
		(start 95.287846 -399.308828)
		(end 95.106744 -399.373852)
		(stroke
			(width 0.07112)
			(type default)
		)
		(layer "In11.Cu")
	)
	(gr_line
		(start 95.323914 -378.575062)
		(end 95.50273 -378.187204)
		(stroke
			(width 0.07112)
			(type default)
		)
		(layer "In11.Cu")
	)
	(gr_line
		(start 95.335344 -385.579112)
		(end 95.388176 -385.548632)
		(stroke
			(width 0.07112)
			(type default)
		)
		(layer "In11.Cu")
	)
	(gr_line
		(start 95.388176 -385.548632)
		(end 95.476314 -385.460494)
		(stroke
			(width 0.07112)
			(type default)
		)
		(layer "In11.Cu")
	)
	(gr_line
		(start 95.390208 -378.755148)
		(end 95.323914 -378.575062)
		(stroke
			(width 0.07112)
			(type default)
		)
		(layer "In11.Cu")
	)
	(gr_line
		(start 95.390716 -378.756926)
		(end 95.39097 -378.756926)
		(stroke
			(width 0.07112)
			(type default)
		)
		(layer "In11.Cu")
	)
	(gr_line
		(start 95.405448 -398.741646)
		(end 95.470218 -398.922748)
		(stroke
			(width 0.07112)
			(type default)
		)
		(layer "In11.Cu")
	)
	(gr_line
		(start 95.406972 -221.083378)
		(end 95.361252 -221.129098)
		(stroke
			(width 0.05715)
			(type default)
		)
		(layer "In11.Cu")
	)
	(gr_line
		(start 95.406972 -221.05493)
		(end 95.406972 -221.083378)
		(stroke
			(width 0.05715)
			(type default)
		)
		(layer "In11.Cu")
	)
	(gr_line
		(start 95.470218 -398.922748)
		(end 95.287846 -399.308828)
		(stroke
			(width 0.07112)
			(type default)
		)
		(layer "In11.Cu")
	)
	(gr_arc
		(start 95.47098 -222.263462)
		(mid 95.475284 -222.26653)
		(end 95.479616 -222.269558)
		(stroke
			(width 0.05715)
			(type default)
		)
		(layer "In11.Cu")
	)
	(gr_line
		(start 95.476314 -385.460494)
		(end 95.476314 -385.334764)
		(stroke
			(width 0.07112)
			(type default)
		)
		(layer "In11.Cu")
	)
	(gr_line
		(start 95.479616 -222.269558)
		(end 95.480632 -222.27032)
		(stroke
			(width 0.05715)
			(type default)
		)
		(layer "In11.Cu")
	)
	(gr_line
		(start 95.480632 -222.27032)
		(end 95.481648 -222.270828)
		(stroke
			(width 0.05715)
			(type default)
		)
		(layer "In11.Cu")
	)
	(gr_line
		(start 95.481648 -222.270828)
		(end 95.486982 -222.273876)
		(stroke
			(width 0.05715)
			(type default)
		)
		(layer "In11.Cu")
	)
	(gr_line
		(start 95.50273 -378.187204)
		(end 95.68307 -378.12091)
		(stroke
			(width 0.07112)
			(type default)
		)
		(layer "In11.Cu")
	)
	(gr_line
		(start 95.547688 -406.731216)
		(end 95.274384 -407.00452)
		(stroke
			(width 0.07112)
			(type default)
		)
		(layer "In11.Cu")
	)
	(gr_line
		(start 95.547688 -406.696164)
		(end 95.547688 -406.731216)
		(stroke
			(width 0.07112)
			(type default)
		)
		(layer "In11.Cu")
	)
	(gr_line
		(start 95.632016 -397.599916)
		(end 95.332042 -398.234154)
		(stroke
			(width 0.07112)
			(type default)
		)
		(layer "In11.Cu")
	)
	(gr_line
		(start 95.646748 -378.875036)
		(end 95.94088 -378.238258)
		(stroke
			(width 0.07112)
			(type default)
		)
		(layer "In11.Cu")
	)
	(gr_line
		(start 95.685102 -378.120148)
		(end 95.684848 -378.120148)
		(stroke
			(width 0.07112)
			(type default)
		)
		(layer "In11.Cu")
	)
	(gr_line
		(start 95.769938 -398.289018)
		(end 95.588836 -398.354042)
		(stroke
			(width 0.07112)
			(type default)
		)
		(layer "In11.Cu")
	)
	(gr_line
		(start 95.830898 -406.697434)
		(end 96.137984 -407.00452)
		(stroke
			(width 0.07112)
			(type default)
		)
		(layer "In11.Cu")
	)
	(gr_line
		(start 95.88754 -397.721836)
		(end 95.95231 -397.902938)
		(stroke
			(width 0.07112)
			(type default)
		)
		(layer "In11.Cu")
	)
	(gr_line
		(start 95.919036 -388.774432)
		(end 95.97136 -388.826756)
		(stroke
			(width 0.07112)
			(type default)
		)
		(layer "In11.Cu")
	)
	(gr_line
		(start 95.919036 -385.31038)
		(end 96.27235 -385.405376)
		(stroke
			(width 0.07112)
			(type default)
		)
		(layer "In11.Cu")
	)
	(gr_line
		(start 95.95231 -397.902938)
		(end 95.769938 -398.289018)
		(stroke
			(width 0.07112)
			(type default)
		)
		(layer "In11.Cu")
	)
	(gr_line
		(start 95.97136 -389.006588)
		(end 95.824802 -389.153146)
		(stroke
			(width 0.07112)
			(type default)
		)
		(layer "In11.Cu")
	)
	(gr_line
		(start 95.97136 -388.826756)
		(end 95.97136 -389.006588)
		(stroke
			(width 0.07112)
			(type default)
		)
		(layer "In11.Cu")
	)
	(gr_line
		(start 96.069912 -221.083378)
		(end 96.115632 -221.129098)
		(stroke
			(width 0.05715)
			(type default)
		)
		(layer "In11.Cu")
	)
	(gr_line
		(start 96.069912 -221.05493)
		(end 96.069912 -221.083378)
		(stroke
			(width 0.05715)
			(type default)
		)
		(layer "In11.Cu")
	)
	(gr_line
		(start 96.07804 -384.780028)
		(end 96.078548 -384.72872)
		(stroke
			(width 0.07112)
			(type default)
		)
		(layer "In11.Cu")
	)
	(gr_arc
		(start 96.07804 -384.780028)
		(mid 96.089959 -384.841743)
		(end 96.124776 -384.894074)
		(stroke
			(width 0.07112)
			(type default)
		)
		(layer "In11.Cu")
	)
	(gr_line
		(start 96.161098 -384.930396)
		(end 96.124776 -384.894074)
		(stroke
			(width 0.07112)
			(type default)
		)
		(layer "In11.Cu")
	)
	(gr_line
		(start 96.204278 -389.352536)
		(end 96.02597 -389.352536)
		(stroke
			(width 0.07112)
			(type default)
		)
		(layer "In11.Cu")
	)
	(gr_line
		(start 96.244664 -379.928374)
		(end 96.471994 -379.566932)
		(stroke
			(width 0.07112)
			(type default)
		)
		(layer "In11.Cu")
	)
	(gr_line
		(start 96.27235 -385.405376)
		(end 96.272858 -385.404868)
		(stroke
			(width 0.07112)
			(type default)
		)
		(layer "In11.Cu")
	)
	(gr_line
		(start 96.287336 -380.11608)
		(end 96.244664 -379.928374)
		(stroke
			(width 0.07112)
			(type default)
		)
		(layer "In11.Cu")
	)
	(gr_line
		(start 96.319086 -389.467344)
		(end 96.204278 -389.352536)
		(stroke
			(width 0.07112)
			(type default)
		)
		(layer "In11.Cu")
	)
	(gr_line
		(start 96.319086 -386.003292)
		(end 96.413828 -385.649724)
		(stroke
			(width 0.07112)
			(type default)
		)
		(layer "In11.Cu")
	)
	(gr_line
		(start 96.351852 -221.083378)
		(end 96.306132 -221.129098)
		(stroke
			(width 0.05715)
			(type default)
		)
		(layer "In11.Cu")
	)
	(gr_line
		(start 96.351852 -221.05493)
		(end 96.351852 -221.083378)
		(stroke
			(width 0.05715)
			(type default)
		)
		(layer "In11.Cu")
	)
	(gr_line
		(start 96.363028 -384.42011)
		(end 96.363028 -384.419602)
		(stroke
			(width 0.07112)
			(type default)
		)
		(layer "In11.Cu")
	)
	(gr_arc
		(start 96.411034 -225.503486)
		(mid 96.414959 -225.506297)
		(end 96.418908 -225.509074)
		(stroke
			(width 0.05715)
			(type default)
		)
		(layer "In11.Cu")
	)
	(gr_line
		(start 96.418908 -225.509074)
		(end 96.425766 -225.513138)
		(stroke
			(width 0.05715)
			(type default)
		)
		(layer "In11.Cu")
	)
	(gr_line
		(start 96.425766 -225.513138)
		(end 96.426528 -225.513646)
		(stroke
			(width 0.05715)
			(type default)
		)
		(layer "In11.Cu")
	)
	(gr_line
		(start 96.426528 -225.513646)
		(end 96.427036 -225.5139)
		(stroke
			(width 0.05715)
			(type default)
		)
		(layer "In11.Cu")
	)
	(gr_line
		(start 96.430084 -296.463974)
		(end 96.430084 -296.435526)
		(stroke
			(width 0.05715)
			(type default)
		)
		(layer "In11.Cu")
	)
	(gr_line
		(start 96.430084 -296.435526)
		(end 96.475804 -296.389806)
		(stroke
			(width 0.05715)
			(type default)
		)
		(layer "In11.Cu")
	)
	(gr_line
		(start 96.45015 -222.287338)
		(end 96.451928 -222.288354)
		(stroke
			(width 0.05715)
			(type default)
		)
		(layer "In11.Cu")
	)
	(gr_line
		(start 96.451674 -225.528124)
		(end 96.45269 -225.528886)
		(stroke
			(width 0.05715)
			(type default)
		)
		(layer "In11.Cu")
	)
	(gr_line
		(start 96.451928 -222.288354)
		(end 96.452944 -222.288862)
		(stroke
			(width 0.05715)
			(type default)
		)
		(layer "In11.Cu")
	)
	(gr_line
		(start 96.45269 -225.528886)
		(end 96.453706 -225.529394)
		(stroke
			(width 0.05715)
			(type default)
		)
		(layer "In11.Cu")
	)
	(gr_line
		(start 96.452944 -222.288862)
		(end 96.453706 -222.28937)
		(stroke
			(width 0.05715)
			(type default)
		)
		(layer "In11.Cu")
	)
	(gr_line
		(start 96.45523 -225.53041)
		(end 96.457008 -225.531426)
		(stroke
			(width 0.05715)
			(type default)
		)
		(layer "In11.Cu")
	)
	(gr_line
		(start 96.457008 -225.531426)
		(end 96.458024 -225.531934)
		(stroke
			(width 0.05715)
			(type default)
		)
		(layer "In11.Cu")
	)
	(gr_line
		(start 96.458024 -225.531934)
		(end 96.458786 -225.532442)
		(stroke
			(width 0.05715)
			(type default)
		)
		(layer "In11.Cu")
	)
	(gr_line
		(start 96.458786 -225.532442)
		(end 96.460056 -225.533204)
		(stroke
			(width 0.05715)
			(type default)
		)
		(layer "In11.Cu")
	)
	(gr_line
		(start 96.471994 -379.566932)
		(end 96.659954 -379.52426)
		(stroke
			(width 0.07112)
			(type default)
		)
		(layer "In11.Cu")
	)
	(gr_line
		(start 96.51365 -400.977354)
		(end 96.513904 -400.977354)
		(stroke
			(width 0.07112)
			(type default)
		)
		(layer "In11.Cu")
	)
	(gr_line
		(start 96.513904 -400.977354)
		(end 96.485456 -401.090892)
		(stroke
			(width 0.07112)
			(type default)
		)
		(layer "In11.Cu")
	)
	(gr_line
		(start 96.515428 -400.976338)
		(end 96.51365 -400.977354)
		(stroke
			(width 0.07112)
			(type default)
		)
		(layer "In11.Cu")
	)
	(gr_line
		(start 96.52635 -380.267972)
		(end 96.899984 -379.674374)
		(stroke
			(width 0.07112)
			(type default)
		)
		(layer "In11.Cu")
	)
	(gr_line
		(start 96.535494 -385.579112)
		(end 96.588326 -385.548632)
		(stroke
			(width 0.07112)
			(type default)
		)
		(layer "In11.Cu")
	)
	(gr_line
		(start 96.546162 -222.122746)
		(end 96.553274 -222.126556)
		(stroke
			(width 0.05715)
			(type default)
		)
		(layer "In11.Cu")
	)
	(gr_line
		(start 96.546416 -225.36277)
		(end 96.546924 -225.363024)
		(stroke
			(width 0.05715)
			(type default)
		)
		(layer "In11.Cu")
	)
	(gr_line
		(start 96.546924 -225.363024)
		(end 96.54794 -225.363532)
		(stroke
			(width 0.05715)
			(type default)
		)
		(layer "In11.Cu")
	)
	(gr_line
		(start 96.54794 -225.363532)
		(end 96.549464 -225.364548)
		(stroke
			(width 0.05715)
			(type default)
		)
		(layer "In11.Cu")
	)
	(gr_line
		(start 96.552004 -225.365818)
		(end 96.553274 -225.36658)
		(stroke
			(width 0.05715)
			(type default)
		)
		(layer "In11.Cu")
	)
	(gr_line
		(start 96.553274 -225.36658)
		(end 96.554036 -225.367088)
		(stroke
			(width 0.05715)
			(type default)
		)
		(layer "In11.Cu")
	)
	(gr_line
		(start 96.554036 -225.367088)
		(end 96.555052 -225.367596)
		(stroke
			(width 0.05715)
			(type default)
		)
		(layer "In11.Cu")
	)
	(gr_line
		(start 96.588326 -385.548632)
		(end 96.676464 -385.460494)
		(stroke
			(width 0.07112)
			(type default)
		)
		(layer "In11.Cu")
	)
	(gr_line
		(start 96.656652 -400.41322)
		(end 96.515428 -400.976338)
		(stroke
			(width 0.07112)
			(type default)
		)
		(layer "In11.Cu")
	)
	(gr_line
		(start 96.658938 -400.41195)
		(end 96.656652 -400.41322)
		(stroke
			(width 0.07112)
			(type default)
		)
		(layer "In11.Cu")
	)
	(gr_line
		(start 96.676464 -385.460494)
		(end 96.676464 -385.334764)
		(stroke
			(width 0.07112)
			(type default)
		)
		(layer "In11.Cu")
	)
	(gr_line
		(start 96.712024 -296.463974)
		(end 96.712024 -296.435526)
		(stroke
			(width 0.05715)
			(type default)
		)
		(layer "In11.Cu")
	)
	(gr_line
		(start 96.712024 -296.435526)
		(end 96.666304 -296.389806)
		(stroke
			(width 0.05715)
			(type default)
		)
		(layer "In11.Cu")
	)
	(gr_arc
		(start 96.729296 -280.22677)
		(mid 96.73297 -280.229071)
		(end 96.736662 -280.231342)
		(stroke
			(width 0.05715)
			(type default)
		)
		(layer "In11.Cu")
	)
	(gr_arc
		(start 96.736662 -279.281382)
		(mid 96.732843 -279.283653)
		(end 96.729042 -279.285954)
		(stroke
			(width 0.05715)
			(type default)
		)
		(layer "In11.Cu")
	)
	(gr_line
		(start 96.737424 -280.23185)
		(end 96.736662 -280.231342)
		(stroke
			(width 0.05715)
			(type default)
		)
		(layer "In11.Cu")
	)
	(gr_line
		(start 96.790764 -399.876264)
		(end 96.793304 -399.880074)
		(stroke
			(width 0.07112)
			(type default)
		)
		(layer "In11.Cu")
	)
	(gr_line
		(start 96.793304 -399.880074)
		(end 96.764856 -399.993866)
		(stroke
			(width 0.07112)
			(type default)
		)
		(layer "In11.Cu")
	)
	(gr_line
		(start 96.832674 -280.066496)
		(end 96.83242 -280.066496)
		(stroke
			(width 0.05715)
			(type default)
		)
		(layer "In11.Cu")
	)
	(gr_line
		(start 96.845374 -378.973842)
		(end 97.072704 -378.6124)
		(stroke
			(width 0.07112)
			(type default)
		)
		(layer "In11.Cu")
	)
	(gr_line
		(start 96.865948 -381.10541)
		(end 97.09023 -380.74219)
		(stroke
			(width 0.07112)
			(type default)
		)
		(layer "In11.Cu")
	)
	(gr_arc
		(start 96.879664 -229.5525)
		(mid 96.884347 -229.555825)
		(end 96.889062 -229.559104)
		(stroke
			(width 0.05715)
			(type default)
		)
		(layer "In11.Cu")
	)
	(gr_line
		(start 96.885252 -279.415494)
		(end 96.892364 -279.41143)
		(stroke
			(width 0.05715)
			(type default)
		)
		(layer "In11.Cu")
	)
	(gr_line
		(start 96.8883 -379.161548)
		(end 96.845374 -378.973842)
		(stroke
			(width 0.07112)
			(type default)
		)
		(layer "In11.Cu")
	)
	(gr_line
		(start 96.889062 -229.559104)
		(end 96.891094 -229.560628)
		(stroke
			(width 0.05715)
			(type default)
		)
		(layer "In11.Cu")
	)
	(gr_line
		(start 96.891094 -229.560628)
		(end 96.89592 -229.563422)
		(stroke
			(width 0.05715)
			(type default)
		)
		(layer "In11.Cu")
	)
	(gr_arc
		(start 96.893126 -279.410922)
		(mid 96.892745 -279.411176)
		(end 96.892364 -279.41143)
		(stroke
			(width 0.05715)
			(type default)
		)
		(layer "In11.Cu")
	)
	(gr_arc
		(start 96.893126 -279.410922)
		(mid 96.897075 -279.408145)
		(end 96.901 -279.405334)
		(stroke
			(width 0.05715)
			(type default)
		)
		(layer "In11.Cu")
	)
	(gr_line
		(start 96.910398 -381.292862)
		(end 96.865948 -381.10541)
		(stroke
			(width 0.07112)
			(type default)
		)
		(layer "In11.Cu")
	)
	(gr_line
		(start 96.926908 -401.059142)
		(end 96.760538 -401.15871)
		(stroke
			(width 0.07112)
			(type default)
		)
		(layer "In11.Cu")
	)
	(gr_line
		(start 96.931226 -399.31594)
		(end 96.790764 -399.876264)
		(stroke
			(width 0.07112)
			(type default)
		)
		(layer "In11.Cu")
	)
	(gr_line
		(start 96.933258 -400.482562)
		(end 97.03054 -400.644868)
		(stroke
			(width 0.07112)
			(type default)
		)
		(layer "In11.Cu")
	)
	(gr_line
		(start 96.93402 -400.479768)
		(end 96.933258 -400.482562)
		(stroke
			(width 0.07112)
			(type default)
		)
		(layer "In11.Cu")
	)
	(gr_line
		(start 97.014792 -221.083378)
		(end 97.060512 -221.129098)
		(stroke
			(width 0.05715)
			(type default)
		)
		(layer "In11.Cu")
	)
	(gr_line
		(start 97.014792 -221.05493)
		(end 97.014792 -221.083378)
		(stroke
			(width 0.05715)
			(type default)
		)
		(layer "In11.Cu")
	)
	(gr_line
		(start 97.023428 -229.41661)
		(end 97.023936 -229.416864)
		(stroke
			(width 0.05715)
			(type default)
		)
		(layer "In11.Cu")
	)
	(gr_line
		(start 97.03054 -400.644868)
		(end 96.926908 -401.059142)
		(stroke
			(width 0.07112)
			(type default)
		)
		(layer "In11.Cu")
	)
	(gr_line
		(start 97.062544 -228.749352)
		(end 97.05467 -228.753924)
		(stroke
			(width 0.05715)
			(type default)
		)
		(layer "In11.Cu")
	)
	(gr_line
		(start 97.063052 -228.749098)
		(end 97.062544 -228.749352)
		(stroke
			(width 0.05715)
			(type default)
		)
		(layer "In11.Cu")
	)
	(gr_arc
		(start 97.063052 -228.749098)
		(mid 97.066235 -228.746823)
		(end 97.069402 -228.744526)
		(stroke
			(width 0.05715)
			(type default)
		)
		(layer "In11.Cu")
	)
	(gr_line
		(start 97.072704 -378.6124)
		(end 97.260664 -378.569728)
		(stroke
			(width 0.07112)
			(type default)
		)
		(layer "In11.Cu")
	)
	(gr_line
		(start 97.09023 -380.74219)
		(end 97.277682 -380.69774)
		(stroke
			(width 0.07112)
			(type default)
		)
		(layer "In11.Cu")
	)
	(gr_line
		(start 97.119186 -388.774432)
		(end 97.17151 -388.826756)
		(stroke
			(width 0.07112)
			(type default)
		)
		(layer "In11.Cu")
	)
	(gr_line
		(start 97.119186 -385.31038)
		(end 97.472246 -385.405376)
		(stroke
			(width 0.07112)
			(type default)
		)
		(layer "In11.Cu")
	)
	(gr_line
		(start 97.127314 -379.31344)
		(end 97.500948 -378.719842)
		(stroke
			(width 0.07112)
			(type default)
		)
		(layer "In11.Cu")
	)
	(gr_line
		(start 97.150936 -381.442468)
		(end 97.519236 -380.845568)
		(stroke
			(width 0.07112)
			(type default)
		)
		(layer "In11.Cu")
	)
	(gr_line
		(start 97.17151 -389.006588)
		(end 97.024952 -389.153146)
		(stroke
			(width 0.07112)
			(type default)
		)
		(layer "In11.Cu")
	)
	(gr_line
		(start 97.17151 -388.826756)
		(end 97.17151 -389.006588)
		(stroke
			(width 0.07112)
			(type default)
		)
		(layer "In11.Cu")
	)
	(gr_arc
		(start 97.185734 -286.583882)
		(mid 97.182679 -286.586031)
		(end 97.179638 -286.5882)
		(stroke
			(width 0.05715)
			(type default)
		)
		(layer "In11.Cu")
	)
	(gr_line
		(start 97.189036 -286.581596)
		(end 97.191068 -286.580072)
		(stroke
			(width 0.05715)
			(type default)
		)
		(layer "In11.Cu")
	)
	(gr_line
		(start 97.191068 -286.580072)
		(end 97.196148 -286.577024)
		(stroke
			(width 0.05715)
			(type default)
		)
		(layer "In11.Cu")
	)
	(gr_line
		(start 97.196148 -286.577024)
		(end 97.19691 -286.576516)
		(stroke
			(width 0.05715)
			(type default)
		)
		(layer "In11.Cu")
	)
	(gr_line
		(start 97.19691 -286.576516)
		(end 97.198688 -286.5755)
		(stroke
			(width 0.05715)
			(type default)
		)
		(layer "In11.Cu")
	)
	(gr_line
		(start 97.200974 -399.965164)
		(end 97.039938 -400.06143)
		(stroke
			(width 0.07112)
			(type default)
		)
		(layer "In11.Cu")
	)
	(gr_line
		(start 97.205292 -398.221962)
		(end 97.034858 -398.902174)
		(stroke
			(width 0.07112)
			(type default)
		)
		(layer "In11.Cu")
	)
	(gr_line
		(start 97.205546 -399.38579)
		(end 97.304606 -399.55089)
		(stroke
			(width 0.07112)
			(type default)
		)
		(layer "In11.Cu")
	)
	(gr_line
		(start 97.296732 -221.083378)
		(end 97.251012 -221.129098)
		(stroke
			(width 0.05715)
			(type default)
		)
		(layer "In11.Cu")
	)
	(gr_line
		(start 97.296732 -221.05493)
		(end 97.296732 -221.083378)
		(stroke
			(width 0.05715)
			(type default)
		)
		(layer "In11.Cu")
	)
	(gr_line
		(start 97.304606 -399.55089)
		(end 97.200974 -399.965164)
		(stroke
			(width 0.07112)
			(type default)
		)
		(layer "In11.Cu")
	)
	(gr_line
		(start 97.370138 -296.463974)
		(end 97.370138 -296.435526)
		(stroke
			(width 0.05715)
			(type default)
		)
		(layer "In11.Cu")
	)
	(gr_line
		(start 97.370138 -296.435526)
		(end 97.415858 -296.389806)
		(stroke
			(width 0.05715)
			(type default)
		)
		(layer "In11.Cu")
	)
	(gr_line
		(start 97.39884 -225.532442)
		(end 97.399348 -225.532696)
		(stroke
			(width 0.05715)
			(type default)
		)
		(layer "In11.Cu")
	)
	(gr_line
		(start 97.40138 -225.533712)
		(end 97.402142 -225.53422)
		(stroke
			(width 0.05715)
			(type default)
		)
		(layer "In11.Cu")
	)
	(gr_line
		(start 97.404174 -389.352536)
		(end 97.22612 -389.352536)
		(stroke
			(width 0.07112)
			(type default)
		)
		(layer "In11.Cu")
	)
	(gr_line
		(start 97.409254 -244.978174)
		(end 97.410524 -244.978936)
		(stroke
			(width 0.05715)
			(type default)
		)
		(layer "In11.Cu")
	)
	(gr_line
		(start 97.446338 -378.01931)
		(end 97.673668 -377.657868)
		(stroke
			(width 0.07112)
			(type default)
		)
		(layer "In11.Cu")
	)
	(gr_line
		(start 97.45853 -380.145798)
		(end 97.682812 -379.782324)
		(stroke
			(width 0.07112)
			(type default)
		)
		(layer "In11.Cu")
	)
	(gr_line
		(start 97.472246 -385.405376)
		(end 97.472754 -385.404868)
		(stroke
			(width 0.07112)
			(type default)
		)
		(layer "In11.Cu")
	)
	(gr_line
		(start 97.47504 -398.871186)
		(end 97.309686 -398.969992)
		(stroke
			(width 0.07112)
			(type default)
		)
		(layer "In11.Cu")
	)
	(gr_line
		(start 97.479612 -398.291812)
		(end 97.578672 -398.456912)
		(stroke
			(width 0.07112)
			(type default)
		)
		(layer "In11.Cu")
	)
	(gr_line
		(start 97.489264 -378.207016)
		(end 97.446338 -378.01931)
		(stroke
			(width 0.07112)
			(type default)
		)
		(layer "In11.Cu")
	)
	(gr_line
		(start 97.493582 -225.366834)
		(end 97.49409 -225.367088)
		(stroke
			(width 0.05715)
			(type default)
		)
		(layer "In11.Cu")
	)
	(gr_line
		(start 97.49409 -225.367088)
		(end 97.495868 -225.368104)
		(stroke
			(width 0.05715)
			(type default)
		)
		(layer "In11.Cu")
	)
	(gr_line
		(start 97.495868 -225.368104)
		(end 97.497392 -225.36912)
		(stroke
			(width 0.05715)
			(type default)
		)
		(layer "In11.Cu")
	)
	(gr_arc
		(start 97.497138 -222.128842)
		(mid 97.497773 -222.129223)
		(end 97.498408 -222.129604)
		(stroke
			(width 0.05715)
			(type default)
		)
		(layer "In11.Cu")
	)
	(gr_line
		(start 97.50298 -380.332996)
		(end 97.45853 -380.145798)
		(stroke
			(width 0.07112)
			(type default)
		)
		(layer "In11.Cu")
	)
	(gr_line
		(start 97.517712 -225.380804)
		(end 97.527872 -225.386646)
		(stroke
			(width 0.05715)
			(type default)
		)
		(layer "In11.Cu")
	)
	(gr_line
		(start 97.518982 -389.467344)
		(end 97.404174 -389.352536)
		(stroke
			(width 0.07112)
			(type default)
		)
		(layer "In11.Cu")
	)
	(gr_line
		(start 97.518982 -386.003292)
		(end 97.613724 -385.649724)
		(stroke
			(width 0.07112)
			(type default)
		)
		(layer "In11.Cu")
	)
	(gr_arc
		(start 97.540064 -225.395282)
		(mid 97.535257 -225.3917)
		(end 97.530412 -225.38817)
		(stroke
			(width 0.05715)
			(type default)
		)
		(layer "In11.Cu")
	)
	(gr_line
		(start 97.578672 -398.456912)
		(end 97.47504 -398.871186)
		(stroke
			(width 0.07112)
			(type default)
		)
		(layer "In11.Cu")
	)
	(gr_line
		(start 97.585784 -225.871532)
		(end 97.585784 -225.87077)
		(stroke
			(width 0.05715)
			(type default)
		)
		(layer "In11.Cu")
	)
	(gr_line
		(start 97.585784 -225.870516)
		(end 97.585784 -225.87077)
		(stroke
			(width 0.05715)
			(type default)
		)
		(layer "In11.Cu")
	)
	(gr_arc
		(start 97.585784 -225.870008)
		(mid 97.585784 -225.870262)
		(end 97.585784 -225.870516)
		(stroke
			(width 0.05715)
			(type default)
		)
		(layer "In11.Cu")
	)
	(gr_line
		(start 97.652078 -296.463974)
		(end 97.652078 -296.435526)
		(stroke
			(width 0.05715)
			(type default)
		)
		(layer "In11.Cu")
	)
	(gr_line
		(start 97.652078 -296.435526)
		(end 97.606358 -296.389806)
		(stroke
			(width 0.05715)
			(type default)
		)
		(layer "In11.Cu")
	)
	(gr_line
		(start 97.673668 -377.657868)
		(end 97.861628 -377.615196)
		(stroke
			(width 0.07112)
			(type default)
		)
		(layer "In11.Cu")
	)
	(gr_line
		(start 97.682812 -379.782324)
		(end 97.870264 -379.738382)
		(stroke
			(width 0.07112)
			(type default)
		)
		(layer "In11.Cu")
	)
	(gr_line
		(start 97.691956 -280.240232)
		(end 97.69094 -280.23947)
		(stroke
			(width 0.05715)
			(type default)
		)
		(layer "In11.Cu")
	)
	(gr_line
		(start 97.691956 -277.65248)
		(end 97.698052 -277.648924)
		(stroke
			(width 0.05715)
			(type default)
		)
		(layer "In11.Cu")
	)
	(gr_line
		(start 97.69221 -279.272492)
		(end 97.695512 -279.27046)
		(stroke
			(width 0.05715)
			(type default)
		)
		(layer "In11.Cu")
	)
	(gr_line
		(start 97.694496 -280.241756)
		(end 97.691956 -280.240232)
		(stroke
			(width 0.05715)
			(type default)
		)
		(layer "In11.Cu")
	)
	(gr_line
		(start 97.695512 -280.242264)
		(end 97.694496 -280.241756)
		(stroke
			(width 0.05715)
			(type default)
		)
		(layer "In11.Cu")
	)
	(gr_line
		(start 97.695512 -279.27046)
		(end 97.697036 -279.269444)
		(stroke
			(width 0.05715)
			(type default)
		)
		(layer "In11.Cu")
	)
	(gr_line
		(start 97.697036 -280.24328)
		(end 97.695512 -280.242264)
		(stroke
			(width 0.05715)
			(type default)
		)
		(layer "In11.Cu")
	)
	(gr_line
		(start 97.697036 -279.269444)
		(end 97.698052 -279.268936)
		(stroke
			(width 0.05715)
			(type default)
		)
		(layer "In11.Cu")
	)
	(gr_line
		(start 97.698052 -280.243788)
		(end 97.697036 -280.24328)
		(stroke
			(width 0.05715)
			(type default)
		)
		(layer "In11.Cu")
	)
	(gr_line
		(start 97.698052 -279.268936)
		(end 97.698814 -279.268428)
		(stroke
			(width 0.05715)
			(type default)
		)
		(layer "In11.Cu")
	)
	(gr_line
		(start 97.698052 -277.648924)
		(end 97.698814 -277.648416)
		(stroke
			(width 0.05715)
			(type default)
		)
		(layer "In11.Cu")
	)
	(gr_line
		(start 97.728278 -378.358908)
		(end 98.101912 -377.76531)
		(stroke
			(width 0.07112)
			(type default)
		)
		(layer "In11.Cu")
	)
	(gr_line
		(start 97.73539 -385.579112)
		(end 97.788222 -385.548632)
		(stroke
			(width 0.07112)
			(type default)
		)
		(layer "In11.Cu")
	)
	(gr_line
		(start 97.743264 -380.482856)
		(end 98.111818 -379.885956)
		(stroke
			(width 0.07112)
			(type default)
		)
		(layer "In11.Cu")
	)
	(gr_line
		(start 97.768156 -225.789998)
		(end 97.76841 -225.791014)
		(stroke
			(width 0.05715)
			(type default)
		)
		(layer "In11.Cu")
	)
	(gr_line
		(start 97.78746 -280.075132)
		(end 97.786444 -280.074624)
		(stroke
			(width 0.05715)
			(type default)
		)
		(layer "In11.Cu")
	)
	(gr_line
		(start 97.788222 -385.548632)
		(end 97.87636 -385.460494)
		(stroke
			(width 0.07112)
			(type default)
		)
		(layer "In11.Cu")
	)
	(gr_line
		(start 97.788222 -280.07564)
		(end 97.78746 -280.075132)
		(stroke
			(width 0.05715)
			(type default)
		)
		(layer "In11.Cu")
	)
	(gr_line
		(start 97.789746 -280.076402)
		(end 97.788222 -280.07564)
		(stroke
			(width 0.05715)
			(type default)
		)
		(layer "In11.Cu")
	)
	(gr_line
		(start 97.790508 -280.07691)
		(end 97.789746 -280.076402)
		(stroke
			(width 0.05715)
			(type default)
		)
		(layer "In11.Cu")
	)
	(gr_line
		(start 97.791524 -279.435306)
		(end 97.793302 -279.43429)
		(stroke
			(width 0.05715)
			(type default)
		)
		(layer "In11.Cu")
	)
	(gr_line
		(start 97.793302 -280.078434)
		(end 97.792794 -280.07818)
		(stroke
			(width 0.05715)
			(type default)
		)
		(layer "In11.Cu")
	)
	(gr_line
		(start 97.793302 -279.43429)
		(end 97.794064 -279.433782)
		(stroke
			(width 0.05715)
			(type default)
		)
		(layer "In11.Cu")
	)
	(gr_line
		(start 97.79381 -280.078688)
		(end 97.793302 -280.078434)
		(stroke
			(width 0.05715)
			(type default)
		)
		(layer "In11.Cu")
	)
	(gr_line
		(start 97.794064 -279.433782)
		(end 97.79508 -279.433274)
		(stroke
			(width 0.05715)
			(type default)
		)
		(layer "In11.Cu")
	)
	(gr_line
		(start 97.794318 -277.81377)
		(end 97.79508 -277.813262)
		(stroke
			(width 0.05715)
			(type default)
		)
		(layer "In11.Cu")
	)
	(gr_arc
		(start 97.818194 -229.55123)
		(mid 97.82489 -229.556105)
		(end 97.831656 -229.560882)
		(stroke
			(width 0.05715)
			(type default)
		)
		(layer "In11.Cu")
	)
	(gr_arc
		(start 97.822512 -226.314508)
		(mid 97.827068 -226.317706)
		(end 97.831656 -226.320858)
		(stroke
			(width 0.05715)
			(type default)
		)
		(layer "In11.Cu")
	)
	(gr_line
		(start 97.82556 -280.09723)
		(end 97.824798 -280.096722)
		(stroke
			(width 0.05715)
			(type default)
		)
		(layer "In11.Cu")
	)
	(gr_line
		(start 97.826322 -280.097738)
		(end 97.82556 -280.09723)
		(stroke
			(width 0.05715)
			(type default)
		)
		(layer "In11.Cu")
	)
	(gr_line
		(start 97.831656 -229.560882)
		(end 97.83445 -229.562406)
		(stroke
			(width 0.05715)
			(type default)
		)
		(layer "In11.Cu")
	)
	(gr_line
		(start 97.831656 -226.320858)
		(end 97.83318 -226.321874)
		(stroke
			(width 0.05715)
			(type default)
		)
		(layer "In11.Cu")
	)
	(gr_line
		(start 97.83318 -280.101802)
		(end 97.826322 -280.097738)
		(stroke
			(width 0.05715)
			(type default)
		)
		(layer "In11.Cu")
	)
	(gr_line
		(start 97.83318 -226.321874)
		(end 97.837752 -226.324414)
		(stroke
			(width 0.05715)
			(type default)
		)
		(layer "In11.Cu")
	)
	(gr_arc
		(start 97.83445 -230.246428)
		(mid 97.826016 -230.252066)
		(end 97.817686 -230.257858)
		(stroke
			(width 0.05715)
			(type default)
		)
		(layer "In11.Cu")
	)
	(gr_line
		(start 97.835974 -230.245412)
		(end 97.83445 -230.246428)
		(stroke
			(width 0.05715)
			(type default)
		)
		(layer "In11.Cu")
	)
	(gr_line
		(start 97.83699 -230.244904)
		(end 97.835974 -230.245412)
		(stroke
			(width 0.05715)
			(type default)
		)
		(layer "In11.Cu")
	)
	(gr_arc
		(start 97.841054 -280.10739)
		(mid 97.837129 -280.104579)
		(end 97.83318 -280.101802)
		(stroke
			(width 0.05715)
			(type default)
		)
		(layer "In11.Cu")
	)
	(gr_arc
		(start 97.856548 -242.535202)
		(mid 97.858958 -242.536605)
		(end 97.861374 -242.537996)
		(stroke
			(width 0.05715)
			(type default)
		)
		(layer "In11.Cu")
	)
	(gr_arc
		(start 97.856548 -240.91519)
		(mid 97.858958 -240.916593)
		(end 97.861374 -240.917984)
		(stroke
			(width 0.05715)
			(type default)
		)
		(layer "In11.Cu")
	)
	(gr_arc
		(start 97.856548 -239.295178)
		(mid 97.858958 -239.296581)
		(end 97.861374 -239.297972)
		(stroke
			(width 0.05715)
			(type default)
		)
		(layer "In11.Cu")
	)
	(gr_arc
		(start 97.856548 -237.675166)
		(mid 97.858958 -237.676569)
		(end 97.861374 -237.67796)
		(stroke
			(width 0.05715)
			(type default)
		)
		(layer "In11.Cu")
	)
	(gr_arc
		(start 97.856548 -236.055154)
		(mid 97.858324 -236.056301)
		(end 97.860104 -236.05744)
		(stroke
			(width 0.05715)
			(type default)
		)
		(layer "In11.Cu")
	)
	(gr_line
		(start 97.866962 -230.227378)
		(end 97.865438 -230.228394)
		(stroke
			(width 0.05715)
			(type default)
		)
		(layer "In11.Cu")
	)
	(gr_line
		(start 97.867724 -242.541806)
		(end 97.867978 -242.541806)
		(stroke
			(width 0.05715)
			(type default)
		)
		(layer "In11.Cu")
	)
	(gr_line
		(start 97.867724 -240.921794)
		(end 97.867978 -240.921794)
		(stroke
			(width 0.05715)
			(type default)
		)
		(layer "In11.Cu")
	)
	(gr_line
		(start 97.867724 -239.301782)
		(end 97.867978 -239.301782)
		(stroke
			(width 0.05715)
			(type default)
		)
		(layer "In11.Cu")
	)
	(gr_line
		(start 97.867724 -237.68177)
		(end 97.867978 -237.68177)
		(stroke
			(width 0.05715)
			(type default)
		)
		(layer "In11.Cu")
	)
	(gr_line
		(start 97.867724 -236.061758)
		(end 97.867978 -236.061758)
		(stroke
			(width 0.05715)
			(type default)
		)
		(layer "In11.Cu")
	)
	(gr_line
		(start 97.867978 -241.566954)
		(end 97.867724 -241.567208)
		(stroke
			(width 0.05715)
			(type default)
		)
		(layer "In11.Cu")
	)
	(gr_line
		(start 97.867978 -239.946942)
		(end 97.867724 -239.947196)
		(stroke
			(width 0.05715)
			(type default)
		)
		(layer "In11.Cu")
	)
	(gr_line
		(start 97.867978 -238.32693)
		(end 97.867724 -238.327184)
		(stroke
			(width 0.05715)
			(type default)
		)
		(layer "In11.Cu")
	)
	(gr_line
		(start 97.867978 -236.706918)
		(end 97.867724 -236.707172)
		(stroke
			(width 0.05715)
			(type default)
		)
		(layer "In11.Cu")
	)
	(gr_line
		(start 97.867978 -235.086906)
		(end 97.867724 -235.08716)
		(stroke
			(width 0.05715)
			(type default)
		)
		(layer "In11.Cu")
	)
	(gr_line
		(start 97.867978 -232.821734)
		(end 97.868486 -232.821988)
		(stroke
			(width 0.05715)
			(type default)
		)
		(layer "In11.Cu")
	)
	(gr_line
		(start 97.867978 -230.22687)
		(end 97.866962 -230.227378)
		(stroke
			(width 0.05715)
			(type default)
		)
		(layer "In11.Cu")
	)
	(gr_line
		(start 97.868486 -230.226616)
		(end 97.867978 -230.22687)
		(stroke
			(width 0.05715)
			(type default)
		)
		(layer "In11.Cu")
	)
	(gr_line
		(start 97.86874 -234.442254)
		(end 97.869248 -234.442508)
		(stroke
			(width 0.05715)
			(type default)
		)
		(layer "In11.Cu")
	)
	(gr_line
		(start 97.86874 -228.606604)
		(end 97.867978 -228.607112)
		(stroke
			(width 0.05715)
			(type default)
		)
		(layer "In11.Cu")
	)
	(gr_line
		(start 97.86874 -223.746568)
		(end 97.867978 -223.747076)
		(stroke
			(width 0.05715)
			(type default)
		)
		(layer "In11.Cu")
	)
	(gr_line
		(start 97.869248 -223.746314)
		(end 97.86874 -223.746568)
		(stroke
			(width 0.05715)
			(type default)
		)
		(layer "In11.Cu")
	)
	(gr_line
		(start 97.870264 -228.605842)
		(end 97.86874 -228.606604)
		(stroke
			(width 0.05715)
			(type default)
		)
		(layer "In11.Cu")
	)
	(gr_line
		(start 97.87128 -223.745298)
		(end 97.870518 -223.745552)
		(stroke
			(width 0.05715)
			(type default)
		)
		(layer "In11.Cu")
	)
	(gr_line
		(start 97.871534 -236.06379)
		(end 97.872296 -236.064298)
		(stroke
			(width 0.05715)
			(type default)
		)
		(layer "In11.Cu")
	)
	(gr_line
		(start 97.872296 -236.064298)
		(end 97.87382 -236.065314)
		(stroke
			(width 0.05715)
			(type default)
		)
		(layer "In11.Cu")
	)
	(gr_line
		(start 97.876106 -223.74225)
		(end 97.873566 -223.743774)
		(stroke
			(width 0.05715)
			(type default)
		)
		(layer "In11.Cu")
	)
	(gr_line
		(start 97.87636 -385.460494)
		(end 97.87636 -385.334764)
		(stroke
			(width 0.07112)
			(type default)
		)
		(layer "In11.Cu")
	)
	(gr_line
		(start 97.877884 -223.741234)
		(end 97.876614 -223.741996)
		(stroke
			(width 0.05715)
			(type default)
		)
		(layer "In11.Cu")
	)
	(gr_line
		(start 97.878138 -228.60127)
		(end 97.877376 -228.601778)
		(stroke
			(width 0.05715)
			(type default)
		)
		(layer "In11.Cu")
	)
	(gr_line
		(start 97.887282 -223.7359)
		(end 97.886266 -223.736408)
		(stroke
			(width 0.05715)
			(type default)
		)
		(layer "In11.Cu")
	)
	(gr_line
		(start 97.8916 -223.73336)
		(end 97.887282 -223.7359)
		(stroke
			(width 0.05715)
			(type default)
		)
		(layer "In11.Cu")
	)
	(gr_line
		(start 97.959672 -221.083378)
		(end 98.005392 -221.129098)
		(stroke
			(width 0.05715)
			(type default)
		)
		(layer "In11.Cu")
	)
	(gr_line
		(start 97.959672 -221.05493)
		(end 97.959672 -221.083378)
		(stroke
			(width 0.05715)
			(type default)
		)
		(layer "In11.Cu")
	)
	(gr_line
		(start 97.961958 -230.39324)
		(end 97.960434 -230.394002)
		(stroke
			(width 0.05715)
			(type default)
		)
		(layer "In11.Cu")
	)
	(gr_line
		(start 97.963228 -230.392478)
		(end 97.961958 -230.39324)
		(stroke
			(width 0.05715)
			(type default)
		)
		(layer "In11.Cu")
	)
	(gr_line
		(start 97.963228 -228.772466)
		(end 97.96272 -228.77272)
		(stroke
			(width 0.05715)
			(type default)
		)
		(layer "In11.Cu")
	)
	(gr_line
		(start 97.963482 -242.376706)
		(end 97.968562 -242.3795)
		(stroke
			(width 0.05715)
			(type default)
		)
		(layer "In11.Cu")
	)
	(gr_line
		(start 97.963482 -240.756694)
		(end 97.968562 -240.759488)
		(stroke
			(width 0.05715)
			(type default)
		)
		(layer "In11.Cu")
	)
	(gr_line
		(start 97.963482 -239.136682)
		(end 97.968562 -239.139476)
		(stroke
			(width 0.05715)
			(type default)
		)
		(layer "In11.Cu")
	)
	(gr_line
		(start 97.963482 -237.51667)
		(end 97.968562 -237.519464)
		(stroke
			(width 0.05715)
			(type default)
		)
		(layer "In11.Cu")
	)
	(gr_line
		(start 97.963482 -235.896658)
		(end 97.967038 -235.89869)
		(stroke
			(width 0.05715)
			(type default)
		)
		(layer "In11.Cu")
	)
	(gr_line
		(start 97.96399 -228.771958)
		(end 97.963228 -228.772466)
		(stroke
			(width 0.05715)
			(type default)
		)
		(layer "In11.Cu")
	)
	(gr_line
		(start 97.965006 -228.77145)
		(end 97.96399 -228.771958)
		(stroke
			(width 0.05715)
			(type default)
		)
		(layer "In11.Cu")
	)
	(gr_line
		(start 97.96653 -228.770434)
		(end 97.965006 -228.77145)
		(stroke
			(width 0.05715)
			(type default)
		)
		(layer "In11.Cu")
	)
	(gr_line
		(start 97.967038 -235.89869)
		(end 97.968562 -235.899452)
		(stroke
			(width 0.05715)
			(type default)
		)
		(layer "In11.Cu")
	)
	(gr_line
		(start 97.967546 -228.769926)
		(end 97.96653 -228.770434)
		(stroke
			(width 0.05715)
			(type default)
		)
		(layer "In11.Cu")
	)
	(gr_line
		(start 97.968562 -242.3795)
		(end 97.969324 -242.380008)
		(stroke
			(width 0.05715)
			(type default)
		)
		(layer "In11.Cu")
	)
	(gr_line
		(start 97.968562 -240.759488)
		(end 97.969324 -240.759996)
		(stroke
			(width 0.05715)
			(type default)
		)
		(layer "In11.Cu")
	)
	(gr_line
		(start 97.968562 -239.139476)
		(end 97.969324 -239.139984)
		(stroke
			(width 0.05715)
			(type default)
		)
		(layer "In11.Cu")
	)
	(gr_line
		(start 97.968562 -237.519464)
		(end 97.969324 -237.519972)
		(stroke
			(width 0.05715)
			(type default)
		)
		(layer "In11.Cu")
	)
	(gr_line
		(start 97.969324 -242.380008)
		(end 97.97034 -242.380516)
		(stroke
			(width 0.05715)
			(type default)
		)
		(layer "In11.Cu")
	)
	(gr_line
		(start 97.969324 -240.759996)
		(end 97.97034 -240.760504)
		(stroke
			(width 0.05715)
			(type default)
		)
		(layer "In11.Cu")
	)
	(gr_line
		(start 97.969324 -239.139984)
		(end 97.97034 -239.140492)
		(stroke
			(width 0.05715)
			(type default)
		)
		(layer "In11.Cu")
	)
	(gr_line
		(start 97.969324 -237.519972)
		(end 97.97034 -237.52048)
		(stroke
			(width 0.05715)
			(type default)
		)
		(layer "In11.Cu")
	)
	(gr_line
		(start 97.972626 -228.766878)
		(end 97.967546 -228.769926)
		(stroke
			(width 0.05715)
			(type default)
		)
		(layer "In11.Cu")
	)
	(gr_line
		(start 97.978214 -223.903794)
		(end 97.974404 -223.905826)
		(stroke
			(width 0.05715)
			(type default)
		)
		(layer "In11.Cu")
	)
	(gr_line
		(start 97.978976 -247.724422)
		(end 97.681034 -247.724422)
		(stroke
			(width 0.05715)
			(type default)
		)
		(layer "In11.Cu")
	)
	(gr_line
		(start 97.978976 -246.10441)
		(end 97.681034 -246.10441)
		(stroke
			(width 0.05715)
			(type default)
		)
		(layer "In11.Cu")
	)
	(gr_line
		(start 97.978976 -244.484398)
		(end 97.681034 -244.484398)
		(stroke
			(width 0.05715)
			(type default)
		)
		(layer "In11.Cu")
	)
	(gr_line
		(start 97.982024 -223.901508)
		(end 97.981008 -223.902016)
		(stroke
			(width 0.05715)
			(type default)
		)
		(layer "In11.Cu")
	)
	(gr_line
		(start 97.982786 -223.901)
		(end 97.982024 -223.901508)
		(stroke
			(width 0.05715)
			(type default)
		)
		(layer "In11.Cu")
	)
	(gr_line
		(start 97.983802 -223.900492)
		(end 97.982786 -223.901)
		(stroke
			(width 0.05715)
			(type default)
		)
		(layer "In11.Cu")
	)
	(gr_line
		(start 97.985072 -241.719608)
		(end 97.984818 -241.719608)
		(stroke
			(width 0.05715)
			(type default)
		)
		(layer "In11.Cu")
	)
	(gr_line
		(start 97.985072 -240.099596)
		(end 97.984818 -240.099596)
		(stroke
			(width 0.05715)
			(type default)
		)
		(layer "In11.Cu")
	)
	(gr_line
		(start 97.985072 -238.479584)
		(end 97.984818 -238.479584)
		(stroke
			(width 0.05715)
			(type default)
		)
		(layer "In11.Cu")
	)
	(gr_line
		(start 97.985072 -236.859572)
		(end 97.984818 -236.859572)
		(stroke
			(width 0.05715)
			(type default)
		)
		(layer "In11.Cu")
	)
	(gr_line
		(start 97.985072 -235.23956)
		(end 97.984818 -235.23956)
		(stroke
			(width 0.05715)
			(type default)
		)
		(layer "In11.Cu")
	)
	(gr_line
		(start 97.994216 -235.914438)
		(end 97.995232 -235.914946)
		(stroke
			(width 0.05715)
			(type default)
		)
		(layer "In11.Cu")
	)
	(gr_line
		(start 97.99447 -242.39474)
		(end 98.002344 -242.399312)
		(stroke
			(width 0.05715)
			(type default)
		)
		(layer "In11.Cu")
	)
	(gr_line
		(start 97.99447 -240.774728)
		(end 98.002344 -240.7793)
		(stroke
			(width 0.05715)
			(type default)
		)
		(layer "In11.Cu")
	)
	(gr_line
		(start 97.99447 -239.154716)
		(end 98.002344 -239.159288)
		(stroke
			(width 0.05715)
			(type default)
		)
		(layer "In11.Cu")
	)
	(gr_line
		(start 97.99447 -237.534704)
		(end 98.002344 -237.539276)
		(stroke
			(width 0.05715)
			(type default)
		)
		(layer "In11.Cu")
	)
	(gr_line
		(start 97.994724 -245.635018)
		(end 98.002344 -245.639336)
		(stroke
			(width 0.05715)
			(type default)
		)
		(layer "In11.Cu")
	)
	(gr_line
		(start 97.994724 -224.574862)
		(end 97.995486 -224.57537)
		(stroke
			(width 0.05715)
			(type default)
		)
		(layer "In11.Cu")
	)
	(gr_line
		(start 97.994978 -241.713766)
		(end 97.993454 -241.714782)
		(stroke
			(width 0.05715)
			(type default)
		)
		(layer "In11.Cu")
	)
	(gr_line
		(start 97.994978 -240.093754)
		(end 97.993454 -240.09477)
		(stroke
			(width 0.05715)
			(type default)
		)
		(layer "In11.Cu")
	)
	(gr_line
		(start 97.994978 -238.473742)
		(end 97.993454 -238.474758)
		(stroke
			(width 0.05715)
			(type default)
		)
		(layer "In11.Cu")
	)
	(gr_line
		(start 97.994978 -236.85373)
		(end 97.993454 -236.854746)
		(stroke
			(width 0.05715)
			(type default)
		)
		(layer "In11.Cu")
	)
	(gr_line
		(start 97.994978 -235.233718)
		(end 97.993454 -235.234734)
		(stroke
			(width 0.05715)
			(type default)
		)
		(layer "In11.Cu")
	)
	(gr_line
		(start 97.994978 -234.29468)
		(end 97.99955 -234.29722)
		(stroke
			(width 0.05715)
			(type default)
		)
		(layer "In11.Cu")
	)
	(gr_line
		(start 97.995232 -235.914946)
		(end 97.995994 -235.915454)
		(stroke
			(width 0.05715)
			(type default)
		)
		(layer "In11.Cu")
	)
	(gr_line
		(start 97.995486 -224.57537)
		(end 97.996248 -224.575878)
		(stroke
			(width 0.05715)
			(type default)
		)
		(layer "In11.Cu")
	)
	(gr_line
		(start 97.99574 -222.955612)
		(end 97.996248 -222.955866)
		(stroke
			(width 0.05715)
			(type default)
		)
		(layer "In11.Cu")
	)
	(gr_line
		(start 97.995994 -235.915454)
		(end 98.002344 -235.919264)
		(stroke
			(width 0.05715)
			(type default)
		)
		(layer "In11.Cu")
	)
	(gr_line
		(start 97.996248 -224.575878)
		(end 98.003106 -224.579942)
		(stroke
			(width 0.05715)
			(type default)
		)
		(layer "In11.Cu")
	)
	(gr_line
		(start 97.996248 -222.955866)
		(end 98.003106 -222.95993)
		(stroke
			(width 0.05715)
			(type default)
		)
		(layer "In11.Cu")
	)
	(gr_line
		(start 97.99955 -234.29722)
		(end 98.002344 -234.299252)
		(stroke
			(width 0.05715)
			(type default)
		)
		(layer "In11.Cu")
	)
	(gr_line
		(start 98.000312 -227.131118)
		(end 97.994978 -227.134166)
		(stroke
			(width 0.05715)
			(type default)
		)
		(layer "In11.Cu")
	)
	(gr_arc
		(start 98.002344 -245.639336)
		(mid 98.002725 -245.63959)
		(end 98.003106 -245.639844)
		(stroke
			(width 0.05715)
			(type default)
		)
		(layer "In11.Cu")
	)
	(gr_arc
		(start 98.002344 -242.399312)
		(mid 98.002725 -242.399566)
		(end 98.003106 -242.39982)
		(stroke
			(width 0.05715)
			(type default)
		)
		(layer "In11.Cu")
	)
	(gr_arc
		(start 98.002344 -240.7793)
		(mid 98.002725 -240.779554)
		(end 98.003106 -240.779808)
		(stroke
			(width 0.05715)
			(type default)
		)
		(layer "In11.Cu")
	)
	(gr_arc
		(start 98.002344 -239.159288)
		(mid 98.002725 -239.159542)
		(end 98.003106 -239.159796)
		(stroke
			(width 0.05715)
			(type default)
		)
		(layer "In11.Cu")
	)
	(gr_arc
		(start 98.002344 -237.539276)
		(mid 98.002725 -237.53953)
		(end 98.003106 -237.539784)
		(stroke
			(width 0.05715)
			(type default)
		)
		(layer "In11.Cu")
	)
	(gr_arc
		(start 98.002344 -235.919264)
		(mid 98.002725 -235.919518)
		(end 98.003106 -235.919772)
		(stroke
			(width 0.05715)
			(type default)
		)
		(layer "In11.Cu")
	)
	(gr_arc
		(start 98.002344 -234.299252)
		(mid 98.002725 -234.299506)
		(end 98.003106 -234.29976)
		(stroke
			(width 0.05715)
			(type default)
		)
		(layer "In11.Cu")
	)
	(gr_line
		(start 98.003106 -227.129086)
		(end 98.000312 -227.131118)
		(stroke
			(width 0.05715)
			(type default)
		)
		(layer "In11.Cu")
	)
	(gr_arc
		(start 98.003106 -227.129086)
		(mid 98.007055 -227.126309)
		(end 98.01098 -227.123498)
		(stroke
			(width 0.05715)
			(type default)
		)
		(layer "In11.Cu")
	)
	(gr_arc
		(start 98.01098 -242.405408)
		(mid 98.007055 -242.402597)
		(end 98.003106 -242.39982)
		(stroke
			(width 0.05715)
			(type default)
		)
		(layer "In11.Cu")
	)
	(gr_arc
		(start 98.01098 -240.785396)
		(mid 98.007055 -240.782585)
		(end 98.003106 -240.779808)
		(stroke
			(width 0.05715)
			(type default)
		)
		(layer "In11.Cu")
	)
	(gr_arc
		(start 98.01098 -239.165384)
		(mid 98.007055 -239.162573)
		(end 98.003106 -239.159796)
		(stroke
			(width 0.05715)
			(type default)
		)
		(layer "In11.Cu")
	)
	(gr_arc
		(start 98.01098 -237.545372)
		(mid 98.007055 -237.542561)
		(end 98.003106 -237.539784)
		(stroke
			(width 0.05715)
			(type default)
		)
		(layer "In11.Cu")
	)
	(gr_arc
		(start 98.01098 -235.92536)
		(mid 98.007055 -235.922549)
		(end 98.003106 -235.919772)
		(stroke
			(width 0.05715)
			(type default)
		)
		(layer "In11.Cu")
	)
	(gr_arc
		(start 98.01098 -234.305348)
		(mid 98.007055 -234.302537)
		(end 98.003106 -234.29976)
		(stroke
			(width 0.05715)
			(type default)
		)
		(layer "In11.Cu")
	)
	(gr_arc
		(start 98.01098 -224.58553)
		(mid 98.007055 -224.582719)
		(end 98.003106 -224.579942)
		(stroke
			(width 0.05715)
			(type default)
		)
		(layer "In11.Cu")
	)
	(gr_arc
		(start 98.011234 -245.645432)
		(mid 98.007182 -245.64262)
		(end 98.003106 -245.639844)
		(stroke
			(width 0.05715)
			(type default)
		)
		(layer "In11.Cu")
	)
	(gr_arc
		(start 98.013774 -229.447344)
		(mid 98.010608 -229.445046)
		(end 98.007424 -229.442772)
		(stroke
			(width 0.05715)
			(type default)
		)
		(layer "In11.Cu")
	)
	(gr_line
		(start 98.048318 -246.035068)
		(end 97.978976 -246.10441)
		(stroke
			(width 0.05715)
			(type default)
		)
		(layer "In11.Cu")
	)
	(gr_line
		(start 98.048318 -244.415056)
		(end 97.978976 -244.484398)
		(stroke
			(width 0.05715)
			(type default)
		)
		(layer "In11.Cu")
	)
	(gr_line
		(start 98.051112 -379.186186)
		(end 98.275394 -378.822712)
		(stroke
			(width 0.07112)
			(type default)
		)
		(layer "In11.Cu")
	)
	(gr_line
		(start 98.06178 -247.641618)
		(end 97.978976 -247.724422)
		(stroke
			(width 0.05715)
			(type default)
		)
		(layer "In11.Cu")
	)
	(gr_arc
		(start 98.06559 -247.618758)
		(mid 98.063568 -247.630168)
		(end 98.06178 -247.641618)
		(stroke
			(width 0.05715)
			(type default)
		)
		(layer "In11.Cu")
	)
	(gr_line
		(start 98.076512 -295.146222)
		(end 98.076512 -295.148254)
		(stroke
			(width 0.05715)
			(type default)
		)
		(layer "In11.Cu")
	)
	(gr_line
		(start 98.095562 -379.373384)
		(end 98.051112 -379.186186)
		(stroke
			(width 0.07112)
			(type default)
		)
		(layer "In11.Cu")
	)
	(gr_arc
		(start 98.12909 -286.581596)
		(mid 98.124374 -286.584873)
		(end 98.119692 -286.5882)
		(stroke
			(width 0.05715)
			(type default)
		)
		(layer "In11.Cu")
	)
	(gr_line
		(start 98.12909 -286.581596)
		(end 98.131122 -286.580072)
		(stroke
			(width 0.05715)
			(type default)
		)
		(layer "In11.Cu")
	)
	(gr_line
		(start 98.131122 -286.580072)
		(end 98.135948 -286.577278)
		(stroke
			(width 0.05715)
			(type default)
		)
		(layer "In11.Cu")
	)
	(gr_line
		(start 98.180906 -381.28321)
		(end 98.403918 -380.919228)
		(stroke
			(width 0.07112)
			(type default)
		)
		(layer "In11.Cu")
	)
	(gr_line
		(start 98.225864 -381.470408)
		(end 98.180906 -381.28321)
		(stroke
			(width 0.07112)
			(type default)
		)
		(layer "In11.Cu")
	)
	(gr_arc
		(start 98.240342 -246.021606)
		(mid 98.238549 -246.010284)
		(end 98.236532 -245.999)
		(stroke
			(width 0.05715)
			(type default)
		)
		(layer "In11.Cu")
	)
	(gr_line
		(start 98.240342 -246.021606)
		(end 98.323146 -246.10441)
		(stroke
			(width 0.05715)
			(type default)
		)
		(layer "In11.Cu")
	)
	(gr_arc
		(start 98.240342 -244.401594)
		(mid 98.238549 -244.390272)
		(end 98.236532 -244.378988)
		(stroke
			(width 0.05715)
			(type default)
		)
		(layer "In11.Cu")
	)
	(gr_line
		(start 98.240342 -244.401594)
		(end 98.323146 -244.484398)
		(stroke
			(width 0.05715)
			(type default)
		)
		(layer "In11.Cu")
	)
	(gr_line
		(start 98.241612 -221.083378)
		(end 98.195892 -221.129098)
		(stroke
			(width 0.05715)
			(type default)
		)
		(layer "In11.Cu")
	)
	(gr_line
		(start 98.241612 -221.05493)
		(end 98.241612 -221.083378)
		(stroke
			(width 0.05715)
			(type default)
		)
		(layer "In11.Cu")
	)
	(gr_line
		(start 98.253804 -247.65508)
		(end 98.323146 -247.724422)
		(stroke
			(width 0.05715)
			(type default)
		)
		(layer "In11.Cu")
	)
	(gr_line
		(start 98.263456 -286.72409)
		(end 98.263964 -286.723836)
		(stroke
			(width 0.05715)
			(type default)
		)
		(layer "In11.Cu")
	)
	(gr_line
		(start 98.275394 -378.822712)
		(end 98.462592 -378.77877)
		(stroke
			(width 0.07112)
			(type default)
		)
		(layer "In11.Cu")
	)
	(gr_line
		(start 98.27895 -278.13635)
		(end 97.981008 -278.13635)
		(stroke
			(width 0.05715)
			(type default)
		)
		(layer "In11.Cu")
	)
	(gr_line
		(start 98.27895 -276.516338)
		(end 97.981008 -276.516338)
		(stroke
			(width 0.05715)
			(type default)
		)
		(layer "In11.Cu")
	)
	(gr_line
		(start 98.27895 -274.896326)
		(end 97.981008 -274.896326)
		(stroke
			(width 0.05715)
			(type default)
		)
		(layer "In11.Cu")
	)
	(gr_arc
		(start 98.29165 -222.26397)
		(mid 98.295576 -222.26678)
		(end 98.299524 -222.269558)
		(stroke
			(width 0.05715)
			(type default)
		)
		(layer "In11.Cu")
	)
	(gr_line
		(start 98.299524 -222.269558)
		(end 98.30054 -222.27032)
		(stroke
			(width 0.05715)
			(type default)
		)
		(layer "In11.Cu")
	)
	(gr_line
		(start 98.30054 -222.27032)
		(end 98.301556 -222.270828)
		(stroke
			(width 0.05715)
			(type default)
		)
		(layer "In11.Cu")
	)
	(gr_line
		(start 98.301556 -222.270828)
		(end 98.30689 -222.273876)
		(stroke
			(width 0.05715)
			(type default)
		)
		(layer "In11.Cu")
	)
	(gr_line
		(start 98.310192 -296.463974)
		(end 98.310192 -296.435526)
		(stroke
			(width 0.05715)
			(type default)
		)
		(layer "In11.Cu")
	)
	(gr_line
		(start 98.310192 -296.435526)
		(end 98.355912 -296.389806)
		(stroke
			(width 0.05715)
			(type default)
		)
		(layer "In11.Cu")
	)
	(gr_line
		(start 98.319082 -388.774432)
		(end 98.371406 -388.826756)
		(stroke
			(width 0.07112)
			(type default)
		)
		(layer "In11.Cu")
	)
	(gr_line
		(start 98.319082 -385.31038)
		(end 98.672396 -385.405376)
		(stroke
			(width 0.07112)
			(type default)
		)
		(layer "In11.Cu")
	)
	(gr_line
		(start 98.323146 -247.724422)
		(end 98.621088 -247.724422)
		(stroke
			(width 0.05715)
			(type default)
		)
		(layer "In11.Cu")
	)
	(gr_line
		(start 98.323146 -246.10441)
		(end 98.621088 -246.10441)
		(stroke
			(width 0.05715)
			(type default)
		)
		(layer "In11.Cu")
	)
	(gr_line
		(start 98.323146 -244.484398)
		(end 98.621088 -244.484398)
		(stroke
			(width 0.05715)
			(type default)
		)
		(layer "In11.Cu")
	)
	(gr_line
		(start 98.335846 -379.52299)
		(end 98.7044 -378.926344)
		(stroke
			(width 0.07112)
			(type default)
		)
		(layer "In11.Cu")
	)
	(gr_line
		(start 98.348292 -278.205692)
		(end 98.27895 -278.13635)
		(stroke
			(width 0.05715)
			(type default)
		)
		(layer "In11.Cu")
	)
	(gr_line
		(start 98.348292 -276.58568)
		(end 98.27895 -276.516338)
		(stroke
			(width 0.05715)
			(type default)
		)
		(layer "In11.Cu")
	)
	(gr_line
		(start 98.361754 -274.97913)
		(end 98.27895 -274.896326)
		(stroke
			(width 0.05715)
			(type default)
		)
		(layer "In11.Cu")
	)
	(gr_arc
		(start 98.361754 -274.97913)
		(mid 98.363545 -274.990452)
		(end 98.365564 -275.001736)
		(stroke
			(width 0.05715)
			(type default)
		)
		(layer "In11.Cu")
	)
	(gr_line
		(start 98.371406 -389.006588)
		(end 98.224848 -389.153146)
		(stroke
			(width 0.07112)
			(type default)
		)
		(layer "In11.Cu")
	)
	(gr_line
		(start 98.371406 -388.826756)
		(end 98.371406 -389.006588)
		(stroke
			(width 0.07112)
			(type default)
		)
		(layer "In11.Cu")
	)
	(gr_line
		(start 98.402648 -222.10903)
		(end 98.402902 -222.10903)
		(stroke
			(width 0.05715)
			(type default)
		)
		(layer "In11.Cu")
	)
	(gr_line
		(start 98.403918 -380.919228)
		(end 98.591116 -380.87427)
		(stroke
			(width 0.07112)
			(type default)
		)
		(layer "In11.Cu")
	)
	(gr_line
		(start 98.46437 -378.778262)
		(end 98.464116 -378.778008)
		(stroke
			(width 0.07112)
			(type default)
		)
		(layer "In11.Cu")
	)
	(gr_line
		(start 98.466656 -381.619252)
		(end 98.833178 -381.02159)
		(stroke
			(width 0.07112)
			(type default)
		)
		(layer "In11.Cu")
	)
	(gr_arc
		(start 98.536506 -278.242014)
		(mid 98.538528 -278.230603)
		(end 98.540316 -278.219154)
		(stroke
			(width 0.05715)
			(type default)
		)
		(layer "In11.Cu")
	)
	(gr_arc
		(start 98.536506 -276.622002)
		(mid 98.538527 -276.610591)
		(end 98.540316 -276.599142)
		(stroke
			(width 0.05715)
			(type default)
		)
		(layer "In11.Cu")
	)
	(gr_line
		(start 98.540316 -278.219154)
		(end 98.62312 -278.13635)
		(stroke
			(width 0.05715)
			(type default)
		)
		(layer "In11.Cu")
	)
	(gr_line
		(start 98.540316 -276.599142)
		(end 98.62312 -276.516338)
		(stroke
			(width 0.05715)
			(type default)
		)
		(layer "In11.Cu")
	)
	(gr_line
		(start 98.553778 -274.965668)
		(end 98.62312 -274.896326)
		(stroke
			(width 0.05715)
			(type default)
		)
		(layer "In11.Cu")
	)
	(gr_arc
		(start 98.590862 -280.215086)
		(mid 98.59365 -280.217127)
		(end 98.59645 -280.21915)
		(stroke
			(width 0.05715)
			(type default)
		)
		(layer "In11.Cu")
	)
	(gr_line
		(start 98.592132 -296.463974)
		(end 98.592132 -296.435526)
		(stroke
			(width 0.05715)
			(type default)
		)
		(layer "In11.Cu")
	)
	(gr_line
		(start 98.592132 -296.435526)
		(end 98.546412 -296.389806)
		(stroke
			(width 0.05715)
			(type default)
		)
		(layer "In11.Cu")
	)
	(gr_arc
		(start 98.596958 -280.219658)
		(mid 98.597973 -280.220294)
		(end 98.59899 -280.220928)
		(stroke
			(width 0.05715)
			(type default)
		)
		(layer "In11.Cu")
	)
	(gr_arc
		(start 98.599752 -280.221436)
		(mid 98.599371 -280.221182)
		(end 98.59899 -280.220928)
		(stroke
			(width 0.05715)
			(type default)
		)
		(layer "In11.Cu")
	)
	(gr_line
		(start 98.604324 -389.352536)
		(end 98.426016 -389.352536)
		(stroke
			(width 0.07112)
			(type default)
		)
		(layer "In11.Cu")
	)
	(gr_line
		(start 98.609404 -280.227024)
		(end 98.599752 -280.221436)
		(stroke
			(width 0.05715)
			(type default)
		)
		(layer "In11.Cu")
	)
	(gr_line
		(start 98.62312 -278.13635)
		(end 98.921062 -278.13635)
		(stroke
			(width 0.05715)
			(type default)
		)
		(layer "In11.Cu")
	)
	(gr_line
		(start 98.62312 -276.516338)
		(end 98.921062 -276.516338)
		(stroke
			(width 0.05715)
			(type default)
		)
		(layer "In11.Cu")
	)
	(gr_line
		(start 98.62312 -274.896326)
		(end 98.921062 -274.896326)
		(stroke
			(width 0.05715)
			(type default)
		)
		(layer "In11.Cu")
	)
	(gr_line
		(start 98.649536 -280.250138)
		(end 98.64725 -280.248868)
		(stroke
			(width 0.05715)
			(type default)
		)
		(layer "In11.Cu")
	)
	(gr_line
		(start 98.672396 -385.405376)
		(end 98.672904 -385.404868)
		(stroke
			(width 0.07112)
			(type default)
		)
		(layer "In11.Cu")
	)
	(gr_line
		(start 98.719132 -389.467344)
		(end 98.604324 -389.352536)
		(stroke
			(width 0.07112)
			(type default)
		)
		(layer "In11.Cu")
	)
	(gr_line
		(start 98.719132 -386.003292)
		(end 98.814128 -385.649216)
		(stroke
			(width 0.07112)
			(type default)
		)
		(layer "In11.Cu")
	)
	(gr_line
		(start 98.77044 -380.32182)
		(end 98.993452 -379.957584)
		(stroke
			(width 0.07112)
			(type default)
		)
		(layer "In11.Cu")
	)
	(gr_line
		(start 98.788982 -385.33832)
		(end 98.79457 -385.335018)
		(stroke
			(width 0.07112)
			(type default)
		)
		(layer "In11.Cu")
	)
	(gr_line
		(start 98.800158 -226.337368)
		(end 98.801936 -226.338384)
		(stroke
			(width 0.05715)
			(type default)
		)
		(layer "In11.Cu")
	)
	(gr_line
		(start 98.801936 -226.338384)
		(end 98.802952 -226.338892)
		(stroke
			(width 0.05715)
			(type default)
		)
		(layer "In11.Cu")
	)
	(gr_line
		(start 98.802952 -226.338892)
		(end 98.803714 -226.3394)
		(stroke
			(width 0.05715)
			(type default)
		)
		(layer "In11.Cu")
	)
	(gr_line
		(start 98.807016 -245.781322)
		(end 98.808032 -245.78183)
		(stroke
			(width 0.05715)
			(type default)
		)
		(layer "In11.Cu")
	)
	(gr_line
		(start 98.807016 -244.16131)
		(end 98.808032 -244.161818)
		(stroke
			(width 0.05715)
			(type default)
		)
		(layer "In11.Cu")
	)
	(gr_line
		(start 98.807016 -242.541298)
		(end 98.808032 -242.541806)
		(stroke
			(width 0.05715)
			(type default)
		)
		(layer "In11.Cu")
	)
	(gr_line
		(start 98.807016 -240.921286)
		(end 98.808032 -240.921794)
		(stroke
			(width 0.05715)
			(type default)
		)
		(layer "In11.Cu")
	)
	(gr_line
		(start 98.807016 -239.301274)
		(end 98.808032 -239.301782)
		(stroke
			(width 0.05715)
			(type default)
		)
		(layer "In11.Cu")
	)
	(gr_line
		(start 98.807016 -237.681262)
		(end 98.808032 -237.68177)
		(stroke
			(width 0.05715)
			(type default)
		)
		(layer "In11.Cu")
	)
	(gr_line
		(start 98.807016 -236.06125)
		(end 98.808032 -236.061758)
		(stroke
			(width 0.05715)
			(type default)
		)
		(layer "In11.Cu")
	)
	(gr_line
		(start 98.807016 -234.441238)
		(end 98.808032 -234.441746)
		(stroke
			(width 0.05715)
			(type default)
		)
		(layer "In11.Cu")
	)
	(gr_line
		(start 98.807016 -232.821226)
		(end 98.808032 -232.821734)
		(stroke
			(width 0.05715)
			(type default)
		)
		(layer "In11.Cu")
	)
	(gr_line
		(start 98.808032 -245.78183)
		(end 98.80854 -245.782084)
		(stroke
			(width 0.05715)
			(type default)
		)
		(layer "In11.Cu")
	)
	(gr_line
		(start 98.808032 -244.161818)
		(end 98.808794 -244.162326)
		(stroke
			(width 0.05715)
			(type default)
		)
		(layer "In11.Cu")
	)
	(gr_line
		(start 98.808032 -242.541806)
		(end 98.80854 -242.54206)
		(stroke
			(width 0.05715)
			(type default)
		)
		(layer "In11.Cu")
	)
	(gr_line
		(start 98.808032 -240.921794)
		(end 98.808794 -240.922302)
		(stroke
			(width 0.05715)
			(type default)
		)
		(layer "In11.Cu")
	)
	(gr_line
		(start 98.808032 -239.301782)
		(end 98.808794 -239.30229)
		(stroke
			(width 0.05715)
			(type default)
		)
		(layer "In11.Cu")
	)
	(gr_line
		(start 98.808032 -237.68177)
		(end 98.80854 -237.682024)
		(stroke
			(width 0.05715)
			(type default)
		)
		(layer "In11.Cu")
	)
	(gr_line
		(start 98.808032 -236.061758)
		(end 98.808794 -236.062266)
		(stroke
			(width 0.05715)
			(type default)
		)
		(layer "In11.Cu")
	)
	(gr_line
		(start 98.808032 -234.441746)
		(end 98.808794 -234.442254)
		(stroke
			(width 0.05715)
			(type default)
		)
		(layer "In11.Cu")
	)
	(gr_line
		(start 98.808032 -232.821734)
		(end 98.808794 -232.822242)
		(stroke
			(width 0.05715)
			(type default)
		)
		(layer "In11.Cu")
	)
	(gr_line
		(start 98.808794 -246.426482)
		(end 98.808032 -246.42699)
		(stroke
			(width 0.05715)
			(type default)
		)
		(layer "In11.Cu")
	)
	(gr_line
		(start 98.808794 -244.80647)
		(end 98.808032 -244.806978)
		(stroke
			(width 0.05715)
			(type default)
		)
		(layer "In11.Cu")
	)
	(gr_line
		(start 98.808794 -243.186458)
		(end 98.808032 -243.186966)
		(stroke
			(width 0.05715)
			(type default)
		)
		(layer "In11.Cu")
	)
	(gr_line
		(start 98.808794 -241.566446)
		(end 98.808032 -241.566954)
		(stroke
			(width 0.05715)
			(type default)
		)
		(layer "In11.Cu")
	)
	(gr_line
		(start 98.808794 -239.946434)
		(end 98.808032 -239.946942)
		(stroke
			(width 0.05715)
			(type default)
		)
		(layer "In11.Cu")
	)
	(gr_line
		(start 98.808794 -236.70641)
		(end 98.808032 -236.706918)
		(stroke
			(width 0.05715)
			(type default)
		)
		(layer "In11.Cu")
	)
	(gr_line
		(start 98.808794 -235.086398)
		(end 98.808032 -235.086906)
		(stroke
			(width 0.05715)
			(type default)
		)
		(layer "In11.Cu")
	)
	(gr_line
		(start 98.808794 -233.466386)
		(end 98.808032 -233.466894)
		(stroke
			(width 0.05715)
			(type default)
		)
		(layer "In11.Cu")
	)
	(gr_line
		(start 98.808794 -231.846374)
		(end 98.808032 -231.846882)
		(stroke
			(width 0.05715)
			(type default)
		)
		(layer "In11.Cu")
	)
	(gr_line
		(start 98.808794 -226.986592)
		(end 98.808032 -226.9871)
		(stroke
			(width 0.05715)
			(type default)
		)
		(layer "In11.Cu")
	)
	(gr_line
		(start 98.810064 -246.42572)
		(end 98.808794 -246.426482)
		(stroke
			(width 0.05715)
			(type default)
		)
		(layer "In11.Cu")
	)
	(gr_line
		(start 98.810064 -244.805708)
		(end 98.808794 -244.80647)
		(stroke
			(width 0.05715)
			(type default)
		)
		(layer "In11.Cu")
	)
	(gr_line
		(start 98.810064 -243.185696)
		(end 98.808794 -243.186458)
		(stroke
			(width 0.05715)
			(type default)
		)
		(layer "In11.Cu")
	)
	(gr_line
		(start 98.810064 -241.565684)
		(end 98.808794 -241.566446)
		(stroke
			(width 0.05715)
			(type default)
		)
		(layer "In11.Cu")
	)
	(gr_line
		(start 98.810064 -239.945672)
		(end 98.808794 -239.946434)
		(stroke
			(width 0.05715)
			(type default)
		)
		(layer "In11.Cu")
	)
	(gr_line
		(start 98.810064 -238.32566)
		(end 98.808794 -238.326422)
		(stroke
			(width 0.05715)
			(type default)
		)
		(layer "In11.Cu")
	)
	(gr_line
		(start 98.810064 -236.705648)
		(end 98.808794 -236.70641)
		(stroke
			(width 0.05715)
			(type default)
		)
		(layer "In11.Cu")
	)
	(gr_line
		(start 98.810064 -235.085636)
		(end 98.808794 -235.086398)
		(stroke
			(width 0.05715)
			(type default)
		)
		(layer "In11.Cu")
	)
	(gr_line
		(start 98.810064 -233.465624)
		(end 98.808794 -233.466386)
		(stroke
			(width 0.05715)
			(type default)
		)
		(layer "In11.Cu")
	)
	(gr_line
		(start 98.810064 -231.845612)
		(end 98.808794 -231.846374)
		(stroke
			(width 0.05715)
			(type default)
		)
		(layer "In11.Cu")
	)
	(gr_line
		(start 98.810318 -228.605842)
		(end 98.808794 -228.606604)
		(stroke
			(width 0.05715)
			(type default)
		)
		(layer "In11.Cu")
	)
	(gr_line
		(start 98.815398 -380.509018)
		(end 98.77044 -380.32182)
		(stroke
			(width 0.07112)
			(type default)
		)
		(layer "In11.Cu")
	)
	(gr_line
		(start 98.818192 -228.60127)
		(end 98.81743 -228.601778)
		(stroke
			(width 0.05715)
			(type default)
		)
		(layer "In11.Cu")
	)
	(gr_arc
		(start 98.825558 -275.707348)
		(mid 98.825675 -275.710777)
		(end 98.825812 -275.714206)
		(stroke
			(width 0.05715)
			(type default)
		)
		(layer "In11.Cu")
	)
	(gr_line
		(start 98.825812 -288.672778)
		(end 98.825812 -288.666174)
		(stroke
			(width 0.05715)
			(type default)
		)
		(layer "In11.Cu")
	)
	(gr_line
		(start 98.89617 -226.172776)
		(end 98.903282 -226.176586)
		(stroke
			(width 0.05715)
			(type default)
		)
		(layer "In11.Cu")
	)
	(gr_line
		(start 98.902012 -245.615714)
		(end 98.903282 -245.616476)
		(stroke
			(width 0.05715)
			(type default)
		)
		(layer "In11.Cu")
	)
	(gr_line
		(start 98.902012 -243.995702)
		(end 98.903282 -243.996464)
		(stroke
			(width 0.05715)
			(type default)
		)
		(layer "In11.Cu")
	)
	(gr_line
		(start 98.902012 -242.37569)
		(end 98.903282 -242.376452)
		(stroke
			(width 0.05715)
			(type default)
		)
		(layer "In11.Cu")
	)
	(gr_line
		(start 98.902012 -240.755678)
		(end 98.903282 -240.75644)
		(stroke
			(width 0.05715)
			(type default)
		)
		(layer "In11.Cu")
	)
	(gr_line
		(start 98.902012 -239.135666)
		(end 98.903282 -239.136428)
		(stroke
			(width 0.05715)
			(type default)
		)
		(layer "In11.Cu")
	)
	(gr_line
		(start 98.902012 -237.515654)
		(end 98.903282 -237.516416)
		(stroke
			(width 0.05715)
			(type default)
		)
		(layer "In11.Cu")
	)
	(gr_line
		(start 98.902012 -235.895642)
		(end 98.903282 -235.896404)
		(stroke
			(width 0.05715)
			(type default)
		)
		(layer "In11.Cu")
	)
	(gr_line
		(start 98.902012 -234.27563)
		(end 98.903282 -234.276392)
		(stroke
			(width 0.05715)
			(type default)
		)
		(layer "In11.Cu")
	)
	(gr_line
		(start 98.902012 -232.655618)
		(end 98.903282 -232.65638)
		(stroke
			(width 0.05715)
			(type default)
		)
		(layer "In11.Cu")
	)
	(gr_line
		(start 98.903282 -243.996464)
		(end 98.904044 -243.996972)
		(stroke
			(width 0.05715)
			(type default)
		)
		(layer "In11.Cu")
	)
	(gr_line
		(start 98.903282 -240.75644)
		(end 98.904044 -240.756948)
		(stroke
			(width 0.05715)
			(type default)
		)
		(layer "In11.Cu")
	)
	(gr_line
		(start 98.903282 -239.136428)
		(end 98.904044 -239.136936)
		(stroke
			(width 0.05715)
			(type default)
		)
		(layer "In11.Cu")
	)
	(gr_line
		(start 98.903282 -235.896404)
		(end 98.904044 -235.896912)
		(stroke
			(width 0.05715)
			(type default)
		)
		(layer "In11.Cu")
	)
	(gr_line
		(start 98.903282 -234.276392)
		(end 98.904044 -234.2769)
		(stroke
			(width 0.05715)
			(type default)
		)
		(layer "In11.Cu")
	)
	(gr_line
		(start 98.903282 -232.65638)
		(end 98.904044 -232.656888)
		(stroke
			(width 0.05715)
			(type default)
		)
		(layer "In11.Cu")
	)
	(gr_line
		(start 98.903282 -226.176586)
		(end 98.904044 -226.177094)
		(stroke
			(width 0.05715)
			(type default)
		)
		(layer "In11.Cu")
	)
	(gr_line
		(start 98.903536 -227.796852)
		(end 98.904044 -227.797106)
		(stroke
			(width 0.05715)
			(type default)
		)
		(layer "In11.Cu")
	)
	(gr_line
		(start 98.904044 -246.591836)
		(end 98.903282 -246.592344)
		(stroke
			(width 0.05715)
			(type default)
		)
		(layer "In11.Cu")
	)
	(gr_line
		(start 98.904044 -244.971824)
		(end 98.903282 -244.972332)
		(stroke
			(width 0.05715)
			(type default)
		)
		(layer "In11.Cu")
	)
	(gr_line
		(start 98.904044 -243.996972)
		(end 98.90506 -243.99748)
		(stroke
			(width 0.05715)
			(type default)
		)
		(layer "In11.Cu")
	)
	(gr_line
		(start 98.904044 -243.351812)
		(end 98.903282 -243.35232)
		(stroke
			(width 0.05715)
			(type default)
		)
		(layer "In11.Cu")
	)
	(gr_line
		(start 98.904044 -241.7318)
		(end 98.903282 -241.732308)
		(stroke
			(width 0.05715)
			(type default)
		)
		(layer "In11.Cu")
	)
	(gr_line
		(start 98.904044 -240.756948)
		(end 98.90506 -240.757456)
		(stroke
			(width 0.05715)
			(type default)
		)
		(layer "In11.Cu")
	)
	(gr_line
		(start 98.904044 -240.111788)
		(end 98.903282 -240.112296)
		(stroke
			(width 0.05715)
			(type default)
		)
		(layer "In11.Cu")
	)
	(gr_line
		(start 98.904044 -239.136936)
		(end 98.90506 -239.137444)
		(stroke
			(width 0.05715)
			(type default)
		)
		(layer "In11.Cu")
	)
	(gr_line
		(start 98.904044 -238.491776)
		(end 98.903536 -238.49203)
		(stroke
			(width 0.05715)
			(type default)
		)
		(layer "In11.Cu")
	)
	(gr_line
		(start 98.904044 -236.871764)
		(end 98.903282 -236.872272)
		(stroke
			(width 0.05715)
			(type default)
		)
		(layer "In11.Cu")
	)
	(gr_line
		(start 98.904044 -235.896912)
		(end 98.90506 -235.89742)
		(stroke
			(width 0.05715)
			(type default)
		)
		(layer "In11.Cu")
	)
	(gr_line
		(start 98.904044 -235.251752)
		(end 98.903282 -235.25226)
		(stroke
			(width 0.05715)
			(type default)
		)
		(layer "In11.Cu")
	)
	(gr_line
		(start 98.904044 -234.2769)
		(end 98.90506 -234.277408)
		(stroke
			(width 0.05715)
			(type default)
		)
		(layer "In11.Cu")
	)
	(gr_line
		(start 98.904044 -233.63174)
		(end 98.903282 -233.632248)
		(stroke
			(width 0.05715)
			(type default)
		)
		(layer "In11.Cu")
	)
	(gr_line
		(start 98.904044 -232.656888)
		(end 98.90506 -232.657396)
		(stroke
			(width 0.05715)
			(type default)
		)
		(layer "In11.Cu")
	)
	(gr_line
		(start 98.904044 -232.011728)
		(end 98.903282 -232.012236)
		(stroke
			(width 0.05715)
			(type default)
		)
		(layer "In11.Cu")
	)
	(gr_line
		(start 98.904044 -228.771958)
		(end 98.903536 -228.772212)
		(stroke
			(width 0.05715)
			(type default)
		)
		(layer "In11.Cu")
	)
	(gr_line
		(start 98.904044 -227.797106)
		(end 98.90506 -227.797614)
		(stroke
			(width 0.05715)
			(type default)
		)
		(layer "In11.Cu")
	)
	(gr_line
		(start 98.904044 -227.151946)
		(end 98.903282 -227.152454)
		(stroke
			(width 0.05715)
			(type default)
		)
		(layer "In11.Cu")
	)
	(gr_line
		(start 98.904552 -221.083378)
		(end 98.950272 -221.129098)
		(stroke
			(width 0.05715)
			(type default)
		)
		(layer "In11.Cu")
	)
	(gr_line
		(start 98.904552 -221.05493)
		(end 98.904552 -221.083378)
		(stroke
			(width 0.05715)
			(type default)
		)
		(layer "In11.Cu")
	)
	(gr_line
		(start 98.90506 -246.591328)
		(end 98.904044 -246.591836)
		(stroke
			(width 0.05715)
			(type default)
		)
		(layer "In11.Cu")
	)
	(gr_line
		(start 98.90506 -244.971316)
		(end 98.904044 -244.971824)
		(stroke
			(width 0.05715)
			(type default)
		)
		(layer "In11.Cu")
	)
	(gr_line
		(start 98.90506 -243.99748)
		(end 98.906838 -243.998496)
		(stroke
			(width 0.05715)
			(type default)
		)
		(layer "In11.Cu")
	)
	(gr_line
		(start 98.90506 -243.351304)
		(end 98.904044 -243.351812)
		(stroke
			(width 0.05715)
			(type default)
		)
		(layer "In11.Cu")
	)
	(gr_line
		(start 98.90506 -241.731292)
		(end 98.904044 -241.7318)
		(stroke
			(width 0.05715)
			(type default)
		)
		(layer "In11.Cu")
	)
	(gr_line
		(start 98.90506 -240.757456)
		(end 98.906838 -240.758472)
		(stroke
			(width 0.05715)
			(type default)
		)
		(layer "In11.Cu")
	)
	(gr_line
		(start 98.90506 -240.11128)
		(end 98.904044 -240.111788)
		(stroke
			(width 0.05715)
			(type default)
		)
		(layer "In11.Cu")
	)
	(gr_line
		(start 98.90506 -239.137444)
		(end 98.906838 -239.13846)
		(stroke
			(width 0.05715)
			(type default)
		)
		(layer "In11.Cu")
	)
	(gr_line
		(start 98.90506 -238.491268)
		(end 98.904044 -238.491776)
		(stroke
			(width 0.05715)
			(type default)
		)
		(layer "In11.Cu")
	)
	(gr_line
		(start 98.90506 -236.871256)
		(end 98.904044 -236.871764)
		(stroke
			(width 0.05715)
			(type default)
		)
		(layer "In11.Cu")
	)
	(gr_line
		(start 98.90506 -235.89742)
		(end 98.906838 -235.898436)
		(stroke
			(width 0.05715)
			(type default)
		)
		(layer "In11.Cu")
	)
	(gr_line
		(start 98.90506 -235.251244)
		(end 98.904044 -235.251752)
		(stroke
			(width 0.05715)
			(type default)
		)
		(layer "In11.Cu")
	)
	(gr_line
		(start 98.90506 -234.277408)
		(end 98.906838 -234.278424)
		(stroke
			(width 0.05715)
			(type default)
		)
		(layer "In11.Cu")
	)
	(gr_line
		(start 98.90506 -233.631232)
		(end 98.904044 -233.63174)
		(stroke
			(width 0.05715)
			(type default)
		)
		(layer "In11.Cu")
	)
	(gr_line
		(start 98.90506 -232.657396)
		(end 98.906838 -232.658412)
		(stroke
			(width 0.05715)
			(type default)
		)
		(layer "In11.Cu")
	)
	(gr_line
		(start 98.90506 -232.01122)
		(end 98.904044 -232.011728)
		(stroke
			(width 0.05715)
			(type default)
		)
		(layer "In11.Cu")
	)
	(gr_line
		(start 98.90506 -228.77145)
		(end 98.904044 -228.771958)
		(stroke
			(width 0.05715)
			(type default)
		)
		(layer "In11.Cu")
	)
	(gr_line
		(start 98.90506 -227.797614)
		(end 98.906838 -227.79863)
		(stroke
			(width 0.05715)
			(type default)
		)
		(layer "In11.Cu")
	)
	(gr_line
		(start 98.906584 -228.770434)
		(end 98.90506 -228.77145)
		(stroke
			(width 0.05715)
			(type default)
		)
		(layer "In11.Cu")
	)
	(gr_line
		(start 98.9076 -228.769926)
		(end 98.906584 -228.770434)
		(stroke
			(width 0.05715)
			(type default)
		)
		(layer "In11.Cu")
	)
	(gr_line
		(start 98.91268 -228.766878)
		(end 98.9076 -228.769926)
		(stroke
			(width 0.05715)
			(type default)
		)
		(layer "In11.Cu")
	)
	(gr_line
		(start 98.929698 -385.582668)
		(end 98.934778 -385.57962)
		(stroke
			(width 0.07112)
			(type default)
		)
		(layer "In11.Cu")
	)
	(gr_line
		(start 98.934778 -385.57962)
		(end 99.07651 -385.497832)
		(stroke
			(width 0.07112)
			(type default)
		)
		(layer "In11.Cu")
	)
	(gr_line
		(start 98.934778 -226.194874)
		(end 98.93554 -226.195382)
		(stroke
			(width 0.05715)
			(type default)
		)
		(layer "In11.Cu")
	)
	(gr_line
		(start 98.93554 -226.195382)
		(end 98.936302 -226.19589)
		(stroke
			(width 0.05715)
			(type default)
		)
		(layer "In11.Cu")
	)
	(gr_line
		(start 98.936302 -226.19589)
		(end 98.94316 -226.199954)
		(stroke
			(width 0.05715)
			(type default)
		)
		(layer "In11.Cu")
	)
	(gr_line
		(start 98.937826 -229.436676)
		(end 98.942652 -229.43947)
		(stroke
			(width 0.05715)
			(type default)
		)
		(layer "In11.Cu")
	)
	(gr_line
		(start 98.940366 -227.131118)
		(end 98.934778 -227.13442)
		(stroke
			(width 0.05715)
			(type default)
		)
		(layer "In11.Cu")
	)
	(gr_line
		(start 98.942652 -229.43947)
		(end 98.94316 -229.439724)
		(stroke
			(width 0.05715)
			(type default)
		)
		(layer "In11.Cu")
	)
	(gr_line
		(start 98.94316 -227.129086)
		(end 98.940366 -227.131118)
		(stroke
			(width 0.05715)
			(type default)
		)
		(layer "In11.Cu")
	)
	(gr_arc
		(start 98.94316 -227.129086)
		(mid 98.947109 -227.126309)
		(end 98.951034 -227.123498)
		(stroke
			(width 0.05715)
			(type default)
		)
		(layer "In11.Cu")
	)
	(gr_arc
		(start 98.951034 -226.205542)
		(mid 98.947109 -226.202731)
		(end 98.94316 -226.199954)
		(stroke
			(width 0.05715)
			(type default)
		)
		(layer "In11.Cu")
	)
	(gr_arc
		(start 98.953828 -229.447344)
		(mid 98.948516 -229.443503)
		(end 98.94316 -229.439724)
		(stroke
			(width 0.05715)
			(type default)
		)
		(layer "In11.Cu")
	)
	(gr_line
		(start 98.993452 -379.957584)
		(end 99.180904 -379.912626)
		(stroke
			(width 0.07112)
			(type default)
		)
		(layer "In11.Cu")
	)
	(gr_line
		(start 99.016312 -278.946102)
		(end 99.016566 -278.946356)
		(stroke
			(width 0.05715)
			(type default)
		)
		(layer "In11.Cu")
	)
	(gr_line
		(start 99.016312 -275.696172)
		(end 99.016312 -275.698204)
		(stroke
			(width 0.05715)
			(type default)
		)
		(layer "In11.Cu")
	)
	(gr_line
		(start 99.05619 -380.657862)
		(end 99.422712 -380.059946)
		(stroke
			(width 0.07112)
			(type default)
		)
		(layer "In11.Cu")
	)
	(gr_arc
		(start 99.071684 -281.720036)
		(mid 99.06402 -281.725307)
		(end 99.056444 -281.730704)
		(stroke
			(width 0.05715)
			(type default)
		)
		(layer "In11.Cu")
	)
	(gr_line
		(start 99.071684 -281.720036)
		(end 99.073208 -281.71902)
		(stroke
			(width 0.05715)
			(type default)
		)
		(layer "In11.Cu")
	)
	(gr_line
		(start 99.073208 -281.71902)
		(end 99.077272 -281.716734)
		(stroke
			(width 0.05715)
			(type default)
		)
		(layer "In11.Cu")
	)
	(gr_line
		(start 99.10826 -293.03853)
		(end 99.108768 -293.038276)
		(stroke
			(width 0.05715)
			(type default)
		)
		(layer "In11.Cu")
	)
	(gr_line
		(start 99.10826 -291.418518)
		(end 99.108768 -291.418264)
		(stroke
			(width 0.05715)
			(type default)
		)
		(layer "In11.Cu")
	)
	(gr_line
		(start 99.10826 -289.798506)
		(end 99.108768 -289.798252)
		(stroke
			(width 0.05715)
			(type default)
		)
		(layer "In11.Cu")
	)
	(gr_line
		(start 99.10826 -284.938724)
		(end 99.108768 -284.93847)
		(stroke
			(width 0.05715)
			(type default)
		)
		(layer "In11.Cu")
	)
	(gr_line
		(start 99.10826 -283.318712)
		(end 99.108768 -283.318458)
		(stroke
			(width 0.05715)
			(type default)
		)
		(layer "In11.Cu")
	)
	(gr_line
		(start 99.10826 -281.6987)
		(end 99.108768 -281.698446)
		(stroke
			(width 0.05715)
			(type default)
		)
		(layer "In11.Cu")
	)
	(gr_line
		(start 99.10826 -278.458676)
		(end 99.108768 -278.458422)
		(stroke
			(width 0.05715)
			(type default)
		)
		(layer "In11.Cu")
	)
	(gr_line
		(start 99.10826 -276.838664)
		(end 99.108768 -276.83841)
		(stroke
			(width 0.05715)
			(type default)
		)
		(layer "In11.Cu")
	)
	(gr_line
		(start 99.108768 -277.814278)
		(end 99.108006 -277.81377)
		(stroke
			(width 0.05715)
			(type default)
		)
		(layer "In11.Cu")
	)
	(gr_line
		(start 99.10953 -287.53435)
		(end 99.109276 -287.53435)
		(stroke
			(width 0.05715)
			(type default)
		)
		(layer "In11.Cu")
	)
	(gr_line
		(start 99.110546 -277.815294)
		(end 99.108768 -277.814278)
		(stroke
			(width 0.05715)
			(type default)
		)
		(layer "In11.Cu")
	)
	(gr_line
		(start 99.110546 -276.195282)
		(end 99.108514 -276.194012)
		(stroke
			(width 0.05715)
			(type default)
		)
		(layer "In11.Cu")
	)
	(gr_line
		(start 99.186492 -221.083378)
		(end 99.140772 -221.129098)
		(stroke
			(width 0.05715)
			(type default)
		)
		(layer "In11.Cu")
	)
	(gr_line
		(start 99.186492 -221.05493)
		(end 99.186492 -221.083378)
		(stroke
			(width 0.05715)
			(type default)
		)
		(layer "In11.Cu")
	)
	(gr_line
		(start 99.19081 -280.881328)
		(end 99.188524 -280.880058)
		(stroke
			(width 0.05715)
			(type default)
		)
		(layer "In11.Cu")
	)
	(gr_line
		(start 99.203256 -281.864308)
		(end 99.205034 -281.863292)
		(stroke
			(width 0.05715)
			(type default)
		)
		(layer "In11.Cu")
	)
	(gr_line
		(start 99.203256 -278.624284)
		(end 99.205034 -278.623268)
		(stroke
			(width 0.05715)
			(type default)
		)
		(layer "In11.Cu")
	)
	(gr_line
		(start 99.203764 -293.203884)
		(end 99.205034 -293.203122)
		(stroke
			(width 0.05715)
			(type default)
		)
		(layer "In11.Cu")
	)
	(gr_line
		(start 99.203764 -291.583872)
		(end 99.205034 -291.58311)
		(stroke
			(width 0.05715)
			(type default)
		)
		(layer "In11.Cu")
	)
	(gr_line
		(start 99.203764 -289.96386)
		(end 99.205034 -289.963098)
		(stroke
			(width 0.05715)
			(type default)
		)
		(layer "In11.Cu")
	)
	(gr_line
		(start 99.203764 -285.104078)
		(end 99.205034 -285.103316)
		(stroke
			(width 0.05715)
			(type default)
		)
		(layer "In11.Cu")
	)
	(gr_line
		(start 99.203764 -283.484066)
		(end 99.205034 -283.483304)
		(stroke
			(width 0.05715)
			(type default)
		)
		(layer "In11.Cu")
	)
	(gr_line
		(start 99.203764 -277.004018)
		(end 99.205034 -277.003256)
		(stroke
			(width 0.05715)
			(type default)
		)
		(layer "In11.Cu")
	)
	(gr_line
		(start 99.206558 -277.650448)
		(end 99.204018 -277.648924)
		(stroke
			(width 0.05715)
			(type default)
		)
		(layer "In11.Cu")
	)
	(gr_line
		(start 99.206558 -276.030436)
		(end 99.205796 -276.029928)
		(stroke
			(width 0.05715)
			(type default)
		)
		(layer "In11.Cu")
	)
	(gr_line
		(start 99.20986 -277.65248)
		(end 99.206558 -277.650448)
		(stroke
			(width 0.05715)
			(type default)
		)
		(layer "In11.Cu")
	)
	(gr_line
		(start 99.20986 -276.032214)
		(end 99.206558 -276.030436)
		(stroke
			(width 0.05715)
			(type default)
		)
		(layer "In11.Cu")
	)
	(gr_arc
		(start 99.230942 -225.503486)
		(mid 99.234867 -225.506297)
		(end 99.238816 -225.509074)
		(stroke
			(width 0.05715)
			(type default)
		)
		(layer "In11.Cu")
	)
	(gr_line
		(start 99.235514 -285.767272)
		(end 99.234752 -285.766764)
		(stroke
			(width 0.05715)
			(type default)
		)
		(layer "In11.Cu")
	)
	(gr_line
		(start 99.236276 -285.76778)
		(end 99.235514 -285.767272)
		(stroke
			(width 0.05715)
			(type default)
		)
		(layer "In11.Cu")
	)
	(gr_line
		(start 99.238816 -225.509074)
		(end 99.245674 -225.513138)
		(stroke
			(width 0.05715)
			(type default)
		)
		(layer "In11.Cu")
	)
	(gr_line
		(start 99.243134 -285.771844)
		(end 99.236276 -285.76778)
		(stroke
			(width 0.05715)
			(type default)
		)
		(layer "In11.Cu")
	)
	(gr_line
		(start 99.245674 -225.513138)
		(end 99.246436 -225.513646)
		(stroke
			(width 0.05715)
			(type default)
		)
		(layer "In11.Cu")
	)
	(gr_line
		(start 99.246436 -225.513646)
		(end 99.246944 -225.5139)
		(stroke
			(width 0.05715)
			(type default)
		)
		(layer "In11.Cu")
	)
	(gr_line
		(start 99.2505 -296.463974)
		(end 99.2505 -296.435526)
		(stroke
			(width 0.05715)
			(type default)
		)
		(layer "In11.Cu")
	)
	(gr_line
		(start 99.2505 -296.435526)
		(end 99.29622 -296.389806)
		(stroke
			(width 0.05715)
			(type default)
		)
		(layer "In11.Cu")
	)
	(gr_arc
		(start 99.251008 -285.777432)
		(mid 99.247083 -285.774621)
		(end 99.243134 -285.771844)
		(stroke
			(width 0.05715)
			(type default)
		)
		(layer "In11.Cu")
	)
	(gr_line
		(start 99.270058 -222.287338)
		(end 99.271836 -222.288354)
		(stroke
			(width 0.05715)
			(type default)
		)
		(layer "In11.Cu")
	)
	(gr_line
		(start 99.271582 -225.528124)
		(end 99.272598 -225.528886)
		(stroke
			(width 0.05715)
			(type default)
		)
		(layer "In11.Cu")
	)
	(gr_line
		(start 99.271836 -222.288354)
		(end 99.272852 -222.288862)
		(stroke
			(width 0.05715)
			(type default)
		)
		(layer "In11.Cu")
	)
	(gr_line
		(start 99.272598 -225.528886)
		(end 99.273614 -225.529394)
		(stroke
			(width 0.05715)
			(type default)
		)
		(layer "In11.Cu")
	)
	(gr_line
		(start 99.272852 -222.288862)
		(end 99.273614 -222.28937)
		(stroke
			(width 0.05715)
			(type default)
		)
		(layer "In11.Cu")
	)
	(gr_line
		(start 99.275138 -225.53041)
		(end 99.276916 -225.531426)
		(stroke
			(width 0.05715)
			(type default)
		)
		(layer "In11.Cu")
	)
	(gr_line
		(start 99.276916 -225.531426)
		(end 99.277932 -225.531934)
		(stroke
			(width 0.05715)
			(type default)
		)
		(layer "In11.Cu")
	)
	(gr_line
		(start 99.277932 -225.531934)
		(end 99.278694 -225.532442)
		(stroke
			(width 0.05715)
			(type default)
		)
		(layer "In11.Cu")
	)
	(gr_line
		(start 99.278694 -225.532442)
		(end 99.279964 -225.533204)
		(stroke
			(width 0.05715)
			(type default)
		)
		(layer "In11.Cu")
	)
	(gr_line
		(start 99.359974 -379.360176)
		(end 99.582986 -378.99594)
		(stroke
			(width 0.07112)
			(type default)
		)
		(layer "In11.Cu")
	)
	(gr_line
		(start 99.36607 -222.122746)
		(end 99.373182 -222.126556)
		(stroke
			(width 0.05715)
			(type default)
		)
		(layer "In11.Cu")
	)
	(gr_line
		(start 99.366324 -225.36277)
		(end 99.366832 -225.363024)
		(stroke
			(width 0.05715)
			(type default)
		)
		(layer "In11.Cu")
	)
	(gr_line
		(start 99.366832 -225.363024)
		(end 99.367848 -225.363532)
		(stroke
			(width 0.05715)
			(type default)
		)
		(layer "In11.Cu")
	)
	(gr_line
		(start 99.367848 -225.363532)
		(end 99.369372 -225.364548)
		(stroke
			(width 0.05715)
			(type default)
		)
		(layer "In11.Cu")
	)
	(gr_line
		(start 99.371912 -225.365818)
		(end 99.373182 -225.36658)
		(stroke
			(width 0.05715)
			(type default)
		)
		(layer "In11.Cu")
	)
	(gr_line
		(start 99.373182 -225.36658)
		(end 99.373944 -225.367088)
		(stroke
			(width 0.05715)
			(type default)
		)
		(layer "In11.Cu")
	)
	(gr_line
		(start 99.373944 -225.367088)
		(end 99.37496 -225.367596)
		(stroke
			(width 0.05715)
			(type default)
		)
		(layer "In11.Cu")
	)
	(gr_line
		(start 99.404932 -379.547374)
		(end 99.359974 -379.360176)
		(stroke
			(width 0.07112)
			(type default)
		)
		(layer "In11.Cu")
	)
	(gr_line
		(start 99.53244 -296.463974)
		(end 99.53244 -296.435526)
		(stroke
			(width 0.05715)
			(type default)
		)
		(layer "In11.Cu")
	)
	(gr_line
		(start 99.53244 -296.435526)
		(end 99.48672 -296.389806)
		(stroke
			(width 0.05715)
			(type default)
		)
		(layer "In11.Cu")
	)
	(gr_line
		(start 99.582986 -378.99594)
		(end 99.770438 -378.950982)
		(stroke
			(width 0.07112)
			(type default)
		)
		(layer "In11.Cu")
	)
	(gr_line
		(start 99.645724 -379.696218)
		(end 100.0125 -379.098302)
		(stroke
			(width 0.07112)
			(type default)
		)
		(layer "In11.Cu")
	)
	(gr_arc
		(start 99.699572 -229.5525)
		(mid 99.704255 -229.555825)
		(end 99.70897 -229.559104)
		(stroke
			(width 0.05715)
			(type default)
		)
		(layer "In11.Cu")
	)
	(gr_line
		(start 99.70897 -229.559104)
		(end 99.711002 -229.560628)
		(stroke
			(width 0.05715)
			(type default)
		)
		(layer "In11.Cu")
	)
	(gr_line
		(start 99.711002 -229.560628)
		(end 99.715828 -229.563422)
		(stroke
			(width 0.05715)
			(type default)
		)
		(layer "In11.Cu")
	)
	(gr_line
		(start 99.765612 -295.193212)
		(end 99.765612 -295.192196)
		(stroke
			(width 0.05715)
			(type default)
		)
		(layer "In11.Cu")
	)
	(gr_line
		(start 99.771708 -378.950728)
		(end 99.771962 -378.950728)
		(stroke
			(width 0.07112)
			(type default)
		)
		(layer "In11.Cu")
	)
	(gr_line
		(start 99.843336 -229.41661)
		(end 99.843844 -229.416864)
		(stroke
			(width 0.05715)
			(type default)
		)
		(layer "In11.Cu")
	)
	(gr_line
		(start 99.854258 -221.083378)
		(end 99.899978 -221.129098)
		(stroke
			(width 0.05715)
			(type default)
		)
		(layer "In11.Cu")
	)
	(gr_line
		(start 99.854258 -221.05493)
		(end 99.854258 -221.083378)
		(stroke
			(width 0.05715)
			(type default)
		)
		(layer "In11.Cu")
	)
	(gr_line
		(start 99.882452 -228.749352)
		(end 99.874578 -228.753924)
		(stroke
			(width 0.05715)
			(type default)
		)
		(layer "In11.Cu")
	)
	(gr_line
		(start 99.88296 -228.749098)
		(end 99.882452 -228.749352)
		(stroke
			(width 0.05715)
			(type default)
		)
		(layer "In11.Cu")
	)
	(gr_arc
		(start 99.88296 -228.749098)
		(mid 99.886143 -228.746823)
		(end 99.88931 -228.744526)
		(stroke
			(width 0.05715)
			(type default)
		)
		(layer "In11.Cu")
	)
	(gr_line
		(start 100.040694 -285.909512)
		(end 100.039424 -285.90875)
		(stroke
			(width 0.05715)
			(type default)
		)
		(layer "In11.Cu")
	)
	(gr_line
		(start 100.040694 -284.2895)
		(end 100.039424 -284.288738)
		(stroke
			(width 0.05715)
			(type default)
		)
		(layer "In11.Cu")
	)
	(gr_line
		(start 100.040694 -282.669488)
		(end 100.039424 -282.668726)
		(stroke
			(width 0.05715)
			(type default)
		)
		(layer "In11.Cu")
	)
	(gr_line
		(start 100.040694 -281.049476)
		(end 100.039424 -281.048714)
		(stroke
			(width 0.05715)
			(type default)
		)
		(layer "In11.Cu")
	)
	(gr_line
		(start 100.042218 -294.662352)
		(end 100.04552 -294.66032)
		(stroke
			(width 0.05715)
			(type default)
		)
		(layer "In11.Cu")
	)
	(gr_line
		(start 100.042218 -293.04234)
		(end 100.04552 -293.040308)
		(stroke
			(width 0.05715)
			(type default)
		)
		(layer "In11.Cu")
	)
	(gr_line
		(start 100.042218 -291.422328)
		(end 100.04552 -291.420296)
		(stroke
			(width 0.05715)
			(type default)
		)
		(layer "In11.Cu")
	)
	(gr_line
		(start 100.042218 -289.802316)
		(end 100.04552 -289.800284)
		(stroke
			(width 0.05715)
			(type default)
		)
		(layer "In11.Cu")
	)
	(gr_line
		(start 100.042218 -284.942534)
		(end 100.04552 -284.940502)
		(stroke
			(width 0.05715)
			(type default)
		)
		(layer "In11.Cu")
	)
	(gr_line
		(start 100.042218 -283.322522)
		(end 100.04552 -283.32049)
		(stroke
			(width 0.05715)
			(type default)
		)
		(layer "In11.Cu")
	)
	(gr_line
		(start 100.042218 -281.70251)
		(end 100.04552 -281.700478)
		(stroke
			(width 0.05715)
			(type default)
		)
		(layer "In11.Cu")
	)
	(gr_line
		(start 100.042218 -278.462486)
		(end 100.04552 -278.460454)
		(stroke
			(width 0.05715)
			(type default)
		)
		(layer "In11.Cu")
	)
	(gr_line
		(start 100.043234 -285.911036)
		(end 100.042472 -285.910528)
		(stroke
			(width 0.05715)
			(type default)
		)
		(layer "In11.Cu")
	)
	(gr_line
		(start 100.043234 -284.291024)
		(end 100.042472 -284.290516)
		(stroke
			(width 0.05715)
			(type default)
		)
		(layer "In11.Cu")
	)
	(gr_line
		(start 100.043234 -282.671012)
		(end 100.042472 -282.670504)
		(stroke
			(width 0.05715)
			(type default)
		)
		(layer "In11.Cu")
	)
	(gr_line
		(start 100.043234 -281.051)
		(end 100.042472 -281.050492)
		(stroke
			(width 0.05715)
			(type default)
		)
		(layer "In11.Cu")
	)
	(gr_line
		(start 100.04552 -294.66032)
		(end 100.047044 -294.659304)
		(stroke
			(width 0.05715)
			(type default)
		)
		(layer "In11.Cu")
	)
	(gr_line
		(start 100.04552 -293.040308)
		(end 100.047044 -293.039292)
		(stroke
			(width 0.05715)
			(type default)
		)
		(layer "In11.Cu")
	)
	(gr_line
		(start 100.04552 -291.420296)
		(end 100.047044 -291.41928)
		(stroke
			(width 0.05715)
			(type default)
		)
		(layer "In11.Cu")
	)
	(gr_line
		(start 100.04552 -289.800284)
		(end 100.047044 -289.799268)
		(stroke
			(width 0.05715)
			(type default)
		)
		(layer "In11.Cu")
	)
	(gr_line
		(start 100.04552 -285.912306)
		(end 100.044504 -285.911798)
		(stroke
			(width 0.05715)
			(type default)
		)
		(layer "In11.Cu")
	)
	(gr_line
		(start 100.04552 -284.940502)
		(end 100.047044 -284.939486)
		(stroke
			(width 0.05715)
			(type default)
		)
		(layer "In11.Cu")
	)
	(gr_line
		(start 100.04552 -284.292294)
		(end 100.044504 -284.291786)
		(stroke
			(width 0.05715)
			(type default)
		)
		(layer "In11.Cu")
	)
	(gr_line
		(start 100.04552 -283.32049)
		(end 100.047044 -283.319474)
		(stroke
			(width 0.05715)
			(type default)
		)
		(layer "In11.Cu")
	)
	(gr_line
		(start 100.04552 -282.672282)
		(end 100.044504 -282.671774)
		(stroke
			(width 0.05715)
			(type default)
		)
		(layer "In11.Cu")
	)
	(gr_line
		(start 100.04552 -281.700478)
		(end 100.047044 -281.699462)
		(stroke
			(width 0.05715)
			(type default)
		)
		(layer "In11.Cu")
	)
	(gr_line
		(start 100.04552 -281.05227)
		(end 100.044504 -281.051762)
		(stroke
			(width 0.05715)
			(type default)
		)
		(layer "In11.Cu")
	)
	(gr_line
		(start 100.04552 -278.460454)
		(end 100.047044 -278.459438)
		(stroke
			(width 0.05715)
			(type default)
		)
		(layer "In11.Cu")
	)
	(gr_line
		(start 100.047044 -294.659304)
		(end 100.04806 -294.658796)
		(stroke
			(width 0.05715)
			(type default)
		)
		(layer "In11.Cu")
	)
	(gr_line
		(start 100.047044 -293.039292)
		(end 100.04806 -293.038784)
		(stroke
			(width 0.05715)
			(type default)
		)
		(layer "In11.Cu")
	)
	(gr_line
		(start 100.047044 -291.41928)
		(end 100.04806 -291.418772)
		(stroke
			(width 0.05715)
			(type default)
		)
		(layer "In11.Cu")
	)
	(gr_line
		(start 100.047044 -289.799268)
		(end 100.04806 -289.79876)
		(stroke
			(width 0.05715)
			(type default)
		)
		(layer "In11.Cu")
	)
	(gr_line
		(start 100.047044 -285.913322)
		(end 100.04552 -285.912306)
		(stroke
			(width 0.05715)
			(type default)
		)
		(layer "In11.Cu")
	)
	(gr_line
		(start 100.047044 -284.939486)
		(end 100.04806 -284.938978)
		(stroke
			(width 0.05715)
			(type default)
		)
		(layer "In11.Cu")
	)
	(gr_line
		(start 100.047044 -284.29331)
		(end 100.04552 -284.292294)
		(stroke
			(width 0.05715)
			(type default)
		)
		(layer "In11.Cu")
	)
	(gr_line
		(start 100.047044 -283.319474)
		(end 100.04806 -283.318966)
		(stroke
			(width 0.05715)
			(type default)
		)
		(layer "In11.Cu")
	)
	(gr_line
		(start 100.047044 -282.673298)
		(end 100.04552 -282.672282)
		(stroke
			(width 0.05715)
			(type default)
		)
		(layer "In11.Cu")
	)
	(gr_line
		(start 100.047044 -281.699462)
		(end 100.04806 -281.698954)
		(stroke
			(width 0.05715)
			(type default)
		)
		(layer "In11.Cu")
	)
	(gr_line
		(start 100.047044 -281.053286)
		(end 100.04552 -281.05227)
		(stroke
			(width 0.05715)
			(type default)
		)
		(layer "In11.Cu")
	)
	(gr_line
		(start 100.047044 -278.459438)
		(end 100.04806 -278.45893)
		(stroke
			(width 0.05715)
			(type default)
		)
		(layer "In11.Cu")
	)
	(gr_line
		(start 100.04806 -294.658796)
		(end 100.048568 -294.658542)
		(stroke
			(width 0.05715)
			(type default)
		)
		(layer "In11.Cu")
	)
	(gr_line
		(start 100.04806 -294.013636)
		(end 100.047044 -294.013128)
		(stroke
			(width 0.05715)
			(type default)
		)
		(layer "In11.Cu")
	)
	(gr_line
		(start 100.04806 -293.038784)
		(end 100.048822 -293.038276)
		(stroke
			(width 0.05715)
			(type default)
		)
		(layer "In11.Cu")
	)
	(gr_line
		(start 100.04806 -292.393624)
		(end 100.047044 -292.393116)
		(stroke
			(width 0.05715)
			(type default)
		)
		(layer "In11.Cu")
	)
	(gr_line
		(start 100.04806 -291.418772)
		(end 100.048822 -291.418264)
		(stroke
			(width 0.05715)
			(type default)
		)
		(layer "In11.Cu")
	)
	(gr_line
		(start 100.04806 -290.773612)
		(end 100.047044 -290.773104)
		(stroke
			(width 0.05715)
			(type default)
		)
		(layer "In11.Cu")
	)
	(gr_line
		(start 100.04806 -289.79876)
		(end 100.048822 -289.798252)
		(stroke
			(width 0.05715)
			(type default)
		)
		(layer "In11.Cu")
	)
	(gr_line
		(start 100.04806 -289.1536)
		(end 100.047044 -289.153092)
		(stroke
			(width 0.05715)
			(type default)
		)
		(layer "In11.Cu")
	)
	(gr_line
		(start 100.04806 -285.91383)
		(end 100.047044 -285.913322)
		(stroke
			(width 0.05715)
			(type default)
		)
		(layer "In11.Cu")
	)
	(gr_line
		(start 100.04806 -284.938978)
		(end 100.048822 -284.93847)
		(stroke
			(width 0.05715)
			(type default)
		)
		(layer "In11.Cu")
	)
	(gr_line
		(start 100.04806 -284.293818)
		(end 100.047044 -284.29331)
		(stroke
			(width 0.05715)
			(type default)
		)
		(layer "In11.Cu")
	)
	(gr_line
		(start 100.04806 -283.318966)
		(end 100.048822 -283.318458)
		(stroke
			(width 0.05715)
			(type default)
		)
		(layer "In11.Cu")
	)
	(gr_line
		(start 100.04806 -282.673806)
		(end 100.047044 -282.673298)
		(stroke
			(width 0.05715)
			(type default)
		)
		(layer "In11.Cu")
	)
	(gr_line
		(start 100.04806 -281.698954)
		(end 100.048822 -281.698446)
		(stroke
			(width 0.05715)
			(type default)
		)
		(layer "In11.Cu")
	)
	(gr_line
		(start 100.04806 -281.053794)
		(end 100.047044 -281.053286)
		(stroke
			(width 0.05715)
			(type default)
		)
		(layer "In11.Cu")
	)
	(gr_line
		(start 100.04806 -278.45893)
		(end 100.048822 -278.458422)
		(stroke
			(width 0.05715)
			(type default)
		)
		(layer "In11.Cu")
	)
	(gr_line
		(start 100.048822 -294.014144)
		(end 100.04806 -294.013636)
		(stroke
			(width 0.05715)
			(type default)
		)
		(layer "In11.Cu")
	)
	(gr_line
		(start 100.048822 -292.394132)
		(end 100.04806 -292.393624)
		(stroke
			(width 0.05715)
			(type default)
		)
		(layer "In11.Cu")
	)
	(gr_line
		(start 100.048822 -290.77412)
		(end 100.04806 -290.773612)
		(stroke
			(width 0.05715)
			(type default)
		)
		(layer "In11.Cu")
	)
	(gr_line
		(start 100.048822 -289.154108)
		(end 100.04806 -289.1536)
		(stroke
			(width 0.05715)
			(type default)
		)
		(layer "In11.Cu")
	)
	(gr_line
		(start 100.050092 -294.014906)
		(end 100.048822 -294.014144)
		(stroke
			(width 0.05715)
			(type default)
		)
		(layer "In11.Cu")
	)
	(gr_line
		(start 100.050092 -292.394894)
		(end 100.048822 -292.394132)
		(stroke
			(width 0.05715)
			(type default)
		)
		(layer "In11.Cu")
	)
	(gr_line
		(start 100.050092 -290.774882)
		(end 100.048822 -290.77412)
		(stroke
			(width 0.05715)
			(type default)
		)
		(layer "In11.Cu")
	)
	(gr_line
		(start 100.050092 -289.15487)
		(end 100.048822 -289.154108)
		(stroke
			(width 0.05715)
			(type default)
		)
		(layer "In11.Cu")
	)
	(gr_line
		(start 100.054156 -294.017192)
		(end 100.052632 -294.016176)
		(stroke
			(width 0.05715)
			(type default)
		)
		(layer "In11.Cu")
	)
	(gr_line
		(start 100.054156 -292.39718)
		(end 100.052632 -292.396164)
		(stroke
			(width 0.05715)
			(type default)
		)
		(layer "In11.Cu")
	)
	(gr_line
		(start 100.054156 -290.777168)
		(end 100.052632 -290.776152)
		(stroke
			(width 0.05715)
			(type default)
		)
		(layer "In11.Cu")
	)
	(gr_line
		(start 100.054156 -289.157156)
		(end 100.052632 -289.15614)
		(stroke
			(width 0.05715)
			(type default)
		)
		(layer "In11.Cu")
	)
	(gr_line
		(start 100.055172 -294.0177)
		(end 100.054156 -294.017192)
		(stroke
			(width 0.05715)
			(type default)
		)
		(layer "In11.Cu")
	)
	(gr_line
		(start 100.055172 -292.397688)
		(end 100.054156 -292.39718)
		(stroke
			(width 0.05715)
			(type default)
		)
		(layer "In11.Cu")
	)
	(gr_line
		(start 100.055172 -290.777676)
		(end 100.054156 -290.777168)
		(stroke
			(width 0.05715)
			(type default)
		)
		(layer "In11.Cu")
	)
	(gr_line
		(start 100.055172 -289.157664)
		(end 100.054156 -289.157156)
		(stroke
			(width 0.05715)
			(type default)
		)
		(layer "In11.Cu")
	)
	(gr_line
		(start 100.055172 -285.917894)
		(end 100.054156 -285.917386)
		(stroke
			(width 0.05715)
			(type default)
		)
		(layer "In11.Cu")
	)
	(gr_line
		(start 100.055172 -284.297882)
		(end 100.054156 -284.297374)
		(stroke
			(width 0.05715)
			(type default)
		)
		(layer "In11.Cu")
	)
	(gr_line
		(start 100.055172 -282.67787)
		(end 100.054156 -282.677362)
		(stroke
			(width 0.05715)
			(type default)
		)
		(layer "In11.Cu")
	)
	(gr_line
		(start 100.055172 -281.057858)
		(end 100.054156 -281.05735)
		(stroke
			(width 0.05715)
			(type default)
		)
		(layer "In11.Cu")
	)
	(gr_line
		(start 100.05568 -294.017954)
		(end 100.055172 -294.0177)
		(stroke
			(width 0.05715)
			(type default)
		)
		(layer "In11.Cu")
	)
	(gr_line
		(start 100.05568 -292.397942)
		(end 100.055172 -292.397688)
		(stroke
			(width 0.05715)
			(type default)
		)
		(layer "In11.Cu")
	)
	(gr_line
		(start 100.05568 -290.77793)
		(end 100.055172 -290.777676)
		(stroke
			(width 0.05715)
			(type default)
		)
		(layer "In11.Cu")
	)
	(gr_line
		(start 100.05568 -289.157918)
		(end 100.055172 -289.157664)
		(stroke
			(width 0.05715)
			(type default)
		)
		(layer "In11.Cu")
	)
	(gr_line
		(start 100.05568 -285.918148)
		(end 100.055172 -285.917894)
		(stroke
			(width 0.05715)
			(type default)
		)
		(layer "In11.Cu")
	)
	(gr_line
		(start 100.05568 -284.298136)
		(end 100.055172 -284.297882)
		(stroke
			(width 0.05715)
			(type default)
		)
		(layer "In11.Cu")
	)
	(gr_line
		(start 100.05568 -282.678124)
		(end 100.055172 -282.67787)
		(stroke
			(width 0.05715)
			(type default)
		)
		(layer "In11.Cu")
	)
	(gr_line
		(start 100.05568 -281.058112)
		(end 100.055172 -281.057858)
		(stroke
			(width 0.05715)
			(type default)
		)
		(layer "In11.Cu")
	)
	(gr_line
		(start 100.136198 -221.083378)
		(end 100.090478 -221.129098)
		(stroke
			(width 0.05715)
			(type default)
		)
		(layer "In11.Cu")
	)
	(gr_line
		(start 100.136198 -221.05493)
		(end 100.136198 -221.083378)
		(stroke
			(width 0.05715)
			(type default)
		)
		(layer "In11.Cu")
	)
	(gr_line
		(start 100.141532 -294.825166)
		(end 100.14331 -294.82415)
		(stroke
			(width 0.05715)
			(type default)
		)
		(layer "In11.Cu")
	)
	(gr_line
		(start 100.141532 -293.205154)
		(end 100.14331 -293.204138)
		(stroke
			(width 0.05715)
			(type default)
		)
		(layer "In11.Cu")
	)
	(gr_line
		(start 100.141532 -291.585142)
		(end 100.14331 -291.584126)
		(stroke
			(width 0.05715)
			(type default)
		)
		(layer "In11.Cu")
	)
	(gr_line
		(start 100.141532 -289.96513)
		(end 100.14331 -289.964114)
		(stroke
			(width 0.05715)
			(type default)
		)
		(layer "In11.Cu")
	)
	(gr_line
		(start 100.141532 -285.105348)
		(end 100.14331 -285.104332)
		(stroke
			(width 0.05715)
			(type default)
		)
		(layer "In11.Cu")
	)
	(gr_line
		(start 100.141532 -283.485336)
		(end 100.14331 -283.48432)
		(stroke
			(width 0.05715)
			(type default)
		)
		(layer "In11.Cu")
	)
	(gr_line
		(start 100.141532 -281.865324)
		(end 100.14331 -281.864308)
		(stroke
			(width 0.05715)
			(type default)
		)
		(layer "In11.Cu")
	)
	(gr_line
		(start 100.141532 -278.6253)
		(end 100.14331 -278.624284)
		(stroke
			(width 0.05715)
			(type default)
		)
		(layer "In11.Cu")
	)
	(gr_line
		(start 100.14331 -293.848282)
		(end 100.14204 -293.84752)
		(stroke
			(width 0.05715)
			(type default)
		)
		(layer "In11.Cu")
	)
	(gr_line
		(start 100.14331 -293.204138)
		(end 100.144072 -293.20363)
		(stroke
			(width 0.05715)
			(type default)
		)
		(layer "In11.Cu")
	)
	(gr_line
		(start 100.14331 -292.22827)
		(end 100.14204 -292.227508)
		(stroke
			(width 0.05715)
			(type default)
		)
		(layer "In11.Cu")
	)
	(gr_line
		(start 100.14331 -291.584126)
		(end 100.144072 -291.583618)
		(stroke
			(width 0.05715)
			(type default)
		)
		(layer "In11.Cu")
	)
	(gr_line
		(start 100.14331 -290.608258)
		(end 100.14204 -290.607496)
		(stroke
			(width 0.05715)
			(type default)
		)
		(layer "In11.Cu")
	)
	(gr_line
		(start 100.14331 -289.964114)
		(end 100.144072 -289.963606)
		(stroke
			(width 0.05715)
			(type default)
		)
		(layer "In11.Cu")
	)
	(gr_line
		(start 100.14331 -288.988246)
		(end 100.14204 -288.987484)
		(stroke
			(width 0.05715)
			(type default)
		)
		(layer "In11.Cu")
	)
	(gr_line
		(start 100.14331 -285.748476)
		(end 100.140516 -285.746952)
		(stroke
			(width 0.05715)
			(type default)
		)
		(layer "In11.Cu")
	)
	(gr_line
		(start 100.14331 -285.104332)
		(end 100.144072 -285.103824)
		(stroke
			(width 0.05715)
			(type default)
		)
		(layer "In11.Cu")
	)
	(gr_line
		(start 100.14331 -284.128464)
		(end 100.140516 -284.12694)
		(stroke
			(width 0.05715)
			(type default)
		)
		(layer "In11.Cu")
	)
	(gr_line
		(start 100.14331 -283.48432)
		(end 100.144072 -283.483812)
		(stroke
			(width 0.05715)
			(type default)
		)
		(layer "In11.Cu")
	)
	(gr_line
		(start 100.14331 -282.508452)
		(end 100.140516 -282.506928)
		(stroke
			(width 0.05715)
			(type default)
		)
		(layer "In11.Cu")
	)
	(gr_line
		(start 100.14331 -281.864308)
		(end 100.144072 -281.8638)
		(stroke
			(width 0.05715)
			(type default)
		)
		(layer "In11.Cu")
	)
	(gr_line
		(start 100.14331 -280.88844)
		(end 100.140516 -280.886916)
		(stroke
			(width 0.05715)
			(type default)
		)
		(layer "In11.Cu")
	)
	(gr_line
		(start 100.14331 -278.624284)
		(end 100.144072 -278.623776)
		(stroke
			(width 0.05715)
			(type default)
		)
		(layer "In11.Cu")
	)
	(gr_line
		(start 100.144072 -293.84879)
		(end 100.14331 -293.848282)
		(stroke
			(width 0.05715)
			(type default)
		)
		(layer "In11.Cu")
	)
	(gr_line
		(start 100.144072 -293.20363)
		(end 100.145088 -293.203122)
		(stroke
			(width 0.05715)
			(type default)
		)
		(layer "In11.Cu")
	)
	(gr_line
		(start 100.144072 -292.228778)
		(end 100.14331 -292.22827)
		(stroke
			(width 0.05715)
			(type default)
		)
		(layer "In11.Cu")
	)
	(gr_line
		(start 100.144072 -291.583618)
		(end 100.145088 -291.58311)
		(stroke
			(width 0.05715)
			(type default)
		)
		(layer "In11.Cu")
	)
	(gr_line
		(start 100.144072 -290.608766)
		(end 100.14331 -290.608258)
		(stroke
			(width 0.05715)
			(type default)
		)
		(layer "In11.Cu")
	)
	(gr_line
		(start 100.144072 -289.963606)
		(end 100.145088 -289.963098)
		(stroke
			(width 0.05715)
			(type default)
		)
		(layer "In11.Cu")
	)
	(gr_line
		(start 100.144072 -288.988754)
		(end 100.14331 -288.988246)
		(stroke
			(width 0.05715)
			(type default)
		)
		(layer "In11.Cu")
	)
	(gr_line
		(start 100.144072 -285.748984)
		(end 100.14331 -285.748476)
		(stroke
			(width 0.05715)
			(type default)
		)
		(layer "In11.Cu")
	)
	(gr_line
		(start 100.144072 -285.103824)
		(end 100.145088 -285.103316)
		(stroke
			(width 0.05715)
			(type default)
		)
		(layer "In11.Cu")
	)
	(gr_line
		(start 100.144072 -284.128972)
		(end 100.14331 -284.128464)
		(stroke
			(width 0.05715)
			(type default)
		)
		(layer "In11.Cu")
	)
	(gr_line
		(start 100.144072 -283.483812)
		(end 100.145088 -283.483304)
		(stroke
			(width 0.05715)
			(type default)
		)
		(layer "In11.Cu")
	)
	(gr_line
		(start 100.144072 -282.50896)
		(end 100.14331 -282.508452)
		(stroke
			(width 0.05715)
			(type default)
		)
		(layer "In11.Cu")
	)
	(gr_line
		(start 100.144072 -281.8638)
		(end 100.145088 -281.863292)
		(stroke
			(width 0.05715)
			(type default)
		)
		(layer "In11.Cu")
	)
	(gr_line
		(start 100.144072 -280.888948)
		(end 100.14331 -280.88844)
		(stroke
			(width 0.05715)
			(type default)
		)
		(layer "In11.Cu")
	)
	(gr_line
		(start 100.144072 -278.623776)
		(end 100.145088 -278.623268)
		(stroke
			(width 0.05715)
			(type default)
		)
		(layer "In11.Cu")
	)
	(gr_line
		(start 100.145088 -293.849298)
		(end 100.144072 -293.84879)
		(stroke
			(width 0.05715)
			(type default)
		)
		(layer "In11.Cu")
	)
	(gr_line
		(start 100.145088 -292.229286)
		(end 100.144072 -292.228778)
		(stroke
			(width 0.05715)
			(type default)
		)
		(layer "In11.Cu")
	)
	(gr_line
		(start 100.145088 -290.609274)
		(end 100.144072 -290.608766)
		(stroke
			(width 0.05715)
			(type default)
		)
		(layer "In11.Cu")
	)
	(gr_line
		(start 100.145088 -288.989262)
		(end 100.144072 -288.988754)
		(stroke
			(width 0.05715)
			(type default)
		)
		(layer "In11.Cu")
	)
	(gr_line
		(start 100.145088 -285.749492)
		(end 100.144072 -285.748984)
		(stroke
			(width 0.05715)
			(type default)
		)
		(layer "In11.Cu")
	)
	(gr_line
		(start 100.145088 -284.12948)
		(end 100.144072 -284.128972)
		(stroke
			(width 0.05715)
			(type default)
		)
		(layer "In11.Cu")
	)
	(gr_line
		(start 100.145088 -282.509468)
		(end 100.144072 -282.50896)
		(stroke
			(width 0.05715)
			(type default)
		)
		(layer "In11.Cu")
	)
	(gr_line
		(start 100.145088 -280.889456)
		(end 100.144072 -280.888948)
		(stroke
			(width 0.05715)
			(type default)
		)
		(layer "In11.Cu")
	)
	(gr_line
		(start 100.146866 -293.850314)
		(end 100.145088 -293.849298)
		(stroke
			(width 0.05715)
			(type default)
		)
		(layer "In11.Cu")
	)
	(gr_line
		(start 100.146866 -292.230302)
		(end 100.145088 -292.229286)
		(stroke
			(width 0.05715)
			(type default)
		)
		(layer "In11.Cu")
	)
	(gr_line
		(start 100.146866 -290.61029)
		(end 100.145088 -290.609274)
		(stroke
			(width 0.05715)
			(type default)
		)
		(layer "In11.Cu")
	)
	(gr_line
		(start 100.146866 -288.990278)
		(end 100.145088 -288.989262)
		(stroke
			(width 0.05715)
			(type default)
		)
		(layer "In11.Cu")
	)
	(gr_line
		(start 100.146866 -285.750508)
		(end 100.145088 -285.749492)
		(stroke
			(width 0.05715)
			(type default)
		)
		(layer "In11.Cu")
	)
	(gr_line
		(start 100.146866 -284.130496)
		(end 100.145088 -284.12948)
		(stroke
			(width 0.05715)
			(type default)
		)
		(layer "In11.Cu")
	)
	(gr_line
		(start 100.146866 -282.510484)
		(end 100.145088 -282.509468)
		(stroke
			(width 0.05715)
			(type default)
		)
		(layer "In11.Cu")
	)
	(gr_line
		(start 100.146866 -280.890472)
		(end 100.145088 -280.889456)
		(stroke
			(width 0.05715)
			(type default)
		)
		(layer "In11.Cu")
	)
	(gr_line
		(start 100.149406 -293.851838)
		(end 100.14839 -293.85133)
		(stroke
			(width 0.05715)
			(type default)
		)
		(layer "In11.Cu")
	)
	(gr_line
		(start 100.149406 -292.231826)
		(end 100.14839 -292.231318)
		(stroke
			(width 0.05715)
			(type default)
		)
		(layer "In11.Cu")
	)
	(gr_line
		(start 100.149406 -290.611814)
		(end 100.14839 -290.611306)
		(stroke
			(width 0.05715)
			(type default)
		)
		(layer "In11.Cu")
	)
	(gr_line
		(start 100.149406 -288.991802)
		(end 100.14839 -288.991294)
		(stroke
			(width 0.05715)
			(type default)
		)
		(layer "In11.Cu")
	)
	(gr_line
		(start 100.149406 -285.752032)
		(end 100.14839 -285.751524)
		(stroke
			(width 0.05715)
			(type default)
		)
		(layer "In11.Cu")
	)
	(gr_line
		(start 100.149406 -284.13202)
		(end 100.14839 -284.131512)
		(stroke
			(width 0.05715)
			(type default)
		)
		(layer "In11.Cu")
	)
	(gr_line
		(start 100.149406 -282.512008)
		(end 100.14839 -282.5115)
		(stroke
			(width 0.05715)
			(type default)
		)
		(layer "In11.Cu")
	)
	(gr_line
		(start 100.149406 -280.891996)
		(end 100.14839 -280.891488)
		(stroke
			(width 0.05715)
			(type default)
		)
		(layer "In11.Cu")
	)
	(gr_line
		(start 100.150422 -293.8526)
		(end 100.149406 -293.851838)
		(stroke
			(width 0.05715)
			(type default)
		)
		(layer "In11.Cu")
	)
	(gr_line
		(start 100.150422 -292.232588)
		(end 100.149406 -292.231826)
		(stroke
			(width 0.05715)
			(type default)
		)
		(layer "In11.Cu")
	)
	(gr_line
		(start 100.150422 -290.612576)
		(end 100.149406 -290.611814)
		(stroke
			(width 0.05715)
			(type default)
		)
		(layer "In11.Cu")
	)
	(gr_line
		(start 100.150422 -288.992564)
		(end 100.149406 -288.991802)
		(stroke
			(width 0.05715)
			(type default)
		)
		(layer "In11.Cu")
	)
	(gr_line
		(start 100.150422 -285.752794)
		(end 100.149406 -285.752032)
		(stroke
			(width 0.05715)
			(type default)
		)
		(layer "In11.Cu")
	)
	(gr_line
		(start 100.150422 -284.132782)
		(end 100.149406 -284.13202)
		(stroke
			(width 0.05715)
			(type default)
		)
		(layer "In11.Cu")
	)
	(gr_line
		(start 100.150422 -282.51277)
		(end 100.149406 -282.512008)
		(stroke
			(width 0.05715)
			(type default)
		)
		(layer "In11.Cu")
	)
	(gr_line
		(start 100.150422 -280.892758)
		(end 100.149406 -280.891996)
		(stroke
			(width 0.05715)
			(type default)
		)
		(layer "In11.Cu")
	)
	(gr_arc
		(start 100.170996 -222.263462)
		(mid 100.1753 -222.26653)
		(end 100.179632 -222.269558)
		(stroke
			(width 0.05715)
			(type default)
		)
		(layer "In11.Cu")
	)
	(gr_line
		(start 100.175568 -293.867078)
		(end 100.17506 -293.866824)
		(stroke
			(width 0.05715)
			(type default)
		)
		(layer "In11.Cu")
	)
	(gr_line
		(start 100.175568 -292.247066)
		(end 100.17506 -292.246812)
		(stroke
			(width 0.05715)
			(type default)
		)
		(layer "In11.Cu")
	)
	(gr_line
		(start 100.175568 -290.627054)
		(end 100.17506 -290.6268)
		(stroke
			(width 0.05715)
			(type default)
		)
		(layer "In11.Cu")
	)
	(gr_line
		(start 100.175568 -289.007042)
		(end 100.17506 -289.006788)
		(stroke
			(width 0.05715)
			(type default)
		)
		(layer "In11.Cu")
	)
	(gr_line
		(start 100.175568 -285.767272)
		(end 100.17506 -285.767018)
		(stroke
			(width 0.05715)
			(type default)
		)
		(layer "In11.Cu")
	)
	(gr_line
		(start 100.175568 -284.14726)
		(end 100.17506 -284.147006)
		(stroke
			(width 0.05715)
			(type default)
		)
		(layer "In11.Cu")
	)
	(gr_line
		(start 100.175568 -282.527248)
		(end 100.17506 -282.526994)
		(stroke
			(width 0.05715)
			(type default)
		)
		(layer "In11.Cu")
	)
	(gr_line
		(start 100.175568 -280.907236)
		(end 100.17506 -280.906982)
		(stroke
			(width 0.05715)
			(type default)
		)
		(layer "In11.Cu")
	)
	(gr_line
		(start 100.17633 -293.867586)
		(end 100.175568 -293.867078)
		(stroke
			(width 0.05715)
			(type default)
		)
		(layer "In11.Cu")
	)
	(gr_line
		(start 100.17633 -292.247574)
		(end 100.175568 -292.247066)
		(stroke
			(width 0.05715)
			(type default)
		)
		(layer "In11.Cu")
	)
	(gr_line
		(start 100.17633 -290.627562)
		(end 100.175568 -290.627054)
		(stroke
			(width 0.05715)
			(type default)
		)
		(layer "In11.Cu")
	)
	(gr_line
		(start 100.17633 -289.00755)
		(end 100.175568 -289.007042)
		(stroke
			(width 0.05715)
			(type default)
		)
		(layer "In11.Cu")
	)
	(gr_line
		(start 100.17633 -285.76778)
		(end 100.175568 -285.767272)
		(stroke
			(width 0.05715)
			(type default)
		)
		(layer "In11.Cu")
	)
	(gr_line
		(start 100.17633 -284.147768)
		(end 100.175568 -284.14726)
		(stroke
			(width 0.05715)
			(type default)
		)
		(layer "In11.Cu")
	)
	(gr_line
		(start 100.17633 -282.527756)
		(end 100.175568 -282.527248)
		(stroke
			(width 0.05715)
			(type default)
		)
		(layer "In11.Cu")
	)
	(gr_line
		(start 100.17633 -280.907744)
		(end 100.175568 -280.907236)
		(stroke
			(width 0.05715)
			(type default)
		)
		(layer "In11.Cu")
	)
	(gr_line
		(start 100.179632 -222.269558)
		(end 100.180648 -222.27032)
		(stroke
			(width 0.05715)
			(type default)
		)
		(layer "In11.Cu")
	)
	(gr_line
		(start 100.180648 -222.27032)
		(end 100.181664 -222.270828)
		(stroke
			(width 0.05715)
			(type default)
		)
		(layer "In11.Cu")
	)
	(gr_line
		(start 100.181664 -222.270828)
		(end 100.186998 -222.273876)
		(stroke
			(width 0.05715)
			(type default)
		)
		(layer "In11.Cu")
	)
	(gr_line
		(start 100.183188 -293.87165)
		(end 100.17633 -293.867586)
		(stroke
			(width 0.05715)
			(type default)
		)
		(layer "In11.Cu")
	)
	(gr_line
		(start 100.183188 -292.251638)
		(end 100.17633 -292.247574)
		(stroke
			(width 0.05715)
			(type default)
		)
		(layer "In11.Cu")
	)
	(gr_line
		(start 100.183188 -290.631626)
		(end 100.17633 -290.627562)
		(stroke
			(width 0.05715)
			(type default)
		)
		(layer "In11.Cu")
	)
	(gr_line
		(start 100.183188 -289.011614)
		(end 100.17633 -289.00755)
		(stroke
			(width 0.05715)
			(type default)
		)
		(layer "In11.Cu")
	)
	(gr_line
		(start 100.183188 -285.771844)
		(end 100.17633 -285.76778)
		(stroke
			(width 0.05715)
			(type default)
		)
		(layer "In11.Cu")
	)
	(gr_line
		(start 100.183188 -284.151832)
		(end 100.17633 -284.147768)
		(stroke
			(width 0.05715)
			(type default)
		)
		(layer "In11.Cu")
	)
	(gr_line
		(start 100.183188 -282.53182)
		(end 100.17633 -282.527756)
		(stroke
			(width 0.05715)
			(type default)
		)
		(layer "In11.Cu")
	)
	(gr_line
		(start 100.183188 -280.911808)
		(end 100.17633 -280.907744)
		(stroke
			(width 0.05715)
			(type default)
		)
		(layer "In11.Cu")
	)
	(gr_line
		(start 100.18522 -296.463974)
		(end 100.18522 -296.435526)
		(stroke
			(width 0.05715)
			(type default)
		)
		(layer "In11.Cu")
	)
	(gr_line
		(start 100.18522 -296.435526)
		(end 100.23094 -296.389806)
		(stroke
			(width 0.05715)
			(type default)
		)
		(layer "In11.Cu")
	)
	(gr_arc
		(start 100.191062 -293.877238)
		(mid 100.187137 -293.874427)
		(end 100.183188 -293.87165)
		(stroke
			(width 0.05715)
			(type default)
		)
		(layer "In11.Cu")
	)
	(gr_arc
		(start 100.191062 -292.257226)
		(mid 100.187137 -292.254415)
		(end 100.183188 -292.251638)
		(stroke
			(width 0.05715)
			(type default)
		)
		(layer "In11.Cu")
	)
	(gr_arc
		(start 100.191062 -290.637214)
		(mid 100.187137 -290.634403)
		(end 100.183188 -290.631626)
		(stroke
			(width 0.05715)
			(type default)
		)
		(layer "In11.Cu")
	)
	(gr_arc
		(start 100.191062 -289.017202)
		(mid 100.187137 -289.014391)
		(end 100.183188 -289.011614)
		(stroke
			(width 0.05715)
			(type default)
		)
		(layer "In11.Cu")
	)
	(gr_arc
		(start 100.191062 -285.777432)
		(mid 100.187137 -285.774621)
		(end 100.183188 -285.771844)
		(stroke
			(width 0.05715)
			(type default)
		)
		(layer "In11.Cu")
	)
	(gr_arc
		(start 100.191062 -284.15742)
		(mid 100.187137 -284.154609)
		(end 100.183188 -284.151832)
		(stroke
			(width 0.05715)
			(type default)
		)
		(layer "In11.Cu")
	)
	(gr_arc
		(start 100.191062 -282.537408)
		(mid 100.187137 -282.534597)
		(end 100.183188 -282.53182)
		(stroke
			(width 0.05715)
			(type default)
		)
		(layer "In11.Cu")
	)
	(gr_arc
		(start 100.191062 -280.917396)
		(mid 100.187137 -280.914585)
		(end 100.183188 -280.911808)
		(stroke
			(width 0.05715)
			(type default)
		)
		(layer "In11.Cu")
	)
	(gr_line
		(start 100.218748 -225.532442)
		(end 100.219256 -225.532696)
		(stroke
			(width 0.05715)
			(type default)
		)
		(layer "In11.Cu")
	)
	(gr_line
		(start 100.221288 -225.533712)
		(end 100.22205 -225.53422)
		(stroke
			(width 0.05715)
			(type default)
		)
		(layer "In11.Cu")
	)
	(gr_line
		(start 100.229162 -244.978174)
		(end 100.230432 -244.978936)
		(stroke
			(width 0.05715)
			(type default)
		)
		(layer "In11.Cu")
	)
	(gr_line
		(start 100.31349 -225.366834)
		(end 100.313998 -225.367088)
		(stroke
			(width 0.05715)
			(type default)
		)
		(layer "In11.Cu")
	)
	(gr_line
		(start 100.313998 -225.367088)
		(end 100.315776 -225.368104)
		(stroke
			(width 0.05715)
			(type default)
		)
		(layer "In11.Cu")
	)
	(gr_line
		(start 100.315776 -225.368104)
		(end 100.3173 -225.36912)
		(stroke
			(width 0.05715)
			(type default)
		)
		(layer "In11.Cu")
	)
	(gr_line
		(start 100.33762 -225.380804)
		(end 100.34778 -225.386646)
		(stroke
			(width 0.05715)
			(type default)
		)
		(layer "In11.Cu")
	)
	(gr_arc
		(start 100.359972 -225.395282)
		(mid 100.355165 -225.3917)
		(end 100.35032 -225.38817)
		(stroke
			(width 0.05715)
			(type default)
		)
		(layer "In11.Cu")
	)
	(gr_line
		(start 100.405692 -225.871532)
		(end 100.405692 -225.87077)
		(stroke
			(width 0.05715)
			(type default)
		)
		(layer "In11.Cu")
	)
	(gr_line
		(start 100.405692 -225.870516)
		(end 100.405692 -225.87077)
		(stroke
			(width 0.05715)
			(type default)
		)
		(layer "In11.Cu")
	)
	(gr_arc
		(start 100.405692 -225.870008)
		(mid 100.405692 -225.870262)
		(end 100.405692 -225.870516)
		(stroke
			(width 0.05715)
			(type default)
		)
		(layer "In11.Cu")
	)
	(gr_line
		(start 100.46716 -296.463974)
		(end 100.46716 -296.435526)
		(stroke
			(width 0.05715)
			(type default)
		)
		(layer "In11.Cu")
	)
	(gr_line
		(start 100.46716 -296.435526)
		(end 100.42144 -296.389806)
		(stroke
			(width 0.05715)
			(type default)
		)
		(layer "In11.Cu")
	)
	(gr_line
		(start 100.588064 -225.789998)
		(end 100.588318 -225.791014)
		(stroke
			(width 0.05715)
			(type default)
		)
		(layer "In11.Cu")
	)
	(gr_arc
		(start 100.638102 -229.55123)
		(mid 100.644798 -229.556105)
		(end 100.651564 -229.560882)
		(stroke
			(width 0.05715)
			(type default)
		)
		(layer "In11.Cu")
	)
	(gr_arc
		(start 100.64242 -226.314508)
		(mid 100.646976 -226.317706)
		(end 100.651564 -226.320858)
		(stroke
			(width 0.05715)
			(type default)
		)
		(layer "In11.Cu")
	)
	(gr_line
		(start 100.651564 -229.560882)
		(end 100.654358 -229.562406)
		(stroke
			(width 0.05715)
			(type default)
		)
		(layer "In11.Cu")
	)
	(gr_line
		(start 100.651564 -226.320858)
		(end 100.653088 -226.321874)
		(stroke
			(width 0.05715)
			(type default)
		)
		(layer "In11.Cu")
	)
	(gr_line
		(start 100.653088 -226.321874)
		(end 100.65766 -226.324414)
		(stroke
			(width 0.05715)
			(type default)
		)
		(layer "In11.Cu")
	)
	(gr_arc
		(start 100.654358 -230.246428)
		(mid 100.645925 -230.252068)
		(end 100.637594 -230.257858)
		(stroke
			(width 0.05715)
			(type default)
		)
		(layer "In11.Cu")
	)
	(gr_line
		(start 100.655882 -230.245412)
		(end 100.654358 -230.246428)
		(stroke
			(width 0.05715)
			(type default)
		)
		(layer "In11.Cu")
	)
	(gr_line
		(start 100.656898 -230.244904)
		(end 100.655882 -230.245412)
		(stroke
			(width 0.05715)
			(type default)
		)
		(layer "In11.Cu")
	)
	(gr_arc
		(start 100.676456 -242.535202)
		(mid 100.678866 -242.536605)
		(end 100.681282 -242.537996)
		(stroke
			(width 0.05715)
			(type default)
		)
		(layer "In11.Cu")
	)
	(gr_arc
		(start 100.676456 -240.91519)
		(mid 100.678866 -240.916593)
		(end 100.681282 -240.917984)
		(stroke
			(width 0.05715)
			(type default)
		)
		(layer "In11.Cu")
	)
	(gr_arc
		(start 100.676456 -239.295178)
		(mid 100.678866 -239.296581)
		(end 100.681282 -239.297972)
		(stroke
			(width 0.05715)
			(type default)
		)
		(layer "In11.Cu")
	)
	(gr_arc
		(start 100.676456 -237.675166)
		(mid 100.678866 -237.676569)
		(end 100.681282 -237.67796)
		(stroke
			(width 0.05715)
			(type default)
		)
		(layer "In11.Cu")
	)
	(gr_arc
		(start 100.676456 -236.055154)
		(mid 100.678232 -236.056301)
		(end 100.680012 -236.05744)
		(stroke
			(width 0.05715)
			(type default)
		)
		(layer "In11.Cu")
	)
	(gr_line
		(start 100.68687 -230.227378)
		(end 100.685346 -230.228394)
		(stroke
			(width 0.05715)
			(type default)
		)
		(layer "In11.Cu")
	)
	(gr_line
		(start 100.687632 -242.541806)
		(end 100.687886 -242.541806)
		(stroke
			(width 0.05715)
			(type default)
		)
		(layer "In11.Cu")
	)
	(gr_line
		(start 100.687632 -240.921794)
		(end 100.687886 -240.921794)
		(stroke
			(width 0.05715)
			(type default)
		)
		(layer "In11.Cu")
	)
	(gr_line
		(start 100.687632 -239.301782)
		(end 100.687886 -239.301782)
		(stroke
			(width 0.05715)
			(type default)
		)
		(layer "In11.Cu")
	)
	(gr_line
		(start 100.687632 -237.68177)
		(end 100.687886 -237.68177)
		(stroke
			(width 0.05715)
			(type default)
		)
		(layer "In11.Cu")
	)
	(gr_line
		(start 100.687632 -236.061758)
		(end 100.687886 -236.061758)
		(stroke
			(width 0.05715)
			(type default)
		)
		(layer "In11.Cu")
	)
	(gr_line
		(start 100.687886 -241.566954)
		(end 100.687632 -241.567208)
		(stroke
			(width 0.05715)
			(type default)
		)
		(layer "In11.Cu")
	)
	(gr_line
		(start 100.687886 -239.946942)
		(end 100.687632 -239.947196)
		(stroke
			(width 0.05715)
			(type default)
		)
		(layer "In11.Cu")
	)
	(gr_line
		(start 100.687886 -238.32693)
		(end 100.687632 -238.327184)
		(stroke
			(width 0.05715)
			(type default)
		)
		(layer "In11.Cu")
	)
	(gr_line
		(start 100.687886 -236.706918)
		(end 100.687632 -236.707172)
		(stroke
			(width 0.05715)
			(type default)
		)
		(layer "In11.Cu")
	)
	(gr_line
		(start 100.687886 -235.086906)
		(end 100.687632 -235.08716)
		(stroke
			(width 0.05715)
			(type default)
		)
		(layer "In11.Cu")
	)
	(gr_line
		(start 100.687886 -232.821734)
		(end 100.688394 -232.821988)
		(stroke
			(width 0.05715)
			(type default)
		)
		(layer "In11.Cu")
	)
	(gr_line
		(start 100.687886 -230.22687)
		(end 100.68687 -230.227378)
		(stroke
			(width 0.05715)
			(type default)
		)
		(layer "In11.Cu")
	)
	(gr_line
		(start 100.688394 -230.226616)
		(end 100.687886 -230.22687)
		(stroke
			(width 0.05715)
			(type default)
		)
		(layer "In11.Cu")
	)
	(gr_line
		(start 100.688648 -234.442254)
		(end 100.689156 -234.442508)
		(stroke
			(width 0.05715)
			(type default)
		)
		(layer "In11.Cu")
	)
	(gr_line
		(start 100.688648 -228.606604)
		(end 100.687886 -228.607112)
		(stroke
			(width 0.05715)
			(type default)
		)
		(layer "In11.Cu")
	)
	(gr_line
		(start 100.690172 -228.605842)
		(end 100.688648 -228.606604)
		(stroke
			(width 0.05715)
			(type default)
		)
		(layer "In11.Cu")
	)
	(gr_line
		(start 100.691442 -236.06379)
		(end 100.692204 -236.064298)
		(stroke
			(width 0.05715)
			(type default)
		)
		(layer "In11.Cu")
	)
	(gr_line
		(start 100.692204 -236.064298)
		(end 100.693728 -236.065314)
		(stroke
			(width 0.05715)
			(type default)
		)
		(layer "In11.Cu")
	)
	(gr_line
		(start 100.698046 -228.60127)
		(end 100.697284 -228.601778)
		(stroke
			(width 0.05715)
			(type default)
		)
		(layer "In11.Cu")
	)
	(gr_line
		(start 100.781866 -230.39324)
		(end 100.780342 -230.394002)
		(stroke
			(width 0.05715)
			(type default)
		)
		(layer "In11.Cu")
	)
	(gr_line
		(start 100.783136 -230.392478)
		(end 100.781866 -230.39324)
		(stroke
			(width 0.05715)
			(type default)
		)
		(layer "In11.Cu")
	)
	(gr_line
		(start 100.783136 -228.772466)
		(end 100.782628 -228.77272)
		(stroke
			(width 0.05715)
			(type default)
		)
		(layer "In11.Cu")
	)
	(gr_line
		(start 100.78339 -242.376706)
		(end 100.78847 -242.3795)
		(stroke
			(width 0.05715)
			(type default)
		)
		(layer "In11.Cu")
	)
	(gr_line
		(start 100.78339 -240.756694)
		(end 100.78847 -240.759488)
		(stroke
			(width 0.05715)
			(type default)
		)
		(layer "In11.Cu")
	)
	(gr_line
		(start 100.78339 -239.136682)
		(end 100.78847 -239.139476)
		(stroke
			(width 0.05715)
			(type default)
		)
		(layer "In11.Cu")
	)
	(gr_line
		(start 100.78339 -237.51667)
		(end 100.78847 -237.519464)
		(stroke
			(width 0.05715)
			(type default)
		)
		(layer "In11.Cu")
	)
	(gr_line
		(start 100.78339 -235.896658)
		(end 100.786946 -235.89869)
		(stroke
			(width 0.05715)
			(type default)
		)
		(layer "In11.Cu")
	)
	(gr_line
		(start 100.783898 -228.771958)
		(end 100.783136 -228.772466)
		(stroke
			(width 0.05715)
			(type default)
		)
		(layer "In11.Cu")
	)
	(gr_line
		(start 100.784914 -228.77145)
		(end 100.783898 -228.771958)
		(stroke
			(width 0.05715)
			(type default)
		)
		(layer "In11.Cu")
	)
	(gr_line
		(start 100.786438 -228.770434)
		(end 100.784914 -228.77145)
		(stroke
			(width 0.05715)
			(type default)
		)
		(layer "In11.Cu")
	)
	(gr_line
		(start 100.786946 -235.89869)
		(end 100.78847 -235.899452)
		(stroke
			(width 0.05715)
			(type default)
		)
		(layer "In11.Cu")
	)
	(gr_line
		(start 100.787454 -228.769926)
		(end 100.786438 -228.770434)
		(stroke
			(width 0.05715)
			(type default)
		)
		(layer "In11.Cu")
	)
	(gr_line
		(start 100.78847 -242.3795)
		(end 100.789232 -242.380008)
		(stroke
			(width 0.05715)
			(type default)
		)
		(layer "In11.Cu")
	)
	(gr_line
		(start 100.78847 -240.759488)
		(end 100.789232 -240.759996)
		(stroke
			(width 0.05715)
			(type default)
		)
		(layer "In11.Cu")
	)
	(gr_line
		(start 100.78847 -239.139476)
		(end 100.789232 -239.139984)
		(stroke
			(width 0.05715)
			(type default)
		)
		(layer "In11.Cu")
	)
	(gr_line
		(start 100.78847 -237.519464)
		(end 100.789232 -237.519972)
		(stroke
			(width 0.05715)
			(type default)
		)
		(layer "In11.Cu")
	)
	(gr_line
		(start 100.789232 -242.380008)
		(end 100.790248 -242.380516)
		(stroke
			(width 0.05715)
			(type default)
		)
		(layer "In11.Cu")
	)
	(gr_line
		(start 100.789232 -240.759996)
		(end 100.790248 -240.760504)
		(stroke
			(width 0.05715)
			(type default)
		)
		(layer "In11.Cu")
	)
	(gr_line
		(start 100.789232 -239.139984)
		(end 100.790248 -239.140492)
		(stroke
			(width 0.05715)
			(type default)
		)
		(layer "In11.Cu")
	)
	(gr_line
		(start 100.789232 -237.519972)
		(end 100.790248 -237.52048)
		(stroke
			(width 0.05715)
			(type default)
		)
		(layer "In11.Cu")
	)
	(gr_line
		(start 100.792534 -228.766878)
		(end 100.787454 -228.769926)
		(stroke
			(width 0.05715)
			(type default)
		)
		(layer "In11.Cu")
	)
	(gr_line
		(start 100.798884 -247.724422)
		(end 100.500942 -247.724422)
		(stroke
			(width 0.05715)
			(type default)
		)
		(layer "In11.Cu")
	)
	(gr_line
		(start 100.798884 -246.10441)
		(end 100.500942 -246.10441)
		(stroke
			(width 0.05715)
			(type default)
		)
		(layer "In11.Cu")
	)
	(gr_line
		(start 100.798884 -244.484398)
		(end 100.500942 -244.484398)
		(stroke
			(width 0.05715)
			(type default)
		)
		(layer "In11.Cu")
	)
	(gr_line
		(start 100.799138 -221.083378)
		(end 100.844858 -221.129098)
		(stroke
			(width 0.05715)
			(type default)
		)
		(layer "In11.Cu")
	)
	(gr_line
		(start 100.799138 -221.05493)
		(end 100.799138 -221.083378)
		(stroke
			(width 0.05715)
			(type default)
		)
		(layer "In11.Cu")
	)
	(gr_line
		(start 100.799138 -215.43899)
		(end 100.799138 -215.51646)
		(stroke
			(width 0.07112)
			(type default)
		)
		(layer "In11.Cu")
	)
	(gr_line
		(start 100.80498 -241.719608)
		(end 100.804726 -241.719608)
		(stroke
			(width 0.05715)
			(type default)
		)
		(layer "In11.Cu")
	)
	(gr_line
		(start 100.80498 -240.099596)
		(end 100.804726 -240.099596)
		(stroke
			(width 0.05715)
			(type default)
		)
		(layer "In11.Cu")
	)
	(gr_line
		(start 100.80498 -238.479584)
		(end 100.804726 -238.479584)
		(stroke
			(width 0.05715)
			(type default)
		)
		(layer "In11.Cu")
	)
	(gr_line
		(start 100.80498 -236.859572)
		(end 100.804726 -236.859572)
		(stroke
			(width 0.05715)
			(type default)
		)
		(layer "In11.Cu")
	)
	(gr_line
		(start 100.80498 -235.23956)
		(end 100.804726 -235.23956)
		(stroke
			(width 0.05715)
			(type default)
		)
		(layer "In11.Cu")
	)
	(gr_line
		(start 100.814124 -235.914438)
		(end 100.81514 -235.914946)
		(stroke
			(width 0.05715)
			(type default)
		)
		(layer "In11.Cu")
	)
	(gr_line
		(start 100.814378 -242.39474)
		(end 100.822252 -242.399312)
		(stroke
			(width 0.05715)
			(type default)
		)
		(layer "In11.Cu")
	)
	(gr_line
		(start 100.814378 -240.774728)
		(end 100.822252 -240.7793)
		(stroke
			(width 0.05715)
			(type default)
		)
		(layer "In11.Cu")
	)
	(gr_line
		(start 100.814378 -239.154716)
		(end 100.822252 -239.159288)
		(stroke
			(width 0.05715)
			(type default)
		)
		(layer "In11.Cu")
	)
	(gr_line
		(start 100.814378 -237.534704)
		(end 100.822252 -237.539276)
		(stroke
			(width 0.05715)
			(type default)
		)
		(layer "In11.Cu")
	)
	(gr_line
		(start 100.814632 -245.635018)
		(end 100.822252 -245.639336)
		(stroke
			(width 0.05715)
			(type default)
		)
		(layer "In11.Cu")
	)
	(gr_line
		(start 100.814886 -241.713766)
		(end 100.813362 -241.714782)
		(stroke
			(width 0.05715)
			(type default)
		)
		(layer "In11.Cu")
	)
	(gr_line
		(start 100.814886 -240.093754)
		(end 100.813362 -240.09477)
		(stroke
			(width 0.05715)
			(type default)
		)
		(layer "In11.Cu")
	)
	(gr_line
		(start 100.814886 -238.473742)
		(end 100.813362 -238.474758)
		(stroke
			(width 0.05715)
			(type default)
		)
		(layer "In11.Cu")
	)
	(gr_line
		(start 100.814886 -236.85373)
		(end 100.813362 -236.854746)
		(stroke
			(width 0.05715)
			(type default)
		)
		(layer "In11.Cu")
	)
	(gr_line
		(start 100.814886 -235.233718)
		(end 100.813362 -235.234734)
		(stroke
			(width 0.05715)
			(type default)
		)
		(layer "In11.Cu")
	)
	(gr_line
		(start 100.814886 -234.29468)
		(end 100.819458 -234.29722)
		(stroke
			(width 0.05715)
			(type default)
		)
		(layer "In11.Cu")
	)
	(gr_line
		(start 100.81514 -235.914946)
		(end 100.815902 -235.915454)
		(stroke
			(width 0.05715)
			(type default)
		)
		(layer "In11.Cu")
	)
	(gr_line
		(start 100.815902 -235.915454)
		(end 100.822252 -235.919264)
		(stroke
			(width 0.05715)
			(type default)
		)
		(layer "In11.Cu")
	)
	(gr_line
		(start 100.819458 -234.29722)
		(end 100.822252 -234.299252)
		(stroke
			(width 0.05715)
			(type default)
		)
		(layer "In11.Cu")
	)
	(gr_line
		(start 100.82022 -227.131118)
		(end 100.814886 -227.134166)
		(stroke
			(width 0.05715)
			(type default)
		)
		(layer "In11.Cu")
	)
	(gr_arc
		(start 100.822252 -245.639336)
		(mid 100.822633 -245.63959)
		(end 100.823014 -245.639844)
		(stroke
			(width 0.05715)
			(type default)
		)
		(layer "In11.Cu")
	)
	(gr_arc
		(start 100.822252 -242.399312)
		(mid 100.822633 -242.399566)
		(end 100.823014 -242.39982)
		(stroke
			(width 0.05715)
			(type default)
		)
		(layer "In11.Cu")
	)
	(gr_arc
		(start 100.822252 -240.7793)
		(mid 100.822633 -240.779554)
		(end 100.823014 -240.779808)
		(stroke
			(width 0.05715)
			(type default)
		)
		(layer "In11.Cu")
	)
	(gr_arc
		(start 100.822252 -239.159288)
		(mid 100.822633 -239.159542)
		(end 100.823014 -239.159796)
		(stroke
			(width 0.05715)
			(type default)
		)
		(layer "In11.Cu")
	)
	(gr_arc
		(start 100.822252 -237.539276)
		(mid 100.822633 -237.53953)
		(end 100.823014 -237.539784)
		(stroke
			(width 0.05715)
			(type default)
		)
		(layer "In11.Cu")
	)
	(gr_arc
		(start 100.822252 -235.919264)
		(mid 100.822633 -235.919518)
		(end 100.823014 -235.919772)
		(stroke
			(width 0.05715)
			(type default)
		)
		(layer "In11.Cu")
	)
	(gr_arc
		(start 100.822252 -234.299252)
		(mid 100.822633 -234.299506)
		(end 100.823014 -234.29976)
		(stroke
			(width 0.05715)
			(type default)
		)
		(layer "In11.Cu")
	)
	(gr_line
		(start 100.823014 -227.129086)
		(end 100.82022 -227.131118)
		(stroke
			(width 0.05715)
			(type default)
		)
		(layer "In11.Cu")
	)
	(gr_arc
		(start 100.823014 -227.129086)
		(mid 100.826963 -227.126309)
		(end 100.830888 -227.123498)
		(stroke
			(width 0.05715)
			(type default)
		)
		(layer "In11.Cu")
	)
	(gr_arc
		(start 100.830888 -242.405408)
		(mid 100.826963 -242.402597)
		(end 100.823014 -242.39982)
		(stroke
			(width 0.05715)
			(type default)
		)
		(layer "In11.Cu")
	)
	(gr_arc
		(start 100.830888 -240.785396)
		(mid 100.826963 -240.782585)
		(end 100.823014 -240.779808)
		(stroke
			(width 0.05715)
			(type default)
		)
		(layer "In11.Cu")
	)
	(gr_arc
		(start 100.830888 -239.165384)
		(mid 100.826963 -239.162573)
		(end 100.823014 -239.159796)
		(stroke
			(width 0.05715)
			(type default)
		)
		(layer "In11.Cu")
	)
	(gr_arc
		(start 100.830888 -237.545372)
		(mid 100.826963 -237.542561)
		(end 100.823014 -237.539784)
		(stroke
			(width 0.05715)
			(type default)
		)
		(layer "In11.Cu")
	)
	(gr_arc
		(start 100.830888 -235.92536)
		(mid 100.826963 -235.922549)
		(end 100.823014 -235.919772)
		(stroke
			(width 0.05715)
			(type default)
		)
		(layer "In11.Cu")
	)
	(gr_arc
		(start 100.830888 -234.305348)
		(mid 100.826963 -234.302537)
		(end 100.823014 -234.29976)
		(stroke
			(width 0.05715)
			(type default)
		)
		(layer "In11.Cu")
	)
	(gr_arc
		(start 100.831142 -245.645432)
		(mid 100.82709 -245.64262)
		(end 100.823014 -245.639844)
		(stroke
			(width 0.05715)
			(type default)
		)
		(layer "In11.Cu")
	)
	(gr_arc
		(start 100.833682 -229.447344)
		(mid 100.830516 -229.445046)
		(end 100.827332 -229.442772)
		(stroke
			(width 0.05715)
			(type default)
		)
		(layer "In11.Cu")
	)
	(gr_line
		(start 100.838254 -215.372696)
		(end 100.799138 -215.43899)
		(stroke
			(width 0.07112)
			(type default)
		)
		(layer "In11.Cu")
	)
	(gr_line
		(start 100.838508 -215.372696)
		(end 100.838254 -215.372696)
		(stroke
			(width 0.07112)
			(type default)
		)
		(layer "In11.Cu")
	)
	(gr_line
		(start 100.868226 -246.035068)
		(end 100.798884 -246.10441)
		(stroke
			(width 0.05715)
			(type default)
		)
		(layer "In11.Cu")
	)
	(gr_line
		(start 100.868226 -244.415056)
		(end 100.798884 -244.484398)
		(stroke
			(width 0.05715)
			(type default)
		)
		(layer "In11.Cu")
	)
	(gr_line
		(start 100.881688 -247.641618)
		(end 100.798884 -247.724422)
		(stroke
			(width 0.05715)
			(type default)
		)
		(layer "In11.Cu")
	)
	(gr_arc
		(start 100.885498 -247.618758)
		(mid 100.883476 -247.630168)
		(end 100.881688 -247.641618)
		(stroke
			(width 0.05715)
			(type default)
		)
		(layer "In11.Cu")
	)
	(gr_arc
		(start 100.941124 -293.985188)
		(mid 100.945049 -293.987999)
		(end 100.948998 -293.990776)
		(stroke
			(width 0.05715)
			(type default)
		)
		(layer "In11.Cu")
	)
	(gr_arc
		(start 100.941124 -292.365176)
		(mid 100.945049 -292.367987)
		(end 100.948998 -292.370764)
		(stroke
			(width 0.05715)
			(type default)
		)
		(layer "In11.Cu")
	)
	(gr_arc
		(start 100.941124 -290.745164)
		(mid 100.945049 -290.747975)
		(end 100.948998 -290.750752)
		(stroke
			(width 0.05715)
			(type default)
		)
		(layer "In11.Cu")
	)
	(gr_arc
		(start 100.941124 -289.125152)
		(mid 100.945049 -289.127963)
		(end 100.948998 -289.13074)
		(stroke
			(width 0.05715)
			(type default)
		)
		(layer "In11.Cu")
	)
	(gr_arc
		(start 100.941124 -287.50514)
		(mid 100.94631 -287.508853)
		(end 100.951538 -287.512506)
		(stroke
			(width 0.05715)
			(type default)
		)
		(layer "In11.Cu")
	)
	(gr_arc
		(start 100.941124 -285.885382)
		(mid 100.945049 -285.888193)
		(end 100.948998 -285.89097)
		(stroke
			(width 0.05715)
			(type default)
		)
		(layer "In11.Cu")
	)
	(gr_arc
		(start 100.94468 -286.584644)
		(mid 100.941498 -286.58692)
		(end 100.93833 -286.589216)
		(stroke
			(width 0.05715)
			(type default)
		)
		(layer "In11.Cu")
	)
	(gr_arc
		(start 100.948236 -294.682164)
		(mid 100.944671 -294.684691)
		(end 100.941124 -294.687244)
		(stroke
			(width 0.05715)
			(type default)
		)
		(layer "In11.Cu")
	)
	(gr_line
		(start 100.948236 -294.682164)
		(end 100.94849 -294.68191)
		(stroke
			(width 0.05715)
			(type default)
		)
		(layer "In11.Cu")
	)
	(gr_arc
		(start 100.94849 -294.68191)
		(mid 100.949125 -294.681529)
		(end 100.94976 -294.681148)
		(stroke
			(width 0.05715)
			(type default)
		)
		(layer "In11.Cu")
	)
	(gr_arc
		(start 100.948998 -286.581596)
		(mid 100.947217 -286.582862)
		(end 100.945442 -286.584136)
		(stroke
			(width 0.05715)
			(type default)
		)
		(layer "In11.Cu")
	)
	(gr_line
		(start 100.948998 -286.581596)
		(end 100.955094 -286.57804)
		(stroke
			(width 0.05715)
			(type default)
		)
		(layer "In11.Cu")
	)
	(gr_arc
		(start 100.948998 -283.341826)
		(mid 100.945049 -283.344603)
		(end 100.941124 -283.347414)
		(stroke
			(width 0.05715)
			(type default)
		)
		(layer "In11.Cu")
	)
	(gr_line
		(start 100.948998 -283.341826)
		(end 100.951792 -283.339794)
		(stroke
			(width 0.05715)
			(type default)
		)
		(layer "In11.Cu")
	)
	(gr_line
		(start 100.94976 -294.681148)
		(end 100.95738 -294.67683)
		(stroke
			(width 0.05715)
			(type default)
		)
		(layer "In11.Cu")
	)
	(gr_arc
		(start 100.94976 -285.891478)
		(mid 100.949379 -285.891224)
		(end 100.948998 -285.89097)
		(stroke
			(width 0.05715)
			(type default)
		)
		(layer "In11.Cu")
	)
	(gr_line
		(start 100.951792 -283.339794)
		(end 100.957126 -283.336746)
		(stroke
			(width 0.05715)
			(type default)
		)
		(layer "In11.Cu")
	)
	(gr_line
		(start 100.955094 -286.57804)
		(end 100.955856 -286.57804)
		(stroke
			(width 0.05715)
			(type default)
		)
		(layer "In11.Cu")
	)
	(gr_line
		(start 100.955856 -293.99484)
		(end 100.948998 -293.990776)
		(stroke
			(width 0.05715)
			(type default)
		)
		(layer "In11.Cu")
	)
	(gr_line
		(start 100.955856 -292.374828)
		(end 100.948998 -292.370764)
		(stroke
			(width 0.05715)
			(type default)
		)
		(layer "In11.Cu")
	)
	(gr_line
		(start 100.955856 -290.754816)
		(end 100.948998 -290.750752)
		(stroke
			(width 0.05715)
			(type default)
		)
		(layer "In11.Cu")
	)
	(gr_line
		(start 100.955856 -289.134804)
		(end 100.948998 -289.13074)
		(stroke
			(width 0.05715)
			(type default)
		)
		(layer "In11.Cu")
	)
	(gr_line
		(start 100.955856 -287.515046)
		(end 100.951538 -287.512506)
		(stroke
			(width 0.05715)
			(type default)
		)
		(layer "In11.Cu")
	)
	(gr_line
		(start 100.956618 -293.995348)
		(end 100.955856 -293.99484)
		(stroke
			(width 0.05715)
			(type default)
		)
		(layer "In11.Cu")
	)
	(gr_line
		(start 100.956618 -292.375336)
		(end 100.955856 -292.374828)
		(stroke
			(width 0.05715)
			(type default)
		)
		(layer "In11.Cu")
	)
	(gr_line
		(start 100.956618 -290.755324)
		(end 100.955856 -290.754816)
		(stroke
			(width 0.05715)
			(type default)
		)
		(layer "In11.Cu")
	)
	(gr_line
		(start 100.956618 -289.135312)
		(end 100.955856 -289.134804)
		(stroke
			(width 0.05715)
			(type default)
		)
		(layer "In11.Cu")
	)
	(gr_line
		(start 100.956618 -287.515554)
		(end 100.955856 -287.515046)
		(stroke
			(width 0.05715)
			(type default)
		)
		(layer "In11.Cu")
	)
	(gr_line
		(start 100.957126 -287.515808)
		(end 100.956618 -287.515554)
		(stroke
			(width 0.05715)
			(type default)
		)
		(layer "In11.Cu")
	)
	(gr_line
		(start 100.95738 -293.995856)
		(end 100.956618 -293.995348)
		(stroke
			(width 0.05715)
			(type default)
		)
		(layer "In11.Cu")
	)
	(gr_line
		(start 100.95738 -292.375844)
		(end 100.956618 -292.375336)
		(stroke
			(width 0.05715)
			(type default)
		)
		(layer "In11.Cu")
	)
	(gr_line
		(start 100.95738 -290.755832)
		(end 100.956618 -290.755324)
		(stroke
			(width 0.05715)
			(type default)
		)
		(layer "In11.Cu")
	)
	(gr_line
		(start 100.95738 -289.13582)
		(end 100.956618 -289.135312)
		(stroke
			(width 0.05715)
			(type default)
		)
		(layer "In11.Cu")
	)
	(gr_line
		(start 100.95738 -285.895796)
		(end 100.94976 -285.891478)
		(stroke
			(width 0.05715)
			(type default)
		)
		(layer "In11.Cu")
	)
	(gr_line
		(start 100.98278 -278.463502)
		(end 100.985066 -278.462232)
		(stroke
			(width 0.05715)
			(type default)
		)
		(layer "In11.Cu")
	)
	(gr_line
		(start 100.983288 -287.531048)
		(end 100.982526 -287.53054)
		(stroke
			(width 0.05715)
			(type default)
		)
		(layer "In11.Cu")
	)
	(gr_line
		(start 100.983542 -285.911036)
		(end 100.98278 -285.910528)
		(stroke
			(width 0.05715)
			(type default)
		)
		(layer "In11.Cu")
	)
	(gr_line
		(start 100.98405 -285.91129)
		(end 100.983542 -285.911036)
		(stroke
			(width 0.05715)
			(type default)
		)
		(layer "In11.Cu")
	)
	(gr_line
		(start 100.986844 -287.53308)
		(end 100.983288 -287.531048)
		(stroke
			(width 0.05715)
			(type default)
		)
		(layer "In11.Cu")
	)
	(gr_line
		(start 100.987098 -293.039292)
		(end 100.988114 -293.038784)
		(stroke
			(width 0.05715)
			(type default)
		)
		(layer "In11.Cu")
	)
	(gr_line
		(start 100.987098 -291.41928)
		(end 100.988114 -291.418772)
		(stroke
			(width 0.05715)
			(type default)
		)
		(layer "In11.Cu")
	)
	(gr_line
		(start 100.987098 -289.799268)
		(end 100.988114 -289.79876)
		(stroke
			(width 0.05715)
			(type default)
		)
		(layer "In11.Cu")
	)
	(gr_line
		(start 100.988368 -286.55899)
		(end 100.98913 -286.558482)
		(stroke
			(width 0.05715)
			(type default)
		)
		(layer "In11.Cu")
	)
	(gr_line
		(start 100.988876 -294.014144)
		(end 100.988114 -294.013636)
		(stroke
			(width 0.05715)
			(type default)
		)
		(layer "In11.Cu")
	)
	(gr_line
		(start 100.989384 -285.914338)
		(end 100.988622 -285.91383)
		(stroke
			(width 0.05715)
			(type default)
		)
		(layer "In11.Cu")
	)
	(gr_line
		(start 100.989638 -287.534604)
		(end 100.988622 -287.534096)
		(stroke
			(width 0.05715)
			(type default)
		)
		(layer "In11.Cu")
	)
	(gr_line
		(start 100.99167 -294.015668)
		(end 100.988876 -294.014144)
		(stroke
			(width 0.05715)
			(type default)
		)
		(layer "In11.Cu")
	)
	(gr_arc
		(start 101.06025 -246.021606)
		(mid 101.058457 -246.010284)
		(end 101.05644 -245.999)
		(stroke
			(width 0.05715)
			(type default)
		)
		(layer "In11.Cu")
	)
	(gr_line
		(start 101.06025 -246.021606)
		(end 101.143054 -246.10441)
		(stroke
			(width 0.05715)
			(type default)
		)
		(layer "In11.Cu")
	)
	(gr_arc
		(start 101.06025 -244.401594)
		(mid 101.058457 -244.390272)
		(end 101.05644 -244.378988)
		(stroke
			(width 0.05715)
			(type default)
		)
		(layer "In11.Cu")
	)
	(gr_line
		(start 101.06025 -244.401594)
		(end 101.143054 -244.484398)
		(stroke
			(width 0.05715)
			(type default)
		)
		(layer "In11.Cu")
	)
	(gr_line
		(start 101.073712 -247.65508)
		(end 101.143054 -247.724422)
		(stroke
			(width 0.05715)
			(type default)
		)
		(layer "In11.Cu")
	)
	(gr_line
		(start 101.0793 -286.72663)
		(end 101.082094 -286.724852)
		(stroke
			(width 0.05715)
			(type default)
		)
		(layer "In11.Cu")
	)
	(gr_line
		(start 101.081078 -221.083378)
		(end 101.035358 -221.129098)
		(stroke
			(width 0.05715)
			(type default)
		)
		(layer "In11.Cu")
	)
	(gr_line
		(start 101.081078 -221.05493)
		(end 101.081078 -221.083378)
		(stroke
			(width 0.05715)
			(type default)
		)
		(layer "In11.Cu")
	)
	(gr_line
		(start 101.081332 -215.516206)
		(end 101.081078 -215.51646)
		(stroke
			(width 0.07112)
			(type default)
		)
		(layer "In11.Cu")
	)
	(gr_line
		(start 101.082094 -293.2049)
		(end 101.083364 -293.204138)
		(stroke
			(width 0.05715)
			(type default)
		)
		(layer "In11.Cu")
	)
	(gr_line
		(start 101.082094 -291.584888)
		(end 101.083364 -291.584126)
		(stroke
			(width 0.05715)
			(type default)
		)
		(layer "In11.Cu")
	)
	(gr_line
		(start 101.082094 -289.964876)
		(end 101.083364 -289.964114)
		(stroke
			(width 0.05715)
			(type default)
		)
		(layer "In11.Cu")
	)
	(gr_line
		(start 101.083364 -293.204138)
		(end 101.084126 -293.20363)
		(stroke
			(width 0.05715)
			(type default)
		)
		(layer "In11.Cu")
	)
	(gr_line
		(start 101.083364 -291.584126)
		(end 101.084126 -291.583618)
		(stroke
			(width 0.05715)
			(type default)
		)
		(layer "In11.Cu")
	)
	(gr_line
		(start 101.083364 -289.964114)
		(end 101.084126 -289.963606)
		(stroke
			(width 0.05715)
			(type default)
		)
		(layer "In11.Cu")
	)
	(gr_line
		(start 101.083872 -287.368996)
		(end 101.084126 -287.368742)
		(stroke
			(width 0.05715)
			(type default)
		)
		(layer "In11.Cu")
	)
	(gr_arc
		(start 101.088444 -277.001224)
		(mid 101.088063 -277.001478)
		(end 101.087682 -277.001732)
		(stroke
			(width 0.05715)
			(type default)
		)
		(layer "In11.Cu")
	)
	(gr_line
		(start 101.099112 -278.13635)
		(end 100.80117 -278.13635)
		(stroke
			(width 0.05715)
			(type default)
		)
		(layer "In11.Cu")
	)
	(gr_line
		(start 101.099112 -276.516338)
		(end 100.80117 -276.516338)
		(stroke
			(width 0.05715)
			(type default)
		)
		(layer "In11.Cu")
	)
	(gr_line
		(start 101.099112 -274.896326)
		(end 100.80117 -274.896326)
		(stroke
			(width 0.05715)
			(type default)
		)
		(layer "In11.Cu")
	)
	(gr_line
		(start 101.106224 -294.810942)
		(end 101.110796 -294.808402)
		(stroke
			(width 0.05715)
			(type default)
		)
		(layer "In11.Cu")
	)
	(gr_arc
		(start 101.11105 -225.503486)
		(mid 101.114975 -225.506297)
		(end 101.118924 -225.509074)
		(stroke
			(width 0.05715)
			(type default)
		)
		(layer "In11.Cu")
	)
	(gr_arc
		(start 101.111812 -222.26397)
		(mid 101.115738 -222.26678)
		(end 101.119686 -222.269558)
		(stroke
			(width 0.05715)
			(type default)
		)
		(layer "In11.Cu")
	)
	(gr_line
		(start 101.115114 -281.84602)
		(end 101.118924 -281.843734)
		(stroke
			(width 0.05715)
			(type default)
		)
		(layer "In11.Cu")
	)
	(gr_line
		(start 101.118924 -281.843734)
		(end 101.120448 -281.842718)
		(stroke
			(width 0.05715)
			(type default)
		)
		(layer "In11.Cu")
	)
	(gr_line
		(start 101.118924 -225.509074)
		(end 101.125782 -225.513138)
		(stroke
			(width 0.05715)
			(type default)
		)
		(layer "In11.Cu")
	)
	(gr_line
		(start 101.119686 -222.269558)
		(end 101.120702 -222.27032)
		(stroke
			(width 0.05715)
			(type default)
		)
		(layer "In11.Cu")
	)
	(gr_arc
		(start 101.120448 -281.842718)
		(mid 101.127599 -281.837821)
		(end 101.134672 -281.832812)
		(stroke
			(width 0.05715)
			(type default)
		)
		(layer "In11.Cu")
	)
	(gr_line
		(start 101.120702 -222.27032)
		(end 101.121718 -222.270828)
		(stroke
			(width 0.05715)
			(type default)
		)
		(layer "In11.Cu")
	)
	(gr_line
		(start 101.121718 -222.270828)
		(end 101.127052 -222.273876)
		(stroke
			(width 0.05715)
			(type default)
		)
		(layer "In11.Cu")
	)
	(gr_line
		(start 101.121972 -294.801798)
		(end 101.137974 -294.790368)
		(stroke
			(width 0.05715)
			(type default)
		)
		(layer "In11.Cu")
	)
	(gr_line
		(start 101.125782 -225.513138)
		(end 101.126544 -225.513646)
		(stroke
			(width 0.05715)
			(type default)
		)
		(layer "In11.Cu")
	)
	(gr_line
		(start 101.126544 -225.513646)
		(end 101.127052 -225.5139)
		(stroke
			(width 0.05715)
			(type default)
		)
		(layer "In11.Cu")
	)
	(gr_line
		(start 101.130354 -296.463974)
		(end 101.130354 -296.435526)
		(stroke
			(width 0.05715)
			(type default)
		)
		(layer "In11.Cu")
	)
	(gr_line
		(start 101.130354 -296.435526)
		(end 101.176074 -296.389806)
		(stroke
			(width 0.05715)
			(type default)
		)
		(layer "In11.Cu")
	)
	(gr_line
		(start 101.143054 -247.724422)
		(end 101.440996 -247.724422)
		(stroke
			(width 0.05715)
			(type default)
		)
		(layer "In11.Cu")
	)
	(gr_line
		(start 101.143054 -246.10441)
		(end 101.440996 -246.10441)
		(stroke
			(width 0.05715)
			(type default)
		)
		(layer "In11.Cu")
	)
	(gr_line
		(start 101.143054 -244.484398)
		(end 101.440996 -244.484398)
		(stroke
			(width 0.05715)
			(type default)
		)
		(layer "In11.Cu")
	)
	(gr_line
		(start 101.15169 -225.528124)
		(end 101.152706 -225.528886)
		(stroke
			(width 0.05715)
			(type default)
		)
		(layer "In11.Cu")
	)
	(gr_line
		(start 101.152706 -225.528886)
		(end 101.153722 -225.529394)
		(stroke
			(width 0.05715)
			(type default)
		)
		(layer "In11.Cu")
	)
	(gr_line
		(start 101.155246 -225.53041)
		(end 101.157024 -225.531426)
		(stroke
			(width 0.05715)
			(type default)
		)
		(layer "In11.Cu")
	)
	(gr_line
		(start 101.157024 -225.531426)
		(end 101.15804 -225.531934)
		(stroke
			(width 0.05715)
			(type default)
		)
		(layer "In11.Cu")
	)
	(gr_line
		(start 101.15804 -225.531934)
		(end 101.158802 -225.532442)
		(stroke
			(width 0.05715)
			(type default)
		)
		(layer "In11.Cu")
	)
	(gr_line
		(start 101.158802 -225.532442)
		(end 101.160072 -225.533204)
		(stroke
			(width 0.05715)
			(type default)
		)
		(layer "In11.Cu")
	)
	(gr_line
		(start 101.1682 -278.205438)
		(end 101.099112 -278.13635)
		(stroke
			(width 0.05715)
			(type default)
		)
		(layer "In11.Cu")
	)
	(gr_line
		(start 101.1682 -276.585426)
		(end 101.099112 -276.516338)
		(stroke
			(width 0.05715)
			(type default)
		)
		(layer "In11.Cu")
	)
	(gr_line
		(start 101.169216 -276.586188)
		(end 101.168962 -276.586188)
		(stroke
			(width 0.05715)
			(type default)
		)
		(layer "In11.Cu")
	)
	(gr_line
		(start 101.181916 -274.97913)
		(end 101.099112 -274.896326)
		(stroke
			(width 0.05715)
			(type default)
		)
		(layer "In11.Cu")
	)
	(gr_arc
		(start 101.181916 -274.97913)
		(mid 101.183706 -274.990452)
		(end 101.185726 -275.001736)
		(stroke
			(width 0.05715)
			(type default)
		)
		(layer "In11.Cu")
	)
	(gr_line
		(start 101.22281 -222.10903)
		(end 101.223064 -222.10903)
		(stroke
			(width 0.05715)
			(type default)
		)
		(layer "In11.Cu")
	)
	(gr_line
		(start 101.246432 -225.36277)
		(end 101.24694 -225.363024)
		(stroke
			(width 0.05715)
			(type default)
		)
		(layer "In11.Cu")
	)
	(gr_line
		(start 101.24694 -225.363024)
		(end 101.247956 -225.363532)
		(stroke
			(width 0.05715)
			(type default)
		)
		(layer "In11.Cu")
	)
	(gr_line
		(start 101.247956 -225.363532)
		(end 101.24948 -225.364548)
		(stroke
			(width 0.05715)
			(type default)
		)
		(layer "In11.Cu")
	)
	(gr_line
		(start 101.25202 -225.365818)
		(end 101.25329 -225.36658)
		(stroke
			(width 0.05715)
			(type default)
		)
		(layer "In11.Cu")
	)
	(gr_line
		(start 101.25329 -225.36658)
		(end 101.254052 -225.367088)
		(stroke
			(width 0.05715)
			(type default)
		)
		(layer "In11.Cu")
	)
	(gr_line
		(start 101.254052 -225.367088)
		(end 101.255068 -225.367596)
		(stroke
			(width 0.05715)
			(type default)
		)
		(layer "In11.Cu")
	)
	(gr_arc
		(start 101.356414 -278.241506)
		(mid 101.358431 -278.230349)
		(end 101.360224 -278.219154)
		(stroke
			(width 0.05715)
			(type default)
		)
		(layer "In11.Cu")
	)
	(gr_arc
		(start 101.356414 -276.622256)
		(mid 101.358139 -276.612744)
		(end 101.359716 -276.603206)
		(stroke
			(width 0.05715)
			(type default)
		)
		(layer "In11.Cu")
	)
	(gr_line
		(start 101.359716 -276.603206)
		(end 101.443028 -276.516338)
		(stroke
			(width 0.05715)
			(type default)
		)
		(layer "In11.Cu")
	)
	(gr_line
		(start 101.360224 -278.219154)
		(end 101.443028 -278.13635)
		(stroke
			(width 0.05715)
			(type default)
		)
		(layer "In11.Cu")
	)
	(gr_line
		(start 101.37394 -274.965414)
		(end 101.443028 -274.896326)
		(stroke
			(width 0.05715)
			(type default)
		)
		(layer "In11.Cu")
	)
	(gr_line
		(start 101.412294 -296.463974)
		(end 101.412294 -296.435526)
		(stroke
			(width 0.05715)
			(type default)
		)
		(layer "In11.Cu")
	)
	(gr_line
		(start 101.412294 -296.435526)
		(end 101.366574 -296.389806)
		(stroke
			(width 0.05715)
			(type default)
		)
		(layer "In11.Cu")
	)
	(gr_line
		(start 101.439218 -279.278588)
		(end 101.440488 -279.277318)
		(stroke
			(width 0.05715)
			(type default)
		)
		(layer "In11.Cu")
	)
	(gr_line
		(start 101.440488 -279.277318)
		(end 101.448362 -279.273254)
		(stroke
			(width 0.05715)
			(type default)
		)
		(layer "In11.Cu")
	)
	(gr_line
		(start 101.443028 -278.13635)
		(end 101.74097 -278.13635)
		(stroke
			(width 0.05715)
			(type default)
		)
		(layer "In11.Cu")
	)
	(gr_line
		(start 101.443028 -276.516338)
		(end 101.74097 -276.516338)
		(stroke
			(width 0.05715)
			(type default)
		)
		(layer "In11.Cu")
	)
	(gr_line
		(start 101.443028 -274.896326)
		(end 101.74097 -274.896326)
		(stroke
			(width 0.05715)
			(type default)
		)
		(layer "In11.Cu")
	)
	(gr_arc
		(start 101.45014 -275.380958)
		(mid 101.449505 -275.380577)
		(end 101.44887 -275.380196)
		(stroke
			(width 0.05715)
			(type default)
		)
		(layer "In11.Cu")
	)
	(gr_line
		(start 101.457252 -275.385022)
		(end 101.456998 -275.385022)
		(stroke
			(width 0.05715)
			(type default)
		)
		(layer "In11.Cu")
	)
	(gr_line
		(start 101.458268 -279.268428)
		(end 101.458776 -279.268428)
		(stroke
			(width 0.05715)
			(type default)
		)
		(layer "In11.Cu")
	)
	(gr_line
		(start 101.458776 -280.244296)
		(end 101.458014 -280.243788)
		(stroke
			(width 0.05715)
			(type default)
		)
		(layer "In11.Cu")
	)
	(gr_line
		(start 101.458776 -279.268428)
		(end 101.460046 -279.267666)
		(stroke
			(width 0.05715)
			(type default)
		)
		(layer "In11.Cu")
	)
	(gr_line
		(start 101.460808 -275.387054)
		(end 101.458268 -275.38553)
		(stroke
			(width 0.05715)
			(type default)
		)
		(layer "In11.Cu")
	)
	(gr_line
		(start 101.531166 -279.44699)
		(end 101.53904 -279.442418)
		(stroke
			(width 0.05715)
			(type default)
		)
		(layer "In11.Cu")
	)
	(gr_line
		(start 101.543866 -279.439624)
		(end 101.553264 -279.43429)
		(stroke
			(width 0.05715)
			(type default)
		)
		(layer "In11.Cu")
	)
	(gr_line
		(start 101.553264 -280.078434)
		(end 101.55047 -280.07691)
		(stroke
			(width 0.05715)
			(type default)
		)
		(layer "In11.Cu")
	)
	(gr_line
		(start 101.553264 -279.43429)
		(end 101.554026 -279.433782)
		(stroke
			(width 0.05715)
			(type default)
		)
		(layer "In11.Cu")
	)
	(gr_line
		(start 101.554026 -280.078942)
		(end 101.553264 -280.078434)
		(stroke
			(width 0.05715)
			(type default)
		)
		(layer "In11.Cu")
	)
	(gr_line
		(start 101.554026 -279.433782)
		(end 101.555042 -279.433274)
		(stroke
			(width 0.05715)
			(type default)
		)
		(layer "In11.Cu")
	)
	(gr_line
		(start 101.555042 -280.07945)
		(end 101.554026 -280.078942)
		(stroke
			(width 0.05715)
			(type default)
		)
		(layer "In11.Cu")
	)
	(gr_line
		(start 101.557074 -280.080466)
		(end 101.555042 -280.07945)
		(stroke
			(width 0.05715)
			(type default)
		)
		(layer "In11.Cu")
	)
	(gr_arc
		(start 101.57968 -229.5525)
		(mid 101.584363 -229.555825)
		(end 101.589078 -229.559104)
		(stroke
			(width 0.05715)
			(type default)
		)
		(layer "In11.Cu")
	)
	(gr_arc
		(start 101.58095 -244.13337)
		(mid 101.584875 -244.136181)
		(end 101.588824 -244.138958)
		(stroke
			(width 0.05715)
			(type default)
		)
		(layer "In11.Cu")
	)
	(gr_arc
		(start 101.58095 -240.893346)
		(mid 101.584875 -240.896157)
		(end 101.588824 -240.898934)
		(stroke
			(width 0.05715)
			(type default)
		)
		(layer "In11.Cu")
	)
	(gr_arc
		(start 101.58095 -239.273334)
		(mid 101.584875 -239.276145)
		(end 101.588824 -239.278922)
		(stroke
			(width 0.05715)
			(type default)
		)
		(layer "In11.Cu")
	)
	(gr_arc
		(start 101.58095 -236.03331)
		(mid 101.584875 -236.036121)
		(end 101.588824 -236.038898)
		(stroke
			(width 0.05715)
			(type default)
		)
		(layer "In11.Cu")
	)
	(gr_arc
		(start 101.58095 -234.413298)
		(mid 101.584875 -234.416109)
		(end 101.588824 -234.418886)
		(stroke
			(width 0.05715)
			(type default)
		)
		(layer "In11.Cu")
	)
	(gr_arc
		(start 101.58095 -232.793286)
		(mid 101.584875 -232.796097)
		(end 101.588824 -232.798874)
		(stroke
			(width 0.05715)
			(type default)
		)
		(layer "In11.Cu")
	)
	(gr_line
		(start 101.585522 -280.09723)
		(end 101.58476 -280.096722)
		(stroke
			(width 0.05715)
			(type default)
		)
		(layer "In11.Cu")
	)
	(gr_line
		(start 101.586284 -280.097738)
		(end 101.585522 -280.09723)
		(stroke
			(width 0.05715)
			(type default)
		)
		(layer "In11.Cu")
	)
	(gr_line
		(start 101.588824 -244.138958)
		(end 101.595682 -244.143022)
		(stroke
			(width 0.05715)
			(type default)
		)
		(layer "In11.Cu")
	)
	(gr_line
		(start 101.588824 -240.898934)
		(end 101.595682 -240.902998)
		(stroke
			(width 0.05715)
			(type default)
		)
		(layer "In11.Cu")
	)
	(gr_line
		(start 101.588824 -239.278922)
		(end 101.595682 -239.282986)
		(stroke
			(width 0.05715)
			(type default)
		)
		(layer "In11.Cu")
	)
	(gr_line
		(start 101.588824 -236.038898)
		(end 101.595682 -236.042962)
		(stroke
			(width 0.05715)
			(type default)
		)
		(layer "In11.Cu")
	)
	(gr_line
		(start 101.588824 -234.418886)
		(end 101.595682 -234.42295)
		(stroke
			(width 0.05715)
			(type default)
		)
		(layer "In11.Cu")
	)
	(gr_line
		(start 101.588824 -232.798874)
		(end 101.595682 -232.802938)
		(stroke
			(width 0.05715)
			(type default)
		)
		(layer "In11.Cu")
	)
	(gr_line
		(start 101.589078 -229.559104)
		(end 101.59111 -229.560628)
		(stroke
			(width 0.05715)
			(type default)
		)
		(layer "In11.Cu")
	)
	(gr_line
		(start 101.59111 -229.560628)
		(end 101.595936 -229.563422)
		(stroke
			(width 0.05715)
			(type default)
		)
		(layer "In11.Cu")
	)
	(gr_line
		(start 101.593142 -280.101802)
		(end 101.586284 -280.097738)
		(stroke
			(width 0.05715)
			(type default)
		)
		(layer "In11.Cu")
	)
	(gr_line
		(start 101.595682 -244.143022)
		(end 101.596444 -244.14353)
		(stroke
			(width 0.05715)
			(type default)
		)
		(layer "In11.Cu")
	)
	(gr_line
		(start 101.595682 -240.902998)
		(end 101.596444 -240.903506)
		(stroke
			(width 0.05715)
			(type default)
		)
		(layer "In11.Cu")
	)
	(gr_line
		(start 101.595682 -239.282986)
		(end 101.596444 -239.283494)
		(stroke
			(width 0.05715)
			(type default)
		)
		(layer "In11.Cu")
	)
	(gr_line
		(start 101.595682 -236.042962)
		(end 101.596444 -236.04347)
		(stroke
			(width 0.05715)
			(type default)
		)
		(layer "In11.Cu")
	)
	(gr_line
		(start 101.595682 -234.42295)
		(end 101.596444 -234.423458)
		(stroke
			(width 0.05715)
			(type default)
		)
		(layer "In11.Cu")
	)
	(gr_line
		(start 101.595682 -232.802938)
		(end 101.596444 -232.803446)
		(stroke
			(width 0.05715)
			(type default)
		)
		(layer "In11.Cu")
	)
	(gr_line
		(start 101.596444 -244.14353)
		(end 101.597206 -244.144038)
		(stroke
			(width 0.05715)
			(type default)
		)
		(layer "In11.Cu")
	)
	(gr_line
		(start 101.596444 -240.903506)
		(end 101.597206 -240.904014)
		(stroke
			(width 0.05715)
			(type default)
		)
		(layer "In11.Cu")
	)
	(gr_line
		(start 101.596444 -239.283494)
		(end 101.597206 -239.284002)
		(stroke
			(width 0.05715)
			(type default)
		)
		(layer "In11.Cu")
	)
	(gr_line
		(start 101.596444 -236.04347)
		(end 101.597206 -236.043978)
		(stroke
			(width 0.05715)
			(type default)
		)
		(layer "In11.Cu")
	)
	(gr_line
		(start 101.596444 -234.423458)
		(end 101.597206 -234.423966)
		(stroke
			(width 0.05715)
			(type default)
		)
		(layer "In11.Cu")
	)
	(gr_line
		(start 101.596444 -232.803446)
		(end 101.597206 -232.803954)
		(stroke
			(width 0.05715)
			(type default)
		)
		(layer "In11.Cu")
	)
	(gr_arc
		(start 101.601016 -280.10739)
		(mid 101.597091 -280.104579)
		(end 101.593142 -280.101802)
		(stroke
			(width 0.05715)
			(type default)
		)
		(layer "In11.Cu")
	)
	(gr_line
		(start 101.62286 -244.15877)
		(end 101.623622 -244.159278)
		(stroke
			(width 0.05715)
			(type default)
		)
		(layer "In11.Cu")
	)
	(gr_line
		(start 101.62286 -240.918746)
		(end 101.623622 -240.919254)
		(stroke
			(width 0.05715)
			(type default)
		)
		(layer "In11.Cu")
	)
	(gr_line
		(start 101.62286 -239.298734)
		(end 101.623622 -239.299242)
		(stroke
			(width 0.05715)
			(type default)
		)
		(layer "In11.Cu")
	)
	(gr_line
		(start 101.62286 -236.05871)
		(end 101.623622 -236.059218)
		(stroke
			(width 0.05715)
			(type default)
		)
		(layer "In11.Cu")
	)
	(gr_line
		(start 101.62286 -234.438698)
		(end 101.623622 -234.439206)
		(stroke
			(width 0.05715)
			(type default)
		)
		(layer "In11.Cu")
	)
	(gr_line
		(start 101.62286 -232.818686)
		(end 101.623622 -232.819194)
		(stroke
			(width 0.05715)
			(type default)
		)
		(layer "In11.Cu")
	)
	(gr_line
		(start 101.625146 -244.160294)
		(end 101.626924 -244.16131)
		(stroke
			(width 0.05715)
			(type default)
		)
		(layer "In11.Cu")
	)
	(gr_line
		(start 101.625146 -240.92027)
		(end 101.626924 -240.921286)
		(stroke
			(width 0.05715)
			(type default)
		)
		(layer "In11.Cu")
	)
	(gr_line
		(start 101.625146 -239.300258)
		(end 101.626924 -239.301274)
		(stroke
			(width 0.05715)
			(type default)
		)
		(layer "In11.Cu")
	)
	(gr_line
		(start 101.625146 -236.060234)
		(end 101.626924 -236.06125)
		(stroke
			(width 0.05715)
			(type default)
		)
		(layer "In11.Cu")
	)
	(gr_line
		(start 101.625146 -234.440222)
		(end 101.626924 -234.441238)
		(stroke
			(width 0.05715)
			(type default)
		)
		(layer "In11.Cu")
	)
	(gr_line
		(start 101.625146 -232.82021)
		(end 101.626924 -232.821226)
		(stroke
			(width 0.05715)
			(type default)
		)
		(layer "In11.Cu")
	)
	(gr_line
		(start 101.626924 -245.781322)
		(end 101.62794 -245.78183)
		(stroke
			(width 0.05715)
			(type default)
		)
		(layer "In11.Cu")
	)
	(gr_line
		(start 101.626924 -244.16131)
		(end 101.62794 -244.161818)
		(stroke
			(width 0.05715)
			(type default)
		)
		(layer "In11.Cu")
	)
	(gr_line
		(start 101.626924 -242.541298)
		(end 101.62794 -242.541806)
		(stroke
			(width 0.05715)
			(type default)
		)
		(layer "In11.Cu")
	)
	(gr_line
		(start 101.626924 -240.921286)
		(end 101.62794 -240.921794)
		(stroke
			(width 0.05715)
			(type default)
		)
		(layer "In11.Cu")
	)
	(gr_line
		(start 101.626924 -239.301274)
		(end 101.62794 -239.301782)
		(stroke
			(width 0.05715)
			(type default)
		)
		(layer "In11.Cu")
	)
	(gr_line
		(start 101.626924 -237.681262)
		(end 101.62794 -237.68177)
		(stroke
			(width 0.05715)
			(type default)
		)
		(layer "In11.Cu")
	)
	(gr_line
		(start 101.626924 -236.06125)
		(end 101.62794 -236.061758)
		(stroke
			(width 0.05715)
			(type default)
		)
		(layer "In11.Cu")
	)
	(gr_line
		(start 101.626924 -234.441238)
		(end 101.62794 -234.441746)
		(stroke
			(width 0.05715)
			(type default)
		)
		(layer "In11.Cu")
	)
	(gr_line
		(start 101.626924 -232.821226)
		(end 101.62794 -232.821734)
		(stroke
			(width 0.05715)
			(type default)
		)
		(layer "In11.Cu")
	)
	(gr_line
		(start 101.62794 -245.78183)
		(end 101.628448 -245.782084)
		(stroke
			(width 0.05715)
			(type default)
		)
		(layer "In11.Cu")
	)
	(gr_line
		(start 101.62794 -244.161818)
		(end 101.628702 -244.162326)
		(stroke
			(width 0.05715)
			(type default)
		)
		(layer "In11.Cu")
	)
	(gr_line
		(start 101.62794 -242.541806)
		(end 101.628448 -242.54206)
		(stroke
			(width 0.05715)
			(type default)
		)
		(layer "In11.Cu")
	)
	(gr_line
		(start 101.62794 -240.921794)
		(end 101.628702 -240.922302)
		(stroke
			(width 0.05715)
			(type default)
		)
		(layer "In11.Cu")
	)
	(gr_line
		(start 101.62794 -239.301782)
		(end 101.628702 -239.30229)
		(stroke
			(width 0.05715)
			(type default)
		)
		(layer "In11.Cu")
	)
	(gr_line
		(start 101.62794 -237.68177)
		(end 101.628448 -237.682024)
		(stroke
			(width 0.05715)
			(type default)
		)
		(layer "In11.Cu")
	)
	(gr_line
		(start 101.62794 -236.061758)
		(end 101.628702 -236.062266)
		(stroke
			(width 0.05715)
			(type default)
		)
		(layer "In11.Cu")
	)
	(gr_line
		(start 101.62794 -234.441746)
		(end 101.628702 -234.442254)
		(stroke
			(width 0.05715)
			(type default)
		)
		(layer "In11.Cu")
	)
	(gr_line
		(start 101.62794 -232.821734)
		(end 101.628702 -232.822242)
		(stroke
			(width 0.05715)
			(type default)
		)
		(layer "In11.Cu")
	)
	(gr_line
		(start 101.628702 -246.426482)
		(end 101.62794 -246.42699)
		(stroke
			(width 0.05715)
			(type default)
		)
		(layer "In11.Cu")
	)
	(gr_line
		(start 101.628702 -244.80647)
		(end 101.62794 -244.806978)
		(stroke
			(width 0.05715)
			(type default)
		)
		(layer "In11.Cu")
	)
	(gr_line
		(start 101.628702 -243.186458)
		(end 101.62794 -243.186966)
		(stroke
			(width 0.05715)
			(type default)
		)
		(layer "In11.Cu")
	)
	(gr_line
		(start 101.628702 -241.566446)
		(end 101.62794 -241.566954)
		(stroke
			(width 0.05715)
			(type default)
		)
		(layer "In11.Cu")
	)
	(gr_line
		(start 101.628702 -239.946434)
		(end 101.62794 -239.946942)
		(stroke
			(width 0.05715)
			(type default)
		)
		(layer "In11.Cu")
	)
	(gr_line
		(start 101.628702 -236.70641)
		(end 101.62794 -236.706918)
		(stroke
			(width 0.05715)
			(type default)
		)
		(layer "In11.Cu")
	)
	(gr_line
		(start 101.628702 -235.086398)
		(end 101.62794 -235.086906)
		(stroke
			(width 0.05715)
			(type default)
		)
		(layer "In11.Cu")
	)
	(gr_line
		(start 101.628702 -233.466386)
		(end 101.62794 -233.466894)
		(stroke
			(width 0.05715)
			(type default)
		)
		(layer "In11.Cu")
	)
	(gr_line
		(start 101.628702 -231.846374)
		(end 101.62794 -231.846882)
		(stroke
			(width 0.05715)
			(type default)
		)
		(layer "In11.Cu")
	)
	(gr_line
		(start 101.629972 -238.32566)
		(end 101.628702 -238.326422)
		(stroke
			(width 0.05715)
			(type default)
		)
		(layer "In11.Cu")
	)
	(gr_line
		(start 101.630988 -246.425212)
		(end 101.628702 -246.426482)
		(stroke
			(width 0.05715)
			(type default)
		)
		(layer "In11.Cu")
	)
	(gr_line
		(start 101.630988 -244.8052)
		(end 101.628702 -244.80647)
		(stroke
			(width 0.05715)
			(type default)
		)
		(layer "In11.Cu")
	)
	(gr_line
		(start 101.630988 -243.185188)
		(end 101.628702 -243.186458)
		(stroke
			(width 0.05715)
			(type default)
		)
		(layer "In11.Cu")
	)
	(gr_line
		(start 101.630988 -241.565176)
		(end 101.628702 -241.566446)
		(stroke
			(width 0.05715)
			(type default)
		)
		(layer "In11.Cu")
	)
	(gr_line
		(start 101.630988 -239.945164)
		(end 101.628702 -239.946434)
		(stroke
			(width 0.05715)
			(type default)
		)
		(layer "In11.Cu")
	)
	(gr_line
		(start 101.630988 -236.70514)
		(end 101.628702 -236.70641)
		(stroke
			(width 0.05715)
			(type default)
		)
		(layer "In11.Cu")
	)
	(gr_line
		(start 101.630988 -235.085128)
		(end 101.628702 -235.086398)
		(stroke
			(width 0.05715)
			(type default)
		)
		(layer "In11.Cu")
	)
	(gr_line
		(start 101.630988 -233.465116)
		(end 101.628702 -233.466386)
		(stroke
			(width 0.05715)
			(type default)
		)
		(layer "In11.Cu")
	)
	(gr_line
		(start 101.630988 -231.845104)
		(end 101.628702 -231.846374)
		(stroke
			(width 0.05715)
			(type default)
		)
		(layer "In11.Cu")
	)
	(gr_line
		(start 101.717856 -243.993416)
		(end 101.71938 -243.994432)
		(stroke
			(width 0.05715)
			(type default)
		)
		(layer "In11.Cu")
	)
	(gr_line
		(start 101.717856 -240.753392)
		(end 101.71938 -240.754408)
		(stroke
			(width 0.05715)
			(type default)
		)
		(layer "In11.Cu")
	)
	(gr_line
		(start 101.717856 -239.13338)
		(end 101.71938 -239.134396)
		(stroke
			(width 0.05715)
			(type default)
		)
		(layer "In11.Cu")
	)
	(gr_line
		(start 101.717856 -235.893356)
		(end 101.71938 -235.894372)
		(stroke
			(width 0.05715)
			(type default)
		)
		(layer "In11.Cu")
	)
	(gr_line
		(start 101.717856 -234.273344)
		(end 101.71938 -234.27436)
		(stroke
			(width 0.05715)
			(type default)
		)
		(layer "In11.Cu")
	)
	(gr_line
		(start 101.717856 -232.653332)
		(end 101.71938 -232.654348)
		(stroke
			(width 0.05715)
			(type default)
		)
		(layer "In11.Cu")
	)
	(gr_line
		(start 101.72192 -245.615714)
		(end 101.72319 -245.616476)
		(stroke
			(width 0.05715)
			(type default)
		)
		(layer "In11.Cu")
	)
	(gr_line
		(start 101.72192 -243.995702)
		(end 101.72319 -243.996464)
		(stroke
			(width 0.05715)
			(type default)
		)
		(layer "In11.Cu")
	)
	(gr_line
		(start 101.72192 -242.37569)
		(end 101.72319 -242.376452)
		(stroke
			(width 0.05715)
			(type default)
		)
		(layer "In11.Cu")
	)
	(gr_line
		(start 101.72192 -240.755678)
		(end 101.72319 -240.75644)
		(stroke
			(width 0.05715)
			(type default)
		)
		(layer "In11.Cu")
	)
	(gr_line
		(start 101.72192 -239.135666)
		(end 101.72319 -239.136428)
		(stroke
			(width 0.05715)
			(type default)
		)
		(layer "In11.Cu")
	)
	(gr_line
		(start 101.72192 -237.515654)
		(end 101.72319 -237.516416)
		(stroke
			(width 0.05715)
			(type default)
		)
		(layer "In11.Cu")
	)
	(gr_line
		(start 101.72192 -235.895642)
		(end 101.72319 -235.896404)
		(stroke
			(width 0.05715)
			(type default)
		)
		(layer "In11.Cu")
	)
	(gr_line
		(start 101.72192 -234.27563)
		(end 101.72319 -234.276392)
		(stroke
			(width 0.05715)
			(type default)
		)
		(layer "In11.Cu")
	)
	(gr_line
		(start 101.72192 -232.655618)
		(end 101.72319 -232.65638)
		(stroke
			(width 0.05715)
			(type default)
		)
		(layer "In11.Cu")
	)
	(gr_line
		(start 101.72319 -243.996464)
		(end 101.723952 -243.996972)
		(stroke
			(width 0.05715)
			(type default)
		)
		(layer "In11.Cu")
	)
	(gr_line
		(start 101.72319 -240.75644)
		(end 101.723952 -240.756948)
		(stroke
			(width 0.05715)
			(type default)
		)
		(layer "In11.Cu")
	)
	(gr_line
		(start 101.72319 -239.136428)
		(end 101.723952 -239.136936)
		(stroke
			(width 0.05715)
			(type default)
		)
		(layer "In11.Cu")
	)
	(gr_line
		(start 101.72319 -235.896404)
		(end 101.723952 -235.896912)
		(stroke
			(width 0.05715)
			(type default)
		)
		(layer "In11.Cu")
	)
	(gr_line
		(start 101.72319 -234.276392)
		(end 101.723952 -234.2769)
		(stroke
			(width 0.05715)
			(type default)
		)
		(layer "In11.Cu")
	)
	(gr_line
		(start 101.72319 -232.65638)
		(end 101.723952 -232.656888)
		(stroke
			(width 0.05715)
			(type default)
		)
		(layer "In11.Cu")
	)
	(gr_line
		(start 101.723444 -229.41661)
		(end 101.723952 -229.416864)
		(stroke
			(width 0.05715)
			(type default)
		)
		(layer "In11.Cu")
	)
	(gr_line
		(start 101.723952 -246.591836)
		(end 101.72319 -246.592344)
		(stroke
			(width 0.05715)
			(type default)
		)
		(layer "In11.Cu")
	)
	(gr_line
		(start 101.723952 -244.971824)
		(end 101.72319 -244.972332)
		(stroke
			(width 0.05715)
			(type default)
		)
		(layer "In11.Cu")
	)
	(gr_line
		(start 101.723952 -243.996972)
		(end 101.724968 -243.99748)
		(stroke
			(width 0.05715)
			(type default)
		)
		(layer "In11.Cu")
	)
	(gr_line
		(start 101.723952 -243.351812)
		(end 101.72319 -243.35232)
		(stroke
			(width 0.05715)
			(type default)
		)
		(layer "In11.Cu")
	)
	(gr_line
		(start 101.723952 -241.7318)
		(end 101.72319 -241.732308)
		(stroke
			(width 0.05715)
			(type default)
		)
		(layer "In11.Cu")
	)
	(gr_line
		(start 101.723952 -240.756948)
		(end 101.724968 -240.757456)
		(stroke
			(width 0.05715)
			(type default)
		)
		(layer "In11.Cu")
	)
	(gr_line
		(start 101.723952 -240.111788)
		(end 101.72319 -240.112296)
		(stroke
			(width 0.05715)
			(type default)
		)
		(layer "In11.Cu")
	)
	(gr_line
		(start 101.723952 -239.136936)
		(end 101.724968 -239.137444)
		(stroke
			(width 0.05715)
			(type default)
		)
		(layer "In11.Cu")
	)
	(gr_line
		(start 101.723952 -238.491776)
		(end 101.723444 -238.49203)
		(stroke
			(width 0.05715)
			(type default)
		)
		(layer "In11.Cu")
	)
	(gr_line
		(start 101.723952 -236.871764)
		(end 101.72319 -236.872272)
		(stroke
			(width 0.05715)
			(type default)
		)
		(layer "In11.Cu")
	)
	(gr_line
		(start 101.723952 -235.896912)
		(end 101.724968 -235.89742)
		(stroke
			(width 0.05715)
			(type default)
		)
		(layer "In11.Cu")
	)
	(gr_line
		(start 101.723952 -235.251752)
		(end 101.72319 -235.25226)
		(stroke
			(width 0.05715)
			(type default)
		)
		(layer "In11.Cu")
	)
	(gr_line
		(start 101.723952 -234.2769)
		(end 101.724968 -234.277408)
		(stroke
			(width 0.05715)
			(type default)
		)
		(layer "In11.Cu")
	)
	(gr_line
		(start 101.723952 -233.63174)
		(end 101.72319 -233.632248)
		(stroke
			(width 0.05715)
			(type default)
		)
		(layer "In11.Cu")
	)
	(gr_line
		(start 101.723952 -232.656888)
		(end 101.724968 -232.657396)
		(stroke
			(width 0.05715)
			(type default)
		)
		(layer "In11.Cu")
	)
	(gr_line
		(start 101.723952 -232.011728)
		(end 101.72319 -232.012236)
		(stroke
			(width 0.05715)
			(type default)
		)
		(layer "In11.Cu")
	)
	(gr_line
		(start 101.724968 -246.591328)
		(end 101.723952 -246.591836)
		(stroke
			(width 0.05715)
			(type default)
		)
		(layer "In11.Cu")
	)
	(gr_line
		(start 101.724968 -244.971316)
		(end 101.723952 -244.971824)
		(stroke
			(width 0.05715)
			(type default)
		)
		(layer "In11.Cu")
	)
	(gr_line
		(start 101.724968 -243.99748)
		(end 101.726746 -243.998496)
		(stroke
			(width 0.05715)
			(type default)
		)
		(layer "In11.Cu")
	)
	(gr_line
		(start 101.724968 -243.351304)
		(end 101.723952 -243.351812)
		(stroke
			(width 0.05715)
			(type default)
		)
		(layer "In11.Cu")
	)
	(gr_line
		(start 101.724968 -241.731292)
		(end 101.723952 -241.7318)
		(stroke
			(width 0.05715)
			(type default)
		)
		(layer "In11.Cu")
	)
	(gr_line
		(start 101.724968 -240.757456)
		(end 101.726746 -240.758472)
		(stroke
			(width 0.05715)
			(type default)
		)
		(layer "In11.Cu")
	)
	(gr_line
		(start 101.724968 -240.11128)
		(end 101.723952 -240.111788)
		(stroke
			(width 0.05715)
			(type default)
		)
		(layer "In11.Cu")
	)
	(gr_line
		(start 101.724968 -239.137444)
		(end 101.726746 -239.13846)
		(stroke
			(width 0.05715)
			(type default)
		)
		(layer "In11.Cu")
	)
	(gr_line
		(start 101.724968 -238.491268)
		(end 101.723952 -238.491776)
		(stroke
			(width 0.05715)
			(type default)
		)
		(layer "In11.Cu")
	)
	(gr_line
		(start 101.724968 -236.871256)
		(end 101.723952 -236.871764)
		(stroke
			(width 0.05715)
			(type default)
		)
		(layer "In11.Cu")
	)
	(gr_line
		(start 101.724968 -235.89742)
		(end 101.726746 -235.898436)
		(stroke
			(width 0.05715)
			(type default)
		)
		(layer "In11.Cu")
	)
	(gr_line
		(start 101.724968 -235.251244)
		(end 101.723952 -235.251752)
		(stroke
			(width 0.05715)
			(type default)
		)
		(layer "In11.Cu")
	)
	(gr_line
		(start 101.724968 -234.277408)
		(end 101.726746 -234.278424)
		(stroke
			(width 0.05715)
			(type default)
		)
		(layer "In11.Cu")
	)
	(gr_line
		(start 101.724968 -233.631232)
		(end 101.723952 -233.63174)
		(stroke
			(width 0.05715)
			(type default)
		)
		(layer "In11.Cu")
	)
	(gr_line
		(start 101.724968 -232.657396)
		(end 101.726746 -232.658412)
		(stroke
			(width 0.05715)
			(type default)
		)
		(layer "In11.Cu")
	)
	(gr_line
		(start 101.724968 -232.01122)
		(end 101.723952 -232.011728)
		(stroke
			(width 0.05715)
			(type default)
		)
		(layer "In11.Cu")
	)
	(gr_line
		(start 101.726492 -246.590312)
		(end 101.724968 -246.591328)
		(stroke
			(width 0.05715)
			(type default)
		)
		(layer "In11.Cu")
	)
	(gr_line
		(start 101.726492 -244.9703)
		(end 101.724968 -244.971316)
		(stroke
			(width 0.05715)
			(type default)
		)
		(layer "In11.Cu")
	)
	(gr_line
		(start 101.726492 -243.350288)
		(end 101.724968 -243.351304)
		(stroke
			(width 0.05715)
			(type default)
		)
		(layer "In11.Cu")
	)
	(gr_line
		(start 101.726492 -241.730276)
		(end 101.724968 -241.731292)
		(stroke
			(width 0.05715)
			(type default)
		)
		(layer "In11.Cu")
	)
	(gr_line
		(start 101.726492 -240.110264)
		(end 101.724968 -240.11128)
		(stroke
			(width 0.05715)
			(type default)
		)
		(layer "In11.Cu")
	)
	(gr_line
		(start 101.726492 -236.87024)
		(end 101.724968 -236.871256)
		(stroke
			(width 0.05715)
			(type default)
		)
		(layer "In11.Cu")
	)
	(gr_line
		(start 101.726492 -235.250228)
		(end 101.724968 -235.251244)
		(stroke
			(width 0.05715)
			(type default)
		)
		(layer "In11.Cu")
	)
	(gr_line
		(start 101.726492 -233.630216)
		(end 101.724968 -233.631232)
		(stroke
			(width 0.05715)
			(type default)
		)
		(layer "In11.Cu")
	)
	(gr_line
		(start 101.726492 -232.010204)
		(end 101.724968 -232.01122)
		(stroke
			(width 0.05715)
			(type default)
		)
		(layer "In11.Cu")
	)
	(gr_line
		(start 101.727508 -246.589804)
		(end 101.726492 -246.590312)
		(stroke
			(width 0.05715)
			(type default)
		)
		(layer "In11.Cu")
	)
	(gr_line
		(start 101.727508 -244.969792)
		(end 101.726492 -244.9703)
		(stroke
			(width 0.05715)
			(type default)
		)
		(layer "In11.Cu")
	)
	(gr_line
		(start 101.727508 -243.34978)
		(end 101.726492 -243.350288)
		(stroke
			(width 0.05715)
			(type default)
		)
		(layer "In11.Cu")
	)
	(gr_line
		(start 101.727508 -241.729768)
		(end 101.726492 -241.730276)
		(stroke
			(width 0.05715)
			(type default)
		)
		(layer "In11.Cu")
	)
	(gr_line
		(start 101.727508 -240.109756)
		(end 101.726492 -240.110264)
		(stroke
			(width 0.05715)
			(type default)
		)
		(layer "In11.Cu")
	)
	(gr_line
		(start 101.727508 -236.869732)
		(end 101.726492 -236.87024)
		(stroke
			(width 0.05715)
			(type default)
		)
		(layer "In11.Cu")
	)
	(gr_line
		(start 101.727508 -235.24972)
		(end 101.726492 -235.250228)
		(stroke
			(width 0.05715)
			(type default)
		)
		(layer "In11.Cu")
	)
	(gr_line
		(start 101.727508 -233.629708)
		(end 101.726492 -233.630216)
		(stroke
			(width 0.05715)
			(type default)
		)
		(layer "In11.Cu")
	)
	(gr_line
		(start 101.727508 -232.009696)
		(end 101.726492 -232.010204)
		(stroke
			(width 0.05715)
			(type default)
		)
		(layer "In11.Cu")
	)
	(gr_line
		(start 101.729794 -246.588534)
		(end 101.727508 -246.589804)
		(stroke
			(width 0.05715)
			(type default)
		)
		(layer "In11.Cu")
	)
	(gr_line
		(start 101.729794 -244.968522)
		(end 101.727508 -244.969792)
		(stroke
			(width 0.05715)
			(type default)
		)
		(layer "In11.Cu")
	)
	(gr_line
		(start 101.729794 -243.34851)
		(end 101.727508 -243.34978)
		(stroke
			(width 0.05715)
			(type default)
		)
		(layer "In11.Cu")
	)
	(gr_line
		(start 101.729794 -241.728498)
		(end 101.727508 -241.729768)
		(stroke
			(width 0.05715)
			(type default)
		)
		(layer "In11.Cu")
	)
	(gr_line
		(start 101.729794 -240.108486)
		(end 101.727508 -240.109756)
		(stroke
			(width 0.05715)
			(type default)
		)
		(layer "In11.Cu")
	)
	(gr_line
		(start 101.729794 -236.868462)
		(end 101.727508 -236.869732)
		(stroke
			(width 0.05715)
			(type default)
		)
		(layer "In11.Cu")
	)
	(gr_line
		(start 101.729794 -235.24845)
		(end 101.727508 -235.24972)
		(stroke
			(width 0.05715)
			(type default)
		)
		(layer "In11.Cu")
	)
	(gr_line
		(start 101.729794 -233.628438)
		(end 101.727508 -233.629708)
		(stroke
			(width 0.05715)
			(type default)
		)
		(layer "In11.Cu")
	)
	(gr_line
		(start 101.729794 -232.008426)
		(end 101.727508 -232.009696)
		(stroke
			(width 0.05715)
			(type default)
		)
		(layer "In11.Cu")
	)
	(gr_line
		(start 101.76256 -228.749352)
		(end 101.754686 -228.753924)
		(stroke
			(width 0.05715)
			(type default)
		)
		(layer "In11.Cu")
	)
	(gr_line
		(start 101.763068 -228.749098)
		(end 101.76256 -228.749352)
		(stroke
			(width 0.05715)
			(type default)
		)
		(layer "In11.Cu")
	)
	(gr_arc
		(start 101.763068 -228.749098)
		(mid 101.766251 -228.746823)
		(end 101.769418 -228.744526)
		(stroke
			(width 0.05715)
			(type default)
		)
		(layer "In11.Cu")
	)
	(gr_line
		(start 101.77018 -221.083378)
		(end 101.8159 -221.129098)
		(stroke
			(width 0.05715)
			(type default)
		)
		(layer "In11.Cu")
	)
	(gr_line
		(start 101.77018 -221.05493)
		(end 101.77018 -221.083378)
		(stroke
			(width 0.05715)
			(type default)
		)
		(layer "In11.Cu")
	)
	(gr_line
		(start 101.77018 -215.657684)
		(end 101.77018 -215.735154)
		(stroke
			(width 0.07112)
			(type default)
		)
		(layer "In11.Cu")
	)
	(gr_line
		(start 101.810058 -215.590374)
		(end 101.77018 -215.657684)
		(stroke
			(width 0.07112)
			(type default)
		)
		(layer "In11.Cu")
	)
	(gr_arc
		(start 101.889052 -286.581596)
		(mid 101.884335 -286.584873)
		(end 101.879654 -286.5882)
		(stroke
			(width 0.05715)
			(type default)
		)
		(layer "In11.Cu")
	)
	(gr_line
		(start 101.889052 -286.581596)
		(end 101.891084 -286.580072)
		(stroke
			(width 0.05715)
			(type default)
		)
		(layer "In11.Cu")
	)
	(gr_line
		(start 101.891084 -286.580072)
		(end 101.89591 -286.577278)
		(stroke
			(width 0.05715)
			(type default)
		)
		(layer "In11.Cu")
	)
	(gr_line
		(start 102.023418 -286.72409)
		(end 102.023926 -286.723836)
		(stroke
			(width 0.05715)
			(type default)
		)
		(layer "In11.Cu")
	)
	(gr_arc
		(start 102.051104 -225.503486)
		(mid 102.055029 -225.506297)
		(end 102.058978 -225.509074)
		(stroke
			(width 0.05715)
			(type default)
		)
		(layer "In11.Cu")
	)
	(gr_line
		(start 102.05212 -221.083378)
		(end 102.0064 -221.129098)
		(stroke
			(width 0.05715)
			(type default)
		)
		(layer "In11.Cu")
	)
	(gr_line
		(start 102.05212 -221.05493)
		(end 102.05212 -221.083378)
		(stroke
			(width 0.05715)
			(type default)
		)
		(layer "In11.Cu")
	)
	(gr_line
		(start 102.058978 -225.509074)
		(end 102.065836 -225.513138)
		(stroke
			(width 0.05715)
			(type default)
		)
		(layer "In11.Cu")
	)
	(gr_line
		(start 102.065836 -225.513138)
		(end 102.066598 -225.513646)
		(stroke
			(width 0.05715)
			(type default)
		)
		(layer "In11.Cu")
	)
	(gr_line
		(start 102.066598 -225.513646)
		(end 102.067106 -225.5139)
		(stroke
			(width 0.05715)
			(type default)
		)
		(layer "In11.Cu")
	)
	(gr_line
		(start 102.075234 -296.41927)
		(end 102.075234 -296.390822)
		(stroke
			(width 0.05715)
			(type default)
		)
		(layer "In11.Cu")
	)
	(gr_line
		(start 102.075234 -296.390822)
		(end 102.120954 -296.345102)
		(stroke
			(width 0.05715)
			(type default)
		)
		(layer "In11.Cu")
	)
	(gr_line
		(start 102.09022 -222.287338)
		(end 102.091998 -222.288354)
		(stroke
			(width 0.05715)
			(type default)
		)
		(layer "In11.Cu")
	)
	(gr_line
		(start 102.091744 -225.528124)
		(end 102.09276 -225.528886)
		(stroke
			(width 0.05715)
			(type default)
		)
		(layer "In11.Cu")
	)
	(gr_line
		(start 102.091998 -222.288354)
		(end 102.093014 -222.288862)
		(stroke
			(width 0.05715)
			(type default)
		)
		(layer "In11.Cu")
	)
	(gr_line
		(start 102.09276 -225.528886)
		(end 102.093776 -225.529394)
		(stroke
			(width 0.05715)
			(type default)
		)
		(layer "In11.Cu")
	)
	(gr_line
		(start 102.093014 -222.288862)
		(end 102.093776 -222.28937)
		(stroke
			(width 0.05715)
			(type default)
		)
		(layer "In11.Cu")
	)
	(gr_line
		(start 102.0953 -225.53041)
		(end 102.097078 -225.531426)
		(stroke
			(width 0.05715)
			(type default)
		)
		(layer "In11.Cu")
	)
	(gr_line
		(start 102.097078 -225.531426)
		(end 102.098094 -225.531934)
		(stroke
			(width 0.05715)
			(type default)
		)
		(layer "In11.Cu")
	)
	(gr_line
		(start 102.098094 -225.531934)
		(end 102.098856 -225.532442)
		(stroke
			(width 0.05715)
			(type default)
		)
		(layer "In11.Cu")
	)
	(gr_line
		(start 102.098856 -225.532442)
		(end 102.100126 -225.533204)
		(stroke
			(width 0.05715)
			(type default)
		)
		(layer "In11.Cu")
	)
	(gr_line
		(start 102.186232 -222.122746)
		(end 102.193344 -222.126556)
		(stroke
			(width 0.05715)
			(type default)
		)
		(layer "In11.Cu")
	)
	(gr_line
		(start 102.186486 -225.36277)
		(end 102.186994 -225.363024)
		(stroke
			(width 0.05715)
			(type default)
		)
		(layer "In11.Cu")
	)
	(gr_line
		(start 102.186994 -225.363024)
		(end 102.18801 -225.363532)
		(stroke
			(width 0.05715)
			(type default)
		)
		(layer "In11.Cu")
	)
	(gr_line
		(start 102.18801 -225.363532)
		(end 102.189534 -225.364548)
		(stroke
			(width 0.05715)
			(type default)
		)
		(layer "In11.Cu")
	)
	(gr_line
		(start 102.192074 -225.365818)
		(end 102.193344 -225.36658)
		(stroke
			(width 0.05715)
			(type default)
		)
		(layer "In11.Cu")
	)
	(gr_line
		(start 102.193344 -225.36658)
		(end 102.194106 -225.367088)
		(stroke
			(width 0.05715)
			(type default)
		)
		(layer "In11.Cu")
	)
	(gr_line
		(start 102.194106 -225.367088)
		(end 102.195122 -225.367596)
		(stroke
			(width 0.05715)
			(type default)
		)
		(layer "In11.Cu")
	)
	(gr_line
		(start 102.357174 -296.41927)
		(end 102.357174 -296.390822)
		(stroke
			(width 0.05715)
			(type default)
		)
		(layer "In11.Cu")
	)
	(gr_line
		(start 102.357174 -296.390822)
		(end 102.311454 -296.345102)
		(stroke
			(width 0.05715)
			(type default)
		)
		(layer "In11.Cu")
	)
	(gr_line
		(start 102.391972 -280.240232)
		(end 102.390956 -280.23947)
		(stroke
			(width 0.05715)
			(type default)
		)
		(layer "In11.Cu")
	)
	(gr_line
		(start 102.392226 -279.272492)
		(end 102.395528 -279.27046)
		(stroke
			(width 0.05715)
			(type default)
		)
		(layer "In11.Cu")
	)
	(gr_line
		(start 102.394512 -280.241756)
		(end 102.391972 -280.240232)
		(stroke
			(width 0.05715)
			(type default)
		)
		(layer "In11.Cu")
	)
	(gr_line
		(start 102.395528 -280.242264)
		(end 102.394512 -280.241756)
		(stroke
			(width 0.05715)
			(type default)
		)
		(layer "In11.Cu")
	)
	(gr_line
		(start 102.395528 -279.27046)
		(end 102.397052 -279.269444)
		(stroke
			(width 0.05715)
			(type default)
		)
		(layer "In11.Cu")
	)
	(gr_line
		(start 102.397052 -280.24328)
		(end 102.395528 -280.242264)
		(stroke
			(width 0.05715)
			(type default)
		)
		(layer "In11.Cu")
	)
	(gr_line
		(start 102.397052 -279.269444)
		(end 102.398068 -279.268936)
		(stroke
			(width 0.05715)
			(type default)
		)
		(layer "In11.Cu")
	)
	(gr_line
		(start 102.398068 -280.243788)
		(end 102.397052 -280.24328)
		(stroke
			(width 0.05715)
			(type default)
		)
		(layer "In11.Cu")
	)
	(gr_line
		(start 102.398068 -279.268936)
		(end 102.39883 -279.268428)
		(stroke
			(width 0.05715)
			(type default)
		)
		(layer "In11.Cu")
	)
	(gr_line
		(start 102.39883 -280.244296)
		(end 102.398068 -280.243788)
		(stroke
			(width 0.05715)
			(type default)
		)
		(layer "In11.Cu")
	)
	(gr_line
		(start 102.489762 -280.076402)
		(end 102.488238 -280.07564)
		(stroke
			(width 0.05715)
			(type default)
		)
		(layer "In11.Cu")
	)
	(gr_line
		(start 102.490524 -280.07691)
		(end 102.489762 -280.076402)
		(stroke
			(width 0.05715)
			(type default)
		)
		(layer "In11.Cu")
	)
	(gr_line
		(start 102.49154 -279.435306)
		(end 102.493318 -279.43429)
		(stroke
			(width 0.05715)
			(type default)
		)
		(layer "In11.Cu")
	)
	(gr_line
		(start 102.493318 -280.078434)
		(end 102.49281 -280.07818)
		(stroke
			(width 0.05715)
			(type default)
		)
		(layer "In11.Cu")
	)
	(gr_line
		(start 102.493318 -279.43429)
		(end 102.49408 -279.433782)
		(stroke
			(width 0.05715)
			(type default)
		)
		(layer "In11.Cu")
	)
	(gr_line
		(start 102.49408 -280.078942)
		(end 102.493318 -280.078434)
		(stroke
			(width 0.05715)
			(type default)
		)
		(layer "In11.Cu")
	)
	(gr_line
		(start 102.49408 -279.433782)
		(end 102.495096 -279.433274)
		(stroke
			(width 0.05715)
			(type default)
		)
		(layer "In11.Cu")
	)
	(gr_line
		(start 102.495096 -280.07945)
		(end 102.49408 -280.078942)
		(stroke
			(width 0.05715)
			(type default)
		)
		(layer "In11.Cu")
	)
	(gr_line
		(start 102.496366 -280.080212)
		(end 102.495096 -280.07945)
		(stroke
			(width 0.05715)
			(type default)
		)
		(layer "In11.Cu")
	)
	(gr_line
		(start 102.49916 -280.081736)
		(end 102.498144 -280.081228)
		(stroke
			(width 0.05715)
			(type default)
		)
		(layer "In11.Cu")
	)
	(gr_arc
		(start 102.519734 -229.5525)
		(mid 102.524417 -229.555825)
		(end 102.529132 -229.559104)
		(stroke
			(width 0.05715)
			(type default)
		)
		(layer "In11.Cu")
	)
	(gr_line
		(start 102.525576 -280.09723)
		(end 102.524814 -280.096722)
		(stroke
			(width 0.05715)
			(type default)
		)
		(layer "In11.Cu")
	)
	(gr_line
		(start 102.526338 -280.097738)
		(end 102.525576 -280.09723)
		(stroke
			(width 0.05715)
			(type default)
		)
		(layer "In11.Cu")
	)
	(gr_line
		(start 102.529132 -229.559104)
		(end 102.531164 -229.560628)
		(stroke
			(width 0.05715)
			(type default)
		)
		(layer "In11.Cu")
	)
	(gr_line
		(start 102.531164 -229.560628)
		(end 102.53599 -229.563422)
		(stroke
			(width 0.05715)
			(type default)
		)
		(layer "In11.Cu")
	)
	(gr_line
		(start 102.533196 -280.101802)
		(end 102.526338 -280.097738)
		(stroke
			(width 0.05715)
			(type default)
		)
		(layer "In11.Cu")
	)
	(gr_arc
		(start 102.54107 -280.10739)
		(mid 102.537145 -280.104579)
		(end 102.533196 -280.101802)
		(stroke
			(width 0.05715)
			(type default)
		)
		(layer "In11.Cu")
	)
	(gr_line
		(start 102.663498 -229.41661)
		(end 102.664006 -229.416864)
		(stroke
			(width 0.05715)
			(type default)
		)
		(layer "In11.Cu")
	)
	(gr_line
		(start 102.702614 -228.749352)
		(end 102.69474 -228.753924)
		(stroke
			(width 0.05715)
			(type default)
		)
		(layer "In11.Cu")
	)
	(gr_line
		(start 102.703122 -228.749098)
		(end 102.702614 -228.749352)
		(stroke
			(width 0.05715)
			(type default)
		)
		(layer "In11.Cu")
	)
	(gr_arc
		(start 102.703122 -228.749098)
		(mid 102.706305 -228.746823)
		(end 102.709472 -228.744526)
		(stroke
			(width 0.05715)
			(type default)
		)
		(layer "In11.Cu")
	)
	(gr_line
		(start 102.752398 -363.314234)
		(end 102.75316 -363.313726)
		(stroke
			(width 0.07112)
			(type default)
		)
		(layer "In11.Cu")
	)
	(gr_arc
		(start 102.829106 -286.581596)
		(mid 102.82439 -286.584873)
		(end 102.819708 -286.5882)
		(stroke
			(width 0.05715)
			(type default)
		)
		(layer "In11.Cu")
	)
	(gr_line
		(start 102.829106 -286.581596)
		(end 102.831138 -286.580072)
		(stroke
			(width 0.05715)
			(type default)
		)
		(layer "In11.Cu")
	)
	(gr_line
		(start 102.831138 -286.580072)
		(end 102.835964 -286.577278)
		(stroke
			(width 0.05715)
			(type default)
		)
		(layer "In11.Cu")
	)
	(gr_line
		(start 102.963472 -286.72409)
		(end 102.96398 -286.723836)
		(stroke
			(width 0.05715)
			(type default)
		)
		(layer "In11.Cu")
	)
	(gr_line
		(start 103.020114 -296.41927)
		(end 103.020114 -296.390822)
		(stroke
			(width 0.05715)
			(type default)
		)
		(layer "In11.Cu")
	)
	(gr_line
		(start 103.020114 -296.390822)
		(end 103.065834 -296.345102)
		(stroke
			(width 0.05715)
			(type default)
		)
		(layer "In11.Cu")
	)
	(gr_line
		(start 103.03891 -225.532442)
		(end 103.039418 -225.532696)
		(stroke
			(width 0.05715)
			(type default)
		)
		(layer "In11.Cu")
	)
	(gr_line
		(start 103.04145 -225.533712)
		(end 103.042212 -225.53422)
		(stroke
			(width 0.05715)
			(type default)
		)
		(layer "In11.Cu")
	)
	(gr_line
		(start 103.049324 -244.978174)
		(end 103.050594 -244.978936)
		(stroke
			(width 0.05715)
			(type default)
		)
		(layer "In11.Cu")
	)
	(gr_line
		(start 103.133652 -225.366834)
		(end 103.13416 -225.367088)
		(stroke
			(width 0.05715)
			(type default)
		)
		(layer "In11.Cu")
	)
	(gr_line
		(start 103.13416 -225.367088)
		(end 103.135938 -225.368104)
		(stroke
			(width 0.05715)
			(type default)
		)
		(layer "In11.Cu")
	)
	(gr_line
		(start 103.135938 -225.368104)
		(end 103.137462 -225.36912)
		(stroke
			(width 0.05715)
			(type default)
		)
		(layer "In11.Cu")
	)
	(gr_line
		(start 103.157782 -225.380804)
		(end 103.167942 -225.386646)
		(stroke
			(width 0.05715)
			(type default)
		)
		(layer "In11.Cu")
	)
	(gr_arc
		(start 103.180134 -225.395282)
		(mid 103.175327 -225.3917)
		(end 103.170482 -225.38817)
		(stroke
			(width 0.05715)
			(type default)
		)
		(layer "In11.Cu")
	)
	(gr_line
		(start 103.225854 -225.871532)
		(end 103.225854 -225.87077)
		(stroke
			(width 0.05715)
			(type default)
		)
		(layer "In11.Cu")
	)
	(gr_line
		(start 103.225854 -225.870516)
		(end 103.225854 -225.87077)
		(stroke
			(width 0.05715)
			(type default)
		)
		(layer "In11.Cu")
	)
	(gr_arc
		(start 103.225854 -225.870008)
		(mid 103.225854 -225.870262)
		(end 103.225854 -225.870516)
		(stroke
			(width 0.05715)
			(type default)
		)
		(layer "In11.Cu")
	)
	(gr_arc
		(start 103.291132 -280.21534)
		(mid 103.295057 -280.218151)
		(end 103.299006 -280.220928)
		(stroke
			(width 0.05715)
			(type default)
		)
		(layer "In11.Cu")
	)
	(gr_arc
		(start 103.299768 -280.221436)
		(mid 103.299387 -280.221182)
		(end 103.299006 -280.220928)
		(stroke
			(width 0.05715)
			(type default)
		)
		(layer "In11.Cu")
	)
	(gr_line
		(start 103.302054 -296.41927)
		(end 103.302054 -296.390822)
		(stroke
			(width 0.05715)
			(type default)
		)
		(layer "In11.Cu")
	)
	(gr_line
		(start 103.302054 -296.390822)
		(end 103.256334 -296.345102)
		(stroke
			(width 0.05715)
			(type default)
		)
		(layer "In11.Cu")
	)
	(gr_line
		(start 103.307388 -280.225754)
		(end 103.299768 -280.221436)
		(stroke
			(width 0.05715)
			(type default)
		)
		(layer "In11.Cu")
	)
	(gr_line
		(start 103.33228 -277.65248)
		(end 103.335582 -277.650448)
		(stroke
			(width 0.05715)
			(type default)
		)
		(layer "In11.Cu")
	)
	(gr_line
		(start 103.335582 -277.650448)
		(end 103.337106 -277.649432)
		(stroke
			(width 0.05715)
			(type default)
		)
		(layer "In11.Cu")
	)
	(gr_line
		(start 103.337106 -277.649432)
		(end 103.338122 -277.648924)
		(stroke
			(width 0.05715)
			(type default)
		)
		(layer "In11.Cu")
	)
	(gr_line
		(start 103.338122 -277.648924)
		(end 103.33863 -277.648924)
		(stroke
			(width 0.05715)
			(type default)
		)
		(layer "In11.Cu")
	)
	(gr_line
		(start 103.33863 -277.648924)
		(end 103.339646 -277.648416)
		(stroke
			(width 0.05715)
			(type default)
		)
		(layer "In11.Cu")
	)
	(gr_line
		(start 103.349806 -279.262332)
		(end 103.350822 -279.26157)
		(stroke
			(width 0.05715)
			(type default)
		)
		(layer "In11.Cu")
	)
	(gr_line
		(start 103.382318 -369.353338)
		(end 103.382064 -369.354354)
		(stroke
			(width 0.07112)
			(type default)
		)
		(layer "In11.Cu")
	)
	(gr_line
		(start 103.408226 -225.789998)
		(end 103.40848 -225.791014)
		(stroke
			(width 0.05715)
			(type default)
		)
		(layer "In11.Cu")
	)
	(gr_line
		(start 103.431594 -277.815294)
		(end 103.433372 -277.814278)
		(stroke
			(width 0.05715)
			(type default)
		)
		(layer "In11.Cu")
	)
	(gr_line
		(start 103.433372 -277.814278)
		(end 103.434134 -277.81377)
		(stroke
			(width 0.05715)
			(type default)
		)
		(layer "In11.Cu")
	)
	(gr_line
		(start 103.434134 -277.81377)
		(end 103.435658 -277.813008)
		(stroke
			(width 0.05715)
			(type default)
		)
		(layer "In11.Cu")
	)
	(gr_arc
		(start 103.443024 -280.084022)
		(mid 103.443405 -280.084276)
		(end 103.443786 -280.08453)
		(stroke
			(width 0.05715)
			(type default)
		)
		(layer "In11.Cu")
	)
	(gr_arc
		(start 103.458264 -229.55123)
		(mid 103.46496 -229.556105)
		(end 103.471726 -229.560882)
		(stroke
			(width 0.05715)
			(type default)
		)
		(layer "In11.Cu")
	)
	(gr_line
		(start 103.461312 -277.798022)
		(end 103.470456 -277.792688)
		(stroke
			(width 0.05715)
			(type default)
		)
		(layer "In11.Cu")
	)
	(gr_arc
		(start 103.462582 -226.314508)
		(mid 103.467138 -226.317706)
		(end 103.471726 -226.320858)
		(stroke
			(width 0.05715)
			(type default)
		)
		(layer "In11.Cu")
	)
	(gr_arc
		(start 103.471218 -277.79218)
		(mid 103.475679 -277.7889)
		(end 103.480108 -277.785576)
		(stroke
			(width 0.05715)
			(type default)
		)
		(layer "In11.Cu")
	)
	(gr_line
		(start 103.471726 -229.560882)
		(end 103.47452 -229.562406)
		(stroke
			(width 0.05715)
			(type default)
		)
		(layer "In11.Cu")
	)
	(gr_line
		(start 103.471726 -226.320858)
		(end 103.47325 -226.321874)
		(stroke
			(width 0.05715)
			(type default)
		)
		(layer "In11.Cu")
	)
	(gr_line
		(start 103.47325 -226.321874)
		(end 103.477822 -226.324414)
		(stroke
			(width 0.05715)
			(type default)
		)
		(layer "In11.Cu")
	)
	(gr_arc
		(start 103.47452 -230.246428)
		(mid 103.466086 -230.252067)
		(end 103.457756 -230.257858)
		(stroke
			(width 0.05715)
			(type default)
		)
		(layer "In11.Cu")
	)
	(gr_line
		(start 103.476044 -230.245412)
		(end 103.47452 -230.246428)
		(stroke
			(width 0.05715)
			(type default)
		)
		(layer "In11.Cu")
	)
	(gr_line
		(start 103.47706 -230.244904)
		(end 103.476044 -230.245412)
		(stroke
			(width 0.05715)
			(type default)
		)
		(layer "In11.Cu")
	)
	(gr_arc
		(start 103.496618 -242.535202)
		(mid 103.499028 -242.536605)
		(end 103.501444 -242.537996)
		(stroke
			(width 0.05715)
			(type default)
		)
		(layer "In11.Cu")
	)
	(gr_arc
		(start 103.496618 -240.91519)
		(mid 103.499028 -240.916593)
		(end 103.501444 -240.917984)
		(stroke
			(width 0.05715)
			(type default)
		)
		(layer "In11.Cu")
	)
	(gr_arc
		(start 103.496618 -239.295178)
		(mid 103.499028 -239.296581)
		(end 103.501444 -239.297972)
		(stroke
			(width 0.05715)
			(type default)
		)
		(layer "In11.Cu")
	)
	(gr_arc
		(start 103.496618 -237.675166)
		(mid 103.499028 -237.676569)
		(end 103.501444 -237.67796)
		(stroke
			(width 0.05715)
			(type default)
		)
		(layer "In11.Cu")
	)
	(gr_arc
		(start 103.496618 -236.055154)
		(mid 103.498394 -236.056301)
		(end 103.500174 -236.05744)
		(stroke
			(width 0.05715)
			(type default)
		)
		(layer "In11.Cu")
	)
	(gr_line
		(start 103.507032 -230.227378)
		(end 103.505508 -230.228394)
		(stroke
			(width 0.05715)
			(type default)
		)
		(layer "In11.Cu")
	)
	(gr_line
		(start 103.507794 -242.541806)
		(end 103.508048 -242.541806)
		(stroke
			(width 0.05715)
			(type default)
		)
		(layer "In11.Cu")
	)
	(gr_line
		(start 103.507794 -240.921794)
		(end 103.508048 -240.921794)
		(stroke
			(width 0.05715)
			(type default)
		)
		(layer "In11.Cu")
	)
	(gr_line
		(start 103.507794 -239.301782)
		(end 103.508048 -239.301782)
		(stroke
			(width 0.05715)
			(type default)
		)
		(layer "In11.Cu")
	)
	(gr_line
		(start 103.507794 -237.68177)
		(end 103.508048 -237.68177)
		(stroke
			(width 0.05715)
			(type default)
		)
		(layer "In11.Cu")
	)
	(gr_line
		(start 103.507794 -236.061758)
		(end 103.508048 -236.061758)
		(stroke
			(width 0.05715)
			(type default)
		)
		(layer "In11.Cu")
	)
	(gr_line
		(start 103.508048 -241.566954)
		(end 103.507794 -241.567208)
		(stroke
			(width 0.05715)
			(type default)
		)
		(layer "In11.Cu")
	)
	(gr_line
		(start 103.508048 -239.946942)
		(end 103.507794 -239.947196)
		(stroke
			(width 0.05715)
			(type default)
		)
		(layer "In11.Cu")
	)
	(gr_line
		(start 103.508048 -238.32693)
		(end 103.507794 -238.327184)
		(stroke
			(width 0.05715)
			(type default)
		)
		(layer "In11.Cu")
	)
	(gr_line
		(start 103.508048 -236.706918)
		(end 103.507794 -236.707172)
		(stroke
			(width 0.05715)
			(type default)
		)
		(layer "In11.Cu")
	)
	(gr_line
		(start 103.508048 -235.086906)
		(end 103.507794 -235.08716)
		(stroke
			(width 0.05715)
			(type default)
		)
		(layer "In11.Cu")
	)
	(gr_line
		(start 103.508048 -232.821734)
		(end 103.508556 -232.821988)
		(stroke
			(width 0.05715)
			(type default)
		)
		(layer "In11.Cu")
	)
	(gr_line
		(start 103.508048 -230.22687)
		(end 103.507032 -230.227378)
		(stroke
			(width 0.05715)
			(type default)
		)
		(layer "In11.Cu")
	)
	(gr_line
		(start 103.508556 -230.226616)
		(end 103.508048 -230.22687)
		(stroke
			(width 0.05715)
			(type default)
		)
		(layer "In11.Cu")
	)
	(gr_line
		(start 103.50881 -234.442254)
		(end 103.509318 -234.442508)
		(stroke
			(width 0.05715)
			(type default)
		)
		(layer "In11.Cu")
	)
	(gr_line
		(start 103.50881 -228.606604)
		(end 103.508048 -228.607112)
		(stroke
			(width 0.05715)
			(type default)
		)
		(layer "In11.Cu")
	)
	(gr_line
		(start 103.510334 -228.605842)
		(end 103.50881 -228.606604)
		(stroke
			(width 0.05715)
			(type default)
		)
		(layer "In11.Cu")
	)
	(gr_line
		(start 103.511604 -236.06379)
		(end 103.512366 -236.064298)
		(stroke
			(width 0.05715)
			(type default)
		)
		(layer "In11.Cu")
	)
	(gr_line
		(start 103.512366 -236.064298)
		(end 103.51389 -236.065314)
		(stroke
			(width 0.05715)
			(type default)
		)
		(layer "In11.Cu")
	)
	(gr_line
		(start 103.518208 -228.60127)
		(end 103.517446 -228.601778)
		(stroke
			(width 0.05715)
			(type default)
		)
		(layer "In11.Cu")
	)
	(gr_line
		(start 103.525574 -295.142666)
		(end 103.525828 -295.141904)
		(stroke
			(width 0.05715)
			(type default)
		)
		(layer "In11.Cu")
	)
	(gr_line
		(start 103.525828 -295.14419)
		(end 103.525574 -295.142666)
		(stroke
			(width 0.05715)
			(type default)
		)
		(layer "In11.Cu")
	)
	(gr_line
		(start 103.525828 -295.141904)
		(end 103.525828 -295.13911)
		(stroke
			(width 0.05715)
			(type default)
		)
		(layer "In11.Cu")
	)
	(gr_arc
		(start 103.525828 -287.046162)
		(mid 103.525824 -287.048321)
		(end 103.525828 -287.05048)
		(stroke
			(width 0.05715)
			(type default)
		)
		(layer "In11.Cu")
	)
	(gr_arc
		(start 103.525828 -277.310342)
		(mid 103.525828 -277.310596)
		(end 103.525828 -277.31085)
		(stroke
			(width 0.05715)
			(type default)
		)
		(layer "In11.Cu")
	)
	(gr_line
		(start 103.525828 -277.310342)
		(end 103.525828 -277.310088)
		(stroke
			(width 0.05715)
			(type default)
		)
		(layer "In11.Cu")
	)
	(gr_line
		(start 103.525828 -277.310088)
		(end 103.525828 -277.309326)
		(stroke
			(width 0.05715)
			(type default)
		)
		(layer "In11.Cu")
	)
	(gr_line
		(start 103.602028 -230.39324)
		(end 103.600504 -230.394002)
		(stroke
			(width 0.05715)
			(type default)
		)
		(layer "In11.Cu")
	)
	(gr_line
		(start 103.603298 -230.392478)
		(end 103.602028 -230.39324)
		(stroke
			(width 0.05715)
			(type default)
		)
		(layer "In11.Cu")
	)
	(gr_line
		(start 103.603298 -228.772466)
		(end 103.60279 -228.77272)
		(stroke
			(width 0.05715)
			(type default)
		)
		(layer "In11.Cu")
	)
	(gr_line
		(start 103.603298 -223.91243)
		(end 103.601774 -223.913446)
		(stroke
			(width 0.05715)
			(type default)
		)
		(layer "In11.Cu")
	)
	(gr_line
		(start 103.603552 -242.376706)
		(end 103.608632 -242.3795)
		(stroke
			(width 0.05715)
			(type default)
		)
		(layer "In11.Cu")
	)
	(gr_line
		(start 103.603552 -240.756694)
		(end 103.608632 -240.759488)
		(stroke
			(width 0.05715)
			(type default)
		)
		(layer "In11.Cu")
	)
	(gr_line
		(start 103.603552 -239.136682)
		(end 103.608632 -239.139476)
		(stroke
			(width 0.05715)
			(type default)
		)
		(layer "In11.Cu")
	)
	(gr_line
		(start 103.603552 -237.51667)
		(end 103.608632 -237.519464)
		(stroke
			(width 0.05715)
			(type default)
		)
		(layer "In11.Cu")
	)
	(gr_line
		(start 103.603552 -235.896658)
		(end 103.607108 -235.89869)
		(stroke
			(width 0.05715)
			(type default)
		)
		(layer "In11.Cu")
	)
	(gr_line
		(start 103.60406 -228.771958)
		(end 103.603298 -228.772466)
		(stroke
			(width 0.05715)
			(type default)
		)
		(layer "In11.Cu")
	)
	(gr_line
		(start 103.605076 -228.77145)
		(end 103.60406 -228.771958)
		(stroke
			(width 0.05715)
			(type default)
		)
		(layer "In11.Cu")
	)
	(gr_line
		(start 103.6066 -228.770434)
		(end 103.605076 -228.77145)
		(stroke
			(width 0.05715)
			(type default)
		)
		(layer "In11.Cu")
	)
	(gr_line
		(start 103.607108 -235.89869)
		(end 103.608632 -235.899452)
		(stroke
			(width 0.05715)
			(type default)
		)
		(layer "In11.Cu")
	)
	(gr_line
		(start 103.607616 -228.769926)
		(end 103.6066 -228.770434)
		(stroke
			(width 0.05715)
			(type default)
		)
		(layer "In11.Cu")
	)
	(gr_line
		(start 103.608632 -242.3795)
		(end 103.609394 -242.380008)
		(stroke
			(width 0.05715)
			(type default)
		)
		(layer "In11.Cu")
	)
	(gr_line
		(start 103.608632 -240.759488)
		(end 103.609394 -240.759996)
		(stroke
			(width 0.05715)
			(type default)
		)
		(layer "In11.Cu")
	)
	(gr_line
		(start 103.608632 -239.139476)
		(end 103.609394 -239.139984)
		(stroke
			(width 0.05715)
			(type default)
		)
		(layer "In11.Cu")
	)
	(gr_line
		(start 103.608632 -237.519464)
		(end 103.609394 -237.519972)
		(stroke
			(width 0.05715)
			(type default)
		)
		(layer "In11.Cu")
	)
	(gr_line
		(start 103.609394 -242.380008)
		(end 103.61041 -242.380516)
		(stroke
			(width 0.05715)
			(type default)
		)
		(layer "In11.Cu")
	)
	(gr_line
		(start 103.609394 -240.759996)
		(end 103.61041 -240.760504)
		(stroke
			(width 0.05715)
			(type default)
		)
		(layer "In11.Cu")
	)
	(gr_line
		(start 103.609394 -239.139984)
		(end 103.61041 -239.140492)
		(stroke
			(width 0.05715)
			(type default)
		)
		(layer "In11.Cu")
	)
	(gr_line
		(start 103.609394 -237.519972)
		(end 103.61041 -237.52048)
		(stroke
			(width 0.05715)
			(type default)
		)
		(layer "In11.Cu")
	)
	(gr_line
		(start 103.612696 -228.766878)
		(end 103.607616 -228.769926)
		(stroke
			(width 0.05715)
			(type default)
		)
		(layer "In11.Cu")
	)
	(gr_line
		(start 103.61549 -221.083378)
		(end 103.66121 -221.129098)
		(stroke
			(width 0.05715)
			(type default)
		)
		(layer "In11.Cu")
	)
	(gr_line
		(start 103.61549 -221.05493)
		(end 103.61549 -221.083378)
		(stroke
			(width 0.05715)
			(type default)
		)
		(layer "In11.Cu")
	)
	(gr_line
		(start 103.619046 -247.724422)
		(end 103.321104 -247.724422)
		(stroke
			(width 0.05715)
			(type default)
		)
		(layer "In11.Cu")
	)
	(gr_line
		(start 103.619046 -246.10441)
		(end 103.321104 -246.10441)
		(stroke
			(width 0.05715)
			(type default)
		)
		(layer "In11.Cu")
	)
	(gr_line
		(start 103.619046 -244.484398)
		(end 103.321104 -244.484398)
		(stroke
			(width 0.05715)
			(type default)
		)
		(layer "In11.Cu")
	)
	(gr_line
		(start 103.625142 -241.719608)
		(end 103.624888 -241.719608)
		(stroke
			(width 0.05715)
			(type default)
		)
		(layer "In11.Cu")
	)
	(gr_line
		(start 103.625142 -240.099596)
		(end 103.624888 -240.099596)
		(stroke
			(width 0.05715)
			(type default)
		)
		(layer "In11.Cu")
	)
	(gr_line
		(start 103.625142 -238.479584)
		(end 103.624888 -238.479584)
		(stroke
			(width 0.05715)
			(type default)
		)
		(layer "In11.Cu")
	)
	(gr_line
		(start 103.625142 -236.859572)
		(end 103.624888 -236.859572)
		(stroke
			(width 0.05715)
			(type default)
		)
		(layer "In11.Cu")
	)
	(gr_line
		(start 103.625142 -235.23956)
		(end 103.624888 -235.23956)
		(stroke
			(width 0.05715)
			(type default)
		)
		(layer "In11.Cu")
	)
	(gr_line
		(start 103.633778 -224.5741)
		(end 103.640382 -224.57791)
		(stroke
			(width 0.05715)
			(type default)
		)
		(layer "In11.Cu")
	)
	(gr_line
		(start 103.634286 -235.914438)
		(end 103.635302 -235.914946)
		(stroke
			(width 0.05715)
			(type default)
		)
		(layer "In11.Cu")
	)
	(gr_line
		(start 103.63454 -242.39474)
		(end 103.642414 -242.399312)
		(stroke
			(width 0.05715)
			(type default)
		)
		(layer "In11.Cu")
	)
	(gr_line
		(start 103.63454 -240.774728)
		(end 103.642414 -240.7793)
		(stroke
			(width 0.05715)
			(type default)
		)
		(layer "In11.Cu")
	)
	(gr_line
		(start 103.63454 -239.154716)
		(end 103.642414 -239.159288)
		(stroke
			(width 0.05715)
			(type default)
		)
		(layer "In11.Cu")
	)
	(gr_line
		(start 103.63454 -237.534704)
		(end 103.642414 -237.539276)
		(stroke
			(width 0.05715)
			(type default)
		)
		(layer "In11.Cu")
	)
	(gr_line
		(start 103.634794 -245.635018)
		(end 103.642414 -245.639336)
		(stroke
			(width 0.05715)
			(type default)
		)
		(layer "In11.Cu")
	)
	(gr_line
		(start 103.635048 -241.713766)
		(end 103.633524 -241.714782)
		(stroke
			(width 0.05715)
			(type default)
		)
		(layer "In11.Cu")
	)
	(gr_line
		(start 103.635048 -240.093754)
		(end 103.633524 -240.09477)
		(stroke
			(width 0.05715)
			(type default)
		)
		(layer "In11.Cu")
	)
	(gr_line
		(start 103.635048 -238.473742)
		(end 103.633524 -238.474758)
		(stroke
			(width 0.05715)
			(type default)
		)
		(layer "In11.Cu")
	)
	(gr_line
		(start 103.635048 -236.85373)
		(end 103.633524 -236.854746)
		(stroke
			(width 0.05715)
			(type default)
		)
		(layer "In11.Cu")
	)
	(gr_line
		(start 103.635048 -235.233718)
		(end 103.633524 -235.234734)
		(stroke
			(width 0.05715)
			(type default)
		)
		(layer "In11.Cu")
	)
	(gr_line
		(start 103.635048 -234.29468)
		(end 103.63962 -234.29722)
		(stroke
			(width 0.05715)
			(type default)
		)
		(layer "In11.Cu")
	)
	(gr_line
		(start 103.635302 -235.914946)
		(end 103.636064 -235.915454)
		(stroke
			(width 0.05715)
			(type default)
		)
		(layer "In11.Cu")
	)
	(gr_line
		(start 103.636064 -235.915454)
		(end 103.642414 -235.919264)
		(stroke
			(width 0.05715)
			(type default)
		)
		(layer "In11.Cu")
	)
	(gr_line
		(start 103.63962 -234.29722)
		(end 103.642414 -234.299252)
		(stroke
			(width 0.05715)
			(type default)
		)
		(layer "In11.Cu")
	)
	(gr_line
		(start 103.640382 -227.131118)
		(end 103.635048 -227.134166)
		(stroke
			(width 0.05715)
			(type default)
		)
		(layer "In11.Cu")
	)
	(gr_line
		(start 103.640382 -224.57791)
		(end 103.643176 -224.579942)
		(stroke
			(width 0.05715)
			(type default)
		)
		(layer "In11.Cu")
	)
	(gr_arc
		(start 103.642414 -245.639336)
		(mid 103.642795 -245.63959)
		(end 103.643176 -245.639844)
		(stroke
			(width 0.05715)
			(type default)
		)
		(layer "In11.Cu")
	)
	(gr_arc
		(start 103.642414 -242.399312)
		(mid 103.642795 -242.399566)
		(end 103.643176 -242.39982)
		(stroke
			(width 0.05715)
			(type default)
		)
		(layer "In11.Cu")
	)
	(gr_arc
		(start 103.642414 -240.7793)
		(mid 103.642795 -240.779554)
		(end 103.643176 -240.779808)
		(stroke
			(width 0.05715)
			(type default)
		)
		(layer "In11.Cu")
	)
	(gr_arc
		(start 103.642414 -239.159288)
		(mid 103.642795 -239.159542)
		(end 103.643176 -239.159796)
		(stroke
			(width 0.05715)
			(type default)
		)
		(layer "In11.Cu")
	)
	(gr_arc
		(start 103.642414 -237.539276)
		(mid 103.642795 -237.53953)
		(end 103.643176 -237.539784)
		(stroke
			(width 0.05715)
			(type default)
		)
		(layer "In11.Cu")
	)
	(gr_arc
		(start 103.642414 -235.919264)
		(mid 103.642795 -235.919518)
		(end 103.643176 -235.919772)
		(stroke
			(width 0.05715)
			(type default)
		)
		(layer "In11.Cu")
	)
	(gr_arc
		(start 103.642414 -234.299252)
		(mid 103.642795 -234.299506)
		(end 103.643176 -234.29976)
		(stroke
			(width 0.05715)
			(type default)
		)
		(layer "In11.Cu")
	)
	(gr_line
		(start 103.643176 -227.129086)
		(end 103.640382 -227.131118)
		(stroke
			(width 0.05715)
			(type default)
		)
		(layer "In11.Cu")
	)
	(gr_arc
		(start 103.643176 -227.129086)
		(mid 103.647125 -227.126309)
		(end 103.65105 -227.123498)
		(stroke
			(width 0.05715)
			(type default)
		)
		(layer "In11.Cu")
	)
	(gr_arc
		(start 103.649526 -224.584514)
		(mid 103.646359 -224.582217)
		(end 103.643176 -224.579942)
		(stroke
			(width 0.05715)
			(type default)
		)
		(layer "In11.Cu")
	)
	(gr_arc
		(start 103.65105 -242.405408)
		(mid 103.647125 -242.402597)
		(end 103.643176 -242.39982)
		(stroke
			(width 0.05715)
			(type default)
		)
		(layer "In11.Cu")
	)
	(gr_arc
		(start 103.65105 -240.785396)
		(mid 103.647125 -240.782585)
		(end 103.643176 -240.779808)
		(stroke
			(width 0.05715)
			(type default)
		)
		(layer "In11.Cu")
	)
	(gr_arc
		(start 103.65105 -239.165384)
		(mid 103.647125 -239.162573)
		(end 103.643176 -239.159796)
		(stroke
			(width 0.05715)
			(type default)
		)
		(layer "In11.Cu")
	)
	(gr_arc
		(start 103.65105 -237.545372)
		(mid 103.647125 -237.542561)
		(end 103.643176 -237.539784)
		(stroke
			(width 0.05715)
			(type default)
		)
		(layer "In11.Cu")
	)
	(gr_arc
		(start 103.65105 -235.92536)
		(mid 103.647125 -235.922549)
		(end 103.643176 -235.919772)
		(stroke
			(width 0.05715)
			(type default)
		)
		(layer "In11.Cu")
	)
	(gr_arc
		(start 103.65105 -234.305348)
		(mid 103.647125 -234.302537)
		(end 103.643176 -234.29976)
		(stroke
			(width 0.05715)
			(type default)
		)
		(layer "In11.Cu")
	)
	(gr_arc
		(start 103.651304 -245.645432)
		(mid 103.647252 -245.64262)
		(end 103.643176 -245.639844)
		(stroke
			(width 0.05715)
			(type default)
		)
		(layer "In11.Cu")
	)
	(gr_arc
		(start 103.653844 -229.447344)
		(mid 103.650678 -229.445046)
		(end 103.647494 -229.442772)
		(stroke
			(width 0.05715)
			(type default)
		)
		(layer "In11.Cu")
	)
	(gr_line
		(start 103.67645 -370.336064)
		(end 103.67645 -370.33581)
		(stroke
			(width 0.07112)
			(type default)
		)
		(layer "In11.Cu")
	)
	(gr_line
		(start 103.688388 -246.035068)
		(end 103.619046 -246.10441)
		(stroke
			(width 0.05715)
			(type default)
		)
		(layer "In11.Cu")
	)
	(gr_line
		(start 103.688388 -244.415056)
		(end 103.619046 -244.484398)
		(stroke
			(width 0.05715)
			(type default)
		)
		(layer "In11.Cu")
	)
	(gr_line
		(start 103.70185 -247.641618)
		(end 103.619046 -247.724422)
		(stroke
			(width 0.05715)
			(type default)
		)
		(layer "In11.Cu")
	)
	(gr_arc
		(start 103.70566 -247.618758)
		(mid 103.703638 -247.630168)
		(end 103.70185 -247.641618)
		(stroke
			(width 0.05715)
			(type default)
		)
		(layer "In11.Cu")
	)
	(gr_line
		(start 103.708454 -277.389844)
		(end 103.7082 -277.39086)
		(stroke
			(width 0.05715)
			(type default)
		)
		(layer "In11.Cu")
	)
	(gr_line
		(start 103.805736 -281.05227)
		(end 103.804974 -281.051762)
		(stroke
			(width 0.05715)
			(type default)
		)
		(layer "In11.Cu")
	)
	(gr_line
		(start 103.808022 -294.658796)
		(end 103.80853 -294.658542)
		(stroke
			(width 0.05715)
			(type default)
		)
		(layer "In11.Cu")
	)
	(gr_line
		(start 103.808022 -278.45893)
		(end 103.808784 -278.458422)
		(stroke
			(width 0.05715)
			(type default)
		)
		(layer "In11.Cu")
	)
	(gr_line
		(start 103.808276 -293.03853)
		(end 103.808784 -293.038276)
		(stroke
			(width 0.05715)
			(type default)
		)
		(layer "In11.Cu")
	)
	(gr_line
		(start 103.808276 -291.418518)
		(end 103.808784 -291.418264)
		(stroke
			(width 0.05715)
			(type default)
		)
		(layer "In11.Cu")
	)
	(gr_line
		(start 103.808276 -289.798506)
		(end 103.808784 -289.798252)
		(stroke
			(width 0.05715)
			(type default)
		)
		(layer "In11.Cu")
	)
	(gr_line
		(start 103.808276 -284.938724)
		(end 103.808784 -284.93847)
		(stroke
			(width 0.05715)
			(type default)
		)
		(layer "In11.Cu")
	)
	(gr_line
		(start 103.808276 -283.318712)
		(end 103.808784 -283.318458)
		(stroke
			(width 0.05715)
			(type default)
		)
		(layer "In11.Cu")
	)
	(gr_line
		(start 103.808276 -281.6987)
		(end 103.808784 -281.698446)
		(stroke
			(width 0.05715)
			(type default)
		)
		(layer "In11.Cu")
	)
	(gr_line
		(start 103.808784 -294.014144)
		(end 103.808022 -294.013636)
		(stroke
			(width 0.05715)
			(type default)
		)
		(layer "In11.Cu")
	)
	(gr_line
		(start 103.808784 -293.038276)
		(end 103.810054 -293.037514)
		(stroke
			(width 0.05715)
			(type default)
		)
		(layer "In11.Cu")
	)
	(gr_line
		(start 103.808784 -292.394132)
		(end 103.808022 -292.393624)
		(stroke
			(width 0.05715)
			(type default)
		)
		(layer "In11.Cu")
	)
	(gr_line
		(start 103.808784 -291.418264)
		(end 103.810054 -291.417502)
		(stroke
			(width 0.05715)
			(type default)
		)
		(layer "In11.Cu")
	)
	(gr_line
		(start 103.808784 -290.77412)
		(end 103.808022 -290.773612)
		(stroke
			(width 0.05715)
			(type default)
		)
		(layer "In11.Cu")
	)
	(gr_line
		(start 103.808784 -289.798252)
		(end 103.810054 -289.79749)
		(stroke
			(width 0.05715)
			(type default)
		)
		(layer "In11.Cu")
	)
	(gr_line
		(start 103.808784 -285.914338)
		(end 103.808022 -285.91383)
		(stroke
			(width 0.05715)
			(type default)
		)
		(layer "In11.Cu")
	)
	(gr_line
		(start 103.808784 -284.93847)
		(end 103.810054 -284.937708)
		(stroke
			(width 0.05715)
			(type default)
		)
		(layer "In11.Cu")
	)
	(gr_line
		(start 103.808784 -284.294326)
		(end 103.808022 -284.293818)
		(stroke
			(width 0.05715)
			(type default)
		)
		(layer "In11.Cu")
	)
	(gr_line
		(start 103.808784 -283.318458)
		(end 103.810054 -283.317696)
		(stroke
			(width 0.05715)
			(type default)
		)
		(layer "In11.Cu")
	)
	(gr_line
		(start 103.808784 -282.674314)
		(end 103.808022 -282.673806)
		(stroke
			(width 0.05715)
			(type default)
		)
		(layer "In11.Cu")
	)
	(gr_line
		(start 103.808784 -281.698446)
		(end 103.810054 -281.697684)
		(stroke
			(width 0.05715)
			(type default)
		)
		(layer "In11.Cu")
	)
	(gr_line
		(start 103.808784 -281.054302)
		(end 103.805736 -281.05227)
		(stroke
			(width 0.05715)
			(type default)
		)
		(layer "In11.Cu")
	)
	(gr_line
		(start 103.808784 -278.458422)
		(end 103.810054 -278.45766)
		(stroke
			(width 0.05715)
			(type default)
		)
		(layer "In11.Cu")
	)
	(gr_line
		(start 103.809546 -281.05481)
		(end 103.808784 -281.054302)
		(stroke
			(width 0.05715)
			(type default)
		)
		(layer "In11.Cu")
	)
	(gr_line
		(start 103.810054 -294.014906)
		(end 103.808784 -294.014144)
		(stroke
			(width 0.05715)
			(type default)
		)
		(layer "In11.Cu")
	)
	(gr_line
		(start 103.810054 -292.394894)
		(end 103.808784 -292.394132)
		(stroke
			(width 0.05715)
			(type default)
		)
		(layer "In11.Cu")
	)
	(gr_line
		(start 103.810054 -290.774882)
		(end 103.808784 -290.77412)
		(stroke
			(width 0.05715)
			(type default)
		)
		(layer "In11.Cu")
	)
	(gr_line
		(start 103.810054 -285.9151)
		(end 103.808784 -285.914338)
		(stroke
			(width 0.05715)
			(type default)
		)
		(layer "In11.Cu")
	)
	(gr_line
		(start 103.810054 -284.295088)
		(end 103.808784 -284.294326)
		(stroke
			(width 0.05715)
			(type default)
		)
		(layer "In11.Cu")
	)
	(gr_line
		(start 103.810054 -282.675076)
		(end 103.808784 -282.674314)
		(stroke
			(width 0.05715)
			(type default)
		)
		(layer "In11.Cu")
	)
	(gr_line
		(start 103.814118 -294.017192)
		(end 103.812594 -294.016176)
		(stroke
			(width 0.05715)
			(type default)
		)
		(layer "In11.Cu")
	)
	(gr_line
		(start 103.814118 -292.39718)
		(end 103.812594 -292.396164)
		(stroke
			(width 0.05715)
			(type default)
		)
		(layer "In11.Cu")
	)
	(gr_line
		(start 103.814118 -290.777168)
		(end 103.812594 -290.776152)
		(stroke
			(width 0.05715)
			(type default)
		)
		(layer "In11.Cu")
	)
	(gr_line
		(start 103.814118 -285.917386)
		(end 103.812594 -285.91637)
		(stroke
			(width 0.05715)
			(type default)
		)
		(layer "In11.Cu")
	)
	(gr_line
		(start 103.814118 -284.297374)
		(end 103.812594 -284.296358)
		(stroke
			(width 0.05715)
			(type default)
		)
		(layer "In11.Cu")
	)
	(gr_line
		(start 103.814118 -282.677362)
		(end 103.812594 -282.676346)
		(stroke
			(width 0.05715)
			(type default)
		)
		(layer "In11.Cu")
	)
	(gr_line
		(start 103.814118 -281.05735)
		(end 103.812594 -281.056334)
		(stroke
			(width 0.05715)
			(type default)
		)
		(layer "In11.Cu")
	)
	(gr_line
		(start 103.815642 -294.017954)
		(end 103.814118 -294.017192)
		(stroke
			(width 0.05715)
			(type default)
		)
		(layer "In11.Cu")
	)
	(gr_line
		(start 103.815642 -292.397942)
		(end 103.814118 -292.39718)
		(stroke
			(width 0.05715)
			(type default)
		)
		(layer "In11.Cu")
	)
	(gr_line
		(start 103.815642 -290.77793)
		(end 103.814118 -290.777168)
		(stroke
			(width 0.05715)
			(type default)
		)
		(layer "In11.Cu")
	)
	(gr_line
		(start 103.815642 -285.918148)
		(end 103.814118 -285.917386)
		(stroke
			(width 0.05715)
			(type default)
		)
		(layer "In11.Cu")
	)
	(gr_line
		(start 103.815642 -284.298136)
		(end 103.814118 -284.297374)
		(stroke
			(width 0.05715)
			(type default)
		)
		(layer "In11.Cu")
	)
	(gr_line
		(start 103.815642 -282.678124)
		(end 103.814118 -282.677362)
		(stroke
			(width 0.05715)
			(type default)
		)
		(layer "In11.Cu")
	)
	(gr_line
		(start 103.815642 -281.058112)
		(end 103.814118 -281.05735)
		(stroke
			(width 0.05715)
			(type default)
		)
		(layer "In11.Cu")
	)
	(gr_arc
		(start 103.880412 -246.021606)
		(mid 103.87862 -246.010284)
		(end 103.876602 -245.999)
		(stroke
			(width 0.05715)
			(type default)
		)
		(layer "In11.Cu")
	)
	(gr_line
		(start 103.880412 -246.021606)
		(end 103.963216 -246.10441)
		(stroke
			(width 0.05715)
			(type default)
		)
		(layer "In11.Cu")
	)
	(gr_arc
		(start 103.880412 -244.401594)
		(mid 103.878619 -244.390272)
		(end 103.876602 -244.378988)
		(stroke
			(width 0.05715)
			(type default)
		)
		(layer "In11.Cu")
	)
	(gr_line
		(start 103.880412 -244.401594)
		(end 103.963216 -244.484398)
		(stroke
			(width 0.05715)
			(type default)
		)
		(layer "In11.Cu")
	)
	(gr_line
		(start 103.893874 -247.65508)
		(end 103.963216 -247.724422)
		(stroke
			(width 0.05715)
			(type default)
		)
		(layer "In11.Cu")
	)
	(gr_line
		(start 103.89743 -221.083378)
		(end 103.85171 -221.129098)
		(stroke
			(width 0.05715)
			(type default)
		)
		(layer "In11.Cu")
	)
	(gr_line
		(start 103.89743 -221.05493)
		(end 103.89743 -221.083378)
		(stroke
			(width 0.05715)
			(type default)
		)
		(layer "In11.Cu")
	)
	(gr_line
		(start 103.89997 -280.886662)
		(end 103.8987 -280.8859)
		(stroke
			(width 0.05715)
			(type default)
		)
		(layer "In11.Cu")
	)
	(gr_line
		(start 103.903272 -280.88844)
		(end 103.89997 -280.886662)
		(stroke
			(width 0.05715)
			(type default)
		)
		(layer "In11.Cu")
	)
	(gr_line
		(start 103.903526 -278.623776)
		(end 103.904034 -278.623776)
		(stroke
			(width 0.05715)
			(type default)
		)
		(layer "In11.Cu")
	)
	(gr_line
		(start 103.904034 -293.20363)
		(end 103.90505 -293.203122)
		(stroke
			(width 0.05715)
			(type default)
		)
		(layer "In11.Cu")
	)
	(gr_line
		(start 103.904034 -291.583618)
		(end 103.90505 -291.58311)
		(stroke
			(width 0.05715)
			(type default)
		)
		(layer "In11.Cu")
	)
	(gr_line
		(start 103.904034 -289.963606)
		(end 103.90505 -289.963098)
		(stroke
			(width 0.05715)
			(type default)
		)
		(layer "In11.Cu")
	)
	(gr_line
		(start 103.904034 -285.103824)
		(end 103.90505 -285.103316)
		(stroke
			(width 0.05715)
			(type default)
		)
		(layer "In11.Cu")
	)
	(gr_line
		(start 103.904034 -283.483812)
		(end 103.90505 -283.483304)
		(stroke
			(width 0.05715)
			(type default)
		)
		(layer "In11.Cu")
	)
	(gr_line
		(start 103.904034 -281.8638)
		(end 103.90505 -281.863292)
		(stroke
			(width 0.05715)
			(type default)
		)
		(layer "In11.Cu")
	)
	(gr_line
		(start 103.904034 -280.888948)
		(end 103.903272 -280.88844)
		(stroke
			(width 0.05715)
			(type default)
		)
		(layer "In11.Cu")
	)
	(gr_line
		(start 103.904034 -278.623776)
		(end 103.90505 -278.623268)
		(stroke
			(width 0.05715)
			(type default)
		)
		(layer "In11.Cu")
	)
	(gr_line
		(start 103.90505 -280.889456)
		(end 103.904034 -280.888948)
		(stroke
			(width 0.05715)
			(type default)
		)
		(layer "In11.Cu")
	)
	(gr_line
		(start 103.906828 -280.890472)
		(end 103.90505 -280.889456)
		(stroke
			(width 0.05715)
			(type default)
		)
		(layer "In11.Cu")
	)
	(gr_line
		(start 103.909114 -293.851838)
		(end 103.908352 -293.85133)
		(stroke
			(width 0.05715)
			(type default)
		)
		(layer "In11.Cu")
	)
	(gr_line
		(start 103.909114 -292.231826)
		(end 103.908352 -292.231318)
		(stroke
			(width 0.05715)
			(type default)
		)
		(layer "In11.Cu")
	)
	(gr_line
		(start 103.909114 -290.611814)
		(end 103.908352 -290.611306)
		(stroke
			(width 0.05715)
			(type default)
		)
		(layer "In11.Cu")
	)
	(gr_line
		(start 103.909114 -285.752032)
		(end 103.908352 -285.751524)
		(stroke
			(width 0.05715)
			(type default)
		)
		(layer "In11.Cu")
	)
	(gr_line
		(start 103.909114 -284.13202)
		(end 103.908352 -284.131512)
		(stroke
			(width 0.05715)
			(type default)
		)
		(layer "In11.Cu")
	)
	(gr_line
		(start 103.909114 -282.512008)
		(end 103.908352 -282.5115)
		(stroke
			(width 0.05715)
			(type default)
		)
		(layer "In11.Cu")
	)
	(gr_line
		(start 103.909114 -280.891996)
		(end 103.908352 -280.891488)
		(stroke
			(width 0.05715)
			(type default)
		)
		(layer "In11.Cu")
	)
	(gr_line
		(start 103.91902 -278.13635)
		(end 103.621078 -278.13635)
		(stroke
			(width 0.05715)
			(type default)
		)
		(layer "In11.Cu")
	)
	(gr_line
		(start 103.91902 -276.516338)
		(end 103.621078 -276.516338)
		(stroke
			(width 0.05715)
			(type default)
		)
		(layer "In11.Cu")
	)
	(gr_line
		(start 103.91902 -274.896326)
		(end 103.621078 -274.896326)
		(stroke
			(width 0.05715)
			(type default)
		)
		(layer "In11.Cu")
	)
	(gr_line
		(start 103.93553 -293.867078)
		(end 103.934768 -293.86657)
		(stroke
			(width 0.05715)
			(type default)
		)
		(layer "In11.Cu")
	)
	(gr_line
		(start 103.93553 -292.247066)
		(end 103.934768 -292.246558)
		(stroke
			(width 0.05715)
			(type default)
		)
		(layer "In11.Cu")
	)
	(gr_line
		(start 103.93553 -290.627054)
		(end 103.934768 -290.626546)
		(stroke
			(width 0.05715)
			(type default)
		)
		(layer "In11.Cu")
	)
	(gr_line
		(start 103.93553 -285.767272)
		(end 103.934768 -285.766764)
		(stroke
			(width 0.05715)
			(type default)
		)
		(layer "In11.Cu")
	)
	(gr_line
		(start 103.93553 -284.14726)
		(end 103.934768 -284.146752)
		(stroke
			(width 0.05715)
			(type default)
		)
		(layer "In11.Cu")
	)
	(gr_line
		(start 103.93553 -282.527248)
		(end 103.934768 -282.52674)
		(stroke
			(width 0.05715)
			(type default)
		)
		(layer "In11.Cu")
	)
	(gr_line
		(start 103.93553 -280.907236)
		(end 103.934768 -280.906728)
		(stroke
			(width 0.05715)
			(type default)
		)
		(layer "In11.Cu")
	)
	(gr_line
		(start 103.936292 -293.867586)
		(end 103.93553 -293.867078)
		(stroke
			(width 0.05715)
			(type default)
		)
		(layer "In11.Cu")
	)
	(gr_line
		(start 103.936292 -292.247574)
		(end 103.93553 -292.247066)
		(stroke
			(width 0.05715)
			(type default)
		)
		(layer "In11.Cu")
	)
	(gr_line
		(start 103.936292 -290.627562)
		(end 103.93553 -290.627054)
		(stroke
			(width 0.05715)
			(type default)
		)
		(layer "In11.Cu")
	)
	(gr_line
		(start 103.936292 -285.76778)
		(end 103.93553 -285.767272)
		(stroke
			(width 0.05715)
			(type default)
		)
		(layer "In11.Cu")
	)
	(gr_line
		(start 103.936292 -284.147768)
		(end 103.93553 -284.14726)
		(stroke
			(width 0.05715)
			(type default)
		)
		(layer "In11.Cu")
	)
	(gr_line
		(start 103.936292 -282.527756)
		(end 103.93553 -282.527248)
		(stroke
			(width 0.05715)
			(type default)
		)
		(layer "In11.Cu")
	)
	(gr_line
		(start 103.936292 -280.907744)
		(end 103.93553 -280.907236)
		(stroke
			(width 0.05715)
			(type default)
		)
		(layer "In11.Cu")
	)
	(gr_line
		(start 103.942388 -289.011106)
		(end 103.935276 -289.007042)
		(stroke
			(width 0.05715)
			(type default)
		)
		(layer "In11.Cu")
	)
	(gr_arc
		(start 103.942388 -289.011106)
		(mid 103.942769 -289.01136)
		(end 103.94315 -289.011614)
		(stroke
			(width 0.05715)
			(type default)
		)
		(layer "In11.Cu")
	)
	(gr_line
		(start 103.94315 -293.87165)
		(end 103.936292 -293.867586)
		(stroke
			(width 0.05715)
			(type default)
		)
		(layer "In11.Cu")
	)
	(gr_line
		(start 103.94315 -292.251638)
		(end 103.936292 -292.247574)
		(stroke
			(width 0.05715)
			(type default)
		)
		(layer "In11.Cu")
	)
	(gr_line
		(start 103.94315 -290.631626)
		(end 103.936292 -290.627562)
		(stroke
			(width 0.05715)
			(type default)
		)
		(layer "In11.Cu")
	)
	(gr_line
		(start 103.94315 -285.771844)
		(end 103.936292 -285.76778)
		(stroke
			(width 0.05715)
			(type default)
		)
		(layer "In11.Cu")
	)
	(gr_line
		(start 103.94315 -284.151832)
		(end 103.936292 -284.147768)
		(stroke
			(width 0.05715)
			(type default)
		)
		(layer "In11.Cu")
	)
	(gr_line
		(start 103.94315 -282.53182)
		(end 103.936292 -282.527756)
		(stroke
			(width 0.05715)
			(type default)
		)
		(layer "In11.Cu")
	)
	(gr_line
		(start 103.94315 -280.911808)
		(end 103.936292 -280.907744)
		(stroke
			(width 0.05715)
			(type default)
		)
		(layer "In11.Cu")
	)
	(gr_arc
		(start 103.951024 -293.877238)
		(mid 103.947099 -293.874427)
		(end 103.94315 -293.87165)
		(stroke
			(width 0.05715)
			(type default)
		)
		(layer "In11.Cu")
	)
	(gr_arc
		(start 103.951024 -292.257226)
		(mid 103.947099 -292.254415)
		(end 103.94315 -292.251638)
		(stroke
			(width 0.05715)
			(type default)
		)
		(layer "In11.Cu")
	)
	(gr_arc
		(start 103.951024 -290.637214)
		(mid 103.947099 -290.634403)
		(end 103.94315 -290.631626)
		(stroke
			(width 0.05715)
			(type default)
		)
		(layer "In11.Cu")
	)
	(gr_arc
		(start 103.951024 -289.017202)
		(mid 103.947099 -289.014391)
		(end 103.94315 -289.011614)
		(stroke
			(width 0.05715)
			(type default)
		)
		(layer "In11.Cu")
	)
	(gr_arc
		(start 103.951024 -285.777432)
		(mid 103.947099 -285.774621)
		(end 103.94315 -285.771844)
		(stroke
			(width 0.05715)
			(type default)
		)
		(layer "In11.Cu")
	)
	(gr_arc
		(start 103.951024 -284.15742)
		(mid 103.947099 -284.154609)
		(end 103.94315 -284.151832)
		(stroke
			(width 0.05715)
			(type default)
		)
		(layer "In11.Cu")
	)
	(gr_arc
		(start 103.951024 -282.537408)
		(mid 103.947099 -282.534597)
		(end 103.94315 -282.53182)
		(stroke
			(width 0.05715)
			(type default)
		)
		(layer "In11.Cu")
	)
	(gr_arc
		(start 103.951024 -280.917396)
		(mid 103.947099 -280.914585)
		(end 103.94315 -280.911808)
		(stroke
			(width 0.05715)
			(type default)
		)
		(layer "In11.Cu")
	)
	(gr_line
		(start 103.963216 -247.724422)
		(end 104.261158 -247.724422)
		(stroke
			(width 0.05715)
			(type default)
		)
		(layer "In11.Cu")
	)
	(gr_line
		(start 103.963216 -246.10441)
		(end 104.261158 -246.10441)
		(stroke
			(width 0.05715)
			(type default)
		)
		(layer "In11.Cu")
	)
	(gr_line
		(start 103.963216 -244.484398)
		(end 104.261158 -244.484398)
		(stroke
			(width 0.05715)
			(type default)
		)
		(layer "In11.Cu")
	)
	(gr_line
		(start 103.9749 -225.529902)
		(end 103.975662 -225.53041)
		(stroke
			(width 0.05715)
			(type default)
		)
		(layer "In11.Cu")
	)
	(gr_line
		(start 103.975662 -225.53041)
		(end 103.978202 -225.531934)
		(stroke
			(width 0.05715)
			(type default)
		)
		(layer "In11.Cu")
	)
	(gr_line
		(start 103.988362 -278.205692)
		(end 103.91902 -278.13635)
		(stroke
			(width 0.05715)
			(type default)
		)
		(layer "In11.Cu")
	)
	(gr_line
		(start 103.988362 -276.58568)
		(end 103.91902 -276.516338)
		(stroke
			(width 0.05715)
			(type default)
		)
		(layer "In11.Cu")
	)
	(gr_line
		(start 104.001824 -274.97913)
		(end 103.91902 -274.896326)
		(stroke
			(width 0.05715)
			(type default)
		)
		(layer "In11.Cu")
	)
	(gr_arc
		(start 104.001824 -274.97913)
		(mid 104.003612 -274.99058)
		(end 104.005634 -275.00199)
		(stroke
			(width 0.05715)
			(type default)
		)
		(layer "In11.Cu")
	)
	(gr_line
		(start 104.026716 -296.371264)
		(end 104.026716 -296.342816)
		(stroke
			(width 0.05715)
			(type default)
		)
		(layer "In11.Cu")
	)
	(gr_line
		(start 104.026716 -296.342816)
		(end 104.072436 -296.297096)
		(stroke
			(width 0.05715)
			(type default)
		)
		(layer "In11.Cu")
	)
	(gr_line
		(start 104.071674 -225.365564)
		(end 104.073452 -225.36658)
		(stroke
			(width 0.05715)
			(type default)
		)
		(layer "In11.Cu")
	)
	(gr_line
		(start 104.073452 -225.36658)
		(end 104.074214 -225.367088)
		(stroke
			(width 0.05715)
			(type default)
		)
		(layer "In11.Cu")
	)
	(gr_line
		(start 104.104948 -225.384868)
		(end 104.10571 -225.385376)
		(stroke
			(width 0.05715)
			(type default)
		)
		(layer "In11.Cu")
	)
	(gr_line
		(start 104.10571 -225.385376)
		(end 104.11333 -225.389948)
		(stroke
			(width 0.05715)
			(type default)
		)
		(layer "In11.Cu")
	)
	(gr_arc
		(start 104.121204 -225.395536)
		(mid 104.117279 -225.392725)
		(end 104.11333 -225.389948)
		(stroke
			(width 0.05715)
			(type default)
		)
		(layer "In11.Cu")
	)
	(gr_arc
		(start 104.176576 -278.242014)
		(mid 104.178597 -278.230603)
		(end 104.180386 -278.219154)
		(stroke
			(width 0.05715)
			(type default)
		)
		(layer "In11.Cu")
	)
	(gr_arc
		(start 104.176576 -276.622002)
		(mid 104.178597 -276.610591)
		(end 104.180386 -276.599142)
		(stroke
			(width 0.05715)
			(type default)
		)
		(layer "In11.Cu")
	)
	(gr_line
		(start 104.180386 -278.219154)
		(end 104.26319 -278.13635)
		(stroke
			(width 0.05715)
			(type default)
		)
		(layer "In11.Cu")
	)
	(gr_line
		(start 104.180386 -276.599142)
		(end 104.26319 -276.516338)
		(stroke
			(width 0.05715)
			(type default)
		)
		(layer "In11.Cu")
	)
	(gr_line
		(start 104.193848 -274.965668)
		(end 104.26319 -274.896326)
		(stroke
			(width 0.05715)
			(type default)
		)
		(layer "In11.Cu")
	)
	(gr_line
		(start 104.26319 -278.13635)
		(end 104.561132 -278.13635)
		(stroke
			(width 0.05715)
			(type default)
		)
		(layer "In11.Cu")
	)
	(gr_line
		(start 104.26319 -276.516338)
		(end 104.561132 -276.516338)
		(stroke
			(width 0.05715)
			(type default)
		)
		(layer "In11.Cu")
	)
	(gr_line
		(start 104.26319 -274.896326)
		(end 104.561132 -274.896326)
		(stroke
			(width 0.05715)
			(type default)
		)
		(layer "In11.Cu")
	)
	(gr_line
		(start 104.275636 -295.590468)
		(end 104.275636 -295.590214)
		(stroke
			(width 0.05715)
			(type default)
		)
		(layer "In11.Cu")
	)
	(gr_line
		(start 104.308656 -296.371264)
		(end 104.308656 -296.342816)
		(stroke
			(width 0.05715)
			(type default)
		)
		(layer "In11.Cu")
	)
	(gr_line
		(start 104.308656 -296.342816)
		(end 104.262936 -296.297096)
		(stroke
			(width 0.05715)
			(type default)
		)
		(layer "In11.Cu")
	)
	(gr_arc
		(start 104.408986 -223.769936)
		(mid 104.405803 -223.772211)
		(end 104.402636 -223.774508)
		(stroke
			(width 0.05715)
			(type default)
		)
		(layer "In11.Cu")
	)
	(gr_line
		(start 104.41178 -223.767904)
		(end 104.408986 -223.769936)
		(stroke
			(width 0.05715)
			(type default)
		)
		(layer "In11.Cu")
	)
	(gr_line
		(start 104.417876 -223.764348)
		(end 104.41178 -223.767904)
		(stroke
			(width 0.05715)
			(type default)
		)
		(layer "In11.Cu")
	)
	(gr_line
		(start 104.448102 -244.161818)
		(end 104.448864 -244.162326)
		(stroke
			(width 0.05715)
			(type default)
		)
		(layer "In11.Cu")
	)
	(gr_line
		(start 104.448102 -240.921794)
		(end 104.448864 -240.922302)
		(stroke
			(width 0.05715)
			(type default)
		)
		(layer "In11.Cu")
	)
	(gr_line
		(start 104.448102 -239.301782)
		(end 104.448864 -239.30229)
		(stroke
			(width 0.05715)
			(type default)
		)
		(layer "In11.Cu")
	)
	(gr_line
		(start 104.448102 -236.061758)
		(end 104.448864 -236.062266)
		(stroke
			(width 0.05715)
			(type default)
		)
		(layer "In11.Cu")
	)
	(gr_line
		(start 104.448102 -234.441746)
		(end 104.448864 -234.442254)
		(stroke
			(width 0.05715)
			(type default)
		)
		(layer "In11.Cu")
	)
	(gr_line
		(start 104.448102 -232.821734)
		(end 104.448864 -232.822242)
		(stroke
			(width 0.05715)
			(type default)
		)
		(layer "In11.Cu")
	)
	(gr_line
		(start 104.450642 -246.42572)
		(end 104.448356 -246.42699)
		(stroke
			(width 0.05715)
			(type default)
		)
		(layer "In11.Cu")
	)
	(gr_line
		(start 104.450642 -244.805708)
		(end 104.448356 -244.806978)
		(stroke
			(width 0.05715)
			(type default)
		)
		(layer "In11.Cu")
	)
	(gr_line
		(start 104.450642 -243.185696)
		(end 104.448356 -243.186966)
		(stroke
			(width 0.05715)
			(type default)
		)
		(layer "In11.Cu")
	)
	(gr_line
		(start 104.450642 -241.565684)
		(end 104.448356 -241.566954)
		(stroke
			(width 0.05715)
			(type default)
		)
		(layer "In11.Cu")
	)
	(gr_line
		(start 104.450642 -239.945672)
		(end 104.448356 -239.946942)
		(stroke
			(width 0.05715)
			(type default)
		)
		(layer "In11.Cu")
	)
	(gr_line
		(start 104.450642 -236.705648)
		(end 104.448356 -236.706918)
		(stroke
			(width 0.05715)
			(type default)
		)
		(layer "In11.Cu")
	)
	(gr_line
		(start 104.450642 -235.085636)
		(end 104.448356 -235.086906)
		(stroke
			(width 0.05715)
			(type default)
		)
		(layer "In11.Cu")
	)
	(gr_line
		(start 104.450642 -233.465624)
		(end 104.448356 -233.466894)
		(stroke
			(width 0.05715)
			(type default)
		)
		(layer "In11.Cu")
	)
	(gr_line
		(start 104.450642 -231.845612)
		(end 104.448356 -231.846882)
		(stroke
			(width 0.05715)
			(type default)
		)
		(layer "In11.Cu")
	)
	(gr_line
		(start 104.454198 -244.165374)
		(end 104.456738 -244.166644)
		(stroke
			(width 0.05715)
			(type default)
		)
		(layer "In11.Cu")
	)
	(gr_line
		(start 104.454198 -240.92535)
		(end 104.456738 -240.92662)
		(stroke
			(width 0.05715)
			(type default)
		)
		(layer "In11.Cu")
	)
	(gr_line
		(start 104.454198 -239.305338)
		(end 104.456738 -239.306608)
		(stroke
			(width 0.05715)
			(type default)
		)
		(layer "In11.Cu")
	)
	(gr_line
		(start 104.454198 -236.065314)
		(end 104.456738 -236.066584)
		(stroke
			(width 0.05715)
			(type default)
		)
		(layer "In11.Cu")
	)
	(gr_line
		(start 104.454198 -234.445302)
		(end 104.456738 -234.446572)
		(stroke
			(width 0.05715)
			(type default)
		)
		(layer "In11.Cu")
	)
	(gr_line
		(start 104.454198 -232.82529)
		(end 104.456738 -232.82656)
		(stroke
			(width 0.05715)
			(type default)
		)
		(layer "In11.Cu")
	)
	(gr_line
		(start 104.465628 -286.992314)
		(end 104.465628 -286.991044)
		(stroke
			(width 0.05715)
			(type default)
		)
		(layer "In11.Cu")
	)
	(gr_line
		(start 104.472232 -228.593142)
		(end 104.470454 -228.594158)
		(stroke
			(width 0.05715)
			(type default)
		)
		(layer "In11.Cu")
	)
	(gr_line
		(start 104.535732 -246.596662)
		(end 104.532176 -246.598694)
		(stroke
			(width 0.05715)
			(type default)
		)
		(layer "In11.Cu")
	)
	(gr_line
		(start 104.535732 -244.97665)
		(end 104.532176 -244.978682)
		(stroke
			(width 0.05715)
			(type default)
		)
		(layer "In11.Cu")
	)
	(gr_line
		(start 104.535732 -243.356638)
		(end 104.532176 -243.35867)
		(stroke
			(width 0.05715)
			(type default)
		)
		(layer "In11.Cu")
	)
	(gr_line
		(start 104.535732 -241.736626)
		(end 104.532176 -241.738658)
		(stroke
			(width 0.05715)
			(type default)
		)
		(layer "In11.Cu")
	)
	(gr_line
		(start 104.535732 -240.116614)
		(end 104.532176 -240.118646)
		(stroke
			(width 0.05715)
			(type default)
		)
		(layer "In11.Cu")
	)
	(gr_line
		(start 104.535732 -236.87659)
		(end 104.532176 -236.878622)
		(stroke
			(width 0.05715)
			(type default)
		)
		(layer "In11.Cu")
	)
	(gr_line
		(start 104.535732 -235.256578)
		(end 104.532176 -235.25861)
		(stroke
			(width 0.05715)
			(type default)
		)
		(layer "In11.Cu")
	)
	(gr_line
		(start 104.535732 -233.636566)
		(end 104.532176 -233.638598)
		(stroke
			(width 0.05715)
			(type default)
		)
		(layer "In11.Cu")
	)
	(gr_line
		(start 104.535732 -232.016554)
		(end 104.532176 -232.018586)
		(stroke
			(width 0.05715)
			(type default)
		)
		(layer "In11.Cu")
	)
	(gr_line
		(start 104.542082 -243.995702)
		(end 104.543352 -243.996464)
		(stroke
			(width 0.05715)
			(type default)
		)
		(layer "In11.Cu")
	)
	(gr_line
		(start 104.542082 -240.755678)
		(end 104.543352 -240.75644)
		(stroke
			(width 0.05715)
			(type default)
		)
		(layer "In11.Cu")
	)
	(gr_line
		(start 104.542082 -239.135666)
		(end 104.543352 -239.136428)
		(stroke
			(width 0.05715)
			(type default)
		)
		(layer "In11.Cu")
	)
	(gr_line
		(start 104.542082 -235.895642)
		(end 104.543352 -235.896404)
		(stroke
			(width 0.05715)
			(type default)
		)
		(layer "In11.Cu")
	)
	(gr_line
		(start 104.542082 -234.27563)
		(end 104.543352 -234.276392)
		(stroke
			(width 0.05715)
			(type default)
		)
		(layer "In11.Cu")
	)
	(gr_line
		(start 104.542082 -232.655618)
		(end 104.543352 -232.65638)
		(stroke
			(width 0.05715)
			(type default)
		)
		(layer "In11.Cu")
	)
	(gr_arc
		(start 104.542844 -222.292418)
		(mid 104.543225 -222.292164)
		(end 104.543606 -222.29191)
		(stroke
			(width 0.05715)
			(type default)
		)
		(layer "In11.Cu")
	)
	(gr_line
		(start 104.543352 -243.996464)
		(end 104.54513 -243.99748)
		(stroke
			(width 0.05715)
			(type default)
		)
		(layer "In11.Cu")
	)
	(gr_line
		(start 104.543352 -240.75644)
		(end 104.54513 -240.757456)
		(stroke
			(width 0.05715)
			(type default)
		)
		(layer "In11.Cu")
	)
	(gr_line
		(start 104.543352 -239.136428)
		(end 104.54513 -239.137444)
		(stroke
			(width 0.05715)
			(type default)
		)
		(layer "In11.Cu")
	)
	(gr_line
		(start 104.543352 -235.896404)
		(end 104.54513 -235.89742)
		(stroke
			(width 0.05715)
			(type default)
		)
		(layer "In11.Cu")
	)
	(gr_line
		(start 104.543352 -234.276392)
		(end 104.54513 -234.277408)
		(stroke
			(width 0.05715)
			(type default)
		)
		(layer "In11.Cu")
	)
	(gr_line
		(start 104.543352 -232.65638)
		(end 104.54513 -232.657396)
		(stroke
			(width 0.05715)
			(type default)
		)
		(layer "In11.Cu")
	)
	(gr_line
		(start 104.54513 -243.99748)
		(end 104.547162 -243.99875)
		(stroke
			(width 0.05715)
			(type default)
		)
		(layer "In11.Cu")
	)
	(gr_line
		(start 104.54513 -240.757456)
		(end 104.547162 -240.758726)
		(stroke
			(width 0.05715)
			(type default)
		)
		(layer "In11.Cu")
	)
	(gr_line
		(start 104.54513 -239.137444)
		(end 104.547162 -239.138714)
		(stroke
			(width 0.05715)
			(type default)
		)
		(layer "In11.Cu")
	)
	(gr_line
		(start 104.54513 -235.89742)
		(end 104.547162 -235.89869)
		(stroke
			(width 0.05715)
			(type default)
		)
		(layer "In11.Cu")
	)
	(gr_line
		(start 104.54513 -234.277408)
		(end 104.547162 -234.278678)
		(stroke
			(width 0.05715)
			(type default)
		)
		(layer "In11.Cu")
	)
	(gr_line
		(start 104.54513 -232.657396)
		(end 104.547162 -232.658666)
		(stroke
			(width 0.05715)
			(type default)
		)
		(layer "In11.Cu")
	)
	(gr_line
		(start 104.546146 -222.290386)
		(end 104.543606 -222.29191)
		(stroke
			(width 0.05715)
			(type default)
		)
		(layer "In11.Cu")
	)
	(gr_line
		(start 104.548432 -243.999512)
		(end 104.549194 -244.00002)
		(stroke
			(width 0.05715)
			(type default)
		)
		(layer "In11.Cu")
	)
	(gr_line
		(start 104.548432 -240.759488)
		(end 104.549194 -240.759996)
		(stroke
			(width 0.05715)
			(type default)
		)
		(layer "In11.Cu")
	)
	(gr_line
		(start 104.548432 -239.139476)
		(end 104.549194 -239.139984)
		(stroke
			(width 0.05715)
			(type default)
		)
		(layer "In11.Cu")
	)
	(gr_line
		(start 104.548432 -235.899452)
		(end 104.549194 -235.89996)
		(stroke
			(width 0.05715)
			(type default)
		)
		(layer "In11.Cu")
	)
	(gr_line
		(start 104.548432 -234.27944)
		(end 104.549194 -234.279948)
		(stroke
			(width 0.05715)
			(type default)
		)
		(layer "In11.Cu")
	)
	(gr_line
		(start 104.548432 -232.659428)
		(end 104.549194 -232.659936)
		(stroke
			(width 0.05715)
			(type default)
		)
		(layer "In11.Cu")
	)
	(gr_line
		(start 104.549194 -244.00002)
		(end 104.55021 -244.000528)
		(stroke
			(width 0.05715)
			(type default)
		)
		(layer "In11.Cu")
	)
	(gr_line
		(start 104.549194 -240.759996)
		(end 104.55021 -240.760504)
		(stroke
			(width 0.05715)
			(type default)
		)
		(layer "In11.Cu")
	)
	(gr_line
		(start 104.549194 -239.139984)
		(end 104.55021 -239.140492)
		(stroke
			(width 0.05715)
			(type default)
		)
		(layer "In11.Cu")
	)
	(gr_line
		(start 104.549194 -235.89996)
		(end 104.55021 -235.900468)
		(stroke
			(width 0.05715)
			(type default)
		)
		(layer "In11.Cu")
	)
	(gr_line
		(start 104.549194 -234.279948)
		(end 104.55021 -234.280456)
		(stroke
			(width 0.05715)
			(type default)
		)
		(layer "In11.Cu")
	)
	(gr_line
		(start 104.549194 -232.659936)
		(end 104.55021 -232.660444)
		(stroke
			(width 0.05715)
			(type default)
		)
		(layer "In11.Cu")
	)
	(gr_line
		(start 104.56545 -294.825674)
		(end 104.565196 -294.825674)
		(stroke
			(width 0.05715)
			(type default)
		)
		(layer "In11.Cu")
	)
	(gr_line
		(start 104.565704 -221.083378)
		(end 104.611424 -221.129098)
		(stroke
			(width 0.05715)
			(type default)
		)
		(layer "In11.Cu")
	)
	(gr_line
		(start 104.565704 -221.05493)
		(end 104.565704 -221.083378)
		(stroke
			(width 0.05715)
			(type default)
		)
		(layer "In11.Cu")
	)
	(gr_line
		(start 104.566466 -222.950024)
		(end 104.570276 -222.95231)
		(stroke
			(width 0.05715)
			(type default)
		)
		(layer "In11.Cu")
	)
	(gr_line
		(start 104.57053 -228.756972)
		(end 104.568752 -228.757734)
		(stroke
			(width 0.05715)
			(type default)
		)
		(layer "In11.Cu")
	)
	(gr_line
		(start 104.57307 -228.755448)
		(end 104.57053 -228.756972)
		(stroke
			(width 0.05715)
			(type default)
		)
		(layer "In11.Cu")
	)
	(gr_line
		(start 104.573832 -228.75494)
		(end 104.57307 -228.755448)
		(stroke
			(width 0.05715)
			(type default)
		)
		(layer "In11.Cu")
	)
	(gr_line
		(start 104.578658 -228.752146)
		(end 104.573832 -228.75494)
		(stroke
			(width 0.05715)
			(type default)
		)
		(layer "In11.Cu")
	)
	(gr_line
		(start 104.58323 -228.749098)
		(end 104.580436 -228.75113)
		(stroke
			(width 0.05715)
			(type default)
		)
		(layer "In11.Cu")
	)
	(gr_arc
		(start 104.58323 -228.749098)
		(mid 104.586413 -228.746823)
		(end 104.58958 -228.744526)
		(stroke
			(width 0.05715)
			(type default)
		)
		(layer "In11.Cu")
	)
	(gr_line
		(start 104.656128 -286.992314)
		(end 104.656128 -286.991298)
		(stroke
			(width 0.05715)
			(type default)
		)
		(layer "In11.Cu")
	)
	(gr_line
		(start 104.73944 -293.043864)
		(end 104.74452 -293.040816)
		(stroke
			(width 0.05715)
			(type default)
		)
		(layer "In11.Cu")
	)
	(gr_line
		(start 104.73944 -291.423852)
		(end 104.74452 -291.420804)
		(stroke
			(width 0.05715)
			(type default)
		)
		(layer "In11.Cu")
	)
	(gr_line
		(start 104.73944 -289.80384)
		(end 104.74452 -289.800792)
		(stroke
			(width 0.05715)
			(type default)
		)
		(layer "In11.Cu")
	)
	(gr_line
		(start 104.74452 -293.040816)
		(end 104.745536 -293.040308)
		(stroke
			(width 0.05715)
			(type default)
		)
		(layer "In11.Cu")
	)
	(gr_line
		(start 104.74452 -291.420804)
		(end 104.745536 -291.420296)
		(stroke
			(width 0.05715)
			(type default)
		)
		(layer "In11.Cu")
	)
	(gr_line
		(start 104.74452 -289.800792)
		(end 104.745536 -289.800284)
		(stroke
			(width 0.05715)
			(type default)
		)
		(layer "In11.Cu")
	)
	(gr_line
		(start 104.745536 -293.040308)
		(end 104.748076 -293.038784)
		(stroke
			(width 0.05715)
			(type default)
		)
		(layer "In11.Cu")
	)
	(gr_line
		(start 104.745536 -291.420296)
		(end 104.748076 -291.418772)
		(stroke
			(width 0.05715)
			(type default)
		)
		(layer "In11.Cu")
	)
	(gr_line
		(start 104.745536 -289.800284)
		(end 104.748076 -289.79876)
		(stroke
			(width 0.05715)
			(type default)
		)
		(layer "In11.Cu")
	)
	(gr_line
		(start 104.745536 -287.532318)
		(end 104.745028 -287.532064)
		(stroke
			(width 0.05715)
			(type default)
		)
		(layer "In11.Cu")
	)
	(gr_line
		(start 104.74706 -287.533334)
		(end 104.745536 -287.532318)
		(stroke
			(width 0.05715)
			(type default)
		)
		(layer "In11.Cu")
	)
	(gr_line
		(start 104.74833 -292.393878)
		(end 104.74706 -292.393116)
		(stroke
			(width 0.05715)
			(type default)
		)
		(layer "In11.Cu")
	)
	(gr_line
		(start 104.74833 -290.773866)
		(end 104.74706 -290.773104)
		(stroke
			(width 0.05715)
			(type default)
		)
		(layer "In11.Cu")
	)
	(gr_line
		(start 104.74833 -289.153854)
		(end 104.74706 -289.153092)
		(stroke
			(width 0.05715)
			(type default)
		)
		(layer "In11.Cu")
	)
	(gr_line
		(start 104.7496 -287.534604)
		(end 104.74706 -287.533334)
		(stroke
			(width 0.05715)
			(type default)
		)
		(layer "In11.Cu")
	)
	(gr_line
		(start 104.780588 -294.64)
		(end 104.780588 -294.639746)
		(stroke
			(width 0.05715)
			(type default)
		)
		(layer "In11.Cu")
	)
	(gr_line
		(start 104.780588 -294.032686)
		(end 104.780588 -294.032432)
		(stroke
			(width 0.05715)
			(type default)
		)
		(layer "In11.Cu")
	)
	(gr_line
		(start 104.781604 -286.538924)
		(end 104.781604 -286.539178)
		(stroke
			(width 0.05715)
			(type default)
		)
		(layer "In11.Cu")
	)
	(gr_line
		(start 104.841802 -293.2049)
		(end 104.843326 -293.204138)
		(stroke
			(width 0.05715)
			(type default)
		)
		(layer "In11.Cu")
	)
	(gr_line
		(start 104.841802 -291.584888)
		(end 104.843326 -291.584126)
		(stroke
			(width 0.05715)
			(type default)
		)
		(layer "In11.Cu")
	)
	(gr_line
		(start 104.841802 -289.964876)
		(end 104.843326 -289.964114)
		(stroke
			(width 0.05715)
			(type default)
		)
		(layer "In11.Cu")
	)
	(gr_line
		(start 104.843326 -293.204138)
		(end 104.844088 -293.20363)
		(stroke
			(width 0.05715)
			(type default)
		)
		(layer "In11.Cu")
	)
	(gr_line
		(start 104.843326 -291.584126)
		(end 104.844088 -291.583618)
		(stroke
			(width 0.05715)
			(type default)
		)
		(layer "In11.Cu")
	)
	(gr_line
		(start 104.843326 -289.964114)
		(end 104.844088 -289.963606)
		(stroke
			(width 0.05715)
			(type default)
		)
		(layer "In11.Cu")
	)
	(gr_line
		(start 104.843326 -287.368488)
		(end 104.841294 -287.367218)
		(stroke
			(width 0.05715)
			(type default)
		)
		(layer "In11.Cu")
	)
	(gr_line
		(start 104.843834 -292.228524)
		(end 104.843326 -292.22827)
		(stroke
			(width 0.05715)
			(type default)
		)
		(layer "In11.Cu")
	)
	(gr_line
		(start 104.843834 -290.608512)
		(end 104.843326 -290.608258)
		(stroke
			(width 0.05715)
			(type default)
		)
		(layer "In11.Cu")
	)
	(gr_line
		(start 104.843834 -288.9885)
		(end 104.843326 -288.988246)
		(stroke
			(width 0.05715)
			(type default)
		)
		(layer "In11.Cu")
	)
	(gr_line
		(start 104.844342 -287.368996)
		(end 104.843326 -287.368488)
		(stroke
			(width 0.05715)
			(type default)
		)
		(layer "In11.Cu")
	)
	(gr_line
		(start 104.844596 -287.369504)
		(end 104.844342 -287.368996)
		(stroke
			(width 0.05715)
			(type default)
		)
		(layer "In11.Cu")
	)
	(gr_line
		(start 104.847644 -221.083378)
		(end 104.801924 -221.129098)
		(stroke
			(width 0.05715)
			(type default)
		)
		(layer "In11.Cu")
	)
	(gr_line
		(start 104.847644 -221.05493)
		(end 104.847644 -221.083378)
		(stroke
			(width 0.05715)
			(type default)
		)
		(layer "In11.Cu")
	)
	(gr_arc
		(start 104.871012 -225.503486)
		(mid 104.874937 -225.506297)
		(end 104.878886 -225.509074)
		(stroke
			(width 0.05715)
			(type default)
		)
		(layer "In11.Cu")
	)
	(gr_line
		(start 104.878886 -225.509074)
		(end 104.885744 -225.513138)
		(stroke
			(width 0.05715)
			(type default)
		)
		(layer "In11.Cu")
	)
	(gr_line
		(start 104.885744 -225.513138)
		(end 104.886506 -225.513646)
		(stroke
			(width 0.05715)
			(type default)
		)
		(layer "In11.Cu")
	)
	(gr_line
		(start 104.886506 -225.513646)
		(end 104.887268 -225.514154)
		(stroke
			(width 0.05715)
			(type default)
		)
		(layer "In11.Cu")
	)
	(gr_line
		(start 104.892602 -293.878254)
		(end 104.886506 -293.873682)
		(stroke
			(width 0.05715)
			(type default)
		)
		(layer "In11.Cu")
	)
	(gr_line
		(start 104.911144 -225.52787)
		(end 104.913684 -225.529394)
		(stroke
			(width 0.05715)
			(type default)
		)
		(layer "In11.Cu")
	)
	(gr_line
		(start 104.915208 -225.53041)
		(end 104.916986 -225.531426)
		(stroke
			(width 0.05715)
			(type default)
		)
		(layer "In11.Cu")
	)
	(gr_line
		(start 104.916986 -225.531426)
		(end 104.918002 -225.531934)
		(stroke
			(width 0.05715)
			(type default)
		)
		(layer "In11.Cu")
	)
	(gr_line
		(start 104.918002 -225.531934)
		(end 104.918764 -225.532442)
		(stroke
			(width 0.05715)
			(type default)
		)
		(layer "In11.Cu")
	)
	(gr_line
		(start 104.918764 -225.532442)
		(end 104.920034 -225.533204)
		(stroke
			(width 0.05715)
			(type default)
		)
		(layer "In11.Cu")
	)
	(gr_line
		(start 104.97185 -296.371264)
		(end 104.97185 -296.342816)
		(stroke
			(width 0.05715)
			(type default)
		)
		(layer "In11.Cu")
	)
	(gr_line
		(start 104.97185 -296.342816)
		(end 105.01757 -296.297096)
		(stroke
			(width 0.05715)
			(type default)
		)
		(layer "In11.Cu")
	)
	(gr_line
		(start 105.011982 -225.365818)
		(end 105.013252 -225.36658)
		(stroke
			(width 0.05715)
			(type default)
		)
		(layer "In11.Cu")
	)
	(gr_line
		(start 105.013252 -225.36658)
		(end 105.014014 -225.367088)
		(stroke
			(width 0.05715)
			(type default)
		)
		(layer "In11.Cu")
	)
	(gr_line
		(start 105.014014 -225.367088)
		(end 105.01503 -225.367596)
		(stroke
			(width 0.05715)
			(type default)
		)
		(layer "In11.Cu")
	)
	(gr_line
		(start 105.066084 -381.078486)
		(end 105.066338 -381.078486)
		(stroke
			(width 0.07112)
			(type default)
		)
		(layer "In11.Cu")
	)
	(gr_line
		(start 105.126282 -286.229806)
		(end 105.126282 -286.23641)
		(stroke
			(width 0.05715)
			(type default)
		)
		(layer "In11.Cu")
	)
	(gr_arc
		(start 105.163366 -280.209244)
		(mid 105.170436 -280.214886)
		(end 105.17759 -280.22042)
		(stroke
			(width 0.05715)
			(type default)
		)
		(layer "In11.Cu")
	)
	(gr_line
		(start 105.195624 -379.941836)
		(end 105.19664 -379.514862)
		(stroke
			(width 0.07112)
			(type default)
		)
		(layer "In11.Cu")
	)
	(gr_line
		(start 105.19664 -379.514862)
		(end 105.333038 -379.379226)
		(stroke
			(width 0.07112)
			(type default)
		)
		(layer "In11.Cu")
	)
	(gr_line
		(start 105.198164 -378.813822)
		(end 105.19918 -378.386848)
		(stroke
			(width 0.07112)
			(type default)
		)
		(layer "In11.Cu")
	)
	(gr_line
		(start 105.19918 -378.386848)
		(end 105.335578 -378.251466)
		(stroke
			(width 0.07112)
			(type default)
		)
		(layer "In11.Cu")
	)
	(gr_line
		(start 105.200704 -377.686062)
		(end 105.20172 -377.259088)
		(stroke
			(width 0.07112)
			(type default)
		)
		(layer "In11.Cu")
	)
	(gr_line
		(start 105.20172 -377.259088)
		(end 105.338118 -377.123706)
		(stroke
			(width 0.07112)
			(type default)
		)
		(layer "In11.Cu")
	)
	(gr_line
		(start 105.217214 -279.268936)
		(end 105.217976 -279.268428)
		(stroke
			(width 0.05715)
			(type default)
		)
		(layer "In11.Cu")
	)
	(gr_line
		(start 105.217976 -279.268428)
		(end 105.220262 -279.267412)
		(stroke
			(width 0.05715)
			(type default)
		)
		(layer "In11.Cu")
	)
	(gr_line
		(start 105.224834 -280.24836)
		(end 105.17759 -280.22042)
		(stroke
			(width 0.05715)
			(type default)
		)
		(layer "In11.Cu")
	)
	(gr_line
		(start 105.246932 -280.26106)
		(end 105.246678 -280.26106)
		(stroke
			(width 0.05715)
			(type default)
		)
		(layer "In11.Cu")
	)
	(gr_line
		(start 105.25379 -296.371264)
		(end 105.25379 -296.342816)
		(stroke
			(width 0.05715)
			(type default)
		)
		(layer "In11.Cu")
	)
	(gr_line
		(start 105.25379 -296.342816)
		(end 105.20807 -296.297096)
		(stroke
			(width 0.05715)
			(type default)
		)
		(layer "In11.Cu")
	)
	(gr_line
		(start 105.307892 -279.437338)
		(end 105.313226 -279.43429)
		(stroke
			(width 0.05715)
			(type default)
		)
		(layer "In11.Cu")
	)
	(gr_line
		(start 105.313226 -279.43429)
		(end 105.313988 -279.433782)
		(stroke
			(width 0.05715)
			(type default)
		)
		(layer "In11.Cu")
	)
	(gr_line
		(start 105.313988 -279.433782)
		(end 105.315004 -279.433274)
		(stroke
			(width 0.05715)
			(type default)
		)
		(layer "In11.Cu")
	)
	(gr_line
		(start 105.315004 -279.433274)
		(end 105.31602 -279.432766)
		(stroke
			(width 0.05715)
			(type default)
		)
		(layer "In11.Cu")
	)
	(gr_line
		(start 105.331768 -380.550928)
		(end 105.331768 -380.550674)
		(stroke
			(width 0.07112)
			(type default)
		)
		(layer "In11.Cu")
	)
	(gr_line
		(start 105.331768 -380.550674)
		(end 105.332276 -380.550674)
		(stroke
			(width 0.07112)
			(type default)
		)
		(layer "In11.Cu")
	)
	(gr_line
		(start 105.332276 -380.550674)
		(end 105.334308 -380.548642)
		(stroke
			(width 0.07112)
			(type default)
		)
		(layer "In11.Cu")
	)
	(gr_line
		(start 105.33253 -380.07925)
		(end 105.195624 -379.941836)
		(stroke
			(width 0.07112)
			(type default)
		)
		(layer "In11.Cu")
	)
	(gr_line
		(start 105.333038 -380.079758)
		(end 105.33253 -380.07925)
		(stroke
			(width 0.07112)
			(type default)
		)
		(layer "In11.Cu")
	)
	(gr_line
		(start 105.3338 -379.378464)
		(end 105.334308 -379.377956)
		(stroke
			(width 0.07112)
			(type default)
		)
		(layer "In11.Cu")
	)
	(gr_line
		(start 105.334308 -379.377956)
		(end 105.33634 -379.375924)
		(stroke
			(width 0.07112)
			(type default)
		)
		(layer "In11.Cu")
	)
	(gr_line
		(start 105.33507 -378.95149)
		(end 105.198164 -378.813822)
		(stroke
			(width 0.07112)
			(type default)
		)
		(layer "In11.Cu")
	)
	(gr_line
		(start 105.335578 -378.951998)
		(end 105.33507 -378.95149)
		(stroke
			(width 0.07112)
			(type default)
		)
		(layer "In11.Cu")
	)
	(gr_line
		(start 105.33634 -378.250704)
		(end 105.336848 -378.250196)
		(stroke
			(width 0.07112)
			(type default)
		)
		(layer "In11.Cu")
	)
	(gr_line
		(start 105.336848 -378.250196)
		(end 105.33888 -378.248164)
		(stroke
			(width 0.07112)
			(type default)
		)
		(layer "In11.Cu")
	)
	(gr_line
		(start 105.33761 -377.82373)
		(end 105.200704 -377.686062)
		(stroke
			(width 0.07112)
			(type default)
		)
		(layer "In11.Cu")
	)
	(gr_line
		(start 105.338118 -377.824238)
		(end 105.33761 -377.82373)
		(stroke
			(width 0.07112)
			(type default)
		)
		(layer "In11.Cu")
	)
	(gr_line
		(start 105.33888 -377.122944)
		(end 105.339388 -377.122436)
		(stroke
			(width 0.07112)
			(type default)
		)
		(layer "In11.Cu")
	)
	(gr_arc
		(start 105.339642 -229.5525)
		(mid 105.344325 -229.555825)
		(end 105.34904 -229.559104)
		(stroke
			(width 0.05715)
			(type default)
		)
		(layer "In11.Cu")
	)
	(gr_arc
		(start 105.341166 -223.073468)
		(mid 105.345091 -223.076279)
		(end 105.34904 -223.079056)
		(stroke
			(width 0.05715)
			(type default)
		)
		(layer "In11.Cu")
	)
	(gr_line
		(start 105.344976 -280.097484)
		(end 105.343452 -280.096468)
		(stroke
			(width 0.05715)
			(type default)
		)
		(layer "In11.Cu")
	)
	(gr_line
		(start 105.347262 -280.099008)
		(end 105.346246 -280.098246)
		(stroke
			(width 0.05715)
			(type default)
		)
		(layer "In11.Cu")
	)
	(gr_line
		(start 105.34904 -229.559104)
		(end 105.351072 -229.560628)
		(stroke
			(width 0.05715)
			(type default)
		)
		(layer "In11.Cu")
	)
	(gr_arc
		(start 105.34904 -223.769936)
		(mid 105.34675 -223.771582)
		(end 105.344468 -223.773238)
		(stroke
			(width 0.05715)
			(type default)
		)
		(layer "In11.Cu")
	)
	(gr_line
		(start 105.34904 -223.079056)
		(end 105.355898 -223.08312)
		(stroke
			(width 0.05715)
			(type default)
		)
		(layer "In11.Cu")
	)
	(gr_line
		(start 105.351072 -229.560628)
		(end 105.355898 -229.563422)
		(stroke
			(width 0.05715)
			(type default)
		)
		(layer "In11.Cu")
	)
	(gr_line
		(start 105.351834 -223.767904)
		(end 105.34904 -223.769936)
		(stroke
			(width 0.05715)
			(type default)
		)
		(layer "In11.Cu")
	)
	(gr_line
		(start 105.355898 -223.08312)
		(end 105.35666 -223.083628)
		(stroke
			(width 0.05715)
			(type default)
		)
		(layer "In11.Cu")
	)
	(gr_line
		(start 105.35666 -223.083628)
		(end 105.357168 -223.083882)
		(stroke
			(width 0.05715)
			(type default)
		)
		(layer "In11.Cu")
	)
	(gr_line
		(start 105.36047 -280.10739)
		(end 105.351072 -280.10104)
		(stroke
			(width 0.05715)
			(type default)
		)
		(layer "In11.Cu")
	)
	(gr_line
		(start 105.36047 -223.762824)
		(end 105.351834 -223.767904)
		(stroke
			(width 0.05715)
			(type default)
		)
		(layer "In11.Cu")
	)
	(gr_line
		(start 105.381806 -223.098106)
		(end 105.382822 -223.098868)
		(stroke
			(width 0.05715)
			(type default)
		)
		(layer "In11.Cu")
	)
	(gr_line
		(start 105.382822 -223.098868)
		(end 105.383838 -223.099376)
		(stroke
			(width 0.05715)
			(type default)
		)
		(layer "In11.Cu")
	)
	(gr_line
		(start 105.385362 -223.100392)
		(end 105.38714 -223.101408)
		(stroke
			(width 0.05715)
			(type default)
		)
		(layer "In11.Cu")
	)
	(gr_line
		(start 105.38714 -223.101408)
		(end 105.388156 -223.101916)
		(stroke
			(width 0.05715)
			(type default)
		)
		(layer "In11.Cu")
	)
	(gr_line
		(start 105.388156 -223.101916)
		(end 105.388918 -223.102424)
		(stroke
			(width 0.05715)
			(type default)
		)
		(layer "In11.Cu")
	)
	(gr_line
		(start 105.388918 -223.102424)
		(end 105.391458 -223.103948)
		(stroke
			(width 0.05715)
			(type default)
		)
		(layer "In11.Cu")
	)
	(gr_arc
		(start 105.420922 -222.108014)
		(mid 105.534916 -221.974888)
		(end 105.575862 -221.804484)
		(stroke
			(width 0.05715)
			(type default)
		)
		(layer "In11.Cu")
	)
	(gr_line
		(start 105.476548 -222.932752)
		(end 105.477056 -222.933006)
		(stroke
			(width 0.05715)
			(type default)
		)
		(layer "In11.Cu")
	)
	(gr_line
		(start 105.477056 -222.933006)
		(end 105.478072 -222.933514)
		(stroke
			(width 0.05715)
			(type default)
		)
		(layer "In11.Cu")
	)
	(gr_line
		(start 105.478072 -222.933514)
		(end 105.479596 -222.93453)
		(stroke
			(width 0.05715)
			(type default)
		)
		(layer "In11.Cu")
	)
	(gr_line
		(start 105.482136 -222.9358)
		(end 105.483406 -222.936562)
		(stroke
			(width 0.05715)
			(type default)
		)
		(layer "In11.Cu")
	)
	(gr_line
		(start 105.483406 -229.41661)
		(end 105.483914 -229.416864)
		(stroke
			(width 0.05715)
			(type default)
		)
		(layer "In11.Cu")
	)
	(gr_line
		(start 105.483406 -222.936562)
		(end 105.484168 -222.93707)
		(stroke
			(width 0.05715)
			(type default)
		)
		(layer "In11.Cu")
	)
	(gr_line
		(start 105.510584 -221.083378)
		(end 105.556304 -221.129098)
		(stroke
			(width 0.05715)
			(type default)
		)
		(layer "In11.Cu")
	)
	(gr_line
		(start 105.510584 -221.05493)
		(end 105.510584 -221.083378)
		(stroke
			(width 0.05715)
			(type default)
		)
		(layer "In11.Cu")
	)
	(gr_line
		(start 105.522522 -228.749352)
		(end 105.514648 -228.753924)
		(stroke
			(width 0.05715)
			(type default)
		)
		(layer "In11.Cu")
	)
	(gr_line
		(start 105.52303 -228.749098)
		(end 105.522522 -228.749352)
		(stroke
			(width 0.05715)
			(type default)
		)
		(layer "In11.Cu")
	)
	(gr_arc
		(start 105.52303 -228.749098)
		(mid 105.526213 -228.746823)
		(end 105.52938 -228.744526)
		(stroke
			(width 0.05715)
			(type default)
		)
		(layer "In11.Cu")
	)
	(gr_arc
		(start 105.52303 -222.26905)
		(mid 105.527874 -222.265647)
		(end 105.532682 -222.262192)
		(stroke
			(width 0.05715)
			(type default)
		)
		(layer "In11.Cu")
	)
	(gr_arc
		(start 105.532682 -222.262192)
		(mid 105.704567 -222.061441)
		(end 105.766362 -221.804484)
		(stroke
			(width 0.05715)
			(type default)
		)
		(layer "In11.Cu")
	)
	(gr_line
		(start 105.614216 -380.550674)
		(end 105.616248 -380.548642)
		(stroke
			(width 0.07112)
			(type default)
		)
		(layer "In11.Cu")
	)
	(gr_line
		(start 105.616248 -380.081028)
		(end 105.616248 -379.378464)
		(stroke
			(width 0.07112)
			(type default)
		)
		(layer "In11.Cu")
	)
	(gr_line
		(start 105.616248 -379.378464)
		(end 105.618788 -379.375924)
		(stroke
			(width 0.07112)
			(type default)
		)
		(layer "In11.Cu")
	)
	(gr_line
		(start 105.618788 -379.375924)
		(end 105.618788 -379.375416)
		(stroke
			(width 0.07112)
			(type default)
		)
		(layer "In11.Cu")
	)
	(gr_line
		(start 105.618788 -378.953268)
		(end 105.618788 -378.250704)
		(stroke
			(width 0.07112)
			(type default)
		)
		(layer "In11.Cu")
	)
	(gr_line
		(start 105.618788 -378.250704)
		(end 105.621328 -378.248164)
		(stroke
			(width 0.07112)
			(type default)
		)
		(layer "In11.Cu")
	)
	(gr_line
		(start 105.621328 -378.248164)
		(end 105.621328 -378.247656)
		(stroke
			(width 0.07112)
			(type default)
		)
		(layer "In11.Cu")
	)
	(gr_line
		(start 105.621328 -377.825508)
		(end 105.621328 -377.122944)
		(stroke
			(width 0.07112)
			(type default)
		)
		(layer "In11.Cu")
	)
	(gr_line
		(start 105.62336 -376.050048)
		(end 105.623614 -376.050048)
		(stroke
			(width 0.07112)
			(type default)
		)
		(layer "In11.Cu")
	)
	(gr_line
		(start 105.782872 -288.344356)
		(end 105.783888 -288.343848)
		(stroke
			(width 0.05715)
			(type default)
		)
		(layer "In11.Cu")
	)
	(gr_line
		(start 105.782872 -286.724344)
		(end 105.783888 -286.723836)
		(stroke
			(width 0.05715)
			(type default)
		)
		(layer "In11.Cu")
	)
	(gr_line
		(start 105.783126 -293.203884)
		(end 105.784396 -293.203376)
		(stroke
			(width 0.05715)
			(type default)
		)
		(layer "In11.Cu")
	)
	(gr_line
		(start 105.783126 -291.583872)
		(end 105.784396 -291.583364)
		(stroke
			(width 0.05715)
			(type default)
		)
		(layer "In11.Cu")
	)
	(gr_line
		(start 105.783126 -289.96386)
		(end 105.784396 -289.963352)
		(stroke
			(width 0.05715)
			(type default)
		)
		(layer "In11.Cu")
	)
	(gr_line
		(start 105.783126 -285.104078)
		(end 105.784396 -285.10357)
		(stroke
			(width 0.05715)
			(type default)
		)
		(layer "In11.Cu")
	)
	(gr_line
		(start 105.783126 -283.484066)
		(end 105.784396 -283.483558)
		(stroke
			(width 0.05715)
			(type default)
		)
		(layer "In11.Cu")
	)
	(gr_line
		(start 105.783126 -281.864054)
		(end 105.784396 -281.863546)
		(stroke
			(width 0.05715)
			(type default)
		)
		(layer "In11.Cu")
	)
	(gr_line
		(start 105.783126 -278.62403)
		(end 105.784396 -278.623522)
		(stroke
			(width 0.05715)
			(type default)
		)
		(layer "In11.Cu")
	)
	(gr_line
		(start 105.783888 -285.748984)
		(end 105.78338 -285.74873)
		(stroke
			(width 0.05715)
			(type default)
		)
		(layer "In11.Cu")
	)
	(gr_line
		(start 105.784904 -293.849298)
		(end 105.783126 -293.848536)
		(stroke
			(width 0.05715)
			(type default)
		)
		(layer "In11.Cu")
	)
	(gr_line
		(start 105.784904 -292.229286)
		(end 105.783126 -292.228524)
		(stroke
			(width 0.05715)
			(type default)
		)
		(layer "In11.Cu")
	)
	(gr_line
		(start 105.784904 -290.609274)
		(end 105.783126 -290.608512)
		(stroke
			(width 0.05715)
			(type default)
		)
		(layer "In11.Cu")
	)
	(gr_line
		(start 105.784904 -288.989262)
		(end 105.783126 -288.9885)
		(stroke
			(width 0.05715)
			(type default)
		)
		(layer "In11.Cu")
	)
	(gr_line
		(start 105.784904 -284.12948)
		(end 105.783126 -284.128718)
		(stroke
			(width 0.05715)
			(type default)
		)
		(layer "In11.Cu")
	)
	(gr_line
		(start 105.784904 -282.509468)
		(end 105.783126 -282.508706)
		(stroke
			(width 0.05715)
			(type default)
		)
		(layer "In11.Cu")
	)
	(gr_line
		(start 105.789222 -280.891996)
		(end 105.785158 -280.88971)
		(stroke
			(width 0.05715)
			(type default)
		)
		(layer "In11.Cu")
	)
	(gr_line
		(start 105.792524 -221.083378)
		(end 105.746804 -221.129098)
		(stroke
			(width 0.05715)
			(type default)
		)
		(layer "In11.Cu")
	)
	(gr_line
		(start 105.792524 -221.05493)
		(end 105.792524 -221.083378)
		(stroke
			(width 0.05715)
			(type default)
		)
		(layer "In11.Cu")
	)
	(gr_line
		(start 105.814876 -285.767018)
		(end 105.814114 -285.76651)
		(stroke
			(width 0.05715)
			(type default)
		)
		(layer "In11.Cu")
	)
	(gr_line
		(start 105.858818 -225.532442)
		(end 105.859326 -225.532696)
		(stroke
			(width 0.05715)
			(type default)
		)
		(layer "In11.Cu")
	)
	(gr_line
		(start 105.861358 -225.533712)
		(end 105.86212 -225.53422)
		(stroke
			(width 0.05715)
			(type default)
		)
		(layer "In11.Cu")
	)
	(gr_line
		(start 105.869232 -244.978174)
		(end 105.870502 -244.978936)
		(stroke
			(width 0.05715)
			(type default)
		)
		(layer "In11.Cu")
	)
	(gr_line
		(start 105.916984 -296.286936)
		(end 105.916984 -296.258488)
		(stroke
			(width 0.05715)
			(type default)
		)
		(layer "In11.Cu")
	)
	(gr_line
		(start 105.916984 -296.258488)
		(end 105.962704 -296.212768)
		(stroke
			(width 0.05715)
			(type default)
		)
		(layer "In11.Cu")
	)
	(gr_line
		(start 105.95356 -225.366834)
		(end 105.954068 -225.367088)
		(stroke
			(width 0.05715)
			(type default)
		)
		(layer "In11.Cu")
	)
	(gr_line
		(start 105.954068 -225.367088)
		(end 105.955846 -225.368104)
		(stroke
			(width 0.05715)
			(type default)
		)
		(layer "In11.Cu")
	)
	(gr_line
		(start 105.955846 -225.368104)
		(end 105.95737 -225.36912)
		(stroke
			(width 0.05715)
			(type default)
		)
		(layer "In11.Cu")
	)
	(gr_line
		(start 105.97769 -225.380804)
		(end 105.98785 -225.386646)
		(stroke
			(width 0.05715)
			(type default)
		)
		(layer "In11.Cu")
	)
	(gr_arc
		(start 106.000042 -225.395282)
		(mid 105.995235 -225.3917)
		(end 105.99039 -225.38817)
		(stroke
			(width 0.05715)
			(type default)
		)
		(layer "In11.Cu")
	)
	(gr_line
		(start 106.045508 -222.61449)
		(end 106.045762 -222.61449)
		(stroke
			(width 0.05715)
			(type default)
		)
		(layer "In11.Cu")
	)
	(gr_line
		(start 106.045762 -225.871532)
		(end 106.045762 -225.87077)
		(stroke
			(width 0.05715)
			(type default)
		)
		(layer "In11.Cu")
	)
	(gr_line
		(start 106.045762 -225.870516)
		(end 106.045762 -225.87077)
		(stroke
			(width 0.05715)
			(type default)
		)
		(layer "In11.Cu")
	)
	(gr_arc
		(start 106.045762 -225.870008)
		(mid 106.045762 -225.870262)
		(end 106.045762 -225.870516)
		(stroke
			(width 0.05715)
			(type default)
		)
		(layer "In11.Cu")
	)
	(gr_line
		(start 106.148124 -280.237946)
		(end 106.147616 -280.237692)
		(stroke
			(width 0.05715)
			(type default)
		)
		(layer "In11.Cu")
	)
	(gr_line
		(start 106.150664 -277.653242)
		(end 106.153966 -277.65121)
		(stroke
			(width 0.05715)
			(type default)
		)
		(layer "In11.Cu")
	)
	(gr_line
		(start 106.153966 -277.65121)
		(end 106.154474 -277.650956)
		(stroke
			(width 0.05715)
			(type default)
		)
		(layer "In11.Cu")
	)
	(gr_line
		(start 106.154474 -280.241756)
		(end 106.150664 -280.23947)
		(stroke
			(width 0.05715)
			(type default)
		)
		(layer "In11.Cu")
	)
	(gr_line
		(start 106.154474 -277.650956)
		(end 106.15803 -277.648416)
		(stroke
			(width 0.05715)
			(type default)
		)
		(layer "In11.Cu")
	)
	(gr_line
		(start 106.15549 -280.242264)
		(end 106.154474 -280.241756)
		(stroke
			(width 0.05715)
			(type default)
		)
		(layer "In11.Cu")
	)
	(gr_line
		(start 106.157014 -280.24328)
		(end 106.15549 -280.242264)
		(stroke
			(width 0.05715)
			(type default)
		)
		(layer "In11.Cu")
	)
	(gr_line
		(start 106.15803 -280.243788)
		(end 106.157014 -280.24328)
		(stroke
			(width 0.05715)
			(type default)
		)
		(layer "In11.Cu")
	)
	(gr_line
		(start 106.15803 -279.268936)
		(end 106.158792 -279.268428)
		(stroke
			(width 0.05715)
			(type default)
		)
		(layer "In11.Cu")
	)
	(gr_line
		(start 106.15803 -277.648416)
		(end 106.159046 -277.647908)
		(stroke
			(width 0.05715)
			(type default)
		)
		(layer "In11.Cu")
	)
	(gr_line
		(start 106.158792 -279.268428)
		(end 106.160062 -279.267666)
		(stroke
			(width 0.05715)
			(type default)
		)
		(layer "In11.Cu")
	)
	(gr_line
		(start 106.160062 -279.267666)
		(end 106.162602 -279.266396)
		(stroke
			(width 0.05715)
			(type default)
		)
		(layer "In11.Cu")
	)
	(gr_line
		(start 106.198924 -296.286936)
		(end 106.198924 -296.258488)
		(stroke
			(width 0.05715)
			(type default)
		)
		(layer "In11.Cu")
	)
	(gr_line
		(start 106.198924 -296.258488)
		(end 106.153204 -296.212768)
		(stroke
			(width 0.05715)
			(type default)
		)
		(layer "In11.Cu")
	)
	(gr_line
		(start 106.228134 -225.789998)
		(end 106.228388 -225.791014)
		(stroke
			(width 0.05715)
			(type default)
		)
		(layer "In11.Cu")
	)
	(gr_line
		(start 106.236262 -222.61449)
		(end 106.236516 -222.61449)
		(stroke
			(width 0.05715)
			(type default)
		)
		(layer "In11.Cu")
	)
	(gr_line
		(start 106.245152 -280.073862)
		(end 106.243628 -280.0731)
		(stroke
			(width 0.05715)
			(type default)
		)
		(layer "In11.Cu")
	)
	(gr_line
		(start 106.249724 -277.81631)
		(end 106.250486 -277.815802)
		(stroke
			(width 0.05715)
			(type default)
		)
		(layer "In11.Cu")
	)
	(gr_line
		(start 106.250486 -280.07691)
		(end 106.249724 -280.076402)
		(stroke
			(width 0.05715)
			(type default)
		)
		(layer "In11.Cu")
	)
	(gr_line
		(start 106.250486 -277.815802)
		(end 106.25328 -277.814278)
		(stroke
			(width 0.05715)
			(type default)
		)
		(layer "In11.Cu")
	)
	(gr_line
		(start 106.25201 -279.435052)
		(end 106.25328 -279.43429)
		(stroke
			(width 0.05715)
			(type default)
		)
		(layer "In11.Cu")
	)
	(gr_line
		(start 106.25328 -280.078434)
		(end 106.250486 -280.07691)
		(stroke
			(width 0.05715)
			(type default)
		)
		(layer "In11.Cu")
	)
	(gr_line
		(start 106.25328 -279.43429)
		(end 106.254042 -279.433782)
		(stroke
			(width 0.05715)
			(type default)
		)
		(layer "In11.Cu")
	)
	(gr_line
		(start 106.25328 -277.814278)
		(end 106.254042 -277.81377)
		(stroke
			(width 0.05715)
			(type default)
		)
		(layer "In11.Cu")
	)
	(gr_line
		(start 106.254042 -280.078942)
		(end 106.25328 -280.078434)
		(stroke
			(width 0.05715)
			(type default)
		)
		(layer "In11.Cu")
	)
	(gr_line
		(start 106.254042 -279.433782)
		(end 106.255058 -279.433274)
		(stroke
			(width 0.05715)
			(type default)
		)
		(layer "In11.Cu")
	)
	(gr_line
		(start 106.254042 -277.81377)
		(end 106.255058 -277.813262)
		(stroke
			(width 0.05715)
			(type default)
		)
		(layer "In11.Cu")
	)
	(gr_line
		(start 106.255058 -279.433274)
		(end 106.256328 -279.432512)
		(stroke
			(width 0.05715)
			(type default)
		)
		(layer "In11.Cu")
	)
	(gr_line
		(start 106.255058 -277.813262)
		(end 106.256582 -277.812246)
		(stroke
			(width 0.05715)
			(type default)
		)
		(layer "In11.Cu")
	)
	(gr_line
		(start 106.256328 -279.432512)
		(end 106.25709 -279.432004)
		(stroke
			(width 0.05715)
			(type default)
		)
		(layer "In11.Cu")
	)
	(gr_line
		(start 106.256582 -277.812246)
		(end 106.261154 -277.809452)
		(stroke
			(width 0.05715)
			(type default)
		)
		(layer "In11.Cu")
	)
	(gr_arc
		(start 106.278172 -229.55123)
		(mid 106.284868 -229.556105)
		(end 106.291634 -229.560882)
		(stroke
			(width 0.05715)
			(type default)
		)
		(layer "In11.Cu")
	)
	(gr_arc
		(start 106.28249 -226.314508)
		(mid 106.287046 -226.317706)
		(end 106.291634 -226.320858)
		(stroke
			(width 0.05715)
			(type default)
		)
		(layer "In11.Cu")
	)
	(gr_line
		(start 106.291634 -229.560882)
		(end 106.294428 -229.562406)
		(stroke
			(width 0.05715)
			(type default)
		)
		(layer "In11.Cu")
	)
	(gr_line
		(start 106.291634 -226.320858)
		(end 106.293158 -226.321874)
		(stroke
			(width 0.05715)
			(type default)
		)
		(layer "In11.Cu")
	)
	(gr_line
		(start 106.293158 -226.321874)
		(end 106.29773 -226.324414)
		(stroke
			(width 0.05715)
			(type default)
		)
		(layer "In11.Cu")
	)
	(gr_arc
		(start 106.294428 -230.246428)
		(mid 106.285994 -230.252067)
		(end 106.277664 -230.257858)
		(stroke
			(width 0.05715)
			(type default)
		)
		(layer "In11.Cu")
	)
	(gr_line
		(start 106.295952 -230.245412)
		(end 106.294428 -230.246428)
		(stroke
			(width 0.05715)
			(type default)
		)
		(layer "In11.Cu")
	)
	(gr_line
		(start 106.296968 -230.244904)
		(end 106.295952 -230.245412)
		(stroke
			(width 0.05715)
			(type default)
		)
		(layer "In11.Cu")
	)
	(gr_arc
		(start 106.316526 -242.535202)
		(mid 106.318936 -242.536605)
		(end 106.321352 -242.537996)
		(stroke
			(width 0.05715)
			(type default)
		)
		(layer "In11.Cu")
	)
	(gr_arc
		(start 106.316526 -240.91519)
		(mid 106.318936 -240.916593)
		(end 106.321352 -240.917984)
		(stroke
			(width 0.05715)
			(type default)
		)
		(layer "In11.Cu")
	)
	(gr_arc
		(start 106.316526 -239.295178)
		(mid 106.318936 -239.296581)
		(end 106.321352 -239.297972)
		(stroke
			(width 0.05715)
			(type default)
		)
		(layer "In11.Cu")
	)
	(gr_arc
		(start 106.316526 -237.675166)
		(mid 106.318936 -237.676569)
		(end 106.321352 -237.67796)
		(stroke
			(width 0.05715)
			(type default)
		)
		(layer "In11.Cu")
	)
	(gr_arc
		(start 106.316526 -236.055154)
		(mid 106.318302 -236.056301)
		(end 106.320082 -236.05744)
		(stroke
			(width 0.05715)
			(type default)
		)
		(layer "In11.Cu")
	)
	(gr_line
		(start 106.326178 -295.623996)
		(end 106.326686 -295.623742)
		(stroke
			(width 0.05715)
			(type default)
		)
		(layer "In11.Cu")
	)
	(gr_line
		(start 106.32694 -230.227378)
		(end 106.325416 -230.228394)
		(stroke
			(width 0.05715)
			(type default)
		)
		(layer "In11.Cu")
	)
	(gr_line
		(start 106.327702 -242.541806)
		(end 106.327956 -242.541806)
		(stroke
			(width 0.05715)
			(type default)
		)
		(layer "In11.Cu")
	)
	(gr_line
		(start 106.327702 -240.921794)
		(end 106.327956 -240.921794)
		(stroke
			(width 0.05715)
			(type default)
		)
		(layer "In11.Cu")
	)
	(gr_line
		(start 106.327702 -239.301782)
		(end 106.327956 -239.301782)
		(stroke
			(width 0.05715)
			(type default)
		)
		(layer "In11.Cu")
	)
	(gr_line
		(start 106.327702 -237.68177)
		(end 106.327956 -237.68177)
		(stroke
			(width 0.05715)
			(type default)
		)
		(layer "In11.Cu")
	)
	(gr_line
		(start 106.327702 -236.061758)
		(end 106.327956 -236.061758)
		(stroke
			(width 0.05715)
			(type default)
		)
		(layer "In11.Cu")
	)
	(gr_line
		(start 106.327956 -241.566954)
		(end 106.327702 -241.567208)
		(stroke
			(width 0.05715)
			(type default)
		)
		(layer "In11.Cu")
	)
	(gr_line
		(start 106.327956 -239.946942)
		(end 106.327702 -239.947196)
		(stroke
			(width 0.05715)
			(type default)
		)
		(layer "In11.Cu")
	)
	(gr_line
		(start 106.327956 -238.32693)
		(end 106.327702 -238.327184)
		(stroke
			(width 0.05715)
			(type default)
		)
		(layer "In11.Cu")
	)
	(gr_line
		(start 106.327956 -236.706918)
		(end 106.327702 -236.707172)
		(stroke
			(width 0.05715)
			(type default)
		)
		(layer "In11.Cu")
	)
	(gr_line
		(start 106.327956 -235.086906)
		(end 106.327702 -235.08716)
		(stroke
			(width 0.05715)
			(type default)
		)
		(layer "In11.Cu")
	)
	(gr_line
		(start 106.327956 -232.821734)
		(end 106.328464 -232.821988)
		(stroke
			(width 0.05715)
			(type default)
		)
		(layer "In11.Cu")
	)
	(gr_line
		(start 106.327956 -230.22687)
		(end 106.32694 -230.227378)
		(stroke
			(width 0.05715)
			(type default)
		)
		(layer "In11.Cu")
	)
	(gr_line
		(start 106.328464 -230.226616)
		(end 106.327956 -230.22687)
		(stroke
			(width 0.05715)
			(type default)
		)
		(layer "In11.Cu")
	)
	(gr_line
		(start 106.328718 -234.442254)
		(end 106.329226 -234.442508)
		(stroke
			(width 0.05715)
			(type default)
		)
		(layer "In11.Cu")
	)
	(gr_line
		(start 106.328718 -228.606604)
		(end 106.327956 -228.607112)
		(stroke
			(width 0.05715)
			(type default)
		)
		(layer "In11.Cu")
	)
	(gr_line
		(start 106.329988 -228.605842)
		(end 106.328718 -228.606604)
		(stroke
			(width 0.05715)
			(type default)
		)
		(layer "In11.Cu")
	)
	(gr_line
		(start 106.330496 -222.125794)
		(end 106.328972 -222.12681)
		(stroke
			(width 0.05715)
			(type default)
		)
		(layer "In11.Cu")
	)
	(gr_line
		(start 106.331512 -236.06379)
		(end 106.332274 -236.064298)
		(stroke
			(width 0.05715)
			(type default)
		)
		(layer "In11.Cu")
	)
	(gr_line
		(start 106.332274 -236.064298)
		(end 106.333798 -236.065314)
		(stroke
			(width 0.05715)
			(type default)
		)
		(layer "In11.Cu")
	)
	(gr_line
		(start 106.35996 -222.108776)
		(end 106.336338 -222.122492)
		(stroke
			(width 0.05715)
			(type default)
		)
		(layer "In11.Cu")
	)
	(gr_line
		(start 106.392726 -222.309944)
		(end 106.392218 -222.310198)
		(stroke
			(width 0.05715)
			(type default)
		)
		(layer "In11.Cu")
	)
	(gr_line
		(start 106.421936 -230.39324)
		(end 106.420412 -230.394002)
		(stroke
			(width 0.05715)
			(type default)
		)
		(layer "In11.Cu")
	)
	(gr_line
		(start 106.423206 -230.392478)
		(end 106.421936 -230.39324)
		(stroke
			(width 0.05715)
			(type default)
		)
		(layer "In11.Cu")
	)
	(gr_line
		(start 106.423206 -228.772466)
		(end 106.422698 -228.77272)
		(stroke
			(width 0.05715)
			(type default)
		)
		(layer "In11.Cu")
	)
	(gr_line
		(start 106.42346 -242.376706)
		(end 106.42854 -242.3795)
		(stroke
			(width 0.05715)
			(type default)
		)
		(layer "In11.Cu")
	)
	(gr_line
		(start 106.42346 -240.756694)
		(end 106.42854 -240.759488)
		(stroke
			(width 0.05715)
			(type default)
		)
		(layer "In11.Cu")
	)
	(gr_line
		(start 106.42346 -239.136682)
		(end 106.42854 -239.139476)
		(stroke
			(width 0.05715)
			(type default)
		)
		(layer "In11.Cu")
	)
	(gr_line
		(start 106.42346 -237.51667)
		(end 106.42854 -237.519464)
		(stroke
			(width 0.05715)
			(type default)
		)
		(layer "In11.Cu")
	)
	(gr_line
		(start 106.42346 -235.896658)
		(end 106.427016 -235.89869)
		(stroke
			(width 0.05715)
			(type default)
		)
		(layer "In11.Cu")
	)
	(gr_line
		(start 106.423968 -228.771958)
		(end 106.423206 -228.772466)
		(stroke
			(width 0.05715)
			(type default)
		)
		(layer "In11.Cu")
	)
	(gr_line
		(start 106.424984 -228.77145)
		(end 106.423968 -228.771958)
		(stroke
			(width 0.05715)
			(type default)
		)
		(layer "In11.Cu")
	)
	(gr_line
		(start 106.427016 -235.89869)
		(end 106.42854 -235.899452)
		(stroke
			(width 0.05715)
			(type default)
		)
		(layer "In11.Cu")
	)
	(gr_line
		(start 106.42854 -242.3795)
		(end 106.429302 -242.380008)
		(stroke
			(width 0.05715)
			(type default)
		)
		(layer "In11.Cu")
	)
	(gr_line
		(start 106.42854 -240.759488)
		(end 106.429302 -240.759996)
		(stroke
			(width 0.05715)
			(type default)
		)
		(layer "In11.Cu")
	)
	(gr_line
		(start 106.42854 -239.139476)
		(end 106.429302 -239.139984)
		(stroke
			(width 0.05715)
			(type default)
		)
		(layer "In11.Cu")
	)
	(gr_line
		(start 106.42854 -237.519464)
		(end 106.429302 -237.519972)
		(stroke
			(width 0.05715)
			(type default)
		)
		(layer "In11.Cu")
	)
	(gr_line
		(start 106.429302 -242.380008)
		(end 106.430318 -242.380516)
		(stroke
			(width 0.05715)
			(type default)
		)
		(layer "In11.Cu")
	)
	(gr_line
		(start 106.429302 -240.759996)
		(end 106.430318 -240.760504)
		(stroke
			(width 0.05715)
			(type default)
		)
		(layer "In11.Cu")
	)
	(gr_line
		(start 106.429302 -239.139984)
		(end 106.430318 -239.140492)
		(stroke
			(width 0.05715)
			(type default)
		)
		(layer "In11.Cu")
	)
	(gr_line
		(start 106.429302 -237.519972)
		(end 106.430318 -237.52048)
		(stroke
			(width 0.05715)
			(type default)
		)
		(layer "In11.Cu")
	)
	(gr_line
		(start 106.438954 -247.724422)
		(end 106.141012 -247.724422)
		(stroke
			(width 0.05715)
			(type default)
		)
		(layer "In11.Cu")
	)
	(gr_line
		(start 106.438954 -246.10441)
		(end 106.141012 -246.10441)
		(stroke
			(width 0.05715)
			(type default)
		)
		(layer "In11.Cu")
	)
	(gr_line
		(start 106.438954 -244.484398)
		(end 106.141012 -244.484398)
		(stroke
			(width 0.05715)
			(type default)
		)
		(layer "In11.Cu")
	)
	(gr_line
		(start 106.44505 -241.719608)
		(end 106.444796 -241.719608)
		(stroke
			(width 0.05715)
			(type default)
		)
		(layer "In11.Cu")
	)
	(gr_line
		(start 106.44505 -240.099596)
		(end 106.444796 -240.099596)
		(stroke
			(width 0.05715)
			(type default)
		)
		(layer "In11.Cu")
	)
	(gr_line
		(start 106.44505 -238.479584)
		(end 106.444796 -238.479584)
		(stroke
			(width 0.05715)
			(type default)
		)
		(layer "In11.Cu")
	)
	(gr_line
		(start 106.44505 -236.859572)
		(end 106.444796 -236.859572)
		(stroke
			(width 0.05715)
			(type default)
		)
		(layer "In11.Cu")
	)
	(gr_line
		(start 106.44505 -235.23956)
		(end 106.444796 -235.23956)
		(stroke
			(width 0.05715)
			(type default)
		)
		(layer "In11.Cu")
	)
	(gr_line
		(start 106.454194 -235.914438)
		(end 106.45521 -235.914946)
		(stroke
			(width 0.05715)
			(type default)
		)
		(layer "In11.Cu")
	)
	(gr_line
		(start 106.454448 -242.39474)
		(end 106.462322 -242.399312)
		(stroke
			(width 0.05715)
			(type default)
		)
		(layer "In11.Cu")
	)
	(gr_line
		(start 106.454448 -240.774728)
		(end 106.462322 -240.7793)
		(stroke
			(width 0.05715)
			(type default)
		)
		(layer "In11.Cu")
	)
	(gr_line
		(start 106.454448 -239.154716)
		(end 106.462322 -239.159288)
		(stroke
			(width 0.05715)
			(type default)
		)
		(layer "In11.Cu")
	)
	(gr_line
		(start 106.454448 -237.534704)
		(end 106.462322 -237.539276)
		(stroke
			(width 0.05715)
			(type default)
		)
		(layer "In11.Cu")
	)
	(gr_line
		(start 106.454702 -245.635018)
		(end 106.462322 -245.639336)
		(stroke
			(width 0.05715)
			(type default)
		)
		(layer "In11.Cu")
	)
	(gr_line
		(start 106.454956 -241.713766)
		(end 106.453432 -241.714782)
		(stroke
			(width 0.05715)
			(type default)
		)
		(layer "In11.Cu")
	)
	(gr_line
		(start 106.454956 -240.093754)
		(end 106.453432 -240.09477)
		(stroke
			(width 0.05715)
			(type default)
		)
		(layer "In11.Cu")
	)
	(gr_line
		(start 106.454956 -238.473742)
		(end 106.453432 -238.474758)
		(stroke
			(width 0.05715)
			(type default)
		)
		(layer "In11.Cu")
	)
	(gr_line
		(start 106.454956 -236.85373)
		(end 106.453432 -236.854746)
		(stroke
			(width 0.05715)
			(type default)
		)
		(layer "In11.Cu")
	)
	(gr_line
		(start 106.454956 -235.233718)
		(end 106.453432 -235.234734)
		(stroke
			(width 0.05715)
			(type default)
		)
		(layer "In11.Cu")
	)
	(gr_line
		(start 106.454956 -234.29468)
		(end 106.459528 -234.29722)
		(stroke
			(width 0.05715)
			(type default)
		)
		(layer "In11.Cu")
	)
	(gr_line
		(start 106.45521 -235.914946)
		(end 106.455972 -235.915454)
		(stroke
			(width 0.05715)
			(type default)
		)
		(layer "In11.Cu")
	)
	(gr_line
		(start 106.45521 -222.273622)
		(end 106.431842 -222.287338)
		(stroke
			(width 0.05715)
			(type default)
		)
		(layer "In11.Cu")
	)
	(gr_line
		(start 106.455972 -235.915454)
		(end 106.462322 -235.919264)
		(stroke
			(width 0.05715)
			(type default)
		)
		(layer "In11.Cu")
	)
	(gr_line
		(start 106.455972 -221.083378)
		(end 106.501692 -221.129098)
		(stroke
			(width 0.05715)
			(type default)
		)
		(layer "In11.Cu")
	)
	(gr_line
		(start 106.455972 -221.05493)
		(end 106.455972 -221.083378)
		(stroke
			(width 0.05715)
			(type default)
		)
		(layer "In11.Cu")
	)
	(gr_line
		(start 106.459528 -234.29722)
		(end 106.462322 -234.299252)
		(stroke
			(width 0.05715)
			(type default)
		)
		(layer "In11.Cu")
	)
	(gr_line
		(start 106.46029 -227.131118)
		(end 106.454956 -227.134166)
		(stroke
			(width 0.05715)
			(type default)
		)
		(layer "In11.Cu")
	)
	(gr_arc
		(start 106.462322 -245.639336)
		(mid 106.462703 -245.63959)
		(end 106.463084 -245.639844)
		(stroke
			(width 0.05715)
			(type default)
		)
		(layer "In11.Cu")
	)
	(gr_arc
		(start 106.462322 -242.399312)
		(mid 106.462703 -242.399566)
		(end 106.463084 -242.39982)
		(stroke
			(width 0.05715)
			(type default)
		)
		(layer "In11.Cu")
	)
	(gr_arc
		(start 106.462322 -240.7793)
		(mid 106.462703 -240.779554)
		(end 106.463084 -240.779808)
		(stroke
			(width 0.05715)
			(type default)
		)
		(layer "In11.Cu")
	)
	(gr_arc
		(start 106.462322 -239.159288)
		(mid 106.462703 -239.159542)
		(end 106.463084 -239.159796)
		(stroke
			(width 0.05715)
			(type default)
		)
		(layer "In11.Cu")
	)
	(gr_arc
		(start 106.462322 -237.539276)
		(mid 106.462703 -237.53953)
		(end 106.463084 -237.539784)
		(stroke
			(width 0.05715)
			(type default)
		)
		(layer "In11.Cu")
	)
	(gr_arc
		(start 106.462322 -235.919264)
		(mid 106.462703 -235.919518)
		(end 106.463084 -235.919772)
		(stroke
			(width 0.05715)
			(type default)
		)
		(layer "In11.Cu")
	)
	(gr_arc
		(start 106.462322 -234.299252)
		(mid 106.462703 -234.299506)
		(end 106.463084 -234.29976)
		(stroke
			(width 0.05715)
			(type default)
		)
		(layer "In11.Cu")
	)
	(gr_line
		(start 106.46283 -222.269558)
		(end 106.463084 -222.26905)
		(stroke
			(width 0.05715)
			(type default)
		)
		(layer "In11.Cu")
	)
	(gr_arc
		(start 106.46283 -222.269558)
		(mid 106.467034 -222.266528)
		(end 106.471212 -222.263462)
		(stroke
			(width 0.05715)
			(type default)
		)
		(layer "In11.Cu")
	)
	(gr_line
		(start 106.463084 -227.129086)
		(end 106.46029 -227.131118)
		(stroke
			(width 0.05715)
			(type default)
		)
		(layer "In11.Cu")
	)
	(gr_arc
		(start 106.463084 -227.129086)
		(mid 106.467033 -227.126309)
		(end 106.470958 -227.123498)
		(stroke
			(width 0.05715)
			(type default)
		)
		(layer "In11.Cu")
	)
	(gr_line
		(start 106.463084 -222.26905)
		(end 106.45521 -222.273622)
		(stroke
			(width 0.05715)
			(type default)
		)
		(layer "In11.Cu")
	)
	(gr_arc
		(start 106.470958 -242.405408)
		(mid 106.467033 -242.402597)
		(end 106.463084 -242.39982)
		(stroke
			(width 0.05715)
			(type default)
		)
		(layer "In11.Cu")
	)
	(gr_arc
		(start 106.470958 -240.785396)
		(mid 106.467033 -240.782585)
		(end 106.463084 -240.779808)
		(stroke
			(width 0.05715)
			(type default)
		)
		(layer "In11.Cu")
	)
	(gr_arc
		(start 106.470958 -239.165384)
		(mid 106.467033 -239.162573)
		(end 106.463084 -239.159796)
		(stroke
			(width 0.05715)
			(type default)
		)
		(layer "In11.Cu")
	)
	(gr_arc
		(start 106.470958 -237.545372)
		(mid 106.467033 -237.542561)
		(end 106.463084 -237.539784)
		(stroke
			(width 0.05715)
			(type default)
		)
		(layer "In11.Cu")
	)
	(gr_arc
		(start 106.470958 -235.92536)
		(mid 106.467033 -235.922549)
		(end 106.463084 -235.919772)
		(stroke
			(width 0.05715)
			(type default)
		)
		(layer "In11.Cu")
	)
	(gr_arc
		(start 106.470958 -234.305348)
		(mid 106.467033 -234.302537)
		(end 106.463084 -234.29976)
		(stroke
			(width 0.05715)
			(type default)
		)
		(layer "In11.Cu")
	)
	(gr_arc
		(start 106.471212 -245.645432)
		(mid 106.46716 -245.64262)
		(end 106.463084 -245.639844)
		(stroke
			(width 0.05715)
			(type default)
		)
		(layer "In11.Cu")
	)
	(gr_arc
		(start 106.473752 -229.447344)
		(mid 106.470586 -229.445046)
		(end 106.467402 -229.442772)
		(stroke
			(width 0.05715)
			(type default)
		)
		(layer "In11.Cu")
	)
	(gr_line
		(start 106.508296 -246.035068)
		(end 106.438954 -246.10441)
		(stroke
			(width 0.05715)
			(type default)
		)
		(layer "In11.Cu")
	)
	(gr_line
		(start 106.508296 -244.415056)
		(end 106.438954 -244.484398)
		(stroke
			(width 0.05715)
			(type default)
		)
		(layer "In11.Cu")
	)
	(gr_line
		(start 106.521758 -247.641618)
		(end 106.438954 -247.724422)
		(stroke
			(width 0.05715)
			(type default)
		)
		(layer "In11.Cu")
	)
	(gr_arc
		(start 106.525568 -247.618758)
		(mid 106.523546 -247.630168)
		(end 106.521758 -247.641618)
		(stroke
			(width 0.05715)
			(type default)
		)
		(layer "In11.Cu")
	)
	(gr_line
		(start 106.536236 -295.122346)
		(end 106.536236 -295.121076)
		(stroke
			(width 0.05715)
			(type default)
		)
		(layer "In11.Cu")
	)
	(gr_arc
		(start 106.589068 -286.581596)
		(mid 106.584351 -286.584873)
		(end 106.57967 -286.5882)
		(stroke
			(width 0.05715)
			(type default)
		)
		(layer "In11.Cu")
	)
	(gr_line
		(start 106.589068 -286.581596)
		(end 106.5911 -286.580072)
		(stroke
			(width 0.05715)
			(type default)
		)
		(layer "In11.Cu")
	)
	(gr_line
		(start 106.5911 -286.580072)
		(end 106.595926 -286.577278)
		(stroke
			(width 0.05715)
			(type default)
		)
		(layer "In11.Cu")
	)
	(gr_line
		(start 106.603292 -294.673274)
		(end 106.6038 -294.67302)
		(stroke
			(width 0.05715)
			(type default)
		)
		(layer "In11.Cu")
	)
	(gr_arc
		(start 106.70032 -246.021606)
		(mid 106.698528 -246.010284)
		(end 106.69651 -245.999)
		(stroke
			(width 0.05715)
			(type default)
		)
		(layer "In11.Cu")
	)
	(gr_line
		(start 106.70032 -246.021606)
		(end 106.783124 -246.10441)
		(stroke
			(width 0.05715)
			(type default)
		)
		(layer "In11.Cu")
	)
	(gr_arc
		(start 106.70032 -244.401594)
		(mid 106.698527 -244.390272)
		(end 106.69651 -244.378988)
		(stroke
			(width 0.05715)
			(type default)
		)
		(layer "In11.Cu")
	)
	(gr_line
		(start 106.70032 -244.401594)
		(end 106.783124 -244.484398)
		(stroke
			(width 0.05715)
			(type default)
		)
		(layer "In11.Cu")
	)
	(gr_line
		(start 106.706416 -221.700598)
		(end 106.706416 -221.707202)
		(stroke
			(width 0.05715)
			(type default)
		)
		(layer "In11.Cu")
	)
	(gr_line
		(start 106.713782 -247.65508)
		(end 106.783124 -247.724422)
		(stroke
			(width 0.05715)
			(type default)
		)
		(layer "In11.Cu")
	)
	(gr_line
		(start 106.72318 -277.004018)
		(end 106.72445 -277.00351)
		(stroke
			(width 0.05715)
			(type default)
		)
		(layer "In11.Cu")
	)
	(gr_line
		(start 106.723434 -286.72409)
		(end 106.723942 -286.723836)
		(stroke
			(width 0.05715)
			(type default)
		)
		(layer "In11.Cu")
	)
	(gr_line
		(start 106.737912 -221.083378)
		(end 106.692192 -221.129098)
		(stroke
			(width 0.05715)
			(type default)
		)
		(layer "In11.Cu")
	)
	(gr_line
		(start 106.737912 -221.05493)
		(end 106.737912 -221.083378)
		(stroke
			(width 0.05715)
			(type default)
		)
		(layer "In11.Cu")
	)
	(gr_line
		(start 106.738928 -279.756362)
		(end 106.440986 -279.756362)
		(stroke
			(width 0.05715)
			(type default)
		)
		(layer "In11.Cu")
	)
	(gr_line
		(start 106.738928 -278.13635)
		(end 106.440986 -278.13635)
		(stroke
			(width 0.05715)
			(type default)
		)
		(layer "In11.Cu")
	)
	(gr_line
		(start 106.738928 -276.516338)
		(end 106.440986 -276.516338)
		(stroke
			(width 0.05715)
			(type default)
		)
		(layer "In11.Cu")
	)
	(gr_line
		(start 106.738928 -274.896326)
		(end 106.440986 -274.896326)
		(stroke
			(width 0.05715)
			(type default)
		)
		(layer "In11.Cu")
	)
	(gr_line
		(start 106.754676 -294.805862)
		(end 106.761534 -294.801798)
		(stroke
			(width 0.05715)
			(type default)
		)
		(layer "In11.Cu")
	)
	(gr_arc
		(start 106.761534 -294.801798)
		(mid 106.762296 -294.801291)
		(end 106.763058 -294.800782)
		(stroke
			(width 0.05715)
			(type default)
		)
		(layer "In11.Cu")
	)
	(gr_arc
		(start 106.763058 -294.800782)
		(mid 106.766241 -294.798507)
		(end 106.769408 -294.79621)
		(stroke
			(width 0.05715)
			(type default)
		)
		(layer "In11.Cu")
	)
	(gr_line
		(start 106.783124 -247.724422)
		(end 107.081066 -247.724422)
		(stroke
			(width 0.05715)
			(type default)
		)
		(layer "In11.Cu")
	)
	(gr_line
		(start 106.783124 -246.10441)
		(end 107.081066 -246.10441)
		(stroke
			(width 0.05715)
			(type default)
		)
		(layer "In11.Cu")
	)
	(gr_line
		(start 106.783124 -244.484398)
		(end 107.081066 -244.484398)
		(stroke
			(width 0.05715)
			(type default)
		)
		(layer "In11.Cu")
	)
	(gr_line
		(start 106.797094 -225.531426)
		(end 106.79811 -225.531934)
		(stroke
			(width 0.05715)
			(type default)
		)
		(layer "In11.Cu")
	)
	(gr_line
		(start 106.80827 -278.205692)
		(end 106.738928 -278.13635)
		(stroke
			(width 0.05715)
			(type default)
		)
		(layer "In11.Cu")
	)
	(gr_line
		(start 106.80827 -276.58568)
		(end 106.738928 -276.516338)
		(stroke
			(width 0.05715)
			(type default)
		)
		(layer "In11.Cu")
	)
	(gr_line
		(start 106.821732 -279.839166)
		(end 106.738928 -279.756362)
		(stroke
			(width 0.05715)
			(type default)
		)
		(layer "In11.Cu")
	)
	(gr_arc
		(start 106.821732 -279.839166)
		(mid 106.823524 -279.850488)
		(end 106.825542 -279.861772)
		(stroke
			(width 0.05715)
			(type default)
		)
		(layer "In11.Cu")
	)
	(gr_line
		(start 106.821732 -274.97913)
		(end 106.738928 -274.896326)
		(stroke
			(width 0.05715)
			(type default)
		)
		(layer "In11.Cu")
	)
	(gr_arc
		(start 106.821732 -274.97913)
		(mid 106.823523 -274.990452)
		(end 106.825542 -275.001736)
		(stroke
			(width 0.05715)
			(type default)
		)
		(layer "In11.Cu")
	)
	(gr_line
		(start 106.82859 -380.666244)
		(end 106.82859 -380.720346)
		(stroke
			(width 0.07112)
			(type default)
		)
		(layer "In11.Cu")
	)
	(gr_line
		(start 106.829352 -379.96495)
		(end 106.82859 -380.666244)
		(stroke
			(width 0.07112)
			(type default)
		)
		(layer "In11.Cu")
	)
	(gr_line
		(start 106.89209 -225.365818)
		(end 106.89336 -225.36658)
		(stroke
			(width 0.05715)
			(type default)
		)
		(layer "In11.Cu")
	)
	(gr_line
		(start 106.89336 -225.36658)
		(end 106.894122 -225.367088)
		(stroke
			(width 0.05715)
			(type default)
		)
		(layer "In11.Cu")
	)
	(gr_line
		(start 106.924856 -225.384868)
		(end 106.925618 -225.385376)
		(stroke
			(width 0.05715)
			(type default)
		)
		(layer "In11.Cu")
	)
	(gr_line
		(start 106.925618 -225.385376)
		(end 106.92638 -225.385884)
		(stroke
			(width 0.05715)
			(type default)
		)
		(layer "In11.Cu")
	)
	(gr_line
		(start 106.92638 -225.385884)
		(end 106.933238 -225.389948)
		(stroke
			(width 0.05715)
			(type default)
		)
		(layer "In11.Cu")
	)
	(gr_arc
		(start 106.941112 -225.395536)
		(mid 106.937187 -225.392725)
		(end 106.933238 -225.389948)
		(stroke
			(width 0.05715)
			(type default)
		)
		(layer "In11.Cu")
	)
	(gr_line
		(start 106.962702 -376.126502)
		(end 106.907838 -376.825764)
		(stroke
			(width 0.07112)
			(type default)
		)
		(layer "In11.Cu")
	)
	(gr_line
		(start 106.985816 -224.234502)
		(end 106.98607 -224.234502)
		(stroke
			(width 0.05715)
			(type default)
		)
		(layer "In11.Cu")
	)
	(gr_line
		(start 106.98607 -224.234502)
		(end 106.98607 -224.235772)
		(stroke
			(width 0.05715)
			(type default)
		)
		(layer "In11.Cu")
	)
	(gr_arc
		(start 106.98607 -224.221802)
		(mid 106.985907 -224.228151)
		(end 106.985816 -224.234502)
		(stroke
			(width 0.05715)
			(type default)
		)
		(layer "In11.Cu")
	)
	(gr_arc
		(start 106.996484 -278.242014)
		(mid 106.998505 -278.230603)
		(end 107.000294 -278.219154)
		(stroke
			(width 0.05715)
			(type default)
		)
		(layer "In11.Cu")
	)
	(gr_arc
		(start 106.996484 -276.622002)
		(mid 106.998505 -276.610591)
		(end 107.000294 -276.599142)
		(stroke
			(width 0.05715)
			(type default)
		)
		(layer "In11.Cu")
	)
	(gr_line
		(start 107.000294 -278.219154)
		(end 107.083098 -278.13635)
		(stroke
			(width 0.05715)
			(type default)
		)
		(layer "In11.Cu")
	)
	(gr_line
		(start 107.000294 -276.599142)
		(end 107.083098 -276.516338)
		(stroke
			(width 0.05715)
			(type default)
		)
		(layer "In11.Cu")
	)
	(gr_line
		(start 107.013756 -279.825704)
		(end 107.083098 -279.756362)
		(stroke
			(width 0.05715)
			(type default)
		)
		(layer "In11.Cu")
	)
	(gr_line
		(start 107.013756 -274.965668)
		(end 107.083098 -274.896326)
		(stroke
			(width 0.05715)
			(type default)
		)
		(layer "In11.Cu")
	)
	(gr_line
		(start 107.014264 -296.612564)
		(end 107.014264 -296.584116)
		(stroke
			(width 0.05715)
			(type default)
		)
		(layer "In11.Cu")
	)
	(gr_line
		(start 107.014264 -296.584116)
		(end 107.059984 -296.538396)
		(stroke
			(width 0.05715)
			(type default)
		)
		(layer "In11.Cu")
	)
	(gr_line
		(start 107.052364 -295.49598)
		(end 107.059222 -295.491154)
		(stroke
			(width 0.05715)
			(type default)
		)
		(layer "In11.Cu")
	)
	(gr_line
		(start 107.059222 -295.491154)
		(end 107.059476 -295.4909)
		(stroke
			(width 0.05715)
			(type default)
		)
		(layer "In11.Cu")
	)
	(gr_line
		(start 107.059476 -295.4909)
		(end 107.067096 -295.486582)
		(stroke
			(width 0.05715)
			(type default)
		)
		(layer "In11.Cu")
	)
	(gr_line
		(start 107.083098 -279.756362)
		(end 107.38104 -279.756362)
		(stroke
			(width 0.05715)
			(type default)
		)
		(layer "In11.Cu")
	)
	(gr_line
		(start 107.083098 -278.13635)
		(end 107.38104 -278.13635)
		(stroke
			(width 0.05715)
			(type default)
		)
		(layer "In11.Cu")
	)
	(gr_line
		(start 107.083098 -276.516338)
		(end 107.38104 -276.516338)
		(stroke
			(width 0.05715)
			(type default)
		)
		(layer "In11.Cu")
	)
	(gr_line
		(start 107.083098 -274.896326)
		(end 107.38104 -274.896326)
		(stroke
			(width 0.05715)
			(type default)
		)
		(layer "In11.Cu")
	)
	(gr_line
		(start 107.11053 -380.666498)
		(end 107.11053 -380.720346)
		(stroke
			(width 0.07112)
			(type default)
		)
		(layer "In11.Cu")
	)
	(gr_line
		(start 107.112562 -379.96622)
		(end 107.248452 -380.102364)
		(stroke
			(width 0.07112)
			(type default)
		)
		(layer "In11.Cu")
	)
	(gr_line
		(start 107.147614 -373.76862)
		(end 107.09275 -374.467882)
		(stroke
			(width 0.07112)
			(type default)
		)
		(layer "In11.Cu")
	)
	(gr_line
		(start 107.194096 -295.633648)
		(end 107.194096 -295.633394)
		(stroke
			(width 0.05715)
			(type default)
		)
		(layer "In11.Cu")
	)
	(gr_arc
		(start 107.216448 -223.070166)
		(mid 107.221382 -223.073748)
		(end 107.226354 -223.077278)
		(stroke
			(width 0.05715)
			(type default)
		)
		(layer "In11.Cu")
	)
	(gr_arc
		(start 107.22102 -244.13337)
		(mid 107.224945 -244.136181)
		(end 107.228894 -244.138958)
		(stroke
			(width 0.05715)
			(type default)
		)
		(layer "In11.Cu")
	)
	(gr_arc
		(start 107.22102 -240.893346)
		(mid 107.224945 -240.896157)
		(end 107.228894 -240.898934)
		(stroke
			(width 0.05715)
			(type default)
		)
		(layer "In11.Cu")
	)
	(gr_arc
		(start 107.22102 -239.273334)
		(mid 107.224945 -239.276145)
		(end 107.228894 -239.278922)
		(stroke
			(width 0.05715)
			(type default)
		)
		(layer "In11.Cu")
	)
	(gr_arc
		(start 107.22102 -236.03331)
		(mid 107.224945 -236.036121)
		(end 107.228894 -236.038898)
		(stroke
			(width 0.05715)
			(type default)
		)
		(layer "In11.Cu")
	)
	(gr_arc
		(start 107.22102 -234.413298)
		(mid 107.224945 -234.416109)
		(end 107.228894 -234.418886)
		(stroke
			(width 0.05715)
			(type default)
		)
		(layer "In11.Cu")
	)
	(gr_arc
		(start 107.22102 -232.793286)
		(mid 107.224945 -232.796097)
		(end 107.228894 -232.798874)
		(stroke
			(width 0.05715)
			(type default)
		)
		(layer "In11.Cu")
	)
	(gr_line
		(start 107.221274 -295.617646)
		(end 107.222036 -295.617138)
		(stroke
			(width 0.05715)
			(type default)
		)
		(layer "In11.Cu")
	)
	(gr_line
		(start 107.222036 -295.617138)
		(end 107.230418 -295.612566)
		(stroke
			(width 0.05715)
			(type default)
		)
		(layer "In11.Cu")
	)
	(gr_line
		(start 107.228894 -244.138958)
		(end 107.235752 -244.143022)
		(stroke
			(width 0.05715)
			(type default)
		)
		(layer "In11.Cu")
	)
	(gr_line
		(start 107.228894 -240.898934)
		(end 107.235752 -240.902998)
		(stroke
			(width 0.05715)
			(type default)
		)
		(layer "In11.Cu")
	)
	(gr_line
		(start 107.228894 -239.278922)
		(end 107.235752 -239.282986)
		(stroke
			(width 0.05715)
			(type default)
		)
		(layer "In11.Cu")
	)
	(gr_line
		(start 107.228894 -236.038898)
		(end 107.235752 -236.042962)
		(stroke
			(width 0.05715)
			(type default)
		)
		(layer "In11.Cu")
	)
	(gr_line
		(start 107.228894 -234.418886)
		(end 107.235752 -234.42295)
		(stroke
			(width 0.05715)
			(type default)
		)
		(layer "In11.Cu")
	)
	(gr_line
		(start 107.228894 -232.798874)
		(end 107.235752 -232.802938)
		(stroke
			(width 0.05715)
			(type default)
		)
		(layer "In11.Cu")
	)
	(gr_arc
		(start 107.230418 -295.612566)
		(mid 107.236029 -295.608534)
		(end 107.241594 -295.604438)
		(stroke
			(width 0.05715)
			(type default)
		)
		(layer "In11.Cu")
	)
	(gr_line
		(start 107.235752 -244.143022)
		(end 107.236514 -244.14353)
		(stroke
			(width 0.05715)
			(type default)
		)
		(layer "In11.Cu")
	)
	(gr_line
		(start 107.235752 -240.902998)
		(end 107.236514 -240.903506)
		(stroke
			(width 0.05715)
			(type default)
		)
		(layer "In11.Cu")
	)
	(gr_line
		(start 107.235752 -239.282986)
		(end 107.236514 -239.283494)
		(stroke
			(width 0.05715)
			(type default)
		)
		(layer "In11.Cu")
	)
	(gr_line
		(start 107.235752 -236.042962)
		(end 107.236514 -236.04347)
		(stroke
			(width 0.05715)
			(type default)
		)
		(layer "In11.Cu")
	)
	(gr_line
		(start 107.235752 -234.42295)
		(end 107.236514 -234.423458)
		(stroke
			(width 0.05715)
			(type default)
		)
		(layer "In11.Cu")
	)
	(gr_line
		(start 107.235752 -232.802938)
		(end 107.236514 -232.803446)
		(stroke
			(width 0.05715)
			(type default)
		)
		(layer "In11.Cu")
	)
	(gr_line
		(start 107.236514 -244.14353)
		(end 107.237022 -244.143784)
		(stroke
			(width 0.05715)
			(type default)
		)
		(layer "In11.Cu")
	)
	(gr_line
		(start 107.236514 -240.903506)
		(end 107.237022 -240.90376)
		(stroke
			(width 0.05715)
			(type default)
		)
		(layer "In11.Cu")
	)
	(gr_line
		(start 107.236514 -239.283494)
		(end 107.237022 -239.283748)
		(stroke
			(width 0.05715)
			(type default)
		)
		(layer "In11.Cu")
	)
	(gr_line
		(start 107.236514 -236.04347)
		(end 107.237022 -236.043724)
		(stroke
			(width 0.05715)
			(type default)
		)
		(layer "In11.Cu")
	)
	(gr_line
		(start 107.236514 -234.423458)
		(end 107.237022 -234.423712)
		(stroke
			(width 0.05715)
			(type default)
		)
		(layer "In11.Cu")
	)
	(gr_line
		(start 107.236514 -232.803446)
		(end 107.237022 -232.8037)
		(stroke
			(width 0.05715)
			(type default)
		)
		(layer "In11.Cu")
	)
	(gr_line
		(start 107.244896 -376.14987)
		(end 107.370118 -376.296174)
		(stroke
			(width 0.07112)
			(type default)
		)
		(layer "In11.Cu")
	)
	(gr_line
		(start 107.248198 -380.529338)
		(end 107.1118 -380.665228)
		(stroke
			(width 0.07112)
			(type default)
		)
		(layer "In11.Cu")
	)
	(gr_line
		(start 107.248452 -380.102364)
		(end 107.248198 -380.529338)
		(stroke
			(width 0.07112)
			(type default)
		)
		(layer "In11.Cu")
	)
	(gr_line
		(start 107.26166 -244.158008)
		(end 107.262676 -244.15877)
		(stroke
			(width 0.05715)
			(type default)
		)
		(layer "In11.Cu")
	)
	(gr_line
		(start 107.26166 -240.917984)
		(end 107.262676 -240.918746)
		(stroke
			(width 0.05715)
			(type default)
		)
		(layer "In11.Cu")
	)
	(gr_line
		(start 107.26166 -239.297972)
		(end 107.262676 -239.298734)
		(stroke
			(width 0.05715)
			(type default)
		)
		(layer "In11.Cu")
	)
	(gr_line
		(start 107.26166 -236.057948)
		(end 107.262676 -236.05871)
		(stroke
			(width 0.05715)
			(type default)
		)
		(layer "In11.Cu")
	)
	(gr_line
		(start 107.26166 -234.437936)
		(end 107.262676 -234.438698)
		(stroke
			(width 0.05715)
			(type default)
		)
		(layer "In11.Cu")
	)
	(gr_line
		(start 107.26166 -232.817924)
		(end 107.262676 -232.818686)
		(stroke
			(width 0.05715)
			(type default)
		)
		(layer "In11.Cu")
	)
	(gr_line
		(start 107.262676 -244.15877)
		(end 107.263692 -244.159278)
		(stroke
			(width 0.05715)
			(type default)
		)
		(layer "In11.Cu")
	)
	(gr_line
		(start 107.262676 -240.918746)
		(end 107.263692 -240.919254)
		(stroke
			(width 0.05715)
			(type default)
		)
		(layer "In11.Cu")
	)
	(gr_line
		(start 107.262676 -239.298734)
		(end 107.263692 -239.299242)
		(stroke
			(width 0.05715)
			(type default)
		)
		(layer "In11.Cu")
	)
	(gr_line
		(start 107.262676 -236.05871)
		(end 107.263692 -236.059218)
		(stroke
			(width 0.05715)
			(type default)
		)
		(layer "In11.Cu")
	)
	(gr_line
		(start 107.262676 -234.438698)
		(end 107.263692 -234.439206)
		(stroke
			(width 0.05715)
			(type default)
		)
		(layer "In11.Cu")
	)
	(gr_line
		(start 107.262676 -232.818686)
		(end 107.263692 -232.819194)
		(stroke
			(width 0.05715)
			(type default)
		)
		(layer "In11.Cu")
	)
	(gr_line
		(start 107.265724 -246.42826)
		(end 107.265216 -246.428514)
		(stroke
			(width 0.05715)
			(type default)
		)
		(layer "In11.Cu")
	)
	(gr_line
		(start 107.265724 -244.808248)
		(end 107.265216 -244.808502)
		(stroke
			(width 0.05715)
			(type default)
		)
		(layer "In11.Cu")
	)
	(gr_line
		(start 107.265724 -243.188236)
		(end 107.265216 -243.18849)
		(stroke
			(width 0.05715)
			(type default)
		)
		(layer "In11.Cu")
	)
	(gr_line
		(start 107.265724 -241.568224)
		(end 107.265216 -241.568478)
		(stroke
			(width 0.05715)
			(type default)
		)
		(layer "In11.Cu")
	)
	(gr_line
		(start 107.265724 -239.948212)
		(end 107.265216 -239.948466)
		(stroke
			(width 0.05715)
			(type default)
		)
		(layer "In11.Cu")
	)
	(gr_line
		(start 107.265724 -236.708188)
		(end 107.265216 -236.708442)
		(stroke
			(width 0.05715)
			(type default)
		)
		(layer "In11.Cu")
	)
	(gr_line
		(start 107.265724 -235.088176)
		(end 107.265216 -235.08843)
		(stroke
			(width 0.05715)
			(type default)
		)
		(layer "In11.Cu")
	)
	(gr_line
		(start 107.265724 -233.468164)
		(end 107.265216 -233.468418)
		(stroke
			(width 0.05715)
			(type default)
		)
		(layer "In11.Cu")
	)
	(gr_line
		(start 107.265724 -231.848152)
		(end 107.265216 -231.848406)
		(stroke
			(width 0.05715)
			(type default)
		)
		(layer "In11.Cu")
	)
	(gr_line
		(start 107.266232 -244.160802)
		(end 107.266994 -244.16131)
		(stroke
			(width 0.05715)
			(type default)
		)
		(layer "In11.Cu")
	)
	(gr_line
		(start 107.266232 -240.920778)
		(end 107.266994 -240.921286)
		(stroke
			(width 0.05715)
			(type default)
		)
		(layer "In11.Cu")
	)
	(gr_line
		(start 107.266232 -239.300766)
		(end 107.266994 -239.301274)
		(stroke
			(width 0.05715)
			(type default)
		)
		(layer "In11.Cu")
	)
	(gr_line
		(start 107.266232 -236.060742)
		(end 107.266994 -236.06125)
		(stroke
			(width 0.05715)
			(type default)
		)
		(layer "In11.Cu")
	)
	(gr_line
		(start 107.266232 -234.44073)
		(end 107.266994 -234.441238)
		(stroke
			(width 0.05715)
			(type default)
		)
		(layer "In11.Cu")
	)
	(gr_line
		(start 107.266232 -232.820718)
		(end 107.266994 -232.821226)
		(stroke
			(width 0.05715)
			(type default)
		)
		(layer "In11.Cu")
	)
	(gr_line
		(start 107.266994 -246.427498)
		(end 107.265724 -246.42826)
		(stroke
			(width 0.05715)
			(type default)
		)
		(layer "In11.Cu")
	)
	(gr_line
		(start 107.266994 -245.781322)
		(end 107.26801 -245.78183)
		(stroke
			(width 0.05715)
			(type default)
		)
		(layer "In11.Cu")
	)
	(gr_line
		(start 107.266994 -244.807486)
		(end 107.265724 -244.808248)
		(stroke
			(width 0.05715)
			(type default)
		)
		(layer "In11.Cu")
	)
	(gr_line
		(start 107.266994 -244.16131)
		(end 107.26801 -244.161818)
		(stroke
			(width 0.05715)
			(type default)
		)
		(layer "In11.Cu")
	)
	(gr_line
		(start 107.266994 -243.187474)
		(end 107.265724 -243.188236)
		(stroke
			(width 0.05715)
			(type default)
		)
		(layer "In11.Cu")
	)
	(gr_line
		(start 107.266994 -242.541298)
		(end 107.26801 -242.541806)
		(stroke
			(width 0.05715)
			(type default)
		)
		(layer "In11.Cu")
	)
	(gr_line
		(start 107.266994 -241.567462)
		(end 107.265724 -241.568224)
		(stroke
			(width 0.05715)
			(type default)
		)
		(layer "In11.Cu")
	)
	(gr_line
		(start 107.266994 -240.921286)
		(end 107.26801 -240.921794)
		(stroke
			(width 0.05715)
			(type default)
		)
		(layer "In11.Cu")
	)
	(gr_line
		(start 107.266994 -239.94745)
		(end 107.265724 -239.948212)
		(stroke
			(width 0.05715)
			(type default)
		)
		(layer "In11.Cu")
	)
	(gr_line
		(start 107.266994 -239.301274)
		(end 107.26801 -239.301782)
		(stroke
			(width 0.05715)
			(type default)
		)
		(layer "In11.Cu")
	)
	(gr_line
		(start 107.266994 -237.681262)
		(end 107.26801 -237.68177)
		(stroke
			(width 0.05715)
			(type default)
		)
		(layer "In11.Cu")
	)
	(gr_line
		(start 107.266994 -236.707426)
		(end 107.265724 -236.708188)
		(stroke
			(width 0.05715)
			(type default)
		)
		(layer "In11.Cu")
	)
	(gr_line
		(start 107.266994 -236.06125)
		(end 107.26801 -236.061758)
		(stroke
			(width 0.05715)
			(type default)
		)
		(layer "In11.Cu")
	)
	(gr_line
		(start 107.266994 -235.087414)
		(end 107.265724 -235.088176)
		(stroke
			(width 0.05715)
			(type default)
		)
		(layer "In11.Cu")
	)
	(gr_line
		(start 107.266994 -234.441238)
		(end 107.26801 -234.441746)
		(stroke
			(width 0.05715)
			(type default)
		)
		(layer "In11.Cu")
	)
	(gr_line
		(start 107.266994 -233.467402)
		(end 107.265724 -233.468164)
		(stroke
			(width 0.05715)
			(type default)
		)
		(layer "In11.Cu")
	)
	(gr_line
		(start 107.266994 -232.821226)
		(end 107.26801 -232.821734)
		(stroke
			(width 0.05715)
			(type default)
		)
		(layer "In11.Cu")
	)
	(gr_line
		(start 107.266994 -231.84739)
		(end 107.265724 -231.848152)
		(stroke
			(width 0.05715)
			(type default)
		)
		(layer "In11.Cu")
	)
	(gr_line
		(start 107.26801 -246.42699)
		(end 107.266994 -246.427498)
		(stroke
			(width 0.05715)
			(type default)
		)
		(layer "In11.Cu")
	)
	(gr_line
		(start 107.26801 -245.78183)
		(end 107.268518 -245.782084)
		(stroke
			(width 0.05715)
			(type default)
		)
		(layer "In11.Cu")
	)
	(gr_line
		(start 107.26801 -244.806978)
		(end 107.266994 -244.807486)
		(stroke
			(width 0.05715)
			(type default)
		)
		(layer "In11.Cu")
	)
	(gr_line
		(start 107.26801 -244.161818)
		(end 107.268772 -244.162326)
		(stroke
			(width 0.05715)
			(type default)
		)
		(layer "In11.Cu")
	)
	(gr_line
		(start 107.26801 -243.186966)
		(end 107.266994 -243.187474)
		(stroke
			(width 0.05715)
			(type default)
		)
		(layer "In11.Cu")
	)
	(gr_line
		(start 107.26801 -242.541806)
		(end 107.268518 -242.54206)
		(stroke
			(width 0.05715)
			(type default)
		)
		(layer "In11.Cu")
	)
	(gr_line
		(start 107.26801 -241.566954)
		(end 107.266994 -241.567462)
		(stroke
			(width 0.05715)
			(type default)
		)
		(layer "In11.Cu")
	)
	(gr_line
		(start 107.26801 -240.921794)
		(end 107.268772 -240.922302)
		(stroke
			(width 0.05715)
			(type default)
		)
		(layer "In11.Cu")
	)
	(gr_line
		(start 107.26801 -239.946942)
		(end 107.266994 -239.94745)
		(stroke
			(width 0.05715)
			(type default)
		)
		(layer "In11.Cu")
	)
	(gr_line
		(start 107.26801 -239.301782)
		(end 107.268772 -239.30229)
		(stroke
			(width 0.05715)
			(type default)
		)
		(layer "In11.Cu")
	)
	(gr_line
		(start 107.26801 -237.68177)
		(end 107.268518 -237.682024)
		(stroke
			(width 0.05715)
			(type default)
		)
		(layer "In11.Cu")
	)
	(gr_line
		(start 107.26801 -236.706918)
		(end 107.266994 -236.707426)
		(stroke
			(width 0.05715)
			(type default)
		)
		(layer "In11.Cu")
	)
	(gr_line
		(start 107.26801 -236.061758)
		(end 107.268772 -236.062266)
		(stroke
			(width 0.05715)
			(type default)
		)
		(layer "In11.Cu")
	)
	(gr_line
		(start 107.26801 -235.086906)
		(end 107.266994 -235.087414)
		(stroke
			(width 0.05715)
			(type default)
		)
		(layer "In11.Cu")
	)
	(gr_line
		(start 107.26801 -234.441746)
		(end 107.268772 -234.442254)
		(stroke
			(width 0.05715)
			(type default)
		)
		(layer "In11.Cu")
	)
	(gr_line
		(start 107.26801 -233.466894)
		(end 107.266994 -233.467402)
		(stroke
			(width 0.05715)
			(type default)
		)
		(layer "In11.Cu")
	)
	(gr_line
		(start 107.26801 -232.821734)
		(end 107.268772 -232.822242)
		(stroke
			(width 0.05715)
			(type default)
		)
		(layer "In11.Cu")
	)
	(gr_line
		(start 107.26801 -231.846882)
		(end 107.266994 -231.84739)
		(stroke
			(width 0.05715)
			(type default)
		)
		(layer "In11.Cu")
	)
	(gr_line
		(start 107.268772 -246.426482)
		(end 107.26801 -246.42699)
		(stroke
			(width 0.05715)
			(type default)
		)
		(layer "In11.Cu")
	)
	(gr_line
		(start 107.268772 -244.80647)
		(end 107.26801 -244.806978)
		(stroke
			(width 0.05715)
			(type default)
		)
		(layer "In11.Cu")
	)
	(gr_line
		(start 107.268772 -244.162326)
		(end 107.271566 -244.16385)
		(stroke
			(width 0.05715)
			(type default)
		)
		(layer "In11.Cu")
	)
	(gr_line
		(start 107.268772 -243.186458)
		(end 107.26801 -243.186966)
		(stroke
			(width 0.05715)
			(type default)
		)
		(layer "In11.Cu")
	)
	(gr_line
		(start 107.268772 -241.566446)
		(end 107.26801 -241.566954)
		(stroke
			(width 0.05715)
			(type default)
		)
		(layer "In11.Cu")
	)
	(gr_line
		(start 107.268772 -240.922302)
		(end 107.271566 -240.923826)
		(stroke
			(width 0.05715)
			(type default)
		)
		(layer "In11.Cu")
	)
	(gr_line
		(start 107.268772 -239.946434)
		(end 107.26801 -239.946942)
		(stroke
			(width 0.05715)
			(type default)
		)
		(layer "In11.Cu")
	)
	(gr_line
		(start 107.268772 -239.30229)
		(end 107.271566 -239.303814)
		(stroke
			(width 0.05715)
			(type default)
		)
		(layer "In11.Cu")
	)
	(gr_line
		(start 107.268772 -236.70641)
		(end 107.26801 -236.706918)
		(stroke
			(width 0.05715)
			(type default)
		)
		(layer "In11.Cu")
	)
	(gr_line
		(start 107.268772 -236.062266)
		(end 107.271566 -236.06379)
		(stroke
			(width 0.05715)
			(type default)
		)
		(layer "In11.Cu")
	)
	(gr_line
		(start 107.268772 -235.086398)
		(end 107.26801 -235.086906)
		(stroke
			(width 0.05715)
			(type default)
		)
		(layer "In11.Cu")
	)
	(gr_line
		(start 107.268772 -234.442254)
		(end 107.271566 -234.443778)
		(stroke
			(width 0.05715)
			(type default)
		)
		(layer "In11.Cu")
	)
	(gr_line
		(start 107.268772 -233.466386)
		(end 107.26801 -233.466894)
		(stroke
			(width 0.05715)
			(type default)
		)
		(layer "In11.Cu")
	)
	(gr_line
		(start 107.268772 -232.822242)
		(end 107.271566 -232.823766)
		(stroke
			(width 0.05715)
			(type default)
		)
		(layer "In11.Cu")
	)
	(gr_line
		(start 107.268772 -231.846374)
		(end 107.26801 -231.846882)
		(stroke
			(width 0.05715)
			(type default)
		)
		(layer "In11.Cu")
	)
	(gr_line
		(start 107.270042 -238.32566)
		(end 107.268772 -238.326422)
		(stroke
			(width 0.05715)
			(type default)
		)
		(layer "In11.Cu")
	)
	(gr_line
		(start 107.270296 -223.745806)
		(end 107.269026 -223.746568)
		(stroke
			(width 0.05715)
			(type default)
		)
		(layer "In11.Cu")
	)
	(gr_line
		(start 107.27055 -246.425466)
		(end 107.268772 -246.426482)
		(stroke
			(width 0.05715)
			(type default)
		)
		(layer "In11.Cu")
	)
	(gr_line
		(start 107.27055 -244.805454)
		(end 107.268772 -244.80647)
		(stroke
			(width 0.05715)
			(type default)
		)
		(layer "In11.Cu")
	)
	(gr_line
		(start 107.27055 -243.185442)
		(end 107.268772 -243.186458)
		(stroke
			(width 0.05715)
			(type default)
		)
		(layer "In11.Cu")
	)
	(gr_line
		(start 107.27055 -241.56543)
		(end 107.268772 -241.566446)
		(stroke
			(width 0.05715)
			(type default)
		)
		(layer "In11.Cu")
	)
	(gr_line
		(start 107.27055 -239.945418)
		(end 107.268772 -239.946434)
		(stroke
			(width 0.05715)
			(type default)
		)
		(layer "In11.Cu")
	)
	(gr_line
		(start 107.27055 -236.705394)
		(end 107.268772 -236.70641)
		(stroke
			(width 0.05715)
			(type default)
		)
		(layer "In11.Cu")
	)
	(gr_line
		(start 107.27055 -235.085382)
		(end 107.268772 -235.086398)
		(stroke
			(width 0.05715)
			(type default)
		)
		(layer "In11.Cu")
	)
	(gr_line
		(start 107.27055 -233.46537)
		(end 107.268772 -233.466386)
		(stroke
			(width 0.05715)
			(type default)
		)
		(layer "In11.Cu")
	)
	(gr_line
		(start 107.27055 -231.845358)
		(end 107.268772 -231.846374)
		(stroke
			(width 0.05715)
			(type default)
		)
		(layer "In11.Cu")
	)
	(gr_line
		(start 107.272074 -223.74479)
		(end 107.270296 -223.745806)
		(stroke
			(width 0.05715)
			(type default)
		)
		(layer "In11.Cu")
	)
	(gr_line
		(start 107.272328 -244.164358)
		(end 107.273344 -244.164866)
		(stroke
			(width 0.05715)
			(type default)
		)
		(layer "In11.Cu")
	)
	(gr_line
		(start 107.272328 -240.924334)
		(end 107.273344 -240.924842)
		(stroke
			(width 0.05715)
			(type default)
		)
		(layer "In11.Cu")
	)
	(gr_line
		(start 107.272328 -239.304322)
		(end 107.273344 -239.30483)
		(stroke
			(width 0.05715)
			(type default)
		)
		(layer "In11.Cu")
	)
	(gr_line
		(start 107.272328 -236.064298)
		(end 107.273344 -236.064806)
		(stroke
			(width 0.05715)
			(type default)
		)
		(layer "In11.Cu")
	)
	(gr_line
		(start 107.272328 -234.444286)
		(end 107.273344 -234.444794)
		(stroke
			(width 0.05715)
			(type default)
		)
		(layer "In11.Cu")
	)
	(gr_line
		(start 107.272328 -232.824274)
		(end 107.273344 -232.824782)
		(stroke
			(width 0.05715)
			(type default)
		)
		(layer "In11.Cu")
	)
	(gr_arc
		(start 107.28579 -275.706332)
		(mid 107.286231 -275.719443)
		(end 107.287568 -275.732494)
		(stroke
			(width 0.05715)
			(type default)
		)
		(layer "In11.Cu")
	)
	(gr_line
		(start 107.289346 -287.080706)
		(end 107.289092 -287.079436)
		(stroke
			(width 0.05715)
			(type default)
		)
		(layer "In11.Cu")
	)
	(gr_line
		(start 107.296204 -296.612564)
		(end 107.296204 -296.584116)
		(stroke
			(width 0.05715)
			(type default)
		)
		(layer "In11.Cu")
	)
	(gr_line
		(start 107.296204 -296.584116)
		(end 107.250484 -296.538396)
		(stroke
			(width 0.05715)
			(type default)
		)
		(layer "In11.Cu")
	)
	(gr_line
		(start 107.332272 -222.918782)
		(end 107.332272 -222.918528)
		(stroke
			(width 0.05715)
			(type default)
		)
		(layer "In11.Cu")
	)
	(gr_line
		(start 107.33659 -376.721878)
		(end 107.190286 -376.846846)
		(stroke
			(width 0.07112)
			(type default)
		)
		(layer "In11.Cu")
	)
	(gr_line
		(start 107.356402 -243.992654)
		(end 107.35691 -243.992908)
		(stroke
			(width 0.05715)
			(type default)
		)
		(layer "In11.Cu")
	)
	(gr_line
		(start 107.356402 -240.75263)
		(end 107.35691 -240.752884)
		(stroke
			(width 0.05715)
			(type default)
		)
		(layer "In11.Cu")
	)
	(gr_line
		(start 107.356402 -239.132618)
		(end 107.35691 -239.132872)
		(stroke
			(width 0.05715)
			(type default)
		)
		(layer "In11.Cu")
	)
	(gr_line
		(start 107.356402 -235.892594)
		(end 107.35691 -235.892848)
		(stroke
			(width 0.05715)
			(type default)
		)
		(layer "In11.Cu")
	)
	(gr_line
		(start 107.356402 -234.272582)
		(end 107.35691 -234.272836)
		(stroke
			(width 0.05715)
			(type default)
		)
		(layer "In11.Cu")
	)
	(gr_line
		(start 107.356402 -232.65257)
		(end 107.35691 -232.652824)
		(stroke
			(width 0.05715)
			(type default)
		)
		(layer "In11.Cu")
	)
	(gr_line
		(start 107.35691 -243.992908)
		(end 107.357926 -243.993416)
		(stroke
			(width 0.05715)
			(type default)
		)
		(layer "In11.Cu")
	)
	(gr_line
		(start 107.35691 -240.752884)
		(end 107.357926 -240.753392)
		(stroke
			(width 0.05715)
			(type default)
		)
		(layer "In11.Cu")
	)
	(gr_line
		(start 107.35691 -239.132872)
		(end 107.357926 -239.13338)
		(stroke
			(width 0.05715)
			(type default)
		)
		(layer "In11.Cu")
	)
	(gr_line
		(start 107.35691 -235.892848)
		(end 107.357926 -235.893356)
		(stroke
			(width 0.05715)
			(type default)
		)
		(layer "In11.Cu")
	)
	(gr_line
		(start 107.35691 -234.272836)
		(end 107.357926 -234.273344)
		(stroke
			(width 0.05715)
			(type default)
		)
		(layer "In11.Cu")
	)
	(gr_line
		(start 107.35691 -232.652824)
		(end 107.357926 -232.653332)
		(stroke
			(width 0.05715)
			(type default)
		)
		(layer "In11.Cu")
	)
	(gr_line
		(start 107.358688 -243.993924)
		(end 107.35945 -243.994432)
		(stroke
			(width 0.05715)
			(type default)
		)
		(layer "In11.Cu")
	)
	(gr_line
		(start 107.358688 -240.7539)
		(end 107.35945 -240.754408)
		(stroke
			(width 0.05715)
			(type default)
		)
		(layer "In11.Cu")
	)
	(gr_line
		(start 107.358688 -239.133888)
		(end 107.35945 -239.134396)
		(stroke
			(width 0.05715)
			(type default)
		)
		(layer "In11.Cu")
	)
	(gr_line
		(start 107.358688 -235.893864)
		(end 107.35945 -235.894372)
		(stroke
			(width 0.05715)
			(type default)
		)
		(layer "In11.Cu")
	)
	(gr_line
		(start 107.358688 -234.273852)
		(end 107.35945 -234.27436)
		(stroke
			(width 0.05715)
			(type default)
		)
		(layer "In11.Cu")
	)
	(gr_line
		(start 107.358688 -232.65384)
		(end 107.35945 -232.654348)
		(stroke
			(width 0.05715)
			(type default)
		)
		(layer "In11.Cu")
	)
	(gr_line
		(start 107.360466 -246.593868)
		(end 107.359704 -246.594376)
		(stroke
			(width 0.05715)
			(type default)
		)
		(layer "In11.Cu")
	)
	(gr_line
		(start 107.360466 -244.973856)
		(end 107.359704 -244.974364)
		(stroke
			(width 0.05715)
			(type default)
		)
		(layer "In11.Cu")
	)
	(gr_line
		(start 107.360466 -243.353844)
		(end 107.359704 -243.354352)
		(stroke
			(width 0.05715)
			(type default)
		)
		(layer "In11.Cu")
	)
	(gr_line
		(start 107.360466 -241.733832)
		(end 107.359704 -241.73434)
		(stroke
			(width 0.05715)
			(type default)
		)
		(layer "In11.Cu")
	)
	(gr_line
		(start 107.360466 -240.11382)
		(end 107.359704 -240.114328)
		(stroke
			(width 0.05715)
			(type default)
		)
		(layer "In11.Cu")
	)
	(gr_line
		(start 107.360466 -236.873796)
		(end 107.359704 -236.874304)
		(stroke
			(width 0.05715)
			(type default)
		)
		(layer "In11.Cu")
	)
	(gr_line
		(start 107.360466 -235.253784)
		(end 107.359704 -235.254292)
		(stroke
			(width 0.05715)
			(type default)
		)
		(layer "In11.Cu")
	)
	(gr_line
		(start 107.360466 -233.633772)
		(end 107.359704 -233.63428)
		(stroke
			(width 0.05715)
			(type default)
		)
		(layer "In11.Cu")
	)
	(gr_line
		(start 107.360466 -232.01376)
		(end 107.359704 -232.014268)
		(stroke
			(width 0.05715)
			(type default)
		)
		(layer "In11.Cu")
	)
	(gr_line
		(start 107.36199 -245.615714)
		(end 107.36326 -245.616476)
		(stroke
			(width 0.05715)
			(type default)
		)
		(layer "In11.Cu")
	)
	(gr_line
		(start 107.36199 -242.37569)
		(end 107.36326 -242.376452)
		(stroke
			(width 0.05715)
			(type default)
		)
		(layer "In11.Cu")
	)
	(gr_line
		(start 107.36199 -237.515654)
		(end 107.36326 -237.516416)
		(stroke
			(width 0.05715)
			(type default)
		)
		(layer "In11.Cu")
	)
	(gr_line
		(start 107.36326 -243.996464)
		(end 107.364022 -243.996972)
		(stroke
			(width 0.05715)
			(type default)
		)
		(layer "In11.Cu")
	)
	(gr_line
		(start 107.36326 -240.75644)
		(end 107.364022 -240.756948)
		(stroke
			(width 0.05715)
			(type default)
		)
		(layer "In11.Cu")
	)
	(gr_line
		(start 107.36326 -239.136428)
		(end 107.364022 -239.136936)
		(stroke
			(width 0.05715)
			(type default)
		)
		(layer "In11.Cu")
	)
	(gr_line
		(start 107.36326 -235.896404)
		(end 107.364022 -235.896912)
		(stroke
			(width 0.05715)
			(type default)
		)
		(layer "In11.Cu")
	)
	(gr_line
		(start 107.36326 -234.276392)
		(end 107.364022 -234.2769)
		(stroke
			(width 0.05715)
			(type default)
		)
		(layer "In11.Cu")
	)
	(gr_line
		(start 107.36326 -232.65638)
		(end 107.364022 -232.656888)
		(stroke
			(width 0.05715)
			(type default)
		)
		(layer "In11.Cu")
	)
	(gr_line
		(start 107.364022 -246.591836)
		(end 107.36326 -246.592344)
		(stroke
			(width 0.05715)
			(type default)
		)
		(layer "In11.Cu")
	)
	(gr_line
		(start 107.364022 -244.971824)
		(end 107.36326 -244.972332)
		(stroke
			(width 0.05715)
			(type default)
		)
		(layer "In11.Cu")
	)
	(gr_line
		(start 107.364022 -243.996972)
		(end 107.365038 -243.99748)
		(stroke
			(width 0.05715)
			(type default)
		)
		(layer "In11.Cu")
	)
	(gr_line
		(start 107.364022 -243.351812)
		(end 107.36326 -243.35232)
		(stroke
			(width 0.05715)
			(type default)
		)
		(layer "In11.Cu")
	)
	(gr_line
		(start 107.364022 -241.7318)
		(end 107.36326 -241.732308)
		(stroke
			(width 0.05715)
			(type default)
		)
		(layer "In11.Cu")
	)
	(gr_line
		(start 107.364022 -240.756948)
		(end 107.365038 -240.757456)
		(stroke
			(width 0.05715)
			(type default)
		)
		(layer "In11.Cu")
	)
	(gr_line
		(start 107.364022 -240.111788)
		(end 107.36326 -240.112296)
		(stroke
			(width 0.05715)
			(type default)
		)
		(layer "In11.Cu")
	)
	(gr_line
		(start 107.364022 -239.136936)
		(end 107.365038 -239.137444)
		(stroke
			(width 0.05715)
			(type default)
		)
		(layer "In11.Cu")
	)
	(gr_line
		(start 107.364022 -238.491776)
		(end 107.363514 -238.49203)
		(stroke
			(width 0.05715)
			(type default)
		)
		(layer "In11.Cu")
	)
	(gr_line
		(start 107.364022 -236.871764)
		(end 107.36326 -236.872272)
		(stroke
			(width 0.05715)
			(type default)
		)
		(layer "In11.Cu")
	)
	(gr_line
		(start 107.364022 -235.896912)
		(end 107.365038 -235.89742)
		(stroke
			(width 0.05715)
			(type default)
		)
		(layer "In11.Cu")
	)
	(gr_line
		(start 107.364022 -235.251752)
		(end 107.36326 -235.25226)
		(stroke
			(width 0.05715)
			(type default)
		)
		(layer "In11.Cu")
	)
	(gr_line
		(start 107.364022 -234.2769)
		(end 107.365038 -234.277408)
		(stroke
			(width 0.05715)
			(type default)
		)
		(layer "In11.Cu")
	)
	(gr_line
		(start 107.364022 -233.63174)
		(end 107.36326 -233.632248)
		(stroke
			(width 0.05715)
			(type default)
		)
		(layer "In11.Cu")
	)
	(gr_line
		(start 107.364022 -232.656888)
		(end 107.365038 -232.657396)
		(stroke
			(width 0.05715)
			(type default)
		)
		(layer "In11.Cu")
	)
	(gr_line
		(start 107.364022 -232.011728)
		(end 107.36326 -232.012236)
		(stroke
			(width 0.05715)
			(type default)
		)
		(layer "In11.Cu")
	)
	(gr_line
		(start 107.364276 -223.911922)
		(end 107.363768 -223.912176)
		(stroke
			(width 0.05715)
			(type default)
		)
		(layer "In11.Cu")
	)
	(gr_line
		(start 107.365038 -243.99748)
		(end 107.366562 -243.998496)
		(stroke
			(width 0.05715)
			(type default)
		)
		(layer "In11.Cu")
	)
	(gr_line
		(start 107.365038 -240.757456)
		(end 107.366562 -240.758472)
		(stroke
			(width 0.05715)
			(type default)
		)
		(layer "In11.Cu")
	)
	(gr_line
		(start 107.365038 -239.137444)
		(end 107.366562 -239.13846)
		(stroke
			(width 0.05715)
			(type default)
		)
		(layer "In11.Cu")
	)
	(gr_line
		(start 107.365038 -238.491268)
		(end 107.364022 -238.491776)
		(stroke
			(width 0.05715)
			(type default)
		)
		(layer "In11.Cu")
	)
	(gr_line
		(start 107.365038 -235.89742)
		(end 107.366562 -235.898436)
		(stroke
			(width 0.05715)
			(type default)
		)
		(layer "In11.Cu")
	)
	(gr_line
		(start 107.365038 -234.277408)
		(end 107.366562 -234.278424)
		(stroke
			(width 0.05715)
			(type default)
		)
		(layer "In11.Cu")
	)
	(gr_line
		(start 107.365038 -232.657396)
		(end 107.366562 -232.658412)
		(stroke
			(width 0.05715)
			(type default)
		)
		(layer "In11.Cu")
	)
	(gr_line
		(start 107.365038 -223.911668)
		(end 107.364276 -223.911922)
		(stroke
			(width 0.05715)
			(type default)
		)
		(layer "In11.Cu")
	)
	(gr_line
		(start 107.366562 -243.998496)
		(end 107.36707 -243.99875)
		(stroke
			(width 0.05715)
			(type default)
		)
		(layer "In11.Cu")
	)
	(gr_line
		(start 107.366562 -240.758472)
		(end 107.36707 -240.758726)
		(stroke
			(width 0.05715)
			(type default)
		)
		(layer "In11.Cu")
	)
	(gr_line
		(start 107.366562 -239.13846)
		(end 107.36707 -239.138714)
		(stroke
			(width 0.05715)
			(type default)
		)
		(layer "In11.Cu")
	)
	(gr_line
		(start 107.366562 -235.898436)
		(end 107.36707 -235.89869)
		(stroke
			(width 0.05715)
			(type default)
		)
		(layer "In11.Cu")
	)
	(gr_line
		(start 107.366562 -234.278424)
		(end 107.36707 -234.278678)
		(stroke
			(width 0.05715)
			(type default)
		)
		(layer "In11.Cu")
	)
	(gr_line
		(start 107.366562 -232.658412)
		(end 107.36707 -232.658666)
		(stroke
			(width 0.05715)
			(type default)
		)
		(layer "In11.Cu")
	)
	(gr_line
		(start 107.36707 -223.910144)
		(end 107.366816 -223.910398)
		(stroke
			(width 0.05715)
			(type default)
		)
		(layer "In11.Cu")
	)
	(gr_line
		(start 107.368594 -243.999766)
		(end 107.36961 -244.000274)
		(stroke
			(width 0.05715)
			(type default)
		)
		(layer "In11.Cu")
	)
	(gr_line
		(start 107.368594 -240.759742)
		(end 107.36961 -240.76025)
		(stroke
			(width 0.05715)
			(type default)
		)
		(layer "In11.Cu")
	)
	(gr_line
		(start 107.368594 -239.13973)
		(end 107.36961 -239.140238)
		(stroke
			(width 0.05715)
			(type default)
		)
		(layer "In11.Cu")
	)
	(gr_line
		(start 107.368594 -235.899706)
		(end 107.36961 -235.900214)
		(stroke
			(width 0.05715)
			(type default)
		)
		(layer "In11.Cu")
	)
	(gr_line
		(start 107.368594 -234.279694)
		(end 107.36961 -234.280202)
		(stroke
			(width 0.05715)
			(type default)
		)
		(layer "In11.Cu")
	)
	(gr_line
		(start 107.368594 -232.659682)
		(end 107.36961 -232.66019)
		(stroke
			(width 0.05715)
			(type default)
		)
		(layer "In11.Cu")
	)
	(gr_line
		(start 107.370118 -376.296174)
		(end 107.33659 -376.721878)
		(stroke
			(width 0.07112)
			(type default)
		)
		(layer "In11.Cu")
	)
	(gr_line
		(start 107.371388 -244.00129)
		(end 107.37215 -244.001798)
		(stroke
			(width 0.05715)
			(type default)
		)
		(layer "In11.Cu")
	)
	(gr_line
		(start 107.371388 -240.761266)
		(end 107.37215 -240.761774)
		(stroke
			(width 0.05715)
			(type default)
		)
		(layer "In11.Cu")
	)
	(gr_line
		(start 107.371388 -239.141254)
		(end 107.37215 -239.141762)
		(stroke
			(width 0.05715)
			(type default)
		)
		(layer "In11.Cu")
	)
	(gr_line
		(start 107.371388 -235.90123)
		(end 107.37215 -235.901738)
		(stroke
			(width 0.05715)
			(type default)
		)
		(layer "In11.Cu")
	)
	(gr_line
		(start 107.371388 -234.281218)
		(end 107.37215 -234.281726)
		(stroke
			(width 0.05715)
			(type default)
		)
		(layer "In11.Cu")
	)
	(gr_line
		(start 107.371388 -232.661206)
		(end 107.37215 -232.661714)
		(stroke
			(width 0.05715)
			(type default)
		)
		(layer "In11.Cu")
	)
	(gr_line
		(start 107.37215 -244.001798)
		(end 107.373166 -244.002306)
		(stroke
			(width 0.05715)
			(type default)
		)
		(layer "In11.Cu")
	)
	(gr_line
		(start 107.37215 -240.761774)
		(end 107.373166 -240.762282)
		(stroke
			(width 0.05715)
			(type default)
		)
		(layer "In11.Cu")
	)
	(gr_line
		(start 107.37215 -239.141762)
		(end 107.373166 -239.14227)
		(stroke
			(width 0.05715)
			(type default)
		)
		(layer "In11.Cu")
	)
	(gr_line
		(start 107.37215 -235.901738)
		(end 107.373166 -235.902246)
		(stroke
			(width 0.05715)
			(type default)
		)
		(layer "In11.Cu")
	)
	(gr_line
		(start 107.37215 -234.281726)
		(end 107.373166 -234.282234)
		(stroke
			(width 0.05715)
			(type default)
		)
		(layer "In11.Cu")
	)
	(gr_line
		(start 107.37215 -232.661714)
		(end 107.373166 -232.662222)
		(stroke
			(width 0.05715)
			(type default)
		)
		(layer "In11.Cu")
	)
	(gr_line
		(start 107.400344 -228.75113)
		(end 107.394248 -228.754686)
		(stroke
			(width 0.05715)
			(type default)
		)
		(layer "In11.Cu")
	)
	(gr_line
		(start 107.400598 -221.083378)
		(end 107.446318 -221.129098)
		(stroke
			(width 0.05715)
			(type default)
		)
		(layer "In11.Cu")
	)
	(gr_line
		(start 107.400598 -221.05493)
		(end 107.400598 -221.083378)
		(stroke
			(width 0.05715)
			(type default)
		)
		(layer "In11.Cu")
	)
	(gr_line
		(start 107.400598 -215.319864)
		(end 107.400598 -215.397842)
		(stroke
			(width 0.07112)
			(type default)
		)
		(layer "In11.Cu")
	)
	(gr_line
		(start 107.403138 -228.749098)
		(end 107.400344 -228.75113)
		(stroke
			(width 0.05715)
			(type default)
		)
		(layer "In11.Cu")
	)
	(gr_arc
		(start 107.403138 -228.749098)
		(mid 107.406321 -228.746823)
		(end 107.409488 -228.744526)
		(stroke
			(width 0.05715)
			(type default)
		)
		(layer "In11.Cu")
	)
	(gr_line
		(start 107.429808 -373.791734)
		(end 107.55503 -373.938292)
		(stroke
			(width 0.07112)
			(type default)
		)
		(layer "In11.Cu")
	)
	(gr_line
		(start 107.439968 -215.253316)
		(end 107.400598 -215.319864)
		(stroke
			(width 0.07112)
			(type default)
		)
		(layer "In11.Cu")
	)
	(gr_arc
		(start 107.47629 -275.706332)
		(mid 107.4763 -275.70303)
		(end 107.47629 -275.699728)
		(stroke
			(width 0.05715)
			(type default)
		)
		(layer "In11.Cu")
	)
	(gr_line
		(start 107.477052 -287.025588)
		(end 107.477052 -287.024826)
		(stroke
			(width 0.05715)
			(type default)
		)
		(layer "In11.Cu")
	)
	(gr_line
		(start 107.483148 -370.886228)
		(end 107.374182 -371.57914)
		(stroke
			(width 0.07112)
			(type default)
		)
		(layer "In11.Cu")
	)
	(gr_line
		(start 107.521502 -374.363996)
		(end 107.375198 -374.488964)
		(stroke
			(width 0.07112)
			(type default)
		)
		(layer "In11.Cu")
	)
	(gr_arc
		(start 107.531662 -286.579818)
		(mid 107.524895 -286.584594)
		(end 107.5182 -286.58947)
		(stroke
			(width 0.05715)
			(type default)
		)
		(layer "In11.Cu")
	)
	(gr_line
		(start 107.531662 -286.579818)
		(end 107.534456 -286.578294)
		(stroke
			(width 0.05715)
			(type default)
		)
		(layer "In11.Cu")
	)
	(gr_line
		(start 107.55503 -373.938292)
		(end 107.521502 -374.363996)
		(stroke
			(width 0.07112)
			(type default)
		)
		(layer "In11.Cu")
	)
	(gr_line
		(start 107.55503 -288.186368)
		(end 107.557062 -288.185098)
		(stroke
			(width 0.05715)
			(type default)
		)
		(layer "In11.Cu")
	)
	(gr_line
		(start 107.555538 -289.146234)
		(end 107.55503 -289.14598)
		(stroke
			(width 0.05715)
			(type default)
		)
		(layer "In11.Cu")
	)
	(gr_arc
		(start 107.556554 -292.38702)
		(mid 107.558964 -292.388423)
		(end 107.56138 -292.389814)
		(stroke
			(width 0.05715)
			(type default)
		)
		(layer "In11.Cu")
	)
	(gr_arc
		(start 107.556554 -290.767008)
		(mid 107.55871 -290.768283)
		(end 107.560872 -290.769548)
		(stroke
			(width 0.05715)
			(type default)
		)
		(layer "In11.Cu")
	)
	(gr_line
		(start 107.558332 -294.665146)
		(end 107.559094 -294.664384)
		(stroke
			(width 0.05715)
			(type default)
		)
		(layer "In11.Cu")
	)
	(gr_line
		(start 107.562142 -281.050492)
		(end 107.558586 -281.047952)
		(stroke
			(width 0.05715)
			(type default)
		)
		(layer "In11.Cu")
	)
	(gr_line
		(start 107.56773 -291.419026)
		(end 107.567984 -291.418772)
		(stroke
			(width 0.05715)
			(type default)
		)
		(layer "In11.Cu")
	)
	(gr_line
		(start 107.56773 -289.799014)
		(end 107.567984 -289.79876)
		(stroke
			(width 0.05715)
			(type default)
		)
		(layer "In11.Cu")
	)
	(gr_line
		(start 107.567984 -292.393624)
		(end 107.56773 -292.393624)
		(stroke
			(width 0.05715)
			(type default)
		)
		(layer "In11.Cu")
	)
	(gr_line
		(start 107.567984 -290.773612)
		(end 107.56773 -290.773612)
		(stroke
			(width 0.05715)
			(type default)
		)
		(layer "In11.Cu")
	)
	(gr_line
		(start 107.567984 -281.053794)
		(end 107.562142 -281.050492)
		(stroke
			(width 0.05715)
			(type default)
		)
		(layer "In11.Cu")
	)
	(gr_line
		(start 107.568238 -284.938724)
		(end 107.568746 -284.93847)
		(stroke
			(width 0.05715)
			(type default)
		)
		(layer "In11.Cu")
	)
	(gr_line
		(start 107.568238 -283.318712)
		(end 107.568746 -283.318458)
		(stroke
			(width 0.05715)
			(type default)
		)
		(layer "In11.Cu")
	)
	(gr_line
		(start 107.568238 -281.6987)
		(end 107.568746 -281.698446)
		(stroke
			(width 0.05715)
			(type default)
		)
		(layer "In11.Cu")
	)
	(gr_line
		(start 107.568746 -294.014144)
		(end 107.567984 -294.013636)
		(stroke
			(width 0.05715)
			(type default)
		)
		(layer "In11.Cu")
	)
	(gr_line
		(start 107.568746 -285.914338)
		(end 107.567984 -285.91383)
		(stroke
			(width 0.05715)
			(type default)
		)
		(layer "In11.Cu")
	)
	(gr_line
		(start 107.568746 -284.93847)
		(end 107.570016 -284.937708)
		(stroke
			(width 0.05715)
			(type default)
		)
		(layer "In11.Cu")
	)
	(gr_line
		(start 107.568746 -284.294326)
		(end 107.567984 -284.293818)
		(stroke
			(width 0.05715)
			(type default)
		)
		(layer "In11.Cu")
	)
	(gr_line
		(start 107.568746 -283.318458)
		(end 107.570016 -283.317696)
		(stroke
			(width 0.05715)
			(type default)
		)
		(layer "In11.Cu")
	)
	(gr_line
		(start 107.568746 -282.674314)
		(end 107.567984 -282.673806)
		(stroke
			(width 0.05715)
			(type default)
		)
		(layer "In11.Cu")
	)
	(gr_line
		(start 107.568746 -281.698446)
		(end 107.570016 -281.697684)
		(stroke
			(width 0.05715)
			(type default)
		)
		(layer "In11.Cu")
	)
	(gr_line
		(start 107.568746 -281.054302)
		(end 107.567984 -281.053794)
		(stroke
			(width 0.05715)
			(type default)
		)
		(layer "In11.Cu")
	)
	(gr_line
		(start 107.569762 -285.914846)
		(end 107.568746 -285.914338)
		(stroke
			(width 0.05715)
			(type default)
		)
		(layer "In11.Cu")
	)
	(gr_line
		(start 107.569762 -284.294834)
		(end 107.568746 -284.294326)
		(stroke
			(width 0.05715)
			(type default)
		)
		(layer "In11.Cu")
	)
	(gr_line
		(start 107.569762 -282.674822)
		(end 107.568746 -282.674314)
		(stroke
			(width 0.05715)
			(type default)
		)
		(layer "In11.Cu")
	)
	(gr_line
		(start 107.569762 -281.05481)
		(end 107.568746 -281.054302)
		(stroke
			(width 0.05715)
			(type default)
		)
		(layer "In11.Cu")
	)
	(gr_line
		(start 107.57662 -292.398704)
		(end 107.57408 -292.39718)
		(stroke
			(width 0.05715)
			(type default)
		)
		(layer "In11.Cu")
	)
	(gr_line
		(start 107.57662 -290.778438)
		(end 107.575858 -290.778184)
		(stroke
			(width 0.05715)
			(type default)
		)
		(layer "In11.Cu")
	)
	(gr_line
		(start 107.577128 -292.398958)
		(end 107.57662 -292.398704)
		(stroke
			(width 0.05715)
			(type default)
		)
		(layer "In11.Cu")
	)
	(gr_line
		(start 107.646216 -229.90429)
		(end 107.64647 -229.90429)
		(stroke
			(width 0.05715)
			(type default)
		)
		(layer "In11.Cu")
	)
	(gr_line
		(start 107.661964 -281.86507)
		(end 107.663234 -281.864308)
		(stroke
			(width 0.05715)
			(type default)
		)
		(layer "In11.Cu")
	)
	(gr_line
		(start 107.663234 -282.508452)
		(end 107.66044 -282.506928)
		(stroke
			(width 0.05715)
			(type default)
		)
		(layer "In11.Cu")
	)
	(gr_line
		(start 107.663234 -281.864308)
		(end 107.663996 -281.8638)
		(stroke
			(width 0.05715)
			(type default)
		)
		(layer "In11.Cu")
	)
	(gr_line
		(start 107.663996 -285.103824)
		(end 107.665012 -285.103316)
		(stroke
			(width 0.05715)
			(type default)
		)
		(layer "In11.Cu")
	)
	(gr_line
		(start 107.663996 -283.483812)
		(end 107.665012 -283.483304)
		(stroke
			(width 0.05715)
			(type default)
		)
		(layer "In11.Cu")
	)
	(gr_line
		(start 107.663996 -282.50896)
		(end 107.663234 -282.508452)
		(stroke
			(width 0.05715)
			(type default)
		)
		(layer "In11.Cu")
	)
	(gr_line
		(start 107.663996 -281.8638)
		(end 107.665012 -281.863292)
		(stroke
			(width 0.05715)
			(type default)
		)
		(layer "In11.Cu")
	)
	(gr_line
		(start 107.663996 -280.888948)
		(end 107.663234 -280.88844)
		(stroke
			(width 0.05715)
			(type default)
		)
		(layer "In11.Cu")
	)
	(gr_line
		(start 107.666282 -282.51023)
		(end 107.663996 -282.50896)
		(stroke
			(width 0.05715)
			(type default)
		)
		(layer "In11.Cu")
	)
	(gr_line
		(start 107.666282 -280.890218)
		(end 107.663996 -280.888948)
		(stroke
			(width 0.05715)
			(type default)
		)
		(layer "In11.Cu")
	)
	(gr_line
		(start 107.667044 -282.510738)
		(end 107.666282 -282.51023)
		(stroke
			(width 0.05715)
			(type default)
		)
		(layer "In11.Cu")
	)
	(gr_line
		(start 107.667044 -280.890726)
		(end 107.666282 -280.890218)
		(stroke
			(width 0.05715)
			(type default)
		)
		(layer "In11.Cu")
	)
	(gr_line
		(start 107.668568 -292.231318)
		(end 107.664504 -292.229032)
		(stroke
			(width 0.05715)
			(type default)
		)
		(layer "In11.Cu")
	)
	(gr_line
		(start 107.669076 -293.851584)
		(end 107.668314 -293.851076)
		(stroke
			(width 0.05715)
			(type default)
		)
		(layer "In11.Cu")
	)
	(gr_line
		(start 107.66933 -292.231826)
		(end 107.668568 -292.231318)
		(stroke
			(width 0.05715)
			(type default)
		)
		(layer "In11.Cu")
	)
	(gr_line
		(start 107.671108 -290.61283)
		(end 107.663488 -290.608512)
		(stroke
			(width 0.05715)
			(type default)
		)
		(layer "In11.Cu")
	)
	(gr_line
		(start 107.672124 -292.233604)
		(end 107.66933 -292.231826)
		(stroke
			(width 0.05715)
			(type default)
		)
		(layer "In11.Cu")
	)
	(gr_line
		(start 107.672632 -290.613846)
		(end 107.671108 -290.61283)
		(stroke
			(width 0.05715)
			(type default)
		)
		(layer "In11.Cu")
	)
	(gr_line
		(start 107.682538 -221.083378)
		(end 107.636818 -221.129098)
		(stroke
			(width 0.05715)
			(type default)
		)
		(layer "In11.Cu")
	)
	(gr_line
		(start 107.682538 -221.05493)
		(end 107.682538 -221.083378)
		(stroke
			(width 0.05715)
			(type default)
		)
		(layer "In11.Cu")
	)
	(gr_line
		(start 107.684824 -291.571426)
		(end 107.685078 -291.571426)
		(stroke
			(width 0.05715)
			(type default)
		)
		(layer "In11.Cu")
	)
	(gr_line
		(start 107.684824 -289.951414)
		(end 107.685078 -289.951414)
		(stroke
			(width 0.05715)
			(type default)
		)
		(layer "In11.Cu")
	)
	(gr_line
		(start 107.69346 -291.5666)
		(end 107.694984 -291.565584)
		(stroke
			(width 0.05715)
			(type default)
		)
		(layer "In11.Cu")
	)
	(gr_line
		(start 107.69346 -289.946588)
		(end 107.694984 -289.945572)
		(stroke
			(width 0.05715)
			(type default)
		)
		(layer "In11.Cu")
	)
	(gr_line
		(start 107.694984 -293.18585)
		(end 107.700318 -293.182802)
		(stroke
			(width 0.05715)
			(type default)
		)
		(layer "In11.Cu")
	)
	(gr_line
		(start 107.695492 -293.867078)
		(end 107.69473 -293.86657)
		(stroke
			(width 0.05715)
			(type default)
		)
		(layer "In11.Cu")
	)
	(gr_line
		(start 107.696 -292.24732)
		(end 107.694222 -292.246304)
		(stroke
			(width 0.05715)
			(type default)
		)
		(layer "In11.Cu")
	)
	(gr_line
		(start 107.696254 -293.867586)
		(end 107.695492 -293.867078)
		(stroke
			(width 0.05715)
			(type default)
		)
		(layer "In11.Cu")
	)
	(gr_line
		(start 107.700318 -293.182802)
		(end 107.703112 -293.18077)
		(stroke
			(width 0.05715)
			(type default)
		)
		(layer "In11.Cu")
	)
	(gr_line
		(start 107.70235 -292.25113)
		(end 107.696 -292.24732)
		(stroke
			(width 0.05715)
			(type default)
		)
		(layer "In11.Cu")
	)
	(gr_arc
		(start 107.70235 -292.25113)
		(mid 107.702731 -292.251384)
		(end 107.703112 -292.251638)
		(stroke
			(width 0.05715)
			(type default)
		)
		(layer "In11.Cu")
	)
	(gr_line
		(start 107.70235 -290.631118)
		(end 107.695746 -290.627308)
		(stroke
			(width 0.05715)
			(type default)
		)
		(layer "In11.Cu")
	)
	(gr_arc
		(start 107.70235 -290.631118)
		(mid 107.702731 -290.631372)
		(end 107.703112 -290.631626)
		(stroke
			(width 0.05715)
			(type default)
		)
		(layer "In11.Cu")
	)
	(gr_line
		(start 107.70235 -289.011106)
		(end 107.695238 -289.007042)
		(stroke
			(width 0.05715)
			(type default)
		)
		(layer "In11.Cu")
	)
	(gr_arc
		(start 107.70235 -289.011106)
		(mid 107.702731 -289.01136)
		(end 107.703112 -289.011614)
		(stroke
			(width 0.05715)
			(type default)
		)
		(layer "In11.Cu")
	)
	(gr_line
		(start 107.70235 -287.391348)
		(end 107.692952 -287.38576)
		(stroke
			(width 0.05715)
			(type default)
		)
		(layer "In11.Cu")
	)
	(gr_line
		(start 107.70235 -287.391094)
		(end 107.70235 -287.391348)
		(stroke
			(width 0.05715)
			(type default)
		)
		(layer "In11.Cu")
	)
	(gr_line
		(start 107.703112 -293.87165)
		(end 107.696254 -293.867586)
		(stroke
			(width 0.05715)
			(type default)
		)
		(layer "In11.Cu")
	)
	(gr_arc
		(start 107.703112 -293.18077)
		(mid 107.707061 -293.177993)
		(end 107.710986 -293.175182)
		(stroke
			(width 0.05715)
			(type default)
		)
		(layer "In11.Cu")
	)
	(gr_arc
		(start 107.704636 -292.252654)
		(mid 107.703874 -292.252145)
		(end 107.703112 -292.251638)
		(stroke
			(width 0.05715)
			(type default)
		)
		(layer "In11.Cu")
	)
	(gr_arc
		(start 107.710986 -293.877238)
		(mid 107.707061 -293.874427)
		(end 107.703112 -293.87165)
		(stroke
			(width 0.05715)
			(type default)
		)
		(layer "In11.Cu")
	)
	(gr_arc
		(start 107.710986 -292.257226)
		(mid 107.708198 -292.255312)
		(end 107.705398 -292.253416)
		(stroke
			(width 0.05715)
			(type default)
		)
		(layer "In11.Cu")
	)
	(gr_arc
		(start 107.710986 -290.637214)
		(mid 107.707061 -290.634403)
		(end 107.703112 -290.631626)
		(stroke
			(width 0.05715)
			(type default)
		)
		(layer "In11.Cu")
	)
	(gr_arc
		(start 107.710986 -289.017202)
		(mid 107.707061 -289.014391)
		(end 107.703112 -289.011614)
		(stroke
			(width 0.05715)
			(type default)
		)
		(layer "In11.Cu")
	)
	(gr_arc
		(start 107.71124 -287.39719)
		(mid 107.70681 -287.39412)
		(end 107.70235 -287.391094)
		(stroke
			(width 0.05715)
			(type default)
		)
		(layer "In11.Cu")
	)
	(gr_line
		(start 107.75569 -276.516338)
		(end 107.755944 -276.516338)
		(stroke
			(width 0.05715)
			(type default)
		)
		(layer "In11.Cu")
	)
	(gr_line
		(start 107.762802 -370.931186)
		(end 107.876086 -371.086634)
		(stroke
			(width 0.07112)
			(type default)
		)
		(layer "In11.Cu")
	)
	(gr_line
		(start 107.809792 -371.508528)
		(end 107.65409 -371.621812)
		(stroke
			(width 0.07112)
			(type default)
		)
		(layer "In11.Cu")
	)
	(gr_line
		(start 107.876086 -371.086634)
		(end 107.809792 -371.508528)
		(stroke
			(width 0.07112)
			(type default)
		)
		(layer "In11.Cu")
	)
	(gr_line
		(start 107.92587 -224.233232)
		(end 107.92587 -224.226628)
		(stroke
			(width 0.05715)
			(type default)
		)
		(layer "In11.Cu")
	)
	(gr_arc
		(start 107.926124 -224.221548)
		(mid 107.925992 -224.224088)
		(end 107.92587 -224.226628)
		(stroke
			(width 0.05715)
			(type default)
		)
		(layer "In11.Cu")
	)
	(gr_arc
		(start 108.161074 -244.13337)
		(mid 108.164999 -244.136181)
		(end 108.168948 -244.138958)
		(stroke
			(width 0.05715)
			(type default)
		)
		(layer "In11.Cu")
	)
	(gr_arc
		(start 108.161074 -242.513358)
		(mid 108.164999 -242.516169)
		(end 108.168948 -242.518946)
		(stroke
			(width 0.05715)
			(type default)
		)
		(layer "In11.Cu")
	)
	(gr_arc
		(start 108.161074 -240.893346)
		(mid 108.164999 -240.896157)
		(end 108.168948 -240.898934)
		(stroke
			(width 0.05715)
			(type default)
		)
		(layer "In11.Cu")
	)
	(gr_arc
		(start 108.161074 -239.273334)
		(mid 108.164999 -239.276145)
		(end 108.168948 -239.278922)
		(stroke
			(width 0.05715)
			(type default)
		)
		(layer "In11.Cu")
	)
	(gr_arc
		(start 108.161074 -237.653322)
		(mid 108.164999 -237.656133)
		(end 108.168948 -237.65891)
		(stroke
			(width 0.05715)
			(type default)
		)
		(layer "In11.Cu")
	)
	(gr_arc
		(start 108.161074 -236.03331)
		(mid 108.164999 -236.036121)
		(end 108.168948 -236.038898)
		(stroke
			(width 0.05715)
			(type default)
		)
		(layer "In11.Cu")
	)
	(gr_arc
		(start 108.161074 -234.413298)
		(mid 108.164999 -234.416109)
		(end 108.168948 -234.418886)
		(stroke
			(width 0.05715)
			(type default)
		)
		(layer "In11.Cu")
	)
	(gr_arc
		(start 108.161074 -232.793286)
		(mid 108.164999 -232.796097)
		(end 108.168948 -232.798874)
		(stroke
			(width 0.05715)
			(type default)
		)
		(layer "In11.Cu")
	)
	(gr_line
		(start 108.161328 -223.775016)
		(end 108.15447 -223.78035)
		(stroke
			(width 0.05715)
			(type default)
		)
		(layer "In11.Cu")
	)
	(gr_line
		(start 108.168948 -244.138958)
		(end 108.175806 -244.143022)
		(stroke
			(width 0.05715)
			(type default)
		)
		(layer "In11.Cu")
	)
	(gr_line
		(start 108.168948 -242.518946)
		(end 108.175806 -242.52301)
		(stroke
			(width 0.05715)
			(type default)
		)
		(layer "In11.Cu")
	)
	(gr_line
		(start 108.168948 -240.898934)
		(end 108.175806 -240.902998)
		(stroke
			(width 0.05715)
			(type default)
		)
		(layer "In11.Cu")
	)
	(gr_line
		(start 108.168948 -239.278922)
		(end 108.175806 -239.282986)
		(stroke
			(width 0.05715)
			(type default)
		)
		(layer "In11.Cu")
	)
	(gr_line
		(start 108.168948 -237.65891)
		(end 108.175806 -237.662974)
		(stroke
			(width 0.05715)
			(type default)
		)
		(layer "In11.Cu")
	)
	(gr_line
		(start 108.168948 -236.038898)
		(end 108.175806 -236.042962)
		(stroke
			(width 0.05715)
			(type default)
		)
		(layer "In11.Cu")
	)
	(gr_line
		(start 108.168948 -234.418886)
		(end 108.175806 -234.42295)
		(stroke
			(width 0.05715)
			(type default)
		)
		(layer "In11.Cu")
	)
	(gr_line
		(start 108.168948 -232.798874)
		(end 108.175806 -232.802938)
		(stroke
			(width 0.05715)
			(type default)
		)
		(layer "In11.Cu")
	)
	(gr_line
		(start 108.175806 -244.143022)
		(end 108.176568 -244.14353)
		(stroke
			(width 0.05715)
			(type default)
		)
		(layer "In11.Cu")
	)
	(gr_line
		(start 108.175806 -242.52301)
		(end 108.176568 -242.523518)
		(stroke
			(width 0.05715)
			(type default)
		)
		(layer "In11.Cu")
	)
	(gr_line
		(start 108.175806 -240.902998)
		(end 108.176568 -240.903506)
		(stroke
			(width 0.05715)
			(type default)
		)
		(layer "In11.Cu")
	)
	(gr_line
		(start 108.175806 -239.282986)
		(end 108.176568 -239.283494)
		(stroke
			(width 0.05715)
			(type default)
		)
		(layer "In11.Cu")
	)
	(gr_line
		(start 108.175806 -237.662974)
		(end 108.176568 -237.663482)
		(stroke
			(width 0.05715)
			(type default)
		)
		(layer "In11.Cu")
	)
	(gr_line
		(start 108.175806 -236.042962)
		(end 108.176568 -236.04347)
		(stroke
			(width 0.05715)
			(type default)
		)
		(layer "In11.Cu")
	)
	(gr_line
		(start 108.175806 -234.42295)
		(end 108.176568 -234.423458)
		(stroke
			(width 0.05715)
			(type default)
		)
		(layer "In11.Cu")
	)
	(gr_line
		(start 108.175806 -232.802938)
		(end 108.176568 -232.803446)
		(stroke
			(width 0.05715)
			(type default)
		)
		(layer "In11.Cu")
	)
	(gr_line
		(start 108.17987 -295.697402)
		(end 108.17987 -295.668954)
		(stroke
			(width 0.05715)
			(type default)
		)
		(layer "In11.Cu")
	)
	(gr_line
		(start 108.17987 -295.668954)
		(end 108.22559 -295.623234)
		(stroke
			(width 0.05715)
			(type default)
		)
		(layer "In11.Cu")
	)
	(gr_line
		(start 108.19765 -226.335844)
		(end 108.198158 -226.336098)
		(stroke
			(width 0.05715)
			(type default)
		)
		(layer "In11.Cu")
	)
	(gr_line
		(start 108.200698 -226.337622)
		(end 108.204508 -226.339908)
		(stroke
			(width 0.05715)
			(type default)
		)
		(layer "In11.Cu")
	)
	(gr_arc
		(start 108.203746 -224.719388)
		(mid 108.204761 -224.720024)
		(end 108.205778 -224.720658)
		(stroke
			(width 0.05715)
			(type default)
		)
		(layer "In11.Cu")
	)
	(gr_line
		(start 108.204508 -226.339908)
		(end 108.205524 -226.340416)
		(stroke
			(width 0.05715)
			(type default)
		)
		(layer "In11.Cu")
	)
	(gr_line
		(start 108.205016 -244.160294)
		(end 108.207048 -244.16131)
		(stroke
			(width 0.05715)
			(type default)
		)
		(layer "In11.Cu")
	)
	(gr_line
		(start 108.205016 -242.540282)
		(end 108.207048 -242.541298)
		(stroke
			(width 0.05715)
			(type default)
		)
		(layer "In11.Cu")
	)
	(gr_line
		(start 108.205016 -240.92027)
		(end 108.207048 -240.921286)
		(stroke
			(width 0.05715)
			(type default)
		)
		(layer "In11.Cu")
	)
	(gr_line
		(start 108.205016 -239.300258)
		(end 108.207048 -239.301274)
		(stroke
			(width 0.05715)
			(type default)
		)
		(layer "In11.Cu")
	)
	(gr_line
		(start 108.205016 -237.680246)
		(end 108.207048 -237.681262)
		(stroke
			(width 0.05715)
			(type default)
		)
		(layer "In11.Cu")
	)
	(gr_line
		(start 108.205016 -236.060234)
		(end 108.207048 -236.06125)
		(stroke
			(width 0.05715)
			(type default)
		)
		(layer "In11.Cu")
	)
	(gr_line
		(start 108.205016 -234.440222)
		(end 108.207048 -234.441238)
		(stroke
			(width 0.05715)
			(type default)
		)
		(layer "In11.Cu")
	)
	(gr_line
		(start 108.205016 -232.82021)
		(end 108.207048 -232.821226)
		(stroke
			(width 0.05715)
			(type default)
		)
		(layer "In11.Cu")
	)
	(gr_line
		(start 108.205524 -226.340416)
		(end 108.207048 -226.341432)
		(stroke
			(width 0.05715)
			(type default)
		)
		(layer "In11.Cu")
	)
	(gr_line
		(start 108.205778 -224.720658)
		(end 108.208064 -224.721928)
		(stroke
			(width 0.05715)
			(type default)
		)
		(layer "In11.Cu")
	)
	(gr_line
		(start 108.207048 -244.16131)
		(end 108.208064 -244.161818)
		(stroke
			(width 0.05715)
			(type default)
		)
		(layer "In11.Cu")
	)
	(gr_line
		(start 108.207048 -242.541298)
		(end 108.208064 -242.541806)
		(stroke
			(width 0.05715)
			(type default)
		)
		(layer "In11.Cu")
	)
	(gr_line
		(start 108.207048 -240.921286)
		(end 108.208064 -240.921794)
		(stroke
			(width 0.05715)
			(type default)
		)
		(layer "In11.Cu")
	)
	(gr_line
		(start 108.207048 -239.301274)
		(end 108.208064 -239.301782)
		(stroke
			(width 0.05715)
			(type default)
		)
		(layer "In11.Cu")
	)
	(gr_line
		(start 108.207048 -237.681262)
		(end 108.208064 -237.68177)
		(stroke
			(width 0.05715)
			(type default)
		)
		(layer "In11.Cu")
	)
	(gr_line
		(start 108.207048 -236.06125)
		(end 108.208064 -236.061758)
		(stroke
			(width 0.05715)
			(type default)
		)
		(layer "In11.Cu")
	)
	(gr_line
		(start 108.207048 -234.441238)
		(end 108.208064 -234.441746)
		(stroke
			(width 0.05715)
			(type default)
		)
		(layer "In11.Cu")
	)
	(gr_line
		(start 108.207048 -232.821226)
		(end 108.208064 -232.821734)
		(stroke
			(width 0.05715)
			(type default)
		)
		(layer "In11.Cu")
	)
	(gr_line
		(start 108.207048 -226.341432)
		(end 108.208064 -226.34194)
		(stroke
			(width 0.05715)
			(type default)
		)
		(layer "In11.Cu")
	)
	(gr_line
		(start 108.208064 -244.161818)
		(end 108.208826 -244.162326)
		(stroke
			(width 0.05715)
			(type default)
		)
		(layer "In11.Cu")
	)
	(gr_line
		(start 108.208064 -242.541806)
		(end 108.208826 -242.542314)
		(stroke
			(width 0.05715)
			(type default)
		)
		(layer "In11.Cu")
	)
	(gr_line
		(start 108.208064 -240.921794)
		(end 108.208826 -240.922302)
		(stroke
			(width 0.05715)
			(type default)
		)
		(layer "In11.Cu")
	)
	(gr_line
		(start 108.208064 -239.301782)
		(end 108.208826 -239.30229)
		(stroke
			(width 0.05715)
			(type default)
		)
		(layer "In11.Cu")
	)
	(gr_line
		(start 108.208064 -237.68177)
		(end 108.208826 -237.682278)
		(stroke
			(width 0.05715)
			(type default)
		)
		(layer "In11.Cu")
	)
	(gr_line
		(start 108.208064 -236.061758)
		(end 108.208826 -236.062266)
		(stroke
			(width 0.05715)
			(type default)
		)
		(layer "In11.Cu")
	)
	(gr_line
		(start 108.208064 -234.441746)
		(end 108.208826 -234.442254)
		(stroke
			(width 0.05715)
			(type default)
		)
		(layer "In11.Cu")
	)
	(gr_line
		(start 108.208064 -232.821734)
		(end 108.208826 -232.822242)
		(stroke
			(width 0.05715)
			(type default)
		)
		(layer "In11.Cu")
	)
	(gr_line
		(start 108.208064 -224.721928)
		(end 108.208826 -224.722436)
		(stroke
			(width 0.05715)
			(type default)
		)
		(layer "In11.Cu")
	)
	(gr_line
		(start 108.208826 -243.186458)
		(end 108.208064 -243.186966)
		(stroke
			(width 0.05715)
			(type default)
		)
		(layer "In11.Cu")
	)
	(gr_line
		(start 108.208826 -241.566446)
		(end 108.208064 -241.566954)
		(stroke
			(width 0.05715)
			(type default)
		)
		(layer "In11.Cu")
	)
	(gr_line
		(start 108.208826 -239.946434)
		(end 108.208064 -239.946942)
		(stroke
			(width 0.05715)
			(type default)
		)
		(layer "In11.Cu")
	)
	(gr_line
		(start 108.208826 -238.326422)
		(end 108.208064 -238.32693)
		(stroke
			(width 0.05715)
			(type default)
		)
		(layer "In11.Cu")
	)
	(gr_line
		(start 108.208826 -236.70641)
		(end 108.208064 -236.706918)
		(stroke
			(width 0.05715)
			(type default)
		)
		(layer "In11.Cu")
	)
	(gr_line
		(start 108.208826 -235.086398)
		(end 108.208064 -235.086906)
		(stroke
			(width 0.05715)
			(type default)
		)
		(layer "In11.Cu")
	)
	(gr_line
		(start 108.208826 -233.466386)
		(end 108.208064 -233.466894)
		(stroke
			(width 0.05715)
			(type default)
		)
		(layer "In11.Cu")
	)
	(gr_line
		(start 108.208826 -226.986592)
		(end 108.208064 -226.9871)
		(stroke
			(width 0.05715)
			(type default)
		)
		(layer "In11.Cu")
	)
	(gr_line
		(start 108.208826 -224.722436)
		(end 108.210096 -224.723198)
		(stroke
			(width 0.05715)
			(type default)
		)
		(layer "In11.Cu")
	)
	(gr_line
		(start 108.209334 -243.186204)
		(end 108.208826 -243.186458)
		(stroke
			(width 0.05715)
			(type default)
		)
		(layer "In11.Cu")
	)
	(gr_line
		(start 108.209334 -241.566192)
		(end 108.208826 -241.566446)
		(stroke
			(width 0.05715)
			(type default)
		)
		(layer "In11.Cu")
	)
	(gr_line
		(start 108.209334 -239.94618)
		(end 108.208826 -239.946434)
		(stroke
			(width 0.05715)
			(type default)
		)
		(layer "In11.Cu")
	)
	(gr_line
		(start 108.209334 -238.326168)
		(end 108.208826 -238.326422)
		(stroke
			(width 0.05715)
			(type default)
		)
		(layer "In11.Cu")
	)
	(gr_line
		(start 108.209334 -236.706156)
		(end 108.208826 -236.70641)
		(stroke
			(width 0.05715)
			(type default)
		)
		(layer "In11.Cu")
	)
	(gr_line
		(start 108.209334 -235.086144)
		(end 108.208826 -235.086398)
		(stroke
			(width 0.05715)
			(type default)
		)
		(layer "In11.Cu")
	)
	(gr_line
		(start 108.209334 -233.466132)
		(end 108.208826 -233.466386)
		(stroke
			(width 0.05715)
			(type default)
		)
		(layer "In11.Cu")
	)
	(gr_line
		(start 108.210096 -231.845612)
		(end 108.208826 -231.846374)
		(stroke
			(width 0.05715)
			(type default)
		)
		(layer "In11.Cu")
	)
	(gr_line
		(start 108.210096 -222.125794)
		(end 108.208826 -222.126556)
		(stroke
			(width 0.05715)
			(type default)
		)
		(layer "In11.Cu")
	)
	(gr_line
		(start 108.211112 -228.605334)
		(end 108.208826 -228.606604)
		(stroke
			(width 0.05715)
			(type default)
		)
		(layer "In11.Cu")
	)
	(gr_line
		(start 108.211874 -226.344226)
		(end 108.212382 -226.34448)
		(stroke
			(width 0.05715)
			(type default)
		)
		(layer "In11.Cu")
	)
	(gr_line
		(start 108.212382 -243.184426)
		(end 108.21162 -243.184934)
		(stroke
			(width 0.05715)
			(type default)
		)
		(layer "In11.Cu")
	)
	(gr_line
		(start 108.212382 -241.564414)
		(end 108.21162 -241.564922)
		(stroke
			(width 0.05715)
			(type default)
		)
		(layer "In11.Cu")
	)
	(gr_line
		(start 108.212382 -239.944402)
		(end 108.21162 -239.94491)
		(stroke
			(width 0.05715)
			(type default)
		)
		(layer "In11.Cu")
	)
	(gr_line
		(start 108.212382 -238.32439)
		(end 108.21162 -238.324898)
		(stroke
			(width 0.05715)
			(type default)
		)
		(layer "In11.Cu")
	)
	(gr_line
		(start 108.212382 -236.704378)
		(end 108.21162 -236.704886)
		(stroke
			(width 0.05715)
			(type default)
		)
		(layer "In11.Cu")
	)
	(gr_line
		(start 108.212382 -235.084366)
		(end 108.21162 -235.084874)
		(stroke
			(width 0.05715)
			(type default)
		)
		(layer "In11.Cu")
	)
	(gr_line
		(start 108.212382 -233.464354)
		(end 108.21162 -233.464862)
		(stroke
			(width 0.05715)
			(type default)
		)
		(layer "In11.Cu")
	)
	(gr_line
		(start 108.213906 -243.183664)
		(end 108.212382 -243.184426)
		(stroke
			(width 0.05715)
			(type default)
		)
		(layer "In11.Cu")
	)
	(gr_line
		(start 108.213906 -241.563652)
		(end 108.212382 -241.564414)
		(stroke
			(width 0.05715)
			(type default)
		)
		(layer "In11.Cu")
	)
	(gr_line
		(start 108.213906 -239.94364)
		(end 108.212382 -239.944402)
		(stroke
			(width 0.05715)
			(type default)
		)
		(layer "In11.Cu")
	)
	(gr_line
		(start 108.213906 -238.323628)
		(end 108.212382 -238.32439)
		(stroke
			(width 0.05715)
			(type default)
		)
		(layer "In11.Cu")
	)
	(gr_line
		(start 108.213906 -236.703616)
		(end 108.212382 -236.704378)
		(stroke
			(width 0.05715)
			(type default)
		)
		(layer "In11.Cu")
	)
	(gr_line
		(start 108.213906 -235.083604)
		(end 108.212382 -235.084366)
		(stroke
			(width 0.05715)
			(type default)
		)
		(layer "In11.Cu")
	)
	(gr_line
		(start 108.213906 -233.463592)
		(end 108.212382 -233.464354)
		(stroke
			(width 0.05715)
			(type default)
		)
		(layer "In11.Cu")
	)
	(gr_line
		(start 108.214668 -243.183156)
		(end 108.213906 -243.183664)
		(stroke
			(width 0.05715)
			(type default)
		)
		(layer "In11.Cu")
	)
	(gr_line
		(start 108.214668 -241.563144)
		(end 108.213906 -241.563652)
		(stroke
			(width 0.05715)
			(type default)
		)
		(layer "In11.Cu")
	)
	(gr_line
		(start 108.214668 -239.943132)
		(end 108.213906 -239.94364)
		(stroke
			(width 0.05715)
			(type default)
		)
		(layer "In11.Cu")
	)
	(gr_line
		(start 108.214668 -238.32312)
		(end 108.213906 -238.323628)
		(stroke
			(width 0.05715)
			(type default)
		)
		(layer "In11.Cu")
	)
	(gr_line
		(start 108.214668 -236.703108)
		(end 108.213906 -236.703616)
		(stroke
			(width 0.05715)
			(type default)
		)
		(layer "In11.Cu")
	)
	(gr_line
		(start 108.214668 -235.083096)
		(end 108.213906 -235.083604)
		(stroke
			(width 0.05715)
			(type default)
		)
		(layer "In11.Cu")
	)
	(gr_line
		(start 108.214668 -233.463084)
		(end 108.213906 -233.463592)
		(stroke
			(width 0.05715)
			(type default)
		)
		(layer "In11.Cu")
	)
	(gr_line
		(start 108.239814 -382.07823)
		(end 108.530644 -382.36906)
		(stroke
			(width 0.07112)
			(type default)
		)
		(layer "In11.Cu")
	)
	(gr_line
		(start 108.239814 -381.79629)
		(end 108.530644 -381.50546)
		(stroke
			(width 0.07112)
			(type default)
		)
		(layer "In11.Cu")
	)
	(gr_line
		(start 108.29417 -226.171506)
		(end 108.295186 -226.172014)
		(stroke
			(width 0.05715)
			(type default)
		)
		(layer "In11.Cu")
	)
	(gr_line
		(start 108.301536 -224.555812)
		(end 108.303314 -224.556574)
		(stroke
			(width 0.05715)
			(type default)
		)
		(layer "In11.Cu")
	)
	(gr_line
		(start 108.303314 -243.996464)
		(end 108.304076 -243.996972)
		(stroke
			(width 0.05715)
			(type default)
		)
		(layer "In11.Cu")
	)
	(gr_line
		(start 108.303314 -242.376452)
		(end 108.304076 -242.37696)
		(stroke
			(width 0.05715)
			(type default)
		)
		(layer "In11.Cu")
	)
	(gr_line
		(start 108.303314 -240.75644)
		(end 108.304076 -240.756948)
		(stroke
			(width 0.05715)
			(type default)
		)
		(layer "In11.Cu")
	)
	(gr_line
		(start 108.303314 -239.136428)
		(end 108.304076 -239.136936)
		(stroke
			(width 0.05715)
			(type default)
		)
		(layer "In11.Cu")
	)
	(gr_line
		(start 108.303314 -237.516416)
		(end 108.304076 -237.516924)
		(stroke
			(width 0.05715)
			(type default)
		)
		(layer "In11.Cu")
	)
	(gr_line
		(start 108.303314 -235.896404)
		(end 108.304076 -235.896912)
		(stroke
			(width 0.05715)
			(type default)
		)
		(layer "In11.Cu")
	)
	(gr_line
		(start 108.303314 -234.276392)
		(end 108.304076 -234.2769)
		(stroke
			(width 0.05715)
			(type default)
		)
		(layer "In11.Cu")
	)
	(gr_line
		(start 108.303314 -232.65638)
		(end 108.304076 -232.656888)
		(stroke
			(width 0.05715)
			(type default)
		)
		(layer "In11.Cu")
	)
	(gr_line
		(start 108.303314 -226.176586)
		(end 108.304076 -226.177094)
		(stroke
			(width 0.05715)
			(type default)
		)
		(layer "In11.Cu")
	)
	(gr_line
		(start 108.303314 -224.556574)
		(end 108.303822 -224.556828)
		(stroke
			(width 0.05715)
			(type default)
		)
		(layer "In11.Cu")
	)
	(gr_line
		(start 108.303568 -227.796852)
		(end 108.304076 -227.797106)
		(stroke
			(width 0.05715)
			(type default)
		)
		(layer "In11.Cu")
	)
	(gr_line
		(start 108.304076 -243.996972)
		(end 108.305092 -243.99748)
		(stroke
			(width 0.05715)
			(type default)
		)
		(layer "In11.Cu")
	)
	(gr_line
		(start 108.304076 -243.351812)
		(end 108.303314 -243.35232)
		(stroke
			(width 0.05715)
			(type default)
		)
		(layer "In11.Cu")
	)
	(gr_line
		(start 108.304076 -242.37696)
		(end 108.305092 -242.377468)
		(stroke
			(width 0.05715)
			(type default)
		)
		(layer "In11.Cu")
	)
	(gr_line
		(start 108.304076 -241.7318)
		(end 108.303314 -241.732308)
		(stroke
			(width 0.05715)
			(type default)
		)
		(layer "In11.Cu")
	)
	(gr_line
		(start 108.304076 -240.756948)
		(end 108.305092 -240.757456)
		(stroke
			(width 0.05715)
			(type default)
		)
		(layer "In11.Cu")
	)
	(gr_line
		(start 108.304076 -240.111788)
		(end 108.303314 -240.112296)
		(stroke
			(width 0.05715)
			(type default)
		)
		(layer "In11.Cu")
	)
	(gr_line
		(start 108.304076 -239.136936)
		(end 108.305092 -239.137444)
		(stroke
			(width 0.05715)
			(type default)
		)
		(layer "In11.Cu")
	)
	(gr_line
		(start 108.304076 -238.491776)
		(end 108.303314 -238.492284)
		(stroke
			(width 0.05715)
			(type default)
		)
		(layer "In11.Cu")
	)
	(gr_line
		(start 108.304076 -237.516924)
		(end 108.305092 -237.517432)
		(stroke
			(width 0.05715)
			(type default)
		)
		(layer "In11.Cu")
	)
	(gr_line
		(start 108.304076 -236.871764)
		(end 108.303314 -236.872272)
		(stroke
			(width 0.05715)
			(type default)
		)
		(layer "In11.Cu")
	)
	(gr_line
		(start 108.304076 -235.896912)
		(end 108.305092 -235.89742)
		(stroke
			(width 0.05715)
			(type default)
		)
		(layer "In11.Cu")
	)
	(gr_line
		(start 108.304076 -235.251752)
		(end 108.303314 -235.25226)
		(stroke
			(width 0.05715)
			(type default)
		)
		(layer "In11.Cu")
	)
	(gr_line
		(start 108.304076 -234.2769)
		(end 108.305092 -234.277408)
		(stroke
			(width 0.05715)
			(type default)
		)
		(layer "In11.Cu")
	)
	(gr_line
		(start 108.304076 -233.63174)
		(end 108.303314 -233.632248)
		(stroke
			(width 0.05715)
			(type default)
		)
		(layer "In11.Cu")
	)
	(gr_line
		(start 108.304076 -232.656888)
		(end 108.305092 -232.657396)
		(stroke
			(width 0.05715)
			(type default)
		)
		(layer "In11.Cu")
	)
	(gr_line
		(start 108.304076 -232.011728)
		(end 108.303568 -232.011982)
		(stroke
			(width 0.05715)
			(type default)
		)
		(layer "In11.Cu")
	)
	(gr_line
		(start 108.304076 -228.771958)
		(end 108.303568 -228.772212)
		(stroke
			(width 0.05715)
			(type default)
		)
		(layer "In11.Cu")
	)
	(gr_line
		(start 108.304076 -227.797106)
		(end 108.305092 -227.797614)
		(stroke
			(width 0.05715)
			(type default)
		)
		(layer "In11.Cu")
	)
	(gr_line
		(start 108.304076 -227.151946)
		(end 108.303314 -227.152454)
		(stroke
			(width 0.05715)
			(type default)
		)
		(layer "In11.Cu")
	)
	(gr_line
		(start 108.304076 -222.29191)
		(end 108.302806 -222.292672)
		(stroke
			(width 0.05715)
			(type default)
		)
		(layer "In11.Cu")
	)
	(gr_line
		(start 108.305092 -243.99748)
		(end 108.307378 -243.99875)
		(stroke
			(width 0.05715)
			(type default)
		)
		(layer "In11.Cu")
	)
	(gr_line
		(start 108.305092 -243.351304)
		(end 108.304076 -243.351812)
		(stroke
			(width 0.05715)
			(type default)
		)
		(layer "In11.Cu")
	)
	(gr_line
		(start 108.305092 -242.377468)
		(end 108.307378 -242.378738)
		(stroke
			(width 0.05715)
			(type default)
		)
		(layer "In11.Cu")
	)
	(gr_line
		(start 108.305092 -241.731292)
		(end 108.304076 -241.7318)
		(stroke
			(width 0.05715)
			(type default)
		)
		(layer "In11.Cu")
	)
	(gr_line
		(start 108.305092 -240.757456)
		(end 108.307378 -240.758726)
		(stroke
			(width 0.05715)
			(type default)
		)
		(layer "In11.Cu")
	)
	(gr_line
		(start 108.305092 -240.11128)
		(end 108.304076 -240.111788)
		(stroke
			(width 0.05715)
			(type default)
		)
		(layer "In11.Cu")
	)
	(gr_line
		(start 108.305092 -239.137444)
		(end 108.307378 -239.138714)
		(stroke
			(width 0.05715)
			(type default)
		)
		(layer "In11.Cu")
	)
	(gr_line
		(start 108.305092 -238.491268)
		(end 108.304076 -238.491776)
		(stroke
			(width 0.05715)
			(type default)
		)
		(layer "In11.Cu")
	)
	(gr_line
		(start 108.305092 -237.517432)
		(end 108.307378 -237.518702)
		(stroke
			(width 0.05715)
			(type default)
		)
		(layer "In11.Cu")
	)
	(gr_line
		(start 108.305092 -236.871256)
		(end 108.304076 -236.871764)
		(stroke
			(width 0.05715)
			(type default)
		)
		(layer "In11.Cu")
	)
	(gr_line
		(start 108.305092 -235.89742)
		(end 108.307378 -235.89869)
		(stroke
			(width 0.05715)
			(type default)
		)
		(layer "In11.Cu")
	)
	(gr_line
		(start 108.305092 -235.251244)
		(end 108.304076 -235.251752)
		(stroke
			(width 0.05715)
			(type default)
		)
		(layer "In11.Cu")
	)
	(gr_line
		(start 108.305092 -234.277408)
		(end 108.307378 -234.278678)
		(stroke
			(width 0.05715)
			(type default)
		)
		(layer "In11.Cu")
	)
	(gr_line
		(start 108.305092 -233.631232)
		(end 108.304076 -233.63174)
		(stroke
			(width 0.05715)
			(type default)
		)
		(layer "In11.Cu")
	)
	(gr_line
		(start 108.305092 -232.657396)
		(end 108.307378 -232.658666)
		(stroke
			(width 0.05715)
			(type default)
		)
		(layer "In11.Cu")
	)
	(gr_line
		(start 108.305092 -232.01122)
		(end 108.304076 -232.011728)
		(stroke
			(width 0.05715)
			(type default)
		)
		(layer "In11.Cu")
	)
	(gr_line
		(start 108.305092 -228.77145)
		(end 108.304076 -228.771958)
		(stroke
			(width 0.05715)
			(type default)
		)
		(layer "In11.Cu")
	)
	(gr_line
		(start 108.305092 -227.797614)
		(end 108.307378 -227.798884)
		(stroke
			(width 0.05715)
			(type default)
		)
		(layer "In11.Cu")
	)
	(gr_line
		(start 108.305092 -222.291402)
		(end 108.304076 -222.29191)
		(stroke
			(width 0.05715)
			(type default)
		)
		(layer "In11.Cu")
	)
	(gr_line
		(start 108.305854 -226.17811)
		(end 108.306616 -226.178618)
		(stroke
			(width 0.05715)
			(type default)
		)
		(layer "In11.Cu")
	)
	(gr_line
		(start 108.306616 -243.350288)
		(end 108.305092 -243.351304)
		(stroke
			(width 0.05715)
			(type default)
		)
		(layer "In11.Cu")
	)
	(gr_line
		(start 108.306616 -241.730276)
		(end 108.305092 -241.731292)
		(stroke
			(width 0.05715)
			(type default)
		)
		(layer "In11.Cu")
	)
	(gr_line
		(start 108.306616 -240.110264)
		(end 108.305092 -240.11128)
		(stroke
			(width 0.05715)
			(type default)
		)
		(layer "In11.Cu")
	)
	(gr_line
		(start 108.306616 -238.490252)
		(end 108.305092 -238.491268)
		(stroke
			(width 0.05715)
			(type default)
		)
		(layer "In11.Cu")
	)
	(gr_line
		(start 108.306616 -236.87024)
		(end 108.305092 -236.871256)
		(stroke
			(width 0.05715)
			(type default)
		)
		(layer "In11.Cu")
	)
	(gr_line
		(start 108.306616 -235.250228)
		(end 108.305092 -235.251244)
		(stroke
			(width 0.05715)
			(type default)
		)
		(layer "In11.Cu")
	)
	(gr_line
		(start 108.306616 -233.630216)
		(end 108.305092 -233.631232)
		(stroke
			(width 0.05715)
			(type default)
		)
		(layer "In11.Cu")
	)
	(gr_line
		(start 108.306616 -228.770434)
		(end 108.305092 -228.77145)
		(stroke
			(width 0.05715)
			(type default)
		)
		(layer "In11.Cu")
	)
	(gr_line
		(start 108.306616 -226.178618)
		(end 108.30941 -226.180142)
		(stroke
			(width 0.05715)
			(type default)
		)
		(layer "In11.Cu")
	)
	(gr_line
		(start 108.307632 -243.34978)
		(end 108.306616 -243.350288)
		(stroke
			(width 0.05715)
			(type default)
		)
		(layer "In11.Cu")
	)
	(gr_line
		(start 108.307632 -241.729768)
		(end 108.306616 -241.730276)
		(stroke
			(width 0.05715)
			(type default)
		)
		(layer "In11.Cu")
	)
	(gr_line
		(start 108.307632 -240.109756)
		(end 108.306616 -240.110264)
		(stroke
			(width 0.05715)
			(type default)
		)
		(layer "In11.Cu")
	)
	(gr_line
		(start 108.307632 -238.489744)
		(end 108.306616 -238.490252)
		(stroke
			(width 0.05715)
			(type default)
		)
		(layer "In11.Cu")
	)
	(gr_line
		(start 108.307632 -236.869732)
		(end 108.306616 -236.87024)
		(stroke
			(width 0.05715)
			(type default)
		)
		(layer "In11.Cu")
	)
	(gr_line
		(start 108.307632 -235.24972)
		(end 108.306616 -235.250228)
		(stroke
			(width 0.05715)
			(type default)
		)
		(layer "In11.Cu")
	)
	(gr_line
		(start 108.307632 -233.629708)
		(end 108.306616 -233.630216)
		(stroke
			(width 0.05715)
			(type default)
		)
		(layer "In11.Cu")
	)
	(gr_line
		(start 108.307632 -228.769926)
		(end 108.306616 -228.770434)
		(stroke
			(width 0.05715)
			(type default)
		)
		(layer "In11.Cu")
	)
	(gr_line
		(start 108.30941 -226.180142)
		(end 108.311442 -226.181412)
		(stroke
			(width 0.05715)
			(type default)
		)
		(layer "In11.Cu")
	)
	(gr_line
		(start 108.310172 -243.348256)
		(end 108.307632 -243.34978)
		(stroke
			(width 0.05715)
			(type default)
		)
		(layer "In11.Cu")
	)
	(gr_line
		(start 108.310172 -241.728244)
		(end 108.307632 -241.729768)
		(stroke
			(width 0.05715)
			(type default)
		)
		(layer "In11.Cu")
	)
	(gr_line
		(start 108.310172 -240.108232)
		(end 108.307632 -240.109756)
		(stroke
			(width 0.05715)
			(type default)
		)
		(layer "In11.Cu")
	)
	(gr_line
		(start 108.310172 -238.48822)
		(end 108.307632 -238.489744)
		(stroke
			(width 0.05715)
			(type default)
		)
		(layer "In11.Cu")
	)
	(gr_line
		(start 108.310172 -236.868208)
		(end 108.307632 -236.869732)
		(stroke
			(width 0.05715)
			(type default)
		)
		(layer "In11.Cu")
	)
	(gr_line
		(start 108.310172 -235.248196)
		(end 108.307632 -235.24972)
		(stroke
			(width 0.05715)
			(type default)
		)
		(layer "In11.Cu")
	)
	(gr_line
		(start 108.310172 -233.628184)
		(end 108.307632 -233.629708)
		(stroke
			(width 0.05715)
			(type default)
		)
		(layer "In11.Cu")
	)
	(gr_line
		(start 108.310934 -243.347748)
		(end 108.310172 -243.348256)
		(stroke
			(width 0.05715)
			(type default)
		)
		(layer "In11.Cu")
	)
	(gr_line
		(start 108.310934 -241.727736)
		(end 108.310172 -241.728244)
		(stroke
			(width 0.05715)
			(type default)
		)
		(layer "In11.Cu")
	)
	(gr_line
		(start 108.310934 -240.107724)
		(end 108.310172 -240.108232)
		(stroke
			(width 0.05715)
			(type default)
		)
		(layer "In11.Cu")
	)
	(gr_line
		(start 108.310934 -238.487712)
		(end 108.310172 -238.48822)
		(stroke
			(width 0.05715)
			(type default)
		)
		(layer "In11.Cu")
	)
	(gr_line
		(start 108.310934 -236.8677)
		(end 108.310172 -236.868208)
		(stroke
			(width 0.05715)
			(type default)
		)
		(layer "In11.Cu")
	)
	(gr_line
		(start 108.310934 -235.247688)
		(end 108.310172 -235.248196)
		(stroke
			(width 0.05715)
			(type default)
		)
		(layer "In11.Cu")
	)
	(gr_line
		(start 108.310934 -233.627676)
		(end 108.310172 -233.628184)
		(stroke
			(width 0.05715)
			(type default)
		)
		(layer "In11.Cu")
	)
	(gr_line
		(start 108.310934 -228.767894)
		(end 108.307632 -228.769926)
		(stroke
			(width 0.05715)
			(type default)
		)
		(layer "In11.Cu")
	)
	(gr_line
		(start 108.330238 -222.016828)
		(end 108.32973 -222.016828)
		(stroke
			(width 0.05715)
			(type default)
		)
		(layer "In11.Cu")
	)
	(gr_line
		(start 108.337858 -229.436676)
		(end 108.342684 -229.43947)
		(stroke
			(width 0.05715)
			(type default)
		)
		(layer "In11.Cu")
	)
	(gr_line
		(start 108.340398 -227.131118)
		(end 108.33481 -227.13442)
		(stroke
			(width 0.05715)
			(type default)
		)
		(layer "In11.Cu")
	)
	(gr_line
		(start 108.34243 -223.889824)
		(end 108.33481 -223.894142)
		(stroke
			(width 0.05715)
			(type default)
		)
		(layer "In11.Cu")
	)
	(gr_arc
		(start 108.34243 -223.889824)
		(mid 108.343447 -223.88919)
		(end 108.344462 -223.888554)
		(stroke
			(width 0.05715)
			(type default)
		)
		(layer "In11.Cu")
	)
	(gr_line
		(start 108.342684 -229.43947)
		(end 108.343192 -229.439724)
		(stroke
			(width 0.05715)
			(type default)
		)
		(layer "In11.Cu")
	)
	(gr_line
		(start 108.343192 -227.129086)
		(end 108.340398 -227.131118)
		(stroke
			(width 0.05715)
			(type default)
		)
		(layer "In11.Cu")
	)
	(gr_arc
		(start 108.343192 -227.129086)
		(mid 108.347141 -227.126309)
		(end 108.351066 -227.123498)
		(stroke
			(width 0.05715)
			(type default)
		)
		(layer "In11.Cu")
	)
	(gr_line
		(start 108.344462 -223.8883)
		(end 108.344462 -223.888554)
		(stroke
			(width 0.05715)
			(type default)
		)
		(layer "In11.Cu")
	)
	(gr_arc
		(start 108.344462 -223.8883)
		(mid 108.347899 -223.885899)
		(end 108.35132 -223.883474)
		(stroke
			(width 0.05715)
			(type default)
		)
		(layer "In11.Cu")
	)
	(gr_line
		(start 108.345224 -221.083378)
		(end 108.390944 -221.129098)
		(stroke
			(width 0.05715)
			(type default)
		)
		(layer "In11.Cu")
	)
	(gr_line
		(start 108.345224 -221.05493)
		(end 108.345224 -221.083378)
		(stroke
			(width 0.05715)
			(type default)
		)
		(layer "In11.Cu")
	)
	(gr_arc
		(start 108.35386 -229.447344)
		(mid 108.348548 -229.443503)
		(end 108.343192 -229.439724)
		(stroke
			(width 0.05715)
			(type default)
		)
		(layer "In11.Cu")
	)
	(gr_line
		(start 108.41609 -295.42359)
		(end 108.416344 -295.423336)
		(stroke
			(width 0.05715)
			(type default)
		)
		(layer "In11.Cu")
	)
	(gr_line
		(start 108.453936 -289.832288)
		(end 108.458254 -289.82924)
		(stroke
			(width 0.05715)
			(type default)
		)
		(layer "In11.Cu")
	)
	(gr_arc
		(start 108.461048 -289.125152)
		(mid 108.464973 -289.127963)
		(end 108.468922 -289.13074)
		(stroke
			(width 0.05715)
			(type default)
		)
		(layer "In11.Cu")
	)
	(gr_line
		(start 108.46181 -295.697402)
		(end 108.46181 -295.668954)
		(stroke
			(width 0.05715)
			(type default)
		)
		(layer "In11.Cu")
	)
	(gr_line
		(start 108.46181 -295.668954)
		(end 108.41609 -295.623234)
		(stroke
			(width 0.05715)
			(type default)
		)
		(layer "In11.Cu")
	)
	(gr_line
		(start 108.465366 -289.824414)
		(end 108.468414 -289.822382)
		(stroke
			(width 0.05715)
			(type default)
		)
		(layer "In11.Cu")
	)
	(gr_line
		(start 108.468668 -280.101802)
		(end 108.471462 -280.100278)
		(stroke
			(width 0.05715)
			(type default)
		)
		(layer "In11.Cu")
	)
	(gr_arc
		(start 108.468922 -281.721814)
		(mid 108.465357 -281.724214)
		(end 108.46181 -281.72664)
		(stroke
			(width 0.05715)
			(type default)
		)
		(layer "In11.Cu")
	)
	(gr_line
		(start 108.468922 -281.721814)
		(end 108.468922 -281.721052)
		(stroke
			(width 0.05715)
			(type default)
		)
		(layer "In11.Cu")
	)
	(gr_line
		(start 108.468922 -281.721052)
		(end 108.484416 -281.712162)
		(stroke
			(width 0.05715)
			(type default)
		)
		(layer "In11.Cu")
	)
	(gr_arc
		(start 108.468922 -280.101802)
		(mid 108.464973 -280.104579)
		(end 108.461048 -280.10739)
		(stroke
			(width 0.05715)
			(type default)
		)
		(layer "In11.Cu")
	)
	(gr_line
		(start 108.468922 -280.101802)
		(end 108.468668 -280.101802)
		(stroke
			(width 0.05715)
			(type default)
		)
		(layer "In11.Cu")
	)
	(gr_arc
		(start 108.468922 -278.48179)
		(mid 108.464973 -278.484567)
		(end 108.461048 -278.487378)
		(stroke
			(width 0.05715)
			(type default)
		)
		(layer "In11.Cu")
	)
	(gr_arc
		(start 108.468922 -278.48179)
		(mid 108.469303 -278.481536)
		(end 108.469684 -278.481282)
		(stroke
			(width 0.05715)
			(type default)
		)
		(layer "In11.Cu")
	)
	(gr_line
		(start 108.46943 -289.82162)
		(end 108.470954 -289.820604)
		(stroke
			(width 0.05715)
			(type default)
		)
		(layer "In11.Cu")
	)
	(gr_line
		(start 108.469684 -278.481282)
		(end 108.47705 -278.476964)
		(stroke
			(width 0.05715)
			(type default)
		)
		(layer "In11.Cu")
	)
	(gr_line
		(start 108.472986 -280.099262)
		(end 108.47705 -280.096976)
		(stroke
			(width 0.05715)
			(type default)
		)
		(layer "In11.Cu")
	)
	(gr_line
		(start 108.476542 -289.135312)
		(end 108.468922 -289.13074)
		(stroke
			(width 0.05715)
			(type default)
		)
		(layer "In11.Cu")
	)
	(gr_line
		(start 108.476796 -289.135312)
		(end 108.476542 -289.135312)
		(stroke
			(width 0.05715)
			(type default)
		)
		(layer "In11.Cu")
	)
	(gr_line
		(start 108.477558 -289.816794)
		(end 108.47832 -289.816286)
		(stroke
			(width 0.05715)
			(type default)
		)
		(layer "In11.Cu")
	)
	(gr_line
		(start 108.478828 -280.09596)
		(end 108.480352 -280.094944)
		(stroke
			(width 0.05715)
			(type default)
		)
		(layer "In11.Cu")
	)
	(gr_line
		(start 108.479082 -289.815778)
		(end 108.479336 -289.815524)
		(stroke
			(width 0.05715)
			(type default)
		)
		(layer "In11.Cu")
	)
	(gr_line
		(start 108.480098 -283.333952)
		(end 108.521246 -283.304488)
		(stroke
			(width 0.05715)
			(type default)
		)
		(layer "In11.Cu")
	)
	(gr_line
		(start 108.485178 -280.091642)
		(end 108.486448 -280.091134)
		(stroke
			(width 0.05715)
			(type default)
		)
		(layer "In11.Cu")
	)
	(gr_line
		(start 108.501434 -285.91002)
		(end 108.49991 -285.909004)
		(stroke
			(width 0.05715)
			(type default)
		)
		(layer "In11.Cu")
	)
	(gr_line
		(start 108.501434 -284.290008)
		(end 108.49991 -284.288992)
		(stroke
			(width 0.05715)
			(type default)
		)
		(layer "In11.Cu")
	)
	(gr_line
		(start 108.501434 -282.669996)
		(end 108.49991 -282.66898)
		(stroke
			(width 0.05715)
			(type default)
		)
		(layer "In11.Cu")
	)
	(gr_line
		(start 108.501434 -281.049984)
		(end 108.49991 -281.048968)
		(stroke
			(width 0.05715)
			(type default)
		)
		(layer "In11.Cu")
	)
	(gr_line
		(start 108.501434 -279.429972)
		(end 108.49991 -279.428956)
		(stroke
			(width 0.05715)
			(type default)
		)
		(layer "In11.Cu")
	)
	(gr_line
		(start 108.501434 -277.80996)
		(end 108.49991 -277.808944)
		(stroke
			(width 0.05715)
			(type default)
		)
		(layer "In11.Cu")
	)
	(gr_line
		(start 108.501688 -294.662606)
		(end 108.50372 -294.661336)
		(stroke
			(width 0.05715)
			(type default)
		)
		(layer "In11.Cu")
	)
	(gr_line
		(start 108.502704 -285.910782)
		(end 108.501434 -285.91002)
		(stroke
			(width 0.05715)
			(type default)
		)
		(layer "In11.Cu")
	)
	(gr_line
		(start 108.502704 -284.29077)
		(end 108.501434 -284.290008)
		(stroke
			(width 0.05715)
			(type default)
		)
		(layer "In11.Cu")
	)
	(gr_line
		(start 108.502704 -282.670758)
		(end 108.501434 -282.669996)
		(stroke
			(width 0.05715)
			(type default)
		)
		(layer "In11.Cu")
	)
	(gr_line
		(start 108.502704 -281.050746)
		(end 108.501434 -281.049984)
		(stroke
			(width 0.05715)
			(type default)
		)
		(layer "In11.Cu")
	)
	(gr_line
		(start 108.502704 -279.430734)
		(end 108.501434 -279.429972)
		(stroke
			(width 0.05715)
			(type default)
		)
		(layer "In11.Cu")
	)
	(gr_line
		(start 108.502704 -277.810722)
		(end 108.501434 -277.80996)
		(stroke
			(width 0.05715)
			(type default)
		)
		(layer "In11.Cu")
	)
	(gr_line
		(start 108.504482 -293.04107)
		(end 108.50626 -293.040054)
		(stroke
			(width 0.05715)
			(type default)
		)
		(layer "In11.Cu")
	)
	(gr_line
		(start 108.50499 -294.660574)
		(end 108.505752 -294.660066)
		(stroke
			(width 0.05715)
			(type default)
		)
		(layer "In11.Cu")
	)
	(gr_line
		(start 108.505498 -285.912306)
		(end 108.502704 -285.910782)
		(stroke
			(width 0.05715)
			(type default)
		)
		(layer "In11.Cu")
	)
	(gr_line
		(start 108.505498 -284.292294)
		(end 108.502704 -284.29077)
		(stroke
			(width 0.05715)
			(type default)
		)
		(layer "In11.Cu")
	)
	(gr_line
		(start 108.505498 -282.672282)
		(end 108.502704 -282.670758)
		(stroke
			(width 0.05715)
			(type default)
		)
		(layer "In11.Cu")
	)
	(gr_line
		(start 108.505498 -281.05227)
		(end 108.502704 -281.050746)
		(stroke
			(width 0.05715)
			(type default)
		)
		(layer "In11.Cu")
	)
	(gr_line
		(start 108.505498 -279.432258)
		(end 108.502704 -279.430734)
		(stroke
			(width 0.05715)
			(type default)
		)
		(layer "In11.Cu")
	)
	(gr_line
		(start 108.505498 -277.812246)
		(end 108.502704 -277.810722)
		(stroke
			(width 0.05715)
			(type default)
		)
		(layer "In11.Cu")
	)
	(gr_line
		(start 108.507022 -285.913322)
		(end 108.505498 -285.912306)
		(stroke
			(width 0.05715)
			(type default)
		)
		(layer "In11.Cu")
	)
	(gr_line
		(start 108.507022 -284.29331)
		(end 108.505498 -284.292294)
		(stroke
			(width 0.05715)
			(type default)
		)
		(layer "In11.Cu")
	)
	(gr_line
		(start 108.507022 -282.673298)
		(end 108.505498 -282.672282)
		(stroke
			(width 0.05715)
			(type default)
		)
		(layer "In11.Cu")
	)
	(gr_line
		(start 108.507022 -281.053286)
		(end 108.505498 -281.05227)
		(stroke
			(width 0.05715)
			(type default)
		)
		(layer "In11.Cu")
	)
	(gr_line
		(start 108.507022 -279.433274)
		(end 108.505498 -279.432258)
		(stroke
			(width 0.05715)
			(type default)
		)
		(layer "In11.Cu")
	)
	(gr_line
		(start 108.507022 -277.813262)
		(end 108.505498 -277.812246)
		(stroke
			(width 0.05715)
			(type default)
		)
		(layer "In11.Cu")
	)
	(gr_line
		(start 108.508038 -285.91383)
		(end 108.507022 -285.913322)
		(stroke
			(width 0.05715)
			(type default)
		)
		(layer "In11.Cu")
	)
	(gr_line
		(start 108.508038 -284.293818)
		(end 108.507022 -284.29331)
		(stroke
			(width 0.05715)
			(type default)
		)
		(layer "In11.Cu")
	)
	(gr_line
		(start 108.508038 -282.673806)
		(end 108.507022 -282.673298)
		(stroke
			(width 0.05715)
			(type default)
		)
		(layer "In11.Cu")
	)
	(gr_line
		(start 108.508038 -281.053794)
		(end 108.507022 -281.053286)
		(stroke
			(width 0.05715)
			(type default)
		)
		(layer "In11.Cu")
	)
	(gr_line
		(start 108.508038 -279.433782)
		(end 108.507022 -279.433274)
		(stroke
			(width 0.05715)
			(type default)
		)
		(layer "In11.Cu")
	)
	(gr_line
		(start 108.508038 -277.81377)
		(end 108.507022 -277.813262)
		(stroke
			(width 0.05715)
			(type default)
		)
		(layer "In11.Cu")
	)
	(gr_line
		(start 108.508292 -294.658542)
		(end 108.510324 -294.657526)
		(stroke
			(width 0.05715)
			(type default)
		)
		(layer "In11.Cu")
	)
	(gr_line
		(start 108.5088 -285.914338)
		(end 108.508038 -285.91383)
		(stroke
			(width 0.05715)
			(type default)
		)
		(layer "In11.Cu")
	)
	(gr_line
		(start 108.5088 -284.294326)
		(end 108.508038 -284.293818)
		(stroke
			(width 0.05715)
			(type default)
		)
		(layer "In11.Cu")
	)
	(gr_line
		(start 108.5088 -282.674314)
		(end 108.508038 -282.673806)
		(stroke
			(width 0.05715)
			(type default)
		)
		(layer "In11.Cu")
	)
	(gr_line
		(start 108.5088 -281.054302)
		(end 108.508038 -281.053794)
		(stroke
			(width 0.05715)
			(type default)
		)
		(layer "In11.Cu")
	)
	(gr_line
		(start 108.5088 -279.43429)
		(end 108.508038 -279.433782)
		(stroke
			(width 0.05715)
			(type default)
		)
		(layer "In11.Cu")
	)
	(gr_line
		(start 108.5088 -277.814278)
		(end 108.508038 -277.81377)
		(stroke
			(width 0.05715)
			(type default)
		)
		(layer "In11.Cu")
	)
	(gr_line
		(start 108.511086 -278.457406)
		(end 108.511594 -278.456898)
		(stroke
			(width 0.05715)
			(type default)
		)
		(layer "In11.Cu")
	)
	(gr_line
		(start 108.511594 -294.656764)
		(end 108.512356 -294.656256)
		(stroke
			(width 0.05715)
			(type default)
		)
		(layer "In11.Cu")
	)
	(gr_line
		(start 108.511594 -278.456898)
		(end 108.512864 -278.456136)
		(stroke
			(width 0.05715)
			(type default)
		)
		(layer "In11.Cu")
	)
	(gr_line
		(start 108.512864 -280.076148)
		(end 108.513626 -280.07564)
		(stroke
			(width 0.05715)
			(type default)
		)
		(layer "In11.Cu")
	)
	(gr_line
		(start 108.512864 -278.456136)
		(end 108.513626 -278.455628)
		(stroke
			(width 0.05715)
			(type default)
		)
		(layer "In11.Cu")
	)
	(gr_line
		(start 108.513626 -280.07564)
		(end 108.514642 -280.075132)
		(stroke
			(width 0.05715)
			(type default)
		)
		(layer "In11.Cu")
	)
	(gr_line
		(start 108.513626 -278.455628)
		(end 108.514642 -278.45512)
		(stroke
			(width 0.05715)
			(type default)
		)
		(layer "In11.Cu")
	)
	(gr_line
		(start 108.51388 -294.655494)
		(end 108.514388 -294.65524)
		(stroke
			(width 0.05715)
			(type default)
		)
		(layer "In11.Cu")
	)
	(gr_line
		(start 108.514642 -280.075132)
		(end 108.515912 -280.07437)
		(stroke
			(width 0.05715)
			(type default)
		)
		(layer "In11.Cu")
	)
	(gr_line
		(start 108.514642 -278.45512)
		(end 108.515912 -278.454358)
		(stroke
			(width 0.05715)
			(type default)
		)
		(layer "In11.Cu")
	)
	(gr_line
		(start 108.515912 -280.07437)
		(end 108.518452 -280.0731)
		(stroke
			(width 0.05715)
			(type default)
		)
		(layer "In11.Cu")
	)
	(gr_line
		(start 108.515912 -278.454358)
		(end 108.516928 -278.45385)
		(stroke
			(width 0.05715)
			(type default)
		)
		(layer "In11.Cu")
	)
	(gr_line
		(start 108.516928 -278.45385)
		(end 108.521246 -278.451564)
		(stroke
			(width 0.05715)
			(type default)
		)
		(layer "In11.Cu")
	)
	(gr_line
		(start 108.517944 -281.693112)
		(end 108.51896 -281.692604)
		(stroke
			(width 0.05715)
			(type default)
		)
		(layer "In11.Cu")
	)
	(gr_line
		(start 108.519722 -281.692096)
		(end 108.52023 -281.691842)
		(stroke
			(width 0.05715)
			(type default)
		)
		(layer "In11.Cu")
	)
	(gr_line
		(start 108.521246 -283.304488)
		(end 108.533946 -283.304488)
		(stroke
			(width 0.05715)
			(type default)
		)
		(layer "In11.Cu")
	)
	(gr_line
		(start 108.524802 -284.928818)
		(end 108.52531 -284.928564)
		(stroke
			(width 0.05715)
			(type default)
		)
		(layer "In11.Cu")
	)
	(gr_line
		(start 108.52658 -284.927802)
		(end 108.527088 -284.927548)
		(stroke
			(width 0.05715)
			(type default)
		)
		(layer "In11.Cu")
	)
	(gr_line
		(start 108.52785 -284.92704)
		(end 108.529882 -284.926024)
		(stroke
			(width 0.05715)
			(type default)
		)
		(layer "In11.Cu")
	)
	(gr_line
		(start 108.531152 -284.925262)
		(end 108.532676 -284.924246)
		(stroke
			(width 0.05715)
			(type default)
		)
		(layer "In11.Cu")
	)
	(gr_line
		(start 108.532676 -284.924246)
		(end 108.5342 -284.923484)
		(stroke
			(width 0.05715)
			(type default)
		)
		(layer "In11.Cu")
	)
	(gr_line
		(start 108.537248 -291.402516)
		(end 108.542836 -291.398452)
		(stroke
			(width 0.05715)
			(type default)
		)
		(layer "In11.Cu")
	)
	(gr_line
		(start 108.539534 -284.920436)
		(end 108.539788 -284.92069)
		(stroke
			(width 0.05715)
			(type default)
		)
		(layer "In11.Cu")
	)
	(gr_line
		(start 108.539534 -278.440642)
		(end 108.539788 -278.440642)
		(stroke
			(width 0.05715)
			(type default)
		)
		(layer "In11.Cu")
	)
	(gr_line
		(start 108.5723 -293.221918)
		(end 108.572554 -293.222172)
		(stroke
			(width 0.05715)
			(type default)
		)
		(layer "In11.Cu")
	)
	(gr_line
		(start 108.5723 -289.982148)
		(end 108.572554 -289.982402)
		(stroke
			(width 0.05715)
			(type default)
		)
		(layer "In11.Cu")
	)
	(gr_line
		(start 108.5723 -281.882088)
		(end 108.5723 -281.882342)
		(stroke
			(width 0.05715)
			(type default)
		)
		(layer "In11.Cu")
	)
	(gr_line
		(start 108.575094 -289.751516)
		(end 108.575348 -289.751262)
		(stroke
			(width 0.05715)
			(type default)
		)
		(layer "In11.Cu")
	)
	(gr_line
		(start 108.577634 -283.498798)
		(end 108.580174 -283.497528)
		(stroke
			(width 0.05715)
			(type default)
		)
		(layer "In11.Cu")
	)
	(gr_line
		(start 108.578904 -280.258266)
		(end 108.580174 -280.257504)
		(stroke
			(width 0.05715)
			(type default)
		)
		(layer "In11.Cu")
	)
	(gr_line
		(start 108.57992 -289.97783)
		(end 108.58246 -289.976052)
		(stroke
			(width 0.05715)
			(type default)
		)
		(layer "In11.Cu")
	)
	(gr_line
		(start 108.580174 -280.257504)
		(end 108.583222 -280.25598)
		(stroke
			(width 0.05715)
			(type default)
		)
		(layer "In11.Cu")
	)
	(gr_line
		(start 108.583222 -289.975544)
		(end 108.584238 -289.974782)
		(stroke
			(width 0.05715)
			(type default)
		)
		(layer "In11.Cu")
	)
	(gr_line
		(start 108.583222 -280.25598)
		(end 108.584746 -280.254964)
		(stroke
			(width 0.05715)
			(type default)
		)
		(layer "In11.Cu")
	)
	(gr_line
		(start 108.584492 -283.494988)
		(end 108.59008 -283.491686)
		(stroke
			(width 0.05715)
			(type default)
		)
		(layer "In11.Cu")
	)
	(gr_line
		(start 108.584746 -289.974274)
		(end 108.585254 -289.97402)
		(stroke
			(width 0.05715)
			(type default)
		)
		(layer "In11.Cu")
	)
	(gr_line
		(start 108.584746 -280.254964)
		(end 108.587286 -280.25344)
		(stroke
			(width 0.05715)
			(type default)
		)
		(layer "In11.Cu")
	)
	(gr_line
		(start 108.59008 -283.491686)
		(end 108.590842 -283.491432)
		(stroke
			(width 0.05715)
			(type default)
		)
		(layer "In11.Cu")
	)
	(gr_line
		(start 108.590842 -283.491432)
		(end 108.591858 -283.490924)
		(stroke
			(width 0.05715)
			(type default)
		)
		(layer "In11.Cu")
	)
	(gr_line
		(start 108.591858 -283.490924)
		(end 108.643166 -283.463492)
		(stroke
			(width 0.05715)
			(type default)
		)
		(layer "In11.Cu")
	)
	(gr_line
		(start 108.596938 -280.247852)
		(end 108.599224 -280.246582)
		(stroke
			(width 0.05715)
			(type default)
		)
		(layer "In11.Cu")
	)
	(gr_line
		(start 108.597192 -294.827706)
		(end 108.597954 -294.827198)
		(stroke
			(width 0.05715)
			(type default)
		)
		(layer "In11.Cu")
	)
	(gr_line
		(start 108.597954 -285.745428)
		(end 108.596938 -285.74492)
		(stroke
			(width 0.05715)
			(type default)
		)
		(layer "In11.Cu")
	)
	(gr_line
		(start 108.597954 -284.125416)
		(end 108.596938 -284.124908)
		(stroke
			(width 0.05715)
			(type default)
		)
		(layer "In11.Cu")
	)
	(gr_line
		(start 108.597954 -282.505404)
		(end 108.596938 -282.504896)
		(stroke
			(width 0.05715)
			(type default)
		)
		(layer "In11.Cu")
	)
	(gr_line
		(start 108.597954 -280.885392)
		(end 108.596938 -280.884884)
		(stroke
			(width 0.05715)
			(type default)
		)
		(layer "In11.Cu")
	)
	(gr_line
		(start 108.597954 -279.26538)
		(end 108.596938 -279.264872)
		(stroke
			(width 0.05715)
			(type default)
		)
		(layer "In11.Cu")
	)
	(gr_line
		(start 108.597954 -277.645368)
		(end 108.596938 -277.64486)
		(stroke
			(width 0.05715)
			(type default)
		)
		(layer "In11.Cu")
	)
	(gr_line
		(start 108.598716 -285.745936)
		(end 108.597954 -285.745428)
		(stroke
			(width 0.05715)
			(type default)
		)
		(layer "In11.Cu")
	)
	(gr_line
		(start 108.598716 -284.125924)
		(end 108.597954 -284.125416)
		(stroke
			(width 0.05715)
			(type default)
		)
		(layer "In11.Cu")
	)
	(gr_line
		(start 108.598716 -282.505912)
		(end 108.597954 -282.505404)
		(stroke
			(width 0.05715)
			(type default)
		)
		(layer "In11.Cu")
	)
	(gr_line
		(start 108.598716 -280.8859)
		(end 108.597954 -280.885392)
		(stroke
			(width 0.05715)
			(type default)
		)
		(layer "In11.Cu")
	)
	(gr_line
		(start 108.598716 -279.265888)
		(end 108.597954 -279.26538)
		(stroke
			(width 0.05715)
			(type default)
		)
		(layer "In11.Cu")
	)
	(gr_line
		(start 108.598716 -277.645876)
		(end 108.597954 -277.645368)
		(stroke
			(width 0.05715)
			(type default)
		)
		(layer "In11.Cu")
	)
	(gr_line
		(start 108.599732 -285.746444)
		(end 108.598716 -285.745936)
		(stroke
			(width 0.05715)
			(type default)
		)
		(layer "In11.Cu")
	)
	(gr_line
		(start 108.599732 -284.126432)
		(end 108.598716 -284.125924)
		(stroke
			(width 0.05715)
			(type default)
		)
		(layer "In11.Cu")
	)
	(gr_line
		(start 108.599732 -282.50642)
		(end 108.598716 -282.505912)
		(stroke
			(width 0.05715)
			(type default)
		)
		(layer "In11.Cu")
	)
	(gr_line
		(start 108.599732 -280.886408)
		(end 108.598716 -280.8859)
		(stroke
			(width 0.05715)
			(type default)
		)
		(layer "In11.Cu")
	)
	(gr_line
		(start 108.599732 -279.266396)
		(end 108.598716 -279.265888)
		(stroke
			(width 0.05715)
			(type default)
		)
		(layer "In11.Cu")
	)
	(gr_line
		(start 108.599732 -277.646384)
		(end 108.598716 -277.645876)
		(stroke
			(width 0.05715)
			(type default)
		)
		(layer "In11.Cu")
	)
	(gr_line
		(start 108.599986 -280.246074)
		(end 108.60151 -280.245312)
		(stroke
			(width 0.05715)
			(type default)
		)
		(layer "In11.Cu")
	)
	(gr_line
		(start 108.600494 -293.205916)
		(end 108.600494 -293.205662)
		(stroke
			(width 0.05715)
			(type default)
		)
		(layer "In11.Cu")
	)
	(gr_line
		(start 108.603288 -285.748476)
		(end 108.600494 -285.746952)
		(stroke
			(width 0.05715)
			(type default)
		)
		(layer "In11.Cu")
	)
	(gr_line
		(start 108.603288 -284.128464)
		(end 108.600494 -284.12694)
		(stroke
			(width 0.05715)
			(type default)
		)
		(layer "In11.Cu")
	)
	(gr_line
		(start 108.603288 -282.508452)
		(end 108.600494 -282.506928)
		(stroke
			(width 0.05715)
			(type default)
		)
		(layer "In11.Cu")
	)
	(gr_line
		(start 108.603288 -280.88844)
		(end 108.600494 -280.886916)
		(stroke
			(width 0.05715)
			(type default)
		)
		(layer "In11.Cu")
	)
	(gr_line
		(start 108.603288 -279.268428)
		(end 108.600494 -279.266904)
		(stroke
			(width 0.05715)
			(type default)
		)
		(layer "In11.Cu")
	)
	(gr_line
		(start 108.603288 -277.648416)
		(end 108.600494 -277.646892)
		(stroke
			(width 0.05715)
			(type default)
		)
		(layer "In11.Cu")
	)
	(gr_line
		(start 108.603796 -280.243788)
		(end 108.607098 -280.24201)
		(stroke
			(width 0.05715)
			(type default)
		)
		(layer "In11.Cu")
	)
	(gr_line
		(start 108.60405 -285.748984)
		(end 108.603288 -285.748476)
		(stroke
			(width 0.05715)
			(type default)
		)
		(layer "In11.Cu")
	)
	(gr_line
		(start 108.60405 -284.128972)
		(end 108.603288 -284.128464)
		(stroke
			(width 0.05715)
			(type default)
		)
		(layer "In11.Cu")
	)
	(gr_line
		(start 108.60405 -282.50896)
		(end 108.603288 -282.508452)
		(stroke
			(width 0.05715)
			(type default)
		)
		(layer "In11.Cu")
	)
	(gr_line
		(start 108.60405 -280.888948)
		(end 108.603288 -280.88844)
		(stroke
			(width 0.05715)
			(type default)
		)
		(layer "In11.Cu")
	)
	(gr_line
		(start 108.60405 -279.268936)
		(end 108.603288 -279.268428)
		(stroke
			(width 0.05715)
			(type default)
		)
		(layer "In11.Cu")
	)
	(gr_line
		(start 108.60405 -277.648924)
		(end 108.603288 -277.648416)
		(stroke
			(width 0.05715)
			(type default)
		)
		(layer "In11.Cu")
	)
	(gr_line
		(start 108.605066 -285.749492)
		(end 108.60405 -285.748984)
		(stroke
			(width 0.05715)
			(type default)
		)
		(layer "In11.Cu")
	)
	(gr_line
		(start 108.605066 -284.12948)
		(end 108.60405 -284.128972)
		(stroke
			(width 0.05715)
			(type default)
		)
		(layer "In11.Cu")
	)
	(gr_line
		(start 108.605066 -282.509468)
		(end 108.60405 -282.50896)
		(stroke
			(width 0.05715)
			(type default)
		)
		(layer "In11.Cu")
	)
	(gr_line
		(start 108.605066 -280.889456)
		(end 108.60405 -280.888948)
		(stroke
			(width 0.05715)
			(type default)
		)
		(layer "In11.Cu")
	)
	(gr_line
		(start 108.605066 -279.269444)
		(end 108.60405 -279.268936)
		(stroke
			(width 0.05715)
			(type default)
		)
		(layer "In11.Cu")
	)
	(gr_line
		(start 108.605066 -277.649432)
		(end 108.60405 -277.648924)
		(stroke
			(width 0.05715)
			(type default)
		)
		(layer "In11.Cu")
	)
	(gr_line
		(start 108.605574 -294.82288)
		(end 108.60659 -294.822118)
		(stroke
			(width 0.05715)
			(type default)
		)
		(layer "In11.Cu")
	)
	(gr_line
		(start 108.605828 -285.75)
		(end 108.605066 -285.749492)
		(stroke
			(width 0.05715)
			(type default)
		)
		(layer "In11.Cu")
	)
	(gr_line
		(start 108.605828 -284.129988)
		(end 108.605066 -284.12948)
		(stroke
			(width 0.05715)
			(type default)
		)
		(layer "In11.Cu")
	)
	(gr_line
		(start 108.605828 -282.509976)
		(end 108.605066 -282.509468)
		(stroke
			(width 0.05715)
			(type default)
		)
		(layer "In11.Cu")
	)
	(gr_line
		(start 108.605828 -280.889964)
		(end 108.605066 -280.889456)
		(stroke
			(width 0.05715)
			(type default)
		)
		(layer "In11.Cu")
	)
	(gr_line
		(start 108.605828 -279.269952)
		(end 108.605066 -279.269444)
		(stroke
			(width 0.05715)
			(type default)
		)
		(layer "In11.Cu")
	)
	(gr_line
		(start 108.605828 -277.64994)
		(end 108.605066 -277.649432)
		(stroke
			(width 0.05715)
			(type default)
		)
		(layer "In11.Cu")
	)
	(gr_line
		(start 108.60659 -294.822118)
		(end 108.608368 -294.821102)
		(stroke
			(width 0.05715)
			(type default)
		)
		(layer "In11.Cu")
	)
	(gr_line
		(start 108.60659 -278.622252)
		(end 108.608622 -278.621236)
		(stroke
			(width 0.05715)
			(type default)
		)
		(layer "In11.Cu")
	)
	(gr_line
		(start 108.608368 -294.821102)
		(end 108.609638 -294.82034)
		(stroke
			(width 0.05715)
			(type default)
		)
		(layer "In11.Cu")
	)
	(gr_line
		(start 108.609638 -294.82034)
		(end 108.6104 -294.819832)
		(stroke
			(width 0.05715)
			(type default)
		)
		(layer "In11.Cu")
	)
	(gr_line
		(start 108.609638 -285.752032)
		(end 108.608368 -285.75127)
		(stroke
			(width 0.05715)
			(type default)
		)
		(layer "In11.Cu")
	)
	(gr_line
		(start 108.609638 -284.13202)
		(end 108.608368 -284.131258)
		(stroke
			(width 0.05715)
			(type default)
		)
		(layer "In11.Cu")
	)
	(gr_line
		(start 108.609638 -282.512008)
		(end 108.608368 -282.511246)
		(stroke
			(width 0.05715)
			(type default)
		)
		(layer "In11.Cu")
	)
	(gr_line
		(start 108.609638 -280.891996)
		(end 108.608368 -280.891234)
		(stroke
			(width 0.05715)
			(type default)
		)
		(layer "In11.Cu")
	)
	(gr_line
		(start 108.609638 -279.271984)
		(end 108.608368 -279.271222)
		(stroke
			(width 0.05715)
			(type default)
		)
		(layer "In11.Cu")
	)
	(gr_line
		(start 108.609638 -277.651972)
		(end 108.608368 -277.65121)
		(stroke
			(width 0.05715)
			(type default)
		)
		(layer "In11.Cu")
	)
	(gr_line
		(start 108.611162 -280.239724)
		(end 108.611416 -280.23947)
		(stroke
			(width 0.05715)
			(type default)
		)
		(layer "In11.Cu")
	)
	(gr_line
		(start 108.613956 -280.237946)
		(end 108.614464 -280.237692)
		(stroke
			(width 0.05715)
			(type default)
		)
		(layer "In11.Cu")
	)
	(gr_line
		(start 108.621576 -285.09341)
		(end 108.622084 -285.093156)
		(stroke
			(width 0.05715)
			(type default)
		)
		(layer "In11.Cu")
	)
	(gr_line
		(start 108.624878 -278.613108)
		(end 108.625894 -278.6126)
		(stroke
			(width 0.05715)
			(type default)
		)
		(layer "In11.Cu")
	)
	(gr_line
		(start 108.625894 -278.6126)
		(end 108.631482 -278.6126)
		(stroke
			(width 0.05715)
			(type default)
		)
		(layer "In11.Cu")
	)
	(gr_line
		(start 108.626402 -285.09087)
		(end 108.62818 -285.089854)
		(stroke
			(width 0.05715)
			(type default)
		)
		(layer "In11.Cu")
	)
	(gr_line
		(start 108.626656 -281.850846)
		(end 108.643166 -281.841702)
		(stroke
			(width 0.05715)
			(type default)
		)
		(layer "In11.Cu")
	)
	(gr_line
		(start 108.627164 -221.083378)
		(end 108.581444 -221.129098)
		(stroke
			(width 0.05715)
			(type default)
		)
		(layer "In11.Cu")
	)
	(gr_line
		(start 108.627164 -221.05493)
		(end 108.627164 -221.083378)
		(stroke
			(width 0.05715)
			(type default)
		)
		(layer "In11.Cu")
	)
	(gr_line
		(start 108.62945 -285.089092)
		(end 108.630974 -285.088076)
		(stroke
			(width 0.05715)
			(type default)
		)
		(layer "In11.Cu")
	)
	(gr_line
		(start 108.630974 -285.088076)
		(end 108.632498 -285.087314)
		(stroke
			(width 0.05715)
			(type default)
		)
		(layer "In11.Cu")
	)
	(gr_line
		(start 108.631482 -278.6126)
		(end 108.639864 -278.604218)
		(stroke
			(width 0.05715)
			(type default)
		)
		(layer "In11.Cu")
	)
	(gr_line
		(start 108.634022 -285.086298)
		(end 108.635292 -285.085536)
		(stroke
			(width 0.05715)
			(type default)
		)
		(layer "In11.Cu")
	)
	(gr_line
		(start 108.635038 -284.147006)
		(end 108.634276 -284.146498)
		(stroke
			(width 0.05715)
			(type default)
		)
		(layer "In11.Cu")
	)
	(gr_line
		(start 108.635038 -280.906982)
		(end 108.634276 -280.906474)
		(stroke
			(width 0.05715)
			(type default)
		)
		(layer "In11.Cu")
	)
	(gr_line
		(start 108.635038 -279.28697)
		(end 108.634276 -279.286462)
		(stroke
			(width 0.05715)
			(type default)
		)
		(layer "In11.Cu")
	)
	(gr_line
		(start 108.635038 -277.666958)
		(end 108.634276 -277.66645)
		(stroke
			(width 0.05715)
			(type default)
		)
		(layer "In11.Cu")
	)
	(gr_line
		(start 108.635546 -285.767272)
		(end 108.634276 -285.76651)
		(stroke
			(width 0.05715)
			(type default)
		)
		(layer "In11.Cu")
	)
	(gr_line
		(start 108.635546 -282.527248)
		(end 108.634276 -282.526486)
		(stroke
			(width 0.05715)
			(type default)
		)
		(layer "In11.Cu")
	)
	(gr_line
		(start 108.6358 -284.147514)
		(end 108.635038 -284.147006)
		(stroke
			(width 0.05715)
			(type default)
		)
		(layer "In11.Cu")
	)
	(gr_line
		(start 108.6358 -280.90749)
		(end 108.635038 -280.906982)
		(stroke
			(width 0.05715)
			(type default)
		)
		(layer "In11.Cu")
	)
	(gr_line
		(start 108.6358 -279.287478)
		(end 108.635038 -279.28697)
		(stroke
			(width 0.05715)
			(type default)
		)
		(layer "In11.Cu")
	)
	(gr_line
		(start 108.6358 -277.667466)
		(end 108.635038 -277.666958)
		(stroke
			(width 0.05715)
			(type default)
		)
		(layer "In11.Cu")
	)
	(gr_line
		(start 108.636308 -285.76778)
		(end 108.635546 -285.767272)
		(stroke
			(width 0.05715)
			(type default)
		)
		(layer "In11.Cu")
	)
	(gr_line
		(start 108.636308 -282.527756)
		(end 108.635546 -282.527248)
		(stroke
			(width 0.05715)
			(type default)
		)
		(layer "In11.Cu")
	)
	(gr_line
		(start 108.638848 -285.083504)
		(end 108.643166 -285.080964)
		(stroke
			(width 0.05715)
			(type default)
		)
		(layer "In11.Cu")
	)
	(gr_line
		(start 108.642912 -278.60117)
		(end 108.643166 -278.600916)
		(stroke
			(width 0.05715)
			(type default)
		)
		(layer "In11.Cu")
	)
	(gr_line
		(start 108.643166 -285.771844)
		(end 108.636308 -285.76778)
		(stroke
			(width 0.05715)
			(type default)
		)
		(layer "In11.Cu")
	)
	(gr_arc
		(start 108.643166 -285.080964)
		(mid 108.647115 -285.078187)
		(end 108.65104 -285.075376)
		(stroke
			(width 0.05715)
			(type default)
		)
		(layer "In11.Cu")
	)
	(gr_line
		(start 108.643166 -284.151832)
		(end 108.6358 -284.147514)
		(stroke
			(width 0.05715)
			(type default)
		)
		(layer "In11.Cu")
	)
	(gr_line
		(start 108.643166 -283.463492)
		(end 108.643166 -283.461714)
		(stroke
			(width 0.05715)
			(type default)
		)
		(layer "In11.Cu")
	)
	(gr_line
		(start 108.643166 -282.53182)
		(end 108.636308 -282.527756)
		(stroke
			(width 0.05715)
			(type default)
		)
		(layer "In11.Cu")
	)
	(gr_line
		(start 108.643166 -281.841702)
		(end 108.643166 -281.84094)
		(stroke
			(width 0.05715)
			(type default)
		)
		(layer "In11.Cu")
	)
	(gr_arc
		(start 108.643166 -281.84094)
		(mid 108.647115 -281.838163)
		(end 108.65104 -281.835352)
		(stroke
			(width 0.05715)
			(type default)
		)
		(layer "In11.Cu")
	)
	(gr_line
		(start 108.643166 -280.911808)
		(end 108.6358 -280.90749)
		(stroke
			(width 0.05715)
			(type default)
		)
		(layer "In11.Cu")
	)
	(gr_line
		(start 108.643166 -279.291796)
		(end 108.6358 -279.287478)
		(stroke
			(width 0.05715)
			(type default)
		)
		(layer "In11.Cu")
	)
	(gr_arc
		(start 108.643166 -278.600916)
		(mid 108.647115 -278.598139)
		(end 108.65104 -278.595328)
		(stroke
			(width 0.05715)
			(type default)
		)
		(layer "In11.Cu")
	)
	(gr_line
		(start 108.643166 -277.671784)
		(end 108.6358 -277.667466)
		(stroke
			(width 0.05715)
			(type default)
		)
		(layer "In11.Cu")
	)
	(gr_arc
		(start 108.650786 -282.537408)
		(mid 108.646988 -282.534597)
		(end 108.643166 -282.53182)
		(stroke
			(width 0.05715)
			(type default)
		)
		(layer "In11.Cu")
	)
	(gr_arc
		(start 108.65104 -285.777432)
		(mid 108.647115 -285.774621)
		(end 108.643166 -285.771844)
		(stroke
			(width 0.05715)
			(type default)
		)
		(layer "In11.Cu")
	)
	(gr_arc
		(start 108.65104 -284.15742)
		(mid 108.647115 -284.154609)
		(end 108.643166 -284.151832)
		(stroke
			(width 0.05715)
			(type default)
		)
		(layer "In11.Cu")
	)
	(gr_arc
		(start 108.65104 -280.917396)
		(mid 108.647115 -280.914585)
		(end 108.643166 -280.911808)
		(stroke
			(width 0.05715)
			(type default)
		)
		(layer "In11.Cu")
	)
	(gr_arc
		(start 108.65104 -279.297384)
		(mid 108.647115 -279.294573)
		(end 108.643166 -279.291796)
		(stroke
			(width 0.05715)
			(type default)
		)
		(layer "In11.Cu")
	)
	(gr_arc
		(start 108.65104 -277.677372)
		(mid 108.647115 -277.674561)
		(end 108.643166 -277.671784)
		(stroke
			(width 0.05715)
			(type default)
		)
		(layer "In11.Cu")
	)
	(gr_line
		(start 108.681012 -289.910012)
		(end 108.689648 -289.904424)
		(stroke
			(width 0.05715)
			(type default)
		)
		(layer "In11.Cu")
	)
	(gr_line
		(start 108.689648 -289.904424)
		(end 108.69041 -289.90417)
		(stroke
			(width 0.05715)
			(type default)
		)
		(layer "In11.Cu")
	)
	(gr_arc
		(start 108.69041 -289.90417)
		(mid 108.697706 -289.897756)
		(end 108.704888 -289.891216)
		(stroke
			(width 0.05715)
			(type default)
		)
		(layer "In11.Cu")
	)
	(gr_line
		(start 108.788962 -248.534428)
		(end 108.49102 -248.534428)
		(stroke
			(width 0.05715)
			(type default)
		)
		(layer "In11.Cu")
	)
	(gr_line
		(start 108.788962 -246.914416)
		(end 108.49102 -246.914416)
		(stroke
			(width 0.05715)
			(type default)
		)
		(layer "In11.Cu")
	)
	(gr_line
		(start 108.788962 -245.294404)
		(end 108.49102 -245.294404)
		(stroke
			(width 0.05715)
			(type default)
		)
		(layer "In11.Cu")
	)
	(gr_line
		(start 108.788962 -243.674392)
		(end 108.49102 -243.674392)
		(stroke
			(width 0.05715)
			(type default)
		)
		(layer "In11.Cu")
	)
	(gr_line
		(start 108.821474 -376.54103)
		(end 108.530644 -376.83186)
		(stroke
			(width 0.07112)
			(type default)
		)
		(layer "In11.Cu")
	)
	(gr_line
		(start 108.821474 -376.25909)
		(end 108.530644 -375.96826)
		(stroke
			(width 0.07112)
			(type default)
		)
		(layer "In11.Cu")
	)
	(gr_line
		(start 108.858304 -245.225062)
		(end 108.788962 -245.294404)
		(stroke
			(width 0.05715)
			(type default)
		)
		(layer "In11.Cu")
	)
	(gr_line
		(start 108.871766 -248.451624)
		(end 108.788962 -248.534428)
		(stroke
			(width 0.05715)
			(type default)
		)
		(layer "In11.Cu")
	)
	(gr_line
		(start 108.871766 -246.831612)
		(end 108.788962 -246.914416)
		(stroke
			(width 0.05715)
			(type default)
		)
		(layer "In11.Cu")
	)
	(gr_line
		(start 108.871766 -243.591588)
		(end 108.788962 -243.674392)
		(stroke
			(width 0.05715)
			(type default)
		)
		(layer "In11.Cu")
	)
	(gr_arc
		(start 108.875576 -248.428764)
		(mid 108.873554 -248.440175)
		(end 108.871766 -248.451624)
		(stroke
			(width 0.05715)
			(type default)
		)
		(layer "In11.Cu")
	)
	(gr_arc
		(start 108.875576 -246.808752)
		(mid 108.873554 -246.820162)
		(end 108.871766 -246.831612)
		(stroke
			(width 0.05715)
			(type default)
		)
		(layer "In11.Cu")
	)
	(gr_arc
		(start 108.875576 -243.568728)
		(mid 108.873553 -243.580138)
		(end 108.871766 -243.591588)
		(stroke
			(width 0.05715)
			(type default)
		)
		(layer "In11.Cu")
	)
	(gr_arc
		(start 109.050328 -245.2116)
		(mid 109.048541 -245.20015)
		(end 109.046518 -245.18874)
		(stroke
			(width 0.05715)
			(type default)
		)
		(layer "In11.Cu")
	)
	(gr_line
		(start 109.050328 -245.2116)
		(end 109.133132 -245.294404)
		(stroke
			(width 0.05715)
			(type default)
		)
		(layer "In11.Cu")
	)
	(gr_line
		(start 109.06379 -248.465086)
		(end 109.133132 -248.534428)
		(stroke
			(width 0.05715)
			(type default)
		)
		(layer "In11.Cu")
	)
	(gr_line
		(start 109.06379 -246.845074)
		(end 109.133132 -246.914416)
		(stroke
			(width 0.05715)
			(type default)
		)
		(layer "In11.Cu")
	)
	(gr_line
		(start 109.06379 -243.60505)
		(end 109.133132 -243.674392)
		(stroke
			(width 0.05715)
			(type default)
		)
		(layer "In11.Cu")
	)
	(gr_line
		(start 109.088936 -278.946356)
		(end 108.790994 -278.946356)
		(stroke
			(width 0.05715)
			(type default)
		)
		(layer "In11.Cu")
	)
	(gr_line
		(start 109.088936 -277.326344)
		(end 108.790994 -277.326344)
		(stroke
			(width 0.05715)
			(type default)
		)
		(layer "In11.Cu")
	)
	(gr_line
		(start 109.088936 -275.706332)
		(end 108.790994 -275.706332)
		(stroke
			(width 0.05715)
			(type default)
		)
		(layer "In11.Cu")
	)
	(gr_arc
		(start 109.09808 -231.171496)
		(mid 109.103519 -231.175338)
		(end 109.109002 -231.179116)
		(stroke
			(width 0.05715)
			(type default)
		)
		(layer "In11.Cu")
	)
	(gr_arc
		(start 109.098334 -229.551484)
		(mid 109.1015 -229.553782)
		(end 109.104684 -229.556056)
		(stroke
			(width 0.05715)
			(type default)
		)
		(layer "In11.Cu")
	)
	(gr_arc
		(start 109.101128 -242.513358)
		(mid 109.105053 -242.516169)
		(end 109.109002 -242.518946)
		(stroke
			(width 0.05715)
			(type default)
		)
		(layer "In11.Cu")
	)
	(gr_arc
		(start 109.101128 -240.893346)
		(mid 109.105053 -240.896157)
		(end 109.109002 -240.898934)
		(stroke
			(width 0.05715)
			(type default)
		)
		(layer "In11.Cu")
	)
	(gr_arc
		(start 109.101128 -239.273334)
		(mid 109.105053 -239.276145)
		(end 109.109002 -239.278922)
		(stroke
			(width 0.05715)
			(type default)
		)
		(layer "In11.Cu")
	)
	(gr_arc
		(start 109.101128 -237.653322)
		(mid 109.105053 -237.656133)
		(end 109.109002 -237.65891)
		(stroke
			(width 0.05715)
			(type default)
		)
		(layer "In11.Cu")
	)
	(gr_arc
		(start 109.101128 -236.03331)
		(mid 109.105053 -236.036121)
		(end 109.109002 -236.038898)
		(stroke
			(width 0.05715)
			(type default)
		)
		(layer "In11.Cu")
	)
	(gr_arc
		(start 109.101128 -234.413298)
		(mid 109.105053 -234.416109)
		(end 109.109002 -234.418886)
		(stroke
			(width 0.05715)
			(type default)
		)
		(layer "In11.Cu")
	)
	(gr_arc
		(start 109.101128 -232.793286)
		(mid 109.105053 -232.796097)
		(end 109.109002 -232.798874)
		(stroke
			(width 0.05715)
			(type default)
		)
		(layer "In11.Cu")
	)
	(gr_arc
		(start 109.101128 -227.933504)
		(mid 109.105053 -227.936315)
		(end 109.109002 -227.939092)
		(stroke
			(width 0.05715)
			(type default)
		)
		(layer "In11.Cu")
	)
	(gr_arc
		(start 109.101128 -226.313492)
		(mid 109.105053 -226.316303)
		(end 109.109002 -226.31908)
		(stroke
			(width 0.05715)
			(type default)
		)
		(layer "In11.Cu")
	)
	(gr_arc
		(start 109.106208 -229.557072)
		(mid 109.107603 -229.55809)
		(end 109.109002 -229.559104)
		(stroke
			(width 0.05715)
			(type default)
		)
		(layer "In11.Cu")
	)
	(gr_line
		(start 109.109002 -242.518946)
		(end 109.11586 -242.52301)
		(stroke
			(width 0.05715)
			(type default)
		)
		(layer "In11.Cu")
	)
	(gr_line
		(start 109.109002 -240.898934)
		(end 109.11586 -240.902998)
		(stroke
			(width 0.05715)
			(type default)
		)
		(layer "In11.Cu")
	)
	(gr_line
		(start 109.109002 -239.278922)
		(end 109.11586 -239.282986)
		(stroke
			(width 0.05715)
			(type default)
		)
		(layer "In11.Cu")
	)
	(gr_line
		(start 109.109002 -237.65891)
		(end 109.11586 -237.662974)
		(stroke
			(width 0.05715)
			(type default)
		)
		(layer "In11.Cu")
	)
	(gr_line
		(start 109.109002 -236.038898)
		(end 109.11586 -236.042962)
		(stroke
			(width 0.05715)
			(type default)
		)
		(layer "In11.Cu")
	)
	(gr_line
		(start 109.109002 -234.418886)
		(end 109.11586 -234.42295)
		(stroke
			(width 0.05715)
			(type default)
		)
		(layer "In11.Cu")
	)
	(gr_line
		(start 109.109002 -232.798874)
		(end 109.11586 -232.802938)
		(stroke
			(width 0.05715)
			(type default)
		)
		(layer "In11.Cu")
	)
	(gr_line
		(start 109.109002 -231.179116)
		(end 109.114336 -231.182164)
		(stroke
			(width 0.05715)
			(type default)
		)
		(layer "In11.Cu")
	)
	(gr_line
		(start 109.109002 -229.559104)
		(end 109.115098 -229.56266)
		(stroke
			(width 0.05715)
			(type default)
		)
		(layer "In11.Cu")
	)
	(gr_arc
		(start 109.109764 -227.9396)
		(mid 109.109383 -227.939346)
		(end 109.109002 -227.939092)
		(stroke
			(width 0.05715)
			(type default)
		)
		(layer "In11.Cu")
	)
	(gr_line
		(start 109.109764 -227.9396)
		(end 109.116622 -227.943664)
		(stroke
			(width 0.05715)
			(type default)
		)
		(layer "In11.Cu")
	)
	(gr_arc
		(start 109.109764 -226.319588)
		(mid 109.109383 -226.319334)
		(end 109.109002 -226.31908)
		(stroke
			(width 0.05715)
			(type default)
		)
		(layer "In11.Cu")
	)
	(gr_line
		(start 109.109764 -226.319588)
		(end 109.117384 -226.323906)
		(stroke
			(width 0.05715)
			(type default)
		)
		(layer "In11.Cu")
	)
	(gr_line
		(start 109.115098 -229.56266)
		(end 109.115352 -229.562914)
		(stroke
			(width 0.05715)
			(type default)
		)
		(layer "In11.Cu")
	)
	(gr_line
		(start 109.11586 -242.52301)
		(end 109.116622 -242.523518)
		(stroke
			(width 0.05715)
			(type default)
		)
		(layer "In11.Cu")
	)
	(gr_line
		(start 109.11586 -240.902998)
		(end 109.116622 -240.903506)
		(stroke
			(width 0.05715)
			(type default)
		)
		(layer "In11.Cu")
	)
	(gr_line
		(start 109.11586 -239.282986)
		(end 109.116622 -239.283494)
		(stroke
			(width 0.05715)
			(type default)
		)
		(layer "In11.Cu")
	)
	(gr_line
		(start 109.11586 -237.662974)
		(end 109.116622 -237.663482)
		(stroke
			(width 0.05715)
			(type default)
		)
		(layer "In11.Cu")
	)
	(gr_line
		(start 109.11586 -236.042962)
		(end 109.116622 -236.04347)
		(stroke
			(width 0.05715)
			(type default)
		)
		(layer "In11.Cu")
	)
	(gr_line
		(start 109.11586 -234.42295)
		(end 109.116622 -234.423458)
		(stroke
			(width 0.05715)
			(type default)
		)
		(layer "In11.Cu")
	)
	(gr_line
		(start 109.11586 -232.802938)
		(end 109.116622 -232.803446)
		(stroke
			(width 0.05715)
			(type default)
		)
		(layer "In11.Cu")
	)
	(gr_line
		(start 109.116622 -242.523518)
		(end 109.117384 -242.524026)
		(stroke
			(width 0.05715)
			(type default)
		)
		(layer "In11.Cu")
	)
	(gr_line
		(start 109.116622 -240.903506)
		(end 109.117384 -240.904014)
		(stroke
			(width 0.05715)
			(type default)
		)
		(layer "In11.Cu")
	)
	(gr_line
		(start 109.116622 -239.283494)
		(end 109.117384 -239.284002)
		(stroke
			(width 0.05715)
			(type default)
		)
		(layer "In11.Cu")
	)
	(gr_line
		(start 109.116622 -237.663482)
		(end 109.117384 -237.66399)
		(stroke
			(width 0.05715)
			(type default)
		)
		(layer "In11.Cu")
	)
	(gr_line
		(start 109.116622 -236.04347)
		(end 109.117384 -236.043978)
		(stroke
			(width 0.05715)
			(type default)
		)
		(layer "In11.Cu")
	)
	(gr_line
		(start 109.116622 -234.423458)
		(end 109.117384 -234.423966)
		(stroke
			(width 0.05715)
			(type default)
		)
		(layer "In11.Cu")
	)
	(gr_line
		(start 109.116622 -232.803446)
		(end 109.117384 -232.803954)
		(stroke
			(width 0.05715)
			(type default)
		)
		(layer "In11.Cu")
	)
	(gr_line
		(start 109.119924 -295.697402)
		(end 109.119924 -295.668954)
		(stroke
			(width 0.05715)
			(type default)
		)
		(layer "In11.Cu")
	)
	(gr_line
		(start 109.119924 -295.668954)
		(end 109.165644 -295.623234)
		(stroke
			(width 0.05715)
			(type default)
		)
		(layer "In11.Cu")
	)
	(gr_line
		(start 109.127544 -373.643906)
		(end 109.42955 -373.945912)
		(stroke
			(width 0.07112)
			(type default)
		)
		(layer "In11.Cu")
	)
	(gr_line
		(start 109.127544 -373.451628)
		(end 109.127544 -373.643906)
		(stroke
			(width 0.07112)
			(type default)
		)
		(layer "In11.Cu")
	)
	(gr_line
		(start 109.133132 -248.534428)
		(end 109.431074 -248.534428)
		(stroke
			(width 0.05715)
			(type default)
		)
		(layer "In11.Cu")
	)
	(gr_line
		(start 109.133132 -246.914416)
		(end 109.431074 -246.914416)
		(stroke
			(width 0.05715)
			(type default)
		)
		(layer "In11.Cu")
	)
	(gr_line
		(start 109.133132 -245.294404)
		(end 109.431074 -245.294404)
		(stroke
			(width 0.05715)
			(type default)
		)
		(layer "In11.Cu")
	)
	(gr_line
		(start 109.133132 -243.674392)
		(end 109.431074 -243.674392)
		(stroke
			(width 0.05715)
			(type default)
		)
		(layer "In11.Cu")
	)
	(gr_line
		(start 109.133132 -227.953316)
		(end 109.13364 -227.95357)
		(stroke
			(width 0.05715)
			(type default)
		)
		(layer "In11.Cu")
	)
	(gr_line
		(start 109.13364 -227.95357)
		(end 109.135164 -227.954586)
		(stroke
			(width 0.05715)
			(type default)
		)
		(layer "In11.Cu")
	)
	(gr_line
		(start 109.13618 -227.955094)
		(end 109.137196 -227.955856)
		(stroke
			(width 0.05715)
			(type default)
		)
		(layer "In11.Cu")
	)
	(gr_line
		(start 109.137958 -227.95611)
		(end 109.140244 -227.95738)
		(stroke
			(width 0.05715)
			(type default)
		)
		(layer "In11.Cu")
	)
	(gr_line
		(start 109.141006 -224.71761)
		(end 109.142022 -224.718372)
		(stroke
			(width 0.05715)
			(type default)
		)
		(layer "In11.Cu")
	)
	(gr_line
		(start 109.142022 -224.718372)
		(end 109.144562 -224.719896)
		(stroke
			(width 0.05715)
			(type default)
		)
		(layer "In11.Cu")
	)
	(gr_line
		(start 109.142784 -226.338638)
		(end 109.143546 -226.339146)
		(stroke
			(width 0.05715)
			(type default)
		)
		(layer "In11.Cu")
	)
	(gr_line
		(start 109.143038 -239.298734)
		(end 109.1438 -239.299242)
		(stroke
			(width 0.05715)
			(type default)
		)
		(layer "In11.Cu")
	)
	(gr_line
		(start 109.143038 -237.678722)
		(end 109.1438 -237.67923)
		(stroke
			(width 0.05715)
			(type default)
		)
		(layer "In11.Cu")
	)
	(gr_line
		(start 109.143038 -234.438698)
		(end 109.1438 -234.439206)
		(stroke
			(width 0.05715)
			(type default)
		)
		(layer "In11.Cu")
	)
	(gr_line
		(start 109.143038 -232.818686)
		(end 109.1438 -232.819194)
		(stroke
			(width 0.05715)
			(type default)
		)
		(layer "In11.Cu")
	)
	(gr_line
		(start 109.143546 -226.339146)
		(end 109.144054 -226.3394)
		(stroke
			(width 0.05715)
			(type default)
		)
		(layer "In11.Cu")
	)
	(gr_line
		(start 109.144562 -224.719896)
		(end 109.145578 -224.720404)
		(stroke
			(width 0.05715)
			(type default)
		)
		(layer "In11.Cu")
	)
	(gr_line
		(start 109.145324 -242.540282)
		(end 109.147102 -242.541298)
		(stroke
			(width 0.05715)
			(type default)
		)
		(layer "In11.Cu")
	)
	(gr_line
		(start 109.145324 -240.92027)
		(end 109.147102 -240.921286)
		(stroke
			(width 0.05715)
			(type default)
		)
		(layer "In11.Cu")
	)
	(gr_line
		(start 109.145324 -236.060234)
		(end 109.147102 -236.06125)
		(stroke
			(width 0.05715)
			(type default)
		)
		(layer "In11.Cu")
	)
	(gr_line
		(start 109.145578 -224.720404)
		(end 109.147102 -224.72142)
		(stroke
			(width 0.05715)
			(type default)
		)
		(layer "In11.Cu")
	)
	(gr_line
		(start 109.14634 -227.960936)
		(end 109.147102 -227.961444)
		(stroke
			(width 0.05715)
			(type default)
		)
		(layer "In11.Cu")
	)
	(gr_line
		(start 109.147102 -242.541298)
		(end 109.148118 -242.541806)
		(stroke
			(width 0.05715)
			(type default)
		)
		(layer "In11.Cu")
	)
	(gr_line
		(start 109.147102 -240.921286)
		(end 109.148118 -240.921794)
		(stroke
			(width 0.05715)
			(type default)
		)
		(layer "In11.Cu")
	)
	(gr_line
		(start 109.147102 -236.06125)
		(end 109.148118 -236.061758)
		(stroke
			(width 0.05715)
			(type default)
		)
		(layer "In11.Cu")
	)
	(gr_line
		(start 109.147102 -224.72142)
		(end 109.148118 -224.721928)
		(stroke
			(width 0.05715)
			(type default)
		)
		(layer "In11.Cu")
	)
	(gr_line
		(start 109.14761 -246.427244)
		(end 109.146848 -246.427752)
		(stroke
			(width 0.05715)
			(type default)
		)
		(layer "In11.Cu")
	)
	(gr_line
		(start 109.148118 -243.186966)
		(end 109.147102 -243.187474)
		(stroke
			(width 0.05715)
			(type default)
		)
		(layer "In11.Cu")
	)
	(gr_line
		(start 109.148118 -242.541806)
		(end 109.14888 -242.542314)
		(stroke
			(width 0.05715)
			(type default)
		)
		(layer "In11.Cu")
	)
	(gr_line
		(start 109.148118 -241.566954)
		(end 109.147102 -241.567462)
		(stroke
			(width 0.05715)
			(type default)
		)
		(layer "In11.Cu")
	)
	(gr_line
		(start 109.148118 -240.921794)
		(end 109.14888 -240.922302)
		(stroke
			(width 0.05715)
			(type default)
		)
		(layer "In11.Cu")
	)
	(gr_line
		(start 109.148118 -239.946942)
		(end 109.147102 -239.94745)
		(stroke
			(width 0.05715)
			(type default)
		)
		(layer "In11.Cu")
	)
	(gr_line
		(start 109.148118 -238.32693)
		(end 109.147102 -238.327438)
		(stroke
			(width 0.05715)
			(type default)
		)
		(layer "In11.Cu")
	)
	(gr_line
		(start 109.148118 -236.706918)
		(end 109.147102 -236.707426)
		(stroke
			(width 0.05715)
			(type default)
		)
		(layer "In11.Cu")
	)
	(gr_line
		(start 109.148118 -236.061758)
		(end 109.14888 -236.062266)
		(stroke
			(width 0.05715)
			(type default)
		)
		(layer "In11.Cu")
	)
	(gr_line
		(start 109.148118 -235.086906)
		(end 109.147102 -235.087414)
		(stroke
			(width 0.05715)
			(type default)
		)
		(layer "In11.Cu")
	)
	(gr_line
		(start 109.148118 -233.466894)
		(end 109.147102 -233.467402)
		(stroke
			(width 0.05715)
			(type default)
		)
		(layer "In11.Cu")
	)
	(gr_line
		(start 109.148118 -231.846882)
		(end 109.147102 -231.84739)
		(stroke
			(width 0.05715)
			(type default)
		)
		(layer "In11.Cu")
	)
	(gr_line
		(start 109.148118 -228.607112)
		(end 109.147102 -228.60762)
		(stroke
			(width 0.05715)
			(type default)
		)
		(layer "In11.Cu")
	)
	(gr_line
		(start 109.148118 -224.721928)
		(end 109.14888 -224.722436)
		(stroke
			(width 0.05715)
			(type default)
		)
		(layer "In11.Cu")
	)
	(gr_line
		(start 109.148626 -228.606858)
		(end 109.148118 -228.607112)
		(stroke
			(width 0.05715)
			(type default)
		)
		(layer "In11.Cu")
	)
	(gr_line
		(start 109.148626 -226.34194)
		(end 109.149388 -226.342448)
		(stroke
			(width 0.05715)
			(type default)
		)
		(layer "In11.Cu")
	)
	(gr_line
		(start 109.14888 -243.186458)
		(end 109.148118 -243.186966)
		(stroke
			(width 0.05715)
			(type default)
		)
		(layer "In11.Cu")
	)
	(gr_line
		(start 109.14888 -242.542314)
		(end 109.151674 -242.543838)
		(stroke
			(width 0.05715)
			(type default)
		)
		(layer "In11.Cu")
	)
	(gr_line
		(start 109.14888 -241.566446)
		(end 109.148118 -241.566954)
		(stroke
			(width 0.05715)
			(type default)
		)
		(layer "In11.Cu")
	)
	(gr_line
		(start 109.14888 -240.922302)
		(end 109.151674 -240.923826)
		(stroke
			(width 0.05715)
			(type default)
		)
		(layer "In11.Cu")
	)
	(gr_line
		(start 109.14888 -236.70641)
		(end 109.148118 -236.706918)
		(stroke
			(width 0.05715)
			(type default)
		)
		(layer "In11.Cu")
	)
	(gr_line
		(start 109.14888 -236.062266)
		(end 109.151674 -236.06379)
		(stroke
			(width 0.05715)
			(type default)
		)
		(layer "In11.Cu")
	)
	(gr_line
		(start 109.15015 -243.185696)
		(end 109.14888 -243.186458)
		(stroke
			(width 0.05715)
			(type default)
		)
		(layer "In11.Cu")
	)
	(gr_line
		(start 109.15015 -241.565684)
		(end 109.14888 -241.566446)
		(stroke
			(width 0.05715)
			(type default)
		)
		(layer "In11.Cu")
	)
	(gr_line
		(start 109.15015 -236.705648)
		(end 109.14888 -236.70641)
		(stroke
			(width 0.05715)
			(type default)
		)
		(layer "In11.Cu")
	)
	(gr_line
		(start 109.15142 -246.425212)
		(end 109.14761 -246.427244)
		(stroke
			(width 0.05715)
			(type default)
		)
		(layer "In11.Cu")
	)
	(gr_line
		(start 109.17174 -279.02916)
		(end 109.088936 -278.946356)
		(stroke
			(width 0.05715)
			(type default)
		)
		(layer "In11.Cu")
	)
	(gr_arc
		(start 109.17174 -279.02916)
		(mid 109.173532 -279.040482)
		(end 109.17555 -279.051766)
		(stroke
			(width 0.05715)
			(type default)
		)
		(layer "In11.Cu")
	)
	(gr_line
		(start 109.17174 -277.409148)
		(end 109.088936 -277.326344)
		(stroke
			(width 0.05715)
			(type default)
		)
		(layer "In11.Cu")
	)
	(gr_arc
		(start 109.17174 -277.409148)
		(mid 109.173532 -277.42047)
		(end 109.17555 -277.431754)
		(stroke
			(width 0.05715)
			(type default)
		)
		(layer "In11.Cu")
	)
	(gr_line
		(start 109.17174 -275.789136)
		(end 109.088936 -275.706332)
		(stroke
			(width 0.05715)
			(type default)
		)
		(layer "In11.Cu")
	)
	(gr_arc
		(start 109.17174 -275.789136)
		(mid 109.173531 -275.800458)
		(end 109.17555 -275.811742)
		(stroke
			(width 0.05715)
			(type default)
		)
		(layer "In11.Cu")
	)
	(gr_line
		(start 109.210348 -231.017318)
		(end 109.210602 -231.017318)
		(stroke
			(width 0.05715)
			(type default)
		)
		(layer "In11.Cu")
	)
	(gr_line
		(start 109.23651 -242.372642)
		(end 109.238034 -242.373404)
		(stroke
			(width 0.05715)
			(type default)
		)
		(layer "In11.Cu")
	)
	(gr_line
		(start 109.23651 -240.75263)
		(end 109.238034 -240.753392)
		(stroke
			(width 0.05715)
			(type default)
		)
		(layer "In11.Cu")
	)
	(gr_line
		(start 109.23651 -239.132618)
		(end 109.238034 -239.13338)
		(stroke
			(width 0.05715)
			(type default)
		)
		(layer "In11.Cu")
	)
	(gr_line
		(start 109.23651 -237.512606)
		(end 109.238034 -237.513368)
		(stroke
			(width 0.05715)
			(type default)
		)
		(layer "In11.Cu")
	)
	(gr_line
		(start 109.23651 -235.892594)
		(end 109.238034 -235.893356)
		(stroke
			(width 0.05715)
			(type default)
		)
		(layer "In11.Cu")
	)
	(gr_line
		(start 109.23651 -234.272582)
		(end 109.238034 -234.273344)
		(stroke
			(width 0.05715)
			(type default)
		)
		(layer "In11.Cu")
	)
	(gr_line
		(start 109.23651 -232.65257)
		(end 109.238034 -232.653332)
		(stroke
			(width 0.05715)
			(type default)
		)
		(layer "In11.Cu")
	)
	(gr_line
		(start 109.23651 -224.552764)
		(end 109.237526 -224.553272)
		(stroke
			(width 0.05715)
			(type default)
		)
		(layer "In11.Cu")
	)
	(gr_line
		(start 109.236764 -227.792788)
		(end 109.237526 -227.793296)
		(stroke
			(width 0.05715)
			(type default)
		)
		(layer "In11.Cu")
	)
	(gr_line
		(start 109.237526 -227.793296)
		(end 109.238542 -227.793804)
		(stroke
			(width 0.05715)
			(type default)
		)
		(layer "In11.Cu")
	)
	(gr_line
		(start 109.237526 -224.553272)
		(end 109.238288 -224.55378)
		(stroke
			(width 0.05715)
			(type default)
		)
		(layer "In11.Cu")
	)
	(gr_line
		(start 109.238034 -242.373404)
		(end 109.239558 -242.37442)
		(stroke
			(width 0.05715)
			(type default)
		)
		(layer "In11.Cu")
	)
	(gr_line
		(start 109.238034 -240.753392)
		(end 109.239558 -240.754408)
		(stroke
			(width 0.05715)
			(type default)
		)
		(layer "In11.Cu")
	)
	(gr_line
		(start 109.238034 -239.13338)
		(end 109.239558 -239.134396)
		(stroke
			(width 0.05715)
			(type default)
		)
		(layer "In11.Cu")
	)
	(gr_line
		(start 109.238034 -237.513368)
		(end 109.239558 -237.514384)
		(stroke
			(width 0.05715)
			(type default)
		)
		(layer "In11.Cu")
	)
	(gr_line
		(start 109.238034 -235.893356)
		(end 109.239558 -235.894372)
		(stroke
			(width 0.05715)
			(type default)
		)
		(layer "In11.Cu")
	)
	(gr_line
		(start 109.238034 -234.273344)
		(end 109.239558 -234.27436)
		(stroke
			(width 0.05715)
			(type default)
		)
		(layer "In11.Cu")
	)
	(gr_line
		(start 109.238034 -232.653332)
		(end 109.239558 -232.654348)
		(stroke
			(width 0.05715)
			(type default)
		)
		(layer "In11.Cu")
	)
	(gr_line
		(start 109.238288 -224.55378)
		(end 109.239812 -224.554542)
		(stroke
			(width 0.05715)
			(type default)
		)
		(layer "In11.Cu")
	)
	(gr_line
		(start 109.238542 -227.793804)
		(end 109.239812 -227.794566)
		(stroke
			(width 0.05715)
			(type default)
		)
		(layer "In11.Cu")
	)
	(gr_line
		(start 109.239812 -224.554542)
		(end 109.240574 -224.55505)
		(stroke
			(width 0.05715)
			(type default)
		)
		(layer "In11.Cu")
	)
	(gr_line
		(start 109.242098 -242.37569)
		(end 109.243368 -242.376452)
		(stroke
			(width 0.05715)
			(type default)
		)
		(layer "In11.Cu")
	)
	(gr_line
		(start 109.242098 -240.755678)
		(end 109.243368 -240.75644)
		(stroke
			(width 0.05715)
			(type default)
		)
		(layer "In11.Cu")
	)
	(gr_line
		(start 109.242098 -239.135666)
		(end 109.243368 -239.136428)
		(stroke
			(width 0.05715)
			(type default)
		)
		(layer "In11.Cu")
	)
	(gr_line
		(start 109.242098 -237.515654)
		(end 109.243368 -237.516416)
		(stroke
			(width 0.05715)
			(type default)
		)
		(layer "In11.Cu")
	)
	(gr_line
		(start 109.242098 -235.895642)
		(end 109.243368 -235.896404)
		(stroke
			(width 0.05715)
			(type default)
		)
		(layer "In11.Cu")
	)
	(gr_line
		(start 109.242098 -234.27563)
		(end 109.243368 -234.276392)
		(stroke
			(width 0.05715)
			(type default)
		)
		(layer "In11.Cu")
	)
	(gr_line
		(start 109.242098 -232.655618)
		(end 109.243368 -232.65638)
		(stroke
			(width 0.05715)
			(type default)
		)
		(layer "In11.Cu")
	)
	(gr_line
		(start 109.24286 -224.55632)
		(end 109.243368 -224.556574)
		(stroke
			(width 0.05715)
			(type default)
		)
		(layer "In11.Cu")
	)
	(gr_line
		(start 109.243368 -243.35232)
		(end 109.242098 -243.353082)
		(stroke
			(width 0.05715)
			(type default)
		)
		(layer "In11.Cu")
	)
	(gr_line
		(start 109.243368 -242.376452)
		(end 109.24413 -242.37696)
		(stroke
			(width 0.05715)
			(type default)
		)
		(layer "In11.Cu")
	)
	(gr_line
		(start 109.243368 -241.732308)
		(end 109.242098 -241.73307)
		(stroke
			(width 0.05715)
			(type default)
		)
		(layer "In11.Cu")
	)
	(gr_line
		(start 109.243368 -240.75644)
		(end 109.24413 -240.756948)
		(stroke
			(width 0.05715)
			(type default)
		)
		(layer "In11.Cu")
	)
	(gr_line
		(start 109.243368 -240.112296)
		(end 109.242098 -240.113058)
		(stroke
			(width 0.05715)
			(type default)
		)
		(layer "In11.Cu")
	)
	(gr_line
		(start 109.243368 -239.136428)
		(end 109.24413 -239.136936)
		(stroke
			(width 0.05715)
			(type default)
		)
		(layer "In11.Cu")
	)
	(gr_line
		(start 109.243368 -238.492284)
		(end 109.242098 -238.493046)
		(stroke
			(width 0.05715)
			(type default)
		)
		(layer "In11.Cu")
	)
	(gr_line
		(start 109.243368 -237.516416)
		(end 109.24413 -237.516924)
		(stroke
			(width 0.05715)
			(type default)
		)
		(layer "In11.Cu")
	)
	(gr_line
		(start 109.243368 -236.872272)
		(end 109.242098 -236.873034)
		(stroke
			(width 0.05715)
			(type default)
		)
		(layer "In11.Cu")
	)
	(gr_line
		(start 109.243368 -235.896404)
		(end 109.24413 -235.896912)
		(stroke
			(width 0.05715)
			(type default)
		)
		(layer "In11.Cu")
	)
	(gr_line
		(start 109.243368 -235.25226)
		(end 109.242098 -235.253022)
		(stroke
			(width 0.05715)
			(type default)
		)
		(layer "In11.Cu")
	)
	(gr_line
		(start 109.243368 -234.276392)
		(end 109.24413 -234.2769)
		(stroke
			(width 0.05715)
			(type default)
		)
		(layer "In11.Cu")
	)
	(gr_line
		(start 109.243368 -233.632248)
		(end 109.242098 -233.63301)
		(stroke
			(width 0.05715)
			(type default)
		)
		(layer "In11.Cu")
	)
	(gr_line
		(start 109.243368 -232.65638)
		(end 109.24413 -232.656888)
		(stroke
			(width 0.05715)
			(type default)
		)
		(layer "In11.Cu")
	)
	(gr_line
		(start 109.243368 -232.012236)
		(end 109.242098 -232.012998)
		(stroke
			(width 0.05715)
			(type default)
		)
		(layer "In11.Cu")
	)
	(gr_line
		(start 109.243368 -228.772466)
		(end 109.242098 -228.773228)
		(stroke
			(width 0.05715)
			(type default)
		)
		(layer "In11.Cu")
	)
	(gr_line
		(start 109.243368 -224.556574)
		(end 109.24413 -224.557082)
		(stroke
			(width 0.05715)
			(type default)
		)
		(layer "In11.Cu")
	)
	(gr_line
		(start 109.243876 -243.352066)
		(end 109.243368 -243.35232)
		(stroke
			(width 0.05715)
			(type default)
		)
		(layer "In11.Cu")
	)
	(gr_line
		(start 109.243876 -241.732054)
		(end 109.243368 -241.732308)
		(stroke
			(width 0.05715)
			(type default)
		)
		(layer "In11.Cu")
	)
	(gr_line
		(start 109.243876 -240.112042)
		(end 109.243368 -240.112296)
		(stroke
			(width 0.05715)
			(type default)
		)
		(layer "In11.Cu")
	)
	(gr_line
		(start 109.243876 -238.49203)
		(end 109.243368 -238.492284)
		(stroke
			(width 0.05715)
			(type default)
		)
		(layer "In11.Cu")
	)
	(gr_line
		(start 109.243876 -236.872018)
		(end 109.243368 -236.872272)
		(stroke
			(width 0.05715)
			(type default)
		)
		(layer "In11.Cu")
	)
	(gr_line
		(start 109.243876 -235.252006)
		(end 109.243368 -235.25226)
		(stroke
			(width 0.05715)
			(type default)
		)
		(layer "In11.Cu")
	)
	(gr_line
		(start 109.243876 -233.631994)
		(end 109.243368 -233.632248)
		(stroke
			(width 0.05715)
			(type default)
		)
		(layer "In11.Cu")
	)
	(gr_line
		(start 109.243876 -232.011982)
		(end 109.243368 -232.012236)
		(stroke
			(width 0.05715)
			(type default)
		)
		(layer "In11.Cu")
	)
	(gr_line
		(start 109.24413 -248.211848)
		(end 109.243622 -248.212102)
		(stroke
			(width 0.05715)
			(type default)
		)
		(layer "In11.Cu")
	)
	(gr_line
		(start 109.24413 -224.557082)
		(end 109.245146 -224.55759)
		(stroke
			(width 0.05715)
			(type default)
		)
		(layer "In11.Cu")
	)
	(gr_line
		(start 109.246416 -246.590312)
		(end 109.245146 -246.591074)
		(stroke
			(width 0.05715)
			(type default)
		)
		(layer "In11.Cu")
	)
	(gr_arc
		(start 109.255052 -228.765862)
		(mid 109.257978 -228.764092)
		(end 109.260894 -228.762306)
		(stroke
			(width 0.05715)
			(type default)
		)
		(layer "In11.Cu")
	)
	(gr_arc
		(start 109.260894 -227.806758)
		(mid 109.257599 -227.804715)
		(end 109.25429 -227.802694)
		(stroke
			(width 0.05715)
			(type default)
		)
		(layer "In11.Cu")
	)
	(gr_line
		(start 109.290104 -221.083378)
		(end 109.335824 -221.129098)
		(stroke
			(width 0.05715)
			(type default)
		)
		(layer "In11.Cu")
	)
	(gr_line
		(start 109.290104 -221.05493)
		(end 109.290104 -221.083378)
		(stroke
			(width 0.05715)
			(type default)
		)
		(layer "In11.Cu")
	)
	(gr_line
		(start 109.326934 -373.25046)
		(end 109.822996 -373.746522)
		(stroke
			(width 0.07112)
			(type default)
		)
		(layer "In11.Cu")
	)
	(gr_line
		(start 109.335824 -221.30893)
		(end 109.335824 -221.309946)
		(stroke
			(width 0.05715)
			(type default)
		)
		(layer "In11.Cu")
	)
	(gr_line
		(start 109.356144 -295.292272)
		(end 109.356398 -295.292018)
		(stroke
			(width 0.05715)
			(type default)
		)
		(layer "In11.Cu")
	)
	(gr_line
		(start 109.356398 -287.046416)
		(end 109.356144 -287.046162)
		(stroke
			(width 0.05715)
			(type default)
		)
		(layer "In11.Cu")
	)
	(gr_line
		(start 109.363764 -279.015698)
		(end 109.433106 -278.946356)
		(stroke
			(width 0.05715)
			(type default)
		)
		(layer "In11.Cu")
	)
	(gr_line
		(start 109.363764 -277.395686)
		(end 109.433106 -277.326344)
		(stroke
			(width 0.05715)
			(type default)
		)
		(layer "In11.Cu")
	)
	(gr_line
		(start 109.363764 -275.775674)
		(end 109.433106 -275.706332)
		(stroke
			(width 0.05715)
			(type default)
		)
		(layer "In11.Cu")
	)
	(gr_line
		(start 109.398562 -229.54615)
		(end 109.398562 -229.546404)
		(stroke
			(width 0.05715)
			(type default)
		)
		(layer "In11.Cu")
	)
	(gr_arc
		(start 109.400848 -276.16531)
		(mid 109.4049 -276.168122)
		(end 109.408976 -276.170898)
		(stroke
			(width 0.05715)
			(type default)
		)
		(layer "In11.Cu")
	)
	(gr_arc
		(start 109.401102 -289.125152)
		(mid 109.405027 -289.127963)
		(end 109.408976 -289.13074)
		(stroke
			(width 0.05715)
			(type default)
		)
		(layer "In11.Cu")
	)
	(gr_line
		(start 109.401864 -295.697402)
		(end 109.401864 -295.668954)
		(stroke
			(width 0.05715)
			(type default)
		)
		(layer "In11.Cu")
	)
	(gr_line
		(start 109.401864 -295.668954)
		(end 109.356144 -295.623234)
		(stroke
			(width 0.05715)
			(type default)
		)
		(layer "In11.Cu")
	)
	(gr_arc
		(start 109.408976 -294.681656)
		(mid 109.405027 -294.684433)
		(end 109.401102 -294.687244)
		(stroke
			(width 0.05715)
			(type default)
		)
		(layer "In11.Cu")
	)
	(gr_arc
		(start 109.408976 -294.681656)
		(mid 109.409357 -294.681402)
		(end 109.409738 -294.681148)
		(stroke
			(width 0.05715)
			(type default)
		)
		(layer "In11.Cu")
	)
	(gr_line
		(start 109.409738 -294.681148)
		(end 109.41685 -294.677084)
		(stroke
			(width 0.05715)
			(type default)
		)
		(layer "In11.Cu")
	)
	(gr_arc
		(start 109.409738 -276.171406)
		(mid 109.409357 -276.171152)
		(end 109.408976 -276.170898)
		(stroke
			(width 0.05715)
			(type default)
		)
		(layer "In11.Cu")
	)
	(gr_line
		(start 109.41304 -286.57931)
		(end 109.41558 -286.577786)
		(stroke
			(width 0.05715)
			(type default)
		)
		(layer "In11.Cu")
	)
	(gr_line
		(start 109.415834 -289.134804)
		(end 109.408976 -289.13074)
		(stroke
			(width 0.05715)
			(type default)
		)
		(layer "In11.Cu")
	)
	(gr_line
		(start 109.416088 -276.175216)
		(end 109.409738 -276.171406)
		(stroke
			(width 0.05715)
			(type default)
		)
		(layer "In11.Cu")
	)
	(gr_line
		(start 109.416596 -289.135312)
		(end 109.415834 -289.134804)
		(stroke
			(width 0.05715)
			(type default)
		)
		(layer "In11.Cu")
	)
	(gr_line
		(start 109.41685 -276.175724)
		(end 109.416088 -276.175216)
		(stroke
			(width 0.05715)
			(type default)
		)
		(layer "In11.Cu")
	)
	(gr_line
		(start 109.417104 -289.135566)
		(end 109.416596 -289.135312)
		(stroke
			(width 0.05715)
			(type default)
		)
		(layer "In11.Cu")
	)
	(gr_line
		(start 109.42955 -373.945912)
		(end 109.621828 -373.945912)
		(stroke
			(width 0.07112)
			(type default)
		)
		(layer "In11.Cu")
	)
	(gr_line
		(start 109.433106 -278.946356)
		(end 109.731048 -278.946356)
		(stroke
			(width 0.05715)
			(type default)
		)
		(layer "In11.Cu")
	)
	(gr_line
		(start 109.433106 -277.326344)
		(end 109.731048 -277.326344)
		(stroke
			(width 0.05715)
			(type default)
		)
		(layer "In11.Cu")
	)
	(gr_line
		(start 109.433106 -275.706332)
		(end 109.731048 -275.706332)
		(stroke
			(width 0.05715)
			(type default)
		)
		(layer "In11.Cu")
	)
	(gr_line
		(start 109.439456 -292.388798)
		(end 109.43844 -292.38829)
		(stroke
			(width 0.05715)
			(type default)
		)
		(layer "In11.Cu")
	)
	(gr_line
		(start 109.440218 -292.389306)
		(end 109.439456 -292.388798)
		(stroke
			(width 0.05715)
			(type default)
		)
		(layer "In11.Cu")
	)
	(gr_line
		(start 109.441488 -292.390068)
		(end 109.440218 -292.389306)
		(stroke
			(width 0.05715)
			(type default)
		)
		(layer "In11.Cu")
	)
	(gr_line
		(start 109.445806 -276.192488)
		(end 109.445044 -276.19198)
		(stroke
			(width 0.05715)
			(type default)
		)
		(layer "In11.Cu")
	)
	(gr_line
		(start 109.447076 -292.393116)
		(end 109.441488 -292.390068)
		(stroke
			(width 0.05715)
			(type default)
		)
		(layer "In11.Cu")
	)
	(gr_line
		(start 109.447076 -291.41928)
		(end 109.448092 -291.418772)
		(stroke
			(width 0.05715)
			(type default)
		)
		(layer "In11.Cu")
	)
	(gr_line
		(start 109.447076 -289.799268)
		(end 109.448092 -289.79876)
		(stroke
			(width 0.05715)
			(type default)
		)
		(layer "In11.Cu")
	)
	(gr_line
		(start 109.447076 -289.153092)
		(end 109.445044 -289.151822)
		(stroke
			(width 0.05715)
			(type default)
		)
		(layer "In11.Cu")
	)
	(gr_line
		(start 109.447838 -276.193504)
		(end 109.445806 -276.192488)
		(stroke
			(width 0.05715)
			(type default)
		)
		(layer "In11.Cu")
	)
	(gr_line
		(start 109.448092 -289.79876)
		(end 109.448854 -289.798252)
		(stroke
			(width 0.05715)
			(type default)
		)
		(layer "In11.Cu")
	)
	(gr_line
		(start 109.448092 -289.1536)
		(end 109.447076 -289.153092)
		(stroke
			(width 0.05715)
			(type default)
		)
		(layer "In11.Cu")
	)
	(gr_line
		(start 109.448854 -289.798252)
		(end 109.450124 -289.79749)
		(stroke
			(width 0.05715)
			(type default)
		)
		(layer "In11.Cu")
	)
	(gr_line
		(start 109.448854 -289.154108)
		(end 109.448092 -289.1536)
		(stroke
			(width 0.05715)
			(type default)
		)
		(layer "In11.Cu")
	)
	(gr_line
		(start 109.450632 -276.195028)
		(end 109.447838 -276.193504)
		(stroke
			(width 0.05715)
			(type default)
		)
		(layer "In11.Cu")
	)
	(gr_line
		(start 109.451648 -289.155632)
		(end 109.448854 -289.154108)
		(stroke
			(width 0.05715)
			(type default)
		)
		(layer "In11.Cu")
	)
	(gr_line
		(start 109.463078 -277.822406)
		(end 109.461046 -277.821136)
		(stroke
			(width 0.05715)
			(type default)
		)
		(layer "In11.Cu")
	)
	(gr_line
		(start 109.469682 -294.026082)
		(end 109.469428 -294.026082)
		(stroke
			(width 0.05715)
			(type default)
		)
		(layer "In11.Cu")
	)
	(gr_arc
		(start 109.522768 -229.935024)
		(mid 109.523833 -229.926902)
		(end 109.5248 -229.918768)
		(stroke
			(width 0.05715)
			(type default)
		)
		(layer "In11.Cu")
	)
	(gr_arc
		(start 109.5248 -229.918768)
		(mid 109.524604 -229.910257)
		(end 109.524292 -229.90175)
		(stroke
			(width 0.05715)
			(type default)
		)
		(layer "In11.Cu")
	)
	(gr_arc
		(start 109.526324 -231.530906)
		(mid 109.526334 -231.527604)
		(end 109.526324 -231.524302)
		(stroke
			(width 0.05715)
			(type default)
		)
		(layer "In11.Cu")
	)
	(gr_line
		(start 109.52734 -221.387924)
		(end 109.52734 -221.38894)
		(stroke
			(width 0.05715)
			(type default)
		)
		(layer "In11.Cu")
	)
	(gr_line
		(start 109.530896 -293.84117)
		(end 109.525054 -293.837868)
		(stroke
			(width 0.05715)
			(type default)
		)
		(layer "In11.Cu")
	)
	(gr_line
		(start 109.540548 -288.986722)
		(end 109.539786 -288.986214)
		(stroke
			(width 0.05715)
			(type default)
		)
		(layer "In11.Cu")
	)
	(gr_line
		(start 109.540802 -293.205154)
		(end 109.541818 -293.204646)
		(stroke
			(width 0.05715)
			(type default)
		)
		(layer "In11.Cu")
	)
	(gr_line
		(start 109.540802 -292.227)
		(end 109.54004 -292.226492)
		(stroke
			(width 0.05715)
			(type default)
		)
		(layer "In11.Cu")
	)
	(gr_line
		(start 109.541818 -292.227508)
		(end 109.540802 -292.227)
		(stroke
			(width 0.05715)
			(type default)
		)
		(layer "In11.Cu")
	)
	(gr_line
		(start 109.542072 -291.584888)
		(end 109.543342 -291.584126)
		(stroke
			(width 0.05715)
			(type default)
		)
		(layer "In11.Cu")
	)
	(gr_line
		(start 109.542072 -289.964876)
		(end 109.543342 -289.964114)
		(stroke
			(width 0.05715)
			(type default)
		)
		(layer "In11.Cu")
	)
	(gr_line
		(start 109.542072 -288.987484)
		(end 109.540548 -288.986722)
		(stroke
			(width 0.05715)
			(type default)
		)
		(layer "In11.Cu")
	)
	(gr_line
		(start 109.54258 -292.228016)
		(end 109.541818 -292.227508)
		(stroke
			(width 0.05715)
			(type default)
		)
		(layer "In11.Cu")
	)
	(gr_line
		(start 109.542834 -288.987992)
		(end 109.542072 -288.987484)
		(stroke
			(width 0.05715)
			(type default)
		)
		(layer "In11.Cu")
	)
	(gr_line
		(start 109.543342 -291.584126)
		(end 109.544104 -291.583618)
		(stroke
			(width 0.05715)
			(type default)
		)
		(layer "In11.Cu")
	)
	(gr_line
		(start 109.543342 -289.964114)
		(end 109.54385 -289.96386)
		(stroke
			(width 0.05715)
			(type default)
		)
		(layer "In11.Cu")
	)
	(gr_line
		(start 109.544104 -290.608766)
		(end 109.543596 -290.608512)
		(stroke
			(width 0.05715)
			(type default)
		)
		(layer "In11.Cu")
	)
	(gr_line
		(start 109.544104 -288.343848)
		(end 109.54385 -288.343594)
		(stroke
			(width 0.05715)
			(type default)
		)
		(layer "In11.Cu")
	)
	(gr_line
		(start 109.54512 -293.202868)
		(end 109.546898 -293.201852)
		(stroke
			(width 0.05715)
			(type default)
		)
		(layer "In11.Cu")
	)
	(gr_line
		(start 109.546136 -276.030182)
		(end 109.542072 -276.027642)
		(stroke
			(width 0.05715)
			(type default)
		)
		(layer "In11.Cu")
	)
	(gr_line
		(start 109.549438 -293.200582)
		(end 109.551724 -293.199312)
		(stroke
			(width 0.05715)
			(type default)
		)
		(layer "In11.Cu")
	)
	(gr_line
		(start 109.551724 -293.199312)
		(end 109.553248 -293.198296)
		(stroke
			(width 0.05715)
			(type default)
		)
		(layer "In11.Cu")
	)
	(gr_arc
		(start 109.554772 -247.278398)
		(mid 109.551971 -247.28093)
		(end 109.549184 -247.283478)
		(stroke
			(width 0.05715)
			(type default)
		)
		(layer "In11.Cu")
	)
	(gr_line
		(start 109.55909 -277.65756)
		(end 109.55909 -277.657306)
		(stroke
			(width 0.05715)
			(type default)
		)
		(layer "In11.Cu")
	)
	(gr_arc
		(start 109.561122 -247.273318)
		(mid 109.557937 -247.275846)
		(end 109.554772 -247.278398)
		(stroke
			(width 0.05715)
			(type default)
		)
		(layer "In11.Cu")
	)
	(gr_line
		(start 109.563662 -288.332164)
		(end 109.56671 -288.330132)
		(stroke
			(width 0.05715)
			(type default)
		)
		(layer "In11.Cu")
	)
	(gr_line
		(start 109.564678 -293.860728)
		(end 109.563662 -293.86022)
		(stroke
			(width 0.05715)
			(type default)
		)
		(layer "In11.Cu")
	)
	(gr_line
		(start 109.56544 -293.861236)
		(end 109.564678 -293.860728)
		(stroke
			(width 0.05715)
			(type default)
		)
		(layer "In11.Cu")
	)
	(gr_line
		(start 109.572044 -221.083378)
		(end 109.526324 -221.129098)
		(stroke
			(width 0.05715)
			(type default)
		)
		(layer "In11.Cu")
	)
	(gr_line
		(start 109.572044 -221.05493)
		(end 109.572044 -221.083378)
		(stroke
			(width 0.05715)
			(type default)
		)
		(layer "In11.Cu")
	)
	(gr_arc
		(start 109.612684 -245.620032)
		(mid 109.613319 -245.619651)
		(end 109.613954 -245.61927)
		(stroke
			(width 0.05715)
			(type default)
		)
		(layer "In11.Cu")
	)
	(gr_line
		(start 109.618018 -247.236996)
		(end 109.61751 -247.23725)
		(stroke
			(width 0.05715)
			(type default)
		)
		(layer "In11.Cu")
	)
	(gr_line
		(start 109.61878 -247.236488)
		(end 109.618018 -247.236996)
		(stroke
			(width 0.05715)
			(type default)
		)
		(layer "In11.Cu")
	)
	(gr_line
		(start 109.620558 -247.235472)
		(end 109.61878 -247.236488)
		(stroke
			(width 0.05715)
			(type default)
		)
		(layer "In11.Cu")
	)
	(gr_line
		(start 109.635544 -287.856422)
		(end 109.635798 -287.856676)
		(stroke
			(width 0.05715)
			(type default)
		)
		(layer "In11.Cu")
	)
	(gr_line
		(start 109.649514 -244.990112)
		(end 109.649768 -244.990112)
		(stroke
			(width 0.05715)
			(type default)
		)
		(layer "In11.Cu")
	)
	(gr_line
		(start 109.71403 -247.401842)
		(end 109.713522 -247.401842)
		(stroke
			(width 0.05715)
			(type default)
		)
		(layer "In11.Cu")
	)
	(gr_line
		(start 109.715046 -247.401334)
		(end 109.71403 -247.401842)
		(stroke
			(width 0.05715)
			(type default)
		)
		(layer "In11.Cu")
	)
	(gr_line
		(start 109.71657 -247.400318)
		(end 109.715046 -247.401334)
		(stroke
			(width 0.05715)
			(type default)
		)
		(layer "In11.Cu")
	)
	(gr_line
		(start 109.719872 -247.398286)
		(end 109.71657 -247.400318)
		(stroke
			(width 0.05715)
			(type default)
		)
		(layer "In11.Cu")
	)
	(gr_line
		(start 109.719872 -245.778274)
		(end 109.713268 -245.782084)
		(stroke
			(width 0.05715)
			(type default)
		)
		(layer "In11.Cu")
	)
	(gr_line
		(start 109.787944 -375.56821)
		(end 109.923834 -375.7041)
		(stroke
			(width 0.07112)
			(type default)
		)
		(layer "In11.Cu")
	)
	(gr_line
		(start 109.787944 -375.14149)
		(end 109.787944 -375.56821)
		(stroke
			(width 0.07112)
			(type default)
		)
		(layer "In11.Cu")
	)
	(gr_line
		(start 109.826298 -286.229806)
		(end 109.826298 -286.23641)
		(stroke
			(width 0.05715)
			(type default)
		)
		(layer "In11.Cu")
	)
	(gr_line
		(start 109.826552 -278.194262)
		(end 109.826298 -278.194516)
		(stroke
			(width 0.05715)
			(type default)
		)
		(layer "In11.Cu")
	)
	(gr_line
		(start 109.908086 -276.997668)
		(end 109.907832 -276.997668)
		(stroke
			(width 0.05715)
			(type default)
		)
		(layer "In11.Cu")
	)
	(gr_line
		(start 109.912404 -211.641944)
		(end 109.91215 -211.642198)
		(stroke
			(width 0.07112)
			(type default)
		)
		(layer "In11.Cu")
	)
	(gr_line
		(start 109.91596 -278.622506)
		(end 109.911388 -278.619458)
		(stroke
			(width 0.05715)
			(type default)
		)
		(layer "In11.Cu")
	)
	(gr_line
		(start 109.91723 -278.623268)
		(end 109.91596 -278.622506)
		(stroke
			(width 0.05715)
			(type default)
		)
		(layer "In11.Cu")
	)
	(gr_line
		(start 109.917992 -277.003764)
		(end 109.917484 -277.00351)
		(stroke
			(width 0.05715)
			(type default)
		)
		(layer "In11.Cu")
	)
	(gr_line
		(start 109.918754 -278.624284)
		(end 109.91723 -278.623268)
		(stroke
			(width 0.05715)
			(type default)
		)
		(layer "In11.Cu")
	)
	(gr_line
		(start 109.918754 -277.004272)
		(end 109.917992 -277.003764)
		(stroke
			(width 0.05715)
			(type default)
		)
		(layer "In11.Cu")
	)
	(gr_line
		(start 109.923834 -375.0056)
		(end 109.787944 -375.14149)
		(stroke
			(width 0.07112)
			(type default)
		)
		(layer "In11.Cu")
	)
	(gr_line
		(start 110.017306 -278.460708)
		(end 110.01502 -278.459438)
		(stroke
			(width 0.05715)
			(type default)
		)
		(layer "In11.Cu")
	)
	(gr_line
		(start 110.0455 -278.477218)
		(end 110.044738 -278.47671)
		(stroke
			(width 0.05715)
			(type default)
		)
		(layer "In11.Cu")
	)
	(gr_line
		(start 110.046262 -278.477726)
		(end 110.0455 -278.477218)
		(stroke
			(width 0.05715)
			(type default)
		)
		(layer "In11.Cu")
	)
	(gr_line
		(start 110.046262 -276.857714)
		(end 110.0455 -276.857206)
		(stroke
			(width 0.05715)
			(type default)
		)
		(layer "In11.Cu")
	)
	(gr_line
		(start 110.05312 -278.48179)
		(end 110.046262 -278.477726)
		(stroke
			(width 0.05715)
			(type default)
		)
		(layer "In11.Cu")
	)
	(gr_line
		(start 110.05312 -276.861778)
		(end 110.046262 -276.857714)
		(stroke
			(width 0.05715)
			(type default)
		)
		(layer "In11.Cu")
	)
	(gr_line
		(start 110.059978 -295.697402)
		(end 110.059978 -295.668954)
		(stroke
			(width 0.05715)
			(type default)
		)
		(layer "In11.Cu")
	)
	(gr_line
		(start 110.059978 -295.668954)
		(end 110.105698 -295.623234)
		(stroke
			(width 0.05715)
			(type default)
		)
		(layer "In11.Cu")
	)
	(gr_arc
		(start 110.060994 -278.487378)
		(mid 110.057069 -278.484567)
		(end 110.05312 -278.48179)
		(stroke
			(width 0.05715)
			(type default)
		)
		(layer "In11.Cu")
	)
	(gr_arc
		(start 110.060994 -276.867366)
		(mid 110.057069 -276.864555)
		(end 110.05312 -276.861778)
		(stroke
			(width 0.05715)
			(type default)
		)
		(layer "In11.Cu")
	)
	(gr_line
		(start 110.15345 -243.369846)
		(end 110.15345 -243.369592)
		(stroke
			(width 0.05715)
			(type default)
		)
		(layer "In11.Cu")
	)
	(gr_line
		(start 110.15345 -240.129822)
		(end 110.15345 -240.129568)
		(stroke
			(width 0.05715)
			(type default)
		)
		(layer "In11.Cu")
	)
	(gr_line
		(start 110.15345 -238.50981)
		(end 110.15345 -238.509556)
		(stroke
			(width 0.05715)
			(type default)
		)
		(layer "In11.Cu")
	)
	(gr_line
		(start 110.15345 -236.889798)
		(end 110.15345 -236.889544)
		(stroke
			(width 0.05715)
			(type default)
		)
		(layer "In11.Cu")
	)
	(gr_line
		(start 110.15345 -235.269786)
		(end 110.15345 -235.269532)
		(stroke
			(width 0.05715)
			(type default)
		)
		(layer "In11.Cu")
	)
	(gr_line
		(start 110.15345 -233.649774)
		(end 110.15345 -233.64952)
		(stroke
			(width 0.05715)
			(type default)
		)
		(layer "In11.Cu")
	)
	(gr_line
		(start 110.207044 -375.00433)
		(end 110.207044 -375.70537)
		(stroke
			(width 0.07112)
			(type default)
		)
		(layer "In11.Cu")
	)
	(gr_line
		(start 110.274354 -242.896898)
		(end 110.274354 -242.89766)
		(stroke
			(width 0.05715)
			(type default)
		)
		(layer "In11.Cu")
	)
	(gr_line
		(start 110.275116 -229.902004)
		(end 110.274862 -229.902004)
		(stroke
			(width 0.05715)
			(type default)
		)
		(layer "In11.Cu")
	)
	(gr_line
		(start 110.275878 -242.864386)
		(end 110.275624 -242.864386)
		(stroke
			(width 0.05715)
			(type default)
		)
		(layer "In11.Cu")
	)
	(gr_line
		(start 110.30585 -220.632274)
		(end 110.306104 -220.632528)
		(stroke
			(width 0.07112)
			(type default)
		)
		(layer "In11.Cu")
	)
	(gr_line
		(start 110.30585 -216.037668)
		(end 110.30585 -216.115392)
		(stroke
			(width 0.07112)
			(type default)
		)
		(layer "In11.Cu")
	)
	(gr_line
		(start 110.306104 -216.037414)
		(end 110.30585 -216.037668)
		(stroke
			(width 0.07112)
			(type default)
		)
		(layer "In11.Cu")
	)
	(gr_line
		(start 110.334806 -215.9889)
		(end 110.306104 -216.037414)
		(stroke
			(width 0.07112)
			(type default)
		)
		(layer "In11.Cu")
	)
	(gr_line
		(start 110.341918 -295.697402)
		(end 110.341918 -295.668954)
		(stroke
			(width 0.05715)
			(type default)
		)
		(layer "In11.Cu")
	)
	(gr_line
		(start 110.341918 -295.668954)
		(end 110.296198 -295.623234)
		(stroke
			(width 0.05715)
			(type default)
		)
		(layer "In11.Cu")
	)
	(gr_arc
		(start 110.34268 -290.74618)
		(mid 110.345088 -290.747965)
		(end 110.347506 -290.749736)
		(stroke
			(width 0.05715)
			(type default)
		)
		(layer "In11.Cu")
	)
	(gr_line
		(start 110.345474 -215.970866)
		(end 110.33506 -215.988392)
		(stroke
			(width 0.07112)
			(type default)
		)
		(layer "In11.Cu")
	)
	(gr_arc
		(start 110.34903 -294.681656)
		(mid 110.34572 -294.683931)
		(end 110.342426 -294.686228)
		(stroke
			(width 0.05715)
			(type default)
		)
		(layer "In11.Cu")
	)
	(gr_arc
		(start 110.350554 -294.68064)
		(mid 110.349792 -294.681147)
		(end 110.34903 -294.681656)
		(stroke
			(width 0.05715)
			(type default)
		)
		(layer "In11.Cu")
	)
	(gr_line
		(start 110.350554 -294.68064)
		(end 110.357412 -294.676576)
		(stroke
			(width 0.05715)
			(type default)
		)
		(layer "In11.Cu")
	)
	(gr_arc
		(start 110.375446 -294.00627)
		(mid 110.377476 -294.007417)
		(end 110.37951 -294.008556)
		(stroke
			(width 0.05715)
			(type default)
		)
		(layer "In11.Cu")
	)
	(gr_line
		(start 110.387892 -293.039038)
		(end 110.388146 -293.038784)
		(stroke
			(width 0.05715)
			(type default)
		)
		(layer "In11.Cu")
	)
	(gr_line
		(start 110.388146 -294.013636)
		(end 110.387892 -294.013636)
		(stroke
			(width 0.05715)
			(type default)
		)
		(layer "In11.Cu")
	)
	(gr_line
		(start 110.3884 -277.81377)
		(end 110.388146 -277.81377)
		(stroke
			(width 0.05715)
			(type default)
		)
		(layer "In11.Cu")
	)
	(gr_line
		(start 110.388908 -285.914084)
		(end 110.387892 -285.913576)
		(stroke
			(width 0.05715)
			(type default)
		)
		(layer "In11.Cu")
	)
	(gr_line
		(start 110.39983 -371.214396)
		(end 110.115096 -371.49913)
		(stroke
			(width 0.07112)
			(type default)
		)
		(layer "In11.Cu")
	)
	(gr_line
		(start 110.39983 -371.202204)
		(end 110.39983 -371.214396)
		(stroke
			(width 0.07112)
			(type default)
		)
		(layer "In11.Cu")
	)
	(gr_arc
		(start 110.428278 -286.534352)
		(mid 110.429168 -286.533591)
		(end 110.430056 -286.532828)
		(stroke
			(width 0.05715)
			(type default)
		)
		(layer "In11.Cu")
	)
	(gr_line
		(start 110.45317 -294.841422)
		(end 110.453424 -294.841422)
		(stroke
			(width 0.05715)
			(type default)
		)
		(layer "In11.Cu")
	)
	(gr_line
		(start 110.46587 -229.902258)
		(end 110.466124 -229.90429)
		(stroke
			(width 0.05715)
			(type default)
		)
		(layer "In11.Cu")
	)
	(gr_line
		(start 110.466124 -229.90429)
		(end 110.466378 -229.90429)
		(stroke
			(width 0.05715)
			(type default)
		)
		(layer "In11.Cu")
	)
	(gr_line
		(start 110.466378 -229.90429)
		(end 110.466378 -229.91572)
		(stroke
			(width 0.05715)
			(type default)
		)
		(layer "In11.Cu")
	)
	(gr_line
		(start 110.483142 -277.648162)
		(end 110.480348 -277.646638)
		(stroke
			(width 0.05715)
			(type default)
		)
		(layer "In11.Cu")
	)
	(gr_line
		(start 110.483904 -277.64867)
		(end 110.483142 -277.648162)
		(stroke
			(width 0.05715)
			(type default)
		)
		(layer "In11.Cu")
	)
	(gr_line
		(start 110.484158 -285.749238)
		(end 110.484158 -285.748984)
		(stroke
			(width 0.05715)
			(type default)
		)
		(layer "In11.Cu")
	)
	(gr_line
		(start 110.484158 -285.748984)
		(end 110.483904 -285.748984)
		(stroke
			(width 0.05715)
			(type default)
		)
		(layer "In11.Cu")
	)
	(gr_line
		(start 110.484412 -277.648924)
		(end 110.483904 -277.64867)
		(stroke
			(width 0.05715)
			(type default)
		)
		(layer "In11.Cu")
	)
	(gr_line
		(start 110.50524 -293.191184)
		(end 110.505494 -293.191184)
		(stroke
			(width 0.05715)
			(type default)
		)
		(layer "In11.Cu")
	)
	(gr_line
		(start 110.514892 -277.666704)
		(end 110.513622 -277.665942)
		(stroke
			(width 0.05715)
			(type default)
		)
		(layer "In11.Cu")
	)
	(gr_line
		(start 110.515654 -293.185088)
		(end 110.516416 -293.18458)
		(stroke
			(width 0.05715)
			(type default)
		)
		(layer "In11.Cu")
	)
	(gr_line
		(start 110.516416 -293.18458)
		(end 110.52302 -293.18077)
		(stroke
			(width 0.05715)
			(type default)
		)
		(layer "In11.Cu")
	)
	(gr_line
		(start 110.521496 -293.870634)
		(end 110.516162 -293.867586)
		(stroke
			(width 0.05715)
			(type default)
		)
		(layer "In11.Cu")
	)
	(gr_arc
		(start 110.52302 -293.87165)
		(mid 110.522258 -293.871141)
		(end 110.521496 -293.870634)
		(stroke
			(width 0.05715)
			(type default)
		)
		(layer "In11.Cu")
	)
	(gr_arc
		(start 110.52302 -293.18077)
		(mid 110.524164 -293.18001)
		(end 110.525306 -293.179246)
		(stroke
			(width 0.05715)
			(type default)
		)
		(layer "In11.Cu")
	)
	(gr_arc
		(start 110.526068 -293.178738)
		(mid 110.528869 -293.176715)
		(end 110.531656 -293.174674)
		(stroke
			(width 0.05715)
			(type default)
		)
		(layer "In11.Cu")
	)
	(gr_line
		(start 110.528608 -293.87546)
		(end 110.52302 -293.87165)
		(stroke
			(width 0.05715)
			(type default)
		)
		(layer "In11.Cu")
	)
	(gr_line
		(start 110.534958 -277.678642)
		(end 110.514892 -277.666704)
		(stroke
			(width 0.05715)
			(type default)
		)
		(layer "In11.Cu")
	)
	(gr_arc
		(start 110.5408 -285.06801)
		(mid 110.542453 -285.066743)
		(end 110.544102 -285.06547)
		(stroke
			(width 0.05715)
			(type default)
		)
		(layer "In11.Cu")
	)
	(gr_arc
		(start 110.544102 -285.06547)
		(mid 110.545628 -285.064203)
		(end 110.54715 -285.06293)
		(stroke
			(width 0.05715)
			(type default)
		)
		(layer "In11.Cu")
	)
	(gr_line
		(start 110.552484 -277.696168)
		(end 110.534958 -277.678642)
		(stroke
			(width 0.05715)
			(type default)
		)
		(layer "In11.Cu")
	)
	(gr_line
		(start 110.575344 -292.730174)
		(end 110.575344 -292.729158)
		(stroke
			(width 0.05715)
			(type default)
		)
		(layer "In11.Cu")
	)
	(gr_line
		(start 110.58779 -220.573854)
		(end 110.588044 -220.574108)
		(stroke
			(width 0.07112)
			(type default)
		)
		(layer "In11.Cu")
	)
	(gr_line
		(start 110.68304 -371.203474)
		(end 110.978696 -371.49913)
		(stroke
			(width 0.07112)
			(type default)
		)
		(layer "In11.Cu")
	)
	(gr_line
		(start 110.724442 -245.808246)
		(end 110.723934 -245.808754)
		(stroke
			(width 0.05715)
			(type default)
		)
		(layer "In11.Cu")
	)
	(gr_line
		(start 110.724442 -245.744238)
		(end 110.724442 -245.808246)
		(stroke
			(width 0.05715)
			(type default)
		)
		(layer "In11.Cu")
	)
	(gr_line
		(start 110.744508 -245.724172)
		(end 110.724442 -245.744238)
		(stroke
			(width 0.05715)
			(type default)
		)
		(layer "In11.Cu")
	)
	(gr_line
		(start 110.765082 -282.961842)
		(end 110.765082 -282.963112)
		(stroke
			(width 0.05715)
			(type default)
		)
		(layer "In11.Cu")
	)
	(gr_arc
		(start 110.765844 -292.737286)
		(mid 110.765983 -292.73373)
		(end 110.766098 -292.730174)
		(stroke
			(width 0.05715)
			(type default)
		)
		(layer "In11.Cu")
	)
	(gr_line
		(start 110.766352 -292.716204)
		(end 110.766098 -292.716204)
		(stroke
			(width 0.05715)
			(type default)
		)
		(layer "In11.Cu")
	)
	(gr_line
		(start 110.838742 -278.316944)
		(end 110.838742 -278.25192)
		(stroke
			(width 0.05715)
			(type default)
		)
		(layer "In11.Cu")
	)
	(gr_line
		(start 110.858808 -278.33701)
		(end 110.838742 -278.316944)
		(stroke
			(width 0.05715)
			(type default)
		)
		(layer "In11.Cu")
	)
	(gr_line
		(start 110.923832 -245.943628)
		(end 110.859824 -245.943628)
		(stroke
			(width 0.05715)
			(type default)
		)
		(layer "In11.Cu")
	)
	(gr_line
		(start 110.943898 -245.923562)
		(end 110.923832 -245.943628)
		(stroke
			(width 0.05715)
			(type default)
		)
		(layer "In11.Cu")
	)
	(gr_line
		(start 111.037878 -278.1173)
		(end 110.973616 -278.1173)
		(stroke
			(width 0.05715)
			(type default)
		)
		(layer "In11.Cu")
	)
	(gr_line
		(start 111.058198 -278.13762)
		(end 111.037878 -278.1173)
		(stroke
			(width 0.05715)
			(type default)
		)
		(layer "In11.Cu")
	)
	(gr_line
		(start 112.107726 -368.7445)
		(end 111.816896 -369.03533)
		(stroke
			(width 0.07112)
			(type default)
		)
		(layer "In11.Cu")
	)
	(gr_line
		(start 112.389666 -368.7445)
		(end 112.680496 -369.03533)
		(stroke
			(width 0.07112)
			(type default)
		)
		(layer "In11.Cu")
	)
	(gr_line
		(start 113.174272 -278.055832)
		(end 113.154206 -278.075898)
		(stroke
			(width 0.05715)
			(type default)
		)
		(layer "In11.Cu")
	)
	(gr_line
		(start 113.238534 -278.055832)
		(end 113.174272 -278.055832)
		(stroke
			(width 0.05715)
			(type default)
		)
		(layer "In11.Cu")
	)
	(gr_line
		(start 113.239296 -278.055324)
		(end 113.238534 -278.055832)
		(stroke
			(width 0.05715)
			(type default)
		)
		(layer "In11.Cu")
	)
	(gr_line
		(start 113.373916 -278.254968)
		(end 113.35385 -278.275034)
		(stroke
			(width 0.05715)
			(type default)
		)
		(layer "In11.Cu")
	)
	(gr_line
		(start 113.373916 -278.191214)
		(end 113.373916 -278.254968)
		(stroke
			(width 0.05715)
			(type default)
		)
		(layer "In11.Cu")
	)
	(gr_line
		(start 113.38941 -286.23641)
		(end 113.389664 -286.23641)
		(stroke
			(width 0.05715)
			(type default)
		)
		(layer "In11.Cu")
	)
	(gr_line
		(start 113.38941 -279.768554)
		(end 113.38941 -279.760934)
		(stroke
			(width 0.05715)
			(type default)
		)
		(layer "In11.Cu")
	)
	(gr_arc
		(start 113.389664 -279.753568)
		(mid 113.389527 -279.757251)
		(end 113.38941 -279.760934)
		(stroke
			(width 0.05715)
			(type default)
		)
		(layer "In11.Cu")
	)
	(gr_arc
		(start 113.389918 -286.215582)
		(mid 113.389779 -286.219138)
		(end 113.389664 -286.222694)
		(stroke
			(width 0.05715)
			(type default)
		)
		(layer "In11.Cu")
	)
	(gr_arc
		(start 113.659158 -285.096458)
		(mid 113.661188 -285.097605)
		(end 113.663222 -285.098744)
		(stroke
			(width 0.05715)
			(type default)
		)
		(layer "In11.Cu")
	)
	(gr_arc
		(start 113.662714 -293.19855)
		(mid 113.663603 -293.199059)
		(end 113.664492 -293.199566)
		(stroke
			(width 0.05715)
			(type default)
		)
		(layer "In11.Cu")
	)
	(gr_arc
		(start 113.665508 -292.23208)
		(mid 113.66411 -292.232967)
		(end 113.662714 -292.233858)
		(stroke
			(width 0.05715)
			(type default)
		)
		(layer "In11.Cu")
	)
	(gr_line
		(start 113.668048 -283.481526)
		(end 113.67262 -283.48432)
		(stroke
			(width 0.05715)
			(type default)
		)
		(layer "In11.Cu")
	)
	(gr_line
		(start 113.668048 -281.861514)
		(end 113.67262 -281.864308)
		(stroke
			(width 0.05715)
			(type default)
		)
		(layer "In11.Cu")
	)
	(gr_line
		(start 113.671604 -285.103824)
		(end 113.671858 -285.103824)
		(stroke
			(width 0.05715)
			(type default)
		)
		(layer "In11.Cu")
	)
	(gr_line
		(start 113.671604 -279.26919)
		(end 113.67008 -279.270206)
		(stroke
			(width 0.05715)
			(type default)
		)
		(layer "In11.Cu")
	)
	(gr_line
		(start 113.671858 -284.128972)
		(end 113.671604 -284.129226)
		(stroke
			(width 0.05715)
			(type default)
		)
		(layer "In11.Cu")
	)
	(gr_line
		(start 113.671858 -282.50896)
		(end 113.668048 -282.511246)
		(stroke
			(width 0.05715)
			(type default)
		)
		(layer "In11.Cu")
	)
	(gr_line
		(start 113.671858 -280.888948)
		(end 113.668048 -280.891234)
		(stroke
			(width 0.05715)
			(type default)
		)
		(layer "In11.Cu")
	)
	(gr_line
		(start 113.671858 -277.648924)
		(end 113.671604 -277.649178)
		(stroke
			(width 0.05715)
			(type default)
		)
		(layer "In11.Cu")
	)
	(gr_line
		(start 113.67262 -283.48432)
		(end 113.673128 -283.484574)
		(stroke
			(width 0.05715)
			(type default)
		)
		(layer "In11.Cu")
	)
	(gr_line
		(start 113.67262 -281.864308)
		(end 113.673128 -281.864562)
		(stroke
			(width 0.05715)
			(type default)
		)
		(layer "In11.Cu")
	)
	(gr_line
		(start 113.672874 -282.508452)
		(end 113.671858 -282.50896)
		(stroke
			(width 0.05715)
			(type default)
		)
		(layer "In11.Cu")
	)
	(gr_line
		(start 113.672874 -280.88844)
		(end 113.671858 -280.888948)
		(stroke
			(width 0.05715)
			(type default)
		)
		(layer "In11.Cu")
	)
	(gr_line
		(start 113.686082 -288.980118)
		(end 113.683034 -288.98215)
		(stroke
			(width 0.05715)
			(type default)
		)
		(layer "In11.Cu")
	)
	(gr_line
		(start 113.76533 -293.037514)
		(end 113.770664 -293.040562)
		(stroke
			(width 0.05715)
			(type default)
		)
		(layer "In11.Cu")
	)
	(gr_line
		(start 113.766346 -288.177986)
		(end 113.769394 -288.179764)
		(stroke
			(width 0.05715)
			(type default)
		)
		(layer "In11.Cu")
	)
	(gr_line
		(start 113.766854 -292.394132)
		(end 113.76533 -292.394894)
		(stroke
			(width 0.05715)
			(type default)
		)
		(layer "In11.Cu")
	)
	(gr_line
		(start 113.768632 -284.29331)
		(end 113.76787 -284.293818)
		(stroke
			(width 0.05715)
			(type default)
		)
		(layer "In11.Cu")
	)
	(gr_line
		(start 113.770664 -293.040562)
		(end 113.771426 -293.04107)
		(stroke
			(width 0.05715)
			(type default)
		)
		(layer "In11.Cu")
	)
	(gr_line
		(start 113.772188 -289.15106)
		(end 113.767616 -289.1536)
		(stroke
			(width 0.05715)
			(type default)
		)
		(layer "In11.Cu")
	)
	(gr_line
		(start 113.787174 -289.141662)
		(end 113.786666 -289.141916)
		(stroke
			(width 0.05715)
			(type default)
		)
		(layer "In11.Cu")
	)
	(gr_line
		(start 113.798096 -283.336746)
		(end 113.805208 -283.34081)
		(stroke
			(width 0.05715)
			(type default)
		)
		(layer "In11.Cu")
	)
	(gr_line
		(start 113.798096 -281.716734)
		(end 113.805208 -281.720798)
		(stroke
			(width 0.05715)
			(type default)
		)
		(layer "In11.Cu")
	)
	(gr_line
		(start 113.79835 -284.956758)
		(end 113.805208 -284.960822)
		(stroke
			(width 0.05715)
			(type default)
		)
		(layer "In11.Cu")
	)
	(gr_line
		(start 113.798858 -293.057072)
		(end 113.80597 -293.061136)
		(stroke
			(width 0.05715)
			(type default)
		)
		(layer "In11.Cu")
	)
	(gr_arc
		(start 113.80597 -293.061136)
		(mid 113.806351 -293.06139)
		(end 113.806732 -293.061644)
		(stroke
			(width 0.05715)
			(type default)
		)
		(layer "In11.Cu")
	)
	(gr_arc
		(start 113.806732 -284.961838)
		(mid 113.80597 -284.961329)
		(end 113.805208 -284.960822)
		(stroke
			(width 0.05715)
			(type default)
		)
		(layer "In11.Cu")
	)
	(gr_arc
		(start 113.806732 -283.341826)
		(mid 113.80597 -283.341317)
		(end 113.805208 -283.34081)
		(stroke
			(width 0.05715)
			(type default)
		)
		(layer "In11.Cu")
	)
	(gr_arc
		(start 113.806732 -281.721814)
		(mid 113.80597 -281.721305)
		(end 113.805208 -281.720798)
		(stroke
			(width 0.05715)
			(type default)
		)
		(layer "In11.Cu")
	)
	(gr_arc
		(start 113.813082 -284.96641)
		(mid 113.809915 -284.964113)
		(end 113.806732 -284.961838)
		(stroke
			(width 0.05715)
			(type default)
		)
		(layer "In11.Cu")
	)
	(gr_arc
		(start 113.813082 -283.346398)
		(mid 113.809915 -283.344101)
		(end 113.806732 -283.341826)
		(stroke
			(width 0.05715)
			(type default)
		)
		(layer "In11.Cu")
	)
	(gr_arc
		(start 113.813082 -281.726386)
		(mid 113.809915 -281.724089)
		(end 113.806732 -281.721814)
		(stroke
			(width 0.05715)
			(type default)
		)
		(layer "In11.Cu")
	)
	(gr_arc
		(start 113.814606 -293.067232)
		(mid 113.810681 -293.064421)
		(end 113.806732 -293.061644)
		(stroke
			(width 0.05715)
			(type default)
		)
		(layer "In11.Cu")
	)
	(gr_line
		(start 114.12982 -276.845522)
		(end 114.128042 -276.846538)
		(stroke
			(width 0.05715)
			(type default)
		)
		(layer "In11.Cu")
	)
	(gr_line
		(start 114.132614 -276.844252)
		(end 114.131344 -276.84476)
		(stroke
			(width 0.05715)
			(type default)
		)
		(layer "In11.Cu")
	)
	(gr_line
		(start 114.134646 -276.842982)
		(end 114.134138 -276.843236)
		(stroke
			(width 0.05715)
			(type default)
		)
		(layer "In11.Cu")
	)
	(gr_line
		(start 114.136678 -276.841966)
		(end 114.135916 -276.84222)
		(stroke
			(width 0.05715)
			(type default)
		)
		(layer "In11.Cu")
	)
	(gr_line
		(start 114.139726 -276.840188)
		(end 114.139218 -276.840442)
		(stroke
			(width 0.05715)
			(type default)
		)
		(layer "In11.Cu")
	)
	(gr_line
		(start 114.14379 -276.837648)
		(end 114.14252 -276.83841)
		(stroke
			(width 0.05715)
			(type default)
		)
		(layer "In11.Cu")
	)
	(gr_line
		(start 114.156744 -278.450294)
		(end 114.154712 -278.451564)
		(stroke
			(width 0.05715)
			(type default)
		)
		(layer "In11.Cu")
	)
	(gr_line
		(start 114.22888 -277.008844)
		(end 114.228118 -277.009352)
		(stroke
			(width 0.05715)
			(type default)
		)
		(layer "In11.Cu")
	)
	(gr_line
		(start 114.232182 -277.007066)
		(end 114.230912 -277.007828)
		(stroke
			(width 0.05715)
			(type default)
		)
		(layer "In11.Cu")
	)
	(gr_line
		(start 114.232944 -277.006558)
		(end 114.232182 -277.007066)
		(stroke
			(width 0.05715)
			(type default)
		)
		(layer "In11.Cu")
	)
	(gr_line
		(start 114.234214 -277.005796)
		(end 114.232944 -277.006558)
		(stroke
			(width 0.05715)
			(type default)
		)
		(layer "In11.Cu")
	)
	(gr_line
		(start 114.23523 -277.005288)
		(end 114.234214 -277.005796)
		(stroke
			(width 0.05715)
			(type default)
		)
		(layer "In11.Cu")
	)
	(gr_line
		(start 114.237008 -277.004272)
		(end 114.2365 -277.004526)
		(stroke
			(width 0.05715)
			(type default)
		)
		(layer "In11.Cu")
	)
	(gr_line
		(start 114.237516 -277.004018)
		(end 114.237008 -277.004272)
		(stroke
			(width 0.05715)
			(type default)
		)
		(layer "In11.Cu")
	)
	(gr_line
		(start 114.252756 -278.61514)
		(end 114.252756 -278.615394)
		(stroke
			(width 0.05715)
			(type default)
		)
		(layer "In11.Cu")
	)
	(gr_line
		(start 114.283744 -296.418762)
		(end 114.283744 -296.44721)
		(stroke
			(width 0.05715)
			(type default)
		)
		(layer "In11.Cu")
	)
	(gr_line
		(start 114.329464 -296.373042)
		(end 114.283744 -296.418762)
		(stroke
			(width 0.05715)
			(type default)
		)
		(layer "In11.Cu")
	)
	(gr_line
		(start 114.424714 -278.946356)
		(end 114.722656 -278.946356)
		(stroke
			(width 0.05715)
			(type default)
		)
		(layer "In11.Cu")
	)
	(gr_line
		(start 114.424714 -277.326344)
		(end 114.722656 -277.326344)
		(stroke
			(width 0.05715)
			(type default)
		)
		(layer "In11.Cu")
	)
	(gr_line
		(start 114.424714 -275.706332)
		(end 114.722656 -275.706332)
		(stroke
			(width 0.05715)
			(type default)
		)
		(layer "In11.Cu")
	)
	(gr_line
		(start 114.519964 -296.373042)
		(end 114.565684 -296.418762)
		(stroke
			(width 0.05715)
			(type default)
		)
		(layer "In11.Cu")
	)
	(gr_arc
		(start 114.564668 -293.175182)
		(mid 114.568593 -293.177993)
		(end 114.572542 -293.18077)
		(stroke
			(width 0.05715)
			(type default)
		)
		(layer "In11.Cu")
	)
	(gr_line
		(start 114.565684 -296.418762)
		(end 114.565684 -296.44721)
		(stroke
			(width 0.05715)
			(type default)
		)
		(layer "In11.Cu")
	)
	(gr_line
		(start 114.572542 -293.18077)
		(end 114.5794 -293.184834)
		(stroke
			(width 0.05715)
			(type default)
		)
		(layer "In11.Cu")
	)
	(gr_line
		(start 114.5794 -293.184834)
		(end 114.580162 -293.185342)
		(stroke
			(width 0.05715)
			(type default)
		)
		(layer "In11.Cu")
	)
	(gr_line
		(start 114.580162 -293.185342)
		(end 114.580924 -293.18585)
		(stroke
			(width 0.05715)
			(type default)
		)
		(layer "In11.Cu")
	)
	(gr_line
		(start 114.59591 -293.845996)
		(end 114.594132 -293.847012)
		(stroke
			(width 0.05715)
			(type default)
		)
		(layer "In11.Cu")
	)
	(gr_arc
		(start 114.600228 -280.895552)
		(mid 114.600609 -280.895298)
		(end 114.60099 -280.895044)
		(stroke
			(width 0.05715)
			(type default)
		)
		(layer "In11.Cu")
	)
	(gr_arc
		(start 114.60099 -281.857704)
		(mid 114.600609 -281.85745)
		(end 114.600228 -281.857196)
		(stroke
			(width 0.05715)
			(type default)
		)
		(layer "In11.Cu")
	)
	(gr_arc
		(start 114.602768 -285.098744)
		(mid 114.604291 -285.099635)
		(end 114.605816 -285.100522)
		(stroke
			(width 0.05715)
			(type default)
		)
		(layer "In11.Cu")
	)
	(gr_arc
		(start 114.602768 -280.238708)
		(mid 114.603657 -280.239217)
		(end 114.604546 -280.239724)
		(stroke
			(width 0.05715)
			(type default)
		)
		(layer "In11.Cu")
	)
	(gr_arc
		(start 114.604292 -293.840662)
		(mid 114.600089 -293.84331)
		(end 114.59591 -293.845996)
		(stroke
			(width 0.05715)
			(type default)
		)
		(layer "In11.Cu")
	)
	(gr_line
		(start 114.604546 -283.479748)
		(end 114.606832 -283.481018)
		(stroke
			(width 0.05715)
			(type default)
		)
		(layer "In11.Cu")
	)
	(gr_line
		(start 114.605308 -293.8399)
		(end 114.604292 -293.840662)
		(stroke
			(width 0.05715)
			(type default)
		)
		(layer "In11.Cu")
	)
	(gr_arc
		(start 114.605562 -284.132274)
		(mid 114.604164 -284.133161)
		(end 114.602768 -284.134052)
		(stroke
			(width 0.05715)
			(type default)
		)
		(layer "In11.Cu")
	)
	(gr_arc
		(start 114.605562 -279.272238)
		(mid 114.604164 -279.273125)
		(end 114.602768 -279.274016)
		(stroke
			(width 0.05715)
			(type default)
		)
		(layer "In11.Cu")
	)
	(gr_line
		(start 114.60734 -292.231318)
		(end 114.605308 -292.232588)
		(stroke
			(width 0.05715)
			(type default)
		)
		(layer "In11.Cu")
	)
	(gr_arc
		(start 114.609372 -285.750254)
		(mid 114.608483 -285.750761)
		(end 114.607594 -285.75127)
		(stroke
			(width 0.05715)
			(type default)
		)
		(layer "In11.Cu")
	)
	(gr_line
		(start 114.609372 -285.75)
		(end 114.609372 -285.750254)
		(stroke
			(width 0.05715)
			(type default)
		)
		(layer "In11.Cu")
	)
	(gr_line
		(start 114.610134 -285.749492)
		(end 114.609372 -285.75)
		(stroke
			(width 0.05715)
			(type default)
		)
		(layer "In11.Cu")
	)
	(gr_line
		(start 114.610642 -292.229286)
		(end 114.609118 -292.230302)
		(stroke
			(width 0.05715)
			(type default)
		)
		(layer "In11.Cu")
	)
	(gr_line
		(start 114.611404 -292.228778)
		(end 114.610642 -292.229286)
		(stroke
			(width 0.05715)
			(type default)
		)
		(layer "In11.Cu")
	)
	(gr_line
		(start 114.611912 -293.203884)
		(end 114.61242 -293.204138)
		(stroke
			(width 0.05715)
			(type default)
		)
		(layer "In11.Cu")
	)
	(gr_line
		(start 114.611912 -288.343594)
		(end 114.611658 -288.343848)
		(stroke
			(width 0.05715)
			(type default)
		)
		(layer "In11.Cu")
	)
	(gr_line
		(start 114.61242 -293.204138)
		(end 114.612928 -293.204392)
		(stroke
			(width 0.05715)
			(type default)
		)
		(layer "In11.Cu")
	)
	(gr_line
		(start 114.614198 -283.485336)
		(end 114.615214 -283.485844)
		(stroke
			(width 0.05715)
			(type default)
		)
		(layer "In11.Cu")
	)
	(gr_line
		(start 114.614452 -280.245312)
		(end 114.616484 -280.246582)
		(stroke
			(width 0.05715)
			(type default)
		)
		(layer "In11.Cu")
	)
	(gr_line
		(start 114.615214 -293.205662)
		(end 114.615976 -293.20617)
		(stroke
			(width 0.05715)
			(type default)
		)
		(layer "In11.Cu")
	)
	(gr_line
		(start 114.615976 -293.20617)
		(end 114.6175 -293.206932)
		(stroke
			(width 0.05715)
			(type default)
		)
		(layer "In11.Cu")
	)
	(gr_line
		(start 114.6175 -293.206932)
		(end 114.618262 -293.20744)
		(stroke
			(width 0.05715)
			(type default)
		)
		(layer "In11.Cu")
	)
	(gr_line
		(start 114.618262 -293.20744)
		(end 114.619278 -293.207948)
		(stroke
			(width 0.05715)
			(type default)
		)
		(layer "In11.Cu")
	)
	(gr_line
		(start 114.619278 -293.207948)
		(end 114.620294 -293.208456)
		(stroke
			(width 0.05715)
			(type default)
		)
		(layer "In11.Cu")
	)
	(gr_line
		(start 114.643154 -289.981894)
		(end 114.643408 -289.981894)
		(stroke
			(width 0.05715)
			(type default)
		)
		(layer "In11.Cu")
	)
	(gr_line
		(start 114.702336 -292.396672)
		(end 114.701574 -292.39718)
		(stroke
			(width 0.05715)
			(type default)
		)
		(layer "In11.Cu")
	)
	(gr_line
		(start 114.703352 -292.396164)
		(end 114.702336 -292.396672)
		(stroke
			(width 0.05715)
			(type default)
		)
		(layer "In11.Cu")
	)
	(gr_line
		(start 114.704114 -292.395656)
		(end 114.703352 -292.396164)
		(stroke
			(width 0.05715)
			(type default)
		)
		(layer "In11.Cu")
	)
	(gr_line
		(start 114.705384 -284.937708)
		(end 114.708686 -284.939486)
		(stroke
			(width 0.05715)
			(type default)
		)
		(layer "In11.Cu")
	)
	(gr_line
		(start 114.705384 -280.077672)
		(end 114.709956 -280.080212)
		(stroke
			(width 0.05715)
			(type default)
		)
		(layer "In11.Cu")
	)
	(gr_line
		(start 114.705638 -292.394894)
		(end 114.704114 -292.395656)
		(stroke
			(width 0.05715)
			(type default)
		)
		(layer "In11.Cu")
	)
	(gr_line
		(start 114.706908 -292.394132)
		(end 114.705638 -292.394894)
		(stroke
			(width 0.05715)
			(type default)
		)
		(layer "In11.Cu")
	)
	(gr_line
		(start 114.706908 -284.294326)
		(end 114.705384 -284.295088)
		(stroke
			(width 0.05715)
			(type default)
		)
		(layer "In11.Cu")
	)
	(gr_line
		(start 114.706908 -279.43429)
		(end 114.705384 -279.435052)
		(stroke
			(width 0.05715)
			(type default)
		)
		(layer "In11.Cu")
	)
	(gr_line
		(start 114.707416 -292.393878)
		(end 114.706908 -292.394132)
		(stroke
			(width 0.05715)
			(type default)
		)
		(layer "In11.Cu")
	)
	(gr_line
		(start 114.70767 -293.038784)
		(end 114.708686 -293.039292)
		(stroke
			(width 0.05715)
			(type default)
		)
		(layer "In11.Cu")
	)
	(gr_line
		(start 114.708686 -293.039292)
		(end 114.71021 -293.040308)
		(stroke
			(width 0.05715)
			(type default)
		)
		(layer "In11.Cu")
	)
	(gr_line
		(start 114.71021 -293.040308)
		(end 114.711226 -293.040816)
		(stroke
			(width 0.05715)
			(type default)
		)
		(layer "In11.Cu")
	)
	(gr_line
		(start 114.711226 -293.040816)
		(end 114.713766 -293.04234)
		(stroke
			(width 0.05715)
			(type default)
		)
		(layer "In11.Cu")
	)
	(gr_line
		(start 114.713766 -293.04234)
		(end 114.714782 -293.043102)
		(stroke
			(width 0.05715)
			(type default)
		)
		(layer "In11.Cu")
	)
	(gr_line
		(start 114.722656 -278.946356)
		(end 114.791998 -279.015698)
		(stroke
			(width 0.05715)
			(type default)
		)
		(layer "In11.Cu")
	)
	(gr_line
		(start 114.722656 -277.326344)
		(end 114.791998 -277.395686)
		(stroke
			(width 0.05715)
			(type default)
		)
		(layer "In11.Cu")
	)
	(gr_line
		(start 114.722656 -275.706332)
		(end 114.791998 -275.775674)
		(stroke
			(width 0.05715)
			(type default)
		)
		(layer "In11.Cu")
	)
	(gr_line
		(start 114.736372 -294.67556)
		(end 114.746024 -294.681148)
		(stroke
			(width 0.05715)
			(type default)
		)
		(layer "In11.Cu")
	)
	(gr_line
		(start 114.738404 -281.716988)
		(end 114.746024 -281.721306)
		(stroke
			(width 0.05715)
			(type default)
		)
		(layer "In11.Cu")
	)
	(gr_line
		(start 114.738658 -284.957012)
		(end 114.746024 -284.96133)
		(stroke
			(width 0.05715)
			(type default)
		)
		(layer "In11.Cu")
	)
	(gr_line
		(start 114.738658 -283.337)
		(end 114.73942 -283.337508)
		(stroke
			(width 0.05715)
			(type default)
		)
		(layer "In11.Cu")
	)
	(gr_line
		(start 114.73942 -283.337508)
		(end 114.746024 -283.341318)
		(stroke
			(width 0.05715)
			(type default)
		)
		(layer "In11.Cu")
	)
	(gr_line
		(start 114.741198 -286.578802)
		(end 114.748818 -286.58312)
		(stroke
			(width 0.05715)
			(type default)
		)
		(layer "In11.Cu")
	)
	(gr_arc
		(start 114.746024 -294.681148)
		(mid 114.746405 -294.681402)
		(end 114.746786 -294.681656)
		(stroke
			(width 0.05715)
			(type default)
		)
		(layer "In11.Cu")
	)
	(gr_arc
		(start 114.746024 -284.96133)
		(mid 114.746405 -284.961584)
		(end 114.746786 -284.961838)
		(stroke
			(width 0.05715)
			(type default)
		)
		(layer "In11.Cu")
	)
	(gr_arc
		(start 114.746024 -283.341318)
		(mid 114.746405 -283.341572)
		(end 114.746786 -283.341826)
		(stroke
			(width 0.05715)
			(type default)
		)
		(layer "In11.Cu")
	)
	(gr_arc
		(start 114.746024 -281.721306)
		(mid 114.746405 -281.72156)
		(end 114.746786 -281.721814)
		(stroke
			(width 0.05715)
			(type default)
		)
		(layer "In11.Cu")
	)
	(gr_line
		(start 114.746786 -284.961838)
		(end 114.748818 -284.963108)
		(stroke
			(width 0.05715)
			(type default)
		)
		(layer "In11.Cu")
	)
	(gr_line
		(start 114.748818 -286.58312)
		(end 114.748818 -286.582866)
		(stroke
			(width 0.05715)
			(type default)
		)
		(layer "In11.Cu")
	)
	(gr_arc
		(start 114.748818 -284.963108)
		(mid 114.749199 -284.963362)
		(end 114.74958 -284.963616)
		(stroke
			(width 0.05715)
			(type default)
		)
		(layer "In11.Cu")
	)
	(gr_arc
		(start 114.75466 -294.687244)
		(mid 114.750735 -294.684433)
		(end 114.746786 -294.681656)
		(stroke
			(width 0.05715)
			(type default)
		)
		(layer "In11.Cu")
	)
	(gr_line
		(start 114.75466 -287.50514)
		(end 114.754152 -287.505648)
		(stroke
			(width 0.05715)
			(type default)
		)
		(layer "In11.Cu")
	)
	(gr_arc
		(start 114.75466 -283.347414)
		(mid 114.750735 -283.344603)
		(end 114.746786 -283.341826)
		(stroke
			(width 0.05715)
			(type default)
		)
		(layer "In11.Cu")
	)
	(gr_arc
		(start 114.75466 -281.727402)
		(mid 114.750735 -281.724591)
		(end 114.746786 -281.721814)
		(stroke
			(width 0.05715)
			(type default)
		)
		(layer "In11.Cu")
	)
	(gr_arc
		(start 114.755422 -284.96768)
		(mid 114.752887 -284.965895)
		(end 114.750342 -284.964124)
		(stroke
			(width 0.05715)
			(type default)
		)
		(layer "In11.Cu")
	)
	(gr_arc
		(start 114.757454 -286.588962)
		(mid 114.753151 -286.585893)
		(end 114.748818 -286.582866)
		(stroke
			(width 0.05715)
			(type default)
		)
		(layer "In11.Cu")
	)
	(gr_line
		(start 114.894106 -412.570168)
		(end 115.184936 -412.860998)
		(stroke
			(width 0.07112)
			(type default)
		)
		(layer "In11.Cu")
	)
	(gr_arc
		(start 114.980212 -279.05202)
		(mid 114.982234 -279.040609)
		(end 114.984022 -279.02916)
		(stroke
			(width 0.05715)
			(type default)
		)
		(layer "In11.Cu")
	)
	(gr_arc
		(start 114.980212 -277.432008)
		(mid 114.982233 -277.420597)
		(end 114.984022 -277.409148)
		(stroke
			(width 0.05715)
			(type default)
		)
		(layer "In11.Cu")
	)
	(gr_arc
		(start 114.980212 -275.811996)
		(mid 114.982233 -275.800585)
		(end 114.984022 -275.789136)
		(stroke
			(width 0.05715)
			(type default)
		)
		(layer "In11.Cu")
	)
	(gr_line
		(start 115.066826 -278.946356)
		(end 114.984022 -279.02916)
		(stroke
			(width 0.05715)
			(type default)
		)
		(layer "In11.Cu")
	)
	(gr_line
		(start 115.066826 -277.326344)
		(end 114.984022 -277.409148)
		(stroke
			(width 0.05715)
			(type default)
		)
		(layer "In11.Cu")
	)
	(gr_line
		(start 115.066826 -275.706332)
		(end 114.984022 -275.789136)
		(stroke
			(width 0.05715)
			(type default)
		)
		(layer "In11.Cu")
	)
	(gr_line
		(start 115.184936 -413.895794)
		(end 115.184936 -413.895032)
		(stroke
			(width 0.07112)
			(type default)
		)
		(layer "In11.Cu")
	)
	(gr_line
		(start 115.22329 -296.788586)
		(end 115.22329 -296.789094)
		(stroke
			(width 0.07112)
			(type default)
		)
		(layer "In11.Cu")
	)
	(gr_line
		(start 115.223798 -296.418762)
		(end 115.223798 -296.44721)
		(stroke
			(width 0.05715)
			(type default)
		)
		(layer "In11.Cu")
	)
	(gr_line
		(start 115.269518 -296.373042)
		(end 115.223798 -296.418762)
		(stroke
			(width 0.05715)
			(type default)
		)
		(layer "In11.Cu")
	)
	(gr_line
		(start 115.364768 -278.946356)
		(end 115.066826 -278.946356)
		(stroke
			(width 0.05715)
			(type default)
		)
		(layer "In11.Cu")
	)
	(gr_line
		(start 115.364768 -277.326344)
		(end 115.066826 -277.326344)
		(stroke
			(width 0.05715)
			(type default)
		)
		(layer "In11.Cu")
	)
	(gr_line
		(start 115.364768 -275.706332)
		(end 115.066826 -275.706332)
		(stroke
			(width 0.05715)
			(type default)
		)
		(layer "In11.Cu")
	)
	(gr_line
		(start 115.460018 -296.373042)
		(end 115.505738 -296.418762)
		(stroke
			(width 0.05715)
			(type default)
		)
		(layer "In11.Cu")
	)
	(gr_line
		(start 115.464082 -373.719344)
		(end 115.220496 -373.96293)
		(stroke
			(width 0.07112)
			(type default)
		)
		(layer "In11.Cu")
	)
	(gr_arc
		(start 115.464082 -373.719344)
		(mid 115.495515 -373.67493)
		(end 115.51031 -373.62257)
		(stroke
			(width 0.07112)
			(type default)
		)
		(layer "In11.Cu")
	)
	(gr_arc
		(start 115.504722 -294.795194)
		(mid 115.508647 -294.798005)
		(end 115.512596 -294.800782)
		(stroke
			(width 0.05715)
			(type default)
		)
		(layer "In11.Cu")
	)
	(gr_arc
		(start 115.504722 -293.175182)
		(mid 115.508647 -293.177993)
		(end 115.512596 -293.18077)
		(stroke
			(width 0.05715)
			(type default)
		)
		(layer "In11.Cu")
	)
	(gr_arc
		(start 115.504722 -291.55517)
		(mid 115.508647 -291.557981)
		(end 115.512596 -291.560758)
		(stroke
			(width 0.05715)
			(type default)
		)
		(layer "In11.Cu")
	)
	(gr_arc
		(start 115.504722 -285.075376)
		(mid 115.508647 -285.078187)
		(end 115.512596 -285.080964)
		(stroke
			(width 0.05715)
			(type default)
		)
		(layer "In11.Cu")
	)
	(gr_arc
		(start 115.504722 -283.455364)
		(mid 115.508647 -283.458175)
		(end 115.512596 -283.460952)
		(stroke
			(width 0.05715)
			(type default)
		)
		(layer "In11.Cu")
	)
	(gr_arc
		(start 115.504722 -281.835352)
		(mid 115.508647 -281.838163)
		(end 115.512596 -281.84094)
		(stroke
			(width 0.05715)
			(type default)
		)
		(layer "In11.Cu")
	)
	(gr_line
		(start 115.505738 -296.774362)
		(end 115.505738 -296.77487)
		(stroke
			(width 0.07112)
			(type default)
		)
		(layer "In11.Cu")
	)
	(gr_line
		(start 115.505738 -296.418762)
		(end 115.505738 -296.44721)
		(stroke
			(width 0.05715)
			(type default)
		)
		(layer "In11.Cu")
	)
	(gr_line
		(start 115.512596 -294.800782)
		(end 115.519454 -294.804846)
		(stroke
			(width 0.05715)
			(type default)
		)
		(layer "In11.Cu")
	)
	(gr_line
		(start 115.512596 -293.18077)
		(end 115.519454 -293.184834)
		(stroke
			(width 0.05715)
			(type default)
		)
		(layer "In11.Cu")
	)
	(gr_line
		(start 115.512596 -291.560758)
		(end 115.519454 -291.564822)
		(stroke
			(width 0.05715)
			(type default)
		)
		(layer "In11.Cu")
	)
	(gr_line
		(start 115.512596 -285.080964)
		(end 115.519454 -285.085028)
		(stroke
			(width 0.05715)
			(type default)
		)
		(layer "In11.Cu")
	)
	(gr_line
		(start 115.512596 -283.460952)
		(end 115.519454 -283.465016)
		(stroke
			(width 0.05715)
			(type default)
		)
		(layer "In11.Cu")
	)
	(gr_line
		(start 115.512596 -281.84094)
		(end 115.519454 -281.845004)
		(stroke
			(width 0.05715)
			(type default)
		)
		(layer "In11.Cu")
	)
	(gr_line
		(start 115.519454 -294.804846)
		(end 115.520216 -294.805354)
		(stroke
			(width 0.05715)
			(type default)
		)
		(layer "In11.Cu")
	)
	(gr_line
		(start 115.519454 -293.184834)
		(end 115.520216 -293.185342)
		(stroke
			(width 0.05715)
			(type default)
		)
		(layer "In11.Cu")
	)
	(gr_line
		(start 115.519454 -291.564822)
		(end 115.520216 -291.56533)
		(stroke
			(width 0.05715)
			(type default)
		)
		(layer "In11.Cu")
	)
	(gr_line
		(start 115.519454 -285.085028)
		(end 115.520216 -285.085536)
		(stroke
			(width 0.05715)
			(type default)
		)
		(layer "In11.Cu")
	)
	(gr_line
		(start 115.519454 -283.465016)
		(end 115.520216 -283.465524)
		(stroke
			(width 0.05715)
			(type default)
		)
		(layer "In11.Cu")
	)
	(gr_line
		(start 115.519454 -281.845004)
		(end 115.520216 -281.845512)
		(stroke
			(width 0.05715)
			(type default)
		)
		(layer "In11.Cu")
	)
	(gr_line
		(start 115.520216 -294.805354)
		(end 115.520978 -294.805862)
		(stroke
			(width 0.05715)
			(type default)
		)
		(layer "In11.Cu")
	)
	(gr_line
		(start 115.520216 -293.185342)
		(end 115.520978 -293.18585)
		(stroke
			(width 0.05715)
			(type default)
		)
		(layer "In11.Cu")
	)
	(gr_line
		(start 115.520216 -291.56533)
		(end 115.520978 -291.565838)
		(stroke
			(width 0.05715)
			(type default)
		)
		(layer "In11.Cu")
	)
	(gr_line
		(start 115.520216 -285.085536)
		(end 115.520978 -285.086044)
		(stroke
			(width 0.05715)
			(type default)
		)
		(layer "In11.Cu")
	)
	(gr_line
		(start 115.520216 -283.465524)
		(end 115.520978 -283.466032)
		(stroke
			(width 0.05715)
			(type default)
		)
		(layer "In11.Cu")
	)
	(gr_line
		(start 115.520216 -281.845512)
		(end 115.520978 -281.84602)
		(stroke
			(width 0.05715)
			(type default)
		)
		(layer "In11.Cu")
	)
	(gr_line
		(start 115.551458 -293.84879)
		(end 115.550696 -293.849298)
		(stroke
			(width 0.05715)
			(type default)
		)
		(layer "In11.Cu")
	)
	(gr_line
		(start 115.551458 -292.228778)
		(end 115.550696 -292.229286)
		(stroke
			(width 0.05715)
			(type default)
		)
		(layer "In11.Cu")
	)
	(gr_line
		(start 115.551458 -290.608766)
		(end 115.550696 -290.609274)
		(stroke
			(width 0.05715)
			(type default)
		)
		(layer "In11.Cu")
	)
	(gr_line
		(start 115.551458 -288.988754)
		(end 115.550696 -288.989262)
		(stroke
			(width 0.05715)
			(type default)
		)
		(layer "In11.Cu")
	)
	(gr_line
		(start 115.551458 -285.748984)
		(end 115.550696 -285.749492)
		(stroke
			(width 0.05715)
			(type default)
		)
		(layer "In11.Cu")
	)
	(gr_line
		(start 115.551458 -284.128972)
		(end 115.550696 -284.12948)
		(stroke
			(width 0.05715)
			(type default)
		)
		(layer "In11.Cu")
	)
	(gr_line
		(start 115.551458 -282.50896)
		(end 115.550696 -282.509468)
		(stroke
			(width 0.05715)
			(type default)
		)
		(layer "In11.Cu")
	)
	(gr_line
		(start 115.551458 -280.888948)
		(end 115.550696 -280.889456)
		(stroke
			(width 0.05715)
			(type default)
		)
		(layer "In11.Cu")
	)
	(gr_line
		(start 115.551966 -294.823896)
		(end 115.552474 -294.82415)
		(stroke
			(width 0.05715)
			(type default)
		)
		(layer "In11.Cu")
	)
	(gr_line
		(start 115.551966 -293.203884)
		(end 115.552474 -293.204138)
		(stroke
			(width 0.05715)
			(type default)
		)
		(layer "In11.Cu")
	)
	(gr_line
		(start 115.551966 -291.583872)
		(end 115.552474 -291.584126)
		(stroke
			(width 0.05715)
			(type default)
		)
		(layer "In11.Cu")
	)
	(gr_line
		(start 115.551966 -285.104078)
		(end 115.552474 -285.104332)
		(stroke
			(width 0.05715)
			(type default)
		)
		(layer "In11.Cu")
	)
	(gr_line
		(start 115.551966 -283.484066)
		(end 115.552474 -283.48432)
		(stroke
			(width 0.05715)
			(type default)
		)
		(layer "In11.Cu")
	)
	(gr_line
		(start 115.551966 -281.864054)
		(end 115.552474 -281.864308)
		(stroke
			(width 0.05715)
			(type default)
		)
		(layer "In11.Cu")
	)
	(gr_line
		(start 115.552474 -294.82415)
		(end 115.553744 -294.824912)
		(stroke
			(width 0.05715)
			(type default)
		)
		(layer "In11.Cu")
	)
	(gr_line
		(start 115.552474 -293.204138)
		(end 115.553744 -293.2049)
		(stroke
			(width 0.05715)
			(type default)
		)
		(layer "In11.Cu")
	)
	(gr_line
		(start 115.552474 -291.584126)
		(end 115.553744 -291.584888)
		(stroke
			(width 0.05715)
			(type default)
		)
		(layer "In11.Cu")
	)
	(gr_line
		(start 115.552474 -289.964114)
		(end 115.553744 -289.964876)
		(stroke
			(width 0.05715)
			(type default)
		)
		(layer "In11.Cu")
	)
	(gr_line
		(start 115.552474 -285.104332)
		(end 115.553744 -285.105094)
		(stroke
			(width 0.05715)
			(type default)
		)
		(layer "In11.Cu")
	)
	(gr_line
		(start 115.552474 -283.48432)
		(end 115.553744 -283.485082)
		(stroke
			(width 0.05715)
			(type default)
		)
		(layer "In11.Cu")
	)
	(gr_line
		(start 115.552474 -281.864308)
		(end 115.553744 -281.86507)
		(stroke
			(width 0.05715)
			(type default)
		)
		(layer "In11.Cu")
	)
	(gr_line
		(start 115.646962 -294.014144)
		(end 115.645692 -294.014906)
		(stroke
			(width 0.05715)
			(type default)
		)
		(layer "In11.Cu")
	)
	(gr_line
		(start 115.646962 -292.394132)
		(end 115.645692 -292.394894)
		(stroke
			(width 0.05715)
			(type default)
		)
		(layer "In11.Cu")
	)
	(gr_line
		(start 115.646962 -290.77412)
		(end 115.645692 -290.774882)
		(stroke
			(width 0.05715)
			(type default)
		)
		(layer "In11.Cu")
	)
	(gr_line
		(start 115.646962 -289.154108)
		(end 115.645692 -289.15487)
		(stroke
			(width 0.05715)
			(type default)
		)
		(layer "In11.Cu")
	)
	(gr_line
		(start 115.646962 -285.914338)
		(end 115.645692 -285.9151)
		(stroke
			(width 0.05715)
			(type default)
		)
		(layer "In11.Cu")
	)
	(gr_line
		(start 115.646962 -284.294326)
		(end 115.645692 -284.295088)
		(stroke
			(width 0.05715)
			(type default)
		)
		(layer "In11.Cu")
	)
	(gr_line
		(start 115.646962 -282.674314)
		(end 115.645692 -282.675076)
		(stroke
			(width 0.05715)
			(type default)
		)
		(layer "In11.Cu")
	)
	(gr_line
		(start 115.646962 -281.054302)
		(end 115.645692 -281.055064)
		(stroke
			(width 0.05715)
			(type default)
		)
		(layer "In11.Cu")
	)
	(gr_line
		(start 115.647216 -289.798506)
		(end 115.647724 -289.79876)
		(stroke
			(width 0.05715)
			(type default)
		)
		(layer "In11.Cu")
	)
	(gr_line
		(start 115.64747 -294.01389)
		(end 115.646962 -294.014144)
		(stroke
			(width 0.05715)
			(type default)
		)
		(layer "In11.Cu")
	)
	(gr_line
		(start 115.64747 -292.393878)
		(end 115.646962 -292.394132)
		(stroke
			(width 0.05715)
			(type default)
		)
		(layer "In11.Cu")
	)
	(gr_line
		(start 115.64747 -290.773866)
		(end 115.646962 -290.77412)
		(stroke
			(width 0.05715)
			(type default)
		)
		(layer "In11.Cu")
	)
	(gr_line
		(start 115.64747 -289.153854)
		(end 115.646962 -289.154108)
		(stroke
			(width 0.05715)
			(type default)
		)
		(layer "In11.Cu")
	)
	(gr_line
		(start 115.64747 -285.914084)
		(end 115.646962 -285.914338)
		(stroke
			(width 0.05715)
			(type default)
		)
		(layer "In11.Cu")
	)
	(gr_line
		(start 115.64747 -284.294072)
		(end 115.646962 -284.294326)
		(stroke
			(width 0.05715)
			(type default)
		)
		(layer "In11.Cu")
	)
	(gr_line
		(start 115.64747 -282.67406)
		(end 115.646962 -282.674314)
		(stroke
			(width 0.05715)
			(type default)
		)
		(layer "In11.Cu")
	)
	(gr_line
		(start 115.64747 -281.054048)
		(end 115.646962 -281.054302)
		(stroke
			(width 0.05715)
			(type default)
		)
		(layer "In11.Cu")
	)
	(gr_line
		(start 115.647724 -294.658796)
		(end 115.64874 -294.659304)
		(stroke
			(width 0.05715)
			(type default)
		)
		(layer "In11.Cu")
	)
	(gr_line
		(start 115.647724 -293.038784)
		(end 115.64874 -293.039292)
		(stroke
			(width 0.05715)
			(type default)
		)
		(layer "In11.Cu")
	)
	(gr_line
		(start 115.647724 -291.418772)
		(end 115.64874 -291.41928)
		(stroke
			(width 0.05715)
			(type default)
		)
		(layer "In11.Cu")
	)
	(gr_line
		(start 115.647724 -289.79876)
		(end 115.64874 -289.799268)
		(stroke
			(width 0.05715)
			(type default)
		)
		(layer "In11.Cu")
	)
	(gr_line
		(start 115.647724 -284.938978)
		(end 115.64874 -284.939486)
		(stroke
			(width 0.05715)
			(type default)
		)
		(layer "In11.Cu")
	)
	(gr_line
		(start 115.647724 -283.318966)
		(end 115.64874 -283.319474)
		(stroke
			(width 0.05715)
			(type default)
		)
		(layer "In11.Cu")
	)
	(gr_line
		(start 115.647724 -281.698954)
		(end 115.64874 -281.699462)
		(stroke
			(width 0.05715)
			(type default)
		)
		(layer "In11.Cu")
	)
	(gr_line
		(start 115.757706 -412.570168)
		(end 115.466876 -412.860998)
		(stroke
			(width 0.07112)
			(type default)
		)
		(layer "In11.Cu")
	)
	(gr_arc
		(start 115.794282 -373.62257)
		(mid 115.809136 -373.674904)
		(end 115.84051 -373.719344)
		(stroke
			(width 0.07112)
			(type default)
		)
		(layer "In11.Cu")
	)
	(gr_line
		(start 115.84051 -373.719344)
		(end 116.084096 -373.96293)
		(stroke
			(width 0.07112)
			(type default)
		)
		(layer "In11.Cu")
	)
	(gr_line
		(start 116.017548 -277.810976)
		(end 116.021358 -277.813516)
		(stroke
			(width 0.05715)
			(type default)
		)
		(layer "In11.Cu")
	)
	(gr_line
		(start 116.163852 -296.418762)
		(end 116.163852 -296.44721)
		(stroke
			(width 0.05715)
			(type default)
		)
		(layer "In11.Cu")
	)
	(gr_line
		(start 116.209572 -296.373042)
		(end 116.163852 -296.418762)
		(stroke
			(width 0.05715)
			(type default)
		)
		(layer "In11.Cu")
	)
	(gr_line
		(start 116.211858 -276.509734)
		(end 116.211604 -276.50948)
		(stroke
			(width 0.05715)
			(type default)
		)
		(layer "In11.Cu")
	)
	(gr_line
		(start 116.381276 -415.059622)
		(end 116.92636 -415.501328)
		(stroke
			(width 0.07112)
			(type default)
		)
		(layer "In11.Cu")
	)
	(gr_line
		(start 116.400072 -296.373042)
		(end 116.445792 -296.418762)
		(stroke
			(width 0.05715)
			(type default)
		)
		(layer "In11.Cu")
	)
	(gr_line
		(start 116.400072 -295.95572)
		(end 116.400072 -295.956228)
		(stroke
			(width 0.05715)
			(type default)
		)
		(layer "In11.Cu")
	)
	(gr_arc
		(start 116.444776 -293.175182)
		(mid 116.448701 -293.177993)
		(end 116.45265 -293.18077)
		(stroke
			(width 0.05715)
			(type default)
		)
		(layer "In11.Cu")
	)
	(gr_arc
		(start 116.444776 -291.55517)
		(mid 116.448701 -291.557981)
		(end 116.45265 -291.560758)
		(stroke
			(width 0.05715)
			(type default)
		)
		(layer "In11.Cu")
	)
	(gr_arc
		(start 116.444776 -289.935158)
		(mid 116.448701 -289.937969)
		(end 116.45265 -289.940746)
		(stroke
			(width 0.05715)
			(type default)
		)
		(layer "In11.Cu")
	)
	(gr_arc
		(start 116.444776 -281.835352)
		(mid 116.448701 -281.838163)
		(end 116.45265 -281.84094)
		(stroke
			(width 0.05715)
			(type default)
		)
		(layer "In11.Cu")
	)
	(gr_line
		(start 116.445792 -296.418762)
		(end 116.445792 -296.44721)
		(stroke
			(width 0.05715)
			(type default)
		)
		(layer "In11.Cu")
	)
	(gr_line
		(start 116.45265 -293.18077)
		(end 116.459508 -293.184834)
		(stroke
			(width 0.05715)
			(type default)
		)
		(layer "In11.Cu")
	)
	(gr_line
		(start 116.45265 -291.560758)
		(end 116.459508 -291.564822)
		(stroke
			(width 0.05715)
			(type default)
		)
		(layer "In11.Cu")
	)
	(gr_line
		(start 116.45265 -289.940746)
		(end 116.459508 -289.94481)
		(stroke
			(width 0.05715)
			(type default)
		)
		(layer "In11.Cu")
	)
	(gr_line
		(start 116.45265 -281.84094)
		(end 116.459508 -281.845004)
		(stroke
			(width 0.05715)
			(type default)
		)
		(layer "In11.Cu")
	)
	(gr_line
		(start 116.459508 -293.184834)
		(end 116.46027 -293.185342)
		(stroke
			(width 0.05715)
			(type default)
		)
		(layer "In11.Cu")
	)
	(gr_line
		(start 116.459508 -291.564822)
		(end 116.46027 -291.56533)
		(stroke
			(width 0.05715)
			(type default)
		)
		(layer "In11.Cu")
	)
	(gr_line
		(start 116.459508 -289.94481)
		(end 116.46027 -289.945318)
		(stroke
			(width 0.05715)
			(type default)
		)
		(layer "In11.Cu")
	)
	(gr_line
		(start 116.459508 -281.845004)
		(end 116.46027 -281.845512)
		(stroke
			(width 0.05715)
			(type default)
		)
		(layer "In11.Cu")
	)
	(gr_line
		(start 116.46027 -293.185342)
		(end 116.461032 -293.18585)
		(stroke
			(width 0.05715)
			(type default)
		)
		(layer "In11.Cu")
	)
	(gr_line
		(start 116.46027 -291.56533)
		(end 116.461032 -291.565838)
		(stroke
			(width 0.05715)
			(type default)
		)
		(layer "In11.Cu")
	)
	(gr_line
		(start 116.46027 -289.945318)
		(end 116.461032 -289.945826)
		(stroke
			(width 0.05715)
			(type default)
		)
		(layer "In11.Cu")
	)
	(gr_line
		(start 116.46027 -281.845512)
		(end 116.461032 -281.84602)
		(stroke
			(width 0.05715)
			(type default)
		)
		(layer "In11.Cu")
	)
	(gr_line
		(start 116.472462 -282.52039)
		(end 116.4717 -282.520644)
		(stroke
			(width 0.05715)
			(type default)
		)
		(layer "In11.Cu")
	)
	(gr_arc
		(start 116.477796 -285.095696)
		(mid 116.479572 -285.096715)
		(end 116.481352 -285.097728)
		(stroke
			(width 0.05715)
			(type default)
		)
		(layer "In11.Cu")
	)
	(gr_line
		(start 116.488718 -294.823134)
		(end 116.50218 -294.836596)
		(stroke
			(width 0.05715)
			(type default)
		)
		(layer "In11.Cu")
	)
	(gr_line
		(start 116.489226 -293.850314)
		(end 116.487956 -293.851076)
		(stroke
			(width 0.05715)
			(type default)
		)
		(layer "In11.Cu")
	)
	(gr_line
		(start 116.489988 -284.129988)
		(end 116.488464 -284.131004)
		(stroke
			(width 0.05715)
			(type default)
		)
		(layer "In11.Cu")
	)
	(gr_line
		(start 116.490496 -283.48305)
		(end 116.492274 -283.484066)
		(stroke
			(width 0.05715)
			(type default)
		)
		(layer "In11.Cu")
	)
	(gr_line
		(start 116.49075 -293.849298)
		(end 116.489226 -293.850314)
		(stroke
			(width 0.05715)
			(type default)
		)
		(layer "In11.Cu")
	)
	(gr_line
		(start 116.491766 -293.849044)
		(end 116.491766 -293.84879)
		(stroke
			(width 0.05715)
			(type default)
		)
		(layer "In11.Cu")
	)
	(gr_line
		(start 116.491766 -293.84879)
		(end 116.49075 -293.849298)
		(stroke
			(width 0.05715)
			(type default)
		)
		(layer "In11.Cu")
	)
	(gr_line
		(start 116.491766 -292.229032)
		(end 116.491766 -292.228778)
		(stroke
			(width 0.05715)
			(type default)
		)
		(layer "In11.Cu")
	)
	(gr_line
		(start 116.491766 -292.228778)
		(end 116.49075 -292.229286)
		(stroke
			(width 0.05715)
			(type default)
		)
		(layer "In11.Cu")
	)
	(gr_line
		(start 116.491766 -290.60902)
		(end 116.491766 -290.608766)
		(stroke
			(width 0.05715)
			(type default)
		)
		(layer "In11.Cu")
	)
	(gr_line
		(start 116.491766 -290.608766)
		(end 116.49075 -290.609274)
		(stroke
			(width 0.05715)
			(type default)
		)
		(layer "In11.Cu")
	)
	(gr_line
		(start 116.491766 -288.988754)
		(end 116.49075 -288.989262)
		(stroke
			(width 0.05715)
			(type default)
		)
		(layer "In11.Cu")
	)
	(gr_line
		(start 116.491766 -288.343594)
		(end 116.492782 -288.344102)
		(stroke
			(width 0.05715)
			(type default)
		)
		(layer "In11.Cu")
	)
	(gr_line
		(start 116.491766 -286.723328)
		(end 116.492274 -286.723582)
		(stroke
			(width 0.05715)
			(type default)
		)
		(layer "In11.Cu")
	)
	(gr_line
		(start 116.491766 -285.748984)
		(end 116.49075 -285.749492)
		(stroke
			(width 0.05715)
			(type default)
		)
		(layer "In11.Cu")
	)
	(gr_line
		(start 116.491766 -282.50896)
		(end 116.488464 -282.510738)
		(stroke
			(width 0.05715)
			(type default)
		)
		(layer "In11.Cu")
	)
	(gr_line
		(start 116.492274 -293.84879)
		(end 116.491766 -293.849044)
		(stroke
			(width 0.05715)
			(type default)
		)
		(layer "In11.Cu")
	)
	(gr_line
		(start 116.492274 -292.228778)
		(end 116.491766 -292.229032)
		(stroke
			(width 0.05715)
			(type default)
		)
		(layer "In11.Cu")
	)
	(gr_line
		(start 116.492274 -290.608766)
		(end 116.491766 -290.60902)
		(stroke
			(width 0.05715)
			(type default)
		)
		(layer "In11.Cu")
	)
	(gr_line
		(start 116.492274 -283.484066)
		(end 116.493036 -283.484574)
		(stroke
			(width 0.05715)
			(type default)
		)
		(layer "In11.Cu")
	)
	(gr_line
		(start 116.492528 -282.508706)
		(end 116.492528 -282.508452)
		(stroke
			(width 0.05715)
			(type default)
		)
		(layer "In11.Cu")
	)
	(gr_line
		(start 116.493036 -288.988246)
		(end 116.491766 -288.988754)
		(stroke
			(width 0.05715)
			(type default)
		)
		(layer "In11.Cu")
	)
	(gr_line
		(start 116.494052 -284.127956)
		(end 116.49075 -284.12948)
		(stroke
			(width 0.05715)
			(type default)
		)
		(layer "In11.Cu")
	)
	(gr_line
		(start 116.49456 -281.865578)
		(end 116.495068 -281.865578)
		(stroke
			(width 0.05715)
			(type default)
		)
		(layer "In11.Cu")
	)
	(gr_line
		(start 116.495322 -282.507182)
		(end 116.494814 -282.507182)
		(stroke
			(width 0.05715)
			(type default)
		)
		(layer "In11.Cu")
	)
	(gr_line
		(start 116.50218 -294.836596)
		(end 116.509546 -294.836596)
		(stroke
			(width 0.05715)
			(type default)
		)
		(layer "In11.Cu")
	)
	(gr_line
		(start 116.505228 -284.121352)
		(end 116.50472 -284.121606)
		(stroke
			(width 0.05715)
			(type default)
		)
		(layer "In11.Cu")
	)
	(gr_line
		(start 116.50599 -284.120844)
		(end 116.505228 -284.121352)
		(stroke
			(width 0.05715)
			(type default)
		)
		(layer "In11.Cu")
	)
	(gr_line
		(start 116.506752 -284.120336)
		(end 116.50599 -284.120844)
		(stroke
			(width 0.05715)
			(type default)
		)
		(layer "In11.Cu")
	)
	(gr_line
		(start 116.506752 -280.880312)
		(end 116.504466 -280.881582)
		(stroke
			(width 0.05715)
			(type default)
		)
		(layer "In11.Cu")
	)
	(gr_line
		(start 116.509292 -284.118812)
		(end 116.50853 -284.11932)
		(stroke
			(width 0.05715)
			(type default)
		)
		(layer "In11.Cu")
	)
	(gr_line
		(start 116.510054 -284.118304)
		(end 116.509292 -284.118812)
		(stroke
			(width 0.05715)
			(type default)
		)
		(layer "In11.Cu")
	)
	(gr_line
		(start 116.510054 -283.49448)
		(end 116.510308 -283.49448)
		(stroke
			(width 0.05715)
			(type default)
		)
		(layer "In11.Cu")
	)
	(gr_line
		(start 116.510562 -284.118304)
		(end 116.510054 -284.118304)
		(stroke
			(width 0.05715)
			(type default)
		)
		(layer "In11.Cu")
	)
	(gr_line
		(start 116.560346 -414.840166)
		(end 116.752116 -414.820354)
		(stroke
			(width 0.07112)
			(type default)
		)
		(layer "In11.Cu")
	)
	(gr_line
		(start 116.582952 -294.656256)
		(end 116.582444 -294.656002)
		(stroke
			(width 0.05715)
			(type default)
		)
		(layer "In11.Cu")
	)
	(gr_line
		(start 116.582952 -294.656256)
		(end 116.585492 -294.65778)
		(stroke
			(width 0.05715)
			(type default)
		)
		(layer "In11.Cu")
	)
	(gr_line
		(start 116.582952 -288.175954)
		(end 116.587778 -288.178748)
		(stroke
			(width 0.05715)
			(type default)
		)
		(layer "In11.Cu")
	)
	(gr_line
		(start 116.584476 -283.317188)
		(end 116.584984 -283.317442)
		(stroke
			(width 0.05715)
			(type default)
		)
		(layer "In11.Cu")
	)
	(gr_line
		(start 116.58473 -284.9372)
		(end 116.587778 -284.938978)
		(stroke
			(width 0.05715)
			(type default)
		)
		(layer "In11.Cu")
	)
	(gr_line
		(start 116.585492 -294.65778)
		(end 116.585746 -294.657526)
		(stroke
			(width 0.05715)
			(type default)
		)
		(layer "In11.Cu")
	)
	(gr_line
		(start 116.585746 -294.657526)
		(end 116.587016 -294.658288)
		(stroke
			(width 0.05715)
			(type default)
		)
		(layer "In11.Cu")
	)
	(gr_line
		(start 116.586 -294.014652)
		(end 116.584222 -294.015668)
		(stroke
			(width 0.05715)
			(type default)
		)
		(layer "In11.Cu")
	)
	(gr_line
		(start 116.586762 -286.557974)
		(end 116.587778 -286.558736)
		(stroke
			(width 0.05715)
			(type default)
		)
		(layer "In11.Cu")
	)
	(gr_line
		(start 116.587016 -294.658288)
		(end 116.587778 -294.658796)
		(stroke
			(width 0.05715)
			(type default)
		)
		(layer "In11.Cu")
	)
	(gr_line
		(start 116.587016 -292.394132)
		(end 116.585746 -292.394894)
		(stroke
			(width 0.05715)
			(type default)
		)
		(layer "In11.Cu")
	)
	(gr_line
		(start 116.587016 -290.77412)
		(end 116.585746 -290.774882)
		(stroke
			(width 0.05715)
			(type default)
		)
		(layer "In11.Cu")
	)
	(gr_line
		(start 116.587016 -289.154108)
		(end 116.585746 -289.15487)
		(stroke
			(width 0.05715)
			(type default)
		)
		(layer "In11.Cu")
	)
	(gr_line
		(start 116.587016 -285.914338)
		(end 116.585746 -285.9151)
		(stroke
			(width 0.05715)
			(type default)
		)
		(layer "In11.Cu")
	)
	(gr_line
		(start 116.587524 -285.914084)
		(end 116.587016 -285.914338)
		(stroke
			(width 0.05715)
			(type default)
		)
		(layer "In11.Cu")
	)
	(gr_line
		(start 116.587524 -282.67406)
		(end 116.583968 -282.675838)
		(stroke
			(width 0.05715)
			(type default)
		)
		(layer "In11.Cu")
	)
	(gr_line
		(start 116.587778 -294.658796)
		(end 116.615718 -294.67683)
		(stroke
			(width 0.05715)
			(type default)
		)
		(layer "In11.Cu")
	)
	(gr_line
		(start 116.587778 -294.013636)
		(end 116.587016 -294.014144)
		(stroke
			(width 0.05715)
			(type default)
		)
		(layer "In11.Cu")
	)
	(gr_line
		(start 116.587778 -292.393624)
		(end 116.587016 -292.394132)
		(stroke
			(width 0.05715)
			(type default)
		)
		(layer "In11.Cu")
	)
	(gr_line
		(start 116.587778 -290.773612)
		(end 116.587016 -290.77412)
		(stroke
			(width 0.05715)
			(type default)
		)
		(layer "In11.Cu")
	)
	(gr_line
		(start 116.587778 -288.178748)
		(end 116.58854 -288.179256)
		(stroke
			(width 0.05715)
			(type default)
		)
		(layer "In11.Cu")
	)
	(gr_line
		(start 116.587778 -286.558736)
		(end 116.588286 -286.55899)
		(stroke
			(width 0.05715)
			(type default)
		)
		(layer "In11.Cu")
	)
	(gr_line
		(start 116.587778 -284.293818)
		(end 116.584476 -284.295596)
		(stroke
			(width 0.05715)
			(type default)
		)
		(layer "In11.Cu")
	)
	(gr_line
		(start 116.587778 -282.673806)
		(end 116.587524 -282.67406)
		(stroke
			(width 0.05715)
			(type default)
		)
		(layer "In11.Cu")
	)
	(gr_line
		(start 116.587778 -281.698954)
		(end 116.590826 -281.700732)
		(stroke
			(width 0.05715)
			(type default)
		)
		(layer "In11.Cu")
	)
	(gr_line
		(start 116.58854 -289.153092)
		(end 116.587016 -289.154108)
		(stroke
			(width 0.05715)
			(type default)
		)
		(layer "In11.Cu")
	)
	(gr_line
		(start 116.590064 -284.292548)
		(end 116.587778 -284.293818)
		(stroke
			(width 0.05715)
			(type default)
		)
		(layer "In11.Cu")
	)
	(gr_line
		(start 116.590826 -282.672028)
		(end 116.587778 -282.673806)
		(stroke
			(width 0.05715)
			(type default)
		)
		(layer "In11.Cu")
	)
	(gr_line
		(start 116.602764 -281.045158)
		(end 116.602764 -281.045412)
		(stroke
			(width 0.05715)
			(type default)
		)
		(layer "In11.Cu")
	)
	(gr_line
		(start 116.603272 -284.284928)
		(end 116.601494 -284.285944)
		(stroke
			(width 0.05715)
			(type default)
		)
		(layer "In11.Cu")
	)
	(gr_line
		(start 116.603526 -283.32811)
		(end 116.605304 -283.329126)
		(stroke
			(width 0.05715)
			(type default)
		)
		(layer "In11.Cu")
	)
	(gr_line
		(start 116.604034 -284.28442)
		(end 116.603272 -284.284928)
		(stroke
			(width 0.05715)
			(type default)
		)
		(layer "In11.Cu")
	)
	(gr_line
		(start 116.605304 -283.329126)
		(end 116.606066 -283.329634)
		(stroke
			(width 0.05715)
			(type default)
		)
		(layer "In11.Cu")
	)
	(gr_line
		(start 116.606066 -284.28315)
		(end 116.604034 -284.28442)
		(stroke
			(width 0.05715)
			(type default)
		)
		(layer "In11.Cu")
	)
	(gr_line
		(start 116.752116 -414.820354)
		(end 117.08384 -415.089086)
		(stroke
			(width 0.07112)
			(type default)
		)
		(layer "In11.Cu")
	)
	(gr_line
		(start 116.774722 -279.756362)
		(end 117.072664 -279.756362)
		(stroke
			(width 0.05715)
			(type default)
		)
		(layer "In11.Cu")
	)
	(gr_line
		(start 116.774722 -278.13635)
		(end 117.072664 -278.13635)
		(stroke
			(width 0.05715)
			(type default)
		)
		(layer "In11.Cu")
	)
	(gr_line
		(start 116.774722 -276.516338)
		(end 117.072664 -276.516338)
		(stroke
			(width 0.05715)
			(type default)
		)
		(layer "In11.Cu")
	)
	(gr_line
		(start 116.774722 -274.896326)
		(end 117.072664 -274.896326)
		(stroke
			(width 0.05715)
			(type default)
		)
		(layer "In11.Cu")
	)
	(gr_line
		(start 117.042692 -295.460166)
		(end 117.046248 -295.462198)
		(stroke
			(width 0.05715)
			(type default)
		)
		(layer "In11.Cu")
	)
	(gr_line
		(start 117.055138 -275.385022)
		(end 117.054122 -275.385784)
		(stroke
			(width 0.05715)
			(type default)
		)
		(layer "In11.Cu")
	)
	(gr_line
		(start 117.072664 -279.756362)
		(end 117.142006 -279.825704)
		(stroke
			(width 0.05715)
			(type default)
		)
		(layer "In11.Cu")
	)
	(gr_line
		(start 117.072664 -278.13635)
		(end 117.155468 -278.219154)
		(stroke
			(width 0.05715)
			(type default)
		)
		(layer "In11.Cu")
	)
	(gr_line
		(start 117.072664 -276.516338)
		(end 117.155468 -276.599142)
		(stroke
			(width 0.05715)
			(type default)
		)
		(layer "In11.Cu")
	)
	(gr_line
		(start 117.072664 -274.896326)
		(end 117.142006 -274.965668)
		(stroke
			(width 0.05715)
			(type default)
		)
		(layer "In11.Cu")
	)
	(gr_line
		(start 117.08384 -415.089086)
		(end 117.103652 -415.280602)
		(stroke
			(width 0.07112)
			(type default)
		)
		(layer "In11.Cu")
	)
	(gr_line
		(start 117.103906 -296.418762)
		(end 117.103906 -296.44721)
		(stroke
			(width 0.05715)
			(type default)
		)
		(layer "In11.Cu")
	)
	(gr_line
		(start 117.149626 -296.373042)
		(end 117.103906 -296.418762)
		(stroke
			(width 0.05715)
			(type default)
		)
		(layer "In11.Cu")
	)
	(gr_arc
		(start 117.155468 -278.219154)
		(mid 117.15726 -278.230476)
		(end 117.159278 -278.24176)
		(stroke
			(width 0.05715)
			(type default)
		)
		(layer "In11.Cu")
	)
	(gr_line
		(start 117.155468 -276.599142)
		(end 117.155722 -276.599142)
		(stroke
			(width 0.05715)
			(type default)
		)
		(layer "In11.Cu")
	)
	(gr_arc
		(start 117.155722 -276.599142)
		(mid 117.157514 -276.610337)
		(end 117.159532 -276.621494)
		(stroke
			(width 0.05715)
			(type default)
		)
		(layer "In11.Cu")
	)
	(gr_line
		(start 117.213126 -371.2083)
		(end 116.922296 -371.49913)
		(stroke
			(width 0.07112)
			(type default)
		)
		(layer "In11.Cu")
	)
	(gr_line
		(start 117.25783 -415.769806)
		(end 117.80266 -416.211512)
		(stroke
			(width 0.07112)
			(type default)
		)
		(layer "In11.Cu")
	)
	(gr_arc
		(start 117.33022 -279.862026)
		(mid 117.332242 -279.850615)
		(end 117.33403 -279.839166)
		(stroke
			(width 0.05715)
			(type default)
		)
		(layer "In11.Cu")
	)
	(gr_arc
		(start 117.33022 -275.00199)
		(mid 117.332241 -274.990579)
		(end 117.33403 -274.97913)
		(stroke
			(width 0.05715)
			(type default)
		)
		(layer "In11.Cu")
	)
	(gr_line
		(start 117.340126 -296.373042)
		(end 117.385846 -296.418762)
		(stroke
			(width 0.05715)
			(type default)
		)
		(layer "In11.Cu")
	)
	(gr_arc
		(start 117.382036 -288.313368)
		(mid 117.385202 -288.315666)
		(end 117.388386 -288.31794)
		(stroke
			(width 0.05715)
			(type default)
		)
		(layer "In11.Cu")
	)
	(gr_arc
		(start 117.384576 -278.595328)
		(mid 117.388628 -278.598139)
		(end 117.392704 -278.600916)
		(stroke
			(width 0.05715)
			(type default)
		)
		(layer "In11.Cu")
	)
	(gr_arc
		(start 117.38483 -283.455364)
		(mid 117.388755 -283.458175)
		(end 117.392704 -283.460952)
		(stroke
			(width 0.05715)
			(type default)
		)
		(layer "In11.Cu")
	)
	(gr_line
		(start 117.385846 -296.418762)
		(end 117.385846 -296.44721)
		(stroke
			(width 0.05715)
			(type default)
		)
		(layer "In11.Cu")
	)
	(gr_arc
		(start 117.389148 -288.318448)
		(mid 117.390924 -288.319721)
		(end 117.392704 -288.320988)
		(stroke
			(width 0.05715)
			(type default)
		)
		(layer "In11.Cu")
	)
	(gr_line
		(start 117.392704 -288.320988)
		(end 117.3988 -288.324544)
		(stroke
			(width 0.05715)
			(type default)
		)
		(layer "In11.Cu")
	)
	(gr_line
		(start 117.392704 -283.460952)
		(end 117.399562 -283.465016)
		(stroke
			(width 0.05715)
			(type default)
		)
		(layer "In11.Cu")
	)
	(gr_line
		(start 117.392704 -278.600916)
		(end 117.399562 -278.60498)
		(stroke
			(width 0.05715)
			(type default)
		)
		(layer "In11.Cu")
	)
	(gr_line
		(start 117.3988 -288.324544)
		(end 117.399054 -288.324544)
		(stroke
			(width 0.05715)
			(type default)
		)
		(layer "In11.Cu")
	)
	(gr_line
		(start 117.399562 -283.465016)
		(end 117.400324 -283.465524)
		(stroke
			(width 0.05715)
			(type default)
		)
		(layer "In11.Cu")
	)
	(gr_line
		(start 117.399562 -278.60498)
		(end 117.400324 -278.605488)
		(stroke
			(width 0.05715)
			(type default)
		)
		(layer "In11.Cu")
	)
	(gr_line
		(start 117.400324 -283.465524)
		(end 117.401086 -283.466032)
		(stroke
			(width 0.05715)
			(type default)
		)
		(layer "In11.Cu")
	)
	(gr_line
		(start 117.400324 -278.605488)
		(end 117.401086 -278.605996)
		(stroke
			(width 0.05715)
			(type default)
		)
		(layer "In11.Cu")
	)
	(gr_line
		(start 117.416834 -279.756362)
		(end 117.33403 -279.839166)
		(stroke
			(width 0.05715)
			(type default)
		)
		(layer "In11.Cu")
	)
	(gr_line
		(start 117.416834 -278.13635)
		(end 117.347492 -278.205692)
		(stroke
			(width 0.05715)
			(type default)
		)
		(layer "In11.Cu")
	)
	(gr_line
		(start 117.416834 -276.516338)
		(end 117.347746 -276.585426)
		(stroke
			(width 0.05715)
			(type default)
		)
		(layer "In11.Cu")
	)
	(gr_line
		(start 117.416834 -274.896326)
		(end 117.33403 -274.97913)
		(stroke
			(width 0.05715)
			(type default)
		)
		(layer "In11.Cu")
	)
	(gr_line
		(start 117.432074 -278.62403)
		(end 117.432582 -278.624284)
		(stroke
			(width 0.05715)
			(type default)
		)
		(layer "In11.Cu")
	)
	(gr_line
		(start 117.432582 -291.584126)
		(end 117.433852 -291.584888)
		(stroke
			(width 0.05715)
			(type default)
		)
		(layer "In11.Cu")
	)
	(gr_line
		(start 117.432582 -278.624284)
		(end 117.432582 -278.62403)
		(stroke
			(width 0.05715)
			(type default)
		)
		(layer "In11.Cu")
	)
	(gr_line
		(start 117.434614 -293.205408)
		(end 117.435122 -293.205408)
		(stroke
			(width 0.05715)
			(type default)
		)
		(layer "In11.Cu")
	)
	(gr_line
		(start 117.434614 -289.965384)
		(end 117.435122 -289.965384)
		(stroke
			(width 0.05715)
			(type default)
		)
		(layer "In11.Cu")
	)
	(gr_line
		(start 117.434614 -285.105602)
		(end 117.435122 -285.105602)
		(stroke
			(width 0.05715)
			(type default)
		)
		(layer "In11.Cu")
	)
	(gr_line
		(start 117.434614 -283.48559)
		(end 117.435122 -283.48559)
		(stroke
			(width 0.05715)
			(type default)
		)
		(layer "In11.Cu")
	)
	(gr_line
		(start 117.434614 -281.865578)
		(end 117.435122 -281.865578)
		(stroke
			(width 0.05715)
			(type default)
		)
		(layer "In11.Cu")
	)
	(gr_line
		(start 117.434868 -288.345372)
		(end 117.435122 -288.345372)
		(stroke
			(width 0.05715)
			(type default)
		)
		(layer "In11.Cu")
	)
	(gr_line
		(start 117.436646 -415.55035)
		(end 117.628162 -415.530538)
		(stroke
			(width 0.07112)
			(type default)
		)
		(layer "In11.Cu")
	)
	(gr_arc
		(start 117.437916 -280.885392)
		(mid 117.438552 -280.885012)
		(end 117.439186 -280.88463)
		(stroke
			(width 0.05715)
			(type default)
		)
		(layer "In11.Cu")
	)
	(gr_line
		(start 117.495066 -371.2083)
		(end 117.785896 -371.49913)
		(stroke
			(width 0.07112)
			(type default)
		)
		(layer "In11.Cu")
	)
	(gr_line
		(start 117.527324 -294.658542)
		(end 117.527832 -294.658796)
		(stroke
			(width 0.05715)
			(type default)
		)
		(layer "In11.Cu")
	)
	(gr_line
		(start 117.527324 -293.03853)
		(end 117.527832 -293.038784)
		(stroke
			(width 0.05715)
			(type default)
		)
		(layer "In11.Cu")
	)
	(gr_line
		(start 117.527324 -291.418518)
		(end 117.527832 -291.418772)
		(stroke
			(width 0.05715)
			(type default)
		)
		(layer "In11.Cu")
	)
	(gr_line
		(start 117.527324 -289.798506)
		(end 117.527832 -289.79876)
		(stroke
			(width 0.05715)
			(type default)
		)
		(layer "In11.Cu")
	)
	(gr_line
		(start 117.527324 -284.938724)
		(end 117.527832 -284.938978)
		(stroke
			(width 0.05715)
			(type default)
		)
		(layer "In11.Cu")
	)
	(gr_line
		(start 117.527324 -281.6987)
		(end 117.527832 -281.698954)
		(stroke
			(width 0.05715)
			(type default)
		)
		(layer "In11.Cu")
	)
	(gr_line
		(start 117.527578 -292.393878)
		(end 117.522244 -292.396926)
		(stroke
			(width 0.05715)
			(type default)
		)
		(layer "In11.Cu")
	)
	(gr_line
		(start 117.527832 -294.658796)
		(end 117.531896 -294.661336)
		(stroke
			(width 0.05715)
			(type default)
		)
		(layer "In11.Cu")
	)
	(gr_line
		(start 117.527832 -293.038784)
		(end 117.53088 -293.040562)
		(stroke
			(width 0.05715)
			(type default)
		)
		(layer "In11.Cu")
	)
	(gr_line
		(start 117.527832 -291.418772)
		(end 117.527832 -291.419026)
		(stroke
			(width 0.05715)
			(type default)
		)
		(layer "In11.Cu")
	)
	(gr_line
		(start 117.527832 -289.79876)
		(end 117.53088 -289.800538)
		(stroke
			(width 0.05715)
			(type default)
		)
		(layer "In11.Cu")
	)
	(gr_line
		(start 117.527832 -284.938978)
		(end 117.53088 -284.940756)
		(stroke
			(width 0.05715)
			(type default)
		)
		(layer "In11.Cu")
	)
	(gr_line
		(start 117.527832 -283.318966)
		(end 117.53088 -283.320744)
		(stroke
			(width 0.05715)
			(type default)
		)
		(layer "In11.Cu")
	)
	(gr_line
		(start 117.527832 -281.698954)
		(end 117.53088 -281.700732)
		(stroke
			(width 0.05715)
			(type default)
		)
		(layer "In11.Cu")
	)
	(gr_line
		(start 117.527832 -281.053794)
		(end 117.527324 -281.054048)
		(stroke
			(width 0.05715)
			(type default)
		)
		(layer "In11.Cu")
	)
	(gr_line
		(start 117.527832 -278.45893)
		(end 117.528848 -278.459438)
		(stroke
			(width 0.05715)
			(type default)
		)
		(layer "In11.Cu")
	)
	(gr_line
		(start 117.53088 -294.011858)
		(end 117.527324 -294.01389)
		(stroke
			(width 0.05715)
			(type default)
		)
		(layer "In11.Cu")
	)
	(gr_line
		(start 117.53088 -290.771834)
		(end 117.527324 -290.773866)
		(stroke
			(width 0.05715)
			(type default)
		)
		(layer "In11.Cu")
	)
	(gr_line
		(start 117.53088 -289.151822)
		(end 117.527324 -289.153854)
		(stroke
			(width 0.05715)
			(type default)
		)
		(layer "In11.Cu")
	)
	(gr_line
		(start 117.53088 -285.912052)
		(end 117.527324 -285.914084)
		(stroke
			(width 0.05715)
			(type default)
		)
		(layer "In11.Cu")
	)
	(gr_line
		(start 117.53088 -284.29204)
		(end 117.527324 -284.294072)
		(stroke
			(width 0.05715)
			(type default)
		)
		(layer "In11.Cu")
	)
	(gr_line
		(start 117.53088 -282.672028)
		(end 117.527324 -282.67406)
		(stroke
			(width 0.05715)
			(type default)
		)
		(layer "In11.Cu")
	)
	(gr_line
		(start 117.542056 -278.467312)
		(end 117.542818 -278.467566)
		(stroke
			(width 0.05715)
			(type default)
		)
		(layer "In11.Cu")
	)
	(gr_line
		(start 117.619526 -295.146222)
		(end 117.619272 -295.146222)
		(stroke
			(width 0.05715)
			(type default)
		)
		(layer "In11.Cu")
	)
	(gr_line
		(start 117.628162 -415.530538)
		(end 117.959886 -415.799524)
		(stroke
			(width 0.07112)
			(type default)
		)
		(layer "In11.Cu")
	)
	(gr_line
		(start 117.714776 -279.756362)
		(end 117.416834 -279.756362)
		(stroke
			(width 0.05715)
			(type default)
		)
		(layer "In11.Cu")
	)
	(gr_line
		(start 117.714776 -278.13635)
		(end 117.416834 -278.13635)
		(stroke
			(width 0.05715)
			(type default)
		)
		(layer "In11.Cu")
	)
	(gr_line
		(start 117.714776 -276.516338)
		(end 117.416834 -276.516338)
		(stroke
			(width 0.05715)
			(type default)
		)
		(layer "In11.Cu")
	)
	(gr_line
		(start 117.714776 -274.896326)
		(end 117.416834 -274.896326)
		(stroke
			(width 0.05715)
			(type default)
		)
		(layer "In11.Cu")
	)
	(gr_line
		(start 117.902482 -295.634156)
		(end 117.905276 -295.63568)
		(stroke
			(width 0.05715)
			(type default)
		)
		(layer "In11.Cu")
	)
	(gr_line
		(start 117.911372 -341.975948)
		(end 117.911372 -341.975694)
		(stroke
			(width 0.07112)
			(type default)
		)
		(layer "In11.Cu")
	)
	(gr_line
		(start 117.957346 -412.570168)
		(end 118.248176 -412.860998)
		(stroke
			(width 0.07112)
			(type default)
		)
		(layer "In11.Cu")
	)
	(gr_line
		(start 117.959886 -415.799524)
		(end 117.979952 -415.990786)
		(stroke
			(width 0.07112)
			(type default)
		)
		(layer "In11.Cu")
	)
	(gr_line
		(start 117.984778 -280.251154)
		(end 117.984524 -280.251408)
		(stroke
			(width 0.05715)
			(type default)
		)
		(layer "In11.Cu")
	)
	(gr_line
		(start 117.997224 -295.468548)
		(end 117.997732 -295.468802)
		(stroke
			(width 0.05715)
			(type default)
		)
		(layer "In11.Cu")
	)
	(gr_line
		(start 117.997732 -295.468802)
		(end 117.998748 -295.46931)
		(stroke
			(width 0.05715)
			(type default)
		)
		(layer "In11.Cu")
	)
	(gr_line
		(start 117.997732 -279.268936)
		(end 117.998748 -279.269444)
		(stroke
			(width 0.05715)
			(type default)
		)
		(layer "In11.Cu")
	)
	(gr_line
		(start 117.998748 -295.46931)
		(end 118.000272 -295.470326)
		(stroke
			(width 0.05715)
			(type default)
		)
		(layer "In11.Cu")
	)
	(gr_line
		(start 118.000272 -295.470326)
		(end 118.001288 -295.470834)
		(stroke
			(width 0.05715)
			(type default)
		)
		(layer "In11.Cu")
	)
	(gr_line
		(start 118.001288 -295.470834)
		(end 118.006368 -295.473882)
		(stroke
			(width 0.05715)
			(type default)
		)
		(layer "In11.Cu")
	)
	(gr_line
		(start 118.00713 -327.095866)
		(end 118.00713 -327.095612)
		(stroke
			(width 0.07112)
			(type default)
		)
		(layer "In11.Cu")
	)
	(gr_line
		(start 118.04396 -296.418762)
		(end 118.04396 -296.44721)
		(stroke
			(width 0.05715)
			(type default)
		)
		(layer "In11.Cu")
	)
	(gr_arc
		(start 118.044976 -277.677626)
		(mid 118.042314 -277.675714)
		(end 118.039642 -277.673816)
		(stroke
			(width 0.05715)
			(type default)
		)
		(layer "In11.Cu")
	)
	(gr_line
		(start 118.08968 -296.373042)
		(end 118.04396 -296.418762)
		(stroke
			(width 0.05715)
			(type default)
		)
		(layer "In11.Cu")
	)
	(gr_line
		(start 118.13413 -416.47999)
		(end 118.67896 -416.921696)
		(stroke
			(width 0.07112)
			(type default)
		)
		(layer "In11.Cu")
	)
	(gr_line
		(start 118.28018 -296.373042)
		(end 118.3259 -296.418762)
		(stroke
			(width 0.05715)
			(type default)
		)
		(layer "In11.Cu")
	)
	(gr_line
		(start 118.312946 -416.260534)
		(end 118.504462 -416.240722)
		(stroke
			(width 0.07112)
			(type default)
		)
		(layer "In11.Cu")
	)
	(gr_line
		(start 118.3259 -296.418762)
		(end 118.3259 -296.44721)
		(stroke
			(width 0.05715)
			(type default)
		)
		(layer "In11.Cu")
	)
	(gr_line
		(start 118.396766 -340.803992)
		(end 118.39702 -340.803738)
		(stroke
			(width 0.07112)
			(type default)
		)
		(layer "In11.Cu")
	)
	(gr_line
		(start 118.466616 -288.17824)
		(end 118.467632 -288.178748)
		(stroke
			(width 0.05715)
			(type default)
		)
		(layer "In11.Cu")
	)
	(gr_line
		(start 118.466616 -286.558228)
		(end 118.467632 -286.558736)
		(stroke
			(width 0.05715)
			(type default)
		)
		(layer "In11.Cu")
	)
	(gr_line
		(start 118.467124 -294.658542)
		(end 118.467632 -294.658796)
		(stroke
			(width 0.05715)
			(type default)
		)
		(layer "In11.Cu")
	)
	(gr_line
		(start 118.467124 -293.03853)
		(end 118.467632 -293.038784)
		(stroke
			(width 0.05715)
			(type default)
		)
		(layer "In11.Cu")
	)
	(gr_line
		(start 118.467124 -291.418518)
		(end 118.467632 -291.418772)
		(stroke
			(width 0.05715)
			(type default)
		)
		(layer "In11.Cu")
	)
	(gr_line
		(start 118.467124 -289.798506)
		(end 118.467632 -289.79876)
		(stroke
			(width 0.05715)
			(type default)
		)
		(layer "In11.Cu")
	)
	(gr_line
		(start 118.467124 -284.938724)
		(end 118.467632 -284.938978)
		(stroke
			(width 0.05715)
			(type default)
		)
		(layer "In11.Cu")
	)
	(gr_line
		(start 118.467124 -283.318712)
		(end 118.467632 -283.318966)
		(stroke
			(width 0.05715)
			(type default)
		)
		(layer "In11.Cu")
	)
	(gr_line
		(start 118.467124 -281.6987)
		(end 118.467632 -281.698954)
		(stroke
			(width 0.05715)
			(type default)
		)
		(layer "In11.Cu")
	)
	(gr_line
		(start 118.467124 -278.458676)
		(end 118.467632 -278.45893)
		(stroke
			(width 0.05715)
			(type default)
		)
		(layer "In11.Cu")
	)
	(gr_line
		(start 118.467632 -294.658796)
		(end 118.468648 -294.659304)
		(stroke
			(width 0.05715)
			(type default)
		)
		(layer "In11.Cu")
	)
	(gr_line
		(start 118.467632 -294.013636)
		(end 118.467124 -294.01389)
		(stroke
			(width 0.05715)
			(type default)
		)
		(layer "In11.Cu")
	)
	(gr_line
		(start 118.467632 -293.038784)
		(end 118.468648 -293.039292)
		(stroke
			(width 0.05715)
			(type default)
		)
		(layer "In11.Cu")
	)
	(gr_line
		(start 118.467632 -292.393624)
		(end 118.467124 -292.393878)
		(stroke
			(width 0.05715)
			(type default)
		)
		(layer "In11.Cu")
	)
	(gr_line
		(start 118.467632 -291.418772)
		(end 118.468648 -291.41928)
		(stroke
			(width 0.05715)
			(type default)
		)
		(layer "In11.Cu")
	)
	(gr_line
		(start 118.467632 -290.773612)
		(end 118.467124 -290.773866)
		(stroke
			(width 0.05715)
			(type default)
		)
		(layer "In11.Cu")
	)
	(gr_line
		(start 118.467632 -289.79876)
		(end 118.468648 -289.799268)
		(stroke
			(width 0.05715)
			(type default)
		)
		(layer "In11.Cu")
	)
	(gr_line
		(start 118.467632 -289.1536)
		(end 118.467124 -289.153854)
		(stroke
			(width 0.05715)
			(type default)
		)
		(layer "In11.Cu")
	)
	(gr_line
		(start 118.467632 -288.178748)
		(end 118.468648 -288.179256)
		(stroke
			(width 0.05715)
			(type default)
		)
		(layer "In11.Cu")
	)
	(gr_line
		(start 118.467632 -286.558736)
		(end 118.468648 -286.559244)
		(stroke
			(width 0.05715)
			(type default)
		)
		(layer "In11.Cu")
	)
	(gr_line
		(start 118.467632 -285.91383)
		(end 118.467124 -285.914084)
		(stroke
			(width 0.05715)
			(type default)
		)
		(layer "In11.Cu")
	)
	(gr_line
		(start 118.467632 -284.938978)
		(end 118.468648 -284.939486)
		(stroke
			(width 0.05715)
			(type default)
		)
		(layer "In11.Cu")
	)
	(gr_line
		(start 118.467632 -284.293818)
		(end 118.467124 -284.294072)
		(stroke
			(width 0.05715)
			(type default)
		)
		(layer "In11.Cu")
	)
	(gr_line
		(start 118.467632 -283.318966)
		(end 118.468648 -283.319474)
		(stroke
			(width 0.05715)
			(type default)
		)
		(layer "In11.Cu")
	)
	(gr_line
		(start 118.467632 -282.673806)
		(end 118.467124 -282.67406)
		(stroke
			(width 0.05715)
			(type default)
		)
		(layer "In11.Cu")
	)
	(gr_line
		(start 118.467632 -281.698954)
		(end 118.468648 -281.699462)
		(stroke
			(width 0.05715)
			(type default)
		)
		(layer "In11.Cu")
	)
	(gr_line
		(start 118.467632 -281.053794)
		(end 118.467124 -281.054048)
		(stroke
			(width 0.05715)
			(type default)
		)
		(layer "In11.Cu")
	)
	(gr_line
		(start 118.467632 -278.45893)
		(end 118.468648 -278.459438)
		(stroke
			(width 0.05715)
			(type default)
		)
		(layer "In11.Cu")
	)
	(gr_line
		(start 118.46814 -294.013382)
		(end 118.467632 -294.013636)
		(stroke
			(width 0.05715)
			(type default)
		)
		(layer "In11.Cu")
	)
	(gr_line
		(start 118.46814 -292.39337)
		(end 118.467632 -292.393624)
		(stroke
			(width 0.05715)
			(type default)
		)
		(layer "In11.Cu")
	)
	(gr_line
		(start 118.46814 -290.773358)
		(end 118.467632 -290.773612)
		(stroke
			(width 0.05715)
			(type default)
		)
		(layer "In11.Cu")
	)
	(gr_line
		(start 118.46814 -289.153346)
		(end 118.467632 -289.1536)
		(stroke
			(width 0.05715)
			(type default)
		)
		(layer "In11.Cu")
	)
	(gr_line
		(start 118.46814 -285.913576)
		(end 118.467632 -285.91383)
		(stroke
			(width 0.05715)
			(type default)
		)
		(layer "In11.Cu")
	)
	(gr_line
		(start 118.46814 -284.293564)
		(end 118.467632 -284.293818)
		(stroke
			(width 0.05715)
			(type default)
		)
		(layer "In11.Cu")
	)
	(gr_line
		(start 118.46814 -282.673552)
		(end 118.467632 -282.673806)
		(stroke
			(width 0.05715)
			(type default)
		)
		(layer "In11.Cu")
	)
	(gr_line
		(start 118.46814 -281.05354)
		(end 118.467632 -281.053794)
		(stroke
			(width 0.05715)
			(type default)
		)
		(layer "In11.Cu")
	)
	(gr_line
		(start 118.504462 -416.240722)
		(end 118.836186 -416.509708)
		(stroke
			(width 0.07112)
			(type default)
		)
		(layer "In11.Cu")
	)
	(gr_line
		(start 118.65737 -340.911942)
		(end 118.67896 -340.860126)
		(stroke
			(width 0.07112)
			(type default)
		)
		(layer "In11.Cu")
	)
	(gr_line
		(start 118.67896 -340.860126)
		(end 118.67896 -340.803738)
		(stroke
			(width 0.07112)
			(type default)
		)
		(layer "In11.Cu")
	)
	(gr_arc
		(start 118.794784 -295.6052)
		(mid 118.799088 -295.608268)
		(end 118.80342 -295.611296)
		(stroke
			(width 0.05715)
			(type default)
		)
		(layer "In11.Cu")
	)
	(gr_arc
		(start 118.794784 -277.785322)
		(mid 118.798709 -277.788133)
		(end 118.802658 -277.79091)
		(stroke
			(width 0.05715)
			(type default)
		)
		(layer "In11.Cu")
	)
	(gr_line
		(start 118.802658 -277.79091)
		(end 118.809516 -277.794974)
		(stroke
			(width 0.05715)
			(type default)
		)
		(layer "In11.Cu")
	)
	(gr_line
		(start 118.80342 -295.611296)
		(end 118.805706 -295.61282)
		(stroke
			(width 0.05715)
			(type default)
		)
		(layer "In11.Cu")
	)
	(gr_line
		(start 118.805706 -295.61282)
		(end 118.810278 -295.61536)
		(stroke
			(width 0.05715)
			(type default)
		)
		(layer "In11.Cu")
	)
	(gr_line
		(start 118.809516 -277.794974)
		(end 118.810278 -277.795482)
		(stroke
			(width 0.05715)
			(type default)
		)
		(layer "In11.Cu")
	)
	(gr_line
		(start 118.810278 -277.795482)
		(end 118.81104 -277.79599)
		(stroke
			(width 0.05715)
			(type default)
		)
		(layer "In11.Cu")
	)
	(gr_line
		(start 118.820946 -412.570168)
		(end 118.530116 -412.860998)
		(stroke
			(width 0.07112)
			(type default)
		)
		(layer "In11.Cu")
	)
	(gr_line
		(start 118.831868 -280.084784)
		(end 118.832122 -280.08453)
		(stroke
			(width 0.05715)
			(type default)
		)
		(layer "In11.Cu")
	)
	(gr_line
		(start 118.836186 -416.509708)
		(end 118.856252 -416.70097)
		(stroke
			(width 0.07112)
			(type default)
		)
		(layer "In11.Cu")
	)
	(gr_line
		(start 118.841266 -280.078688)
		(end 118.840758 -280.079196)
		(stroke
			(width 0.05715)
			(type default)
		)
		(layer "In11.Cu")
	)
	(gr_line
		(start 118.841774 -279.43429)
		(end 118.84279 -279.434798)
		(stroke
			(width 0.05715)
			(type default)
		)
		(layer "In11.Cu")
	)
	(gr_line
		(start 118.842028 -277.814024)
		(end 118.842536 -277.814278)
		(stroke
			(width 0.05715)
			(type default)
		)
		(layer "In11.Cu")
	)
	(gr_line
		(start 118.842536 -277.814278)
		(end 118.844314 -277.81504)
		(stroke
			(width 0.05715)
			(type default)
		)
		(layer "In11.Cu")
	)
	(gr_line
		(start 118.84279 -279.434798)
		(end 118.844314 -279.435814)
		(stroke
			(width 0.05715)
			(type default)
		)
		(layer "In11.Cu")
	)
	(gr_line
		(start 118.85676 -276.830282)
		(end 118.854474 -276.831552)
		(stroke
			(width 0.05715)
			(type default)
		)
		(layer "In11.Cu")
	)
	(gr_line
		(start 118.899178 -414.384744)
		(end 119.39524 -414.880806)
		(stroke
			(width 0.07112)
			(type default)
		)
		(layer "In11.Cu")
	)
	(gr_line
		(start 118.914926 -368.7445)
		(end 118.624096 -369.03533)
		(stroke
			(width 0.07112)
			(type default)
		)
		(layer "In11.Cu")
	)
	(gr_line
		(start 118.927372 -280.249884)
		(end 118.926102 -280.250646)
		(stroke
			(width 0.05715)
			(type default)
		)
		(layer "In11.Cu")
	)
	(gr_line
		(start 118.937024 -279.268428)
		(end 118.937786 -279.268936)
		(stroke
			(width 0.05715)
			(type default)
		)
		(layer "In11.Cu")
	)
	(gr_line
		(start 118.937786 -279.268936)
		(end 118.938802 -279.269444)
		(stroke
			(width 0.05715)
			(type default)
		)
		(layer "In11.Cu")
	)
	(gr_line
		(start 118.937786 -277.648924)
		(end 118.940072 -277.650194)
		(stroke
			(width 0.05715)
			(type default)
		)
		(layer "In11.Cu")
	)
	(gr_line
		(start 118.938802 -279.269444)
		(end 118.939818 -279.269952)
		(stroke
			(width 0.05715)
			(type default)
		)
		(layer "In11.Cu")
	)
	(gr_line
		(start 118.940834 -280.24201)
		(end 118.938802 -280.24328)
		(stroke
			(width 0.05715)
			(type default)
		)
		(layer "In11.Cu")
	)
	(gr_arc
		(start 118.942104 -277.651464)
		(mid 118.941089 -277.650828)
		(end 118.940072 -277.650194)
		(stroke
			(width 0.05715)
			(type default)
		)
		(layer "In11.Cu")
	)
	(gr_line
		(start 118.946676 -279.274016)
		(end 118.948454 -279.275032)
		(stroke
			(width 0.05715)
			(type default)
		)
		(layer "In11.Cu")
	)
	(gr_line
		(start 118.952772 -276.995128)
		(end 118.952772 -276.995382)
		(stroke
			(width 0.05715)
			(type default)
		)
		(layer "In11.Cu")
	)
	(gr_line
		(start 118.98376 -296.418762)
		(end 118.98376 -296.44721)
		(stroke
			(width 0.05715)
			(type default)
		)
		(layer "In11.Cu")
	)
	(gr_line
		(start 119.01043 -417.190174)
		(end 119.55526 -417.63188)
		(stroke
			(width 0.07112)
			(type default)
		)
		(layer "In11.Cu")
	)
	(gr_line
		(start 119.02948 -296.373042)
		(end 118.98376 -296.418762)
		(stroke
			(width 0.05715)
			(type default)
		)
		(layer "In11.Cu")
	)
	(gr_line
		(start 119.100346 -414.185354)
		(end 119.292624 -414.185354)
		(stroke
			(width 0.07112)
			(type default)
		)
		(layer "In11.Cu")
	)
	(gr_line
		(start 119.1895 -416.970718)
		(end 119.380762 -416.950906)
		(stroke
			(width 0.07112)
			(type default)
		)
		(layer "In11.Cu")
	)
	(gr_line
		(start 119.196866 -368.7445)
		(end 119.487696 -369.03533)
		(stroke
			(width 0.07112)
			(type default)
		)
		(layer "In11.Cu")
	)
	(gr_line
		(start 119.21998 -296.373042)
		(end 119.2657 -296.418762)
		(stroke
			(width 0.05715)
			(type default)
		)
		(layer "In11.Cu")
	)
	(gr_line
		(start 119.2657 -296.418762)
		(end 119.2657 -296.44721)
		(stroke
			(width 0.05715)
			(type default)
		)
		(layer "In11.Cu")
	)
	(gr_line
		(start 119.292624 -414.185354)
		(end 119.59463 -414.48736)
		(stroke
			(width 0.07112)
			(type default)
		)
		(layer "In11.Cu")
	)
	(gr_line
		(start 119.296688 -278.61514)
		(end 119.296434 -278.61514)
		(stroke
			(width 0.05715)
			(type default)
		)
		(layer "In11.Cu")
	)
	(gr_arc
		(start 119.300244 -293.197026)
		(mid 119.3024 -293.198301)
		(end 119.304562 -293.199566)
		(stroke
			(width 0.05715)
			(type default)
		)
		(layer "In11.Cu")
	)
	(gr_line
		(start 119.30126 -278.617934)
		(end 119.3038 -278.619204)
		(stroke
			(width 0.05715)
			(type default)
		)
		(layer "In11.Cu")
	)
	(gr_line
		(start 119.306594 -278.620728)
		(end 119.307356 -278.621236)
		(stroke
			(width 0.05715)
			(type default)
		)
		(layer "In11.Cu")
	)
	(gr_line
		(start 119.307356 -278.621236)
		(end 119.308372 -278.621744)
		(stroke
			(width 0.05715)
			(type default)
		)
		(layer "In11.Cu")
	)
	(gr_line
		(start 119.307864 -286.72155)
		(end 119.307102 -286.721296)
		(stroke
			(width 0.05715)
			(type default)
		)
		(layer "In11.Cu")
	)
	(gr_line
		(start 119.308372 -278.621744)
		(end 119.309134 -278.622252)
		(stroke
			(width 0.05715)
			(type default)
		)
		(layer "In11.Cu")
	)
	(gr_arc
		(start 119.30888 -288.990278)
		(mid 119.307482 -288.991038)
		(end 119.306086 -288.991802)
		(stroke
			(width 0.05715)
			(type default)
		)
		(layer "In11.Cu")
	)
	(gr_arc
		(start 119.30888 -284.12821)
		(mid 119.306845 -284.129475)
		(end 119.304816 -284.13075)
		(stroke
			(width 0.05715)
			(type default)
		)
		(layer "In11.Cu")
	)
	(gr_arc
		(start 119.30888 -282.508198)
		(mid 119.306845 -282.509463)
		(end 119.304816 -282.510738)
		(stroke
			(width 0.05715)
			(type default)
		)
		(layer "In11.Cu")
	)
	(gr_line
		(start 119.309134 -285.750254)
		(end 119.309388 -285.750254)
		(stroke
			(width 0.05715)
			(type default)
		)
		(layer "In11.Cu")
	)
	(gr_line
		(start 119.309388 -286.722566)
		(end 119.311166 -286.723582)
		(stroke
			(width 0.05715)
			(type default)
		)
		(layer "In11.Cu")
	)
	(gr_arc
		(start 119.309388 -285.750254)
		(mid 119.308499 -285.750761)
		(end 119.30761 -285.75127)
		(stroke
			(width 0.05715)
			(type default)
		)
		(layer "In11.Cu")
	)
	(gr_line
		(start 119.309896 -285.749746)
		(end 119.309134 -285.750254)
		(stroke
			(width 0.05715)
			(type default)
		)
		(layer "In11.Cu")
	)
	(gr_line
		(start 119.31142 -293.20363)
		(end 119.311674 -293.20363)
		(stroke
			(width 0.05715)
			(type default)
		)
		(layer "In11.Cu")
	)
	(gr_line
		(start 119.311674 -291.583618)
		(end 119.312436 -291.584126)
		(stroke
			(width 0.05715)
			(type default)
		)
		(layer "In11.Cu")
	)
	(gr_line
		(start 119.312436 -291.584126)
		(end 119.313706 -291.584888)
		(stroke
			(width 0.05715)
			(type default)
		)
		(layer "In11.Cu")
	)
	(gr_line
		(start 119.312436 -276.029674)
		(end 119.312182 -276.029928)
		(stroke
			(width 0.05715)
			(type default)
		)
		(layer "In11.Cu")
	)
	(gr_line
		(start 119.31269 -278.624284)
		(end 119.313452 -278.624792)
		(stroke
			(width 0.05715)
			(type default)
		)
		(layer "In11.Cu")
	)
	(gr_line
		(start 119.313452 -278.624792)
		(end 119.314214 -278.625046)
		(stroke
			(width 0.05715)
			(type default)
		)
		(layer "In11.Cu")
	)
	(gr_line
		(start 119.314214 -278.625046)
		(end 119.314976 -278.625554)
		(stroke
			(width 0.05715)
			(type default)
		)
		(layer "In11.Cu")
	)
	(gr_line
		(start 119.314976 -278.625554)
		(end 119.315992 -278.626062)
		(stroke
			(width 0.05715)
			(type default)
		)
		(layer "In11.Cu")
	)
	(gr_line
		(start 119.315484 -287.36417)
		(end 119.310658 -287.366964)
		(stroke
			(width 0.05715)
			(type default)
		)
		(layer "In11.Cu")
	)
	(gr_line
		(start 119.319548 -293.208202)
		(end 119.32031 -293.208456)
		(stroke
			(width 0.05715)
			(type default)
		)
		(layer "In11.Cu")
	)
	(gr_line
		(start 119.337074 -341.004144)
		(end 119.337328 -341.00389)
		(stroke
			(width 0.07112)
			(type default)
		)
		(layer "In11.Cu")
	)
	(gr_line
		(start 119.380762 -416.950906)
		(end 119.712486 -417.219892)
		(stroke
			(width 0.07112)
			(type default)
		)
		(layer "In11.Cu")
	)
	(gr_line
		(start 119.393716 -278.451056)
		(end 119.394224 -278.45131)
		(stroke
			(width 0.05715)
			(type default)
		)
		(layer "In11.Cu")
	)
	(gr_line
		(start 119.396256 -278.452326)
		(end 119.398796 -278.45385)
		(stroke
			(width 0.05715)
			(type default)
		)
		(layer "In11.Cu")
	)
	(gr_line
		(start 119.398796 -278.45385)
		(end 119.399558 -278.454358)
		(stroke
			(width 0.05715)
			(type default)
		)
		(layer "In11.Cu")
	)
	(gr_line
		(start 119.399558 -278.454358)
		(end 119.400574 -278.454866)
		(stroke
			(width 0.05715)
			(type default)
		)
		(layer "In11.Cu")
	)
	(gr_line
		(start 119.403114 -278.456136)
		(end 119.403876 -278.456644)
		(stroke
			(width 0.05715)
			(type default)
		)
		(layer "In11.Cu")
	)
	(gr_line
		(start 119.403876 -278.456644)
		(end 119.404892 -278.457152)
		(stroke
			(width 0.05715)
			(type default)
		)
		(layer "In11.Cu")
	)
	(gr_line
		(start 119.404638 -289.796982)
		(end 119.407686 -289.79876)
		(stroke
			(width 0.05715)
			(type default)
		)
		(layer "In11.Cu")
	)
	(gr_line
		(start 119.405146 -286.55772)
		(end 119.405908 -286.558228)
		(stroke
			(width 0.05715)
			(type default)
		)
		(layer "In11.Cu")
	)
	(gr_line
		(start 119.405908 -286.558228)
		(end 119.407178 -286.55899)
		(stroke
			(width 0.05715)
			(type default)
		)
		(layer "In11.Cu")
	)
	(gr_line
		(start 119.405908 -278.45766)
		(end 119.40667 -278.458168)
		(stroke
			(width 0.05715)
			(type default)
		)
		(layer "In11.Cu")
	)
	(gr_line
		(start 119.40667 -281.054302)
		(end 119.406416 -281.054302)
		(stroke
			(width 0.05715)
			(type default)
		)
		(layer "In11.Cu")
	)
	(gr_line
		(start 119.40667 -276.19579)
		(end 119.40413 -276.197314)
		(stroke
			(width 0.05715)
			(type default)
		)
		(layer "In11.Cu")
	)
	(gr_line
		(start 119.407178 -293.03853)
		(end 119.414798 -293.042848)
		(stroke
			(width 0.05715)
			(type default)
		)
		(layer "In11.Cu")
	)
	(gr_line
		(start 119.407178 -291.418772)
		(end 119.407686 -291.418772)
		(stroke
			(width 0.05715)
			(type default)
		)
		(layer "In11.Cu")
	)
	(gr_line
		(start 119.407178 -286.55899)
		(end 119.407686 -286.559244)
		(stroke
			(width 0.05715)
			(type default)
		)
		(layer "In11.Cu")
	)
	(gr_arc
		(start 119.407178 -284.291786)
		(mid 119.406543 -284.292167)
		(end 119.405908 -284.292548)
		(stroke
			(width 0.05715)
			(type default)
		)
		(layer "In11.Cu")
	)
	(gr_line
		(start 119.407686 -291.418772)
		(end 119.408702 -291.41928)
		(stroke
			(width 0.05715)
			(type default)
		)
		(layer "In11.Cu")
	)
	(gr_line
		(start 119.407686 -289.79876)
		(end 119.408702 -289.799268)
		(stroke
			(width 0.05715)
			(type default)
		)
		(layer "In11.Cu")
	)
	(gr_line
		(start 119.408448 -281.053286)
		(end 119.40794 -281.05354)
		(stroke
			(width 0.05715)
			(type default)
		)
		(layer "In11.Cu")
	)
	(gr_line
		(start 119.410988 -289.151568)
		(end 119.404892 -289.155124)
		(stroke
			(width 0.05715)
			(type default)
		)
		(layer "In11.Cu")
	)
	(gr_line
		(start 119.410988 -278.460708)
		(end 119.412004 -278.46147)
		(stroke
			(width 0.05715)
			(type default)
		)
		(layer "In11.Cu")
	)
	(gr_line
		(start 119.414798 -293.042848)
		(end 119.416322 -293.043864)
		(stroke
			(width 0.05715)
			(type default)
		)
		(layer "In11.Cu")
	)
	(gr_line
		(start 119.438674 -294.67683)
		(end 119.44604 -294.681148)
		(stroke
			(width 0.05715)
			(type default)
		)
		(layer "In11.Cu")
	)
	(gr_line
		(start 119.439436 -293.057326)
		(end 119.44604 -293.061136)
		(stroke
			(width 0.05715)
			(type default)
		)
		(layer "In11.Cu")
	)
	(gr_arc
		(start 119.44604 -294.681148)
		(mid 119.446421 -294.681402)
		(end 119.446802 -294.681656)
		(stroke
			(width 0.05715)
			(type default)
		)
		(layer "In11.Cu")
	)
	(gr_arc
		(start 119.44604 -293.061136)
		(mid 119.446421 -293.06139)
		(end 119.446802 -293.061644)
		(stroke
			(width 0.05715)
			(type default)
		)
		(layer "In11.Cu")
	)
	(gr_arc
		(start 119.454676 -294.687244)
		(mid 119.450751 -294.684433)
		(end 119.446802 -294.681656)
		(stroke
			(width 0.05715)
			(type default)
		)
		(layer "In11.Cu")
	)
	(gr_arc
		(start 119.454676 -293.067232)
		(mid 119.450751 -293.064421)
		(end 119.446802 -293.061644)
		(stroke
			(width 0.05715)
			(type default)
		)
		(layer "In11.Cu")
	)
	(gr_line
		(start 119.49938 -295.146222)
		(end 119.499634 -295.146222)
		(stroke
			(width 0.05715)
			(type default)
		)
		(layer "In11.Cu")
	)
	(gr_line
		(start 119.59463 -414.48736)
		(end 119.59463 -414.679638)
		(stroke
			(width 0.07112)
			(type default)
		)
		(layer "In11.Cu")
	)
	(gr_line
		(start 119.59463 -278.13635)
		(end 119.892572 -278.13635)
		(stroke
			(width 0.05715)
			(type default)
		)
		(layer "In11.Cu")
	)
	(gr_line
		(start 119.59463 -276.516338)
		(end 119.892572 -276.516338)
		(stroke
			(width 0.05715)
			(type default)
		)
		(layer "In11.Cu")
	)
	(gr_line
		(start 119.59463 -274.896326)
		(end 119.892572 -274.896326)
		(stroke
			(width 0.05715)
			(type default)
		)
		(layer "In11.Cu")
	)
	(gr_line
		(start 119.597678 -341.112094)
		(end 119.619268 -341.060278)
		(stroke
			(width 0.07112)
			(type default)
		)
		(layer "In11.Cu")
	)
	(gr_line
		(start 119.619268 -341.060278)
		(end 119.619268 -341.00389)
		(stroke
			(width 0.07112)
			(type default)
		)
		(layer "In11.Cu")
	)
	(gr_line
		(start 119.696738 -415.182304)
		(end 120.1928 -415.678366)
		(stroke
			(width 0.07112)
			(type default)
		)
		(layer "In11.Cu")
	)
	(gr_line
		(start 119.700548 -326.309736)
		(end 119.700548 -326.309482)
		(stroke
			(width 0.07112)
			(type default)
		)
		(layer "In11.Cu")
	)
	(gr_line
		(start 119.712486 -417.219892)
		(end 119.732552 -417.411154)
		(stroke
			(width 0.07112)
			(type default)
		)
		(layer "In11.Cu")
	)
	(gr_line
		(start 119.749316 -295.614598)
		(end 119.75211 -295.616376)
		(stroke
			(width 0.05715)
			(type default)
		)
		(layer "In11.Cu")
	)
	(gr_line
		(start 119.892572 -278.13635)
		(end 119.975376 -278.219154)
		(stroke
			(width 0.05715)
			(type default)
		)
		(layer "In11.Cu")
	)
	(gr_line
		(start 119.892572 -276.516338)
		(end 119.975376 -276.599142)
		(stroke
			(width 0.05715)
			(type default)
		)
		(layer "In11.Cu")
	)
	(gr_line
		(start 119.892572 -274.896326)
		(end 119.961914 -274.965668)
		(stroke
			(width 0.05715)
			(type default)
		)
		(layer "In11.Cu")
	)
	(gr_line
		(start 119.897906 -414.982914)
		(end 120.090184 -414.982914)
		(stroke
			(width 0.07112)
			(type default)
		)
		(layer "In11.Cu")
	)
	(gr_line
		(start 119.923814 -296.584116)
		(end 119.923814 -296.612564)
		(stroke
			(width 0.05715)
			(type default)
		)
		(layer "In11.Cu")
	)
	(gr_line
		(start 119.969534 -296.538396)
		(end 119.923814 -296.584116)
		(stroke
			(width 0.05715)
			(type default)
		)
		(layer "In11.Cu")
	)
	(gr_arc
		(start 119.975376 -278.219154)
		(mid 119.977168 -278.230476)
		(end 119.979186 -278.24176)
		(stroke
			(width 0.05715)
			(type default)
		)
		(layer "In11.Cu")
	)
	(gr_arc
		(start 119.975376 -276.599142)
		(mid 119.977167 -276.610464)
		(end 119.979186 -276.621748)
		(stroke
			(width 0.05715)
			(type default)
		)
		(layer "In11.Cu")
	)
	(gr_line
		(start 120.090184 -414.982914)
		(end 120.39219 -415.28492)
		(stroke
			(width 0.07112)
			(type default)
		)
		(layer "In11.Cu")
	)
	(gr_arc
		(start 120.150128 -275.00199)
		(mid 120.152149 -274.990579)
		(end 120.153938 -274.97913)
		(stroke
			(width 0.05715)
			(type default)
		)
		(layer "In11.Cu")
	)
	(gr_line
		(start 120.160034 -296.538396)
		(end 120.205754 -296.584116)
		(stroke
			(width 0.05715)
			(type default)
		)
		(layer "In11.Cu")
	)
	(gr_arc
		(start 120.201944 -288.313368)
		(mid 120.20511 -288.315666)
		(end 120.208294 -288.31794)
		(stroke
			(width 0.05715)
			(type default)
		)
		(layer "In11.Cu")
	)
	(gr_arc
		(start 120.204484 -278.595328)
		(mid 120.208536 -278.59814)
		(end 120.212612 -278.600916)
		(stroke
			(width 0.05715)
			(type default)
		)
		(layer "In11.Cu")
	)
	(gr_arc
		(start 120.204484 -276.975316)
		(mid 120.208536 -276.978128)
		(end 120.212612 -276.980904)
		(stroke
			(width 0.05715)
			(type default)
		)
		(layer "In11.Cu")
	)
	(gr_arc
		(start 120.204738 -283.455364)
		(mid 120.208663 -283.458175)
		(end 120.212612 -283.460952)
		(stroke
			(width 0.05715)
			(type default)
		)
		(layer "In11.Cu")
	)
	(gr_line
		(start 120.205754 -296.584116)
		(end 120.205754 -296.612564)
		(stroke
			(width 0.05715)
			(type default)
		)
		(layer "In11.Cu")
	)
	(gr_arc
		(start 120.209056 -288.318448)
		(mid 120.210832 -288.319721)
		(end 120.212612 -288.320988)
		(stroke
			(width 0.05715)
			(type default)
		)
		(layer "In11.Cu")
	)
	(gr_line
		(start 120.212612 -288.320988)
		(end 120.218708 -288.324544)
		(stroke
			(width 0.05715)
			(type default)
		)
		(layer "In11.Cu")
	)
	(gr_line
		(start 120.212612 -283.460952)
		(end 120.21947 -283.465016)
		(stroke
			(width 0.05715)
			(type default)
		)
		(layer "In11.Cu")
	)
	(gr_line
		(start 120.212612 -278.600916)
		(end 120.21947 -278.60498)
		(stroke
			(width 0.05715)
			(type default)
		)
		(layer "In11.Cu")
	)
	(gr_line
		(start 120.212612 -276.980904)
		(end 120.21947 -276.984968)
		(stroke
			(width 0.05715)
			(type default)
		)
		(layer "In11.Cu")
	)
	(gr_line
		(start 120.218708 -288.324544)
		(end 120.218962 -288.324544)
		(stroke
			(width 0.05715)
			(type default)
		)
		(layer "In11.Cu")
	)
	(gr_line
		(start 120.21947 -283.465016)
		(end 120.220232 -283.465524)
		(stroke
			(width 0.05715)
			(type default)
		)
		(layer "In11.Cu")
	)
	(gr_line
		(start 120.21947 -278.60498)
		(end 120.220232 -278.605488)
		(stroke
			(width 0.05715)
			(type default)
		)
		(layer "In11.Cu")
	)
	(gr_line
		(start 120.21947 -276.984968)
		(end 120.220232 -276.985476)
		(stroke
			(width 0.05715)
			(type default)
		)
		(layer "In11.Cu")
	)
	(gr_line
		(start 120.220232 -283.465524)
		(end 120.220994 -283.466032)
		(stroke
			(width 0.05715)
			(type default)
		)
		(layer "In11.Cu")
	)
	(gr_line
		(start 120.220232 -278.605488)
		(end 120.220994 -278.605996)
		(stroke
			(width 0.05715)
			(type default)
		)
		(layer "In11.Cu")
	)
	(gr_line
		(start 120.220232 -276.985476)
		(end 120.220994 -276.985984)
		(stroke
			(width 0.05715)
			(type default)
		)
		(layer "In11.Cu")
	)
	(gr_line
		(start 120.236742 -278.13635)
		(end 120.1674 -278.205692)
		(stroke
			(width 0.05715)
			(type default)
		)
		(layer "In11.Cu")
	)
	(gr_line
		(start 120.236742 -276.516338)
		(end 120.1674 -276.58568)
		(stroke
			(width 0.05715)
			(type default)
		)
		(layer "In11.Cu")
	)
	(gr_line
		(start 120.236742 -274.896326)
		(end 120.153938 -274.97913)
		(stroke
			(width 0.05715)
			(type default)
		)
		(layer "In11.Cu")
	)
	(gr_line
		(start 120.251728 -277.003764)
		(end 120.251982 -277.004018)
		(stroke
			(width 0.05715)
			(type default)
		)
		(layer "In11.Cu")
	)
	(gr_line
		(start 120.251982 -278.62403)
		(end 120.25249 -278.624284)
		(stroke
			(width 0.05715)
			(type default)
		)
		(layer "In11.Cu")
	)
	(gr_line
		(start 120.251982 -277.004018)
		(end 120.25249 -277.004272)
		(stroke
			(width 0.05715)
			(type default)
		)
		(layer "In11.Cu")
	)
	(gr_line
		(start 120.25249 -291.584126)
		(end 120.25376 -291.584888)
		(stroke
			(width 0.05715)
			(type default)
		)
		(layer "In11.Cu")
	)
	(gr_line
		(start 120.25249 -278.624284)
		(end 120.25249 -278.62403)
		(stroke
			(width 0.05715)
			(type default)
		)
		(layer "In11.Cu")
	)
	(gr_line
		(start 120.25249 -277.004272)
		(end 120.255284 -277.005796)
		(stroke
			(width 0.05715)
			(type default)
		)
		(layer "In11.Cu")
	)
	(gr_line
		(start 120.254522 -293.205408)
		(end 120.25503 -293.205408)
		(stroke
			(width 0.05715)
			(type default)
		)
		(layer "In11.Cu")
	)
	(gr_line
		(start 120.254522 -289.965384)
		(end 120.25503 -289.965384)
		(stroke
			(width 0.05715)
			(type default)
		)
		(layer "In11.Cu")
	)
	(gr_line
		(start 120.254522 -285.105602)
		(end 120.25503 -285.105602)
		(stroke
			(width 0.05715)
			(type default)
		)
		(layer "In11.Cu")
	)
	(gr_line
		(start 120.254522 -283.48559)
		(end 120.25503 -283.48559)
		(stroke
			(width 0.05715)
			(type default)
		)
		(layer "In11.Cu")
	)
	(gr_line
		(start 120.254522 -281.865578)
		(end 120.25503 -281.865578)
		(stroke
			(width 0.05715)
			(type default)
		)
		(layer "In11.Cu")
	)
	(gr_line
		(start 120.254776 -288.345372)
		(end 120.25503 -288.345372)
		(stroke
			(width 0.05715)
			(type default)
		)
		(layer "In11.Cu")
	)
	(gr_line
		(start 120.255284 -277.005796)
		(end 120.255792 -277.00605)
		(stroke
			(width 0.05715)
			(type default)
		)
		(layer "In11.Cu")
	)
	(gr_arc
		(start 120.257824 -280.885392)
		(mid 120.25846 -280.885012)
		(end 120.259094 -280.88463)
		(stroke
			(width 0.05715)
			(type default)
		)
		(layer "In11.Cu")
	)
	(gr_line
		(start 120.347232 -294.658542)
		(end 120.34774 -294.658796)
		(stroke
			(width 0.05715)
			(type default)
		)
		(layer "In11.Cu")
	)
	(gr_line
		(start 120.347232 -293.03853)
		(end 120.34774 -293.038784)
		(stroke
			(width 0.05715)
			(type default)
		)
		(layer "In11.Cu")
	)
	(gr_line
		(start 120.347232 -291.418518)
		(end 120.34774 -291.418772)
		(stroke
			(width 0.05715)
			(type default)
		)
		(layer "In11.Cu")
	)
	(gr_line
		(start 120.347232 -289.798506)
		(end 120.34774 -289.79876)
		(stroke
			(width 0.05715)
			(type default)
		)
		(layer "In11.Cu")
	)
	(gr_line
		(start 120.347232 -284.938724)
		(end 120.34774 -284.938978)
		(stroke
			(width 0.05715)
			(type default)
		)
		(layer "In11.Cu")
	)
	(gr_line
		(start 120.347232 -281.6987)
		(end 120.34774 -281.698954)
		(stroke
			(width 0.05715)
			(type default)
		)
		(layer "In11.Cu")
	)
	(gr_line
		(start 120.347486 -292.393878)
		(end 120.342152 -292.396926)
		(stroke
			(width 0.05715)
			(type default)
		)
		(layer "In11.Cu")
	)
	(gr_line
		(start 120.34774 -294.658796)
		(end 120.351804 -294.661336)
		(stroke
			(width 0.05715)
			(type default)
		)
		(layer "In11.Cu")
	)
	(gr_line
		(start 120.34774 -293.038784)
		(end 120.350788 -293.040562)
		(stroke
			(width 0.05715)
			(type default)
		)
		(layer "In11.Cu")
	)
	(gr_line
		(start 120.34774 -291.418772)
		(end 120.34774 -291.419026)
		(stroke
			(width 0.05715)
			(type default)
		)
		(layer "In11.Cu")
	)
	(gr_line
		(start 120.34774 -289.79876)
		(end 120.350788 -289.800538)
		(stroke
			(width 0.05715)
			(type default)
		)
		(layer "In11.Cu")
	)
	(gr_line
		(start 120.34774 -284.938978)
		(end 120.350788 -284.940756)
		(stroke
			(width 0.05715)
			(type default)
		)
		(layer "In11.Cu")
	)
	(gr_line
		(start 120.34774 -283.318966)
		(end 120.350788 -283.320744)
		(stroke
			(width 0.05715)
			(type default)
		)
		(layer "In11.Cu")
	)
	(gr_line
		(start 120.34774 -281.698954)
		(end 120.350788 -281.700732)
		(stroke
			(width 0.05715)
			(type default)
		)
		(layer "In11.Cu")
	)
	(gr_line
		(start 120.34774 -281.053794)
		(end 120.347232 -281.054048)
		(stroke
			(width 0.05715)
			(type default)
		)
		(layer "In11.Cu")
	)
	(gr_line
		(start 120.34774 -278.45893)
		(end 120.348756 -278.459438)
		(stroke
			(width 0.05715)
			(type default)
		)
		(layer "In11.Cu")
	)
	(gr_line
		(start 120.34774 -276.838918)
		(end 120.351042 -276.84095)
		(stroke
			(width 0.05715)
			(type default)
		)
		(layer "In11.Cu")
	)
	(gr_line
		(start 120.350788 -294.011858)
		(end 120.347232 -294.01389)
		(stroke
			(width 0.05715)
			(type default)
		)
		(layer "In11.Cu")
	)
	(gr_line
		(start 120.350788 -290.771834)
		(end 120.347232 -290.773866)
		(stroke
			(width 0.05715)
			(type default)
		)
		(layer "In11.Cu")
	)
	(gr_line
		(start 120.350788 -289.151822)
		(end 120.347232 -289.153854)
		(stroke
			(width 0.05715)
			(type default)
		)
		(layer "In11.Cu")
	)
	(gr_line
		(start 120.350788 -285.912052)
		(end 120.347232 -285.914084)
		(stroke
			(width 0.05715)
			(type default)
		)
		(layer "In11.Cu")
	)
	(gr_line
		(start 120.350788 -284.29204)
		(end 120.347232 -284.294072)
		(stroke
			(width 0.05715)
			(type default)
		)
		(layer "In11.Cu")
	)
	(gr_line
		(start 120.350788 -282.672028)
		(end 120.347232 -282.67406)
		(stroke
			(width 0.05715)
			(type default)
		)
		(layer "In11.Cu")
	)
	(gr_line
		(start 120.361964 -278.467312)
		(end 120.362726 -278.467566)
		(stroke
			(width 0.05715)
			(type default)
		)
		(layer "In11.Cu")
	)
	(gr_line
		(start 120.39219 -415.28492)
		(end 120.39219 -415.477198)
		(stroke
			(width 0.07112)
			(type default)
		)
		(layer "In11.Cu")
	)
	(gr_line
		(start 120.534684 -278.13635)
		(end 120.236742 -278.13635)
		(stroke
			(width 0.05715)
			(type default)
		)
		(layer "In11.Cu")
	)
	(gr_line
		(start 120.534684 -276.516338)
		(end 120.236742 -276.516338)
		(stroke
			(width 0.05715)
			(type default)
		)
		(layer "In11.Cu")
	)
	(gr_line
		(start 120.534684 -274.896326)
		(end 120.236742 -274.896326)
		(stroke
			(width 0.05715)
			(type default)
		)
		(layer "In11.Cu")
	)
	(gr_line
		(start 120.629934 -295.146222)
		(end 120.630188 -295.146222)
		(stroke
			(width 0.05715)
			(type default)
		)
		(layer "In11.Cu")
	)
	(gr_line
		(start 120.753124 -277.832058)
		(end 120.753378 -277.832058)
		(stroke
			(width 0.05715)
			(type default)
		)
		(layer "In11.Cu")
	)
	(gr_line
		(start 120.794018 -295.455086)
		(end 120.795288 -295.455848)
		(stroke
			(width 0.05715)
			(type default)
		)
		(layer "In11.Cu")
	)
	(gr_line
		(start 120.804686 -280.251154)
		(end 120.804432 -280.251408)
		(stroke
			(width 0.05715)
			(type default)
		)
		(layer "In11.Cu")
	)
	(gr_line
		(start 120.81764 -279.268936)
		(end 120.818656 -279.269444)
		(stroke
			(width 0.05715)
			(type default)
		)
		(layer "In11.Cu")
	)
	(gr_line
		(start 120.940322 -296.612564)
		(end 120.940322 -296.613072)
		(stroke
			(width 0.07112)
			(type default)
		)
		(layer "In11.Cu")
	)
	(gr_line
		(start 120.940322 -296.584116)
		(end 120.940322 -296.612564)
		(stroke
			(width 0.05715)
			(type default)
		)
		(layer "In11.Cu")
	)
	(gr_line
		(start 120.986042 -296.538396)
		(end 120.940322 -296.584116)
		(stroke
			(width 0.05715)
			(type default)
		)
		(layer "In11.Cu")
	)
	(gr_line
		(start 121.020586 -412.570168)
		(end 121.320052 -412.869634)
		(stroke
			(width 0.07112)
			(type default)
		)
		(layer "In11.Cu")
	)
	(gr_line
		(start 121.10212 -296.01287)
		(end 121.10212 -296.013886)
		(stroke
			(width 0.05715)
			(type default)
		)
		(layer "In11.Cu")
	)
	(gr_line
		(start 121.176542 -296.538396)
		(end 121.222262 -296.584116)
		(stroke
			(width 0.05715)
			(type default)
		)
		(layer "In11.Cu")
	)
	(gr_line
		(start 121.192544 -325.74611)
		(end 121.192544 -325.746364)
		(stroke
			(width 0.07112)
			(type default)
		)
		(layer "In11.Cu")
	)
	(gr_line
		(start 121.222262 -296.584116)
		(end 121.222262 -296.612564)
		(stroke
			(width 0.05715)
			(type default)
		)
		(layer "In11.Cu")
	)
	(gr_line
		(start 121.22277 -296.659808)
		(end 121.22277 -296.660316)
		(stroke
			(width 0.07112)
			(type default)
		)
		(layer "In11.Cu")
	)
	(gr_line
		(start 121.277634 -333.469742)
		(end 121.277888 -333.469742)
		(stroke
			(width 0.07112)
			(type default)
		)
		(layer "In11.Cu")
	)
	(gr_line
		(start 121.379234 -295.146222)
		(end 121.379488 -295.146222)
		(stroke
			(width 0.05715)
			(type default)
		)
		(layer "In11.Cu")
	)
	(gr_line
		(start 121.606564 -412.865062)
		(end 121.601992 -412.869634)
		(stroke
			(width 0.07112)
			(type default)
		)
		(layer "In11.Cu")
	)
	(gr_line
		(start 121.606564 -412.84779)
		(end 121.606564 -412.865062)
		(stroke
			(width 0.07112)
			(type default)
		)
		(layer "In11.Cu")
	)
	(gr_arc
		(start 121.614692 -279.405334)
		(mid 121.618617 -279.408145)
		(end 121.622566 -279.410922)
		(stroke
			(width 0.05715)
			(type default)
		)
		(layer "In11.Cu")
	)
	(gr_line
		(start 121.622566 -279.410922)
		(end 121.629424 -279.414986)
		(stroke
			(width 0.05715)
			(type default)
		)
		(layer "In11.Cu")
	)
	(gr_line
		(start 121.629424 -279.414986)
		(end 121.630186 -279.415494)
		(stroke
			(width 0.05715)
			(type default)
		)
		(layer "In11.Cu")
	)
	(gr_line
		(start 121.630186 -279.415494)
		(end 121.630948 -279.416002)
		(stroke
			(width 0.05715)
			(type default)
		)
		(layer "In11.Cu")
	)
	(gr_line
		(start 121.661428 -280.078942)
		(end 121.660666 -280.07945)
		(stroke
			(width 0.05715)
			(type default)
		)
		(layer "In11.Cu")
	)
	(gr_line
		(start 121.661936 -279.434036)
		(end 121.662444 -279.43429)
		(stroke
			(width 0.05715)
			(type default)
		)
		(layer "In11.Cu")
	)
	(gr_line
		(start 121.662444 -279.43429)
		(end 121.665238 -279.435814)
		(stroke
			(width 0.05715)
			(type default)
		)
		(layer "In11.Cu")
	)
	(gr_line
		(start 121.756932 -280.244296)
		(end 121.755662 -280.245058)
		(stroke
			(width 0.05715)
			(type default)
		)
		(layer "In11.Cu")
	)
	(gr_line
		(start 121.75744 -280.244042)
		(end 121.756932 -280.244296)
		(stroke
			(width 0.05715)
			(type default)
		)
		(layer "In11.Cu")
	)
	(gr_line
		(start 121.757694 -279.268936)
		(end 121.75871 -279.269444)
		(stroke
			(width 0.05715)
			(type default)
		)
		(layer "In11.Cu")
	)
	(gr_line
		(start 121.75871 -279.269444)
		(end 121.760234 -279.27046)
		(stroke
			(width 0.05715)
			(type default)
		)
		(layer "In11.Cu")
	)
	(gr_line
		(start 121.760234 -279.27046)
		(end 121.76125 -279.270968)
		(stroke
			(width 0.05715)
			(type default)
		)
		(layer "In11.Cu")
	)
	(gr_line
		(start 121.76125 -279.270968)
		(end 121.76633 -279.274016)
		(stroke
			(width 0.05715)
			(type default)
		)
		(layer "In11.Cu")
	)
	(gr_line
		(start 121.884186 -412.570168)
		(end 121.606564 -412.84779)
		(stroke
			(width 0.07112)
			(type default)
		)
		(layer "In11.Cu")
	)
	(gr_line
		(start 121.885964 -296.584116)
		(end 121.885964 -296.612564)
		(stroke
			(width 0.05715)
			(type default)
		)
		(layer "In11.Cu")
	)
	(gr_arc
		(start 121.911872 -295.598088)
		(mid 121.910605 -295.596435)
		(end 121.909332 -295.594786)
		(stroke
			(width 0.05715)
			(type default)
		)
		(layer "In11.Cu")
	)
	(gr_arc
		(start 121.913904 -295.600628)
		(mid 121.91289 -295.599357)
		(end 121.911872 -295.598088)
		(stroke
			(width 0.05715)
			(type default)
		)
		(layer "In11.Cu")
	)
	(gr_line
		(start 121.931684 -296.538396)
		(end 121.885964 -296.584116)
		(stroke
			(width 0.05715)
			(type default)
		)
		(layer "In11.Cu")
	)
	(gr_arc
		(start 122.084846 -294.795194)
		(mid 122.088771 -294.798005)
		(end 122.09272 -294.800782)
		(stroke
			(width 0.05715)
			(type default)
		)
		(layer "In11.Cu")
	)
	(gr_arc
		(start 122.084846 -293.175182)
		(mid 122.088771 -293.177993)
		(end 122.09272 -293.18077)
		(stroke
			(width 0.05715)
			(type default)
		)
		(layer "In11.Cu")
	)
	(gr_arc
		(start 122.084846 -289.935158)
		(mid 122.088771 -289.937969)
		(end 122.09272 -289.940746)
		(stroke
			(width 0.05715)
			(type default)
		)
		(layer "In11.Cu")
	)
	(gr_arc
		(start 122.084846 -281.835352)
		(mid 122.088771 -281.838163)
		(end 122.09272 -281.84094)
		(stroke
			(width 0.05715)
			(type default)
		)
		(layer "In11.Cu")
	)
	(gr_arc
		(start 122.084846 -278.595328)
		(mid 122.088771 -278.598139)
		(end 122.09272 -278.600916)
		(stroke
			(width 0.05715)
			(type default)
		)
		(layer "In11.Cu")
	)
	(gr_arc
		(start 122.084846 -276.975316)
		(mid 122.088771 -276.978127)
		(end 122.09272 -276.980904)
		(stroke
			(width 0.05715)
			(type default)
		)
		(layer "In11.Cu")
	)
	(gr_line
		(start 122.09272 -294.800782)
		(end 122.099578 -294.804846)
		(stroke
			(width 0.05715)
			(type default)
		)
		(layer "In11.Cu")
	)
	(gr_line
		(start 122.09272 -293.18077)
		(end 122.099578 -293.184834)
		(stroke
			(width 0.05715)
			(type default)
		)
		(layer "In11.Cu")
	)
	(gr_line
		(start 122.09272 -289.940746)
		(end 122.099578 -289.94481)
		(stroke
			(width 0.05715)
			(type default)
		)
		(layer "In11.Cu")
	)
	(gr_line
		(start 122.09272 -281.84094)
		(end 122.099578 -281.845004)
		(stroke
			(width 0.05715)
			(type default)
		)
		(layer "In11.Cu")
	)
	(gr_line
		(start 122.09272 -278.600916)
		(end 122.099578 -278.60498)
		(stroke
			(width 0.05715)
			(type default)
		)
		(layer "In11.Cu")
	)
	(gr_line
		(start 122.09272 -276.980904)
		(end 122.099578 -276.984968)
		(stroke
			(width 0.05715)
			(type default)
		)
		(layer "In11.Cu")
	)
	(gr_line
		(start 122.099578 -294.804846)
		(end 122.10034 -294.805354)
		(stroke
			(width 0.05715)
			(type default)
		)
		(layer "In11.Cu")
	)
	(gr_line
		(start 122.099578 -293.184834)
		(end 122.10034 -293.185342)
		(stroke
			(width 0.05715)
			(type default)
		)
		(layer "In11.Cu")
	)
	(gr_line
		(start 122.099578 -289.94481)
		(end 122.10034 -289.945318)
		(stroke
			(width 0.05715)
			(type default)
		)
		(layer "In11.Cu")
	)
	(gr_line
		(start 122.099578 -281.845004)
		(end 122.10034 -281.845512)
		(stroke
			(width 0.05715)
			(type default)
		)
		(layer "In11.Cu")
	)
	(gr_line
		(start 122.099578 -278.60498)
		(end 122.10034 -278.605488)
		(stroke
			(width 0.05715)
			(type default)
		)
		(layer "In11.Cu")
	)
	(gr_line
		(start 122.099578 -276.984968)
		(end 122.10034 -276.985476)
		(stroke
			(width 0.05715)
			(type default)
		)
		(layer "In11.Cu")
	)
	(gr_line
		(start 122.10034 -294.805354)
		(end 122.101102 -294.805862)
		(stroke
			(width 0.05715)
			(type default)
		)
		(layer "In11.Cu")
	)
	(gr_line
		(start 122.10034 -293.185342)
		(end 122.101102 -293.18585)
		(stroke
			(width 0.05715)
			(type default)
		)
		(layer "In11.Cu")
	)
	(gr_line
		(start 122.10034 -289.945318)
		(end 122.101102 -289.945826)
		(stroke
			(width 0.05715)
			(type default)
		)
		(layer "In11.Cu")
	)
	(gr_line
		(start 122.10034 -281.845512)
		(end 122.101102 -281.84602)
		(stroke
			(width 0.05715)
			(type default)
		)
		(layer "In11.Cu")
	)
	(gr_line
		(start 122.10034 -278.605488)
		(end 122.101102 -278.605996)
		(stroke
			(width 0.05715)
			(type default)
		)
		(layer "In11.Cu")
	)
	(gr_line
		(start 122.10034 -276.985476)
		(end 122.101102 -276.985984)
		(stroke
			(width 0.05715)
			(type default)
		)
		(layer "In11.Cu")
	)
	(gr_line
		(start 122.122184 -296.538396)
		(end 122.167904 -296.584116)
		(stroke
			(width 0.05715)
			(type default)
		)
		(layer "In11.Cu")
	)
	(gr_line
		(start 122.12574 -292.232334)
		(end 122.124724 -292.233096)
		(stroke
			(width 0.05715)
			(type default)
		)
		(layer "In11.Cu")
	)
	(gr_line
		(start 122.12574 -290.612322)
		(end 122.124724 -290.613084)
		(stroke
			(width 0.05715)
			(type default)
		)
		(layer "In11.Cu")
	)
	(gr_line
		(start 122.12574 -288.99231)
		(end 122.124724 -288.993072)
		(stroke
			(width 0.05715)
			(type default)
		)
		(layer "In11.Cu")
	)
	(gr_line
		(start 122.12574 -285.75254)
		(end 122.124724 -285.753302)
		(stroke
			(width 0.05715)
			(type default)
		)
		(layer "In11.Cu")
	)
	(gr_line
		(start 122.12574 -284.132528)
		(end 122.124724 -284.13329)
		(stroke
			(width 0.05715)
			(type default)
		)
		(layer "In11.Cu")
	)
	(gr_line
		(start 122.12574 -282.512516)
		(end 122.124724 -282.513278)
		(stroke
			(width 0.05715)
			(type default)
		)
		(layer "In11.Cu")
	)
	(gr_line
		(start 122.12574 -280.892504)
		(end 122.124724 -280.893266)
		(stroke
			(width 0.05715)
			(type default)
		)
		(layer "In11.Cu")
	)
	(gr_line
		(start 122.12574 -277.65248)
		(end 122.124724 -277.653242)
		(stroke
			(width 0.05715)
			(type default)
		)
		(layer "In11.Cu")
	)
	(gr_line
		(start 122.12574 -276.032468)
		(end 122.124724 -276.03323)
		(stroke
			(width 0.05715)
			(type default)
		)
		(layer "In11.Cu")
	)
	(gr_line
		(start 122.127518 -292.231318)
		(end 122.12574 -292.232334)
		(stroke
			(width 0.05715)
			(type default)
		)
		(layer "In11.Cu")
	)
	(gr_line
		(start 122.127518 -290.611306)
		(end 122.12574 -290.612322)
		(stroke
			(width 0.05715)
			(type default)
		)
		(layer "In11.Cu")
	)
	(gr_line
		(start 122.127518 -288.991294)
		(end 122.12574 -288.99231)
		(stroke
			(width 0.05715)
			(type default)
		)
		(layer "In11.Cu")
	)
	(gr_line
		(start 122.127518 -285.751524)
		(end 122.12574 -285.75254)
		(stroke
			(width 0.05715)
			(type default)
		)
		(layer "In11.Cu")
	)
	(gr_line
		(start 122.127518 -284.131512)
		(end 122.12574 -284.132528)
		(stroke
			(width 0.05715)
			(type default)
		)
		(layer "In11.Cu")
	)
	(gr_line
		(start 122.127518 -282.5115)
		(end 122.12574 -282.512516)
		(stroke
			(width 0.05715)
			(type default)
		)
		(layer "In11.Cu")
	)
	(gr_line
		(start 122.127518 -280.891488)
		(end 122.12574 -280.892504)
		(stroke
			(width 0.05715)
			(type default)
		)
		(layer "In11.Cu")
	)
	(gr_line
		(start 122.127518 -277.651464)
		(end 122.12574 -277.65248)
		(stroke
			(width 0.05715)
			(type default)
		)
		(layer "In11.Cu")
	)
	(gr_line
		(start 122.127518 -276.031452)
		(end 122.12574 -276.032468)
		(stroke
			(width 0.05715)
			(type default)
		)
		(layer "In11.Cu")
	)
	(gr_line
		(start 122.13082 -292.229286)
		(end 122.129296 -292.230302)
		(stroke
			(width 0.05715)
			(type default)
		)
		(layer "In11.Cu")
	)
	(gr_line
		(start 122.13082 -290.609274)
		(end 122.129296 -290.61029)
		(stroke
			(width 0.05715)
			(type default)
		)
		(layer "In11.Cu")
	)
	(gr_line
		(start 122.13082 -288.989262)
		(end 122.129296 -288.990278)
		(stroke
			(width 0.05715)
			(type default)
		)
		(layer "In11.Cu")
	)
	(gr_line
		(start 122.13082 -285.749492)
		(end 122.129296 -285.750508)
		(stroke
			(width 0.05715)
			(type default)
		)
		(layer "In11.Cu")
	)
	(gr_line
		(start 122.13082 -284.12948)
		(end 122.129296 -284.130496)
		(stroke
			(width 0.05715)
			(type default)
		)
		(layer "In11.Cu")
	)
	(gr_line
		(start 122.13082 -282.509468)
		(end 122.129296 -282.510484)
		(stroke
			(width 0.05715)
			(type default)
		)
		(layer "In11.Cu")
	)
	(gr_line
		(start 122.13082 -280.889456)
		(end 122.129296 -280.890472)
		(stroke
			(width 0.05715)
			(type default)
		)
		(layer "In11.Cu")
	)
	(gr_line
		(start 122.13082 -277.649432)
		(end 122.129296 -277.650448)
		(stroke
			(width 0.05715)
			(type default)
		)
		(layer "In11.Cu")
	)
	(gr_line
		(start 122.13082 -276.02942)
		(end 122.129296 -276.030436)
		(stroke
			(width 0.05715)
			(type default)
		)
		(layer "In11.Cu")
	)
	(gr_line
		(start 122.131836 -293.84879)
		(end 122.13082 -293.849298)
		(stroke
			(width 0.05715)
			(type default)
		)
		(layer "In11.Cu")
	)
	(gr_line
		(start 122.131836 -292.228778)
		(end 122.13082 -292.229286)
		(stroke
			(width 0.05715)
			(type default)
		)
		(layer "In11.Cu")
	)
	(gr_line
		(start 122.131836 -290.608766)
		(end 122.13082 -290.609274)
		(stroke
			(width 0.05715)
			(type default)
		)
		(layer "In11.Cu")
	)
	(gr_line
		(start 122.131836 -288.988754)
		(end 122.13082 -288.989262)
		(stroke
			(width 0.05715)
			(type default)
		)
		(layer "In11.Cu")
	)
	(gr_line
		(start 122.131836 -285.748984)
		(end 122.13082 -285.749492)
		(stroke
			(width 0.05715)
			(type default)
		)
		(layer "In11.Cu")
	)
	(gr_line
		(start 122.131836 -284.128972)
		(end 122.13082 -284.12948)
		(stroke
			(width 0.05715)
			(type default)
		)
		(layer "In11.Cu")
	)
	(gr_line
		(start 122.131836 -282.50896)
		(end 122.13082 -282.509468)
		(stroke
			(width 0.05715)
			(type default)
		)
		(layer "In11.Cu")
	)
	(gr_line
		(start 122.131836 -280.888948)
		(end 122.13082 -280.889456)
		(stroke
			(width 0.05715)
			(type default)
		)
		(layer "In11.Cu")
	)
	(gr_line
		(start 122.131836 -277.648924)
		(end 122.13082 -277.649432)
		(stroke
			(width 0.05715)
			(type default)
		)
		(layer "In11.Cu")
	)
	(gr_line
		(start 122.131836 -276.028912)
		(end 122.13082 -276.02942)
		(stroke
			(width 0.05715)
			(type default)
		)
		(layer "In11.Cu")
	)
	(gr_line
		(start 122.13209 -294.823896)
		(end 122.132598 -294.82415)
		(stroke
			(width 0.05715)
			(type default)
		)
		(layer "In11.Cu")
	)
	(gr_line
		(start 122.13209 -293.203884)
		(end 122.132598 -293.204138)
		(stroke
			(width 0.05715)
			(type default)
		)
		(layer "In11.Cu")
	)
	(gr_line
		(start 122.13209 -289.96386)
		(end 122.132598 -289.964114)
		(stroke
			(width 0.05715)
			(type default)
		)
		(layer "In11.Cu")
	)
	(gr_line
		(start 122.13209 -281.864054)
		(end 122.132598 -281.864308)
		(stroke
			(width 0.05715)
			(type default)
		)
		(layer "In11.Cu")
	)
	(gr_line
		(start 122.13209 -278.62403)
		(end 122.132598 -278.624284)
		(stroke
			(width 0.05715)
			(type default)
		)
		(layer "In11.Cu")
	)
	(gr_line
		(start 122.13209 -277.004018)
		(end 122.132598 -277.004272)
		(stroke
			(width 0.05715)
			(type default)
		)
		(layer "In11.Cu")
	)
	(gr_line
		(start 122.132344 -293.848536)
		(end 122.131836 -293.84879)
		(stroke
			(width 0.05715)
			(type default)
		)
		(layer "In11.Cu")
	)
	(gr_line
		(start 122.132344 -292.228524)
		(end 122.131836 -292.228778)
		(stroke
			(width 0.05715)
			(type default)
		)
		(layer "In11.Cu")
	)
	(gr_line
		(start 122.132344 -290.608512)
		(end 122.131836 -290.608766)
		(stroke
			(width 0.05715)
			(type default)
		)
		(layer "In11.Cu")
	)
	(gr_line
		(start 122.132344 -288.9885)
		(end 122.131836 -288.988754)
		(stroke
			(width 0.05715)
			(type default)
		)
		(layer "In11.Cu")
	)
	(gr_line
		(start 122.132344 -285.74873)
		(end 122.131836 -285.748984)
		(stroke
			(width 0.05715)
			(type default)
		)
		(layer "In11.Cu")
	)
	(gr_line
		(start 122.132344 -284.128718)
		(end 122.131836 -284.128972)
		(stroke
			(width 0.05715)
			(type default)
		)
		(layer "In11.Cu")
	)
	(gr_line
		(start 122.132344 -282.508706)
		(end 122.131836 -282.50896)
		(stroke
			(width 0.05715)
			(type default)
		)
		(layer "In11.Cu")
	)
	(gr_line
		(start 122.132344 -280.888694)
		(end 122.131836 -280.888948)
		(stroke
			(width 0.05715)
			(type default)
		)
		(layer "In11.Cu")
	)
	(gr_line
		(start 122.132344 -277.64867)
		(end 122.131836 -277.648924)
		(stroke
			(width 0.05715)
			(type default)
		)
		(layer "In11.Cu")
	)
	(gr_line
		(start 122.132344 -276.028658)
		(end 122.131836 -276.028912)
		(stroke
			(width 0.05715)
			(type default)
		)
		(layer "In11.Cu")
	)
	(gr_line
		(start 122.132598 -294.82415)
		(end 122.133868 -294.824912)
		(stroke
			(width 0.05715)
			(type default)
		)
		(layer "In11.Cu")
	)
	(gr_line
		(start 122.132598 -293.204138)
		(end 122.133868 -293.2049)
		(stroke
			(width 0.05715)
			(type default)
		)
		(layer "In11.Cu")
	)
	(gr_line
		(start 122.132598 -291.584126)
		(end 122.133868 -291.584888)
		(stroke
			(width 0.05715)
			(type default)
		)
		(layer "In11.Cu")
	)
	(gr_line
		(start 122.132598 -289.964114)
		(end 122.133868 -289.964876)
		(stroke
			(width 0.05715)
			(type default)
		)
		(layer "In11.Cu")
	)
	(gr_line
		(start 122.132598 -285.104332)
		(end 122.133868 -285.105094)
		(stroke
			(width 0.05715)
			(type default)
		)
		(layer "In11.Cu")
	)
	(gr_line
		(start 122.132598 -283.48432)
		(end 122.133868 -283.485082)
		(stroke
			(width 0.05715)
			(type default)
		)
		(layer "In11.Cu")
	)
	(gr_line
		(start 122.132598 -281.864308)
		(end 122.133868 -281.86507)
		(stroke
			(width 0.05715)
			(type default)
		)
		(layer "In11.Cu")
	)
	(gr_line
		(start 122.132598 -278.624284)
		(end 122.133868 -278.625046)
		(stroke
			(width 0.05715)
			(type default)
		)
		(layer "In11.Cu")
	)
	(gr_line
		(start 122.132598 -277.004272)
		(end 122.133868 -277.005034)
		(stroke
			(width 0.05715)
			(type default)
		)
		(layer "In11.Cu")
	)
	(gr_line
		(start 122.133868 -294.824912)
		(end 122.135392 -294.825674)
		(stroke
			(width 0.05715)
			(type default)
		)
		(layer "In11.Cu")
	)
	(gr_line
		(start 122.133868 -293.2049)
		(end 122.135392 -293.205662)
		(stroke
			(width 0.05715)
			(type default)
		)
		(layer "In11.Cu")
	)
	(gr_line
		(start 122.133868 -289.964876)
		(end 122.135392 -289.965638)
		(stroke
			(width 0.05715)
			(type default)
		)
		(layer "In11.Cu")
	)
	(gr_line
		(start 122.133868 -281.86507)
		(end 122.135392 -281.865832)
		(stroke
			(width 0.05715)
			(type default)
		)
		(layer "In11.Cu")
	)
	(gr_line
		(start 122.133868 -278.625046)
		(end 122.135392 -278.625808)
		(stroke
			(width 0.05715)
			(type default)
		)
		(layer "In11.Cu")
	)
	(gr_line
		(start 122.133868 -277.005034)
		(end 122.135392 -277.005796)
		(stroke
			(width 0.05715)
			(type default)
		)
		(layer "In11.Cu")
	)
	(gr_line
		(start 122.152156 -414.640522)
		(end 122.556778 -415.213546)
		(stroke
			(width 0.07112)
			(type default)
		)
		(layer "In11.Cu")
	)
	(gr_line
		(start 122.167904 -296.584116)
		(end 122.167904 -296.612564)
		(stroke
			(width 0.05715)
			(type default)
		)
		(layer "In11.Cu")
	)
	(gr_line
		(start 122.221752 -333.379572)
		(end 122.221498 -333.379572)
		(stroke
			(width 0.07112)
			(type default)
		)
		(layer "In11.Cu")
	)
	(gr_line
		(start 122.22353 -292.396164)
		(end 122.222006 -292.396926)
		(stroke
			(width 0.05715)
			(type default)
		)
		(layer "In11.Cu")
	)
	(gr_line
		(start 122.22353 -290.776152)
		(end 122.222006 -290.776914)
		(stroke
			(width 0.05715)
			(type default)
		)
		(layer "In11.Cu")
	)
	(gr_line
		(start 122.22353 -289.15614)
		(end 122.222006 -289.156902)
		(stroke
			(width 0.05715)
			(type default)
		)
		(layer "In11.Cu")
	)
	(gr_line
		(start 122.22353 -285.91637)
		(end 122.222006 -285.917132)
		(stroke
			(width 0.05715)
			(type default)
		)
		(layer "In11.Cu")
	)
	(gr_line
		(start 122.22353 -284.296358)
		(end 122.222006 -284.29712)
		(stroke
			(width 0.05715)
			(type default)
		)
		(layer "In11.Cu")
	)
	(gr_line
		(start 122.22353 -282.676346)
		(end 122.222006 -282.677108)
		(stroke
			(width 0.05715)
			(type default)
		)
		(layer "In11.Cu")
	)
	(gr_line
		(start 122.22353 -281.056334)
		(end 122.222006 -281.057096)
		(stroke
			(width 0.05715)
			(type default)
		)
		(layer "In11.Cu")
	)
	(gr_line
		(start 122.22353 -277.81631)
		(end 122.222006 -277.817072)
		(stroke
			(width 0.05715)
			(type default)
		)
		(layer "In11.Cu")
	)
	(gr_line
		(start 122.22353 -276.196298)
		(end 122.222006 -276.19706)
		(stroke
			(width 0.05715)
			(type default)
		)
		(layer "In11.Cu")
	)
	(gr_line
		(start 122.224292 -292.395656)
		(end 122.22353 -292.396164)
		(stroke
			(width 0.05715)
			(type default)
		)
		(layer "In11.Cu")
	)
	(gr_line
		(start 122.224292 -290.775644)
		(end 122.22353 -290.776152)
		(stroke
			(width 0.05715)
			(type default)
		)
		(layer "In11.Cu")
	)
	(gr_line
		(start 122.224292 -289.155632)
		(end 122.22353 -289.15614)
		(stroke
			(width 0.05715)
			(type default)
		)
		(layer "In11.Cu")
	)
	(gr_line
		(start 122.224292 -285.915862)
		(end 122.22353 -285.91637)
		(stroke
			(width 0.05715)
			(type default)
		)
		(layer "In11.Cu")
	)
	(gr_line
		(start 122.224292 -284.29585)
		(end 122.22353 -284.296358)
		(stroke
			(width 0.05715)
			(type default)
		)
		(layer "In11.Cu")
	)
	(gr_line
		(start 122.224292 -282.675838)
		(end 122.22353 -282.676346)
		(stroke
			(width 0.05715)
			(type default)
		)
		(layer "In11.Cu")
	)
	(gr_line
		(start 122.224292 -281.055826)
		(end 122.22353 -281.056334)
		(stroke
			(width 0.05715)
			(type default)
		)
		(layer "In11.Cu")
	)
	(gr_line
		(start 122.224292 -277.815802)
		(end 122.22353 -277.81631)
		(stroke
			(width 0.05715)
			(type default)
		)
		(layer "In11.Cu")
	)
	(gr_line
		(start 122.224292 -276.19579)
		(end 122.22353 -276.196298)
		(stroke
			(width 0.05715)
			(type default)
		)
		(layer "In11.Cu")
	)
	(gr_line
		(start 122.225816 -292.394894)
		(end 122.224292 -292.395656)
		(stroke
			(width 0.05715)
			(type default)
		)
		(layer "In11.Cu")
	)
	(gr_line
		(start 122.225816 -290.774882)
		(end 122.224292 -290.775644)
		(stroke
			(width 0.05715)
			(type default)
		)
		(layer "In11.Cu")
	)
	(gr_line
		(start 122.225816 -289.15487)
		(end 122.224292 -289.155632)
		(stroke
			(width 0.05715)
			(type default)
		)
		(layer "In11.Cu")
	)
	(gr_line
		(start 122.225816 -285.9151)
		(end 122.224292 -285.915862)
		(stroke
			(width 0.05715)
			(type default)
		)
		(layer "In11.Cu")
	)
	(gr_line
		(start 122.225816 -284.295088)
		(end 122.224292 -284.29585)
		(stroke
			(width 0.05715)
			(type default)
		)
		(layer "In11.Cu")
	)
	(gr_line
		(start 122.225816 -282.675076)
		(end 122.224292 -282.675838)
		(stroke
			(width 0.05715)
			(type default)
		)
		(layer "In11.Cu")
	)
	(gr_line
		(start 122.225816 -281.055064)
		(end 122.224292 -281.055826)
		(stroke
			(width 0.05715)
			(type default)
		)
		(layer "In11.Cu")
	)
	(gr_line
		(start 122.225816 -277.81504)
		(end 122.224292 -277.815802)
		(stroke
			(width 0.05715)
			(type default)
		)
		(layer "In11.Cu")
	)
	(gr_line
		(start 122.225816 -276.195028)
		(end 122.224292 -276.19579)
		(stroke
			(width 0.05715)
			(type default)
		)
		(layer "In11.Cu")
	)
	(gr_line
		(start 122.227086 -294.014144)
		(end 122.225816 -294.014906)
		(stroke
			(width 0.05715)
			(type default)
		)
		(layer "In11.Cu")
	)
	(gr_line
		(start 122.227086 -292.394132)
		(end 122.225816 -292.394894)
		(stroke
			(width 0.05715)
			(type default)
		)
		(layer "In11.Cu")
	)
	(gr_line
		(start 122.227086 -290.77412)
		(end 122.225816 -290.774882)
		(stroke
			(width 0.05715)
			(type default)
		)
		(layer "In11.Cu")
	)
	(gr_line
		(start 122.227086 -289.154108)
		(end 122.225816 -289.15487)
		(stroke
			(width 0.05715)
			(type default)
		)
		(layer "In11.Cu")
	)
	(gr_line
		(start 122.227086 -285.914338)
		(end 122.225816 -285.9151)
		(stroke
			(width 0.05715)
			(type default)
		)
		(layer "In11.Cu")
	)
	(gr_line
		(start 122.227086 -284.294326)
		(end 122.225816 -284.295088)
		(stroke
			(width 0.05715)
			(type default)
		)
		(layer "In11.Cu")
	)
	(gr_line
		(start 122.227086 -282.674314)
		(end 122.225816 -282.675076)
		(stroke
			(width 0.05715)
			(type default)
		)
		(layer "In11.Cu")
	)
	(gr_line
		(start 122.227086 -281.054302)
		(end 122.225816 -281.055064)
		(stroke
			(width 0.05715)
			(type default)
		)
		(layer "In11.Cu")
	)
	(gr_line
		(start 122.227086 -277.814278)
		(end 122.225816 -277.81504)
		(stroke
			(width 0.05715)
			(type default)
		)
		(layer "In11.Cu")
	)
	(gr_line
		(start 122.227086 -276.194266)
		(end 122.225816 -276.195028)
		(stroke
			(width 0.05715)
			(type default)
		)
		(layer "In11.Cu")
	)
	(gr_line
		(start 122.22734 -291.418518)
		(end 122.227848 -291.418772)
		(stroke
			(width 0.05715)
			(type default)
		)
		(layer "In11.Cu")
	)
	(gr_line
		(start 122.22734 -284.938724)
		(end 122.227848 -284.938978)
		(stroke
			(width 0.05715)
			(type default)
		)
		(layer "In11.Cu")
	)
	(gr_line
		(start 122.22734 -283.318712)
		(end 122.227848 -283.318966)
		(stroke
			(width 0.05715)
			(type default)
		)
		(layer "In11.Cu")
	)
	(gr_line
		(start 122.227594 -292.393878)
		(end 122.227086 -292.394132)
		(stroke
			(width 0.05715)
			(type default)
		)
		(layer "In11.Cu")
	)
	(gr_line
		(start 122.227594 -290.773866)
		(end 122.227086 -290.77412)
		(stroke
			(width 0.05715)
			(type default)
		)
		(layer "In11.Cu")
	)
	(gr_line
		(start 122.227594 -289.153854)
		(end 122.227086 -289.154108)
		(stroke
			(width 0.05715)
			(type default)
		)
		(layer "In11.Cu")
	)
	(gr_line
		(start 122.227594 -285.914084)
		(end 122.227086 -285.914338)
		(stroke
			(width 0.05715)
			(type default)
		)
		(layer "In11.Cu")
	)
	(gr_line
		(start 122.227594 -284.294072)
		(end 122.227086 -284.294326)
		(stroke
			(width 0.05715)
			(type default)
		)
		(layer "In11.Cu")
	)
	(gr_line
		(start 122.227594 -282.67406)
		(end 122.227086 -282.674314)
		(stroke
			(width 0.05715)
			(type default)
		)
		(layer "In11.Cu")
	)
	(gr_line
		(start 122.227594 -281.054048)
		(end 122.227086 -281.054302)
		(stroke
			(width 0.05715)
			(type default)
		)
		(layer "In11.Cu")
	)
	(gr_line
		(start 122.227594 -277.814024)
		(end 122.227086 -277.814278)
		(stroke
			(width 0.05715)
			(type default)
		)
		(layer "In11.Cu")
	)
	(gr_line
		(start 122.227594 -276.194012)
		(end 122.227086 -276.194266)
		(stroke
			(width 0.05715)
			(type default)
		)
		(layer "In11.Cu")
	)
	(gr_line
		(start 122.227848 -294.658796)
		(end 122.228864 -294.659304)
		(stroke
			(width 0.05715)
			(type default)
		)
		(layer "In11.Cu")
	)
	(gr_line
		(start 122.227848 -293.038784)
		(end 122.228864 -293.039292)
		(stroke
			(width 0.05715)
			(type default)
		)
		(layer "In11.Cu")
	)
	(gr_line
		(start 122.227848 -291.418772)
		(end 122.228864 -291.41928)
		(stroke
			(width 0.05715)
			(type default)
		)
		(layer "In11.Cu")
	)
	(gr_line
		(start 122.227848 -289.79876)
		(end 122.228864 -289.799268)
		(stroke
			(width 0.05715)
			(type default)
		)
		(layer "In11.Cu")
	)
	(gr_line
		(start 122.227848 -284.938978)
		(end 122.228864 -284.939486)
		(stroke
			(width 0.05715)
			(type default)
		)
		(layer "In11.Cu")
	)
	(gr_line
		(start 122.227848 -283.318966)
		(end 122.228864 -283.319474)
		(stroke
			(width 0.05715)
			(type default)
		)
		(layer "In11.Cu")
	)
	(gr_line
		(start 122.227848 -281.698954)
		(end 122.228864 -281.699462)
		(stroke
			(width 0.05715)
			(type default)
		)
		(layer "In11.Cu")
	)
	(gr_line
		(start 122.227848 -278.45893)
		(end 122.228864 -278.459438)
		(stroke
			(width 0.05715)
			(type default)
		)
		(layer "In11.Cu")
	)
	(gr_line
		(start 122.227848 -276.838918)
		(end 122.228864 -276.839426)
		(stroke
			(width 0.05715)
			(type default)
		)
		(layer "In11.Cu")
	)
	(gr_line
		(start 122.228864 -294.659304)
		(end 122.230388 -294.66032)
		(stroke
			(width 0.05715)
			(type default)
		)
		(layer "In11.Cu")
	)
	(gr_line
		(start 122.228864 -293.039292)
		(end 122.230388 -293.040308)
		(stroke
			(width 0.05715)
			(type default)
		)
		(layer "In11.Cu")
	)
	(gr_line
		(start 122.228864 -289.799268)
		(end 122.230388 -289.800284)
		(stroke
			(width 0.05715)
			(type default)
		)
		(layer "In11.Cu")
	)
	(gr_line
		(start 122.228864 -281.699462)
		(end 122.230388 -281.700478)
		(stroke
			(width 0.05715)
			(type default)
		)
		(layer "In11.Cu")
	)
	(gr_line
		(start 122.228864 -278.459438)
		(end 122.230388 -278.460454)
		(stroke
			(width 0.05715)
			(type default)
		)
		(layer "In11.Cu")
	)
	(gr_line
		(start 122.228864 -276.839426)
		(end 122.230388 -276.840442)
		(stroke
			(width 0.05715)
			(type default)
		)
		(layer "In11.Cu")
	)
	(gr_line
		(start 122.232166 -294.661336)
		(end 122.233436 -294.662098)
		(stroke
			(width 0.05715)
			(type default)
		)
		(layer "In11.Cu")
	)
	(gr_line
		(start 122.232166 -293.041324)
		(end 122.233436 -293.042086)
		(stroke
			(width 0.05715)
			(type default)
		)
		(layer "In11.Cu")
	)
	(gr_line
		(start 122.232166 -289.8013)
		(end 122.233436 -289.802062)
		(stroke
			(width 0.05715)
			(type default)
		)
		(layer "In11.Cu")
	)
	(gr_line
		(start 122.232166 -281.701494)
		(end 122.233436 -281.702256)
		(stroke
			(width 0.05715)
			(type default)
		)
		(layer "In11.Cu")
	)
	(gr_line
		(start 122.232166 -278.46147)
		(end 122.233436 -278.462232)
		(stroke
			(width 0.05715)
			(type default)
		)
		(layer "In11.Cu")
	)
	(gr_line
		(start 122.232166 -276.841458)
		(end 122.233436 -276.84222)
		(stroke
			(width 0.05715)
			(type default)
		)
		(layer "In11.Cu")
	)
	(gr_line
		(start 122.234706 -294.66286)
		(end 122.236484 -294.663876)
		(stroke
			(width 0.05715)
			(type default)
		)
		(layer "In11.Cu")
	)
	(gr_line
		(start 122.234706 -293.042848)
		(end 122.236484 -293.043864)
		(stroke
			(width 0.05715)
			(type default)
		)
		(layer "In11.Cu")
	)
	(gr_line
		(start 122.234706 -289.802824)
		(end 122.236484 -289.80384)
		(stroke
			(width 0.05715)
			(type default)
		)
		(layer "In11.Cu")
	)
	(gr_line
		(start 122.234706 -281.703018)
		(end 122.236484 -281.704034)
		(stroke
			(width 0.05715)
			(type default)
		)
		(layer "In11.Cu")
	)
	(gr_line
		(start 122.234706 -278.462994)
		(end 122.236484 -278.46401)
		(stroke
			(width 0.05715)
			(type default)
		)
		(layer "In11.Cu")
	)
	(gr_line
		(start 122.234706 -276.842982)
		(end 122.236484 -276.843998)
		(stroke
			(width 0.05715)
			(type default)
		)
		(layer "In11.Cu")
	)
	(gr_line
		(start 122.271282 -373.719344)
		(end 122.027696 -373.96293)
		(stroke
			(width 0.07112)
			(type default)
		)
		(layer "In11.Cu")
	)
	(gr_arc
		(start 122.271282 -373.719344)
		(mid 122.302715 -373.67493)
		(end 122.31751 -373.62257)
		(stroke
			(width 0.07112)
			(type default)
		)
		(layer "In11.Cu")
	)
	(gr_line
		(start 122.319542 -295.146222)
		(end 122.319288 -295.146222)
		(stroke
			(width 0.05715)
			(type default)
		)
		(layer "In11.Cu")
	)
	(gr_line
		(start 122.384312 -414.478216)
		(end 122.573542 -414.510728)
		(stroke
			(width 0.07112)
			(type default)
		)
		(layer "In11.Cu")
	)
	(gr_line
		(start 122.414792 -278.13635)
		(end 122.712734 -278.13635)
		(stroke
			(width 0.05715)
			(type default)
		)
		(layer "In11.Cu")
	)
	(gr_line
		(start 122.414792 -276.516338)
		(end 122.712734 -276.516338)
		(stroke
			(width 0.05715)
			(type default)
		)
		(layer "In11.Cu")
	)
	(gr_line
		(start 122.414792 -274.896326)
		(end 122.712734 -274.896326)
		(stroke
			(width 0.05715)
			(type default)
		)
		(layer "In11.Cu")
	)
	(gr_line
		(start 122.510296 -295.146222)
		(end 122.510042 -295.146222)
		(stroke
			(width 0.05715)
			(type default)
		)
		(layer "In11.Cu")
	)
	(gr_line
		(start 122.573542 -414.510728)
		(end 122.820176 -414.85947)
		(stroke
			(width 0.07112)
			(type default)
		)
		(layer "In11.Cu")
	)
	(gr_arc
		(start 122.601482 -373.62257)
		(mid 122.616336 -373.674904)
		(end 122.64771 -373.719344)
		(stroke
			(width 0.07112)
			(type default)
		)
		(layer "In11.Cu")
	)
	(gr_line
		(start 122.602498 -295.634156)
		(end 122.605292 -295.63568)
		(stroke
			(width 0.05715)
			(type default)
		)
		(layer "In11.Cu")
	)
	(gr_line
		(start 122.605292 -295.63568)
		(end 122.606054 -295.636188)
		(stroke
			(width 0.05715)
			(type default)
		)
		(layer "In11.Cu")
	)
	(gr_line
		(start 122.64771 -373.719344)
		(end 122.891296 -373.96293)
		(stroke
			(width 0.07112)
			(type default)
		)
		(layer "In11.Cu")
	)
	(gr_line
		(start 122.69724 -295.468548)
		(end 122.697748 -295.468802)
		(stroke
			(width 0.05715)
			(type default)
		)
		(layer "In11.Cu")
	)
	(gr_line
		(start 122.697748 -295.468802)
		(end 122.698764 -295.46931)
		(stroke
			(width 0.05715)
			(type default)
		)
		(layer "In11.Cu")
	)
	(gr_line
		(start 122.698764 -295.46931)
		(end 122.700288 -295.470326)
		(stroke
			(width 0.05715)
			(type default)
		)
		(layer "In11.Cu")
	)
	(gr_line
		(start 122.700288 -295.470326)
		(end 122.701304 -295.470834)
		(stroke
			(width 0.05715)
			(type default)
		)
		(layer "In11.Cu")
	)
	(gr_line
		(start 122.701304 -295.470834)
		(end 122.706638 -295.473882)
		(stroke
			(width 0.05715)
			(type default)
		)
		(layer "In11.Cu")
	)
	(gr_line
		(start 122.712734 -278.13635)
		(end 122.795538 -278.219154)
		(stroke
			(width 0.05715)
			(type default)
		)
		(layer "In11.Cu")
	)
	(gr_line
		(start 122.712734 -276.516338)
		(end 122.795538 -276.599142)
		(stroke
			(width 0.05715)
			(type default)
		)
		(layer "In11.Cu")
	)
	(gr_line
		(start 122.712734 -274.896326)
		(end 122.782076 -274.965668)
		(stroke
			(width 0.05715)
			(type default)
		)
		(layer "In11.Cu")
	)
	(gr_arc
		(start 122.795538 -278.219154)
		(mid 122.79733 -278.230476)
		(end 122.799348 -278.24176)
		(stroke
			(width 0.05715)
			(type default)
		)
		(layer "In11.Cu")
	)
	(gr_arc
		(start 122.795538 -276.599142)
		(mid 122.79733 -276.610464)
		(end 122.799348 -276.621748)
		(stroke
			(width 0.05715)
			(type default)
		)
		(layer "In11.Cu")
	)
	(gr_line
		(start 122.820176 -414.85947)
		(end 122.78741 -415.049208)
		(stroke
			(width 0.07112)
			(type default)
		)
		(layer "In11.Cu")
	)
	(gr_line
		(start 122.83059 -296.584116)
		(end 122.83059 -296.612564)
		(stroke
			(width 0.05715)
			(type default)
		)
		(layer "In11.Cu")
	)
	(gr_line
		(start 122.87631 -296.538396)
		(end 122.83059 -296.584116)
		(stroke
			(width 0.05715)
			(type default)
		)
		(layer "In11.Cu")
	)
	(gr_arc
		(start 122.97029 -275.00199)
		(mid 122.972311 -274.990579)
		(end 122.9741 -274.97913)
		(stroke
			(width 0.05715)
			(type default)
		)
		(layer "In11.Cu")
	)
	(gr_arc
		(start 123.022106 -288.313368)
		(mid 123.025272 -288.315666)
		(end 123.028456 -288.31794)
		(stroke
			(width 0.05715)
			(type default)
		)
		(layer "In11.Cu")
	)
	(gr_arc
		(start 123.024646 -278.595328)
		(mid 123.028698 -278.59814)
		(end 123.032774 -278.600916)
		(stroke
			(width 0.05715)
			(type default)
		)
		(layer "In11.Cu")
	)
	(gr_arc
		(start 123.024646 -276.975316)
		(mid 123.028698 -276.978128)
		(end 123.032774 -276.980904)
		(stroke
			(width 0.05715)
			(type default)
		)
		(layer "In11.Cu")
	)
	(gr_arc
		(start 123.0249 -283.455364)
		(mid 123.028825 -283.458175)
		(end 123.032774 -283.460952)
		(stroke
			(width 0.05715)
			(type default)
		)
		(layer "In11.Cu")
	)
	(gr_arc
		(start 123.029218 -288.318448)
		(mid 123.030994 -288.319721)
		(end 123.032774 -288.320988)
		(stroke
			(width 0.05715)
			(type default)
		)
		(layer "In11.Cu")
	)
	(gr_line
		(start 123.032774 -288.320988)
		(end 123.03887 -288.324544)
		(stroke
			(width 0.05715)
			(type default)
		)
		(layer "In11.Cu")
	)
	(gr_line
		(start 123.032774 -283.460952)
		(end 123.039632 -283.465016)
		(stroke
			(width 0.05715)
			(type default)
		)
		(layer "In11.Cu")
	)
	(gr_line
		(start 123.032774 -278.600916)
		(end 123.039632 -278.60498)
		(stroke
			(width 0.05715)
			(type default)
		)
		(layer "In11.Cu")
	)
	(gr_line
		(start 123.032774 -276.980904)
		(end 123.039632 -276.984968)
		(stroke
			(width 0.05715)
			(type default)
		)
		(layer "In11.Cu")
	)
	(gr_line
		(start 123.03887 -288.324544)
		(end 123.039124 -288.324544)
		(stroke
			(width 0.05715)
			(type default)
		)
		(layer "In11.Cu")
	)
	(gr_line
		(start 123.039632 -283.465016)
		(end 123.040394 -283.465524)
		(stroke
			(width 0.05715)
			(type default)
		)
		(layer "In11.Cu")
	)
	(gr_line
		(start 123.039632 -278.60498)
		(end 123.040394 -278.605488)
		(stroke
			(width 0.05715)
			(type default)
		)
		(layer "In11.Cu")
	)
	(gr_line
		(start 123.039632 -276.984968)
		(end 123.040394 -276.985476)
		(stroke
			(width 0.05715)
			(type default)
		)
		(layer "In11.Cu")
	)
	(gr_line
		(start 123.040394 -283.465524)
		(end 123.041156 -283.466032)
		(stroke
			(width 0.05715)
			(type default)
		)
		(layer "In11.Cu")
	)
	(gr_line
		(start 123.040394 -278.605488)
		(end 123.041156 -278.605996)
		(stroke
			(width 0.05715)
			(type default)
		)
		(layer "In11.Cu")
	)
	(gr_line
		(start 123.040394 -276.985476)
		(end 123.041156 -276.985984)
		(stroke
			(width 0.05715)
			(type default)
		)
		(layer "In11.Cu")
	)
	(gr_line
		(start 123.056904 -278.13635)
		(end 122.987562 -278.205692)
		(stroke
			(width 0.05715)
			(type default)
		)
		(layer "In11.Cu")
	)
	(gr_line
		(start 123.056904 -276.516338)
		(end 122.987562 -276.58568)
		(stroke
			(width 0.05715)
			(type default)
		)
		(layer "In11.Cu")
	)
	(gr_line
		(start 123.056904 -274.896326)
		(end 122.9741 -274.97913)
		(stroke
			(width 0.05715)
			(type default)
		)
		(layer "In11.Cu")
	)
	(gr_line
		(start 123.06681 -296.538396)
		(end 123.11253 -296.584116)
		(stroke
			(width 0.05715)
			(type default)
		)
		(layer "In11.Cu")
	)
	(gr_line
		(start 123.07189 -277.003764)
		(end 123.072144 -277.004018)
		(stroke
			(width 0.05715)
			(type default)
		)
		(layer "In11.Cu")
	)
	(gr_line
		(start 123.072144 -278.62403)
		(end 123.072652 -278.624284)
		(stroke
			(width 0.05715)
			(type default)
		)
		(layer "In11.Cu")
	)
	(gr_line
		(start 123.072144 -277.004018)
		(end 123.072652 -277.004272)
		(stroke
			(width 0.05715)
			(type default)
		)
		(layer "In11.Cu")
	)
	(gr_line
		(start 123.072652 -291.584126)
		(end 123.073922 -291.584888)
		(stroke
			(width 0.05715)
			(type default)
		)
		(layer "In11.Cu")
	)
	(gr_line
		(start 123.072652 -278.624284)
		(end 123.072652 -278.62403)
		(stroke
			(width 0.05715)
			(type default)
		)
		(layer "In11.Cu")
	)
	(gr_line
		(start 123.072652 -277.004272)
		(end 123.075446 -277.005796)
		(stroke
			(width 0.05715)
			(type default)
		)
		(layer "In11.Cu")
	)
	(gr_line
		(start 123.074684 -293.205408)
		(end 123.075192 -293.205408)
		(stroke
			(width 0.05715)
			(type default)
		)
		(layer "In11.Cu")
	)
	(gr_line
		(start 123.074684 -289.965384)
		(end 123.075192 -289.965384)
		(stroke
			(width 0.05715)
			(type default)
		)
		(layer "In11.Cu")
	)
	(gr_line
		(start 123.074684 -285.105602)
		(end 123.075192 -285.105602)
		(stroke
			(width 0.05715)
			(type default)
		)
		(layer "In11.Cu")
	)
	(gr_line
		(start 123.074684 -283.48559)
		(end 123.075192 -283.48559)
		(stroke
			(width 0.05715)
			(type default)
		)
		(layer "In11.Cu")
	)
	(gr_line
		(start 123.074684 -281.865578)
		(end 123.075192 -281.865578)
		(stroke
			(width 0.05715)
			(type default)
		)
		(layer "In11.Cu")
	)
	(gr_line
		(start 123.074938 -288.345372)
		(end 123.075192 -288.345372)
		(stroke
			(width 0.05715)
			(type default)
		)
		(layer "In11.Cu")
	)
	(gr_line
		(start 123.075446 -277.005796)
		(end 123.075954 -277.00605)
		(stroke
			(width 0.05715)
			(type default)
		)
		(layer "In11.Cu")
	)
	(gr_arc
		(start 123.077986 -280.885392)
		(mid 123.078622 -280.885012)
		(end 123.079256 -280.88463)
		(stroke
			(width 0.05715)
			(type default)
		)
		(layer "In11.Cu")
	)
	(gr_line
		(start 123.11253 -296.584116)
		(end 123.11253 -296.612564)
		(stroke
			(width 0.05715)
			(type default)
		)
		(layer "In11.Cu")
	)
	(gr_line
		(start 123.167394 -294.658542)
		(end 123.167902 -294.658796)
		(stroke
			(width 0.05715)
			(type default)
		)
		(layer "In11.Cu")
	)
	(gr_line
		(start 123.167394 -293.03853)
		(end 123.167902 -293.038784)
		(stroke
			(width 0.05715)
			(type default)
		)
		(layer "In11.Cu")
	)
	(gr_line
		(start 123.167394 -291.418518)
		(end 123.167902 -291.418772)
		(stroke
			(width 0.05715)
			(type default)
		)
		(layer "In11.Cu")
	)
	(gr_line
		(start 123.167394 -289.798506)
		(end 123.167902 -289.79876)
		(stroke
			(width 0.05715)
			(type default)
		)
		(layer "In11.Cu")
	)
	(gr_line
		(start 123.167394 -284.938724)
		(end 123.167902 -284.938978)
		(stroke
			(width 0.05715)
			(type default)
		)
		(layer "In11.Cu")
	)
	(gr_line
		(start 123.167394 -281.6987)
		(end 123.167902 -281.698954)
		(stroke
			(width 0.05715)
			(type default)
		)
		(layer "In11.Cu")
	)
	(gr_line
		(start 123.167648 -292.393878)
		(end 123.162314 -292.396926)
		(stroke
			(width 0.05715)
			(type default)
		)
		(layer "In11.Cu")
	)
	(gr_line
		(start 123.167902 -294.658796)
		(end 123.171966 -294.661336)
		(stroke
			(width 0.05715)
			(type default)
		)
		(layer "In11.Cu")
	)
	(gr_line
		(start 123.167902 -293.038784)
		(end 123.17095 -293.040562)
		(stroke
			(width 0.05715)
			(type default)
		)
		(layer "In11.Cu")
	)
	(gr_line
		(start 123.167902 -291.418772)
		(end 123.167902 -291.419026)
		(stroke
			(width 0.05715)
			(type default)
		)
		(layer "In11.Cu")
	)
	(gr_line
		(start 123.167902 -289.79876)
		(end 123.17095 -289.800538)
		(stroke
			(width 0.05715)
			(type default)
		)
		(layer "In11.Cu")
	)
	(gr_line
		(start 123.167902 -284.938978)
		(end 123.17095 -284.940756)
		(stroke
			(width 0.05715)
			(type default)
		)
		(layer "In11.Cu")
	)
	(gr_line
		(start 123.167902 -283.318966)
		(end 123.17095 -283.320744)
		(stroke
			(width 0.05715)
			(type default)
		)
		(layer "In11.Cu")
	)
	(gr_line
		(start 123.167902 -281.698954)
		(end 123.17095 -281.700732)
		(stroke
			(width 0.05715)
			(type default)
		)
		(layer "In11.Cu")
	)
	(gr_line
		(start 123.167902 -281.053794)
		(end 123.167394 -281.054048)
		(stroke
			(width 0.05715)
			(type default)
		)
		(layer "In11.Cu")
	)
	(gr_line
		(start 123.167902 -278.45893)
		(end 123.168918 -278.459438)
		(stroke
			(width 0.05715)
			(type default)
		)
		(layer "In11.Cu")
	)
	(gr_line
		(start 123.167902 -276.838918)
		(end 123.171204 -276.84095)
		(stroke
			(width 0.05715)
			(type default)
		)
		(layer "In11.Cu")
	)
	(gr_line
		(start 123.17095 -294.011858)
		(end 123.167394 -294.01389)
		(stroke
			(width 0.05715)
			(type default)
		)
		(layer "In11.Cu")
	)
	(gr_line
		(start 123.17095 -290.771834)
		(end 123.167394 -290.773866)
		(stroke
			(width 0.05715)
			(type default)
		)
		(layer "In11.Cu")
	)
	(gr_line
		(start 123.17095 -289.151822)
		(end 123.167394 -289.153854)
		(stroke
			(width 0.05715)
			(type default)
		)
		(layer "In11.Cu")
	)
	(gr_line
		(start 123.17095 -285.912052)
		(end 123.167394 -285.914084)
		(stroke
			(width 0.05715)
			(type default)
		)
		(layer "In11.Cu")
	)
	(gr_line
		(start 123.17095 -284.29204)
		(end 123.167394 -284.294072)
		(stroke
			(width 0.05715)
			(type default)
		)
		(layer "In11.Cu")
	)
	(gr_line
		(start 123.17095 -282.672028)
		(end 123.167394 -282.67406)
		(stroke
			(width 0.05715)
			(type default)
		)
		(layer "In11.Cu")
	)
	(gr_line
		(start 123.182126 -278.467312)
		(end 123.182888 -278.467566)
		(stroke
			(width 0.05715)
			(type default)
		)
		(layer "In11.Cu")
	)
	(gr_line
		(start 123.207526 -416.13455)
		(end 123.274836 -416.230054)
		(stroke
			(width 0.07112)
			(type default)
		)
		(layer "In11.Cu")
	)
	(gr_line
		(start 123.215146 -333.215234)
		(end 123.214892 -333.215234)
		(stroke
			(width 0.07112)
			(type default)
		)
		(layer "In11.Cu")
	)
	(gr_line
		(start 123.259596 -295.146222)
		(end 123.259342 -295.146222)
		(stroke
			(width 0.05715)
			(type default)
		)
		(layer "In11.Cu")
	)
	(gr_line
		(start 123.27509 -416.230054)
		(end 123.274836 -416.230054)
		(stroke
			(width 0.07112)
			(type default)
		)
		(layer "In11.Cu")
	)
	(gr_line
		(start 123.27509 -416.230054)
		(end 123.612148 -416.70732)
		(stroke
			(width 0.07112)
			(type default)
		)
		(layer "In11.Cu")
	)
	(gr_line
		(start 123.354846 -278.13635)
		(end 123.056904 -278.13635)
		(stroke
			(width 0.05715)
			(type default)
		)
		(layer "In11.Cu")
	)
	(gr_line
		(start 123.354846 -276.516338)
		(end 123.056904 -276.516338)
		(stroke
			(width 0.05715)
			(type default)
		)
		(layer "In11.Cu")
	)
	(gr_line
		(start 123.354846 -274.896326)
		(end 123.056904 -274.896326)
		(stroke
			(width 0.05715)
			(type default)
		)
		(layer "In11.Cu")
	)
	(gr_line
		(start 123.439174 -415.97199)
		(end 123.628912 -416.004502)
		(stroke
			(width 0.07112)
			(type default)
		)
		(layer "In11.Cu")
	)
	(gr_line
		(start 123.573286 -277.832058)
		(end 123.57354 -277.832058)
		(stroke
			(width 0.05715)
			(type default)
		)
		(layer "In11.Cu")
	)
	(gr_line
		(start 123.624848 -280.251154)
		(end 123.624594 -280.251408)
		(stroke
			(width 0.05715)
			(type default)
		)
		(layer "In11.Cu")
	)
	(gr_line
		(start 123.628912 -416.004502)
		(end 123.875546 -416.353244)
		(stroke
			(width 0.07112)
			(type default)
		)
		(layer "In11.Cu")
	)
	(gr_line
		(start 123.637294 -295.468548)
		(end 123.638056 -295.468802)
		(stroke
			(width 0.05715)
			(type default)
		)
		(layer "In11.Cu")
	)
	(gr_line
		(start 123.637802 -279.268936)
		(end 123.638818 -279.269444)
		(stroke
			(width 0.05715)
			(type default)
		)
		(layer "In11.Cu")
	)
	(gr_line
		(start 123.729242 -295.956228)
		(end 123.729496 -295.955974)
		(stroke
			(width 0.05715)
			(type default)
		)
		(layer "In11.Cu")
	)
	(gr_line
		(start 123.858274 -417.055554)
		(end 124.262896 -417.628324)
		(stroke
			(width 0.07112)
			(type default)
		)
		(layer "In11.Cu")
	)
	(gr_line
		(start 123.875546 -416.353244)
		(end 123.84278 -416.542728)
		(stroke
			(width 0.07112)
			(type default)
		)
		(layer "In11.Cu")
	)
	(gr_line
		(start 123.92787 -296.87647)
		(end 123.92787 -296.876978)
		(stroke
			(width 0.07112)
			(type default)
		)
		(layer "In11.Cu")
	)
	(gr_line
		(start 123.92787 -296.838116)
		(end 123.92787 -296.866564)
		(stroke
			(width 0.05715)
			(type default)
		)
		(layer "In11.Cu")
	)
	(gr_line
		(start 123.97359 -296.792396)
		(end 123.92787 -296.838116)
		(stroke
			(width 0.05715)
			(type default)
		)
		(layer "In11.Cu")
	)
	(gr_line
		(start 124.020326 -371.2083)
		(end 123.729496 -371.49913)
		(stroke
			(width 0.07112)
			(type default)
		)
		(layer "In11.Cu")
	)
	(gr_line
		(start 124.083826 -412.570168)
		(end 124.374656 -412.860998)
		(stroke
			(width 0.07112)
			(type default)
		)
		(layer "In11.Cu")
	)
	(gr_line
		(start 124.09043 -416.893248)
		(end 124.27966 -416.92576)
		(stroke
			(width 0.07112)
			(type default)
		)
		(layer "In11.Cu")
	)
	(gr_line
		(start 124.16409 -296.792396)
		(end 124.20981 -296.838116)
		(stroke
			(width 0.05715)
			(type default)
		)
		(layer "In11.Cu")
	)
	(gr_line
		(start 124.200666 -342.02243)
		(end 124.20092 -342.022176)
		(stroke
			(width 0.07112)
			(type default)
		)
		(layer "In11.Cu")
	)
	(gr_line
		(start 124.20981 -296.838116)
		(end 124.20981 -296.866564)
		(stroke
			(width 0.05715)
			(type default)
		)
		(layer "In11.Cu")
	)
	(gr_line
		(start 124.210318 -296.905426)
		(end 124.210318 -296.905934)
		(stroke
			(width 0.07112)
			(type default)
		)
		(layer "In11.Cu")
	)
	(gr_line
		(start 124.27966 -416.92576)
		(end 124.526294 -417.274502)
		(stroke
			(width 0.07112)
			(type default)
		)
		(layer "In11.Cu")
	)
	(gr_line
		(start 124.302266 -371.2083)
		(end 124.593096 -371.49913)
		(stroke
			(width 0.07112)
			(type default)
		)
		(layer "In11.Cu")
	)
	(gr_arc
		(start 124.434854 -279.405334)
		(mid 124.438779 -279.408145)
		(end 124.442728 -279.410922)
		(stroke
			(width 0.05715)
			(type default)
		)
		(layer "In11.Cu")
	)
	(gr_line
		(start 124.442728 -279.410922)
		(end 124.449586 -279.414986)
		(stroke
			(width 0.05715)
			(type default)
		)
		(layer "In11.Cu")
	)
	(gr_line
		(start 124.449586 -279.414986)
		(end 124.450348 -279.415494)
		(stroke
			(width 0.05715)
			(type default)
		)
		(layer "In11.Cu")
	)
	(gr_line
		(start 124.450348 -279.415494)
		(end 124.45111 -279.416002)
		(stroke
			(width 0.05715)
			(type default)
		)
		(layer "In11.Cu")
	)
	(gr_line
		(start 124.46127 -342.13038)
		(end 124.48286 -342.078564)
		(stroke
			(width 0.07112)
			(type default)
		)
		(layer "In11.Cu")
	)
	(gr_line
		(start 124.461778 -358.85755)
		(end 124.42825 -359.046272)
		(stroke
			(width 0.07112)
			(type default)
		)
		(layer "In11.Cu")
	)
	(gr_line
		(start 124.48159 -280.078942)
		(end 124.480828 -280.07945)
		(stroke
			(width 0.05715)
			(type default)
		)
		(layer "In11.Cu")
	)
	(gr_line
		(start 124.482098 -279.434036)
		(end 124.482606 -279.43429)
		(stroke
			(width 0.05715)
			(type default)
		)
		(layer "In11.Cu")
	)
	(gr_line
		(start 124.482606 -279.43429)
		(end 124.4854 -279.435814)
		(stroke
			(width 0.05715)
			(type default)
		)
		(layer "In11.Cu")
	)
	(gr_line
		(start 124.48286 -342.078564)
		(end 124.48286 -342.022176)
		(stroke
			(width 0.07112)
			(type default)
		)
		(layer "In11.Cu")
	)
	(gr_line
		(start 124.493528 -417.46551)
		(end 124.493274 -417.465764)
		(stroke
			(width 0.07112)
			(type default)
		)
		(layer "In11.Cu")
	)
	(gr_line
		(start 124.526294 -417.274502)
		(end 124.493528 -417.463986)
		(stroke
			(width 0.07112)
			(type default)
		)
		(layer "In11.Cu")
	)
	(gr_line
		(start 124.55652 -33.386268)
		(end 124.84735 -33.095438)
		(stroke
			(width 0.07112)
			(type default)
		)
		(layer "In11.Cu")
	)
	(gr_line
		(start 124.577094 -280.244296)
		(end 124.575824 -280.245058)
		(stroke
			(width 0.05715)
			(type default)
		)
		(layer "In11.Cu")
	)
	(gr_line
		(start 124.577602 -280.244042)
		(end 124.577094 -280.244296)
		(stroke
			(width 0.05715)
			(type default)
		)
		(layer "In11.Cu")
	)
	(gr_line
		(start 124.577856 -279.268936)
		(end 124.578872 -279.269444)
		(stroke
			(width 0.05715)
			(type default)
		)
		(layer "In11.Cu")
	)
	(gr_line
		(start 124.578872 -279.269444)
		(end 124.580396 -279.27046)
		(stroke
			(width 0.05715)
			(type default)
		)
		(layer "In11.Cu")
	)
	(gr_line
		(start 124.580396 -279.27046)
		(end 124.581412 -279.270968)
		(stroke
			(width 0.05715)
			(type default)
		)
		(layer "In11.Cu")
	)
	(gr_line
		(start 124.581412 -279.270968)
		(end 124.586492 -279.274016)
		(stroke
			(width 0.05715)
			(type default)
		)
		(layer "In11.Cu")
	)
	(gr_line
		(start 124.60605 -330.266802)
		(end 124.605796 -330.266802)
		(stroke
			(width 0.07112)
			(type default)
		)
		(layer "In11.Cu")
	)
	(gr_line
		(start 124.657866 -414.29559)
		(end 124.690124 -414.35274)
		(stroke
			(width 0.07112)
			(type default)
		)
		(layer "In11.Cu")
	)
	(gr_line
		(start 124.669296 -296.042588)
		(end 124.66955 -296.042842)
		(stroke
			(width 0.05715)
			(type default)
		)
		(layer "In11.Cu")
	)
	(gr_line
		(start 124.66955 -295.956228)
		(end 124.669296 -295.956482)
		(stroke
			(width 0.05715)
			(type default)
		)
		(layer "In11.Cu")
	)
	(gr_line
		(start 124.690124 -414.35274)
		(end 125.035818 -414.963102)
		(stroke
			(width 0.07112)
			(type default)
		)
		(layer "In11.Cu")
	)
	(gr_line
		(start 124.811536 -358.61244)
		(end 124.461778 -358.85755)
		(stroke
			(width 0.07112)
			(type default)
		)
		(layer "In11.Cu")
	)
	(gr_line
		(start 124.87275 -296.87647)
		(end 124.87275 -296.876978)
		(stroke
			(width 0.07112)
			(type default)
		)
		(layer "In11.Cu")
	)
	(gr_line
		(start 124.87275 -296.838116)
		(end 124.87275 -296.866564)
		(stroke
			(width 0.05715)
			(type default)
		)
		(layer "In11.Cu")
	)
	(gr_arc
		(start 124.904754 -294.795194)
		(mid 124.908679 -294.798005)
		(end 124.912628 -294.800782)
		(stroke
			(width 0.05715)
			(type default)
		)
		(layer "In11.Cu")
	)
	(gr_arc
		(start 124.904754 -293.175182)
		(mid 124.908679 -293.177993)
		(end 124.912628 -293.18077)
		(stroke
			(width 0.05715)
			(type default)
		)
		(layer "In11.Cu")
	)
	(gr_arc
		(start 124.904754 -289.935158)
		(mid 124.908679 -289.937969)
		(end 124.912628 -289.940746)
		(stroke
			(width 0.05715)
			(type default)
		)
		(layer "In11.Cu")
	)
	(gr_arc
		(start 124.904754 -281.835352)
		(mid 124.908679 -281.838163)
		(end 124.912628 -281.84094)
		(stroke
			(width 0.05715)
			(type default)
		)
		(layer "In11.Cu")
	)
	(gr_arc
		(start 124.904754 -278.595328)
		(mid 124.908679 -278.598139)
		(end 124.912628 -278.600916)
		(stroke
			(width 0.05715)
			(type default)
		)
		(layer "In11.Cu")
	)
	(gr_arc
		(start 124.904754 -276.975316)
		(mid 124.908679 -276.978127)
		(end 124.912628 -276.980904)
		(stroke
			(width 0.05715)
			(type default)
		)
		(layer "In11.Cu")
	)
	(gr_line
		(start 124.912628 -294.800782)
		(end 124.919486 -294.804846)
		(stroke
			(width 0.05715)
			(type default)
		)
		(layer "In11.Cu")
	)
	(gr_line
		(start 124.912628 -293.18077)
		(end 124.919486 -293.184834)
		(stroke
			(width 0.05715)
			(type default)
		)
		(layer "In11.Cu")
	)
	(gr_line
		(start 124.912628 -289.940746)
		(end 124.919486 -289.94481)
		(stroke
			(width 0.05715)
			(type default)
		)
		(layer "In11.Cu")
	)
	(gr_line
		(start 124.912628 -281.84094)
		(end 124.919486 -281.845004)
		(stroke
			(width 0.05715)
			(type default)
		)
		(layer "In11.Cu")
	)
	(gr_line
		(start 124.912628 -278.600916)
		(end 124.919486 -278.60498)
		(stroke
			(width 0.05715)
			(type default)
		)
		(layer "In11.Cu")
	)
	(gr_line
		(start 124.912628 -276.980904)
		(end 124.919486 -276.984968)
		(stroke
			(width 0.05715)
			(type default)
		)
		(layer "In11.Cu")
	)
	(gr_line
		(start 124.91847 -296.792396)
		(end 124.87275 -296.838116)
		(stroke
			(width 0.05715)
			(type default)
		)
		(layer "In11.Cu")
	)
	(gr_line
		(start 124.919486 -294.804846)
		(end 124.920248 -294.805354)
		(stroke
			(width 0.05715)
			(type default)
		)
		(layer "In11.Cu")
	)
	(gr_line
		(start 124.919486 -293.184834)
		(end 124.920248 -293.185342)
		(stroke
			(width 0.05715)
			(type default)
		)
		(layer "In11.Cu")
	)
	(gr_line
		(start 124.919486 -289.94481)
		(end 124.920248 -289.945318)
		(stroke
			(width 0.05715)
			(type default)
		)
		(layer "In11.Cu")
	)
	(gr_line
		(start 124.919486 -281.845004)
		(end 124.920248 -281.845512)
		(stroke
			(width 0.05715)
			(type default)
		)
		(layer "In11.Cu")
	)
	(gr_line
		(start 124.919486 -278.60498)
		(end 124.920248 -278.605488)
		(stroke
			(width 0.05715)
			(type default)
		)
		(layer "In11.Cu")
	)
	(gr_line
		(start 124.919486 -276.984968)
		(end 124.920248 -276.985476)
		(stroke
			(width 0.05715)
			(type default)
		)
		(layer "In11.Cu")
	)
	(gr_line
		(start 124.920248 -294.805354)
		(end 124.92101 -294.805862)
		(stroke
			(width 0.05715)
			(type default)
		)
		(layer "In11.Cu")
	)
	(gr_line
		(start 124.920248 -293.185342)
		(end 124.92101 -293.18585)
		(stroke
			(width 0.05715)
			(type default)
		)
		(layer "In11.Cu")
	)
	(gr_line
		(start 124.920248 -289.945318)
		(end 124.92101 -289.945826)
		(stroke
			(width 0.05715)
			(type default)
		)
		(layer "In11.Cu")
	)
	(gr_line
		(start 124.920248 -281.845512)
		(end 124.92101 -281.84602)
		(stroke
			(width 0.05715)
			(type default)
		)
		(layer "In11.Cu")
	)
	(gr_line
		(start 124.920248 -278.605488)
		(end 124.92101 -278.605996)
		(stroke
			(width 0.05715)
			(type default)
		)
		(layer "In11.Cu")
	)
	(gr_line
		(start 124.920248 -276.985476)
		(end 124.92101 -276.985984)
		(stroke
			(width 0.05715)
			(type default)
		)
		(layer "In11.Cu")
	)
	(gr_line
		(start 124.936758 -358.634538)
		(end 124.811536 -358.61244)
		(stroke
			(width 0.07112)
			(type default)
		)
		(layer "In11.Cu")
	)
	(gr_arc
		(start 124.936758 -358.634538)
		(mid 124.990955 -358.634758)
		(end 125.042168 -358.617012)
		(stroke
			(width 0.07112)
			(type default)
		)
		(layer "In11.Cu")
	)
	(gr_line
		(start 124.937266 -414.21431)
		(end 125.122686 -414.265618)
		(stroke
			(width 0.07112)
			(type default)
		)
		(layer "In11.Cu")
	)
	(gr_line
		(start 124.945648 -292.232334)
		(end 124.944632 -292.233096)
		(stroke
			(width 0.05715)
			(type default)
		)
		(layer "In11.Cu")
	)
	(gr_line
		(start 124.945648 -290.612322)
		(end 124.944632 -290.613084)
		(stroke
			(width 0.05715)
			(type default)
		)
		(layer "In11.Cu")
	)
	(gr_line
		(start 124.945648 -288.99231)
		(end 124.944632 -288.993072)
		(stroke
			(width 0.05715)
			(type default)
		)
		(layer "In11.Cu")
	)
	(gr_line
		(start 124.945648 -285.75254)
		(end 124.944632 -285.753302)
		(stroke
			(width 0.05715)
			(type default)
		)
		(layer "In11.Cu")
	)
	(gr_line
		(start 124.945648 -284.132528)
		(end 124.944632 -284.13329)
		(stroke
			(width 0.05715)
			(type default)
		)
		(layer "In11.Cu")
	)
	(gr_line
		(start 124.945648 -282.512516)
		(end 124.944632 -282.513278)
		(stroke
			(width 0.05715)
			(type default)
		)
		(layer "In11.Cu")
	)
	(gr_line
		(start 124.945648 -280.892504)
		(end 124.944632 -280.893266)
		(stroke
			(width 0.05715)
			(type default)
		)
		(layer "In11.Cu")
	)
	(gr_line
		(start 124.945648 -277.65248)
		(end 124.944632 -277.653242)
		(stroke
			(width 0.05715)
			(type default)
		)
		(layer "In11.Cu")
	)
	(gr_line
		(start 124.945648 -276.032468)
		(end 124.944632 -276.03323)
		(stroke
			(width 0.05715)
			(type default)
		)
		(layer "In11.Cu")
	)
	(gr_line
		(start 124.947426 -412.570168)
		(end 124.656596 -412.860998)
		(stroke
			(width 0.07112)
			(type default)
		)
		(layer "In11.Cu")
	)
	(gr_line
		(start 124.947426 -292.231318)
		(end 124.945648 -292.232334)
		(stroke
			(width 0.05715)
			(type default)
		)
		(layer "In11.Cu")
	)
	(gr_line
		(start 124.947426 -290.611306)
		(end 124.945648 -290.612322)
		(stroke
			(width 0.05715)
			(type default)
		)
		(layer "In11.Cu")
	)
	(gr_line
		(start 124.947426 -288.991294)
		(end 124.945648 -288.99231)
		(stroke
			(width 0.05715)
			(type default)
		)
		(layer "In11.Cu")
	)
	(gr_line
		(start 124.947426 -285.751524)
		(end 124.945648 -285.75254)
		(stroke
			(width 0.05715)
			(type default)
		)
		(layer "In11.Cu")
	)
	(gr_line
		(start 124.947426 -284.131512)
		(end 124.945648 -284.132528)
		(stroke
			(width 0.05715)
			(type default)
		)
		(layer "In11.Cu")
	)
	(gr_line
		(start 124.947426 -282.5115)
		(end 124.945648 -282.512516)
		(stroke
			(width 0.05715)
			(type default)
		)
		(layer "In11.Cu")
	)
	(gr_line
		(start 124.947426 -280.891488)
		(end 124.945648 -280.892504)
		(stroke
			(width 0.05715)
			(type default)
		)
		(layer "In11.Cu")
	)
	(gr_line
		(start 124.947426 -277.651464)
		(end 124.945648 -277.65248)
		(stroke
			(width 0.05715)
			(type default)
		)
		(layer "In11.Cu")
	)
	(gr_line
		(start 124.947426 -276.031452)
		(end 124.945648 -276.032468)
		(stroke
			(width 0.05715)
			(type default)
		)
		(layer "In11.Cu")
	)
	(gr_line
		(start 124.950728 -292.229286)
		(end 124.949204 -292.230302)
		(stroke
			(width 0.05715)
			(type default)
		)
		(layer "In11.Cu")
	)
	(gr_line
		(start 124.950728 -290.609274)
		(end 124.949204 -290.61029)
		(stroke
			(width 0.05715)
			(type default)
		)
		(layer "In11.Cu")
	)
	(gr_line
		(start 124.950728 -288.989262)
		(end 124.949204 -288.990278)
		(stroke
			(width 0.05715)
			(type default)
		)
		(layer "In11.Cu")
	)
	(gr_line
		(start 124.950728 -285.749492)
		(end 124.949204 -285.750508)
		(stroke
			(width 0.05715)
			(type default)
		)
		(layer "In11.Cu")
	)
	(gr_line
		(start 124.950728 -284.12948)
		(end 124.949204 -284.130496)
		(stroke
			(width 0.05715)
			(type default)
		)
		(layer "In11.Cu")
	)
	(gr_line
		(start 124.950728 -282.509468)
		(end 124.949204 -282.510484)
		(stroke
			(width 0.05715)
			(type default)
		)
		(layer "In11.Cu")
	)
	(gr_line
		(start 124.950728 -280.889456)
		(end 124.949204 -280.890472)
		(stroke
			(width 0.05715)
			(type default)
		)
		(layer "In11.Cu")
	)
	(gr_line
		(start 124.950728 -277.649432)
		(end 124.949204 -277.650448)
		(stroke
			(width 0.05715)
			(type default)
		)
		(layer "In11.Cu")
	)
	(gr_line
		(start 124.950728 -276.02942)
		(end 124.949204 -276.030436)
		(stroke
			(width 0.05715)
			(type default)
		)
		(layer "In11.Cu")
	)
	(gr_line
		(start 124.951744 -293.84879)
		(end 124.950728 -293.849298)
		(stroke
			(width 0.05715)
			(type default)
		)
		(layer "In11.Cu")
	)
	(gr_line
		(start 124.951744 -292.228778)
		(end 124.950728 -292.229286)
		(stroke
			(width 0.05715)
			(type default)
		)
		(layer "In11.Cu")
	)
	(gr_line
		(start 124.951744 -290.608766)
		(end 124.950728 -290.609274)
		(stroke
			(width 0.05715)
			(type default)
		)
		(layer "In11.Cu")
	)
	(gr_line
		(start 124.951744 -288.988754)
		(end 124.950728 -288.989262)
		(stroke
			(width 0.05715)
			(type default)
		)
		(layer "In11.Cu")
	)
	(gr_line
		(start 124.951744 -285.748984)
		(end 124.950728 -285.749492)
		(stroke
			(width 0.05715)
			(type default)
		)
		(layer "In11.Cu")
	)
	(gr_line
		(start 124.951744 -284.128972)
		(end 124.950728 -284.12948)
		(stroke
			(width 0.05715)
			(type default)
		)
		(layer "In11.Cu")
	)
	(gr_line
		(start 124.951744 -282.50896)
		(end 124.950728 -282.509468)
		(stroke
			(width 0.05715)
			(type default)
		)
		(layer "In11.Cu")
	)
	(gr_line
		(start 124.951744 -280.888948)
		(end 124.950728 -280.889456)
		(stroke
			(width 0.05715)
			(type default)
		)
		(layer "In11.Cu")
	)
	(gr_line
		(start 124.951744 -277.648924)
		(end 124.950728 -277.649432)
		(stroke
			(width 0.05715)
			(type default)
		)
		(layer "In11.Cu")
	)
	(gr_line
		(start 124.951744 -276.028912)
		(end 124.950728 -276.02942)
		(stroke
			(width 0.05715)
			(type default)
		)
		(layer "In11.Cu")
	)
	(gr_line
		(start 124.951998 -294.823896)
		(end 124.952506 -294.82415)
		(stroke
			(width 0.05715)
			(type default)
		)
		(layer "In11.Cu")
	)
	(gr_line
		(start 124.951998 -293.203884)
		(end 124.952506 -293.204138)
		(stroke
			(width 0.05715)
			(type default)
		)
		(layer "In11.Cu")
	)
	(gr_line
		(start 124.951998 -289.96386)
		(end 124.952506 -289.964114)
		(stroke
			(width 0.05715)
			(type default)
		)
		(layer "In11.Cu")
	)
	(gr_line
		(start 124.951998 -281.864054)
		(end 124.952506 -281.864308)
		(stroke
			(width 0.05715)
			(type default)
		)
		(layer "In11.Cu")
	)
	(gr_line
		(start 124.951998 -278.62403)
		(end 124.952506 -278.624284)
		(stroke
			(width 0.05715)
			(type default)
		)
		(layer "In11.Cu")
	)
	(gr_line
		(start 124.951998 -277.004018)
		(end 124.952506 -277.004272)
		(stroke
			(width 0.05715)
			(type default)
		)
		(layer "In11.Cu")
	)
	(gr_line
		(start 124.952252 -293.848536)
		(end 124.951744 -293.84879)
		(stroke
			(width 0.05715)
			(type default)
		)
		(layer "In11.Cu")
	)
	(gr_line
		(start 124.952252 -292.228524)
		(end 124.951744 -292.228778)
		(stroke
			(width 0.05715)
			(type default)
		)
		(layer "In11.Cu")
	)
	(gr_line
		(start 124.952252 -290.608512)
		(end 124.951744 -290.608766)
		(stroke
			(width 0.05715)
			(type default)
		)
		(layer "In11.Cu")
	)
	(gr_line
		(start 124.952252 -288.9885)
		(end 124.951744 -288.988754)
		(stroke
			(width 0.05715)
			(type default)
		)
		(layer "In11.Cu")
	)
	(gr_line
		(start 124.952252 -285.74873)
		(end 124.951744 -285.748984)
		(stroke
			(width 0.05715)
			(type default)
		)
		(layer "In11.Cu")
	)
	(gr_line
		(start 124.952252 -284.128718)
		(end 124.951744 -284.128972)
		(stroke
			(width 0.05715)
			(type default)
		)
		(layer "In11.Cu")
	)
	(gr_line
		(start 124.952252 -282.508706)
		(end 124.951744 -282.50896)
		(stroke
			(width 0.05715)
			(type default)
		)
		(layer "In11.Cu")
	)
	(gr_line
		(start 124.952252 -280.888694)
		(end 124.951744 -280.888948)
		(stroke
			(width 0.05715)
			(type default)
		)
		(layer "In11.Cu")
	)
	(gr_line
		(start 124.952252 -277.64867)
		(end 124.951744 -277.648924)
		(stroke
			(width 0.05715)
			(type default)
		)
		(layer "In11.Cu")
	)
	(gr_line
		(start 124.952252 -276.028658)
		(end 124.951744 -276.028912)
		(stroke
			(width 0.05715)
			(type default)
		)
		(layer "In11.Cu")
	)
	(gr_line
		(start 124.952506 -294.82415)
		(end 124.953776 -294.824912)
		(stroke
			(width 0.05715)
			(type default)
		)
		(layer "In11.Cu")
	)
	(gr_line
		(start 124.952506 -293.204138)
		(end 124.953776 -293.2049)
		(stroke
			(width 0.05715)
			(type default)
		)
		(layer "In11.Cu")
	)
	(gr_line
		(start 124.952506 -291.584126)
		(end 124.953776 -291.584888)
		(stroke
			(width 0.05715)
			(type default)
		)
		(layer "In11.Cu")
	)
	(gr_line
		(start 124.952506 -289.964114)
		(end 124.953776 -289.964876)
		(stroke
			(width 0.05715)
			(type default)
		)
		(layer "In11.Cu")
	)
	(gr_line
		(start 124.952506 -285.104332)
		(end 124.953776 -285.105094)
		(stroke
			(width 0.05715)
			(type default)
		)
		(layer "In11.Cu")
	)
	(gr_line
		(start 124.952506 -283.48432)
		(end 124.953776 -283.485082)
		(stroke
			(width 0.05715)
			(type default)
		)
		(layer "In11.Cu")
	)
	(gr_line
		(start 124.952506 -281.864308)
		(end 124.953776 -281.86507)
		(stroke
			(width 0.05715)
			(type default)
		)
		(layer "In11.Cu")
	)
	(gr_line
		(start 124.952506 -278.624284)
		(end 124.953776 -278.625046)
		(stroke
			(width 0.05715)
			(type default)
		)
		(layer "In11.Cu")
	)
	(gr_line
		(start 124.952506 -277.004272)
		(end 124.953776 -277.005034)
		(stroke
			(width 0.05715)
			(type default)
		)
		(layer "In11.Cu")
	)
	(gr_line
		(start 124.953776 -294.824912)
		(end 124.9553 -294.825674)
		(stroke
			(width 0.05715)
			(type default)
		)
		(layer "In11.Cu")
	)
	(gr_line
		(start 124.953776 -293.2049)
		(end 124.9553 -293.205662)
		(stroke
			(width 0.05715)
			(type default)
		)
		(layer "In11.Cu")
	)
	(gr_line
		(start 124.953776 -289.964876)
		(end 124.9553 -289.965638)
		(stroke
			(width 0.05715)
			(type default)
		)
		(layer "In11.Cu")
	)
	(gr_line
		(start 124.953776 -281.86507)
		(end 124.9553 -281.865832)
		(stroke
			(width 0.05715)
			(type default)
		)
		(layer "In11.Cu")
	)
	(gr_line
		(start 124.953776 -278.625046)
		(end 124.9553 -278.625808)
		(stroke
			(width 0.05715)
			(type default)
		)
		(layer "In11.Cu")
	)
	(gr_line
		(start 124.953776 -277.005034)
		(end 124.9553 -277.005796)
		(stroke
			(width 0.05715)
			(type default)
		)
		(layer "In11.Cu")
	)
	(gr_line
		(start 125.043438 -292.396164)
		(end 125.041914 -292.396926)
		(stroke
			(width 0.05715)
			(type default)
		)
		(layer "In11.Cu")
	)
	(gr_line
		(start 125.043438 -290.776152)
		(end 125.041914 -290.776914)
		(stroke
			(width 0.05715)
			(type default)
		)
		(layer "In11.Cu")
	)
	(gr_line
		(start 125.043438 -289.15614)
		(end 125.041914 -289.156902)
		(stroke
			(width 0.05715)
			(type default)
		)
		(layer "In11.Cu")
	)
	(gr_line
		(start 125.043438 -285.91637)
		(end 125.041914 -285.917132)
		(stroke
			(width 0.05715)
			(type default)
		)
		(layer "In11.Cu")
	)
	(gr_line
		(start 125.043438 -284.296358)
		(end 125.041914 -284.29712)
		(stroke
			(width 0.05715)
			(type default)
		)
		(layer "In11.Cu")
	)
	(gr_line
		(start 125.043438 -282.676346)
		(end 125.041914 -282.677108)
		(stroke
			(width 0.05715)
			(type default)
		)
		(layer "In11.Cu")
	)
	(gr_line
		(start 125.043438 -281.056334)
		(end 125.041914 -281.057096)
		(stroke
			(width 0.05715)
			(type default)
		)
		(layer "In11.Cu")
	)
	(gr_line
		(start 125.043438 -277.81631)
		(end 125.041914 -277.817072)
		(stroke
			(width 0.05715)
			(type default)
		)
		(layer "In11.Cu")
	)
	(gr_line
		(start 125.043438 -276.196298)
		(end 125.041914 -276.19706)
		(stroke
			(width 0.05715)
			(type default)
		)
		(layer "In11.Cu")
	)
	(gr_line
		(start 125.0442 -292.395656)
		(end 125.043438 -292.396164)
		(stroke
			(width 0.05715)
			(type default)
		)
		(layer "In11.Cu")
	)
	(gr_line
		(start 125.0442 -290.775644)
		(end 125.043438 -290.776152)
		(stroke
			(width 0.05715)
			(type default)
		)
		(layer "In11.Cu")
	)
	(gr_line
		(start 125.0442 -289.155632)
		(end 125.043438 -289.15614)
		(stroke
			(width 0.05715)
			(type default)
		)
		(layer "In11.Cu")
	)
	(gr_line
		(start 125.0442 -285.915862)
		(end 125.043438 -285.91637)
		(stroke
			(width 0.05715)
			(type default)
		)
		(layer "In11.Cu")
	)
	(gr_line
		(start 125.0442 -284.29585)
		(end 125.043438 -284.296358)
		(stroke
			(width 0.05715)
			(type default)
		)
		(layer "In11.Cu")
	)
	(gr_line
		(start 125.0442 -282.675838)
		(end 125.043438 -282.676346)
		(stroke
			(width 0.05715)
			(type default)
		)
		(layer "In11.Cu")
	)
	(gr_line
		(start 125.0442 -281.055826)
		(end 125.043438 -281.056334)
		(stroke
			(width 0.05715)
			(type default)
		)
		(layer "In11.Cu")
	)
	(gr_line
		(start 125.0442 -277.815802)
		(end 125.043438 -277.81631)
		(stroke
			(width 0.05715)
			(type default)
		)
		(layer "In11.Cu")
	)
	(gr_line
		(start 125.0442 -276.19579)
		(end 125.043438 -276.196298)
		(stroke
			(width 0.05715)
			(type default)
		)
		(layer "In11.Cu")
	)
	(gr_line
		(start 125.045724 -292.394894)
		(end 125.0442 -292.395656)
		(stroke
			(width 0.05715)
			(type default)
		)
		(layer "In11.Cu")
	)
	(gr_line
		(start 125.045724 -290.774882)
		(end 125.0442 -290.775644)
		(stroke
			(width 0.05715)
			(type default)
		)
		(layer "In11.Cu")
	)
	(gr_line
		(start 125.045724 -289.15487)
		(end 125.0442 -289.155632)
		(stroke
			(width 0.05715)
			(type default)
		)
		(layer "In11.Cu")
	)
	(gr_line
		(start 125.045724 -285.9151)
		(end 125.0442 -285.915862)
		(stroke
			(width 0.05715)
			(type default)
		)
		(layer "In11.Cu")
	)
	(gr_line
		(start 125.045724 -284.295088)
		(end 125.0442 -284.29585)
		(stroke
			(width 0.05715)
			(type default)
		)
		(layer "In11.Cu")
	)
	(gr_line
		(start 125.045724 -282.675076)
		(end 125.0442 -282.675838)
		(stroke
			(width 0.05715)
			(type default)
		)
		(layer "In11.Cu")
	)
	(gr_line
		(start 125.045724 -281.055064)
		(end 125.0442 -281.055826)
		(stroke
			(width 0.05715)
			(type default)
		)
		(layer "In11.Cu")
	)
	(gr_line
		(start 125.045724 -277.81504)
		(end 125.0442 -277.815802)
		(stroke
			(width 0.05715)
			(type default)
		)
		(layer "In11.Cu")
	)
	(gr_line
		(start 125.045724 -276.195028)
		(end 125.0442 -276.19579)
		(stroke
			(width 0.05715)
			(type default)
		)
		(layer "In11.Cu")
	)
	(gr_line
		(start 125.046994 -294.014144)
		(end 125.045724 -294.014906)
		(stroke
			(width 0.05715)
			(type default)
		)
		(layer "In11.Cu")
	)
	(gr_line
		(start 125.046994 -292.394132)
		(end 125.045724 -292.394894)
		(stroke
			(width 0.05715)
			(type default)
		)
		(layer "In11.Cu")
	)
	(gr_line
		(start 125.046994 -290.77412)
		(end 125.045724 -290.774882)
		(stroke
			(width 0.05715)
			(type default)
		)
		(layer "In11.Cu")
	)
	(gr_line
		(start 125.046994 -289.154108)
		(end 125.045724 -289.15487)
		(stroke
			(width 0.05715)
			(type default)
		)
		(layer "In11.Cu")
	)
	(gr_line
		(start 125.046994 -285.914338)
		(end 125.045724 -285.9151)
		(stroke
			(width 0.05715)
			(type default)
		)
		(layer "In11.Cu")
	)
	(gr_line
		(start 125.046994 -284.294326)
		(end 125.045724 -284.295088)
		(stroke
			(width 0.05715)
			(type default)
		)
		(layer "In11.Cu")
	)
	(gr_line
		(start 125.046994 -282.674314)
		(end 125.045724 -282.675076)
		(stroke
			(width 0.05715)
			(type default)
		)
		(layer "In11.Cu")
	)
	(gr_line
		(start 125.046994 -281.054302)
		(end 125.045724 -281.055064)
		(stroke
			(width 0.05715)
			(type default)
		)
		(layer "In11.Cu")
	)
	(gr_line
		(start 125.046994 -277.814278)
		(end 125.045724 -277.81504)
		(stroke
			(width 0.05715)
			(type default)
		)
		(layer "In11.Cu")
	)
	(gr_line
		(start 125.046994 -276.194266)
		(end 125.045724 -276.195028)
		(stroke
			(width 0.05715)
			(type default)
		)
		(layer "In11.Cu")
	)
	(gr_line
		(start 125.047248 -291.418518)
		(end 125.047756 -291.418772)
		(stroke
			(width 0.05715)
			(type default)
		)
		(layer "In11.Cu")
	)
	(gr_line
		(start 125.047248 -284.938724)
		(end 125.047756 -284.938978)
		(stroke
			(width 0.05715)
			(type default)
		)
		(layer "In11.Cu")
	)
	(gr_line
		(start 125.047248 -283.318712)
		(end 125.047756 -283.318966)
		(stroke
			(width 0.05715)
			(type default)
		)
		(layer "In11.Cu")
	)
	(gr_line
		(start 125.047502 -292.393878)
		(end 125.046994 -292.394132)
		(stroke
			(width 0.05715)
			(type default)
		)
		(layer "In11.Cu")
	)
	(gr_line
		(start 125.047502 -290.773866)
		(end 125.046994 -290.77412)
		(stroke
			(width 0.05715)
			(type default)
		)
		(layer "In11.Cu")
	)
	(gr_line
		(start 125.047502 -289.153854)
		(end 125.046994 -289.154108)
		(stroke
			(width 0.05715)
			(type default)
		)
		(layer "In11.Cu")
	)
	(gr_line
		(start 125.047502 -285.914084)
		(end 125.046994 -285.914338)
		(stroke
			(width 0.05715)
			(type default)
		)
		(layer "In11.Cu")
	)
	(gr_line
		(start 125.047502 -284.294072)
		(end 125.046994 -284.294326)
		(stroke
			(width 0.05715)
			(type default)
		)
		(layer "In11.Cu")
	)
	(gr_line
		(start 125.047502 -282.67406)
		(end 125.046994 -282.674314)
		(stroke
			(width 0.05715)
			(type default)
		)
		(layer "In11.Cu")
	)
	(gr_line
		(start 125.047502 -281.054048)
		(end 125.046994 -281.054302)
		(stroke
			(width 0.05715)
			(type default)
		)
		(layer "In11.Cu")
	)
	(gr_line
		(start 125.047502 -277.814024)
		(end 125.046994 -277.814278)
		(stroke
			(width 0.05715)
			(type default)
		)
		(layer "In11.Cu")
	)
	(gr_line
		(start 125.047502 -276.194012)
		(end 125.046994 -276.194266)
		(stroke
			(width 0.05715)
			(type default)
		)
		(layer "In11.Cu")
	)
	(gr_line
		(start 125.047756 -294.658796)
		(end 125.048772 -294.659304)
		(stroke
			(width 0.05715)
			(type default)
		)
		(layer "In11.Cu")
	)
	(gr_line
		(start 125.047756 -293.038784)
		(end 125.048772 -293.039292)
		(stroke
			(width 0.05715)
			(type default)
		)
		(layer "In11.Cu")
	)
	(gr_line
		(start 125.047756 -291.418772)
		(end 125.048772 -291.41928)
		(stroke
			(width 0.05715)
			(type default)
		)
		(layer "In11.Cu")
	)
	(gr_line
		(start 125.047756 -289.79876)
		(end 125.048772 -289.799268)
		(stroke
			(width 0.05715)
			(type default)
		)
		(layer "In11.Cu")
	)
	(gr_line
		(start 125.047756 -284.938978)
		(end 125.048772 -284.939486)
		(stroke
			(width 0.05715)
			(type default)
		)
		(layer "In11.Cu")
	)
	(gr_line
		(start 125.047756 -283.318966)
		(end 125.048772 -283.319474)
		(stroke
			(width 0.05715)
			(type default)
		)
		(layer "In11.Cu")
	)
	(gr_line
		(start 125.047756 -281.698954)
		(end 125.048772 -281.699462)
		(stroke
			(width 0.05715)
			(type default)
		)
		(layer "In11.Cu")
	)
	(gr_line
		(start 125.047756 -278.45893)
		(end 125.048772 -278.459438)
		(stroke
			(width 0.05715)
			(type default)
		)
		(layer "In11.Cu")
	)
	(gr_line
		(start 125.047756 -276.838918)
		(end 125.048772 -276.839426)
		(stroke
			(width 0.05715)
			(type default)
		)
		(layer "In11.Cu")
	)
	(gr_line
		(start 125.048772 -294.659304)
		(end 125.050296 -294.66032)
		(stroke
			(width 0.05715)
			(type default)
		)
		(layer "In11.Cu")
	)
	(gr_line
		(start 125.048772 -293.039292)
		(end 125.050296 -293.040308)
		(stroke
			(width 0.05715)
			(type default)
		)
		(layer "In11.Cu")
	)
	(gr_line
		(start 125.048772 -289.799268)
		(end 125.050296 -289.800284)
		(stroke
			(width 0.05715)
			(type default)
		)
		(layer "In11.Cu")
	)
	(gr_line
		(start 125.048772 -281.699462)
		(end 125.050296 -281.700478)
		(stroke
			(width 0.05715)
			(type default)
		)
		(layer "In11.Cu")
	)
	(gr_line
		(start 125.048772 -278.459438)
		(end 125.050296 -278.460454)
		(stroke
			(width 0.05715)
			(type default)
		)
		(layer "In11.Cu")
	)
	(gr_line
		(start 125.048772 -276.839426)
		(end 125.050296 -276.840442)
		(stroke
			(width 0.05715)
			(type default)
		)
		(layer "In11.Cu")
	)
	(gr_line
		(start 125.052074 -294.661336)
		(end 125.053344 -294.662098)
		(stroke
			(width 0.05715)
			(type default)
		)
		(layer "In11.Cu")
	)
	(gr_line
		(start 125.052074 -293.041324)
		(end 125.053344 -293.042086)
		(stroke
			(width 0.05715)
			(type default)
		)
		(layer "In11.Cu")
	)
	(gr_line
		(start 125.052074 -289.8013)
		(end 125.053344 -289.802062)
		(stroke
			(width 0.05715)
			(type default)
		)
		(layer "In11.Cu")
	)
	(gr_line
		(start 125.052074 -281.701494)
		(end 125.053344 -281.702256)
		(stroke
			(width 0.05715)
			(type default)
		)
		(layer "In11.Cu")
	)
	(gr_line
		(start 125.052074 -278.46147)
		(end 125.053344 -278.462232)
		(stroke
			(width 0.05715)
			(type default)
		)
		(layer "In11.Cu")
	)
	(gr_line
		(start 125.052074 -276.841458)
		(end 125.053344 -276.84222)
		(stroke
			(width 0.05715)
			(type default)
		)
		(layer "In11.Cu")
	)
	(gr_line
		(start 125.054614 -294.66286)
		(end 125.056392 -294.663876)
		(stroke
			(width 0.05715)
			(type default)
		)
		(layer "In11.Cu")
	)
	(gr_line
		(start 125.054614 -293.042848)
		(end 125.056392 -293.043864)
		(stroke
			(width 0.05715)
			(type default)
		)
		(layer "In11.Cu")
	)
	(gr_line
		(start 125.054614 -289.802824)
		(end 125.056392 -289.80384)
		(stroke
			(width 0.05715)
			(type default)
		)
		(layer "In11.Cu")
	)
	(gr_line
		(start 125.054614 -281.703018)
		(end 125.056392 -281.704034)
		(stroke
			(width 0.05715)
			(type default)
		)
		(layer "In11.Cu")
	)
	(gr_line
		(start 125.054614 -278.462994)
		(end 125.056392 -278.46401)
		(stroke
			(width 0.05715)
			(type default)
		)
		(layer "In11.Cu")
	)
	(gr_line
		(start 125.054614 -276.842982)
		(end 125.056392 -276.843998)
		(stroke
			(width 0.05715)
			(type default)
		)
		(layer "In11.Cu")
	)
	(gr_line
		(start 125.10897 -296.792396)
		(end 125.15469 -296.838116)
		(stroke
			(width 0.05715)
			(type default)
		)
		(layer "In11.Cu")
	)
	(gr_line
		(start 125.122686 -414.265618)
		(end 125.332998 -414.636966)
		(stroke
			(width 0.07112)
			(type default)
		)
		(layer "In11.Cu")
	)
	(gr_line
		(start 125.13564 -418.86378)
		(end 125.540262 -419.43655)
		(stroke
			(width 0.07112)
			(type default)
		)
		(layer "In11.Cu")
	)
	(gr_line
		(start 125.15469 -296.838116)
		(end 125.15469 -296.866564)
		(stroke
			(width 0.05715)
			(type default)
		)
		(layer "In11.Cu")
	)
	(gr_line
		(start 125.155198 -296.890694)
		(end 125.155198 -296.891202)
		(stroke
			(width 0.07112)
			(type default)
		)
		(layer "In11.Cu")
	)
	(gr_line
		(start 125.195076 -358.855518)
		(end 124.589794 -359.278936)
		(stroke
			(width 0.07112)
			(type default)
		)
		(layer "In11.Cu")
	)
	(gr_line
		(start 125.218952 -358.838754)
		(end 125.219206 -358.838754)
		(stroke
			(width 0.07112)
			(type default)
		)
		(layer "In11.Cu")
	)
	(gr_line
		(start 125.2347 -278.13635)
		(end 125.532642 -278.13635)
		(stroke
			(width 0.05715)
			(type default)
		)
		(layer "In11.Cu")
	)
	(gr_line
		(start 125.2347 -276.516338)
		(end 125.532642 -276.516338)
		(stroke
			(width 0.05715)
			(type default)
		)
		(layer "In11.Cu")
	)
	(gr_line
		(start 125.2347 -274.896326)
		(end 125.532642 -274.896326)
		(stroke
			(width 0.05715)
			(type default)
		)
		(layer "In11.Cu")
	)
	(gr_line
		(start 125.31725 -342.060276)
		(end 125.317504 -342.060022)
		(stroke
			(width 0.07112)
			(type default)
		)
		(layer "In11.Cu")
	)
	(gr_line
		(start 125.332998 -414.636966)
		(end 125.28169 -414.82264)
		(stroke
			(width 0.07112)
			(type default)
		)
		(layer "In11.Cu")
	)
	(gr_line
		(start 125.367542 -418.70122)
		(end 125.55728 -418.733732)
		(stroke
			(width 0.07112)
			(type default)
		)
		(layer "In11.Cu")
	)
	(gr_line
		(start 125.41758 -415.636964)
		(end 125.763274 -416.247072)
		(stroke
			(width 0.07112)
			(type default)
		)
		(layer "In11.Cu")
	)
	(gr_line
		(start 125.42012 -33.386268)
		(end 125.12929 -33.095438)
		(stroke
			(width 0.07112)
			(type default)
		)
		(layer "In11.Cu")
	)
	(gr_line
		(start 125.421644 -295.633648)
		(end 125.421898 -295.633648)
		(stroke
			(width 0.05715)
			(type default)
		)
		(layer "In11.Cu")
	)
	(gr_line
		(start 125.440186 -358.172004)
		(end 125.406658 -358.361488)
		(stroke
			(width 0.07112)
			(type default)
		)
		(layer "In11.Cu")
	)
	(gr_line
		(start 125.468888 -295.664128)
		(end 125.469142 -295.663874)
		(stroke
			(width 0.05715)
			(type default)
		)
		(layer "In11.Cu")
	)
	(gr_line
		(start 125.532642 -278.13635)
		(end 125.615446 -278.219154)
		(stroke
			(width 0.05715)
			(type default)
		)
		(layer "In11.Cu")
	)
	(gr_line
		(start 125.532642 -276.516338)
		(end 125.615446 -276.599142)
		(stroke
			(width 0.05715)
			(type default)
		)
		(layer "In11.Cu")
	)
	(gr_line
		(start 125.532642 -274.896326)
		(end 125.601984 -274.965668)
		(stroke
			(width 0.05715)
			(type default)
		)
		(layer "In11.Cu")
	)
	(gr_line
		(start 125.55728 -418.733732)
		(end 125.80366 -419.082474)
		(stroke
			(width 0.07112)
			(type default)
		)
		(layer "In11.Cu")
	)
	(gr_line
		(start 125.580648 -342.161876)
		(end 125.599444 -342.112854)
		(stroke
			(width 0.07112)
			(type default)
		)
		(layer "In11.Cu")
	)
	(gr_line
		(start 125.59919 -430.125632)
		(end 125.622812 -430.125632)
		(stroke
			(width 0.07112)
			(type default)
		)
		(layer "In11.Cu")
	)
	(gr_line
		(start 125.599444 -342.112854)
		(end 125.599444 -342.060022)
		(stroke
			(width 0.07112)
			(type default)
		)
		(layer "In11.Cu")
	)
	(gr_line
		(start 125.60046 -430.408842)
		(end 125.749812 -430.558194)
		(stroke
			(width 0.07112)
			(type default)
		)
		(layer "In11.Cu")
	)
	(gr_arc
		(start 125.615446 -278.219154)
		(mid 125.617238 -278.230476)
		(end 125.619256 -278.24176)
		(stroke
			(width 0.05715)
			(type default)
		)
		(layer "In11.Cu")
	)
	(gr_arc
		(start 125.615446 -276.599142)
		(mid 125.617238 -276.610464)
		(end 125.619256 -276.621748)
		(stroke
			(width 0.05715)
			(type default)
		)
		(layer "In11.Cu")
	)
	(gr_line
		(start 125.622812 -430.125632)
		(end 125.749812 -429.998632)
		(stroke
			(width 0.07112)
			(type default)
		)
		(layer "In11.Cu")
	)
	(gr_line
		(start 125.664468 -415.498026)
		(end 125.850396 -415.549334)
		(stroke
			(width 0.07112)
			(type default)
		)
		(layer "In11.Cu")
	)
	(gr_line
		(start 125.722126 -368.7445)
		(end 125.431296 -369.03533)
		(stroke
			(width 0.07112)
			(type default)
		)
		(layer "In11.Cu")
	)
	(gr_line
		(start 125.749812 -430.558194)
		(end 125.749812 -430.889918)
		(stroke
			(width 0.07112)
			(type default)
		)
		(layer "In11.Cu")
	)
	(gr_line
		(start 125.749812 -429.998632)
		(end 125.749812 -429.689768)
		(stroke
			(width 0.07112)
			(type default)
		)
		(layer "In11.Cu")
	)
	(gr_line
		(start 125.789944 -357.926894)
		(end 125.440186 -358.172004)
		(stroke
			(width 0.07112)
			(type default)
		)
		(layer "In11.Cu")
	)
	(gr_arc
		(start 125.790198 -275.00199)
		(mid 125.792219 -274.990579)
		(end 125.794008 -274.97913)
		(stroke
			(width 0.05715)
			(type default)
		)
		(layer "In11.Cu")
	)
	(gr_line
		(start 125.80366 -419.082474)
		(end 125.771148 -419.272466)
		(stroke
			(width 0.07112)
			(type default)
		)
		(layer "In11.Cu")
	)
	(gr_line
		(start 125.838204 -296.87647)
		(end 125.838204 -296.876978)
		(stroke
			(width 0.07112)
			(type default)
		)
		(layer "In11.Cu")
	)
	(gr_line
		(start 125.838204 -296.838116)
		(end 125.838204 -296.866564)
		(stroke
			(width 0.05715)
			(type default)
		)
		(layer "In11.Cu")
	)
	(gr_arc
		(start 125.842014 -288.313368)
		(mid 125.84518 -288.315666)
		(end 125.848364 -288.31794)
		(stroke
			(width 0.05715)
			(type default)
		)
		(layer "In11.Cu")
	)
	(gr_arc
		(start 125.844554 -278.595328)
		(mid 125.848606 -278.59814)
		(end 125.852682 -278.600916)
		(stroke
			(width 0.05715)
			(type default)
		)
		(layer "In11.Cu")
	)
	(gr_arc
		(start 125.844554 -276.975316)
		(mid 125.848606 -276.978128)
		(end 125.852682 -276.980904)
		(stroke
			(width 0.05715)
			(type default)
		)
		(layer "In11.Cu")
	)
	(gr_arc
		(start 125.844808 -283.455364)
		(mid 125.848733 -283.458175)
		(end 125.852682 -283.460952)
		(stroke
			(width 0.05715)
			(type default)
		)
		(layer "In11.Cu")
	)
	(gr_arc
		(start 125.849126 -288.318448)
		(mid 125.850902 -288.319721)
		(end 125.852682 -288.320988)
		(stroke
			(width 0.05715)
			(type default)
		)
		(layer "In11.Cu")
	)
	(gr_line
		(start 125.850396 -415.549334)
		(end 126.060708 -415.920936)
		(stroke
			(width 0.07112)
			(type default)
		)
		(layer "In11.Cu")
	)
	(gr_line
		(start 125.852682 -288.320988)
		(end 125.858778 -288.324544)
		(stroke
			(width 0.05715)
			(type default)
		)
		(layer "In11.Cu")
	)
	(gr_line
		(start 125.852682 -283.460952)
		(end 125.85954 -283.465016)
		(stroke
			(width 0.05715)
			(type default)
		)
		(layer "In11.Cu")
	)
	(gr_line
		(start 125.852682 -278.600916)
		(end 125.85954 -278.60498)
		(stroke
			(width 0.05715)
			(type default)
		)
		(layer "In11.Cu")
	)
	(gr_line
		(start 125.852682 -276.980904)
		(end 125.85954 -276.984968)
		(stroke
			(width 0.05715)
			(type default)
		)
		(layer "In11.Cu")
	)
	(gr_line
		(start 125.858778 -288.324544)
		(end 125.859032 -288.324544)
		(stroke
			(width 0.05715)
			(type default)
		)
		(layer "In11.Cu")
	)
	(gr_line
		(start 125.85954 -283.465016)
		(end 125.860302 -283.465524)
		(stroke
			(width 0.05715)
			(type default)
		)
		(layer "In11.Cu")
	)
	(gr_line
		(start 125.85954 -278.60498)
		(end 125.860302 -278.605488)
		(stroke
			(width 0.05715)
			(type default)
		)
		(layer "In11.Cu")
	)
	(gr_line
		(start 125.85954 -276.984968)
		(end 125.860302 -276.985476)
		(stroke
			(width 0.05715)
			(type default)
		)
		(layer "In11.Cu")
	)
	(gr_line
		(start 125.860302 -283.465524)
		(end 125.861064 -283.466032)
		(stroke
			(width 0.05715)
			(type default)
		)
		(layer "In11.Cu")
	)
	(gr_line
		(start 125.860302 -278.605488)
		(end 125.861064 -278.605996)
		(stroke
			(width 0.05715)
			(type default)
		)
		(layer "In11.Cu")
	)
	(gr_line
		(start 125.860302 -276.985476)
		(end 125.861064 -276.985984)
		(stroke
			(width 0.05715)
			(type default)
		)
		(layer "In11.Cu")
	)
	(gr_line
		(start 125.876812 -278.13635)
		(end 125.80747 -278.205692)
		(stroke
			(width 0.05715)
			(type default)
		)
		(layer "In11.Cu")
	)
	(gr_line
		(start 125.876812 -276.516338)
		(end 125.80747 -276.58568)
		(stroke
			(width 0.05715)
			(type default)
		)
		(layer "In11.Cu")
	)
	(gr_line
		(start 125.876812 -274.896326)
		(end 125.794008 -274.97913)
		(stroke
			(width 0.05715)
			(type default)
		)
		(layer "In11.Cu")
	)
	(gr_line
		(start 125.883924 -296.792396)
		(end 125.838204 -296.838116)
		(stroke
			(width 0.05715)
			(type default)
		)
		(layer "In11.Cu")
	)
	(gr_line
		(start 125.891798 -277.003764)
		(end 125.892052 -277.004018)
		(stroke
			(width 0.05715)
			(type default)
		)
		(layer "In11.Cu")
	)
	(gr_line
		(start 125.892052 -278.62403)
		(end 125.89256 -278.624284)
		(stroke
			(width 0.05715)
			(type default)
		)
		(layer "In11.Cu")
	)
	(gr_line
		(start 125.892052 -277.004018)
		(end 125.89256 -277.004272)
		(stroke
			(width 0.05715)
			(type default)
		)
		(layer "In11.Cu")
	)
	(gr_line
		(start 125.89256 -294.82415)
		(end 125.893322 -294.824404)
		(stroke
			(width 0.05715)
			(type default)
		)
		(layer "In11.Cu")
	)
	(gr_line
		(start 125.89256 -291.584126)
		(end 125.89383 -291.584888)
		(stroke
			(width 0.05715)
			(type default)
		)
		(layer "In11.Cu")
	)
	(gr_line
		(start 125.89256 -278.624284)
		(end 125.89256 -278.62403)
		(stroke
			(width 0.05715)
			(type default)
		)
		(layer "In11.Cu")
	)
	(gr_line
		(start 125.89256 -277.004272)
		(end 125.895354 -277.005796)
		(stroke
			(width 0.05715)
			(type default)
		)
		(layer "In11.Cu")
	)
	(gr_line
		(start 125.894592 -293.205408)
		(end 125.8951 -293.205408)
		(stroke
			(width 0.05715)
			(type default)
		)
		(layer "In11.Cu")
	)
	(gr_line
		(start 125.894592 -289.965384)
		(end 125.8951 -289.965384)
		(stroke
			(width 0.05715)
			(type default)
		)
		(layer "In11.Cu")
	)
	(gr_line
		(start 125.894592 -285.105602)
		(end 125.8951 -285.105602)
		(stroke
			(width 0.05715)
			(type default)
		)
		(layer "In11.Cu")
	)
	(gr_line
		(start 125.894592 -283.48559)
		(end 125.8951 -283.48559)
		(stroke
			(width 0.05715)
			(type default)
		)
		(layer "In11.Cu")
	)
	(gr_line
		(start 125.894592 -281.865578)
		(end 125.8951 -281.865578)
		(stroke
			(width 0.05715)
			(type default)
		)
		(layer "In11.Cu")
	)
	(gr_line
		(start 125.894846 -288.345372)
		(end 125.8951 -288.345372)
		(stroke
			(width 0.05715)
			(type default)
		)
		(layer "In11.Cu")
	)
	(gr_line
		(start 125.895354 -277.005796)
		(end 125.895862 -277.00605)
		(stroke
			(width 0.05715)
			(type default)
		)
		(layer "In11.Cu")
	)
	(gr_arc
		(start 125.897894 -280.885392)
		(mid 125.89853 -280.885012)
		(end 125.899164 -280.88463)
		(stroke
			(width 0.05715)
			(type default)
		)
		(layer "In11.Cu")
	)
	(gr_line
		(start 125.979428 -357.960168)
		(end 125.789944 -357.926894)
		(stroke
			(width 0.07112)
			(type default)
		)
		(layer "In11.Cu")
	)
	(gr_line
		(start 125.987302 -294.658542)
		(end 125.98781 -294.658796)
		(stroke
			(width 0.05715)
			(type default)
		)
		(layer "In11.Cu")
	)
	(gr_line
		(start 125.987302 -293.03853)
		(end 125.98781 -293.038784)
		(stroke
			(width 0.05715)
			(type default)
		)
		(layer "In11.Cu")
	)
	(gr_line
		(start 125.987302 -291.418518)
		(end 125.98781 -291.418772)
		(stroke
			(width 0.05715)
			(type default)
		)
		(layer "In11.Cu")
	)
	(gr_line
		(start 125.987302 -289.798506)
		(end 125.98781 -289.79876)
		(stroke
			(width 0.05715)
			(type default)
		)
		(layer "In11.Cu")
	)
	(gr_line
		(start 125.987302 -284.938724)
		(end 125.98781 -284.938978)
		(stroke
			(width 0.05715)
			(type default)
		)
		(layer "In11.Cu")
	)
	(gr_line
		(start 125.987302 -281.6987)
		(end 125.98781 -281.698954)
		(stroke
			(width 0.05715)
			(type default)
		)
		(layer "In11.Cu")
	)
	(gr_line
		(start 125.987556 -292.393878)
		(end 125.982222 -292.396926)
		(stroke
			(width 0.05715)
			(type default)
		)
		(layer "In11.Cu")
	)
	(gr_line
		(start 125.98781 -294.658796)
		(end 125.991366 -294.660828)
		(stroke
			(width 0.05715)
			(type default)
		)
		(layer "In11.Cu")
	)
	(gr_line
		(start 125.98781 -293.038784)
		(end 125.990858 -293.040562)
		(stroke
			(width 0.05715)
			(type default)
		)
		(layer "In11.Cu")
	)
	(gr_line
		(start 125.98781 -291.418772)
		(end 125.98781 -291.419026)
		(stroke
			(width 0.05715)
			(type default)
		)
		(layer "In11.Cu")
	)
	(gr_line
		(start 125.98781 -289.79876)
		(end 125.990858 -289.800538)
		(stroke
			(width 0.05715)
			(type default)
		)
		(layer "In11.Cu")
	)
	(gr_line
		(start 125.98781 -284.938978)
		(end 125.990858 -284.940756)
		(stroke
			(width 0.05715)
			(type default)
		)
		(layer "In11.Cu")
	)
	(gr_line
		(start 125.98781 -283.318966)
		(end 125.990858 -283.320744)
		(stroke
			(width 0.05715)
			(type default)
		)
		(layer "In11.Cu")
	)
	(gr_line
		(start 125.98781 -281.698954)
		(end 125.990858 -281.700732)
		(stroke
			(width 0.05715)
			(type default)
		)
		(layer "In11.Cu")
	)
	(gr_line
		(start 125.98781 -281.053794)
		(end 125.987302 -281.054048)
		(stroke
			(width 0.05715)
			(type default)
		)
		(layer "In11.Cu")
	)
	(gr_line
		(start 125.98781 -278.45893)
		(end 125.988826 -278.459438)
		(stroke
			(width 0.05715)
			(type default)
		)
		(layer "In11.Cu")
	)
	(gr_line
		(start 125.98781 -276.838918)
		(end 125.991112 -276.84095)
		(stroke
			(width 0.05715)
			(type default)
		)
		(layer "In11.Cu")
	)
	(gr_line
		(start 125.990858 -294.011858)
		(end 125.987302 -294.01389)
		(stroke
			(width 0.05715)
			(type default)
		)
		(layer "In11.Cu")
	)
	(gr_line
		(start 125.990858 -290.771834)
		(end 125.987302 -290.773866)
		(stroke
			(width 0.05715)
			(type default)
		)
		(layer "In11.Cu")
	)
	(gr_line
		(start 125.990858 -289.151822)
		(end 125.987302 -289.153854)
		(stroke
			(width 0.05715)
			(type default)
		)
		(layer "In11.Cu")
	)
	(gr_line
		(start 125.990858 -285.912052)
		(end 125.987302 -285.914084)
		(stroke
			(width 0.05715)
			(type default)
		)
		(layer "In11.Cu")
	)
	(gr_line
		(start 125.990858 -284.29204)
		(end 125.987302 -284.294072)
		(stroke
			(width 0.05715)
			(type default)
		)
		(layer "In11.Cu")
	)
	(gr_line
		(start 125.990858 -282.672028)
		(end 125.987302 -282.67406)
		(stroke
			(width 0.05715)
			(type default)
		)
		(layer "In11.Cu")
	)
	(gr_line
		(start 125.991366 -294.660828)
		(end 125.992128 -294.661336)
		(stroke
			(width 0.05715)
			(type default)
		)
		(layer "In11.Cu")
	)
	(gr_line
		(start 126.002034 -278.467312)
		(end 126.002796 -278.467566)
		(stroke
			(width 0.05715)
			(type default)
		)
		(layer "In11.Cu")
	)
	(gr_line
		(start 126.004066 -368.7445)
		(end 126.294896 -369.03533)
		(stroke
			(width 0.07112)
			(type default)
		)
		(layer "In11.Cu")
	)
	(gr_line
		(start 126.060708 -415.920936)
		(end 126.009146 -416.106864)
		(stroke
			(width 0.07112)
			(type default)
		)
		(layer "In11.Cu")
	)
	(gr_line
		(start 126.074424 -296.792396)
		(end 126.120144 -296.838116)
		(stroke
			(width 0.05715)
			(type default)
		)
		(layer "In11.Cu")
	)
	(gr_line
		(start 126.120144 -296.838116)
		(end 126.120144 -296.866564)
		(stroke
			(width 0.05715)
			(type default)
		)
		(layer "In11.Cu")
	)
	(gr_line
		(start 126.120652 -296.934636)
		(end 126.120652 -296.935144)
		(stroke
			(width 0.07112)
			(type default)
		)
		(layer "In11.Cu")
	)
	(gr_line
		(start 126.14275 -358.191562)
		(end 125.568202 -358.594152)
		(stroke
			(width 0.07112)
			(type default)
		)
		(layer "In11.Cu")
	)
	(gr_line
		(start 126.174754 -278.13635)
		(end 125.876812 -278.13635)
		(stroke
			(width 0.05715)
			(type default)
		)
		(layer "In11.Cu")
	)
	(gr_line
		(start 126.174754 -276.516338)
		(end 125.876812 -276.516338)
		(stroke
			(width 0.05715)
			(type default)
		)
		(layer "In11.Cu")
	)
	(gr_line
		(start 126.174754 -274.896326)
		(end 125.876812 -274.896326)
		(stroke
			(width 0.05715)
			(type default)
		)
		(layer "In11.Cu")
	)
	(gr_line
		(start 126.262384 -342.278208)
		(end 126.262638 -342.277954)
		(stroke
			(width 0.07112)
			(type default)
		)
		(layer "In11.Cu")
	)
	(gr_line
		(start 126.36373 -295.634664)
		(end 126.364746 -295.635172)
		(stroke
			(width 0.05715)
			(type default)
		)
		(layer "In11.Cu")
	)
	(gr_line
		(start 126.392178 -327.061322)
		(end 126.391162 -327.055734)
		(stroke
			(width 0.07112)
			(type default)
		)
		(layer "In11.Cu")
	)
	(gr_line
		(start 126.393194 -277.832058)
		(end 126.393448 -277.832058)
		(stroke
			(width 0.05715)
			(type default)
		)
		(layer "In11.Cu")
	)
	(gr_line
		(start 126.444756 -280.251154)
		(end 126.444502 -280.251408)
		(stroke
			(width 0.05715)
			(type default)
		)
		(layer "In11.Cu")
	)
	(gr_line
		(start 126.45771 -279.268936)
		(end 126.458726 -279.269444)
		(stroke
			(width 0.05715)
			(type default)
		)
		(layer "In11.Cu")
	)
	(gr_line
		(start 126.461266 -295.714928)
		(end 126.46152 -295.715182)
		(stroke
			(width 0.05715)
			(type default)
		)
		(layer "In11.Cu")
	)
	(gr_line
		(start 126.525782 -342.379808)
		(end 126.544578 -342.330786)
		(stroke
			(width 0.07112)
			(type default)
		)
		(layer "In11.Cu")
	)
	(gr_line
		(start 126.544578 -342.330786)
		(end 126.544578 -342.277954)
		(stroke
			(width 0.07112)
			(type default)
		)
		(layer "In11.Cu")
	)
	(gr_line
		(start 126.783084 -296.838116)
		(end 126.783084 -296.866564)
		(stroke
			(width 0.05715)
			(type default)
		)
		(layer "In11.Cu")
	)
	(gr_line
		(start 126.828804 -296.792396)
		(end 126.783084 -296.838116)
		(stroke
			(width 0.05715)
			(type default)
		)
		(layer "In11.Cu")
	)
	(gr_line
		(start 127.019304 -296.792396)
		(end 127.065024 -296.838116)
		(stroke
			(width 0.05715)
			(type default)
		)
		(layer "In11.Cu")
	)
	(gr_line
		(start 127.065024 -296.838116)
		(end 127.065024 -296.866564)
		(stroke
			(width 0.05715)
			(type default)
		)
		(layer "In11.Cu")
	)
	(gr_line
		(start 127.079502 -319.57137)
		(end 127.079756 -319.57137)
		(stroke
			(width 0.07112)
			(type default)
		)
		(layer "In11.Cu")
	)
	(gr_line
		(start 127.147066 -412.570168)
		(end 127.437896 -412.860998)
		(stroke
			(width 0.07112)
			(type default)
		)
		(layer "In11.Cu")
	)
	(gr_arc
		(start 127.254762 -279.405334)
		(mid 127.258687 -279.408145)
		(end 127.262636 -279.410922)
		(stroke
			(width 0.05715)
			(type default)
		)
		(layer "In11.Cu")
	)
	(gr_line
		(start 127.262636 -279.410922)
		(end 127.269494 -279.414986)
		(stroke
			(width 0.05715)
			(type default)
		)
		(layer "In11.Cu")
	)
	(gr_line
		(start 127.269494 -279.414986)
		(end 127.270256 -279.415494)
		(stroke
			(width 0.05715)
			(type default)
		)
		(layer "In11.Cu")
	)
	(gr_line
		(start 127.270256 -279.415494)
		(end 127.271018 -279.416002)
		(stroke
			(width 0.05715)
			(type default)
		)
		(layer "In11.Cu")
	)
	(gr_line
		(start 127.297688 -319.3923)
		(end 127.306578 -319.403222)
		(stroke
			(width 0.07112)
			(type default)
		)
		(layer "In11.Cu")
	)
	(gr_line
		(start 127.301498 -280.078942)
		(end 127.300736 -280.07945)
		(stroke
			(width 0.05715)
			(type default)
		)
		(layer "In11.Cu")
	)
	(gr_line
		(start 127.302006 -279.434036)
		(end 127.302514 -279.43429)
		(stroke
			(width 0.05715)
			(type default)
		)
		(layer "In11.Cu")
	)
	(gr_line
		(start 127.302514 -295.634156)
		(end 127.305308 -295.63568)
		(stroke
			(width 0.05715)
			(type default)
		)
		(layer "In11.Cu")
	)
	(gr_line
		(start 127.302514 -279.43429)
		(end 127.305308 -279.435814)
		(stroke
			(width 0.05715)
			(type default)
		)
		(layer "In11.Cu")
	)
	(gr_line
		(start 127.306578 -319.403222)
		(end 127.314198 -319.414652)
		(stroke
			(width 0.07112)
			(type default)
		)
		(layer "In11.Cu")
	)
	(gr_line
		(start 127.397002 -280.244296)
		(end 127.395732 -280.245058)
		(stroke
			(width 0.05715)
			(type default)
		)
		(layer "In11.Cu")
	)
	(gr_line
		(start 127.397256 -295.468548)
		(end 127.397764 -295.468802)
		(stroke
			(width 0.05715)
			(type default)
		)
		(layer "In11.Cu")
	)
	(gr_line
		(start 127.39751 -280.244042)
		(end 127.397002 -280.244296)
		(stroke
			(width 0.05715)
			(type default)
		)
		(layer "In11.Cu")
	)
	(gr_line
		(start 127.397764 -295.468802)
		(end 127.39878 -295.46931)
		(stroke
			(width 0.05715)
			(type default)
		)
		(layer "In11.Cu")
	)
	(gr_line
		(start 127.397764 -279.268936)
		(end 127.39878 -279.269444)
		(stroke
			(width 0.05715)
			(type default)
		)
		(layer "In11.Cu")
	)
	(gr_line
		(start 127.39878 -295.46931)
		(end 127.400304 -295.470326)
		(stroke
			(width 0.05715)
			(type default)
		)
		(layer "In11.Cu")
	)
	(gr_line
		(start 127.39878 -279.269444)
		(end 127.400304 -279.27046)
		(stroke
			(width 0.05715)
			(type default)
		)
		(layer "In11.Cu")
	)
	(gr_line
		(start 127.400304 -295.470326)
		(end 127.40132 -295.470834)
		(stroke
			(width 0.05715)
			(type default)
		)
		(layer "In11.Cu")
	)
	(gr_line
		(start 127.400304 -279.27046)
		(end 127.40132 -279.270968)
		(stroke
			(width 0.05715)
			(type default)
		)
		(layer "In11.Cu")
	)
	(gr_line
		(start 127.40132 -295.470834)
		(end 127.4064 -295.473882)
		(stroke
			(width 0.05715)
			(type default)
		)
		(layer "In11.Cu")
	)
	(gr_line
		(start 127.40132 -279.270968)
		(end 127.4064 -279.274016)
		(stroke
			(width 0.05715)
			(type default)
		)
		(layer "In11.Cu")
	)
	(gr_line
		(start 127.423418 -295.743884)
		(end 127.423672 -295.74363)
		(stroke
			(width 0.05715)
			(type default)
		)
		(layer "In11.Cu")
	)
	(gr_line
		(start 127.489458 -295.956228)
		(end 127.489712 -295.955974)
		(stroke
			(width 0.05715)
			(type default)
		)
		(layer "In11.Cu")
	)
	(gr_line
		(start 127.622554 -431.430938)
		(end 127.749808 -431.558192)
		(stroke
			(width 0.07112)
			(type default)
		)
		(layer "In11.Cu")
	)
	(gr_line
		(start 127.622554 -431.148744)
		(end 127.749808 -431.02149)
		(stroke
			(width 0.07112)
			(type default)
		)
		(layer "In11.Cu")
	)
	(gr_line
		(start 127.727964 -296.809668)
		(end 127.727964 -296.838116)
		(stroke
			(width 0.05715)
			(type default)
		)
		(layer "In11.Cu")
	)
	(gr_line
		(start 127.739902 -414.358074)
		(end 127.997712 -414.890712)
		(stroke
			(width 0.07112)
			(type default)
		)
		(layer "In11.Cu")
	)
	(gr_line
		(start 127.749808 -431.558192)
		(end 127.749808 -431.889916)
		(stroke
			(width 0.07112)
			(type default)
		)
		(layer "In11.Cu")
	)
	(gr_line
		(start 127.749808 -431.02149)
		(end 127.749808 -430.689766)
		(stroke
			(width 0.07112)
			(type default)
		)
		(layer "In11.Cu")
	)
	(gr_line
		(start 127.773684 -296.763948)
		(end 127.727964 -296.809668)
		(stroke
			(width 0.05715)
			(type default)
		)
		(layer "In11.Cu")
	)
	(gr_line
		(start 127.964184 -296.763948)
		(end 128.009904 -296.809668)
		(stroke
			(width 0.05715)
			(type default)
		)
		(layer "In11.Cu")
	)
	(gr_line
		(start 127.993648 -414.235138)
		(end 128.251458 -414.767776)
		(stroke
			(width 0.07112)
			(type default)
		)
		(layer "In11.Cu")
	)
	(gr_line
		(start 127.997712 -414.890712)
		(end 128.303528 -415.521902)
		(stroke
			(width 0.07112)
			(type default)
		)
		(layer "In11.Cu")
	)
	(gr_line
		(start 128.009904 -296.809668)
		(end 128.009904 -296.838116)
		(stroke
			(width 0.05715)
			(type default)
		)
		(layer "In11.Cu")
	)
	(gr_line
		(start 128.010666 -412.570168)
		(end 127.719836 -412.860998)
		(stroke
			(width 0.07112)
			(type default)
		)
		(layer "In11.Cu")
	)
	(gr_line
		(start 128.253236 -414.768284)
		(end 128.4351 -414.83153)
		(stroke
			(width 0.07112)
			(type default)
		)
		(layer "In11.Cu")
	)
	(gr_line
		(start 128.260348 -349.529654)
		(end 128.260602 -349.528892)
		(stroke
			(width 0.07112)
			(type default)
		)
		(layer "In11.Cu")
	)
	(gr_line
		(start 128.304544 -342.64981)
		(end 128.304798 -342.649556)
		(stroke
			(width 0.07112)
			(type default)
		)
		(layer "In11.Cu")
	)
	(gr_line
		(start 128.4351 -414.83153)
		(end 128.621028 -415.215832)
		(stroke
			(width 0.07112)
			(type default)
		)
		(layer "In11.Cu")
	)
	(gr_line
		(start 128.567688 -342.751156)
		(end 128.567942 -342.751156)
		(stroke
			(width 0.07112)
			(type default)
		)
		(layer "In11.Cu")
	)
	(gr_line
		(start 128.567942 -342.751156)
		(end 128.586738 -342.702388)
		(stroke
			(width 0.07112)
			(type default)
		)
		(layer "In11.Cu")
	)
	(gr_line
		(start 128.571498 -305.353466)
		(end 128.571752 -305.35372)
		(stroke
			(width 0.07112)
			(type default)
		)
		(layer "In11.Cu")
	)
	(gr_line
		(start 128.586738 -342.702388)
		(end 128.586738 -342.649556)
		(stroke
			(width 0.07112)
			(type default)
		)
		(layer "In11.Cu")
	)
	(gr_line
		(start 128.607058 -416.14852)
		(end 128.91262 -416.77971)
		(stroke
			(width 0.07112)
			(type default)
		)
		(layer "In11.Cu")
	)
	(gr_line
		(start 128.621028 -415.215832)
		(end 128.557782 -415.397442)
		(stroke
			(width 0.07112)
			(type default)
		)
		(layer "In11.Cu")
	)
	(gr_arc
		(start 128.680972 -321.978528)
		(mid 128.670054 -321.957239)
		(end 128.658366 -321.936364)
		(stroke
			(width 0.07112)
			(type default)
		)
		(layer "In11.Cu")
	)
	(gr_line
		(start 128.862328 -416.026092)
		(end 129.044192 -416.089338)
		(stroke
			(width 0.07112)
			(type default)
		)
		(layer "In11.Cu")
	)
	(gr_line
		(start 128.898142 -321.785234)
		(end 128.92278 -321.822318)
		(stroke
			(width 0.07112)
			(type default)
		)
		(layer "In11.Cu")
	)
	(gr_line
		(start 128.92278 -321.822318)
		(end 128.939544 -321.862704)
		(stroke
			(width 0.07112)
			(type default)
		)
		(layer "In11.Cu")
	)
	(gr_line
		(start 129.044192 -416.089338)
		(end 129.23012 -416.47364)
		(stroke
			(width 0.07112)
			(type default)
		)
		(layer "In11.Cu")
	)
	(gr_line
		(start 129.078482 -373.719344)
		(end 128.834896 -373.96293)
		(stroke
			(width 0.07112)
			(type default)
		)
		(layer "In11.Cu")
	)
	(gr_arc
		(start 129.078482 -373.719344)
		(mid 129.109915 -373.67493)
		(end 129.12471 -373.62257)
		(stroke
			(width 0.07112)
			(type default)
		)
		(layer "In11.Cu")
	)
	(gr_line
		(start 129.13614 -369.172744)
		(end 129.13614 -369.171982)
		(stroke
			(width 0.07112)
			(type default)
		)
		(layer "In11.Cu")
	)
	(gr_line
		(start 129.23012 -416.47364)
		(end 129.167128 -416.65525)
		(stroke
			(width 0.07112)
			(type default)
		)
		(layer "In11.Cu")
	)
	(gr_line
		(start 129.407666 -369.335812)
		(end 129.407666 -369.33632)
		(stroke
			(width 0.07112)
			(type default)
		)
		(layer "In11.Cu")
	)
	(gr_arc
		(start 129.408682 -373.62257)
		(mid 129.423536 -373.674904)
		(end 129.45491 -373.719344)
		(stroke
			(width 0.07112)
			(type default)
		)
		(layer "In11.Cu")
	)
	(gr_line
		(start 129.41681 -417.820348)
		(end 129.722372 -418.451538)
		(stroke
			(width 0.07112)
			(type default)
		)
		(layer "In11.Cu")
	)
	(gr_line
		(start 129.45491 -373.719344)
		(end 129.698496 -373.96293)
		(stroke
			(width 0.07112)
			(type default)
		)
		(layer "In11.Cu")
	)
	(gr_line
		(start 129.57175 -113.231422)
		(end 129.57175 -113.231676)
		(stroke
			(width 0.07112)
			(type default)
		)
		(layer "In11.Cu")
	)
	(gr_line
		(start 129.62255 -430.43094)
		(end 129.749804 -430.558194)
		(stroke
			(width 0.07112)
			(type default)
		)
		(layer "In11.Cu")
	)
	(gr_line
		(start 129.62255 -430.148746)
		(end 129.749804 -430.021492)
		(stroke
			(width 0.07112)
			(type default)
		)
		(layer "In11.Cu")
	)
	(gr_line
		(start 129.67208 -417.69792)
		(end 129.853944 -417.760912)
		(stroke
			(width 0.07112)
			(type default)
		)
		(layer "In11.Cu")
	)
	(gr_line
		(start 129.749804 -430.558194)
		(end 129.749804 -430.889918)
		(stroke
			(width 0.07112)
			(type default)
		)
		(layer "In11.Cu")
	)
	(gr_line
		(start 129.749804 -430.021492)
		(end 129.749804 -429.689768)
		(stroke
			(width 0.07112)
			(type default)
		)
		(layer "In11.Cu")
	)
	(gr_line
		(start 129.853944 -417.760912)
		(end 130.040126 -418.145214)
		(stroke
			(width 0.07112)
			(type default)
		)
		(layer "In11.Cu")
	)
	(gr_line
		(start 130.008122 -419.041326)
		(end 130.313938 -419.672516)
		(stroke
			(width 0.07112)
			(type default)
		)
		(layer "In11.Cu")
	)
	(gr_line
		(start 130.040126 -418.145214)
		(end 129.97688 -418.327078)
		(stroke
			(width 0.07112)
			(type default)
		)
		(layer "In11.Cu")
	)
	(gr_line
		(start 130.210306 -412.570168)
		(end 130.453638 -412.8135)
		(stroke
			(width 0.07112)
			(type default)
		)
		(layer "In11.Cu")
	)
	(gr_line
		(start 130.263392 -418.918898)
		(end 130.44551 -418.982144)
		(stroke
			(width 0.07112)
			(type default)
		)
		(layer "In11.Cu")
	)
	(gr_line
		(start 130.44551 -418.982144)
		(end 130.631438 -419.366446)
		(stroke
			(width 0.07112)
			(type default)
		)
		(layer "In11.Cu")
	)
	(gr_arc
		(start 130.50012 -412.910782)
		(mid 130.485238 -412.858145)
		(end 130.453638 -412.8135)
		(stroke
			(width 0.07112)
			(type default)
		)
		(layer "In11.Cu")
	)
	(gr_line
		(start 130.631438 -419.366446)
		(end 130.568446 -419.54831)
		(stroke
			(width 0.07112)
			(type default)
		)
		(layer "In11.Cu")
	)
	(gr_line
		(start 130.6322 -191.523366)
		(end 130.6322 -191.52362)
		(stroke
			(width 0.07112)
			(type default)
		)
		(layer "In11.Cu")
	)
	(gr_line
		(start 130.764026 -414.227518)
		(end 131.000246 -414.888172)
		(stroke
			(width 0.07112)
			(type default)
		)
		(layer "In11.Cu")
	)
	(gr_line
		(start 130.827526 -371.2083)
		(end 130.536696 -371.49913)
		(stroke
			(width 0.07112)
			(type default)
		)
		(layer "In11.Cu")
	)
	(gr_arc
		(start 130.830574 -412.8135)
		(mid 130.79901 -412.858166)
		(end 130.784092 -412.910782)
		(stroke
			(width 0.07112)
			(type default)
		)
		(layer "In11.Cu")
	)
	(gr_line
		(start 130.930142 -366.49406)
		(end 130.93065 -366.493806)
		(stroke
			(width 0.07112)
			(type default)
		)
		(layer "In11.Cu")
	)
	(gr_line
		(start 131.03098 -414.133284)
		(end 131.20497 -414.21558)
		(stroke
			(width 0.07112)
			(type default)
		)
		(layer "In11.Cu")
	)
	(gr_line
		(start 131.073906 -412.570168)
		(end 130.830574 -412.8135)
		(stroke
			(width 0.07112)
			(type default)
		)
		(layer "In11.Cu")
	)
	(gr_line
		(start 131.109466 -371.2083)
		(end 131.400296 -371.49913)
		(stroke
			(width 0.07112)
			(type default)
		)
		(layer "In11.Cu")
	)
	(gr_line
		(start 131.12115 -366.395254)
		(end 131.120642 -366.395508)
		(stroke
			(width 0.07112)
			(type default)
		)
		(layer "In11.Cu")
	)
	(gr_line
		(start 131.143502 -415.288476)
		(end 131.143756 -415.289238)
		(stroke
			(width 0.07112)
			(type default)
		)
		(layer "In11.Cu")
	)
	(gr_line
		(start 131.143756 -415.289238)
		(end 131.379976 -415.949892)
		(stroke
			(width 0.07112)
			(type default)
		)
		(layer "In11.Cu")
	)
	(gr_line
		(start 131.20497 -414.21558)
		(end 131.348734 -414.617662)
		(stroke
			(width 0.07112)
			(type default)
		)
		(layer "In11.Cu")
	)
	(gr_line
		(start 131.348734 -414.617662)
		(end 131.266438 -414.791652)
		(stroke
			(width 0.07112)
			(type default)
		)
		(layer "In11.Cu")
	)
	(gr_line
		(start 131.40944 -415.193734)
		(end 131.409694 -415.194496)
		(stroke
			(width 0.07112)
			(type default)
		)
		(layer "In11.Cu")
	)
	(gr_line
		(start 131.410964 -415.195004)
		(end 131.585208 -415.277554)
		(stroke
			(width 0.07112)
			(type default)
		)
		(layer "In11.Cu")
	)
	(gr_line
		(start 131.585208 -415.277554)
		(end 131.728972 -415.679636)
		(stroke
			(width 0.07112)
			(type default)
		)
		(layer "In11.Cu")
	)
	(gr_line
		(start 131.622546 -431.430938)
		(end 131.7498 -431.558192)
		(stroke
			(width 0.07112)
			(type default)
		)
		(layer "In11.Cu")
	)
	(gr_line
		(start 131.622546 -431.148744)
		(end 131.7498 -431.02149)
		(stroke
			(width 0.07112)
			(type default)
		)
		(layer "In11.Cu")
	)
	(gr_line
		(start 131.728972 -415.679636)
		(end 131.646422 -415.853626)
		(stroke
			(width 0.07112)
			(type default)
		)
		(layer "In11.Cu")
	)
	(gr_line
		(start 131.7498 -431.558192)
		(end 131.7498 -431.889916)
		(stroke
			(width 0.07112)
			(type default)
		)
		(layer "In11.Cu")
	)
	(gr_line
		(start 131.7498 -431.02149)
		(end 131.7498 -430.689766)
		(stroke
			(width 0.07112)
			(type default)
		)
		(layer "In11.Cu")
	)
	(gr_line
		(start 132.529326 -368.7445)
		(end 132.238496 -369.03533)
		(stroke
			(width 0.07112)
			(type default)
		)
		(layer "In11.Cu")
	)
	(gr_line
		(start 132.811266 -368.7445)
		(end 133.102096 -369.03533)
		(stroke
			(width 0.07112)
			(type default)
		)
		(layer "In11.Cu")
	)
	(gr_line
		(start 133.273546 -412.570168)
		(end 133.564376 -412.860998)
		(stroke
			(width 0.07112)
			(type default)
		)
		(layer "In11.Cu")
	)
	(gr_line
		(start 133.599174 -430.125632)
		(end 133.622796 -430.125632)
		(stroke
			(width 0.07112)
			(type default)
		)
		(layer "In11.Cu")
	)
	(gr_line
		(start 133.600444 -430.408842)
		(end 133.749796 -430.558194)
		(stroke
			(width 0.07112)
			(type default)
		)
		(layer "In11.Cu")
	)
	(gr_line
		(start 133.622796 -430.125632)
		(end 133.749796 -429.998632)
		(stroke
			(width 0.07112)
			(type default)
		)
		(layer "In11.Cu")
	)
	(gr_line
		(start 133.749796 -430.558194)
		(end 133.749796 -430.889918)
		(stroke
			(width 0.07112)
			(type default)
		)
		(layer "In11.Cu")
	)
	(gr_line
		(start 133.749796 -429.998632)
		(end 133.749796 -429.689768)
		(stroke
			(width 0.07112)
			(type default)
		)
		(layer "In11.Cu")
	)
	(gr_line
		(start 134.137146 -412.570168)
		(end 133.846316 -412.860998)
		(stroke
			(width 0.07112)
			(type default)
		)
		(layer "In11.Cu")
	)
	(gr_line
		(start 134.13867 -415.705544)
		(end 134.309104 -416.385756)
		(stroke
			(width 0.07112)
			(type default)
		)
		(layer "In11.Cu")
	)
	(gr_line
		(start 134.413752 -415.63798)
		(end 134.578852 -415.736786)
		(stroke
			(width 0.07112)
			(type default)
		)
		(layer "In11.Cu")
	)
	(gr_line
		(start 134.483856 -417.08324)
		(end 134.578852 -417.463224)
		(stroke
			(width 0.07112)
			(type default)
		)
		(layer "In11.Cu")
	)
	(gr_line
		(start 134.578852 -417.463224)
		(end 134.749286 -418.143436)
		(stroke
			(width 0.07112)
			(type default)
		)
		(layer "In11.Cu")
	)
	(gr_line
		(start 134.578852 -415.736786)
		(end 134.682484 -416.150806)
		(stroke
			(width 0.07112)
			(type default)
		)
		(layer "In11.Cu")
	)
	(gr_arc
		(start 134.657338 -341.5284)
		(mid 134.657338 -341.528654)
		(end 134.657338 -341.528908)
		(stroke
			(width 0.07112)
			(type default)
		)
		(layer "In11.Cu")
	)
	(gr_line
		(start 134.682484 -416.150806)
		(end 134.583424 -416.315652)
		(stroke
			(width 0.07112)
			(type default)
		)
		(layer "In11.Cu")
	)
	(gr_line
		(start 134.853934 -417.39566)
		(end 135.019034 -417.494466)
		(stroke
			(width 0.07112)
			(type default)
		)
		(layer "In11.Cu")
	)
	(gr_line
		(start 134.898384 -418.73805)
		(end 135.068818 -419.418262)
		(stroke
			(width 0.07112)
			(type default)
		)
		(layer "In11.Cu")
	)
	(gr_line
		(start 135.019034 -417.494466)
		(end 135.122666 -417.908486)
		(stroke
			(width 0.07112)
			(type default)
		)
		(layer "In11.Cu")
	)
	(gr_line
		(start 135.122666 -417.908486)
		(end 135.02386 -418.073586)
		(stroke
			(width 0.07112)
			(type default)
		)
		(layer "In11.Cu")
	)
	(gr_line
		(start 135.173212 -418.670232)
		(end 135.338566 -418.769038)
		(stroke
			(width 0.07112)
			(type default)
		)
		(layer "In11.Cu")
	)
	(gr_line
		(start 135.338566 -418.769038)
		(end 135.442198 -419.183312)
		(stroke
			(width 0.07112)
			(type default)
		)
		(layer "In11.Cu")
	)
	(gr_line
		(start 135.396732 -420.727632)
		(end 135.567166 -421.407844)
		(stroke
			(width 0.07112)
			(type default)
		)
		(layer "In11.Cu")
	)
	(gr_line
		(start 135.442198 -419.183312)
		(end 135.343138 -419.348412)
		(stroke
			(width 0.07112)
			(type default)
		)
		(layer "In11.Cu")
	)
	(gr_line
		(start 135.622538 -431.430938)
		(end 135.749792 -431.558192)
		(stroke
			(width 0.07112)
			(type default)
		)
		(layer "In11.Cu")
	)
	(gr_line
		(start 135.622538 -431.148744)
		(end 135.749792 -431.02149)
		(stroke
			(width 0.07112)
			(type default)
		)
		(layer "In11.Cu")
	)
	(gr_line
		(start 135.67156 -420.659814)
		(end 135.836914 -420.75862)
		(stroke
			(width 0.07112)
			(type default)
		)
		(layer "In11.Cu")
	)
	(gr_line
		(start 135.749792 -431.558192)
		(end 135.749792 -431.889916)
		(stroke
			(width 0.07112)
			(type default)
		)
		(layer "In11.Cu")
	)
	(gr_line
		(start 135.749792 -431.02149)
		(end 135.749792 -430.689766)
		(stroke
			(width 0.07112)
			(type default)
		)
		(layer "In11.Cu")
	)
	(gr_line
		(start 135.836914 -420.75862)
		(end 135.940546 -421.172894)
		(stroke
			(width 0.07112)
			(type default)
		)
		(layer "In11.Cu")
	)
	(gr_line
		(start 135.906002 -12.245848)
		(end 135.615172 -11.955018)
		(stroke
			(width 0.07112)
			(type default)
		)
		(layer "In11.Cu")
	)
	(gr_line
		(start 135.932926 -368.7445)
		(end 135.642096 -369.03533)
		(stroke
			(width 0.07112)
			(type default)
		)
		(layer "In11.Cu")
	)
	(gr_line
		(start 135.940546 -421.172894)
		(end 135.841486 -421.337994)
		(stroke
			(width 0.07112)
			(type default)
		)
		(layer "In11.Cu")
	)
	(gr_line
		(start 136.187942 -12.245848)
		(end 136.478772 -11.955018)
		(stroke
			(width 0.07112)
			(type default)
		)
		(layer "In11.Cu")
	)
	(gr_line
		(start 136.214866 -368.7445)
		(end 136.505696 -369.03533)
		(stroke
			(width 0.07112)
			(type default)
		)
		(layer "In11.Cu")
	)
	(gr_line
		(start 136.336786 -412.570168)
		(end 136.627616 -412.860998)
		(stroke
			(width 0.07112)
			(type default)
		)
		(layer "In11.Cu")
	)
	(gr_line
		(start 136.479788 -312.802524)
		(end 136.479788 -312.802778)
		(stroke
			(width 0.07112)
			(type default)
		)
		(layer "In11.Cu")
	)
	(gr_line
		(start 136.957054 -415.245804)
		(end 137.085324 -415.93516)
		(stroke
			(width 0.07112)
			(type default)
		)
		(layer "In11.Cu")
	)
	(gr_line
		(start 137.200386 -412.570168)
		(end 136.909556 -412.860998)
		(stroke
			(width 0.07112)
			(type default)
		)
		(layer "In11.Cu")
	)
	(gr_line
		(start 137.20699 -416.587178)
		(end 137.33526 -417.276026)
		(stroke
			(width 0.07112)
			(type default)
		)
		(layer "In11.Cu")
	)
	(gr_line
		(start 137.235692 -415.195258)
		(end 137.394188 -415.303716)
		(stroke
			(width 0.07112)
			(type default)
		)
		(layer "In11.Cu")
	)
	(gr_line
		(start 137.33526 -417.276026)
		(end 137.33526 -417.276534)
		(stroke
			(width 0.07112)
			(type default)
		)
		(layer "In11.Cu")
	)
	(gr_line
		(start 137.394188 -415.303716)
		(end 137.47242 -415.723578)
		(stroke
			(width 0.07112)
			(type default)
		)
		(layer "In11.Cu")
	)
	(gr_line
		(start 137.47242 -415.723578)
		(end 137.363708 -415.882328)
		(stroke
			(width 0.07112)
			(type default)
		)
		(layer "In11.Cu")
	)
	(gr_line
		(start 137.485628 -416.536632)
		(end 137.644378 -416.645344)
		(stroke
			(width 0.07112)
			(type default)
		)
		(layer "In11.Cu")
	)
	(gr_line
		(start 137.599166 -430.125632)
		(end 137.622788 -430.125632)
		(stroke
			(width 0.07112)
			(type default)
		)
		(layer "In11.Cu")
	)
	(gr_line
		(start 137.600436 -430.408842)
		(end 137.749788 -430.558194)
		(stroke
			(width 0.07112)
			(type default)
		)
		(layer "In11.Cu")
	)
	(gr_line
		(start 137.613136 -417.22421)
		(end 137.612628 -417.224972)
		(stroke
			(width 0.07112)
			(type default)
		)
		(layer "In11.Cu")
	)
	(gr_line
		(start 137.622788 -430.125632)
		(end 137.749788 -429.998632)
		(stroke
			(width 0.07112)
			(type default)
		)
		(layer "In11.Cu")
	)
	(gr_line
		(start 137.644378 -416.645344)
		(end 137.722356 -417.064952)
		(stroke
			(width 0.07112)
			(type default)
		)
		(layer "In11.Cu")
	)
	(gr_line
		(start 137.722356 -417.064952)
		(end 137.613644 -417.223702)
		(stroke
			(width 0.07112)
			(type default)
		)
		(layer "In11.Cu")
	)
	(gr_line
		(start 137.749788 -430.558194)
		(end 137.749788 -430.889918)
		(stroke
			(width 0.07112)
			(type default)
		)
		(layer "In11.Cu")
	)
	(gr_line
		(start 137.749788 -429.998632)
		(end 137.749788 -429.689768)
		(stroke
			(width 0.07112)
			(type default)
		)
		(layer "In11.Cu")
	)
	(gr_line
		(start 138.086846 -376.665998)
		(end 138.377676 -376.956828)
		(stroke
			(width 0.07112)
			(type default)
		)
		(layer "In11.Cu")
	)
	(gr_line
		(start 138.086846 -376.384058)
		(end 138.377676 -376.093228)
		(stroke
			(width 0.07112)
			(type default)
		)
		(layer "In11.Cu")
	)
	(gr_line
		(start 138.574272 -374.196864)
		(end 138.382248 -374.196864)
		(stroke
			(width 0.07112)
			(type default)
		)
		(layer "In11.Cu")
	)
	(gr_line
		(start 138.668506 -380.069598)
		(end 138.377676 -380.360428)
		(stroke
			(width 0.07112)
			(type default)
		)
		(layer "In11.Cu")
	)
	(gr_line
		(start 138.668506 -379.787658)
		(end 138.377676 -379.496828)
		(stroke
			(width 0.07112)
			(type default)
		)
		(layer "In11.Cu")
	)
	(gr_line
		(start 138.676888 -373.501666)
		(end 138.18108 -373.997474)
		(stroke
			(width 0.07112)
			(type default)
		)
		(layer "In11.Cu")
	)
	(gr_line
		(start 138.876278 -373.894858)
		(end 138.574272 -374.196864)
		(stroke
			(width 0.07112)
			(type default)
		)
		(layer "In11.Cu")
	)
	(gr_line
		(start 138.876278 -373.702834)
		(end 138.876278 -373.894858)
		(stroke
			(width 0.07112)
			(type default)
		)
		(layer "In11.Cu")
	)
	(gr_line
		(start 139.400026 -412.570168)
		(end 139.690856 -412.860998)
		(stroke
			(width 0.07112)
			(type default)
		)
		(layer "In11.Cu")
	)
	(gr_line
		(start 139.458446 -378.498608)
		(end 139.594336 -378.634498)
		(stroke
			(width 0.07112)
			(type default)
		)
		(layer "In11.Cu")
	)
	(gr_line
		(start 139.458446 -378.071888)
		(end 139.458446 -378.498608)
		(stroke
			(width 0.07112)
			(type default)
		)
		(layer "In11.Cu")
	)
	(gr_line
		(start 139.594336 -377.935998)
		(end 139.458446 -378.071888)
		(stroke
			(width 0.07112)
			(type default)
		)
		(layer "In11.Cu")
	)
	(gr_line
		(start 139.62253 -431.430938)
		(end 139.749784 -431.558192)
		(stroke
			(width 0.07112)
			(type default)
		)
		(layer "In11.Cu")
	)
	(gr_line
		(start 139.62253 -431.148744)
		(end 139.749784 -431.02149)
		(stroke
			(width 0.07112)
			(type default)
		)
		(layer "In11.Cu")
	)
	(gr_line
		(start 139.654788 -369.78717)
		(end 139.654788 -370.521484)
		(stroke
			(width 0.07112)
			(type default)
		)
		(layer "In11.Cu")
	)
	(gr_line
		(start 139.654788 -368.65941)
		(end 139.654788 -369.36045)
		(stroke
			(width 0.07112)
			(type default)
		)
		(layer "In11.Cu")
	)
	(gr_line
		(start 139.749784 -431.558192)
		(end 139.749784 -431.889916)
		(stroke
			(width 0.07112)
			(type default)
		)
		(layer "In11.Cu")
	)
	(gr_line
		(start 139.749784 -431.02149)
		(end 139.749784 -430.689766)
		(stroke
			(width 0.07112)
			(type default)
		)
		(layer "In11.Cu")
	)
	(gr_line
		(start 139.764516 -414.51149)
		(end 139.833096 -415.209482)
		(stroke
			(width 0.07112)
			(type default)
		)
		(layer "In11.Cu")
	)
	(gr_line
		(start 139.877546 -377.934728)
		(end 139.877546 -378.635768)
		(stroke
			(width 0.07112)
			(type default)
		)
		(layer "In11.Cu")
	)
	(gr_line
		(start 139.937998 -369.78844)
		(end 140.073888 -369.92433)
		(stroke
			(width 0.07112)
			(type default)
		)
		(layer "In11.Cu")
	)
	(gr_line
		(start 139.937998 -368.66068)
		(end 140.073888 -368.79657)
		(stroke
			(width 0.07112)
			(type default)
		)
		(layer "In11.Cu")
	)
	(gr_line
		(start 139.944348 -416.343338)
		(end 139.955778 -416.459924)
		(stroke
			(width 0.07112)
			(type default)
		)
		(layer "In11.Cu")
	)
	(gr_line
		(start 139.955778 -416.459924)
		(end 139.956032 -416.460178)
		(stroke
			(width 0.07112)
			(type default)
		)
		(layer "In11.Cu")
	)
	(gr_line
		(start 139.956032 -416.460178)
		(end 140.013182 -417.04133)
		(stroke
			(width 0.07112)
			(type default)
		)
		(layer "In11.Cu")
	)
	(gr_arc
		(start 139.983972 -370.440966)
		(mid 139.953166 -370.483997)
		(end 139.937998 -370.534692)
		(stroke
			(width 0.07112)
			(type default)
		)
		(layer "In11.Cu")
	)
	(gr_line
		(start 140.046456 -414.48482)
		(end 140.1953 -414.606994)
		(stroke
			(width 0.07112)
			(type default)
		)
		(layer "In11.Cu")
	)
	(gr_line
		(start 140.073888 -370.35105)
		(end 139.983972 -370.440966)
		(stroke
			(width 0.07112)
			(type default)
		)
		(layer "In11.Cu")
	)
	(gr_line
		(start 140.073888 -369.92433)
		(end 140.073888 -370.35105)
		(stroke
			(width 0.07112)
			(type default)
		)
		(layer "In11.Cu")
	)
	(gr_line
		(start 140.073888 -369.22329)
		(end 139.937998 -369.35918)
		(stroke
			(width 0.07112)
			(type default)
		)
		(layer "In11.Cu")
	)
	(gr_line
		(start 140.073888 -368.79657)
		(end 140.073888 -369.22329)
		(stroke
			(width 0.07112)
			(type default)
		)
		(layer "In11.Cu")
	)
	(gr_line
		(start 140.078968 -417.70935)
		(end 140.147802 -418.407342)
		(stroke
			(width 0.07112)
			(type default)
		)
		(layer "In11.Cu")
	)
	(gr_line
		(start 140.1953 -414.606994)
		(end 140.236956 -415.031682)
		(stroke
			(width 0.07112)
			(type default)
		)
		(layer "In11.Cu")
	)
	(gr_line
		(start 140.206984 -419.008306)
		(end 140.275818 -419.706298)
		(stroke
			(width 0.07112)
			(type default)
		)
		(layer "In11.Cu")
	)
	(gr_line
		(start 140.226288 -416.316668)
		(end 140.375386 -416.439096)
		(stroke
			(width 0.07112)
			(type default)
		)
		(layer "In11.Cu")
	)
	(gr_line
		(start 140.236956 -415.031682)
		(end 140.114782 -415.18078)
		(stroke
			(width 0.07112)
			(type default)
		)
		(layer "In11.Cu")
	)
	(gr_line
		(start 140.263626 -412.570168)
		(end 139.972796 -412.860998)
		(stroke
			(width 0.07112)
			(type default)
		)
		(layer "In11.Cu")
	)
	(gr_line
		(start 140.355828 -417.642802)
		(end 140.359638 -417.681918)
		(stroke
			(width 0.07112)
			(type default)
		)
		(layer "In11.Cu")
	)
	(gr_line
		(start 140.361162 -417.683188)
		(end 140.510006 -417.804854)
		(stroke
			(width 0.07112)
			(type default)
		)
		(layer "In11.Cu")
	)
	(gr_line
		(start 140.375386 -416.439096)
		(end 140.417296 -416.864038)
		(stroke
			(width 0.07112)
			(type default)
		)
		(layer "In11.Cu")
	)
	(gr_line
		(start 140.417296 -416.864038)
		(end 140.295122 -417.012882)
		(stroke
			(width 0.07112)
			(type default)
		)
		(layer "In11.Cu")
	)
	(gr_line
		(start 140.488924 -418.981382)
		(end 140.638022 -419.10381)
		(stroke
			(width 0.07112)
			(type default)
		)
		(layer "In11.Cu")
	)
	(gr_line
		(start 140.510006 -417.804854)
		(end 140.551662 -418.229796)
		(stroke
			(width 0.07112)
			(type default)
		)
		(layer "In11.Cu")
	)
	(gr_line
		(start 140.551662 -418.229796)
		(end 140.429488 -418.37864)
		(stroke
			(width 0.07112)
			(type default)
		)
		(layer "In11.Cu")
	)
	(gr_line
		(start 140.638022 -419.10381)
		(end 140.679678 -419.528752)
		(stroke
			(width 0.07112)
			(type default)
		)
		(layer "In11.Cu")
	)
	(gr_line
		(start 140.679678 -419.528752)
		(end 140.557504 -419.677596)
		(stroke
			(width 0.07112)
			(type default)
		)
		(layer "In11.Cu")
	)
	(gr_line
		(start 140.901674 -370.830094)
		(end 141.037564 -370.965984)
		(stroke
			(width 0.07112)
			(type default)
		)
		(layer "In11.Cu")
	)
	(gr_line
		(start 140.901674 -370.403374)
		(end 140.901674 -370.830094)
		(stroke
			(width 0.07112)
			(type default)
		)
		(layer "In11.Cu")
	)
	(gr_line
		(start 140.901674 -369.702334)
		(end 141.037564 -369.838224)
		(stroke
			(width 0.07112)
			(type default)
		)
		(layer "In11.Cu")
	)
	(gr_line
		(start 140.901674 -369.275614)
		(end 140.901674 -369.702334)
		(stroke
			(width 0.07112)
			(type default)
		)
		(layer "In11.Cu")
	)
	(gr_line
		(start 140.901674 -368.574574)
		(end 141.037564 -368.710464)
		(stroke
			(width 0.07112)
			(type default)
		)
		(layer "In11.Cu")
	)
	(gr_line
		(start 140.901674 -368.147854)
		(end 140.901674 -368.574574)
		(stroke
			(width 0.07112)
			(type default)
		)
		(layer "In11.Cu")
	)
	(gr_line
		(start 141.0208 -363.30636)
		(end 140.752322 -363.954314)
		(stroke
			(width 0.07112)
			(type default)
		)
		(layer "In11.Cu")
	)
	(gr_line
		(start 141.021054 -363.30636)
		(end 141.0208 -363.30636)
		(stroke
			(width 0.07112)
			(type default)
		)
		(layer "In11.Cu")
	)
	(gr_line
		(start 141.037564 -370.267484)
		(end 140.901674 -370.403374)
		(stroke
			(width 0.07112)
			(type default)
		)
		(layer "In11.Cu")
	)
	(gr_line
		(start 141.037564 -369.139724)
		(end 140.901674 -369.275614)
		(stroke
			(width 0.07112)
			(type default)
		)
		(layer "In11.Cu")
	)
	(gr_line
		(start 141.037564 -368.011964)
		(end 140.901674 -368.147854)
		(stroke
			(width 0.07112)
			(type default)
		)
		(layer "In11.Cu")
	)
	(gr_line
		(start 141.192504 -363.988096)
		(end 141.01445 -364.061756)
		(stroke
			(width 0.07112)
			(type default)
		)
		(layer "In11.Cu")
	)
	(gr_line
		(start 141.282166 -363.41558)
		(end 141.355826 -363.593634)
		(stroke
			(width 0.07112)
			(type default)
		)
		(layer "In11.Cu")
	)
	(gr_line
		(start 141.320774 -370.266214)
		(end 141.320774 -370.967254)
		(stroke
			(width 0.07112)
			(type default)
		)
		(layer "In11.Cu")
	)
	(gr_line
		(start 141.320774 -369.138454)
		(end 141.320774 -369.839494)
		(stroke
			(width 0.07112)
			(type default)
		)
		(layer "In11.Cu")
	)
	(gr_line
		(start 141.320774 -368.010694)
		(end 141.320774 -368.711734)
		(stroke
			(width 0.07112)
			(type default)
		)
		(layer "In11.Cu")
	)
	(gr_line
		(start 141.355826 -363.593634)
		(end 141.192504 -363.988096)
		(stroke
			(width 0.07112)
			(type default)
		)
		(layer "In11.Cu")
	)
	(gr_line
		(start 142.463266 -412.570168)
		(end 142.754096 -412.860998)
		(stroke
			(width 0.07112)
			(type default)
		)
		(layer "In11.Cu")
	)
	(gr_line
		(start 142.59941 -430.125632)
		(end 142.623032 -430.125632)
		(stroke
			(width 0.07112)
			(type default)
		)
		(layer "In11.Cu")
	)
	(gr_line
		(start 142.60068 -430.408842)
		(end 142.750032 -430.558194)
		(stroke
			(width 0.07112)
			(type default)
		)
		(layer "In11.Cu")
	)
	(gr_line
		(start 142.623032 -430.125632)
		(end 142.750032 -429.998632)
		(stroke
			(width 0.07112)
			(type default)
		)
		(layer "In11.Cu")
	)
	(gr_line
		(start 142.750032 -430.558194)
		(end 142.750032 -430.889918)
		(stroke
			(width 0.07112)
			(type default)
		)
		(layer "In11.Cu")
	)
	(gr_line
		(start 142.750032 -429.998632)
		(end 142.750032 -429.689768)
		(stroke
			(width 0.07112)
			(type default)
		)
		(layer "In11.Cu")
	)
	(gr_line
		(start 142.758922 -414.839658)
		(end 142.797276 -415.228532)
		(stroke
			(width 0.07112)
			(type default)
		)
		(layer "In11.Cu")
	)
	(gr_line
		(start 142.797276 -415.228532)
		(end 142.865856 -415.926778)
		(stroke
			(width 0.07112)
			(type default)
		)
		(layer "In11.Cu")
	)
	(gr_line
		(start 142.912592 -416.39998)
		(end 142.981172 -417.096448)
		(stroke
			(width 0.07112)
			(type default)
		)
		(layer "In11.Cu")
	)
	(gr_line
		(start 142.981172 -417.096448)
		(end 142.981426 -417.097464)
		(stroke
			(width 0.07112)
			(type default)
		)
		(layer "In11.Cu")
	)
	(gr_line
		(start 143.039592 -414.812226)
		(end 143.077692 -415.2011)
		(stroke
			(width 0.07112)
			(type default)
		)
		(layer "In11.Cu")
	)
	(gr_line
		(start 143.079216 -415.20237)
		(end 143.22806 -415.32429)
		(stroke
			(width 0.07112)
			(type default)
		)
		(layer "In11.Cu")
	)
	(gr_line
		(start 143.194532 -416.37331)
		(end 143.343376 -416.49523)
		(stroke
			(width 0.07112)
			(type default)
		)
		(layer "In11.Cu")
	)
	(gr_line
		(start 143.22806 -415.32429)
		(end 143.269716 -415.749232)
		(stroke
			(width 0.07112)
			(type default)
		)
		(layer "In11.Cu")
	)
	(gr_line
		(start 143.269716 -415.749232)
		(end 143.147796 -415.897822)
		(stroke
			(width 0.07112)
			(type default)
		)
		(layer "In11.Cu")
	)
	(gr_line
		(start 143.326866 -412.570168)
		(end 143.036036 -412.860998)
		(stroke
			(width 0.07112)
			(type default)
		)
		(layer "In11.Cu")
	)
	(gr_line
		(start 143.343376 -416.49523)
		(end 143.385286 -416.920172)
		(stroke
			(width 0.07112)
			(type default)
		)
		(layer "In11.Cu")
	)
	(gr_line
		(start 143.385286 -416.920172)
		(end 143.262096 -417.070032)
		(stroke
			(width 0.07112)
			(type default)
		)
		(layer "In11.Cu")
	)
	(gr_line
		(start 144.622774 -431.430938)
		(end 144.750028 -431.558192)
		(stroke
			(width 0.07112)
			(type default)
		)
		(layer "In11.Cu")
	)
	(gr_line
		(start 144.622774 -431.148744)
		(end 144.750028 -431.02149)
		(stroke
			(width 0.07112)
			(type default)
		)
		(layer "In11.Cu")
	)
	(gr_line
		(start 144.750028 -431.558192)
		(end 144.750028 -431.889916)
		(stroke
			(width 0.07112)
			(type default)
		)
		(layer "In11.Cu")
	)
	(gr_line
		(start 144.750028 -431.02149)
		(end 144.750028 -430.689766)
		(stroke
			(width 0.07112)
			(type default)
		)
		(layer "In11.Cu")
	)
	(gr_line
		(start 145.526506 -412.570168)
		(end 145.805144 -412.848806)
		(stroke
			(width 0.07112)
			(type default)
		)
		(layer "In11.Cu")
	)
	(gr_line
		(start 145.805144 -417.992052)
		(end 145.805144 -418.693092)
		(stroke
			(width 0.07112)
			(type default)
		)
		(layer "In11.Cu")
	)
	(gr_line
		(start 145.805144 -416.819588)
		(end 145.805144 -417.520628)
		(stroke
			(width 0.07112)
			(type default)
		)
		(layer "In11.Cu")
	)
	(gr_line
		(start 145.805144 -415.318194)
		(end 145.805144 -416.019234)
		(stroke
			(width 0.07112)
			(type default)
		)
		(layer "In11.Cu")
	)
	(gr_line
		(start 145.805144 -414.190434)
		(end 145.805144 -414.891474)
		(stroke
			(width 0.07112)
			(type default)
		)
		(layer "In11.Cu")
	)
	(gr_line
		(start 145.805144 -412.848806)
		(end 145.805144 -412.87319)
		(stroke
			(width 0.07112)
			(type default)
		)
		(layer "In11.Cu")
	)
	(gr_line
		(start 146.088354 -417.993322)
		(end 146.224244 -418.129212)
		(stroke
			(width 0.07112)
			(type default)
		)
		(layer "In11.Cu")
	)
	(gr_line
		(start 146.088354 -416.820858)
		(end 146.224244 -416.956748)
		(stroke
			(width 0.07112)
			(type default)
		)
		(layer "In11.Cu")
	)
	(gr_line
		(start 146.088354 -415.319464)
		(end 146.224244 -415.455354)
		(stroke
			(width 0.07112)
			(type default)
		)
		(layer "In11.Cu")
	)
	(gr_line
		(start 146.088354 -414.191704)
		(end 146.224244 -414.327594)
		(stroke
			(width 0.07112)
			(type default)
		)
		(layer "In11.Cu")
	)
	(gr_line
		(start 146.224244 -418.555932)
		(end 146.088354 -418.691822)
		(stroke
			(width 0.07112)
			(type default)
		)
		(layer "In11.Cu")
	)
	(gr_line
		(start 146.224244 -418.129212)
		(end 146.224244 -418.555932)
		(stroke
			(width 0.07112)
			(type default)
		)
		(layer "In11.Cu")
	)
	(gr_line
		(start 146.224244 -417.383468)
		(end 146.088354 -417.519358)
		(stroke
			(width 0.07112)
			(type default)
		)
		(layer "In11.Cu")
	)
	(gr_line
		(start 146.224244 -416.956748)
		(end 146.224244 -417.383468)
		(stroke
			(width 0.07112)
			(type default)
		)
		(layer "In11.Cu")
	)
	(gr_line
		(start 146.224244 -415.882074)
		(end 146.088354 -416.017964)
		(stroke
			(width 0.07112)
			(type default)
		)
		(layer "In11.Cu")
	)
	(gr_line
		(start 146.224244 -415.455354)
		(end 146.224244 -415.882074)
		(stroke
			(width 0.07112)
			(type default)
		)
		(layer "In11.Cu")
	)
	(gr_line
		(start 146.224244 -414.754314)
		(end 146.088354 -414.890204)
		(stroke
			(width 0.07112)
			(type default)
		)
		(layer "In11.Cu")
	)
	(gr_line
		(start 146.224244 -414.327594)
		(end 146.224244 -414.754314)
		(stroke
			(width 0.07112)
			(type default)
		)
		(layer "In11.Cu")
	)
	(gr_line
		(start 146.390106 -412.570168)
		(end 146.088354 -412.87192)
		(stroke
			(width 0.07112)
			(type default)
		)
		(layer "In11.Cu")
	)
	(gr_line
		(start 146.599402 -430.125632)
		(end 146.623024 -430.125632)
		(stroke
			(width 0.07112)
			(type default)
		)
		(layer "In11.Cu")
	)
	(gr_line
		(start 146.600672 -430.408842)
		(end 146.750024 -430.558194)
		(stroke
			(width 0.07112)
			(type default)
		)
		(layer "In11.Cu")
	)
	(gr_line
		(start 146.623024 -430.125632)
		(end 146.750024 -429.998632)
		(stroke
			(width 0.07112)
			(type default)
		)
		(layer "In11.Cu")
	)
	(gr_line
		(start 146.750024 -430.558194)
		(end 146.750024 -430.889918)
		(stroke
			(width 0.07112)
			(type default)
		)
		(layer "In11.Cu")
	)
	(gr_line
		(start 146.750024 -429.998632)
		(end 146.750024 -429.689768)
		(stroke
			(width 0.07112)
			(type default)
		)
		(layer "In11.Cu")
	)
	(gr_line
		(start 148.566378 -417.199826)
		(end 148.543264 -417.43376)
		(stroke
			(width 0.07112)
			(type default)
		)
		(layer "In11.Cu")
	)
	(gr_line
		(start 148.589492 -416.967416)
		(end 148.566378 -417.199826)
		(stroke
			(width 0.07112)
			(type default)
		)
		(layer "In11.Cu")
	)
	(gr_line
		(start 148.589746 -412.570168)
		(end 148.880576 -412.860998)
		(stroke
			(width 0.07112)
			(type default)
		)
		(layer "In11.Cu")
	)
	(gr_line
		(start 148.613114 -431.139346)
		(end 148.632164 -431.139346)
		(stroke
			(width 0.07112)
			(type default)
		)
		(layer "In11.Cu")
	)
	(gr_line
		(start 148.614384 -431.422556)
		(end 148.75002 -431.558192)
		(stroke
			(width 0.07112)
			(type default)
		)
		(layer "In11.Cu")
	)
	(gr_line
		(start 148.632164 -431.139346)
		(end 148.75002 -431.02149)
		(stroke
			(width 0.07112)
			(type default)
		)
		(layer "In11.Cu")
	)
	(gr_line
		(start 148.635212 -416.502088)
		(end 148.589492 -416.967416)
		(stroke
			(width 0.07112)
			(type default)
		)
		(layer "In11.Cu")
	)
	(gr_line
		(start 148.68144 -416.031172)
		(end 148.635212 -416.502088)
		(stroke
			(width 0.07112)
			(type default)
		)
		(layer "In11.Cu")
	)
	(gr_line
		(start 148.75002 -431.558192)
		(end 148.75002 -431.889916)
		(stroke
			(width 0.07112)
			(type default)
		)
		(layer "In11.Cu")
	)
	(gr_line
		(start 148.75002 -431.02149)
		(end 148.75002 -430.689766)
		(stroke
			(width 0.07112)
			(type default)
		)
		(layer "In11.Cu")
	)
	(gr_line
		(start 148.75002 -415.332926)
		(end 148.68144 -416.031172)
		(stroke
			(width 0.07112)
			(type default)
		)
		(layer "In11.Cu")
	)
	(gr_line
		(start 148.846794 -417.227258)
		(end 148.82368 -417.461446)
		(stroke
			(width 0.07112)
			(type default)
		)
		(layer "In11.Cu")
	)
	(gr_line
		(start 148.879306 -414.017714)
		(end 148.870416 -414.10763)
		(stroke
			(width 0.07112)
			(type default)
		)
		(layer "In11.Cu")
	)
	(gr_line
		(start 148.880322 -414.0073)
		(end 148.880576 -414.007046)
		(stroke
			(width 0.07112)
			(type default)
		)
		(layer "In11.Cu")
	)
	(gr_line
		(start 148.916898 -416.531044)
		(end 149.038818 -416.67938)
		(stroke
			(width 0.07112)
			(type default)
		)
		(layer "In11.Cu")
	)
	(gr_line
		(start 148.961856 -416.058604)
		(end 148.915628 -416.52952)
		(stroke
			(width 0.07112)
			(type default)
		)
		(layer "In11.Cu")
	)
	(gr_line
		(start 148.996908 -417.104322)
		(end 148.848318 -417.225988)
		(stroke
			(width 0.07112)
			(type default)
		)
		(layer "In11.Cu")
	)
	(gr_line
		(start 149.031706 -415.361882)
		(end 149.15388 -415.510726)
		(stroke
			(width 0.07112)
			(type default)
		)
		(layer "In11.Cu")
	)
	(gr_line
		(start 149.038818 -416.67938)
		(end 148.996908 -417.104322)
		(stroke
			(width 0.07112)
			(type default)
		)
		(layer "In11.Cu")
	)
	(gr_line
		(start 149.11197 -415.935414)
		(end 148.96338 -416.057334)
		(stroke
			(width 0.07112)
			(type default)
		)
		(layer "In11.Cu")
	)
	(gr_line
		(start 149.15388 -415.510726)
		(end 149.11197 -415.935414)
		(stroke
			(width 0.07112)
			(type default)
		)
		(layer "In11.Cu")
	)
	(gr_line
		(start 149.453346 -412.570168)
		(end 149.162516 -412.860998)
		(stroke
			(width 0.07112)
			(type default)
		)
		(layer "In11.Cu")
	)
	(gr_line
		(start 150.599394 -430.125632)
		(end 150.623016 -430.125632)
		(stroke
			(width 0.07112)
			(type default)
		)
		(layer "In11.Cu")
	)
	(gr_line
		(start 150.600664 -430.408842)
		(end 150.750016 -430.558194)
		(stroke
			(width 0.07112)
			(type default)
		)
		(layer "In11.Cu")
	)
	(gr_line
		(start 150.623016 -430.125632)
		(end 150.750016 -429.998632)
		(stroke
			(width 0.07112)
			(type default)
		)
		(layer "In11.Cu")
	)
	(gr_line
		(start 150.750016 -430.558194)
		(end 150.750016 -430.889918)
		(stroke
			(width 0.07112)
			(type default)
		)
		(layer "In11.Cu")
	)
	(gr_line
		(start 150.750016 -429.998632)
		(end 150.750016 -429.689768)
		(stroke
			(width 0.07112)
			(type default)
		)
		(layer "In11.Cu")
	)
	(gr_line
		(start 150.945342 -418.19449)
		(end 150.791672 -418.878766)
		(stroke
			(width 0.07112)
			(type default)
		)
		(layer "In11.Cu")
	)
	(gr_line
		(start 151.221186 -418.257736)
		(end 151.32431 -418.420042)
		(stroke
			(width 0.07112)
			(type default)
		)
		(layer "In11.Cu")
	)
	(gr_line
		(start 151.230838 -418.836856)
		(end 151.068024 -418.939726)
		(stroke
			(width 0.07112)
			(type default)
		)
		(layer "In11.Cu")
	)
	(gr_line
		(start 151.284686 -416.68319)
		(end 151.132032 -417.362386)
		(stroke
			(width 0.07112)
			(type default)
		)
		(layer "In11.Cu")
	)
	(gr_line
		(start 151.28494 -416.682682)
		(end 151.284686 -416.68319)
		(stroke
			(width 0.07112)
			(type default)
		)
		(layer "In11.Cu")
	)
	(gr_line
		(start 151.32431 -418.420042)
		(end 151.230838 -418.836856)
		(stroke
			(width 0.07112)
			(type default)
		)
		(layer "In11.Cu")
	)
	(gr_line
		(start 151.405844 -417.430712)
		(end 151.40559 -417.431728)
		(stroke
			(width 0.07112)
			(type default)
		)
		(layer "In11.Cu")
	)
	(gr_line
		(start 151.406352 -417.430458)
		(end 151.405844 -417.430712)
		(stroke
			(width 0.07112)
			(type default)
		)
		(layer "In11.Cu")
	)
	(gr_line
		(start 151.45639 -415.918396)
		(end 151.456136 -415.919412)
		(stroke
			(width 0.07112)
			(type default)
		)
		(layer "In11.Cu")
	)
	(gr_line
		(start 151.560276 -416.744404)
		(end 151.560022 -416.745166)
		(stroke
			(width 0.07112)
			(type default)
		)
		(layer "In11.Cu")
	)
	(gr_line
		(start 151.56053 -416.747452)
		(end 151.6634 -416.910266)
		(stroke
			(width 0.07112)
			(type default)
		)
		(layer "In11.Cu")
	)
	(gr_line
		(start 151.569928 -417.326826)
		(end 151.407368 -417.429696)
		(stroke
			(width 0.07112)
			(type default)
		)
		(layer "In11.Cu")
	)
	(gr_line
		(start 151.609806 -415.23539)
		(end 151.45639 -415.918396)
		(stroke
			(width 0.07112)
			(type default)
		)
		(layer "In11.Cu")
	)
	(gr_line
		(start 151.61006 -415.234882)
		(end 151.609806 -415.23539)
		(stroke
			(width 0.07112)
			(type default)
		)
		(layer "In11.Cu")
	)
	(gr_line
		(start 151.652986 -412.570168)
		(end 151.943816 -412.860998)
		(stroke
			(width 0.07112)
			(type default)
		)
		(layer "In11.Cu")
	)
	(gr_line
		(start 151.6634 -416.910266)
		(end 151.569928 -417.326826)
		(stroke
			(width 0.07112)
			(type default)
		)
		(layer "In11.Cu")
	)
	(gr_line
		(start 151.704548 -414.812988)
		(end 151.703278 -414.819592)
		(stroke
			(width 0.07112)
			(type default)
		)
		(layer "In11.Cu")
	)
	(gr_line
		(start 151.732234 -415.980372)
		(end 151.731472 -415.98088)
		(stroke
			(width 0.07112)
			(type default)
		)
		(layer "In11.Cu")
	)
	(gr_line
		(start 151.856948 -414.1343)
		(end 151.704802 -414.811972)
		(stroke
			(width 0.07112)
			(type default)
		)
		(layer "In11.Cu")
	)
	(gr_line
		(start 151.885142 -415.296604)
		(end 151.88565 -415.297366)
		(stroke
			(width 0.07112)
			(type default)
		)
		(layer "In11.Cu")
	)
	(gr_line
		(start 151.885904 -415.297874)
		(end 151.989028 -415.460434)
		(stroke
			(width 0.07112)
			(type default)
		)
		(layer "In11.Cu")
	)
	(gr_line
		(start 151.895556 -415.876994)
		(end 151.732742 -415.980118)
		(stroke
			(width 0.07112)
			(type default)
		)
		(layer "In11.Cu")
	)
	(gr_line
		(start 151.937212 -413.776414)
		(end 151.937212 -413.776668)
		(stroke
			(width 0.07112)
			(type default)
		)
		(layer "In11.Cu")
	)
	(gr_line
		(start 151.989028 -415.460434)
		(end 151.895556 -415.876994)
		(stroke
			(width 0.07112)
			(type default)
		)
		(layer "In11.Cu")
	)
	(gr_line
		(start 152.070308 -424.931586)
		(end 152.070054 -424.931332)
		(stroke
			(width 0.07112)
			(type default)
		)
		(layer "In11.Cu")
	)
	(gr_line
		(start 152.133046 -414.197292)
		(end 152.23617 -414.359852)
		(stroke
			(width 0.07112)
			(type default)
		)
		(layer "In11.Cu")
	)
	(gr_line
		(start 152.142698 -414.776412)
		(end 151.979884 -414.879536)
		(stroke
			(width 0.07112)
			(type default)
		)
		(layer "In11.Cu")
	)
	(gr_line
		(start 152.225756 -413.719518)
		(end 152.225756 -413.720534)
		(stroke
			(width 0.07112)
			(type default)
		)
		(layer "In11.Cu")
	)
	(gr_line
		(start 152.23617 -414.359852)
		(end 152.142698 -414.776412)
		(stroke
			(width 0.07112)
			(type default)
		)
		(layer "In11.Cu")
	)
	(gr_line
		(start 152.516586 -412.570168)
		(end 152.225756 -412.860998)
		(stroke
			(width 0.07112)
			(type default)
		)
		(layer "In11.Cu")
	)
	(gr_line
		(start 152.622758 -431.430938)
		(end 152.750012 -431.558192)
		(stroke
			(width 0.07112)
			(type default)
		)
		(layer "In11.Cu")
	)
	(gr_line
		(start 152.622758 -431.148744)
		(end 152.750012 -431.02149)
		(stroke
			(width 0.07112)
			(type default)
		)
		(layer "In11.Cu")
	)
	(gr_line
		(start 152.750012 -431.558192)
		(end 152.750012 -431.889916)
		(stroke
			(width 0.07112)
			(type default)
		)
		(layer "In11.Cu")
	)
	(gr_line
		(start 152.750012 -431.02149)
		(end 152.750012 -430.689766)
		(stroke
			(width 0.07112)
			(type default)
		)
		(layer "In11.Cu")
	)
	(gr_line
		(start 153.626566 -166.886128)
		(end 153.626566 -166.885874)
		(stroke
			(width 0.07112)
			(type default)
		)
		(layer "In11.Cu")
	)
	(gr_line
		(start 153.899362 -171.04995)
		(end 153.899108 -171.050712)
		(stroke
			(width 0.07112)
			(type default)
		)
		(layer "In11.Cu")
	)
	(gr_line
		(start 154.203146 -416.810444)
		(end 154.202892 -416.810952)
		(stroke
			(width 0.07112)
			(type default)
		)
		(layer "In11.Cu")
	)
	(gr_line
		(start 154.224228 -423.734484)
		(end 154.224228 -423.734738)
		(stroke
			(width 0.07112)
			(type default)
		)
		(layer "In11.Cu")
	)
	(gr_line
		(start 154.367484 -416.241484)
		(end 154.372564 -416.25139)
		(stroke
			(width 0.07112)
			(type default)
		)
		(layer "In11.Cu")
	)
	(gr_line
		(start 154.372564 -416.25139)
		(end 154.203146 -416.810444)
		(stroke
			(width 0.07112)
			(type default)
		)
		(layer "In11.Cu")
	)
	(gr_line
		(start 154.401266 -416.129724)
		(end 154.367484 -416.241484)
		(stroke
			(width 0.07112)
			(type default)
		)
		(layer "In11.Cu")
	)
	(gr_line
		(start 154.472894 -416.892486)
		(end 154.47264 -416.892994)
		(stroke
			(width 0.07112)
			(type default)
		)
		(layer "In11.Cu")
	)
	(gr_line
		(start 154.599386 -430.125632)
		(end 154.623008 -430.125632)
		(stroke
			(width 0.07112)
			(type default)
		)
		(layer "In11.Cu")
	)
	(gr_line
		(start 154.600656 -430.408842)
		(end 154.750008 -430.558194)
		(stroke
			(width 0.07112)
			(type default)
		)
		(layer "In11.Cu")
	)
	(gr_line
		(start 154.612086 -139.96289)
		(end 154.61234 -139.96289)
		(stroke
			(width 0.07112)
			(type default)
		)
		(layer "In11.Cu")
	)
	(gr_line
		(start 154.623008 -430.125632)
		(end 154.750008 -429.998632)
		(stroke
			(width 0.07112)
			(type default)
		)
		(layer "In11.Cu")
	)
	(gr_line
		(start 154.64409 -416.801046)
		(end 154.474418 -416.891724)
		(stroke
			(width 0.07112)
			(type default)
		)
		(layer "In11.Cu")
	)
	(gr_line
		(start 154.67203 -416.213036)
		(end 154.768042 -416.392614)
		(stroke
			(width 0.07112)
			(type default)
		)
		(layer "In11.Cu")
	)
	(gr_line
		(start 154.691588 -415.172398)
		(end 154.657552 -415.284412)
		(stroke
			(width 0.07112)
			(type default)
		)
		(layer "In11.Cu")
	)
	(gr_line
		(start 154.701494 -415.167064)
		(end 154.691588 -415.172398)
		(stroke
			(width 0.07112)
			(type default)
		)
		(layer "In11.Cu")
	)
	(gr_line
		(start 154.716226 -412.570168)
		(end 155.007056 -412.860998)
		(stroke
			(width 0.07112)
			(type default)
		)
		(layer "In11.Cu")
	)
	(gr_line
		(start 154.750008 -430.558194)
		(end 154.750008 -430.889918)
		(stroke
			(width 0.07112)
			(type default)
		)
		(layer "In11.Cu")
	)
	(gr_line
		(start 154.750008 -429.998632)
		(end 154.750008 -429.689768)
		(stroke
			(width 0.07112)
			(type default)
		)
		(layer "In11.Cu")
	)
	(gr_line
		(start 154.768042 -416.392614)
		(end 154.64409 -416.801046)
		(stroke
			(width 0.07112)
			(type default)
		)
		(layer "In11.Cu")
	)
	(gr_line
		(start 154.866086 -139.839954)
		(end 154.866594 -139.840208)
		(stroke
			(width 0.07112)
			(type default)
		)
		(layer "In11.Cu")
	)
	(gr_line
		(start 154.87142 -414.607502)
		(end 154.701494 -415.167064)
		(stroke
			(width 0.07112)
			(type default)
		)
		(layer "In11.Cu")
	)
	(gr_line
		(start 154.872436 -414.604454)
		(end 154.87142 -414.607502)
		(stroke
			(width 0.07112)
			(type default)
		)
		(layer "In11.Cu")
	)
	(gr_line
		(start 155.037282 -170.663108)
		(end 155.034996 -170.669458)
		(stroke
			(width 0.07112)
			(type default)
		)
		(layer "In11.Cu")
	)
	(gr_line
		(start 155.046934 -171.547282)
		(end 155.04668 -171.547282)
		(stroke
			(width 0.07112)
			(type default)
		)
		(layer "In11.Cu")
	)
	(gr_line
		(start 155.10891 -415.269426)
		(end 154.929078 -415.365438)
		(stroke
			(width 0.07112)
			(type default)
		)
		(layer "In11.Cu")
	)
	(gr_line
		(start 155.14193 -414.691068)
		(end 155.232862 -414.860994)
		(stroke
			(width 0.07112)
			(type default)
		)
		(layer "In11.Cu")
	)
	(gr_line
		(start 155.142692 -414.686242)
		(end 155.141422 -414.689798)
		(stroke
			(width 0.07112)
			(type default)
		)
		(layer "In11.Cu")
	)
	(gr_line
		(start 155.232862 -414.860994)
		(end 155.10891 -415.269426)
		(stroke
			(width 0.07112)
			(type default)
		)
		(layer "In11.Cu")
	)
	(gr_line
		(start 155.579826 -412.570168)
		(end 155.288996 -412.860998)
		(stroke
			(width 0.07112)
			(type default)
		)
		(layer "In11.Cu")
	)
	(gr_line
		(start 155.77439 -419.516052)
		(end 155.4861 -420.155624)
		(stroke
			(width 0.07112)
			(type default)
		)
		(layer "In11.Cu")
	)
	(gr_line
		(start 155.88615 -166.116508)
		(end 155.88615 -166.116254)
		(stroke
			(width 0.07112)
			(type default)
		)
		(layer "In11.Cu")
	)
	(gr_line
		(start 155.925266 -420.202868)
		(end 155.744672 -420.271194)
		(stroke
			(width 0.07112)
			(type default)
		)
		(layer "In11.Cu")
	)
	(gr_line
		(start 156.0322 -419.6334)
		(end 156.100526 -419.813486)
		(stroke
			(width 0.07112)
			(type default)
		)
		(layer "In11.Cu")
	)
	(gr_line
		(start 156.100526 -419.813486)
		(end 155.925266 -420.202868)
		(stroke
			(width 0.07112)
			(type default)
		)
		(layer "In11.Cu")
	)
	(gr_line
		(start 156.474668 -417.868608)
		(end 156.470096 -417.880292)
		(stroke
			(width 0.07112)
			(type default)
		)
		(layer "In11.Cu")
	)
	(gr_line
		(start 156.481272 -417.851336)
		(end 156.4767 -417.86302)
		(stroke
			(width 0.07112)
			(type default)
		)
		(layer "In11.Cu")
	)
	(gr_line
		(start 156.48178 -417.850574)
		(end 156.481272 -417.851336)
		(stroke
			(width 0.07112)
			(type default)
		)
		(layer "In11.Cu")
	)
	(gr_line
		(start 156.482034 -417.849812)
		(end 156.48178 -417.850574)
		(stroke
			(width 0.07112)
			(type default)
		)
		(layer "In11.Cu")
	)
	(gr_line
		(start 156.62275 -431.430938)
		(end 156.750004 -431.558192)
		(stroke
			(width 0.07112)
			(type default)
		)
		(layer "In11.Cu")
	)
	(gr_line
		(start 156.62275 -431.148744)
		(end 156.750004 -431.02149)
		(stroke
			(width 0.07112)
			(type default)
		)
		(layer "In11.Cu")
	)
	(gr_line
		(start 156.661104 -172.594524)
		(end 156.661104 -172.594778)
		(stroke
			(width 0.07112)
			(type default)
		)
		(layer "In11.Cu")
	)
	(gr_line
		(start 156.661358 -172.594524)
		(end 156.661104 -172.594524)
		(stroke
			(width 0.07112)
			(type default)
		)
		(layer "In11.Cu")
	)
	(gr_line
		(start 156.734256 -417.196016)
		(end 156.482034 -417.849812)
		(stroke
			(width 0.07112)
			(type default)
		)
		(layer "In11.Cu")
	)
	(gr_line
		(start 156.737558 -417.975542)
		(end 156.736034 -417.977828)
		(stroke
			(width 0.07112)
			(type default)
		)
		(layer "In11.Cu")
	)
	(gr_line
		(start 156.741368 -417.964112)
		(end 156.737558 -417.975542)
		(stroke
			(width 0.07112)
			(type default)
		)
		(layer "In11.Cu")
	)
	(gr_line
		(start 156.745432 -417.951666)
		(end 156.744924 -417.952936)
		(stroke
			(width 0.07112)
			(type default)
		)
		(layer "In11.Cu")
	)
	(gr_line
		(start 156.750004 -431.558192)
		(end 156.750004 -431.889916)
		(stroke
			(width 0.07112)
			(type default)
		)
		(layer "In11.Cu")
	)
	(gr_line
		(start 156.750004 -431.02149)
		(end 156.750004 -430.689766)
		(stroke
			(width 0.07112)
			(type default)
		)
		(layer "In11.Cu")
	)
	(gr_line
		(start 156.887672 -416.798252)
		(end 156.824172 -416.963098)
		(stroke
			(width 0.07112)
			(type default)
		)
		(layer "In11.Cu")
	)
	(gr_line
		(start 156.887926 -416.79749)
		(end 156.887672 -416.798252)
		(stroke
			(width 0.07112)
			(type default)
		)
		(layer "In11.Cu")
	)
	(gr_line
		(start 156.92247 -417.87318)
		(end 156.746448 -417.951158)
		(stroke
			(width 0.07112)
			(type default)
		)
		(layer "In11.Cu")
	)
	(gr_line
		(start 156.998162 -417.298886)
		(end 157.075886 -417.474654)
		(stroke
			(width 0.07112)
			(type default)
		)
		(layer "In11.Cu")
	)
	(gr_line
		(start 157.075886 -417.474654)
		(end 156.92247 -417.87318)
		(stroke
			(width 0.07112)
			(type default)
		)
		(layer "In11.Cu")
	)
	(gr_line
		(start 157.140148 -416.143694)
		(end 156.887926 -416.79749)
		(stroke
			(width 0.07112)
			(type default)
		)
		(layer "In11.Cu")
	)
	(gr_line
		(start 157.151324 -416.89909)
		(end 157.150816 -416.899344)
		(stroke
			(width 0.07112)
			(type default)
		)
		(layer "In11.Cu")
	)
	(gr_line
		(start 157.293818 -415.745676)
		(end 157.18409 -416.029648)
		(stroke
			(width 0.07112)
			(type default)
		)
		(layer "In11.Cu")
	)
	(gr_line
		(start 157.328362 -416.820858)
		(end 157.152594 -416.898582)
		(stroke
			(width 0.07112)
			(type default)
		)
		(layer "In11.Cu")
	)
	(gr_line
		(start 157.404054 -416.246564)
		(end 157.481778 -416.422332)
		(stroke
			(width 0.07112)
			(type default)
		)
		(layer "In11.Cu")
	)
	(gr_line
		(start 157.481778 -416.422332)
		(end 157.328362 -416.820858)
		(stroke
			(width 0.07112)
			(type default)
		)
		(layer "In11.Cu")
	)
	(gr_line
		(start 157.541468 -415.103564)
		(end 157.293818 -415.745676)
		(stroke
			(width 0.07112)
			(type default)
		)
		(layer "In11.Cu")
	)
	(gr_line
		(start 157.546548 -415.090356)
		(end 157.54604 -415.091626)
		(stroke
			(width 0.07112)
			(type default)
		)
		(layer "In11.Cu")
	)
	(gr_line
		(start 157.546548 -415.089848)
		(end 157.546548 -415.090356)
		(stroke
			(width 0.07112)
			(type default)
		)
		(layer "In11.Cu")
	)
	(gr_line
		(start 157.546548 -415.08934)
		(end 157.546802 -415.08934)
		(stroke
			(width 0.07112)
			(type default)
		)
		(layer "In11.Cu")
	)
	(gr_line
		(start 157.556708 -415.847022)
		(end 157.447234 -416.130994)
		(stroke
			(width 0.07112)
			(type default)
		)
		(layer "In11.Cu")
	)
	(gr_line
		(start 157.734254 -415.768536)
		(end 157.558486 -415.84626)
		(stroke
			(width 0.07112)
			(type default)
		)
		(layer "In11.Cu")
	)
	(gr_line
		(start 157.779466 -412.570168)
		(end 158.070296 -412.860998)
		(stroke
			(width 0.07112)
			(type default)
		)
		(layer "In11.Cu")
	)
	(gr_line
		(start 157.809184 -415.192718)
		(end 157.809438 -415.193226)
		(stroke
			(width 0.07112)
			(type default)
		)
		(layer "In11.Cu")
	)
	(gr_line
		(start 157.809438 -415.191956)
		(end 157.809184 -415.192718)
		(stroke
			(width 0.07112)
			(type default)
		)
		(layer "In11.Cu")
	)
	(gr_line
		(start 157.809692 -415.19094)
		(end 157.809438 -415.191956)
		(stroke
			(width 0.07112)
			(type default)
		)
		(layer "In11.Cu")
	)
	(gr_line
		(start 157.809946 -415.194496)
		(end 157.887924 -415.37001)
		(stroke
			(width 0.07112)
			(type default)
		)
		(layer "In11.Cu")
	)
	(gr_line
		(start 157.887924 -415.37001)
		(end 157.734254 -415.768536)
		(stroke
			(width 0.07112)
			(type default)
		)
		(layer "In11.Cu")
	)
	(gr_line
		(start 158.070296 -413.561276)
		(end 158.070042 -413.561022)
		(stroke
			(width 0.07112)
			(type default)
		)
		(layer "In11.Cu")
	)
	(gr_line
		(start 158.643066 -412.570168)
		(end 158.352236 -412.860998)
		(stroke
			(width 0.07112)
			(type default)
		)
		(layer "In11.Cu")
	)
	(gr_line
		(start 160.212532 -416.384994)
		(end 159.912812 -417.018978)
		(stroke
			(width 0.07112)
			(type default)
		)
		(layer "In11.Cu")
	)
	(gr_line
		(start 160.350708 -417.07435)
		(end 160.169098 -417.13912)
		(stroke
			(width 0.07112)
			(type default)
		)
		(layer "In11.Cu")
	)
	(gr_line
		(start 160.46831 -416.506914)
		(end 160.53308 -416.68827)
		(stroke
			(width 0.07112)
			(type default)
		)
		(layer "In11.Cu")
	)
	(gr_line
		(start 160.53308 -416.68827)
		(end 160.350708 -417.07435)
		(stroke
			(width 0.07112)
			(type default)
		)
		(layer "In11.Cu")
	)
	(gr_line
		(start 160.842706 -412.570168)
		(end 161.133536 -412.860998)
		(stroke
			(width 0.07112)
			(type default)
		)
		(layer "In11.Cu")
	)
	(gr_line
		(start 160.933384 -414.405064)
		(end 160.729676 -415.076386)
		(stroke
			(width 0.07112)
			(type default)
		)
		(layer "In11.Cu")
	)
	(gr_line
		(start 160.947608 -145.904458)
		(end 160.947608 -145.480278)
		(stroke
			(width 0.07112)
			(type default)
		)
		(layer "In11.Cu")
	)
	(gr_line
		(start 160.947608 -145.480278)
		(end 161.083498 -145.344388)
		(stroke
			(width 0.07112)
			(type default)
		)
		(layer "In11.Cu")
	)
	(gr_line
		(start 160.947608 -144.781778)
		(end 160.947608 -144.357598)
		(stroke
			(width 0.07112)
			(type default)
		)
		(layer "In11.Cu")
	)
	(gr_line
		(start 160.947608 -144.357598)
		(end 161.083498 -144.221708)
		(stroke
			(width 0.07112)
			(type default)
		)
		(layer "In11.Cu")
	)
	(gr_line
		(start 160.947608 -143.659098)
		(end 160.947608 -143.234918)
		(stroke
			(width 0.07112)
			(type default)
		)
		(layer "In11.Cu")
	)
	(gr_line
		(start 160.947608 -143.234918)
		(end 161.083498 -143.099028)
		(stroke
			(width 0.07112)
			(type default)
		)
		(layer "In11.Cu")
	)
	(gr_line
		(start 161.083498 -146.040348)
		(end 160.947608 -145.904458)
		(stroke
			(width 0.07112)
			(type default)
		)
		(layer "In11.Cu")
	)
	(gr_line
		(start 161.083498 -144.917668)
		(end 160.947608 -144.781778)
		(stroke
			(width 0.07112)
			(type default)
		)
		(layer "In11.Cu")
	)
	(gr_line
		(start 161.083498 -143.794988)
		(end 160.947608 -143.659098)
		(stroke
			(width 0.07112)
			(type default)
		)
		(layer "In11.Cu")
	)
	(gr_line
		(start 161.133536 -413.70377)
		(end 161.133282 -413.70377)
		(stroke
			(width 0.07112)
			(type default)
		)
		(layer "In11.Cu")
	)
	(gr_line
		(start 161.170874 -415.066734)
		(end 161.001202 -415.157412)
		(stroke
			(width 0.07112)
			(type default)
		)
		(layer "In11.Cu")
	)
	(gr_line
		(start 161.204148 -414.488122)
		(end 161.294826 -414.658048)
		(stroke
			(width 0.07112)
			(type default)
		)
		(layer "In11.Cu")
	)
	(gr_line
		(start 161.294826 -414.658048)
		(end 161.170874 -415.066734)
		(stroke
			(width 0.07112)
			(type default)
		)
		(layer "In11.Cu")
	)
	(gr_line
		(start 161.366708 -145.343118)
		(end 161.366708 -146.041618)
		(stroke
			(width 0.07112)
			(type default)
		)
		(layer "In11.Cu")
	)
	(gr_line
		(start 161.366708 -144.220438)
		(end 161.366708 -144.918938)
		(stroke
			(width 0.07112)
			(type default)
		)
		(layer "In11.Cu")
	)
	(gr_line
		(start 161.366708 -143.097758)
		(end 161.366708 -143.796258)
		(stroke
			(width 0.07112)
			(type default)
		)
		(layer "In11.Cu")
	)
	(gr_line
		(start 161.388044 -147.234656)
		(end 161.388044 -147.042378)
		(stroke
			(width 0.07112)
			(type default)
		)
		(layer "In11.Cu")
	)
	(gr_line
		(start 161.3916 -413.866584)
		(end 161.391346 -413.867092)
		(stroke
			(width 0.07112)
			(type default)
		)
		(layer "In11.Cu")
	)
	(gr_line
		(start 161.434018 -170.630596)
		(end 161.724848 -170.339766)
		(stroke
			(width 0.07112)
			(type default)
		)
		(layer "In11.Cu")
	)
	(gr_line
		(start 161.587434 -146.84121)
		(end 162.081718 -147.335494)
		(stroke
			(width 0.07112)
			(type default)
		)
		(layer "In11.Cu")
	)
	(gr_line
		(start 161.59607 -150.34641)
		(end 161.237676 -149.988016)
		(stroke
			(width 0.07112)
			(type default)
		)
		(layer "In11.Cu")
	)
	(gr_line
		(start 161.688272 -147.534884)
		(end 161.388044 -147.234656)
		(stroke
			(width 0.07112)
			(type default)
		)
		(layer "In11.Cu")
	)
	(gr_line
		(start 161.706306 -412.570168)
		(end 161.415476 -412.860998)
		(stroke
			(width 0.07112)
			(type default)
		)
		(layer "In11.Cu")
	)
	(gr_line
		(start 161.87928 -150.337012)
		(end 161.87928 -150.34768)
		(stroke
			(width 0.07112)
			(type default)
		)
		(layer "In11.Cu")
	)
	(gr_line
		(start 161.88055 -147.534884)
		(end 161.688272 -147.534884)
		(stroke
			(width 0.07112)
			(type default)
		)
		(layer "In11.Cu")
	)
	(gr_line
		(start 162.182048 -148.02866)
		(end 162.182048 -147.836382)
		(stroke
			(width 0.07112)
			(type default)
		)
		(layer "In11.Cu")
	)
	(gr_line
		(start 162.228276 -149.988016)
		(end 161.87928 -150.337012)
		(stroke
			(width 0.07112)
			(type default)
		)
		(layer "In11.Cu")
	)
	(gr_line
		(start 162.297618 -170.630596)
		(end 162.006788 -170.339766)
		(stroke
			(width 0.07112)
			(type default)
		)
		(layer "In11.Cu")
	)
	(gr_line
		(start 162.381438 -147.635214)
		(end 162.875722 -148.129498)
		(stroke
			(width 0.07112)
			(type default)
		)
		(layer "In11.Cu")
	)
	(gr_line
		(start 162.482276 -148.328888)
		(end 162.182048 -148.02866)
		(stroke
			(width 0.07112)
			(type default)
		)
		(layer "In11.Cu")
	)
	(gr_line
		(start 162.674554 -148.328888)
		(end 162.482276 -148.328888)
		(stroke
			(width 0.07112)
			(type default)
		)
		(layer "In11.Cu")
	)
	(gr_line
		(start 163.394898 -145.833084)
		(end 163.749228 -145.478754)
		(stroke
			(width 0.07112)
			(type default)
		)
		(layer "In11.Cu")
	)
	(gr_line
		(start 164.031168 -145.478754)
		(end 164.385498 -145.833084)
		(stroke
			(width 0.07112)
			(type default)
		)
		(layer "In11.Cu")
	)
	(gr_line
		(start 164.174932 -149.940264)
		(end 164.529262 -149.585934)
		(stroke
			(width 0.07112)
			(type default)
		)
		(layer "In11.Cu")
	)
	(gr_line
		(start 164.811202 -149.585934)
		(end 165.165532 -149.940264)
		(stroke
			(width 0.07112)
			(type default)
		)
		(layer "In11.Cu")
	)
	(gr_line
		(start 214.24011 -2.678176)
		(end 213.94928 -2.969006)
		(stroke
			(width 0.07112)
			(type default)
		)
		(layer "In11.Cu")
	)
	(gr_line
		(start 214.24011 -2.396236)
		(end 213.94928 -2.105406)
		(stroke
			(width 0.07112)
			(type default)
		)
		(layer "In11.Cu")
	)
	(gr_line
		(start 299.060616 -2.969006)
		(end 298.769786 -2.678176)
		(stroke
			(width 0.07112)
			(type default)
		)
		(layer "In11.Cu")
	)
	(gr_line
		(start 299.060616 -2.105406)
		(end 298.769786 -2.396236)
		(stroke
			(width 0.07112)
			(type default)
		)
		(layer "In11.Cu")
	)
	(gr_line
		(start 303.793906 -420.952168)
		(end 304.084736 -421.242998)
		(stroke
			(width 0.07112)
			(type default)
		)
		(layer "In11.Cu")
	)
	(gr_line
		(start 304.657506 -420.952168)
		(end 304.366676 -421.242998)
		(stroke
			(width 0.07112)
			(type default)
		)
		(layer "In11.Cu")
	)
	(gr_line
		(start 304.764694 -422.46042)
		(end 305.296062 -422.918382)
		(stroke
			(width 0.07112)
			(type default)
		)
		(layer "In11.Cu")
	)
	(gr_line
		(start 304.950368 -422.246806)
		(end 305.142392 -422.232582)
		(stroke
			(width 0.07112)
			(type default)
		)
		(layer "In11.Cu")
	)
	(gr_line
		(start 305.142392 -422.232582)
		(end 305.465734 -422.511474)
		(stroke
			(width 0.07112)
			(type default)
		)
		(layer "In11.Cu")
	)
	(gr_line
		(start 305.465734 -422.511474)
		(end 305.480212 -422.703244)
		(stroke
			(width 0.07112)
			(type default)
		)
		(layer "In11.Cu")
	)
	(gr_line
		(start 305.704494 -423.270426)
		(end 306.235862 -423.728388)
		(stroke
			(width 0.07112)
			(type default)
		)
		(layer "In11.Cu")
	)
	(gr_line
		(start 305.890168 -423.056812)
		(end 306.082192 -423.042588)
		(stroke
			(width 0.07112)
			(type default)
		)
		(layer "In11.Cu")
	)
	(gr_line
		(start 306.082192 -423.042588)
		(end 306.405788 -423.32148)
		(stroke
			(width 0.07112)
			(type default)
		)
		(layer "In11.Cu")
	)
	(gr_line
		(start 306.405788 -423.32148)
		(end 306.420012 -423.51325)
		(stroke
			(width 0.07112)
			(type default)
		)
		(layer "In11.Cu")
	)
	(gr_line
		(start 306.668424 -424.10126)
		(end 307.199792 -424.559222)
		(stroke
			(width 0.07112)
			(type default)
		)
		(layer "In11.Cu")
	)
	(gr_line
		(start 306.854352 -423.887646)
		(end 307.046122 -423.873168)
		(stroke
			(width 0.07112)
			(type default)
		)
		(layer "In11.Cu")
	)
	(gr_line
		(start 306.857146 -420.952168)
		(end 307.147976 -421.242998)
		(stroke
			(width 0.07112)
			(type default)
		)
		(layer "In11.Cu")
	)
	(gr_line
		(start 307.046122 -423.873168)
		(end 307.369464 -424.15206)
		(stroke
			(width 0.07112)
			(type default)
		)
		(layer "In11.Cu")
	)
	(gr_line
		(start 307.369464 -424.15206)
		(end 307.383688 -424.34383)
		(stroke
			(width 0.07112)
			(type default)
		)
		(layer "In11.Cu")
	)
	(gr_line
		(start 307.68798 -422.422066)
		(end 308.183788 -422.917874)
		(stroke
			(width 0.07112)
			(type default)
		)
		(layer "In11.Cu")
	)
	(gr_line
		(start 307.720746 -420.952168)
		(end 307.429916 -421.242998)
		(stroke
			(width 0.07112)
			(type default)
		)
		(layer "In11.Cu")
	)
	(gr_line
		(start 307.727604 -425.014136)
		(end 308.258972 -425.472098)
		(stroke
			(width 0.07112)
			(type default)
		)
		(layer "In11.Cu")
	)
	(gr_line
		(start 307.889148 -422.222676)
		(end 308.081172 -422.222676)
		(stroke
			(width 0.07112)
			(type default)
		)
		(layer "In11.Cu")
	)
	(gr_line
		(start 307.913532 -424.800268)
		(end 308.105302 -424.786044)
		(stroke
			(width 0.07112)
			(type default)
		)
		(layer "In11.Cu")
	)
	(gr_line
		(start 308.081172 -422.222676)
		(end 308.383178 -422.524682)
		(stroke
			(width 0.07112)
			(type default)
		)
		(layer "In11.Cu")
	)
	(gr_line
		(start 308.105302 -424.786044)
		(end 308.428644 -425.064936)
		(stroke
			(width 0.07112)
			(type default)
		)
		(layer "In11.Cu")
	)
	(gr_line
		(start 308.383178 -422.524682)
		(end 308.383178 -422.716706)
		(stroke
			(width 0.07112)
			(type default)
		)
		(layer "In11.Cu")
	)
	(gr_line
		(start 308.428644 -425.064936)
		(end 308.442868 -425.256706)
		(stroke
			(width 0.07112)
			(type default)
		)
		(layer "In11.Cu")
	)
	(gr_line
		(start 308.569868 -423.303954)
		(end 309.065676 -423.799762)
		(stroke
			(width 0.07112)
			(type default)
		)
		(layer "In11.Cu")
	)
	(gr_line
		(start 308.771036 -423.104564)
		(end 308.96306 -423.104564)
		(stroke
			(width 0.07112)
			(type default)
		)
		(layer "In11.Cu")
	)
	(gr_line
		(start 308.96306 -423.104564)
		(end 309.265066 -423.40657)
		(stroke
			(width 0.07112)
			(type default)
		)
		(layer "In11.Cu")
	)
	(gr_line
		(start 309.265066 -423.40657)
		(end 309.265066 -423.598594)
		(stroke
			(width 0.07112)
			(type default)
		)
		(layer "In11.Cu")
	)
	(gr_line
		(start 309.920386 -420.952168)
		(end 310.211216 -421.242998)
		(stroke
			(width 0.07112)
			(type default)
		)
		(layer "In11.Cu")
	)
	(gr_arc
		(start 310.211216 -422.67251)
		(mid 310.396688 -423.120246)
		(end 310.844438 -423.305732)
		(stroke
			(width 0.07112)
			(type default)
		)
		(layer "In11.Cu")
	)
	(gr_line
		(start 310.211216 -421.742108)
		(end 310.211216 -422.300908)
		(stroke
			(width 0.07112)
			(type default)
		)
		(layer "In11.Cu")
	)
	(gr_line
		(start 310.494426 -421.743378)
		(end 310.630316 -421.879268)
		(stroke
			(width 0.07112)
			(type default)
		)
		(layer "In11.Cu")
	)
	(gr_line
		(start 310.630316 -422.163748)
		(end 310.494426 -422.299638)
		(stroke
			(width 0.07112)
			(type default)
		)
		(layer "In11.Cu")
	)
	(gr_line
		(start 310.630316 -421.879268)
		(end 310.630316 -422.163748)
		(stroke
			(width 0.07112)
			(type default)
		)
		(layer "In11.Cu")
	)
	(gr_line
		(start 310.783986 -420.952168)
		(end 310.493156 -421.242998)
		(stroke
			(width 0.07112)
			(type default)
		)
		(layer "In11.Cu")
	)
	(gr_line
		(start 311.078626 -168.76903)
		(end 311.078626 -168.769284)
		(stroke
			(width 0.07112)
			(type default)
		)
		(layer "In11.Cu")
	)
	(gr_line
		(start 311.100216 -168.821354)
		(end 311.078626 -168.769284)
		(stroke
			(width 0.07112)
			(type default)
		)
		(layer "In11.Cu")
	)
	(gr_line
		(start 311.13984 -168.860978)
		(end 311.100216 -168.821354)
		(stroke
			(width 0.07112)
			(type default)
		)
		(layer "In11.Cu")
	)
	(gr_line
		(start 311.199784 -423.305732)
		(end 311.758584 -423.305732)
		(stroke
			(width 0.07112)
			(type default)
		)
		(layer "In11.Cu")
	)
	(gr_line
		(start 311.201054 -423.022522)
		(end 311.336944 -422.886632)
		(stroke
			(width 0.07112)
			(type default)
		)
		(layer "In11.Cu")
	)
	(gr_line
		(start 311.336944 -422.886632)
		(end 311.621424 -422.886632)
		(stroke
			(width 0.07112)
			(type default)
		)
		(layer "In11.Cu")
	)
	(gr_line
		(start 311.33923 -168.661334)
		(end 311.33923 -168.661588)
		(stroke
			(width 0.07112)
			(type default)
		)
		(layer "In11.Cu")
	)
	(gr_line
		(start 311.621424 -422.886632)
		(end 311.757314 -423.022522)
		(stroke
			(width 0.07112)
			(type default)
		)
		(layer "In11.Cu")
	)
	(gr_line
		(start 312.043064 -423.305732)
		(end 312.601864 -423.305732)
		(stroke
			(width 0.07112)
			(type default)
		)
		(layer "In11.Cu")
	)
	(gr_line
		(start 312.044334 -423.022522)
		(end 312.180224 -422.886632)
		(stroke
			(width 0.07112)
			(type default)
		)
		(layer "In11.Cu")
	)
	(gr_line
		(start 312.180224 -422.886632)
		(end 312.464704 -422.886632)
		(stroke
			(width 0.07112)
			(type default)
		)
		(layer "In11.Cu")
	)
	(gr_line
		(start 312.464704 -422.886632)
		(end 312.600594 -423.022522)
		(stroke
			(width 0.07112)
			(type default)
		)
		(layer "In11.Cu")
	)
	(gr_line
		(start 312.886344 -423.305732)
		(end 313.445144 -423.305732)
		(stroke
			(width 0.07112)
			(type default)
		)
		(layer "In11.Cu")
	)
	(gr_line
		(start 312.887614 -423.022522)
		(end 313.023504 -422.886632)
		(stroke
			(width 0.07112)
			(type default)
		)
		(layer "In11.Cu")
	)
	(gr_line
		(start 312.983626 -420.952168)
		(end 313.274456 -421.242998)
		(stroke
			(width 0.07112)
			(type default)
		)
		(layer "In11.Cu")
	)
	(gr_line
		(start 313.023504 -422.886632)
		(end 313.307984 -422.886632)
		(stroke
			(width 0.07112)
			(type default)
		)
		(layer "In11.Cu")
	)
	(gr_line
		(start 313.307984 -422.886632)
		(end 313.443874 -423.022522)
		(stroke
			(width 0.07112)
			(type default)
		)
		(layer "In11.Cu")
	)
	(gr_line
		(start 313.847226 -420.952168)
		(end 313.556396 -421.242998)
		(stroke
			(width 0.07112)
			(type default)
		)
		(layer "In11.Cu")
	)
	(gr_line
		(start 314.190888 -166.537132)
		(end 314.169298 -166.485062)
		(stroke
			(width 0.07112)
			(type default)
		)
		(layer "In11.Cu")
	)
	(gr_line
		(start 314.230512 -166.576756)
		(end 314.190888 -166.537132)
		(stroke
			(width 0.07112)
			(type default)
		)
		(layer "In11.Cu")
	)
	(gr_line
		(start 314.28817 -174.687992)
		(end 314.263278 -174.6631)
		(stroke
			(width 0.07112)
			(type default)
		)
		(layer "In11.Cu")
	)
	(gr_line
		(start 314.291726 -422.320212)
		(end 314.992766 -422.320212)
		(stroke
			(width 0.07112)
			(type default)
		)
		(layer "In11.Cu")
	)
	(gr_line
		(start 314.292996 -422.037002)
		(end 314.428886 -421.901112)
		(stroke
			(width 0.07112)
			(type default)
		)
		(layer "In11.Cu")
	)
	(gr_line
		(start 314.317888 -174.705772)
		(end 314.28817 -174.687992)
		(stroke
			(width 0.07112)
			(type default)
		)
		(layer "In11.Cu")
	)
	(gr_line
		(start 314.428886 -421.901112)
		(end 314.855606 -421.901112)
		(stroke
			(width 0.07112)
			(type default)
		)
		(layer "In11.Cu")
	)
	(gr_line
		(start 314.429902 -166.377112)
		(end 314.429902 -166.377366)
		(stroke
			(width 0.07112)
			(type default)
		)
		(layer "In11.Cu")
	)
	(gr_line
		(start 314.462922 -174.46371)
		(end 314.462922 -174.463964)
		(stroke
			(width 0.07112)
			(type default)
		)
		(layer "In11.Cu")
	)
	(gr_line
		(start 314.507372 -430.430686)
		(end 314.649612 -430.572926)
		(stroke
			(width 0.07112)
			(type default)
		)
		(layer "In11.Cu")
	)
	(gr_line
		(start 314.507372 -430.148746)
		(end 314.649612 -430.006506)
		(stroke
			(width 0.07112)
			(type default)
		)
		(layer "In11.Cu")
	)
	(gr_line
		(start 314.649612 -430.572926)
		(end 314.649612 -430.889918)
		(stroke
			(width 0.07112)
			(type default)
		)
		(layer "In11.Cu")
	)
	(gr_line
		(start 314.649612 -430.006506)
		(end 314.649612 -429.689768)
		(stroke
			(width 0.07112)
			(type default)
		)
		(layer "In11.Cu")
	)
	(gr_line
		(start 314.855606 -421.901112)
		(end 314.991496 -422.037002)
		(stroke
			(width 0.07112)
			(type default)
		)
		(layer "In11.Cu")
	)
	(gr_line
		(start 315.071252 -424.047158)
		(end 315.071252 -424.046904)
		(stroke
			(width 0.07112)
			(type default)
		)
		(layer "In11.Cu")
	)
	(gr_line
		(start 316.046866 -420.952168)
		(end 316.342014 -421.247316)
		(stroke
			(width 0.07112)
			(type default)
		)
		(layer "In11.Cu")
	)
	(gr_line
		(start 316.117224 -161.440876)
		(end 316.117224 -161.385504)
		(stroke
			(width 0.07112)
			(type default)
		)
		(layer "In11.Cu")
	)
	(gr_line
		(start 316.117224 -161.374582)
		(end 316.117224 -161.374074)
		(stroke
			(width 0.07112)
			(type default)
		)
		(layer "In11.Cu")
	)
	(gr_line
		(start 316.117478 -161.442146)
		(end 316.117478 -161.441384)
		(stroke
			(width 0.07112)
			(type default)
		)
		(layer "In11.Cu")
	)
	(gr_line
		(start 316.117478 -161.441384)
		(end 316.117224 -161.440876)
		(stroke
			(width 0.07112)
			(type default)
		)
		(layer "In11.Cu")
	)
	(gr_line
		(start 316.139322 -161.49447)
		(end 316.117478 -161.442146)
		(stroke
			(width 0.07112)
			(type default)
		)
		(layer "In11.Cu")
	)
	(gr_line
		(start 316.507368 -431.430938)
		(end 316.649608 -431.573178)
		(stroke
			(width 0.07112)
			(type default)
		)
		(layer "In11.Cu")
	)
	(gr_line
		(start 316.507368 -431.148998)
		(end 316.649608 -431.006758)
		(stroke
			(width 0.07112)
			(type default)
		)
		(layer "In11.Cu")
	)
	(gr_line
		(start 316.625224 -421.23741)
		(end 316.625224 -421.248586)
		(stroke
			(width 0.07112)
			(type default)
		)
		(layer "In11.Cu")
	)
	(gr_line
		(start 316.643258 -128.927352)
		(end 316.65037 -128.907794)
		(stroke
			(width 0.07112)
			(type default)
		)
		(layer "In11.Cu")
	)
	(gr_line
		(start 316.649608 -431.573178)
		(end 316.649608 -431.889916)
		(stroke
			(width 0.07112)
			(type default)
		)
		(layer "In11.Cu")
	)
	(gr_line
		(start 316.649608 -431.006758)
		(end 316.649608 -430.689766)
		(stroke
			(width 0.07112)
			(type default)
		)
		(layer "In11.Cu")
	)
	(gr_line
		(start 316.65037 -128.907794)
		(end 316.660022 -128.889506)
		(stroke
			(width 0.07112)
			(type default)
		)
		(layer "In11.Cu")
	)
	(gr_line
		(start 316.660276 -128.889506)
		(end 316.660022 -128.889506)
		(stroke
			(width 0.07112)
			(type default)
		)
		(layer "In11.Cu")
	)
	(gr_line
		(start 316.910466 -420.952168)
		(end 316.625224 -421.23741)
		(stroke
			(width 0.07112)
			(type default)
		)
		(layer "In11.Cu")
	)
	(gr_line
		(start 317.281052 -166.990522)
		(end 317.281306 -166.990522)
		(stroke
			(width 0.07112)
			(type default)
		)
		(layer "In11.Cu")
	)
	(gr_line
		(start 317.461392 -422.246298)
		(end 318.162432 -422.246298)
		(stroke
			(width 0.07112)
			(type default)
		)
		(layer "In11.Cu")
	)
	(gr_line
		(start 317.462662 -421.963088)
		(end 317.598552 -421.827198)
		(stroke
			(width 0.07112)
			(type default)
		)
		(layer "In11.Cu")
	)
	(gr_line
		(start 317.598552 -421.827198)
		(end 318.025272 -421.827198)
		(stroke
			(width 0.07112)
			(type default)
		)
		(layer "In11.Cu")
	)
	(gr_line
		(start 318.025272 -421.827198)
		(end 318.161162 -421.963088)
		(stroke
			(width 0.07112)
			(type default)
		)
		(layer "In11.Cu")
	)
	(gr_line
		(start 318.502284 -430.435766)
		(end 318.512444 -430.435766)
		(stroke
			(width 0.07112)
			(type default)
		)
		(layer "In11.Cu")
	)
	(gr_line
		(start 318.503554 -430.152556)
		(end 318.649604 -430.006506)
		(stroke
			(width 0.07112)
			(type default)
		)
		(layer "In11.Cu")
	)
	(gr_line
		(start 318.512444 -430.435766)
		(end 318.649604 -430.572926)
		(stroke
			(width 0.07112)
			(type default)
		)
		(layer "In11.Cu")
	)
	(gr_line
		(start 318.649604 -430.572926)
		(end 318.649604 -430.889918)
		(stroke
			(width 0.07112)
			(type default)
		)
		(layer "In11.Cu")
	)
	(gr_line
		(start 318.649604 -430.006506)
		(end 318.649604 -429.689768)
		(stroke
			(width 0.07112)
			(type default)
		)
		(layer "In11.Cu")
	)
	(gr_line
		(start 318.79413 -424.109896)
		(end 319.290192 -424.605958)
		(stroke
			(width 0.07112)
			(type default)
		)
		(layer "In11.Cu")
	)
	(gr_line
		(start 318.825118 -167.14597)
		(end 318.815466 -167.136318)
		(stroke
			(width 0.07112)
			(type default)
		)
		(layer "In11.Cu")
	)
	(gr_line
		(start 318.830198 -167.150542)
		(end 318.825118 -167.14597)
		(stroke
			(width 0.07112)
			(type default)
		)
		(layer "In11.Cu")
	)
	(gr_line
		(start 318.995298 -423.910506)
		(end 319.187576 -423.910506)
		(stroke
			(width 0.07112)
			(type default)
		)
		(layer "In11.Cu")
	)
	(gr_line
		(start 319.110106 -420.952168)
		(end 319.400936 -421.242998)
		(stroke
			(width 0.07112)
			(type default)
		)
		(layer "In11.Cu")
	)
	(gr_line
		(start 319.187576 -423.910506)
		(end 319.489582 -424.212512)
		(stroke
			(width 0.07112)
			(type default)
		)
		(layer "In11.Cu")
	)
	(gr_line
		(start 319.489582 -424.212512)
		(end 319.489582 -424.40479)
		(stroke
			(width 0.07112)
			(type default)
		)
		(layer "In11.Cu")
	)
	(gr_line
		(start 319.589658 -423.238422)
		(end 320.172842 -423.628058)
		(stroke
			(width 0.07112)
			(type default)
		)
		(layer "In11.Cu")
	)
	(gr_line
		(start 319.748154 -423.003726)
		(end 319.936622 -422.966134)
		(stroke
			(width 0.07112)
			(type default)
		)
		(layer "In11.Cu")
	)
	(gr_line
		(start 319.936622 -422.966134)
		(end 320.291714 -423.20337)
		(stroke
			(width 0.07112)
			(type default)
		)
		(layer "In11.Cu")
	)
	(gr_line
		(start 319.973706 -420.952168)
		(end 319.682876 -421.242998)
		(stroke
			(width 0.07112)
			(type default)
		)
		(layer "In11.Cu")
	)
	(gr_line
		(start 320.155824 -168.221406)
		(end 320.156078 -168.221406)
		(stroke
			(width 0.07112)
			(type default)
		)
		(layer "In11.Cu")
	)
	(gr_line
		(start 320.185542 -179.039266)
		(end 320.185542 -179.039012)
		(stroke
			(width 0.07112)
			(type default)
		)
		(layer "In11.Cu")
	)
	(gr_line
		(start 320.196972 -179.046886)
		(end 320.185542 -179.039012)
		(stroke
			(width 0.07112)
			(type default)
		)
		(layer "In11.Cu")
	)
	(gr_line
		(start 320.20764 -179.055522)
		(end 320.196972 -179.046886)
		(stroke
			(width 0.07112)
			(type default)
		)
		(layer "In11.Cu")
	)
	(gr_line
		(start 320.291714 -423.20337)
		(end 320.329306 -423.392092)
		(stroke
			(width 0.07112)
			(type default)
		)
		(layer "In11.Cu")
	)
	(gr_line
		(start 320.29527 -167.976042)
		(end 320.289174 -167.97274)
		(stroke
			(width 0.07112)
			(type default)
		)
		(layer "In11.Cu")
	)
	(gr_line
		(start 320.301366 -167.979598)
		(end 320.29527 -167.976042)
		(stroke
			(width 0.07112)
			(type default)
		)
		(layer "In11.Cu")
	)
	(gr_line
		(start 320.301366 -167.979598)
		(end 320.301112 -167.979598)
		(stroke
			(width 0.07112)
			(type default)
		)
		(layer "In11.Cu")
	)
	(gr_line
		(start 320.50736 -431.430938)
		(end 320.6496 -431.573178)
		(stroke
			(width 0.07112)
			(type default)
		)
		(layer "In11.Cu")
	)
	(gr_line
		(start 320.50736 -431.148998)
		(end 320.6496 -431.006758)
		(stroke
			(width 0.07112)
			(type default)
		)
		(layer "In11.Cu")
	)
	(gr_line
		(start 320.527426 -423.86504)
		(end 321.11061 -424.25493)
		(stroke
			(width 0.07112)
			(type default)
		)
		(layer "In11.Cu")
	)
	(gr_line
		(start 320.6496 -431.573178)
		(end 320.6496 -431.889916)
		(stroke
			(width 0.07112)
			(type default)
		)
		(layer "In11.Cu")
	)
	(gr_line
		(start 320.6496 -431.006758)
		(end 320.6496 -430.689766)
		(stroke
			(width 0.07112)
			(type default)
		)
		(layer "In11.Cu")
	)
	(gr_line
		(start 320.685668 -423.630344)
		(end 320.87439 -423.592752)
		(stroke
			(width 0.07112)
			(type default)
		)
		(layer "In11.Cu")
	)
	(gr_line
		(start 320.87439 -423.592752)
		(end 321.229482 -423.830242)
		(stroke
			(width 0.07112)
			(type default)
		)
		(layer "In11.Cu")
	)
	(gr_line
		(start 321.229482 -423.830242)
		(end 321.267074 -424.01871)
		(stroke
			(width 0.07112)
			(type default)
		)
		(layer "In11.Cu")
	)
	(gr_line
		(start 321.735196 -423.010584)
		(end 321.735196 -423.010838)
		(stroke
			(width 0.07112)
			(type default)
		)
		(layer "In11.Cu")
	)
	(gr_line
		(start 321.73545 -423.011092)
		(end 322.231004 -423.507154)
		(stroke
			(width 0.07112)
			(type default)
		)
		(layer "In11.Cu")
	)
	(gr_line
		(start 321.93484 -422.81094)
		(end 321.935094 -422.811448)
		(stroke
			(width 0.07112)
			(type default)
		)
		(layer "In11.Cu")
	)
	(gr_line
		(start 321.936364 -422.811448)
		(end 322.128896 -422.811448)
		(stroke
			(width 0.07112)
			(type default)
		)
		(layer "In11.Cu")
	)
	(gr_line
		(start 322.128896 -422.811448)
		(end 322.430648 -423.113708)
		(stroke
			(width 0.07112)
			(type default)
		)
		(layer "In11.Cu")
	)
	(gr_line
		(start 322.173346 -420.952168)
		(end 322.464176 -421.242998)
		(stroke
			(width 0.07112)
			(type default)
		)
		(layer "In11.Cu")
	)
	(gr_line
		(start 322.430648 -423.113708)
		(end 322.430648 -423.30624)
		(stroke
			(width 0.07112)
			(type default)
		)
		(layer "In11.Cu")
	)
	(gr_line
		(start 322.522596 -430.459896)
		(end 322.649596 -430.586896)
		(stroke
			(width 0.07112)
			(type default)
		)
		(layer "In11.Cu")
	)
	(gr_line
		(start 322.522596 -430.177702)
		(end 322.649596 -430.050702)
		(stroke
			(width 0.07112)
			(type default)
		)
		(layer "In11.Cu")
	)
	(gr_line
		(start 322.647056 -423.923714)
		(end 323.142864 -424.42003)
		(stroke
			(width 0.07112)
			(type default)
		)
		(layer "In11.Cu")
	)
	(gr_line
		(start 322.649596 -430.586896)
		(end 322.649596 -430.889918)
		(stroke
			(width 0.07112)
			(type default)
		)
		(layer "In11.Cu")
	)
	(gr_line
		(start 322.649596 -430.050702)
		(end 322.649596 -429.689768)
		(stroke
			(width 0.07112)
			(type default)
		)
		(layer "In11.Cu")
	)
	(gr_line
		(start 322.848224 -423.724324)
		(end 323.040756 -423.724324)
		(stroke
			(width 0.07112)
			(type default)
		)
		(layer "In11.Cu")
	)
	(gr_line
		(start 322.943982 -422.43502)
		(end 323.522848 -422.822116)
		(stroke
			(width 0.07112)
			(type default)
		)
		(layer "In11.Cu")
	)
	(gr_line
		(start 323.036946 -420.952168)
		(end 322.746116 -421.242998)
		(stroke
			(width 0.07112)
			(type default)
		)
		(layer "In11.Cu")
	)
	(gr_line
		(start 323.040756 -423.724324)
		(end 323.342508 -424.026584)
		(stroke
			(width 0.07112)
			(type default)
		)
		(layer "In11.Cu")
	)
	(gr_line
		(start 323.102224 -422.200324)
		(end 323.28739 -422.163494)
		(stroke
			(width 0.07112)
			(type default)
		)
		(layer "In11.Cu")
	)
	(gr_line
		(start 323.28739 -422.163494)
		(end 323.642482 -422.40073)
		(stroke
			(width 0.07112)
			(type default)
		)
		(layer "In11.Cu")
	)
	(gr_line
		(start 323.342508 -424.026584)
		(end 323.342508 -424.219116)
		(stroke
			(width 0.07112)
			(type default)
		)
		(layer "In11.Cu")
	)
	(gr_line
		(start 323.642482 -422.40073)
		(end 323.679312 -422.585896)
		(stroke
			(width 0.07112)
			(type default)
		)
		(layer "In11.Cu")
	)
	(gr_line
		(start 323.877432 -423.058844)
		(end 324.456298 -423.44594)
		(stroke
			(width 0.07112)
			(type default)
		)
		(layer "In11.Cu")
	)
	(gr_line
		(start 324.035674 -422.824148)
		(end 324.22084 -422.787318)
		(stroke
			(width 0.07112)
			(type default)
		)
		(layer "In11.Cu")
	)
	(gr_line
		(start 324.130416 -174.074582)
		(end 324.130416 -174.074836)
		(stroke
			(width 0.07112)
			(type default)
		)
		(layer "In11.Cu")
	)
	(gr_line
		(start 324.22084 -422.787318)
		(end 324.575932 -423.024554)
		(stroke
			(width 0.07112)
			(type default)
		)
		(layer "In11.Cu")
	)
	(gr_line
		(start 324.330314 -171.927266)
		(end 324.330314 -171.927012)
		(stroke
			(width 0.07112)
			(type default)
		)
		(layer "In11.Cu")
	)
	(gr_line
		(start 324.507352 -431.430938)
		(end 324.649592 -431.573178)
		(stroke
			(width 0.07112)
			(type default)
		)
		(layer "In11.Cu")
	)
	(gr_line
		(start 324.507352 -431.148998)
		(end 324.649592 -431.006758)
		(stroke
			(width 0.07112)
			(type default)
		)
		(layer "In11.Cu")
	)
	(gr_line
		(start 324.575932 -423.024554)
		(end 324.612762 -423.20972)
		(stroke
			(width 0.07112)
			(type default)
		)
		(layer "In11.Cu")
	)
	(gr_line
		(start 324.649592 -431.573178)
		(end 324.649592 -431.889916)
		(stroke
			(width 0.07112)
			(type default)
		)
		(layer "In11.Cu")
	)
	(gr_line
		(start 324.649592 -431.006758)
		(end 324.649592 -430.689766)
		(stroke
			(width 0.07112)
			(type default)
		)
		(layer "In11.Cu")
	)
	(gr_line
		(start 324.810882 -423.682922)
		(end 325.389748 -424.069764)
		(stroke
			(width 0.07112)
			(type default)
		)
		(layer "In11.Cu")
	)
	(gr_line
		(start 324.969124 -423.447972)
		(end 325.15429 -423.411142)
		(stroke
			(width 0.07112)
			(type default)
		)
		(layer "In11.Cu")
	)
	(gr_line
		(start 325.15429 -423.411142)
		(end 325.509382 -423.648378)
		(stroke
			(width 0.07112)
			(type default)
		)
		(layer "In11.Cu")
	)
	(gr_line
		(start 325.236586 -420.952168)
		(end 325.535798 -421.25138)
		(stroke
			(width 0.07112)
			(type default)
		)
		(layer "In11.Cu")
	)
	(gr_line
		(start 325.509382 -423.648378)
		(end 325.546212 -423.833544)
		(stroke
			(width 0.07112)
			(type default)
		)
		(layer "In11.Cu")
	)
	(gr_line
		(start 325.819008 -421.233346)
		(end 325.819008 -421.25265)
		(stroke
			(width 0.07112)
			(type default)
		)
		(layer "In11.Cu")
	)
	(gr_line
		(start 326.04837 -422.620694)
		(end 326.11314 -422.717722)
		(stroke
			(width 0.07112)
			(type default)
		)
		(layer "In11.Cu")
	)
	(gr_line
		(start 326.100186 -420.952168)
		(end 325.819008 -421.233346)
		(stroke
			(width 0.07112)
			(type default)
		)
		(layer "In11.Cu")
	)
	(gr_line
		(start 326.11314 -422.717722)
		(end 326.113394 -422.717722)
		(stroke
			(width 0.07112)
			(type default)
		)
		(layer "In11.Cu")
	)
	(gr_line
		(start 326.113394 -422.717722)
		(end 326.438006 -423.203624)
		(stroke
			(width 0.07112)
			(type default)
		)
		(layer "In11.Cu")
	)
	(gr_line
		(start 326.284336 -422.46423)
		(end 326.473058 -422.501822)
		(stroke
			(width 0.07112)
			(type default)
		)
		(layer "In11.Cu")
	)
	(gr_line
		(start 326.473058 -422.501822)
		(end 326.710548 -422.85666)
		(stroke
			(width 0.07112)
			(type default)
		)
		(layer "In11.Cu")
	)
	(gr_line
		(start 326.493124 -430.44491)
		(end 326.50684 -430.44491)
		(stroke
			(width 0.07112)
			(type default)
		)
		(layer "In11.Cu")
	)
	(gr_line
		(start 326.494394 -430.1617)
		(end 326.649588 -430.006506)
		(stroke
			(width 0.07112)
			(type default)
		)
		(layer "In11.Cu")
	)
	(gr_line
		(start 326.50684 -430.44491)
		(end 326.649588 -430.587658)
		(stroke
			(width 0.07112)
			(type default)
		)
		(layer "In11.Cu")
	)
	(gr_line
		(start 326.649588 -430.587658)
		(end 326.649588 -430.889918)
		(stroke
			(width 0.07112)
			(type default)
		)
		(layer "In11.Cu")
	)
	(gr_line
		(start 326.649588 -430.006506)
		(end 326.649588 -429.689768)
		(stroke
			(width 0.07112)
			(type default)
		)
		(layer "In11.Cu")
	)
	(gr_line
		(start 326.674988 -423.558208)
		(end 327.064624 -424.141392)
		(stroke
			(width 0.07112)
			(type default)
		)
		(layer "In11.Cu")
	)
	(gr_line
		(start 326.710548 -422.85666)
		(end 326.672956 -423.045382)
		(stroke
			(width 0.07112)
			(type default)
		)
		(layer "In11.Cu")
	)
	(gr_line
		(start 326.910954 -423.401744)
		(end 327.09993 -423.439336)
		(stroke
			(width 0.07112)
			(type default)
		)
		(layer "In11.Cu")
	)
	(gr_line
		(start 327.09993 -423.439336)
		(end 327.337166 -423.794428)
		(stroke
			(width 0.07112)
			(type default)
		)
		(layer "In11.Cu")
	)
	(gr_line
		(start 327.337166 -423.794428)
		(end 327.299574 -423.98315)
		(stroke
			(width 0.07112)
			(type default)
		)
		(layer "In11.Cu")
	)
	(gr_line
		(start 328.299826 -420.952168)
		(end 328.590656 -421.242998)
		(stroke
			(width 0.07112)
			(type default)
		)
		(layer "In11.Cu")
	)
	(gr_line
		(start 328.507344 -431.430938)
		(end 328.649584 -431.573178)
		(stroke
			(width 0.07112)
			(type default)
		)
		(layer "In11.Cu")
	)
	(gr_line
		(start 328.507344 -431.148998)
		(end 328.649584 -431.006758)
		(stroke
			(width 0.07112)
			(type default)
		)
		(layer "In11.Cu")
	)
	(gr_line
		(start 328.649584 -431.573178)
		(end 328.649584 -431.889916)
		(stroke
			(width 0.07112)
			(type default)
		)
		(layer "In11.Cu")
	)
	(gr_line
		(start 328.649584 -431.006758)
		(end 328.649584 -430.689766)
		(stroke
			(width 0.07112)
			(type default)
		)
		(layer "In11.Cu")
	)
	(gr_line
		(start 328.776076 -422.159938)
		(end 328.82078 -422.268142)
		(stroke
			(width 0.07112)
			(type default)
		)
		(layer "In11.Cu")
	)
	(gr_line
		(start 328.82078 -422.270174)
		(end 329.043538 -422.807892)
		(stroke
			(width 0.07112)
			(type default)
		)
		(layer "In11.Cu")
	)
	(gr_line
		(start 328.82078 -422.268142)
		(end 328.821796 -422.26865)
		(stroke
			(width 0.07112)
			(type default)
		)
		(layer "In11.Cu")
	)
	(gr_line
		(start 328.821796 -422.26865)
		(end 328.82078 -422.270174)
		(stroke
			(width 0.07112)
			(type default)
		)
		(layer "In11.Cu")
	)
	(gr_line
		(start 329.038204 -422.053004)
		(end 329.215242 -422.126156)
		(stroke
			(width 0.07112)
			(type default)
		)
		(layer "In11.Cu")
	)
	(gr_line
		(start 329.163426 -420.952168)
		(end 328.872596 -421.242998)
		(stroke
			(width 0.07112)
			(type default)
		)
		(layer "In11.Cu")
	)
	(gr_line
		(start 329.20686 -423.201846)
		(end 329.475084 -423.849038)
		(stroke
			(width 0.07112)
			(type default)
		)
		(layer "In11.Cu")
	)
	(gr_line
		(start 329.215242 -422.126156)
		(end 329.378564 -422.520618)
		(stroke
			(width 0.07112)
			(type default)
		)
		(layer "In11.Cu")
	)
	(gr_line
		(start 329.378564 -422.520618)
		(end 329.304904 -422.698672)
		(stroke
			(width 0.07112)
			(type default)
		)
		(layer "In11.Cu")
	)
	(gr_line
		(start 329.468988 -423.094912)
		(end 329.647042 -423.168318)
		(stroke
			(width 0.07112)
			(type default)
		)
		(layer "In11.Cu")
	)
	(gr_line
		(start 329.475084 -423.849038)
		(end 329.475846 -423.849292)
		(stroke
			(width 0.07112)
			(type default)
		)
		(layer "In11.Cu")
	)
	(gr_line
		(start 329.640692 -424.245024)
		(end 329.685396 -424.353482)
		(stroke
			(width 0.07112)
			(type default)
		)
		(layer "In11.Cu")
	)
	(gr_line
		(start 329.647042 -423.168318)
		(end 329.810364 -423.56278)
		(stroke
			(width 0.07112)
			(type default)
		)
		(layer "In11.Cu")
	)
	(gr_line
		(start 329.68438 -424.355006)
		(end 329.906884 -424.892216)
		(stroke
			(width 0.07112)
			(type default)
		)
		(layer "In11.Cu")
	)
	(gr_line
		(start 329.685396 -424.353482)
		(end 329.68438 -424.355006)
		(stroke
			(width 0.07112)
			(type default)
		)
		(layer "In11.Cu")
	)
	(gr_line
		(start 329.736958 -423.739818)
		(end 329.737974 -423.742104)
		(stroke
			(width 0.07112)
			(type default)
		)
		(layer "In11.Cu")
	)
	(gr_line
		(start 329.810364 -423.56278)
		(end 329.736958 -423.739818)
		(stroke
			(width 0.07112)
			(type default)
		)
		(layer "In11.Cu")
	)
	(gr_line
		(start 329.90282 -424.137836)
		(end 330.078588 -424.21048)
		(stroke
			(width 0.07112)
			(type default)
		)
		(layer "In11.Cu")
	)
	(gr_line
		(start 330.070206 -425.28617)
		(end 330.338684 -425.934378)
		(stroke
			(width 0.07112)
			(type default)
		)
		(layer "In11.Cu")
	)
	(gr_line
		(start 330.078588 -424.21048)
		(end 330.24191 -424.604942)
		(stroke
			(width 0.07112)
			(type default)
		)
		(layer "In11.Cu")
	)
	(gr_line
		(start 330.24191 -424.604942)
		(end 330.16825 -424.782996)
		(stroke
			(width 0.07112)
			(type default)
		)
		(layer "In11.Cu")
	)
	(gr_line
		(start 330.332334 -425.179236)
		(end 330.510388 -425.252642)
		(stroke
			(width 0.07112)
			(type default)
		)
		(layer "In11.Cu")
	)
	(gr_line
		(start 330.510388 -425.252642)
		(end 330.67371 -425.647104)
		(stroke
			(width 0.07112)
			(type default)
		)
		(layer "In11.Cu")
	)
	(gr_line
		(start 330.546456 -381.410972)
		(end 330.546456 -381.218694)
		(stroke
			(width 0.07112)
			(type default)
		)
		(layer "In11.Cu")
	)
	(gr_line
		(start 330.67371 -425.647104)
		(end 330.60005 -425.824904)
		(stroke
			(width 0.07112)
			(type default)
		)
		(layer "In11.Cu")
	)
	(gr_line
		(start 330.848462 -381.712978)
		(end 330.546456 -381.410972)
		(stroke
			(width 0.07112)
			(type default)
		)
		(layer "In11.Cu")
	)
	(gr_line
		(start 331.04074 -381.712978)
		(end 330.848462 -381.712978)
		(stroke
			(width 0.07112)
			(type default)
		)
		(layer "In11.Cu")
	)
	(gr_line
		(start 331.241654 -381.513334)
		(end 330.745846 -381.017526)
		(stroke
			(width 0.07112)
			(type default)
		)
		(layer "In11.Cu")
	)
	(gr_line
		(start 331.344016 -382.208532)
		(end 331.344016 -382.016254)
		(stroke
			(width 0.07112)
			(type default)
		)
		(layer "In11.Cu")
	)
	(gr_line
		(start 331.363066 -420.952168)
		(end 331.653896 -421.242998)
		(stroke
			(width 0.07112)
			(type default)
		)
		(layer "In11.Cu")
	)
	(gr_line
		(start 331.506576 -430.149)
		(end 331.507592 -430.149)
		(stroke
			(width 0.07112)
			(type default)
		)
		(layer "In11.Cu")
	)
	(gr_line
		(start 331.507592 -430.431956)
		(end 331.649832 -430.574196)
		(stroke
			(width 0.07112)
			(type default)
		)
		(layer "In11.Cu")
	)
	(gr_line
		(start 331.507592 -430.149)
		(end 331.649832 -430.00676)
		(stroke
			(width 0.07112)
			(type default)
		)
		(layer "In11.Cu")
	)
	(gr_line
		(start 331.646022 -382.510538)
		(end 331.344016 -382.208532)
		(stroke
			(width 0.07112)
			(type default)
		)
		(layer "In11.Cu")
	)
	(gr_line
		(start 331.649832 -430.574196)
		(end 331.649832 -430.889918)
		(stroke
			(width 0.07112)
			(type default)
		)
		(layer "In11.Cu")
	)
	(gr_line
		(start 331.649832 -430.00676)
		(end 331.649832 -429.689768)
		(stroke
			(width 0.07112)
			(type default)
		)
		(layer "In11.Cu")
	)
	(gr_line
		(start 331.789532 -422.352724)
		(end 331.95895 -422.911524)
		(stroke
			(width 0.07112)
			(type default)
		)
		(layer "In11.Cu")
	)
	(gr_line
		(start 331.8383 -382.510538)
		(end 331.646022 -382.510538)
		(stroke
			(width 0.07112)
			(type default)
		)
		(layer "In11.Cu")
	)
	(gr_line
		(start 331.91196 -378.230892)
		(end 331.91196 -378.230638)
		(stroke
			(width 0.07112)
			(type default)
		)
		(layer "In11.Cu")
	)
	(gr_line
		(start 331.95768 -422.914318)
		(end 331.991716 -423.026332)
		(stroke
			(width 0.07112)
			(type default)
		)
		(layer "In11.Cu")
	)
	(gr_line
		(start 331.95895 -422.911524)
		(end 331.95768 -422.914318)
		(stroke
			(width 0.07112)
			(type default)
		)
		(layer "In11.Cu")
	)
	(gr_line
		(start 332.039214 -382.310894)
		(end 331.543406 -381.815086)
		(stroke
			(width 0.07112)
			(type default)
		)
		(layer "In11.Cu")
	)
	(gr_line
		(start 332.061058 -422.271698)
		(end 332.23073 -422.362376)
		(stroke
			(width 0.07112)
			(type default)
		)
		(layer "In11.Cu")
	)
	(gr_line
		(start 332.114398 -423.430954)
		(end 332.14818 -423.542968)
		(stroke
			(width 0.07112)
			(type default)
		)
		(layer "In11.Cu")
	)
	(gr_line
		(start 332.141576 -383.006092)
		(end 332.141576 -382.813814)
		(stroke
			(width 0.07112)
			(type default)
		)
		(layer "In11.Cu")
	)
	(gr_line
		(start 332.142592 -378.067824)
		(end 332.139036 -378.062236)
		(stroke
			(width 0.07112)
			(type default)
		)
		(layer "In11.Cu")
	)
	(gr_line
		(start 332.14818 -423.542968)
		(end 332.150974 -423.544492)
		(stroke
			(width 0.07112)
			(type default)
		)
		(layer "In11.Cu")
	)
	(gr_line
		(start 332.150974 -423.544492)
		(end 332.320392 -424.103546)
		(stroke
			(width 0.07112)
			(type default)
		)
		(layer "In11.Cu")
	)
	(gr_line
		(start 332.226666 -420.952168)
		(end 331.935836 -421.242998)
		(stroke
			(width 0.07112)
			(type default)
		)
		(layer "In11.Cu")
	)
	(gr_line
		(start 332.23073 -422.362376)
		(end 332.354682 -422.771062)
		(stroke
			(width 0.07112)
			(type default)
		)
		(layer "In11.Cu")
	)
	(gr_arc
		(start 332.236318 -378.579126)
		(mid 332.23581 -378.578745)
		(end 332.235302 -378.578364)
		(stroke
			(width 0.07112)
			(type default)
		)
		(layer "In11.Cu")
	)
	(gr_line
		(start 332.354682 -422.771062)
		(end 332.26248 -422.943274)
		(stroke
			(width 0.07112)
			(type default)
		)
		(layer "In11.Cu")
	)
	(gr_line
		(start 332.38567 -423.349674)
		(end 332.557882 -423.441876)
		(stroke
			(width 0.07112)
			(type default)
		)
		(layer "In11.Cu")
	)
	(gr_line
		(start 332.443582 -383.308098)
		(end 332.141576 -383.006092)
		(stroke
			(width 0.07112)
			(type default)
		)
		(layer "In11.Cu")
	)
	(gr_line
		(start 332.557882 -423.441876)
		(end 332.681834 -423.850562)
		(stroke
			(width 0.07112)
			(type default)
		)
		(layer "In11.Cu")
	)
	(gr_line
		(start 332.63586 -383.308098)
		(end 332.443582 -383.308098)
		(stroke
			(width 0.07112)
			(type default)
		)
		(layer "In11.Cu")
	)
	(gr_line
		(start 332.681834 -423.850562)
		(end 332.591156 -424.020234)
		(stroke
			(width 0.07112)
			(type default)
		)
		(layer "In11.Cu")
	)
	(gr_line
		(start 332.837028 -383.108708)
		(end 332.340966 -382.612646)
		(stroke
			(width 0.07112)
			(type default)
		)
		(layer "In11.Cu")
	)
	(gr_line
		(start 332.880208 -378.513848)
		(end 332.879446 -378.513848)
		(stroke
			(width 0.07112)
			(type default)
		)
		(layer "In11.Cu")
	)
	(gr_line
		(start 332.880208 -378.513848)
		(end 332.881478 -378.513848)
		(stroke
			(width 0.07112)
			(type default)
		)
		(layer "In11.Cu")
	)
	(gr_line
		(start 333.507588 -431.430938)
		(end 333.649828 -431.573178)
		(stroke
			(width 0.07112)
			(type default)
		)
		(layer "In11.Cu")
	)
	(gr_line
		(start 333.507588 -431.148998)
		(end 333.649828 -431.006758)
		(stroke
			(width 0.07112)
			(type default)
		)
		(layer "In11.Cu")
	)
	(gr_line
		(start 333.649828 -431.573178)
		(end 333.649828 -431.889916)
		(stroke
			(width 0.07112)
			(type default)
		)
		(layer "In11.Cu")
	)
	(gr_line
		(start 333.649828 -431.006758)
		(end 333.649828 -430.689766)
		(stroke
			(width 0.07112)
			(type default)
		)
		(layer "In11.Cu")
	)
	(gr_line
		(start 333.798418 -386.2705)
		(end 333.798164 -386.2705)
		(stroke
			(width 0.07112)
			(type default)
		)
		(layer "In11.Cu")
	)
	(gr_line
		(start 334.426306 -420.952168)
		(end 334.698848 -421.22471)
		(stroke
			(width 0.07112)
			(type default)
		)
		(layer "In11.Cu")
	)
	(gr_line
		(start 334.605884 -387.72592)
		(end 334.643476 -387.537198)
		(stroke
			(width 0.07112)
			(type default)
		)
		(layer "In11.Cu")
	)
	(gr_line
		(start 334.698848 -423.943526)
		(end 334.698848 -424.644566)
		(stroke
			(width 0.07112)
			(type default)
		)
		(layer "In11.Cu")
	)
	(gr_line
		(start 334.698848 -422.815766)
		(end 334.698848 -423.516806)
		(stroke
			(width 0.07112)
			(type default)
		)
		(layer "In11.Cu")
	)
	(gr_line
		(start 334.698848 -421.688006)
		(end 334.698848 -422.389046)
		(stroke
			(width 0.07112)
			(type default)
		)
		(layer "In11.Cu")
	)
	(gr_line
		(start 334.698848 -421.22471)
		(end 334.698848 -421.261286)
		(stroke
			(width 0.07112)
			(type default)
		)
		(layer "In11.Cu")
	)
	(gr_line
		(start 334.84312 -388.081012)
		(end 334.605884 -387.72592)
		(stroke
			(width 0.07112)
			(type default)
		)
		(layer "In11.Cu")
	)
	(gr_line
		(start 334.982058 -423.944796)
		(end 335.117948 -424.080686)
		(stroke
			(width 0.07112)
			(type default)
		)
		(layer "In11.Cu")
	)
	(gr_line
		(start 334.982058 -422.817036)
		(end 335.117948 -422.952926)
		(stroke
			(width 0.07112)
			(type default)
		)
		(layer "In11.Cu")
	)
	(gr_line
		(start 334.982058 -421.689276)
		(end 335.117948 -421.825166)
		(stroke
			(width 0.07112)
			(type default)
		)
		(layer "In11.Cu")
	)
	(gr_line
		(start 335.031842 -388.118604)
		(end 334.84312 -388.081012)
		(stroke
			(width 0.07112)
			(type default)
		)
		(layer "In11.Cu")
	)
	(gr_line
		(start 335.117948 -424.507406)
		(end 334.982058 -424.643296)
		(stroke
			(width 0.07112)
			(type default)
		)
		(layer "In11.Cu")
	)
	(gr_line
		(start 335.117948 -424.080686)
		(end 335.117948 -424.507406)
		(stroke
			(width 0.07112)
			(type default)
		)
		(layer "In11.Cu")
	)
	(gr_line
		(start 335.117948 -423.379646)
		(end 334.982058 -423.515536)
		(stroke
			(width 0.07112)
			(type default)
		)
		(layer "In11.Cu")
	)
	(gr_line
		(start 335.117948 -422.952926)
		(end 335.117948 -423.379646)
		(stroke
			(width 0.07112)
			(type default)
		)
		(layer "In11.Cu")
	)
	(gr_line
		(start 335.117948 -422.251886)
		(end 334.982058 -422.387776)
		(stroke
			(width 0.07112)
			(type default)
		)
		(layer "In11.Cu")
	)
	(gr_line
		(start 335.117948 -421.825166)
		(end 335.117948 -422.251886)
		(stroke
			(width 0.07112)
			(type default)
		)
		(layer "In11.Cu")
	)
	(gr_line
		(start 335.232502 -388.663688)
		(end 335.270094 -388.474966)
		(stroke
			(width 0.07112)
			(type default)
		)
		(layer "In11.Cu")
	)
	(gr_line
		(start 335.268062 -387.96214)
		(end 334.878426 -387.378956)
		(stroke
			(width 0.07112)
			(type default)
		)
		(layer "In11.Cu")
	)
	(gr_line
		(start 335.289906 -420.952168)
		(end 334.982058 -421.260016)
		(stroke
			(width 0.07112)
			(type default)
		)
		(layer "In11.Cu")
	)
	(gr_line
		(start 335.469738 -389.01878)
		(end 335.232502 -388.663688)
		(stroke
			(width 0.07112)
			(type default)
		)
		(layer "In11.Cu")
	)
	(gr_line
		(start 335.4832 -430.148746)
		(end 335.507584 -430.148746)
		(stroke
			(width 0.07112)
			(type default)
		)
		(layer "In11.Cu")
	)
	(gr_line
		(start 335.48447 -430.431956)
		(end 335.649824 -430.59731)
		(stroke
			(width 0.07112)
			(type default)
		)
		(layer "In11.Cu")
	)
	(gr_line
		(start 335.507584 -430.148746)
		(end 335.649824 -430.006506)
		(stroke
			(width 0.07112)
			(type default)
		)
		(layer "In11.Cu")
	)
	(gr_line
		(start 335.649824 -430.59731)
		(end 335.649824 -430.889918)
		(stroke
			(width 0.07112)
			(type default)
		)
		(layer "In11.Cu")
	)
	(gr_line
		(start 335.649824 -430.006506)
		(end 335.649824 -429.689768)
		(stroke
			(width 0.07112)
			(type default)
		)
		(layer "In11.Cu")
	)
	(gr_line
		(start 335.658714 -389.056372)
		(end 335.469738 -389.01878)
		(stroke
			(width 0.07112)
			(type default)
		)
		(layer "In11.Cu")
	)
	(gr_line
		(start 335.85912 -389.601456)
		(end 335.896712 -389.412734)
		(stroke
			(width 0.07112)
			(type default)
		)
		(layer "In11.Cu")
	)
	(gr_line
		(start 335.89468 -388.899908)
		(end 335.505044 -388.316724)
		(stroke
			(width 0.07112)
			(type default)
		)
		(layer "In11.Cu")
	)
	(gr_line
		(start 336.096356 -389.956548)
		(end 335.85912 -389.601456)
		(stroke
			(width 0.07112)
			(type default)
		)
		(layer "In11.Cu")
	)
	(gr_line
		(start 336.285332 -389.99414)
		(end 336.096356 -389.956548)
		(stroke
			(width 0.07112)
			(type default)
		)
		(layer "In11.Cu")
	)
	(gr_line
		(start 336.31886 -393.69238)
		(end 336.672174 -393.787376)
		(stroke
			(width 0.07112)
			(type default)
		)
		(layer "In11.Cu")
	)
	(gr_line
		(start 336.521298 -389.837676)
		(end 336.131662 -389.254492)
		(stroke
			(width 0.07112)
			(type default)
		)
		(layer "In11.Cu")
	)
	(gr_line
		(start 336.672174 -393.787376)
		(end 336.672682 -393.786868)
		(stroke
			(width 0.07112)
			(type default)
		)
		(layer "In11.Cu")
	)
	(gr_line
		(start 336.71891 -394.385292)
		(end 336.813652 -394.031724)
		(stroke
			(width 0.07112)
			(type default)
		)
		(layer "In11.Cu")
	)
	(gr_line
		(start 336.78622 -390.780016)
		(end 336.785966 -390.78027)
		(stroke
			(width 0.07112)
			(type default)
		)
		(layer "In11.Cu")
	)
	(gr_arc
		(start 336.823812 -431.198782)
		(mid 336.823304 -431.198274)
		(end 336.822796 -431.197766)
		(stroke
			(width 0.07112)
			(type default)
		)
		(layer "In11.Cu")
	)
	(gr_line
		(start 336.935318 -393.961112)
		(end 336.98815 -393.930632)
		(stroke
			(width 0.07112)
			(type default)
		)
		(layer "In11.Cu")
	)
	(gr_line
		(start 336.985864 -430.909476)
		(end 336.986118 -430.909476)
		(stroke
			(width 0.07112)
			(type default)
		)
		(layer "In11.Cu")
	)
	(gr_line
		(start 336.98815 -393.930632)
		(end 337.076288 -393.842494)
		(stroke
			(width 0.07112)
			(type default)
		)
		(layer "In11.Cu")
	)
	(gr_line
		(start 337.076288 -393.842494)
		(end 337.076288 -393.716764)
		(stroke
			(width 0.07112)
			(type default)
		)
		(layer "In11.Cu")
	)
	(gr_line
		(start 337.206844 -422.978834)
		(end 336.938366 -423.626534)
		(stroke
			(width 0.07112)
			(type default)
		)
		(layer "In11.Cu")
	)
	(gr_line
		(start 337.246722 -387.863588)
		(end 337.284314 -387.674866)
		(stroke
			(width 0.07112)
			(type default)
		)
		(layer "In11.Cu")
	)
	(gr_line
		(start 337.358228 -173.286928)
		(end 337.348322 -173.264576)
		(stroke
			(width 0.07112)
			(type default)
		)
		(layer "In11.Cu")
	)
	(gr_line
		(start 337.37169 -173.307248)
		(end 337.358228 -173.286928)
		(stroke
			(width 0.07112)
			(type default)
		)
		(layer "In11.Cu")
	)
	(gr_line
		(start 337.378294 -423.660062)
		(end 337.200494 -423.733722)
		(stroke
			(width 0.07112)
			(type default)
		)
		(layer "In11.Cu")
	)
	(gr_line
		(start 337.467956 -423.088054)
		(end 337.541616 -423.2656)
		(stroke
			(width 0.07112)
			(type default)
		)
		(layer "In11.Cu")
	)
	(gr_line
		(start 337.483958 -388.21868)
		(end 337.246722 -387.863588)
		(stroke
			(width 0.07112)
			(type default)
		)
		(layer "In11.Cu")
	)
	(gr_line
		(start 337.489546 -420.952168)
		(end 337.780376 -421.242998)
		(stroke
			(width 0.07112)
			(type default)
		)
		(layer "In11.Cu")
	)
	(gr_line
		(start 337.50758 -431.430938)
		(end 337.64982 -431.573178)
		(stroke
			(width 0.07112)
			(type default)
		)
		(layer "In11.Cu")
	)
	(gr_line
		(start 337.50758 -431.148998)
		(end 337.64982 -431.006758)
		(stroke
			(width 0.07112)
			(type default)
		)
		(layer "In11.Cu")
	)
	(gr_line
		(start 337.518756 -393.69238)
		(end 337.87207 -393.787376)
		(stroke
			(width 0.07112)
			(type default)
		)
		(layer "In11.Cu")
	)
	(gr_line
		(start 337.541616 -423.2656)
		(end 337.378294 -423.660062)
		(stroke
			(width 0.07112)
			(type default)
		)
		(layer "In11.Cu")
	)
	(gr_line
		(start 337.60664 -173.151038)
		(end 337.60664 -173.151292)
		(stroke
			(width 0.07112)
			(type default)
		)
		(layer "In11.Cu")
	)
	(gr_line
		(start 337.630516 -422.692322)
		(end 337.570318 -422.83761)
		(stroke
			(width 0.07112)
			(type default)
		)
		(layer "In11.Cu")
	)
	(gr_line
		(start 337.63839 -421.936418)
		(end 337.370166 -422.584626)
		(stroke
			(width 0.07112)
			(type default)
		)
		(layer "In11.Cu")
	)
	(gr_line
		(start 337.64982 -431.573178)
		(end 337.64982 -431.889916)
		(stroke
			(width 0.07112)
			(type default)
		)
		(layer "In11.Cu")
	)
	(gr_line
		(start 337.64982 -431.006758)
		(end 337.64982 -430.689766)
		(stroke
			(width 0.07112)
			(type default)
		)
		(layer "In11.Cu")
	)
	(gr_line
		(start 337.67268 -388.256272)
		(end 337.483958 -388.21868)
		(stroke
			(width 0.07112)
			(type default)
		)
		(layer "In11.Cu")
	)
	(gr_line
		(start 337.810094 -422.6179)
		(end 337.632294 -422.69156)
		(stroke
			(width 0.07112)
			(type default)
		)
		(layer "In11.Cu")
	)
	(gr_line
		(start 337.87207 -393.787376)
		(end 337.872578 -393.786868)
		(stroke
			(width 0.07112)
			(type default)
		)
		(layer "In11.Cu")
	)
	(gr_line
		(start 337.87334 -388.801356)
		(end 337.910932 -388.612634)
		(stroke
			(width 0.07112)
			(type default)
		)
		(layer "In11.Cu")
	)
	(gr_line
		(start 337.899756 -422.045638)
		(end 337.973416 -422.223438)
		(stroke
			(width 0.07112)
			(type default)
		)
		(layer "In11.Cu")
	)
	(gr_line
		(start 337.9089 -388.099808)
		(end 337.519264 -387.516624)
		(stroke
			(width 0.07112)
			(type default)
		)
		(layer "In11.Cu")
	)
	(gr_line
		(start 337.918806 -394.385292)
		(end 338.013548 -394.031724)
		(stroke
			(width 0.07112)
			(type default)
		)
		(layer "In11.Cu")
	)
	(gr_line
		(start 337.96478 -390.744964)
		(end 337.96478 -390.74471)
		(stroke
			(width 0.07112)
			(type default)
		)
		(layer "In11.Cu")
	)
	(gr_line
		(start 337.973416 -422.223438)
		(end 337.810094 -422.6179)
		(stroke
			(width 0.07112)
			(type default)
		)
		(layer "In11.Cu")
	)
	(gr_line
		(start 338.08543 -176.17694)
		(end 338.085176 -176.17694)
		(stroke
			(width 0.07112)
			(type default)
		)
		(layer "In11.Cu")
	)
	(gr_line
		(start 338.110576 -389.156448)
		(end 337.87334 -388.801356)
		(stroke
			(width 0.07112)
			(type default)
		)
		(layer "In11.Cu")
	)
	(gr_line
		(start 338.135214 -393.961112)
		(end 338.188046 -393.930632)
		(stroke
			(width 0.07112)
			(type default)
		)
		(layer "In11.Cu")
	)
	(gr_line
		(start 338.188046 -393.930632)
		(end 338.276184 -393.842494)
		(stroke
			(width 0.07112)
			(type default)
		)
		(layer "In11.Cu")
	)
	(gr_line
		(start 338.276184 -393.842494)
		(end 338.276184 -393.716764)
		(stroke
			(width 0.07112)
			(type default)
		)
		(layer "In11.Cu")
	)
	(gr_line
		(start 338.297012 -387.382512)
		(end 338.334604 -387.194044)
		(stroke
			(width 0.07112)
			(type default)
		)
		(layer "In11.Cu")
	)
	(gr_line
		(start 338.299552 -389.19404)
		(end 338.110576 -389.156448)
		(stroke
			(width 0.07112)
			(type default)
		)
		(layer "In11.Cu")
	)
	(gr_line
		(start 338.353146 -420.952168)
		(end 338.062316 -421.242998)
		(stroke
			(width 0.07112)
			(type default)
		)
		(layer "In11.Cu")
	)
	(gr_line
		(start 338.499958 -389.739124)
		(end 338.53755 -389.550402)
		(stroke
			(width 0.07112)
			(type default)
		)
		(layer "In11.Cu")
	)
	(gr_line
		(start 338.534248 -387.737604)
		(end 338.297012 -387.382512)
		(stroke
			(width 0.07112)
			(type default)
		)
		(layer "In11.Cu")
	)
	(gr_line
		(start 338.535518 -389.037576)
		(end 338.145882 -388.454392)
		(stroke
			(width 0.07112)
			(type default)
		)
		(layer "In11.Cu")
	)
	(gr_line
		(start 338.56041 -381.552704)
		(end 338.560156 -381.552704)
		(stroke
			(width 0.07112)
			(type default)
		)
		(layer "In11.Cu")
	)
	(gr_line
		(start 338.718906 -393.69238)
		(end 339.071966 -393.787376)
		(stroke
			(width 0.07112)
			(type default)
		)
		(layer "In11.Cu")
	)
	(gr_line
		(start 338.71916 -378.230892)
		(end 338.71916 -378.230638)
		(stroke
			(width 0.07112)
			(type default)
		)
		(layer "In11.Cu")
	)
	(gr_line
		(start 338.72297 -387.775196)
		(end 338.534248 -387.737604)
		(stroke
			(width 0.07112)
			(type default)
		)
		(layer "In11.Cu")
	)
	(gr_line
		(start 338.737194 -390.094216)
		(end 338.499958 -389.739124)
		(stroke
			(width 0.07112)
			(type default)
		)
		(layer "In11.Cu")
	)
	(gr_line
		(start 338.759546 -424.284902)
		(end 338.695538 -424.36288)
		(stroke
			(width 0.07112)
			(type default)
		)
		(layer "In11.Cu")
	)
	(gr_line
		(start 338.92363 -388.32028)
		(end 338.961222 -388.131812)
		(stroke
			(width 0.07112)
			(type default)
		)
		(layer "In11.Cu")
	)
	(gr_line
		(start 338.92617 -390.131808)
		(end 338.737194 -390.094216)
		(stroke
			(width 0.07112)
			(type default)
		)
		(layer "In11.Cu")
	)
	(gr_line
		(start 338.95411 -378.074428)
		(end 338.953094 -378.073158)
		(stroke
			(width 0.07112)
			(type default)
		)
		(layer "In11.Cu")
	)
	(gr_line
		(start 338.958936 -387.618732)
		(end 338.5693 -387.035548)
		(stroke
			(width 0.07112)
			(type default)
		)
		(layer "In11.Cu")
	)
	(gr_line
		(start 338.983574 -424.011852)
		(end 338.759546 -424.284902)
		(stroke
			(width 0.07112)
			(type default)
		)
		(layer "In11.Cu")
	)
	(gr_arc
		(start 339.043518 -378.579126)
		(mid 339.04301 -378.578745)
		(end 339.042502 -378.578364)
		(stroke
			(width 0.07112)
			(type default)
		)
		(layer "In11.Cu")
	)
	(gr_line
		(start 339.071966 -393.787376)
		(end 339.072474 -393.786868)
		(stroke
			(width 0.07112)
			(type default)
		)
		(layer "In11.Cu")
	)
	(gr_line
		(start 339.118702 -394.385292)
		(end 339.213444 -394.031724)
		(stroke
			(width 0.07112)
			(type default)
		)
		(layer "In11.Cu")
	)
	(gr_line
		(start 339.160866 -388.675372)
		(end 338.92363 -388.32028)
		(stroke
			(width 0.07112)
			(type default)
		)
		(layer "In11.Cu")
	)
	(gr_line
		(start 339.162136 -389.975344)
		(end 338.7725 -389.39216)
		(stroke
			(width 0.07112)
			(type default)
		)
		(layer "In11.Cu")
	)
	(gr_line
		(start 339.186012 -390.557004)
		(end 339.185758 -390.557258)
		(stroke
			(width 0.07112)
			(type default)
		)
		(layer "In11.Cu")
	)
	(gr_line
		(start 339.201506 -424.190668)
		(end 338.977478 -424.463718)
		(stroke
			(width 0.07112)
			(type default)
		)
		(layer "In11.Cu")
	)
	(gr_line
		(start 339.33511 -393.961112)
		(end 339.387942 -393.930632)
		(stroke
			(width 0.07112)
			(type default)
		)
		(layer "In11.Cu")
	)
	(gr_line
		(start 339.349588 -388.712964)
		(end 339.160866 -388.675372)
		(stroke
			(width 0.07112)
			(type default)
		)
		(layer "In11.Cu")
	)
	(gr_line
		(start 339.379052 -424.173142)
		(end 339.203284 -424.190414)
		(stroke
			(width 0.07112)
			(type default)
		)
		(layer "In11.Cu")
	)
	(gr_line
		(start 339.387942 -393.930632)
		(end 339.47608 -393.842494)
		(stroke
			(width 0.07112)
			(type default)
		)
		(layer "In11.Cu")
	)
	(gr_line
		(start 339.414612 -423.48658)
		(end 338.983574 -424.011852)
		(stroke
			(width 0.07112)
			(type default)
		)
		(layer "In11.Cu")
	)
	(gr_line
		(start 339.452712 -430.170336)
		(end 339.485986 -430.170336)
		(stroke
			(width 0.07112)
			(type default)
		)
		(layer "In11.Cu")
	)
	(gr_line
		(start 339.453982 -430.453546)
		(end 339.649816 -430.64938)
		(stroke
			(width 0.07112)
			(type default)
		)
		(layer "In11.Cu")
	)
	(gr_arc
		(start 339.461856 -382.05537)
		(mid 339.46211 -382.055624)
		(end 339.462364 -382.055878)
		(stroke
			(width 0.07112)
			(type default)
		)
		(layer "In11.Cu")
	)
	(gr_line
		(start 339.47608 -393.842494)
		(end 339.47608 -393.716764)
		(stroke
			(width 0.07112)
			(type default)
		)
		(layer "In11.Cu")
	)
	(gr_line
		(start 339.485986 -430.170336)
		(end 339.649816 -430.006506)
		(stroke
			(width 0.07112)
			(type default)
		)
		(layer "In11.Cu")
	)
	(gr_line
		(start 339.550248 -389.258048)
		(end 339.58784 -389.06958)
		(stroke
			(width 0.07112)
			(type default)
		)
		(layer "In11.Cu")
	)
	(gr_line
		(start 339.585554 -388.5565)
		(end 339.195918 -387.973316)
		(stroke
			(width 0.07112)
			(type default)
		)
		(layer "In11.Cu")
	)
	(gr_line
		(start 339.632798 -423.667174)
		(end 339.65007 -423.842942)
		(stroke
			(width 0.07112)
			(type default)
		)
		(layer "In11.Cu")
	)
	(gr_line
		(start 339.649816 -430.64938)
		(end 339.649816 -430.889918)
		(stroke
			(width 0.07112)
			(type default)
		)
		(layer "In11.Cu")
	)
	(gr_line
		(start 339.649816 -430.006506)
		(end 339.649816 -429.689768)
		(stroke
			(width 0.07112)
			(type default)
		)
		(layer "In11.Cu")
	)
	(gr_line
		(start 339.65007 -423.842942)
		(end 339.379052 -424.173142)
		(stroke
			(width 0.07112)
			(type default)
		)
		(layer "In11.Cu")
	)
	(gr_line
		(start 339.687408 -378.513848)
		(end 339.686646 -378.513848)
		(stroke
			(width 0.07112)
			(type default)
		)
		(layer "In11.Cu")
	)
	(gr_line
		(start 339.687408 -378.513848)
		(end 339.688678 -378.513848)
		(stroke
			(width 0.07112)
			(type default)
		)
		(layer "In11.Cu")
	)
	(gr_line
		(start 339.787484 -389.61314)
		(end 339.550248 -389.258048)
		(stroke
			(width 0.07112)
			(type default)
		)
		(layer "In11.Cu")
	)
	(gr_line
		(start 339.918802 -393.69238)
		(end 340.272116 -393.787376)
		(stroke
			(width 0.07112)
			(type default)
		)
		(layer "In11.Cu")
	)
	(gr_line
		(start 339.976206 -389.650732)
		(end 339.787484 -389.61314)
		(stroke
			(width 0.07112)
			(type default)
		)
		(layer "In11.Cu")
	)
	(gr_line
		(start 340.063328 -423.357548)
		(end 339.871304 -423.376344)
		(stroke
			(width 0.07112)
			(type default)
		)
		(layer "In11.Cu")
	)
	(gr_line
		(start 340.09711 -422.654476)
		(end 339.651594 -423.197782)
		(stroke
			(width 0.07112)
			(type default)
		)
		(layer "In11.Cu")
	)
	(gr_line
		(start 340.212172 -389.494268)
		(end 339.822536 -388.911084)
		(stroke
			(width 0.07112)
			(type default)
		)
		(layer "In11.Cu")
	)
	(gr_line
		(start 340.272116 -393.787376)
		(end 340.272624 -393.786868)
		(stroke
			(width 0.07112)
			(type default)
		)
		(layer "In11.Cu")
	)
	(gr_line
		(start 340.31555 -422.83507)
		(end 340.334346 -423.027348)
		(stroke
			(width 0.07112)
			(type default)
		)
		(layer "In11.Cu")
	)
	(gr_line
		(start 340.318852 -394.385292)
		(end 340.413594 -394.031724)
		(stroke
			(width 0.07112)
			(type default)
		)
		(layer "In11.Cu")
	)
	(gr_line
		(start 340.334346 -423.027348)
		(end 340.063328 -423.357548)
		(stroke
			(width 0.07112)
			(type default)
		)
		(layer "In11.Cu")
	)
	(gr_line
		(start 340.506558 -386.776468)
		(end 340.597236 -386.606542)
		(stroke
			(width 0.07112)
			(type default)
		)
		(layer "In11.Cu")
	)
	(gr_line
		(start 340.53526 -393.961112)
		(end 340.588092 -393.930632)
		(stroke
			(width 0.07112)
			(type default)
		)
		(layer "In11.Cu")
	)
	(gr_line
		(start 340.552786 -420.952168)
		(end 340.843616 -421.242998)
		(stroke
			(width 0.07112)
			(type default)
		)
		(layer "In11.Cu")
	)
	(gr_line
		(start 340.588092 -393.930632)
		(end 340.67623 -393.842494)
		(stroke
			(width 0.07112)
			(type default)
		)
		(layer "In11.Cu")
	)
	(gr_line
		(start 340.628986 -381.130556)
		(end 340.628732 -381.130302)
		(stroke
			(width 0.07112)
			(type default)
		)
		(layer "In11.Cu")
	)
	(gr_line
		(start 340.630256 -387.185154)
		(end 340.506558 -386.776468)
		(stroke
			(width 0.07112)
			(type default)
		)
		(layer "In11.Cu")
	)
	(gr_line
		(start 340.674198 -421.951404)
		(end 340.300564 -422.406572)
		(stroke
			(width 0.07112)
			(type default)
		)
		(layer "In11.Cu")
	)
	(gr_line
		(start 340.674198 -421.950642)
		(end 340.674198 -421.951404)
		(stroke
			(width 0.07112)
			(type default)
		)
		(layer "In11.Cu")
	)
	(gr_line
		(start 340.67623 -393.842494)
		(end 340.67623 -393.716764)
		(stroke
			(width 0.07112)
			(type default)
		)
		(layer "In11.Cu")
	)
	(gr_line
		(start 340.725506 -422.565068)
		(end 340.520274 -422.585388)
		(stroke
			(width 0.07112)
			(type default)
		)
		(layer "In11.Cu")
	)
	(gr_line
		(start 340.800436 -387.275832)
		(end 340.630256 -387.185154)
		(stroke
			(width 0.07112)
			(type default)
		)
		(layer "In11.Cu")
	)
	(gr_line
		(start 340.833964 -387.855714)
		(end 340.924896 -387.685788)
		(stroke
			(width 0.07112)
			(type default)
		)
		(layer "In11.Cu")
	)
	(gr_line
		(start 340.842346 -421.745664)
		(end 340.674198 -421.950642)
		(stroke
			(width 0.07112)
			(type default)
		)
		(layer "In11.Cu")
	)
	(gr_line
		(start 340.925404 -387.684772)
		(end 340.92515 -387.684772)
		(stroke
			(width 0.07112)
			(type default)
		)
		(layer "In11.Cu")
	)
	(gr_line
		(start 340.928706 -422.092628)
		(end 340.948518 -422.293542)
		(stroke
			(width 0.07112)
			(type default)
		)
		(layer "In11.Cu")
	)
	(gr_line
		(start 340.948518 -422.293542)
		(end 340.725506 -422.565068)
		(stroke
			(width 0.07112)
			(type default)
		)
		(layer "In11.Cu")
	)
	(gr_line
		(start 340.957662 -388.2644)
		(end 340.833964 -387.855714)
		(stroke
			(width 0.07112)
			(type default)
		)
		(layer "In11.Cu")
	)
	(gr_line
		(start 341.05088 -384.366516)
		(end 341.147908 -384.199892)
		(stroke
			(width 0.07112)
			(type default)
		)
		(layer "In11.Cu")
	)
	(gr_line
		(start 341.071708 -387.194552)
		(end 340.868 -386.523484)
		(stroke
			(width 0.07112)
			(type default)
		)
		(layer "In11.Cu")
	)
	(gr_line
		(start 341.118698 -393.69238)
		(end 341.472012 -393.787376)
		(stroke
			(width 0.07112)
			(type default)
		)
		(layer "In11.Cu")
	)
	(gr_line
		(start 341.125556 -421.852852)
		(end 340.928706 -422.092628)
		(stroke
			(width 0.07112)
			(type default)
		)
		(layer "In11.Cu")
	)
	(gr_line
		(start 341.125556 -421.74414)
		(end 341.125556 -421.852852)
		(stroke
			(width 0.07112)
			(type default)
		)
		(layer "In11.Cu")
	)
	(gr_line
		(start 341.127842 -388.355078)
		(end 340.957662 -388.2644)
		(stroke
			(width 0.07112)
			(type default)
		)
		(layer "In11.Cu")
	)
	(gr_line
		(start 341.1601 -384.779266)
		(end 341.05088 -384.366516)
		(stroke
			(width 0.07112)
			(type default)
		)
		(layer "In11.Cu")
	)
	(gr_line
		(start 341.16137 -388.93496)
		(end 341.252302 -388.765034)
		(stroke
			(width 0.07112)
			(type default)
		)
		(layer "In11.Cu")
	)
	(gr_line
		(start 341.285322 -389.343646)
		(end 341.16137 -388.93496)
		(stroke
			(width 0.07112)
			(type default)
		)
		(layer "In11.Cu")
	)
	(gr_line
		(start 341.326724 -384.87604)
		(end 341.1601 -384.779266)
		(stroke
			(width 0.07112)
			(type default)
		)
		(layer "In11.Cu")
	)
	(gr_line
		(start 341.339424 -385.456938)
		(end 341.436198 -385.290568)
		(stroke
			(width 0.07112)
			(type default)
		)
		(layer "In11.Cu")
	)
	(gr_line
		(start 341.399114 -388.274052)
		(end 341.195406 -387.60273)
		(stroke
			(width 0.07112)
			(type default)
		)
		(layer "In11.Cu")
	)
	(gr_line
		(start 341.416386 -420.952168)
		(end 341.125556 -421.242998)
		(stroke
			(width 0.07112)
			(type default)
		)
		(layer "In11.Cu")
	)
	(gr_line
		(start 341.44839 -385.869688)
		(end 341.339424 -385.456938)
		(stroke
			(width 0.07112)
			(type default)
		)
		(layer "In11.Cu")
	)
	(gr_line
		(start 341.455248 -389.434324)
		(end 341.285322 -389.343646)
		(stroke
			(width 0.07112)
			(type default)
		)
		(layer "In11.Cu")
	)
	(gr_line
		(start 341.472012 -393.787376)
		(end 341.47252 -393.786868)
		(stroke
			(width 0.07112)
			(type default)
		)
		(layer "In11.Cu")
	)
	(gr_line
		(start 341.491824 -431.446686)
		(end 341.522812 -431.446686)
		(stroke
			(width 0.07112)
			(type default)
		)
		(layer "In11.Cu")
	)
	(gr_line
		(start 341.493094 -431.163476)
		(end 341.649812 -431.006758)
		(stroke
			(width 0.07112)
			(type default)
		)
		(layer "In11.Cu")
	)
	(gr_line
		(start 341.518748 -394.385292)
		(end 341.61349 -394.031724)
		(stroke
			(width 0.07112)
			(type default)
		)
		(layer "In11.Cu")
	)
	(gr_line
		(start 341.522812 -431.446686)
		(end 341.649812 -431.573686)
		(stroke
			(width 0.07112)
			(type default)
		)
		(layer "In11.Cu")
	)
	(gr_line
		(start 341.586058 -390.035542)
		(end 341.585804 -390.035796)
		(stroke
			(width 0.07112)
			(type default)
		)
		(layer "In11.Cu")
	)
	(gr_line
		(start 341.60079 -384.804666)
		(end 341.421466 -384.12674)
		(stroke
			(width 0.07112)
			(type default)
		)
		(layer "In11.Cu")
	)
	(gr_line
		(start 341.615014 -385.966462)
		(end 341.44839 -385.869688)
		(stroke
			(width 0.07112)
			(type default)
		)
		(layer "In11.Cu")
	)
	(gr_line
		(start 341.637874 -423.961814)
		(end 341.449152 -423.924222)
		(stroke
			(width 0.07112)
			(type default)
		)
		(layer "In11.Cu")
	)
	(gr_line
		(start 341.649812 -431.573686)
		(end 341.649812 -431.889916)
		(stroke
			(width 0.07112)
			(type default)
		)
		(layer "In11.Cu")
	)
	(gr_line
		(start 341.649812 -431.006758)
		(end 341.649812 -430.689766)
		(stroke
			(width 0.07112)
			(type default)
		)
		(layer "In11.Cu")
	)
	(gr_line
		(start 341.726774 -389.353298)
		(end 341.522812 -388.681468)
		(stroke
			(width 0.07112)
			(type default)
		)
		(layer "In11.Cu")
	)
	(gr_line
		(start 341.735156 -393.961112)
		(end 341.787988 -393.930632)
		(stroke
			(width 0.07112)
			(type default)
		)
		(layer "In11.Cu")
	)
	(gr_line
		(start 341.787988 -393.930632)
		(end 341.876126 -393.842494)
		(stroke
			(width 0.07112)
			(type default)
		)
		(layer "In11.Cu")
	)
	(gr_line
		(start 341.87384 -423.29989)
		(end 341.29091 -423.689272)
		(stroke
			(width 0.07112)
			(type default)
		)
		(layer "In11.Cu")
	)
	(gr_line
		(start 341.876126 -393.842494)
		(end 341.876126 -393.716764)
		(stroke
			(width 0.07112)
			(type default)
		)
		(layer "In11.Cu")
	)
	(gr_line
		(start 341.88908 -385.895088)
		(end 341.709756 -385.217162)
		(stroke
			(width 0.07112)
			(type default)
		)
		(layer "In11.Cu")
	)
	(gr_line
		(start 341.992712 -423.724578)
		(end 341.637874 -423.961814)
		(stroke
			(width 0.07112)
			(type default)
		)
		(layer "In11.Cu")
	)
	(gr_line
		(start 342.030304 -423.535856)
		(end 341.992712 -423.724578)
		(stroke
			(width 0.07112)
			(type default)
		)
		(layer "In11.Cu")
	)
	(gr_line
		(start 342.318848 -393.69238)
		(end 342.672162 -393.787376)
		(stroke
			(width 0.07112)
			(type default)
		)
		(layer "In11.Cu")
	)
	(gr_line
		(start 342.575388 -423.335196)
		(end 342.38692 -423.297604)
		(stroke
			(width 0.07112)
			(type default)
		)
		(layer "In11.Cu")
	)
	(gr_line
		(start 342.672162 -393.787376)
		(end 342.67267 -393.786868)
		(stroke
			(width 0.07112)
			(type default)
		)
		(layer "In11.Cu")
	)
	(gr_line
		(start 342.718898 -394.385292)
		(end 342.81364 -394.031724)
		(stroke
			(width 0.07112)
			(type default)
		)
		(layer "In11.Cu")
	)
	(gr_line
		(start 342.78189 -390.373362)
		(end 342.781636 -390.373362)
		(stroke
			(width 0.07112)
			(type default)
		)
		(layer "In11.Cu")
	)
	(gr_line
		(start 342.811608 -422.673272)
		(end 342.228424 -423.062908)
		(stroke
			(width 0.07112)
			(type default)
		)
		(layer "In11.Cu")
	)
	(gr_line
		(start 342.93048 -423.09796)
		(end 342.575388 -423.335196)
		(stroke
			(width 0.07112)
			(type default)
		)
		(layer "In11.Cu")
	)
	(gr_line
		(start 342.935306 -393.961112)
		(end 342.988138 -393.930632)
		(stroke
			(width 0.07112)
			(type default)
		)
		(layer "In11.Cu")
	)
	(gr_line
		(start 342.968072 -422.909492)
		(end 342.93048 -423.09796)
		(stroke
			(width 0.07112)
			(type default)
		)
		(layer "In11.Cu")
	)
	(gr_line
		(start 342.982804 -387.387084)
		(end 343.0778 -387.219698)
		(stroke
			(width 0.07112)
			(type default)
		)
		(layer "In11.Cu")
	)
	(gr_line
		(start 342.988138 -393.930632)
		(end 343.076276 -393.842494)
		(stroke
			(width 0.07112)
			(type default)
		)
		(layer "In11.Cu")
	)
	(gr_arc
		(start 343.068148 -390.405112)
		(mid 343.068148 -390.405366)
		(end 343.068148 -390.40562)
		(stroke
			(width 0.07112)
			(type default)
		)
		(layer "In11.Cu")
	)
	(gr_line
		(start 343.076276 -393.842494)
		(end 343.076276 -393.716764)
		(stroke
			(width 0.07112)
			(type default)
		)
		(layer "In11.Cu")
	)
	(gr_line
		(start 343.09685 -387.798564)
		(end 342.982804 -387.387084)
		(stroke
			(width 0.07112)
			(type default)
		)
		(layer "In11.Cu")
	)
	(gr_line
		(start 343.264236 -387.893052)
		(end 343.09685 -387.798564)
		(stroke
			(width 0.07112)
			(type default)
		)
		(layer "In11.Cu")
	)
	(gr_line
		(start 343.283794 -388.474204)
		(end 343.37879 -388.306818)
		(stroke
			(width 0.07112)
			(type default)
		)
		(layer "In11.Cu")
	)
	(gr_line
		(start 343.290906 -387.985)
		(end 343.26576 -387.894068)
		(stroke
			(width 0.07112)
			(type default)
		)
		(layer "In11.Cu")
	)
	(gr_line
		(start 343.39784 -388.885684)
		(end 343.283794 -388.474204)
		(stroke
			(width 0.07112)
			(type default)
		)
		(layer "In11.Cu")
	)
	(gr_line
		(start 343.507568 -430.430686)
		(end 343.649808 -430.572926)
		(stroke
			(width 0.07112)
			(type default)
		)
		(layer "In11.Cu")
	)
	(gr_line
		(start 343.507568 -430.148746)
		(end 343.649808 -430.006506)
		(stroke
			(width 0.07112)
			(type default)
		)
		(layer "In11.Cu")
	)
	(gr_line
		(start 343.518744 -393.69238)
		(end 343.872058 -393.787376)
		(stroke
			(width 0.07112)
			(type default)
		)
		(layer "In11.Cu")
	)
	(gr_line
		(start 343.53754 -387.818884)
		(end 343.350342 -387.14299)
		(stroke
			(width 0.07112)
			(type default)
		)
		(layer "In11.Cu")
	)
	(gr_line
		(start 343.562686 -387.909562)
		(end 343.53754 -387.818884)
		(stroke
			(width 0.07112)
			(type default)
		)
		(layer "In11.Cu")
	)
	(gr_line
		(start 343.565226 -388.980172)
		(end 343.39784 -388.885684)
		(stroke
			(width 0.07112)
			(type default)
		)
		(layer "In11.Cu")
	)
	(gr_line
		(start 343.584784 -389.561324)
		(end 343.67978 -389.393938)
		(stroke
			(width 0.07112)
			(type default)
		)
		(layer "In11.Cu")
	)
	(gr_line
		(start 343.59215 -389.072882)
		(end 343.56675 -388.981188)
		(stroke
			(width 0.07112)
			(type default)
		)
		(layer "In11.Cu")
	)
	(gr_line
		(start 343.616026 -420.952168)
		(end 343.906856 -421.242998)
		(stroke
			(width 0.07112)
			(type default)
		)
		(layer "In11.Cu")
	)
	(gr_line
		(start 343.624154 -424.114722)
		(end 343.431876 -424.114722)
		(stroke
			(width 0.07112)
			(type default)
		)
		(layer "In11.Cu")
	)
	(gr_line
		(start 343.649808 -430.572926)
		(end 343.649808 -430.889918)
		(stroke
			(width 0.07112)
			(type default)
		)
		(layer "In11.Cu")
	)
	(gr_line
		(start 343.649808 -430.006506)
		(end 343.649808 -429.689768)
		(stroke
			(width 0.07112)
			(type default)
		)
		(layer "In11.Cu")
	)
	(gr_line
		(start 343.69883 -389.972804)
		(end 343.584784 -389.561324)
		(stroke
			(width 0.07112)
			(type default)
		)
		(layer "In11.Cu")
	)
	(gr_line
		(start 343.72677 -423.41927)
		(end 343.230708 -423.915332)
		(stroke
			(width 0.07112)
			(type default)
		)
		(layer "In11.Cu")
	)
	(gr_line
		(start 343.83853 -388.906004)
		(end 343.651332 -388.23011)
		(stroke
			(width 0.07112)
			(type default)
		)
		(layer "In11.Cu")
	)
	(gr_line
		(start 343.86393 -388.997698)
		(end 343.83853 -388.906004)
		(stroke
			(width 0.07112)
			(type default)
		)
		(layer "In11.Cu")
	)
	(gr_line
		(start 343.866216 -390.067292)
		(end 343.69883 -389.972804)
		(stroke
			(width 0.07112)
			(type default)
		)
		(layer "In11.Cu")
	)
	(gr_line
		(start 343.872058 -393.787376)
		(end 343.872566 -393.786868)
		(stroke
			(width 0.07112)
			(type default)
		)
		(layer "In11.Cu")
	)
	(gr_line
		(start 343.893394 -390.161018)
		(end 343.86774 -390.068308)
		(stroke
			(width 0.07112)
			(type default)
		)
		(layer "In11.Cu")
	)
	(gr_line
		(start 343.918794 -394.385292)
		(end 344.013536 -394.031724)
		(stroke
			(width 0.07112)
			(type default)
		)
		(layer "In11.Cu")
	)
	(gr_line
		(start 343.92616 -423.812716)
		(end 343.624154 -424.114722)
		(stroke
			(width 0.07112)
			(type default)
		)
		(layer "In11.Cu")
	)
	(gr_line
		(start 343.92616 -423.620438)
		(end 343.92616 -423.812716)
		(stroke
			(width 0.07112)
			(type default)
		)
		(layer "In11.Cu")
	)
	(gr_line
		(start 344.135202 -393.961112)
		(end 344.188034 -393.930632)
		(stroke
			(width 0.07112)
			(type default)
		)
		(layer "In11.Cu")
	)
	(gr_line
		(start 344.13952 -389.993124)
		(end 343.952322 -389.31723)
		(stroke
			(width 0.07112)
			(type default)
		)
		(layer "In11.Cu")
	)
	(gr_line
		(start 344.165174 -390.085834)
		(end 344.13952 -389.993124)
		(stroke
			(width 0.07112)
			(type default)
		)
		(layer "In11.Cu")
	)
	(gr_line
		(start 344.188034 -393.930632)
		(end 344.276172 -393.842494)
		(stroke
			(width 0.07112)
			(type default)
		)
		(layer "In11.Cu")
	)
	(gr_line
		(start 344.276172 -393.842494)
		(end 344.276172 -393.716764)
		(stroke
			(width 0.07112)
			(type default)
		)
		(layer "In11.Cu")
	)
	(gr_line
		(start 344.370152 -296.46372)
		(end 344.370152 -296.435272)
		(stroke
			(width 0.05715)
			(type default)
		)
		(layer "In11.Cu")
	)
	(gr_line
		(start 344.370152 -296.435272)
		(end 344.415872 -296.389552)
		(stroke
			(width 0.05715)
			(type default)
		)
		(layer "In11.Cu")
	)
	(gr_line
		(start 344.479626 -420.952168)
		(end 344.188796 -421.242998)
		(stroke
			(width 0.07112)
			(type default)
		)
		(layer "In11.Cu")
	)
	(gr_line
		(start 344.652092 -296.46372)
		(end 344.652092 -296.435272)
		(stroke
			(width 0.05715)
			(type default)
		)
		(layer "In11.Cu")
	)
	(gr_line
		(start 344.652092 -296.435272)
		(end 344.606372 -296.389552)
		(stroke
			(width 0.05715)
			(type default)
		)
		(layer "In11.Cu")
	)
	(gr_arc
		(start 344.669364 -280.226516)
		(mid 344.673038 -280.228817)
		(end 344.67673 -280.231088)
		(stroke
			(width 0.05715)
			(type default)
		)
		(layer "In11.Cu")
	)
	(gr_arc
		(start 344.67673 -279.281128)
		(mid 344.672911 -279.283399)
		(end 344.66911 -279.2857)
		(stroke
			(width 0.05715)
			(type default)
		)
		(layer "In11.Cu")
	)
	(gr_line
		(start 344.677492 -280.231596)
		(end 344.67673 -280.231088)
		(stroke
			(width 0.05715)
			(type default)
		)
		(layer "In11.Cu")
	)
	(gr_line
		(start 344.718894 -393.69238)
		(end 345.071954 -393.787376)
		(stroke
			(width 0.07112)
			(type default)
		)
		(layer "In11.Cu")
	)
	(gr_line
		(start 344.772742 -280.066242)
		(end 344.772488 -280.066242)
		(stroke
			(width 0.05715)
			(type default)
		)
		(layer "In11.Cu")
	)
	(gr_line
		(start 344.777314 -422.78427)
		(end 344.777314 -422.784524)
		(stroke
			(width 0.07112)
			(type default)
		)
		(layer "In11.Cu")
	)
	(gr_line
		(start 344.82532 -279.41524)
		(end 344.832432 -279.411176)
		(stroke
			(width 0.05715)
			(type default)
		)
		(layer "In11.Cu")
	)
	(gr_arc
		(start 344.833194 -279.410668)
		(mid 344.832813 -279.410922)
		(end 344.832432 -279.411176)
		(stroke
			(width 0.05715)
			(type default)
		)
		(layer "In11.Cu")
	)
	(gr_arc
		(start 344.833194 -279.410668)
		(mid 344.837143 -279.407891)
		(end 344.841068 -279.40508)
		(stroke
			(width 0.05715)
			(type default)
		)
		(layer "In11.Cu")
	)
	(gr_arc
		(start 344.955622 -424.08729)
		(mid 344.954094 -424.089319)
		(end 344.952574 -424.091354)
		(stroke
			(width 0.07112)
			(type default)
		)
		(layer "In11.Cu")
	)
	(gr_line
		(start 344.986102 -424.846496)
		(end 344.985848 -424.846242)
		(stroke
			(width 0.07112)
			(type default)
		)
		(layer "In11.Cu")
	)
	(gr_line
		(start 345.064334 -423.119296)
		(end 344.88628 -423.045636)
		(stroke
			(width 0.07112)
			(type default)
		)
		(layer "In11.Cu")
	)
	(gr_line
		(start 345.071954 -393.787376)
		(end 345.072462 -393.786868)
		(stroke
			(width 0.07112)
			(type default)
		)
		(layer "In11.Cu")
	)
	(gr_line
		(start 345.076272 -295.239694)
		(end 345.076526 -295.23944)
		(stroke
			(width 0.05715)
			(type default)
		)
		(layer "In11.Cu")
	)
	(gr_line
		(start 345.11869 -394.385292)
		(end 345.213432 -394.031724)
		(stroke
			(width 0.07112)
			(type default)
		)
		(layer "In11.Cu")
	)
	(gr_arc
		(start 345.129104 -286.581342)
		(mid 345.124388 -286.58462)
		(end 345.119706 -286.587946)
		(stroke
			(width 0.05715)
			(type default)
		)
		(layer "In11.Cu")
	)
	(gr_line
		(start 345.129104 -286.581342)
		(end 345.131136 -286.579818)
		(stroke
			(width 0.05715)
			(type default)
		)
		(layer "In11.Cu")
	)
	(gr_line
		(start 345.131136 -286.579818)
		(end 345.135962 -286.577024)
		(stroke
			(width 0.05715)
			(type default)
		)
		(layer "In11.Cu")
	)
	(gr_line
		(start 345.150948 -387.41096)
		(end 345.171776 -386.984494)
		(stroke
			(width 0.07112)
			(type default)
		)
		(layer "In11.Cu")
	)
	(gr_line
		(start 345.171776 -386.984494)
		(end 345.314524 -386.855462)
		(stroke
			(width 0.07112)
			(type default)
		)
		(layer "In11.Cu")
	)
	(gr_line
		(start 345.20632 -386.284724)
		(end 345.227148 -385.858258)
		(stroke
			(width 0.07112)
			(type default)
		)
		(layer "In11.Cu")
	)
	(gr_line
		(start 345.227148 -385.858258)
		(end 345.369642 -385.729226)
		(stroke
			(width 0.07112)
			(type default)
		)
		(layer "In11.Cu")
	)
	(gr_line
		(start 345.261692 -385.158234)
		(end 345.28252 -384.731768)
		(stroke
			(width 0.07112)
			(type default)
		)
		(layer "In11.Cu")
	)
	(gr_line
		(start 345.26347 -286.723836)
		(end 345.263978 -286.723582)
		(stroke
			(width 0.05715)
			(type default)
		)
		(layer "In11.Cu")
	)
	(gr_line
		(start 345.280234 -387.553454)
		(end 345.150948 -387.41096)
		(stroke
			(width 0.07112)
			(type default)
		)
		(layer "In11.Cu")
	)
	(gr_line
		(start 345.28252 -384.731768)
		(end 345.425014 -384.602736)
		(stroke
			(width 0.07112)
			(type default)
		)
		(layer "In11.Cu")
	)
	(gr_line
		(start 345.310206 -296.46372)
		(end 345.310206 -296.435272)
		(stroke
			(width 0.05715)
			(type default)
		)
		(layer "In11.Cu")
	)
	(gr_line
		(start 345.310206 -296.435272)
		(end 345.355926 -296.389552)
		(stroke
			(width 0.05715)
			(type default)
		)
		(layer "In11.Cu")
	)
	(gr_line
		(start 345.315794 -386.854192)
		(end 345.31554 -386.854192)
		(stroke
			(width 0.07112)
			(type default)
		)
		(layer "In11.Cu")
	)
	(gr_line
		(start 345.335098 -393.961112)
		(end 345.38793 -393.930632)
		(stroke
			(width 0.07112)
			(type default)
		)
		(layer "In11.Cu")
	)
	(gr_line
		(start 345.335352 -386.426964)
		(end 345.20632 -386.284724)
		(stroke
			(width 0.07112)
			(type default)
		)
		(layer "In11.Cu")
	)
	(gr_line
		(start 345.336368 -386.428234)
		(end 345.336622 -386.428234)
		(stroke
			(width 0.07112)
			(type default)
		)
		(layer "In11.Cu")
	)
	(gr_line
		(start 345.371166 -385.727956)
		(end 345.370912 -385.727956)
		(stroke
			(width 0.07112)
			(type default)
		)
		(layer "In11.Cu")
	)
	(gr_line
		(start 345.38793 -393.930632)
		(end 345.476068 -393.842494)
		(stroke
			(width 0.07112)
			(type default)
		)
		(layer "In11.Cu")
	)
	(gr_line
		(start 345.390724 -385.300728)
		(end 345.261692 -385.158234)
		(stroke
			(width 0.07112)
			(type default)
		)
		(layer "In11.Cu")
	)
	(gr_line
		(start 345.39174 -385.301998)
		(end 345.391994 -385.301998)
		(stroke
			(width 0.07112)
			(type default)
		)
		(layer "In11.Cu")
	)
	(gr_line
		(start 345.425268 -422.516046)
		(end 344.777314 -422.78427)
		(stroke
			(width 0.07112)
			(type default)
		)
		(layer "In11.Cu")
	)
	(gr_line
		(start 345.426538 -384.601466)
		(end 345.426284 -384.601466)
		(stroke
			(width 0.07112)
			(type default)
		)
		(layer "In11.Cu")
	)
	(gr_line
		(start 345.458796 -422.956228)
		(end 345.064334 -423.119296)
		(stroke
			(width 0.07112)
			(type default)
		)
		(layer "In11.Cu")
	)
	(gr_line
		(start 345.476068 -393.842494)
		(end 345.476068 -393.716764)
		(stroke
			(width 0.07112)
			(type default)
		)
		(layer "In11.Cu")
	)
	(gr_line
		(start 345.507564 -431.430938)
		(end 345.649804 -431.573178)
		(stroke
			(width 0.07112)
			(type default)
		)
		(layer "In11.Cu")
	)
	(gr_line
		(start 345.507564 -431.148998)
		(end 345.649804 -431.006758)
		(stroke
			(width 0.07112)
			(type default)
		)
		(layer "In11.Cu")
	)
	(gr_line
		(start 345.52636 -378.230892)
		(end 345.52636 -378.230638)
		(stroke
			(width 0.07112)
			(type default)
		)
		(layer "In11.Cu")
	)
	(gr_line
		(start 345.532202 -422.778174)
		(end 345.458796 -422.956228)
		(stroke
			(width 0.07112)
			(type default)
		)
		(layer "In11.Cu")
	)
	(gr_line
		(start 345.562936 -387.56844)
		(end 345.596464 -386.885434)
		(stroke
			(width 0.07112)
			(type default)
		)
		(layer "In11.Cu")
	)
	(gr_line
		(start 345.592146 -296.46372)
		(end 345.592146 -296.435272)
		(stroke
			(width 0.05715)
			(type default)
		)
		(layer "In11.Cu")
	)
	(gr_line
		(start 345.592146 -296.435272)
		(end 345.546426 -296.389552)
		(stroke
			(width 0.05715)
			(type default)
		)
		(layer "In11.Cu")
	)
	(gr_line
		(start 345.596718 -386.883148)
		(end 345.59748 -386.865622)
		(stroke
			(width 0.07112)
			(type default)
		)
		(layer "In11.Cu")
	)
	(gr_line
		(start 345.618308 -386.44195)
		(end 345.652598 -385.741672)
		(stroke
			(width 0.07112)
			(type default)
		)
		(layer "In11.Cu")
	)
	(gr_line
		(start 345.632024 -280.239978)
		(end 345.631008 -280.239216)
		(stroke
			(width 0.05715)
			(type default)
		)
		(layer "In11.Cu")
	)
	(gr_line
		(start 345.632278 -279.272238)
		(end 345.63558 -279.270206)
		(stroke
			(width 0.05715)
			(type default)
		)
		(layer "In11.Cu")
	)
	(gr_line
		(start 345.632278 -277.652226)
		(end 345.63558 -277.650194)
		(stroke
			(width 0.05715)
			(type default)
		)
		(layer "In11.Cu")
	)
	(gr_line
		(start 345.634564 -280.241502)
		(end 345.632024 -280.239978)
		(stroke
			(width 0.05715)
			(type default)
		)
		(layer "In11.Cu")
	)
	(gr_line
		(start 345.63558 -280.24201)
		(end 345.634564 -280.241502)
		(stroke
			(width 0.05715)
			(type default)
		)
		(layer "In11.Cu")
	)
	(gr_line
		(start 345.63558 -279.270206)
		(end 345.637104 -279.26919)
		(stroke
			(width 0.05715)
			(type default)
		)
		(layer "In11.Cu")
	)
	(gr_line
		(start 345.63558 -277.650194)
		(end 345.637104 -277.649178)
		(stroke
			(width 0.05715)
			(type default)
		)
		(layer "In11.Cu")
	)
	(gr_line
		(start 345.637104 -280.243026)
		(end 345.63558 -280.24201)
		(stroke
			(width 0.05715)
			(type default)
		)
		(layer "In11.Cu")
	)
	(gr_line
		(start 345.637104 -279.26919)
		(end 345.63812 -279.268682)
		(stroke
			(width 0.05715)
			(type default)
		)
		(layer "In11.Cu")
	)
	(gr_line
		(start 345.637104 -277.649178)
		(end 345.63812 -277.64867)
		(stroke
			(width 0.05715)
			(type default)
		)
		(layer "In11.Cu")
	)
	(gr_line
		(start 345.63812 -280.243534)
		(end 345.637104 -280.243026)
		(stroke
			(width 0.05715)
			(type default)
		)
		(layer "In11.Cu")
	)
	(gr_line
		(start 345.63812 -279.268682)
		(end 345.638882 -279.268174)
		(stroke
			(width 0.05715)
			(type default)
		)
		(layer "In11.Cu")
	)
	(gr_line
		(start 345.63812 -277.64867)
		(end 345.638882 -277.648162)
		(stroke
			(width 0.05715)
			(type default)
		)
		(layer "In11.Cu")
	)
	(gr_line
		(start 345.649804 -431.573178)
		(end 345.649804 -431.889916)
		(stroke
			(width 0.07112)
			(type default)
		)
		(layer "In11.Cu")
	)
	(gr_line
		(start 345.649804 -431.006758)
		(end 345.649804 -430.689766)
		(stroke
			(width 0.07112)
			(type default)
		)
		(layer "In11.Cu")
	)
	(gr_line
		(start 345.67368 -385.315714)
		(end 345.70797 -384.615436)
		(stroke
			(width 0.07112)
			(type default)
		)
		(layer "In11.Cu")
	)
	(gr_line
		(start 345.727528 -280.074878)
		(end 345.726512 -280.07437)
		(stroke
			(width 0.05715)
			(type default)
		)
		(layer "In11.Cu")
	)
	(gr_line
		(start 345.72829 -280.075386)
		(end 345.727528 -280.074878)
		(stroke
			(width 0.05715)
			(type default)
		)
		(layer "In11.Cu")
	)
	(gr_line
		(start 345.729814 -280.076148)
		(end 345.72829 -280.075386)
		(stroke
			(width 0.05715)
			(type default)
		)
		(layer "In11.Cu")
	)
	(gr_line
		(start 345.730576 -280.076656)
		(end 345.729814 -280.076148)
		(stroke
			(width 0.05715)
			(type default)
		)
		(layer "In11.Cu")
	)
	(gr_line
		(start 345.731592 -279.435052)
		(end 345.73337 -279.434036)
		(stroke
			(width 0.05715)
			(type default)
		)
		(layer "In11.Cu")
	)
	(gr_line
		(start 345.731592 -277.81504)
		(end 345.73337 -277.814024)
		(stroke
			(width 0.05715)
			(type default)
		)
		(layer "In11.Cu")
	)
	(gr_line
		(start 345.73337 -280.07818)
		(end 345.732862 -280.077926)
		(stroke
			(width 0.05715)
			(type default)
		)
		(layer "In11.Cu")
	)
	(gr_line
		(start 345.73337 -279.434036)
		(end 345.734132 -279.433528)
		(stroke
			(width 0.05715)
			(type default)
		)
		(layer "In11.Cu")
	)
	(gr_line
		(start 345.73337 -277.814024)
		(end 345.734132 -277.813516)
		(stroke
			(width 0.05715)
			(type default)
		)
		(layer "In11.Cu")
	)
	(gr_line
		(start 345.733878 -280.078434)
		(end 345.73337 -280.07818)
		(stroke
			(width 0.05715)
			(type default)
		)
		(layer "In11.Cu")
	)
	(gr_line
		(start 345.734132 -279.433528)
		(end 345.735148 -279.43302)
		(stroke
			(width 0.05715)
			(type default)
		)
		(layer "In11.Cu")
	)
	(gr_line
		(start 345.734132 -277.813516)
		(end 345.735148 -277.813008)
		(stroke
			(width 0.05715)
			(type default)
		)
		(layer "In11.Cu")
	)
	(gr_line
		(start 345.76131 -378.074428)
		(end 345.760294 -378.073158)
		(stroke
			(width 0.07112)
			(type default)
		)
		(layer "In11.Cu")
	)
	(gr_line
		(start 345.765628 -280.096976)
		(end 345.764866 -280.096468)
		(stroke
			(width 0.05715)
			(type default)
		)
		(layer "In11.Cu")
	)
	(gr_line
		(start 345.76639 -280.097484)
		(end 345.765628 -280.096976)
		(stroke
			(width 0.05715)
			(type default)
		)
		(layer "In11.Cu")
	)
	(gr_line
		(start 345.773248 -280.101548)
		(end 345.76639 -280.097484)
		(stroke
			(width 0.05715)
			(type default)
		)
		(layer "In11.Cu")
	)
	(gr_arc
		(start 345.781122 -280.107136)
		(mid 345.777197 -280.104325)
		(end 345.773248 -280.101548)
		(stroke
			(width 0.05715)
			(type default)
		)
		(layer "In11.Cu")
	)
	(gr_line
		(start 345.825826 -295.192958)
		(end 345.825826 -295.191942)
		(stroke
			(width 0.05715)
			(type default)
		)
		(layer "In11.Cu")
	)
	(gr_arc
		(start 345.850718 -378.579126)
		(mid 345.85021 -378.578745)
		(end 345.849702 -378.578364)
		(stroke
			(width 0.07112)
			(type default)
		)
		(layer "In11.Cu")
	)
	(gr_line
		(start 345.91879 -393.69238)
		(end 346.272104 -393.787376)
		(stroke
			(width 0.07112)
			(type default)
		)
		(layer "In11.Cu")
	)
	(gr_arc
		(start 346.069158 -286.581342)
		(mid 346.064442 -286.584619)
		(end 346.05976 -286.587946)
		(stroke
			(width 0.05715)
			(type default)
		)
		(layer "In11.Cu")
	)
	(gr_line
		(start 346.069158 -286.581342)
		(end 346.07119 -286.579818)
		(stroke
			(width 0.05715)
			(type default)
		)
		(layer "In11.Cu")
	)
	(gr_line
		(start 346.07119 -286.579818)
		(end 346.076016 -286.577024)
		(stroke
			(width 0.05715)
			(type default)
		)
		(layer "In11.Cu")
	)
	(gr_line
		(start 346.106496 -422.68775)
		(end 345.928696 -422.61409)
		(stroke
			(width 0.07112)
			(type default)
		)
		(layer "In11.Cu")
	)
	(gr_line
		(start 346.203524 -286.723836)
		(end 346.204032 -286.723582)
		(stroke
			(width 0.05715)
			(type default)
		)
		(layer "In11.Cu")
	)
	(gr_line
		(start 346.219018 -278.136096)
		(end 345.921076 -278.136096)
		(stroke
			(width 0.05715)
			(type default)
		)
		(layer "In11.Cu")
	)
	(gr_line
		(start 346.219018 -276.516084)
		(end 345.921076 -276.516084)
		(stroke
			(width 0.05715)
			(type default)
		)
		(layer "In11.Cu")
	)
	(gr_line
		(start 346.219018 -274.896072)
		(end 345.921076 -274.896072)
		(stroke
			(width 0.05715)
			(type default)
		)
		(layer "In11.Cu")
	)
	(gr_line
		(start 346.24899 -390.22782)
		(end 346.24899 -389.8011)
		(stroke
			(width 0.07112)
			(type default)
		)
		(layer "In11.Cu")
	)
	(gr_line
		(start 346.24899 -389.8011)
		(end 346.38488 -389.66521)
		(stroke
			(width 0.07112)
			(type default)
		)
		(layer "In11.Cu")
	)
	(gr_line
		(start 346.24899 -389.10006)
		(end 346.24899 -388.67334)
		(stroke
			(width 0.07112)
			(type default)
		)
		(layer "In11.Cu")
	)
	(gr_line
		(start 346.24899 -388.67334)
		(end 346.38488 -388.53745)
		(stroke
			(width 0.07112)
			(type default)
		)
		(layer "In11.Cu")
	)
	(gr_line
		(start 346.24899 -387.9723)
		(end 346.24899 -387.54558)
		(stroke
			(width 0.07112)
			(type default)
		)
		(layer "In11.Cu")
	)
	(gr_line
		(start 346.24899 -387.54558)
		(end 346.38488 -387.40969)
		(stroke
			(width 0.07112)
			(type default)
		)
		(layer "In11.Cu")
	)
	(gr_line
		(start 346.25026 -296.46372)
		(end 346.25026 -296.435272)
		(stroke
			(width 0.05715)
			(type default)
		)
		(layer "In11.Cu")
	)
	(gr_line
		(start 346.25026 -296.435272)
		(end 346.29598 -296.389552)
		(stroke
			(width 0.05715)
			(type default)
		)
		(layer "In11.Cu")
	)
	(gr_line
		(start 346.272104 -393.787376)
		(end 346.272612 -393.786868)
		(stroke
			(width 0.07112)
			(type default)
		)
		(layer "In11.Cu")
	)
	(gr_line
		(start 346.28836 -278.205438)
		(end 346.219018 -278.136096)
		(stroke
			(width 0.05715)
			(type default)
		)
		(layer "In11.Cu")
	)
	(gr_line
		(start 346.28836 -276.585426)
		(end 346.219018 -276.516084)
		(stroke
			(width 0.05715)
			(type default)
		)
		(layer "In11.Cu")
	)
	(gr_line
		(start 346.301822 -274.978876)
		(end 346.219018 -274.896072)
		(stroke
			(width 0.05715)
			(type default)
		)
		(layer "In11.Cu")
	)
	(gr_arc
		(start 346.301822 -274.978876)
		(mid 346.303614 -274.990198)
		(end 346.305632 -275.001482)
		(stroke
			(width 0.05715)
			(type default)
		)
		(layer "In11.Cu")
	)
	(gr_line
		(start 346.31884 -394.385292)
		(end 346.413582 -394.031724)
		(stroke
			(width 0.07112)
			(type default)
		)
		(layer "In11.Cu")
	)
	(gr_line
		(start 346.38488 -390.36371)
		(end 346.24899 -390.22782)
		(stroke
			(width 0.07112)
			(type default)
		)
		(layer "In11.Cu")
	)
	(gr_line
		(start 346.38488 -389.23595)
		(end 346.24899 -389.10006)
		(stroke
			(width 0.07112)
			(type default)
		)
		(layer "In11.Cu")
	)
	(gr_line
		(start 346.38488 -388.10819)
		(end 346.24899 -387.9723)
		(stroke
			(width 0.07112)
			(type default)
		)
		(layer "In11.Cu")
	)
	(gr_line
		(start 346.46743 -422.084754)
		(end 345.819222 -422.352978)
		(stroke
			(width 0.07112)
			(type default)
		)
		(layer "In11.Cu")
	)
	(gr_arc
		(start 346.476574 -278.24176)
		(mid 346.478596 -278.23035)
		(end 346.480384 -278.2189)
		(stroke
			(width 0.05715)
			(type default)
		)
		(layer "In11.Cu")
	)
	(gr_arc
		(start 346.476574 -276.621748)
		(mid 346.478596 -276.610338)
		(end 346.480384 -276.598888)
		(stroke
			(width 0.05715)
			(type default)
		)
		(layer "In11.Cu")
	)
	(gr_line
		(start 346.480384 -278.2189)
		(end 346.563188 -278.136096)
		(stroke
			(width 0.05715)
			(type default)
		)
		(layer "In11.Cu")
	)
	(gr_line
		(start 346.480384 -276.598888)
		(end 346.563188 -276.516084)
		(stroke
			(width 0.05715)
			(type default)
		)
		(layer "In11.Cu")
	)
	(gr_line
		(start 346.493846 -274.965414)
		(end 346.563188 -274.896072)
		(stroke
			(width 0.05715)
			(type default)
		)
		(layer "In11.Cu")
	)
	(gr_line
		(start 346.494608 -378.513848)
		(end 346.493846 -378.513848)
		(stroke
			(width 0.07112)
			(type default)
		)
		(layer "In11.Cu")
	)
	(gr_line
		(start 346.494608 -378.513848)
		(end 346.495878 -378.513848)
		(stroke
			(width 0.07112)
			(type default)
		)
		(layer "In11.Cu")
	)
	(gr_line
		(start 346.500958 -422.524682)
		(end 346.106496 -422.68775)
		(stroke
			(width 0.07112)
			(type default)
		)
		(layer "In11.Cu")
	)
	(gr_arc
		(start 346.531184 -280.215086)
		(mid 346.535109 -280.217897)
		(end 346.539058 -280.220674)
		(stroke
			(width 0.05715)
			(type default)
		)
		(layer "In11.Cu")
	)
	(gr_line
		(start 346.5322 -296.46372)
		(end 346.5322 -296.435272)
		(stroke
			(width 0.05715)
			(type default)
		)
		(layer "In11.Cu")
	)
	(gr_line
		(start 346.5322 -296.435272)
		(end 346.48648 -296.389552)
		(stroke
			(width 0.05715)
			(type default)
		)
		(layer "In11.Cu")
	)
	(gr_line
		(start 346.535248 -393.961112)
		(end 346.58808 -393.930632)
		(stroke
			(width 0.07112)
			(type default)
		)
		(layer "In11.Cu")
	)
	(gr_arc
		(start 346.53982 -280.221182)
		(mid 346.539439 -280.220928)
		(end 346.539058 -280.220674)
		(stroke
			(width 0.05715)
			(type default)
		)
		(layer "In11.Cu")
	)
	(gr_line
		(start 346.549218 -280.226516)
		(end 346.53982 -280.221182)
		(stroke
			(width 0.05715)
			(type default)
		)
		(layer "In11.Cu")
	)
	(gr_line
		(start 346.563188 -278.136096)
		(end 346.86113 -278.136096)
		(stroke
			(width 0.05715)
			(type default)
		)
		(layer "In11.Cu")
	)
	(gr_line
		(start 346.563188 -276.516084)
		(end 346.86113 -276.516084)
		(stroke
			(width 0.05715)
			(type default)
		)
		(layer "In11.Cu")
	)
	(gr_line
		(start 346.563188 -274.896072)
		(end 346.86113 -274.896072)
		(stroke
			(width 0.05715)
			(type default)
		)
		(layer "In11.Cu")
	)
	(gr_line
		(start 346.574364 -422.346882)
		(end 346.500958 -422.524682)
		(stroke
			(width 0.07112)
			(type default)
		)
		(layer "In11.Cu")
	)
	(gr_line
		(start 346.58808 -393.930632)
		(end 346.676218 -393.842494)
		(stroke
			(width 0.07112)
			(type default)
		)
		(layer "In11.Cu")
	)
	(gr_line
		(start 346.589604 -280.249884)
		(end 346.587318 -280.248614)
		(stroke
			(width 0.05715)
			(type default)
		)
		(layer "In11.Cu")
	)
	(gr_line
		(start 346.66809 -390.36498)
		(end 346.66809 -389.66394)
		(stroke
			(width 0.07112)
			(type default)
		)
		(layer "In11.Cu")
	)
	(gr_line
		(start 346.66809 -389.23722)
		(end 346.66809 -388.53618)
		(stroke
			(width 0.07112)
			(type default)
		)
		(layer "In11.Cu")
	)
	(gr_line
		(start 346.66809 -388.10946)
		(end 346.66809 -387.40842)
		(stroke
			(width 0.07112)
			(type default)
		)
		(layer "In11.Cu")
	)
	(gr_line
		(start 346.676218 -393.842494)
		(end 346.676218 -393.716764)
		(stroke
			(width 0.07112)
			(type default)
		)
		(layer "In11.Cu")
	)
	(gr_line
		(start 346.679266 -420.952168)
		(end 346.970096 -421.242998)
		(stroke
			(width 0.07112)
			(type default)
		)
		(layer "In11.Cu")
	)
	(gr_arc
		(start 346.765626 -275.707094)
		(mid 346.765743 -275.710523)
		(end 346.76588 -275.713952)
		(stroke
			(width 0.05715)
			(type default)
		)
		(layer "In11.Cu")
	)
	(gr_arc
		(start 346.76588 -295.139364)
		(mid 346.76587 -295.142666)
		(end 346.76588 -295.145968)
		(stroke
			(width 0.05715)
			(type default)
		)
		(layer "In11.Cu")
	)
	(gr_line
		(start 346.76588 -288.672524)
		(end 346.76588 -288.66592)
		(stroke
			(width 0.05715)
			(type default)
		)
		(layer "In11.Cu")
	)
	(gr_line
		(start 346.809568 -421.943022)
		(end 346.46743 -422.084754)
		(stroke
			(width 0.07112)
			(type default)
		)
		(layer "In11.Cu")
	)
	(gr_line
		(start 346.917518 -422.203626)
		(end 346.575126 -422.345104)
		(stroke
			(width 0.07112)
			(type default)
		)
		(layer "In11.Cu")
	)
	(gr_line
		(start 346.95638 -275.695918)
		(end 346.95638 -275.69795)
		(stroke
			(width 0.05715)
			(type default)
		)
		(layer "In11.Cu")
	)
	(gr_arc
		(start 347.011752 -281.719782)
		(mid 347.004088 -281.725054)
		(end 346.996512 -281.73045)
		(stroke
			(width 0.05715)
			(type default)
		)
		(layer "In11.Cu")
	)
	(gr_line
		(start 347.011752 -281.719782)
		(end 347.013276 -281.718766)
		(stroke
			(width 0.05715)
			(type default)
		)
		(layer "In11.Cu")
	)
	(gr_line
		(start 347.013276 -281.718766)
		(end 347.01734 -281.71648)
		(stroke
			(width 0.05715)
			(type default)
		)
		(layer "In11.Cu")
	)
	(gr_line
		(start 347.039184 -276.187916)
		(end 347.038676 -276.187662)
		(stroke
			(width 0.05715)
			(type default)
		)
		(layer "In11.Cu")
	)
	(gr_line
		(start 347.042232 -276.190202)
		(end 347.040708 -276.189186)
		(stroke
			(width 0.05715)
			(type default)
		)
		(layer "In11.Cu")
	)
	(gr_line
		(start 347.046296 -281.052778)
		(end 347.045026 -281.052016)
		(stroke
			(width 0.05715)
			(type default)
		)
		(layer "In11.Cu")
	)
	(gr_line
		(start 347.048074 -294.658542)
		(end 347.048582 -294.658288)
		(stroke
			(width 0.05715)
			(type default)
		)
		(layer "In11.Cu")
	)
	(gr_line
		(start 347.048074 -276.193504)
		(end 347.042232 -276.190202)
		(stroke
			(width 0.05715)
			(type default)
		)
		(layer "In11.Cu")
	)
	(gr_line
		(start 347.048328 -293.038276)
		(end 347.048836 -293.038022)
		(stroke
			(width 0.05715)
			(type default)
		)
		(layer "In11.Cu")
	)
	(gr_line
		(start 347.048328 -291.418264)
		(end 347.048836 -291.41801)
		(stroke
			(width 0.05715)
			(type default)
		)
		(layer "In11.Cu")
	)
	(gr_line
		(start 347.048328 -289.798252)
		(end 347.048836 -289.797998)
		(stroke
			(width 0.05715)
			(type default)
		)
		(layer "In11.Cu")
	)
	(gr_line
		(start 347.048328 -284.93847)
		(end 347.048836 -284.938216)
		(stroke
			(width 0.05715)
			(type default)
		)
		(layer "In11.Cu")
	)
	(gr_line
		(start 347.048328 -283.318458)
		(end 347.048836 -283.318204)
		(stroke
			(width 0.05715)
			(type default)
		)
		(layer "In11.Cu")
	)
	(gr_line
		(start 347.048328 -281.698446)
		(end 347.048836 -281.698192)
		(stroke
			(width 0.05715)
			(type default)
		)
		(layer "In11.Cu")
	)
	(gr_line
		(start 347.048328 -278.458422)
		(end 347.048836 -278.458168)
		(stroke
			(width 0.05715)
			(type default)
		)
		(layer "In11.Cu")
	)
	(gr_line
		(start 347.048328 -276.83841)
		(end 347.048836 -276.838156)
		(stroke
			(width 0.05715)
			(type default)
		)
		(layer "In11.Cu")
	)
	(gr_line
		(start 347.048836 -294.01389)
		(end 347.048074 -294.013382)
		(stroke
			(width 0.05715)
			(type default)
		)
		(layer "In11.Cu")
	)
	(gr_line
		(start 347.048836 -293.038022)
		(end 347.050106 -293.03726)
		(stroke
			(width 0.05715)
			(type default)
		)
		(layer "In11.Cu")
	)
	(gr_line
		(start 347.048836 -292.393878)
		(end 347.048074 -292.39337)
		(stroke
			(width 0.05715)
			(type default)
		)
		(layer "In11.Cu")
	)
	(gr_line
		(start 347.048836 -291.41801)
		(end 347.050106 -291.417248)
		(stroke
			(width 0.05715)
			(type default)
		)
		(layer "In11.Cu")
	)
	(gr_line
		(start 347.048836 -290.773866)
		(end 347.048074 -290.773358)
		(stroke
			(width 0.05715)
			(type default)
		)
		(layer "In11.Cu")
	)
	(gr_line
		(start 347.048836 -289.797998)
		(end 347.050106 -289.797236)
		(stroke
			(width 0.05715)
			(type default)
		)
		(layer "In11.Cu")
	)
	(gr_line
		(start 347.048836 -289.153854)
		(end 347.048074 -289.153346)
		(stroke
			(width 0.05715)
			(type default)
		)
		(layer "In11.Cu")
	)
	(gr_line
		(start 347.048836 -285.914084)
		(end 347.048074 -285.913576)
		(stroke
			(width 0.05715)
			(type default)
		)
		(layer "In11.Cu")
	)
	(gr_line
		(start 347.048836 -284.938216)
		(end 347.050106 -284.937454)
		(stroke
			(width 0.05715)
			(type default)
		)
		(layer "In11.Cu")
	)
	(gr_line
		(start 347.048836 -284.294072)
		(end 347.048074 -284.293564)
		(stroke
			(width 0.05715)
			(type default)
		)
		(layer "In11.Cu")
	)
	(gr_line
		(start 347.048836 -283.318204)
		(end 347.050106 -283.317442)
		(stroke
			(width 0.05715)
			(type default)
		)
		(layer "In11.Cu")
	)
	(gr_line
		(start 347.048836 -282.67406)
		(end 347.048074 -282.673552)
		(stroke
			(width 0.05715)
			(type default)
		)
		(layer "In11.Cu")
	)
	(gr_line
		(start 347.048836 -281.698192)
		(end 347.050106 -281.69743)
		(stroke
			(width 0.05715)
			(type default)
		)
		(layer "In11.Cu")
	)
	(gr_line
		(start 347.048836 -281.054302)
		(end 347.046296 -281.052778)
		(stroke
			(width 0.05715)
			(type default)
		)
		(layer "In11.Cu")
	)
	(gr_line
		(start 347.048836 -278.458168)
		(end 347.050106 -278.457406)
		(stroke
			(width 0.05715)
			(type default)
		)
		(layer "In11.Cu")
	)
	(gr_line
		(start 347.048836 -277.814024)
		(end 347.048074 -277.813516)
		(stroke
			(width 0.05715)
			(type default)
		)
		(layer "In11.Cu")
	)
	(gr_line
		(start 347.048836 -276.838156)
		(end 347.050106 -276.837394)
		(stroke
			(width 0.05715)
			(type default)
		)
		(layer "In11.Cu")
	)
	(gr_line
		(start 347.048836 -276.194012)
		(end 347.048074 -276.193504)
		(stroke
			(width 0.05715)
			(type default)
		)
		(layer "In11.Cu")
	)
	(gr_line
		(start 347.050106 -277.814786)
		(end 347.048836 -277.814024)
		(stroke
			(width 0.05715)
			(type default)
		)
		(layer "In11.Cu")
	)
	(gr_line
		(start 347.050106 -276.194774)
		(end 347.048836 -276.194012)
		(stroke
			(width 0.05715)
			(type default)
		)
		(layer "In11.Cu")
	)
	(gr_line
		(start 347.118686 -393.69238)
		(end 347.472 -393.787376)
		(stroke
			(width 0.07112)
			(type default)
		)
		(layer "In11.Cu")
	)
	(gr_line
		(start 347.130116 -280.880566)
		(end 347.128592 -280.879804)
		(stroke
			(width 0.05715)
			(type default)
		)
		(layer "In11.Cu")
	)
	(gr_line
		(start 347.143324 -281.864054)
		(end 347.144086 -281.863546)
		(stroke
			(width 0.05715)
			(type default)
		)
		(layer "In11.Cu")
	)
	(gr_line
		(start 347.143324 -278.62403)
		(end 347.144086 -278.623522)
		(stroke
			(width 0.05715)
			(type default)
		)
		(layer "In11.Cu")
	)
	(gr_line
		(start 347.144086 -293.203376)
		(end 347.145102 -293.202868)
		(stroke
			(width 0.05715)
			(type default)
		)
		(layer "In11.Cu")
	)
	(gr_line
		(start 347.144086 -291.583364)
		(end 347.145102 -291.582856)
		(stroke
			(width 0.05715)
			(type default)
		)
		(layer "In11.Cu")
	)
	(gr_line
		(start 347.144086 -289.963352)
		(end 347.145102 -289.962844)
		(stroke
			(width 0.05715)
			(type default)
		)
		(layer "In11.Cu")
	)
	(gr_line
		(start 347.144086 -285.10357)
		(end 347.145102 -285.103062)
		(stroke
			(width 0.05715)
			(type default)
		)
		(layer "In11.Cu")
	)
	(gr_line
		(start 347.144086 -283.483558)
		(end 347.145102 -283.48305)
		(stroke
			(width 0.05715)
			(type default)
		)
		(layer "In11.Cu")
	)
	(gr_line
		(start 347.144086 -281.863546)
		(end 347.145102 -281.863038)
		(stroke
			(width 0.05715)
			(type default)
		)
		(layer "In11.Cu")
	)
	(gr_line
		(start 347.144086 -278.623522)
		(end 347.145102 -278.623014)
		(stroke
			(width 0.05715)
			(type default)
		)
		(layer "In11.Cu")
	)
	(gr_line
		(start 347.144086 -277.00351)
		(end 347.145102 -277.003002)
		(stroke
			(width 0.05715)
			(type default)
		)
		(layer "In11.Cu")
	)
	(gr_line
		(start 347.144086 -276.028658)
		(end 347.143324 -276.02815)
		(stroke
			(width 0.05715)
			(type default)
		)
		(layer "In11.Cu")
	)
	(gr_line
		(start 347.145102 -277.649178)
		(end 347.144086 -277.64867)
		(stroke
			(width 0.05715)
			(type default)
		)
		(layer "In11.Cu")
	)
	(gr_line
		(start 347.145102 -276.029166)
		(end 347.144086 -276.028658)
		(stroke
			(width 0.05715)
			(type default)
		)
		(layer "In11.Cu")
	)
	(gr_line
		(start 347.149166 -293.85133)
		(end 347.148404 -293.850822)
		(stroke
			(width 0.05715)
			(type default)
		)
		(layer "In11.Cu")
	)
	(gr_line
		(start 347.149166 -292.231318)
		(end 347.148404 -292.23081)
		(stroke
			(width 0.05715)
			(type default)
		)
		(layer "In11.Cu")
	)
	(gr_line
		(start 347.149166 -290.611306)
		(end 347.148404 -290.610798)
		(stroke
			(width 0.05715)
			(type default)
		)
		(layer "In11.Cu")
	)
	(gr_line
		(start 347.149166 -288.991294)
		(end 347.148404 -288.990786)
		(stroke
			(width 0.05715)
			(type default)
		)
		(layer "In11.Cu")
	)
	(gr_line
		(start 347.149166 -285.751524)
		(end 347.148404 -285.751016)
		(stroke
			(width 0.05715)
			(type default)
		)
		(layer "In11.Cu")
	)
	(gr_line
		(start 347.149166 -284.131512)
		(end 347.148404 -284.131004)
		(stroke
			(width 0.05715)
			(type default)
		)
		(layer "In11.Cu")
	)
	(gr_line
		(start 347.149166 -282.5115)
		(end 347.148404 -282.510992)
		(stroke
			(width 0.05715)
			(type default)
		)
		(layer "In11.Cu")
	)
	(gr_line
		(start 347.175582 -293.866824)
		(end 347.17482 -293.866316)
		(stroke
			(width 0.05715)
			(type default)
		)
		(layer "In11.Cu")
	)
	(gr_line
		(start 347.175582 -292.246812)
		(end 347.17482 -292.246304)
		(stroke
			(width 0.05715)
			(type default)
		)
		(layer "In11.Cu")
	)
	(gr_line
		(start 347.175582 -290.6268)
		(end 347.17482 -290.626292)
		(stroke
			(width 0.05715)
			(type default)
		)
		(layer "In11.Cu")
	)
	(gr_line
		(start 347.175582 -289.006788)
		(end 347.17482 -289.00628)
		(stroke
			(width 0.05715)
			(type default)
		)
		(layer "In11.Cu")
	)
	(gr_line
		(start 347.175582 -285.767018)
		(end 347.17482 -285.76651)
		(stroke
			(width 0.05715)
			(type default)
		)
		(layer "In11.Cu")
	)
	(gr_line
		(start 347.175582 -284.147006)
		(end 347.17482 -284.146498)
		(stroke
			(width 0.05715)
			(type default)
		)
		(layer "In11.Cu")
	)
	(gr_line
		(start 347.175582 -282.526994)
		(end 347.17482 -282.526486)
		(stroke
			(width 0.05715)
			(type default)
		)
		(layer "In11.Cu")
	)
	(gr_line
		(start 347.175582 -280.906982)
		(end 347.174058 -280.905966)
		(stroke
			(width 0.05715)
			(type default)
		)
		(layer "In11.Cu")
	)
	(gr_line
		(start 347.176344 -293.867332)
		(end 347.175582 -293.866824)
		(stroke
			(width 0.05715)
			(type default)
		)
		(layer "In11.Cu")
	)
	(gr_line
		(start 347.176344 -292.24732)
		(end 347.175582 -292.246812)
		(stroke
			(width 0.05715)
			(type default)
		)
		(layer "In11.Cu")
	)
	(gr_line
		(start 347.176344 -290.627308)
		(end 347.175582 -290.6268)
		(stroke
			(width 0.05715)
			(type default)
		)
		(layer "In11.Cu")
	)
	(gr_line
		(start 347.176344 -289.007296)
		(end 347.175582 -289.006788)
		(stroke
			(width 0.05715)
			(type default)
		)
		(layer "In11.Cu")
	)
	(gr_line
		(start 347.176344 -285.767526)
		(end 347.175582 -285.767018)
		(stroke
			(width 0.05715)
			(type default)
		)
		(layer "In11.Cu")
	)
	(gr_line
		(start 347.176344 -284.147514)
		(end 347.175582 -284.147006)
		(stroke
			(width 0.05715)
			(type default)
		)
		(layer "In11.Cu")
	)
	(gr_line
		(start 347.176344 -282.527502)
		(end 347.175582 -282.526994)
		(stroke
			(width 0.05715)
			(type default)
		)
		(layer "In11.Cu")
	)
	(gr_line
		(start 347.176344 -280.90749)
		(end 347.175582 -280.906982)
		(stroke
			(width 0.05715)
			(type default)
		)
		(layer "In11.Cu")
	)
	(gr_line
		(start 347.183202 -293.871396)
		(end 347.176344 -293.867332)
		(stroke
			(width 0.05715)
			(type default)
		)
		(layer "In11.Cu")
	)
	(gr_line
		(start 347.183202 -292.251384)
		(end 347.176344 -292.24732)
		(stroke
			(width 0.05715)
			(type default)
		)
		(layer "In11.Cu")
	)
	(gr_line
		(start 347.183202 -290.631372)
		(end 347.176344 -290.627308)
		(stroke
			(width 0.05715)
			(type default)
		)
		(layer "In11.Cu")
	)
	(gr_line
		(start 347.183202 -289.01136)
		(end 347.176344 -289.007296)
		(stroke
			(width 0.05715)
			(type default)
		)
		(layer "In11.Cu")
	)
	(gr_line
		(start 347.183202 -285.77159)
		(end 347.176344 -285.767526)
		(stroke
			(width 0.05715)
			(type default)
		)
		(layer "In11.Cu")
	)
	(gr_line
		(start 347.183202 -284.151578)
		(end 347.176344 -284.147514)
		(stroke
			(width 0.05715)
			(type default)
		)
		(layer "In11.Cu")
	)
	(gr_line
		(start 347.183202 -282.531566)
		(end 347.176344 -282.527502)
		(stroke
			(width 0.05715)
			(type default)
		)
		(layer "In11.Cu")
	)
	(gr_line
		(start 347.183202 -280.911554)
		(end 347.176344 -280.90749)
		(stroke
			(width 0.05715)
			(type default)
		)
		(layer "In11.Cu")
	)
	(gr_line
		(start 347.190568 -296.46372)
		(end 347.190568 -296.435272)
		(stroke
			(width 0.05715)
			(type default)
		)
		(layer "In11.Cu")
	)
	(gr_line
		(start 347.190568 -296.435272)
		(end 347.236288 -296.389552)
		(stroke
			(width 0.05715)
			(type default)
		)
		(layer "In11.Cu")
	)
	(gr_arc
		(start 347.191076 -293.876984)
		(mid 347.187151 -293.874173)
		(end 347.183202 -293.871396)
		(stroke
			(width 0.05715)
			(type default)
		)
		(layer "In11.Cu")
	)
	(gr_arc
		(start 347.191076 -292.256972)
		(mid 347.187151 -292.254161)
		(end 347.183202 -292.251384)
		(stroke
			(width 0.05715)
			(type default)
		)
		(layer "In11.Cu")
	)
	(gr_arc
		(start 347.191076 -290.63696)
		(mid 347.187151 -290.634149)
		(end 347.183202 -290.631372)
		(stroke
			(width 0.05715)
			(type default)
		)
		(layer "In11.Cu")
	)
	(gr_arc
		(start 347.191076 -289.016948)
		(mid 347.187151 -289.014137)
		(end 347.183202 -289.01136)
		(stroke
			(width 0.05715)
			(type default)
		)
		(layer "In11.Cu")
	)
	(gr_arc
		(start 347.191076 -285.777178)
		(mid 347.187151 -285.774367)
		(end 347.183202 -285.77159)
		(stroke
			(width 0.05715)
			(type default)
		)
		(layer "In11.Cu")
	)
	(gr_arc
		(start 347.191076 -284.157166)
		(mid 347.187151 -284.154355)
		(end 347.183202 -284.151578)
		(stroke
			(width 0.05715)
			(type default)
		)
		(layer "In11.Cu")
	)
	(gr_arc
		(start 347.191076 -282.537154)
		(mid 347.187151 -282.534343)
		(end 347.183202 -282.531566)
		(stroke
			(width 0.05715)
			(type default)
		)
		(layer "In11.Cu")
	)
	(gr_arc
		(start 347.191076 -280.917142)
		(mid 347.187151 -280.914331)
		(end 347.183202 -280.911554)
		(stroke
			(width 0.05715)
			(type default)
		)
		(layer "In11.Cu")
	)
	(gr_line
		(start 347.384116 -423.096182)
		(end 347.384116 -423.096436)
		(stroke
			(width 0.07112)
			(type default)
		)
		(layer "In11.Cu")
	)
	(gr_line
		(start 347.441266 -387.248146)
		(end 347.462094 -386.82168)
		(stroke
			(width 0.07112)
			(type default)
		)
		(layer "In11.Cu")
	)
	(gr_line
		(start 347.462094 -386.82168)
		(end 347.604842 -386.692648)
		(stroke
			(width 0.07112)
			(type default)
		)
		(layer "In11.Cu")
	)
	(gr_line
		(start 347.472 -393.787376)
		(end 347.472508 -393.786868)
		(stroke
			(width 0.07112)
			(type default)
		)
		(layer "In11.Cu")
	)
	(gr_line
		(start 347.472508 -296.46372)
		(end 347.472508 -296.435272)
		(stroke
			(width 0.05715)
			(type default)
		)
		(layer "In11.Cu")
	)
	(gr_line
		(start 347.472508 -296.435272)
		(end 347.426788 -296.389552)
		(stroke
			(width 0.05715)
			(type default)
		)
		(layer "In11.Cu")
	)
	(gr_line
		(start 347.496638 -386.121656)
		(end 347.517466 -385.69519)
		(stroke
			(width 0.07112)
			(type default)
		)
		(layer "In11.Cu")
	)
	(gr_line
		(start 347.517466 -385.69519)
		(end 347.65996 -385.566158)
		(stroke
			(width 0.07112)
			(type default)
		)
		(layer "In11.Cu")
	)
	(gr_line
		(start 347.518736 -394.385292)
		(end 347.613478 -394.031724)
		(stroke
			(width 0.07112)
			(type default)
		)
		(layer "In11.Cu")
	)
	(gr_line
		(start 347.542866 -420.952168)
		(end 347.252036 -421.242998)
		(stroke
			(width 0.07112)
			(type default)
		)
		(layer "In11.Cu")
	)
	(gr_line
		(start 347.55201 -384.995166)
		(end 347.572838 -384.5687)
		(stroke
			(width 0.07112)
			(type default)
		)
		(layer "In11.Cu")
	)
	(gr_line
		(start 347.570552 -387.39064)
		(end 347.441266 -387.248146)
		(stroke
			(width 0.07112)
			(type default)
		)
		(layer "In11.Cu")
	)
	(gr_line
		(start 347.572838 -384.5687)
		(end 347.715332 -384.439668)
		(stroke
			(width 0.07112)
			(type default)
		)
		(layer "In11.Cu")
	)
	(gr_line
		(start 347.606112 -386.691378)
		(end 347.605858 -386.691378)
		(stroke
			(width 0.07112)
			(type default)
		)
		(layer "In11.Cu")
	)
	(gr_line
		(start 347.62567 -386.26415)
		(end 347.496638 -386.121656)
		(stroke
			(width 0.07112)
			(type default)
		)
		(layer "In11.Cu")
	)
	(gr_line
		(start 347.626686 -386.26542)
		(end 347.62694 -386.26542)
		(stroke
			(width 0.07112)
			(type default)
		)
		(layer "In11.Cu")
	)
	(gr_line
		(start 347.65488 -423.44467)
		(end 347.480636 -423.362374)
		(stroke
			(width 0.07112)
			(type default)
		)
		(layer "In11.Cu")
	)
	(gr_line
		(start 347.661484 -385.564888)
		(end 347.66123 -385.564888)
		(stroke
			(width 0.07112)
			(type default)
		)
		(layer "In11.Cu")
	)
	(gr_line
		(start 347.681042 -385.13766)
		(end 347.55201 -384.995166)
		(stroke
			(width 0.07112)
			(type default)
		)
		(layer "In11.Cu")
	)
	(gr_line
		(start 347.682058 -385.13893)
		(end 347.682312 -385.13893)
		(stroke
			(width 0.07112)
			(type default)
		)
		(layer "In11.Cu")
	)
	(gr_line
		(start 347.70568 -295.192958)
		(end 347.70568 -295.191942)
		(stroke
			(width 0.05715)
			(type default)
		)
		(layer "In11.Cu")
	)
	(gr_line
		(start 347.716856 -384.438398)
		(end 347.716602 -384.438398)
		(stroke
			(width 0.07112)
			(type default)
		)
		(layer "In11.Cu")
	)
	(gr_line
		(start 347.735144 -393.961112)
		(end 347.787976 -393.930632)
		(stroke
			(width 0.07112)
			(type default)
		)
		(layer "In11.Cu")
	)
	(gr_line
		(start 347.787976 -393.930632)
		(end 347.876114 -393.842494)
		(stroke
			(width 0.07112)
			(type default)
		)
		(layer "In11.Cu")
	)
	(gr_line
		(start 347.853254 -387.405626)
		(end 347.886782 -386.72262)
		(stroke
			(width 0.07112)
			(type default)
		)
		(layer "In11.Cu")
	)
	(gr_line
		(start 347.876114 -393.842494)
		(end 347.876114 -393.716764)
		(stroke
			(width 0.07112)
			(type default)
		)
		(layer "In11.Cu")
	)
	(gr_line
		(start 347.887036 -386.720334)
		(end 347.887798 -386.702808)
		(stroke
			(width 0.07112)
			(type default)
		)
		(layer "In11.Cu")
	)
	(gr_line
		(start 347.908626 -386.279136)
		(end 347.942916 -385.578604)
		(stroke
			(width 0.07112)
			(type default)
		)
		(layer "In11.Cu")
	)
	(gr_line
		(start 347.963998 -385.152646)
		(end 347.998288 -384.452368)
		(stroke
			(width 0.07112)
			(type default)
		)
		(layer "In11.Cu")
	)
	(gr_line
		(start 347.980762 -285.909258)
		(end 347.979492 -285.908496)
		(stroke
			(width 0.05715)
			(type default)
		)
		(layer "In11.Cu")
	)
	(gr_line
		(start 347.980762 -284.289246)
		(end 347.979492 -284.288484)
		(stroke
			(width 0.05715)
			(type default)
		)
		(layer "In11.Cu")
	)
	(gr_line
		(start 347.980762 -282.669234)
		(end 347.979492 -282.668472)
		(stroke
			(width 0.05715)
			(type default)
		)
		(layer "In11.Cu")
	)
	(gr_line
		(start 347.980762 -281.049222)
		(end 347.979492 -281.04846)
		(stroke
			(width 0.05715)
			(type default)
		)
		(layer "In11.Cu")
	)
	(gr_line
		(start 347.982286 -294.662098)
		(end 347.985588 -294.660066)
		(stroke
			(width 0.05715)
			(type default)
		)
		(layer "In11.Cu")
	)
	(gr_line
		(start 347.982286 -293.042086)
		(end 347.985588 -293.040054)
		(stroke
			(width 0.05715)
			(type default)
		)
		(layer "In11.Cu")
	)
	(gr_line
		(start 347.982286 -291.422074)
		(end 347.985588 -291.420042)
		(stroke
			(width 0.05715)
			(type default)
		)
		(layer "In11.Cu")
	)
	(gr_line
		(start 347.982286 -289.802062)
		(end 347.985588 -289.80003)
		(stroke
			(width 0.05715)
			(type default)
		)
		(layer "In11.Cu")
	)
	(gr_line
		(start 347.982286 -284.94228)
		(end 347.985588 -284.940248)
		(stroke
			(width 0.05715)
			(type default)
		)
		(layer "In11.Cu")
	)
	(gr_line
		(start 347.982286 -283.322268)
		(end 347.985588 -283.320236)
		(stroke
			(width 0.05715)
			(type default)
		)
		(layer "In11.Cu")
	)
	(gr_line
		(start 347.982286 -281.702256)
		(end 347.985588 -281.700224)
		(stroke
			(width 0.05715)
			(type default)
		)
		(layer "In11.Cu")
	)
	(gr_line
		(start 347.982286 -278.462232)
		(end 347.985588 -278.4602)
		(stroke
			(width 0.05715)
			(type default)
		)
		(layer "In11.Cu")
	)
	(gr_line
		(start 347.983302 -285.910782)
		(end 347.98254 -285.910274)
		(stroke
			(width 0.05715)
			(type default)
		)
		(layer "In11.Cu")
	)
	(gr_line
		(start 347.983302 -284.29077)
		(end 347.98254 -284.290262)
		(stroke
			(width 0.05715)
			(type default)
		)
		(layer "In11.Cu")
	)
	(gr_line
		(start 347.983302 -282.670758)
		(end 347.98254 -282.67025)
		(stroke
			(width 0.05715)
			(type default)
		)
		(layer "In11.Cu")
	)
	(gr_line
		(start 347.983302 -281.050746)
		(end 347.98254 -281.050238)
		(stroke
			(width 0.05715)
			(type default)
		)
		(layer "In11.Cu")
	)
	(gr_line
		(start 347.985588 -294.660066)
		(end 347.987112 -294.65905)
		(stroke
			(width 0.05715)
			(type default)
		)
		(layer "In11.Cu")
	)
	(gr_line
		(start 347.985588 -293.040054)
		(end 347.987112 -293.039038)
		(stroke
			(width 0.05715)
			(type default)
		)
		(layer "In11.Cu")
	)
	(gr_line
		(start 347.985588 -291.420042)
		(end 347.987112 -291.419026)
		(stroke
			(width 0.05715)
			(type default)
		)
		(layer "In11.Cu")
	)
	(gr_line
		(start 347.985588 -289.80003)
		(end 347.987112 -289.799014)
		(stroke
			(width 0.05715)
			(type default)
		)
		(layer "In11.Cu")
	)
	(gr_line
		(start 347.985588 -285.912052)
		(end 347.984572 -285.911544)
		(stroke
			(width 0.05715)
			(type default)
		)
		(layer "In11.Cu")
	)
	(gr_line
		(start 347.985588 -284.940248)
		(end 347.987112 -284.939232)
		(stroke
			(width 0.05715)
			(type default)
		)
		(layer "In11.Cu")
	)
	(gr_line
		(start 347.985588 -284.29204)
		(end 347.984572 -284.291532)
		(stroke
			(width 0.05715)
			(type default)
		)
		(layer "In11.Cu")
	)
	(gr_line
		(start 347.985588 -283.320236)
		(end 347.987112 -283.31922)
		(stroke
			(width 0.05715)
			(type default)
		)
		(layer "In11.Cu")
	)
	(gr_line
		(start 347.985588 -282.672028)
		(end 347.984572 -282.67152)
		(stroke
			(width 0.05715)
			(type default)
		)
		(layer "In11.Cu")
	)
	(gr_line
		(start 347.985588 -281.700224)
		(end 347.987112 -281.699208)
		(stroke
			(width 0.05715)
			(type default)
		)
		(layer "In11.Cu")
	)
	(gr_line
		(start 347.985588 -281.052016)
		(end 347.984572 -281.051508)
		(stroke
			(width 0.05715)
			(type default)
		)
		(layer "In11.Cu")
	)
	(gr_line
		(start 347.985588 -278.4602)
		(end 347.987112 -278.459184)
		(stroke
			(width 0.05715)
			(type default)
		)
		(layer "In11.Cu")
	)
	(gr_line
		(start 347.987112 -294.65905)
		(end 347.988128 -294.658542)
		(stroke
			(width 0.05715)
			(type default)
		)
		(layer "In11.Cu")
	)
	(gr_line
		(start 347.987112 -293.039038)
		(end 347.988128 -293.03853)
		(stroke
			(width 0.05715)
			(type default)
		)
		(layer "In11.Cu")
	)
	(gr_line
		(start 347.987112 -291.419026)
		(end 347.988128 -291.418518)
		(stroke
			(width 0.05715)
			(type default)
		)
		(layer "In11.Cu")
	)
	(gr_line
		(start 347.987112 -289.799014)
		(end 347.988128 -289.798506)
		(stroke
			(width 0.05715)
			(type default)
		)
		(layer "In11.Cu")
	)
	(gr_line
		(start 347.987112 -285.913068)
		(end 347.985588 -285.912052)
		(stroke
			(width 0.05715)
			(type default)
		)
		(layer "In11.Cu")
	)
	(gr_line
		(start 347.987112 -284.939232)
		(end 347.988128 -284.938724)
		(stroke
			(width 0.05715)
			(type default)
		)
		(layer "In11.Cu")
	)
	(gr_line
		(start 347.987112 -284.293056)
		(end 347.985588 -284.29204)
		(stroke
			(width 0.05715)
			(type default)
		)
		(layer "In11.Cu")
	)
	(gr_line
		(start 347.987112 -283.31922)
		(end 347.988128 -283.318712)
		(stroke
			(width 0.05715)
			(type default)
		)
		(layer "In11.Cu")
	)
	(gr_line
		(start 347.987112 -282.673044)
		(end 347.985588 -282.672028)
		(stroke
			(width 0.05715)
			(type default)
		)
		(layer "In11.Cu")
	)
	(gr_line
		(start 347.987112 -281.699208)
		(end 347.988128 -281.6987)
		(stroke
			(width 0.05715)
			(type default)
		)
		(layer "In11.Cu")
	)
	(gr_line
		(start 347.987112 -281.053032)
		(end 347.985588 -281.052016)
		(stroke
			(width 0.05715)
			(type default)
		)
		(layer "In11.Cu")
	)
	(gr_line
		(start 347.987112 -278.459184)
		(end 347.988128 -278.458676)
		(stroke
			(width 0.05715)
			(type default)
		)
		(layer "In11.Cu")
	)
	(gr_line
		(start 347.988128 -294.658542)
		(end 347.988636 -294.658288)
		(stroke
			(width 0.05715)
			(type default)
		)
		(layer "In11.Cu")
	)
	(gr_line
		(start 347.988128 -294.013382)
		(end 347.987112 -294.012874)
		(stroke
			(width 0.05715)
			(type default)
		)
		(layer "In11.Cu")
	)
	(gr_line
		(start 347.988128 -293.03853)
		(end 347.98889 -293.038022)
		(stroke
			(width 0.05715)
			(type default)
		)
		(layer "In11.Cu")
	)
	(gr_line
		(start 347.988128 -292.39337)
		(end 347.987112 -292.392862)
		(stroke
			(width 0.05715)
			(type default)
		)
		(layer "In11.Cu")
	)
	(gr_line
		(start 347.988128 -291.418518)
		(end 347.98889 -291.41801)
		(stroke
			(width 0.05715)
			(type default)
		)
		(layer "In11.Cu")
	)
	(gr_line
		(start 347.988128 -290.773358)
		(end 347.987112 -290.77285)
		(stroke
			(width 0.05715)
			(type default)
		)
		(layer "In11.Cu")
	)
	(gr_line
		(start 347.988128 -289.798506)
		(end 347.98889 -289.797998)
		(stroke
			(width 0.05715)
			(type default)
		)
		(layer "In11.Cu")
	)
	(gr_line
		(start 347.988128 -289.153346)
		(end 347.987112 -289.152838)
		(stroke
			(width 0.05715)
			(type default)
		)
		(layer "In11.Cu")
	)
	(gr_line
		(start 347.988128 -285.913576)
		(end 347.987112 -285.913068)
		(stroke
			(width 0.05715)
			(type default)
		)
		(layer "In11.Cu")
	)
	(gr_line
		(start 347.988128 -284.938724)
		(end 347.98889 -284.938216)
		(stroke
			(width 0.05715)
			(type default)
		)
		(layer "In11.Cu")
	)
	(gr_line
		(start 347.988128 -284.293564)
		(end 347.987112 -284.293056)
		(stroke
			(width 0.05715)
			(type default)
		)
		(layer "In11.Cu")
	)
	(gr_line
		(start 347.988128 -283.318712)
		(end 347.98889 -283.318204)
		(stroke
			(width 0.05715)
			(type default)
		)
		(layer "In11.Cu")
	)
	(gr_line
		(start 347.988128 -282.673552)
		(end 347.987112 -282.673044)
		(stroke
			(width 0.05715)
			(type default)
		)
		(layer "In11.Cu")
	)
	(gr_line
		(start 347.988128 -281.6987)
		(end 347.98889 -281.698192)
		(stroke
			(width 0.05715)
			(type default)
		)
		(layer "In11.Cu")
	)
	(gr_line
		(start 347.988128 -281.05354)
		(end 347.987112 -281.053032)
		(stroke
			(width 0.05715)
			(type default)
		)
		(layer "In11.Cu")
	)
	(gr_line
		(start 347.988128 -278.458676)
		(end 347.98889 -278.458168)
		(stroke
			(width 0.05715)
			(type default)
		)
		(layer "In11.Cu")
	)
	(gr_line
		(start 347.98889 -294.01389)
		(end 347.988128 -294.013382)
		(stroke
			(width 0.05715)
			(type default)
		)
		(layer "In11.Cu")
	)
	(gr_line
		(start 347.98889 -292.393878)
		(end 347.988128 -292.39337)
		(stroke
			(width 0.05715)
			(type default)
		)
		(layer "In11.Cu")
	)
	(gr_line
		(start 347.98889 -290.773866)
		(end 347.988128 -290.773358)
		(stroke
			(width 0.05715)
			(type default)
		)
		(layer "In11.Cu")
	)
	(gr_line
		(start 347.98889 -289.153854)
		(end 347.988128 -289.153346)
		(stroke
			(width 0.05715)
			(type default)
		)
		(layer "In11.Cu")
	)
	(gr_line
		(start 347.99016 -294.014652)
		(end 347.98889 -294.01389)
		(stroke
			(width 0.05715)
			(type default)
		)
		(layer "In11.Cu")
	)
	(gr_line
		(start 347.99016 -292.39464)
		(end 347.98889 -292.393878)
		(stroke
			(width 0.05715)
			(type default)
		)
		(layer "In11.Cu")
	)
	(gr_line
		(start 347.99016 -290.774628)
		(end 347.98889 -290.773866)
		(stroke
			(width 0.05715)
			(type default)
		)
		(layer "In11.Cu")
	)
	(gr_line
		(start 347.99016 -289.154616)
		(end 347.98889 -289.153854)
		(stroke
			(width 0.05715)
			(type default)
		)
		(layer "In11.Cu")
	)
	(gr_line
		(start 347.994224 -294.016938)
		(end 347.9927 -294.015922)
		(stroke
			(width 0.05715)
			(type default)
		)
		(layer "In11.Cu")
	)
	(gr_line
		(start 347.994224 -292.396926)
		(end 347.9927 -292.39591)
		(stroke
			(width 0.05715)
			(type default)
		)
		(layer "In11.Cu")
	)
	(gr_line
		(start 347.994224 -290.776914)
		(end 347.9927 -290.775898)
		(stroke
			(width 0.05715)
			(type default)
		)
		(layer "In11.Cu")
	)
	(gr_line
		(start 347.994224 -289.156902)
		(end 347.9927 -289.155886)
		(stroke
			(width 0.05715)
			(type default)
		)
		(layer "In11.Cu")
	)
	(gr_line
		(start 347.99524 -294.017446)
		(end 347.994224 -294.016938)
		(stroke
			(width 0.05715)
			(type default)
		)
		(layer "In11.Cu")
	)
	(gr_line
		(start 347.99524 -292.397434)
		(end 347.994224 -292.396926)
		(stroke
			(width 0.05715)
			(type default)
		)
		(layer "In11.Cu")
	)
	(gr_line
		(start 347.99524 -290.777422)
		(end 347.994224 -290.776914)
		(stroke
			(width 0.05715)
			(type default)
		)
		(layer "In11.Cu")
	)
	(gr_line
		(start 347.99524 -289.15741)
		(end 347.994224 -289.156902)
		(stroke
			(width 0.05715)
			(type default)
		)
		(layer "In11.Cu")
	)
	(gr_line
		(start 347.99524 -285.91764)
		(end 347.994224 -285.917132)
		(stroke
			(width 0.05715)
			(type default)
		)
		(layer "In11.Cu")
	)
	(gr_line
		(start 347.99524 -284.297628)
		(end 347.994224 -284.29712)
		(stroke
			(width 0.05715)
			(type default)
		)
		(layer "In11.Cu")
	)
	(gr_line
		(start 347.99524 -282.677616)
		(end 347.994224 -282.677108)
		(stroke
			(width 0.05715)
			(type default)
		)
		(layer "In11.Cu")
	)
	(gr_line
		(start 347.99524 -281.057604)
		(end 347.994224 -281.057096)
		(stroke
			(width 0.05715)
			(type default)
		)
		(layer "In11.Cu")
	)
	(gr_line
		(start 347.995748 -294.0177)
		(end 347.99524 -294.017446)
		(stroke
			(width 0.05715)
			(type default)
		)
		(layer "In11.Cu")
	)
	(gr_line
		(start 347.995748 -292.397688)
		(end 347.99524 -292.397434)
		(stroke
			(width 0.05715)
			(type default)
		)
		(layer "In11.Cu")
	)
	(gr_line
		(start 347.995748 -290.777676)
		(end 347.99524 -290.777422)
		(stroke
			(width 0.05715)
			(type default)
		)
		(layer "In11.Cu")
	)
	(gr_line
		(start 347.995748 -289.157664)
		(end 347.99524 -289.15741)
		(stroke
			(width 0.05715)
			(type default)
		)
		(layer "In11.Cu")
	)
	(gr_line
		(start 347.995748 -285.917894)
		(end 347.99524 -285.91764)
		(stroke
			(width 0.05715)
			(type default)
		)
		(layer "In11.Cu")
	)
	(gr_line
		(start 347.995748 -284.297882)
		(end 347.99524 -284.297628)
		(stroke
			(width 0.05715)
			(type default)
		)
		(layer "In11.Cu")
	)
	(gr_line
		(start 347.995748 -282.67787)
		(end 347.99524 -282.677616)
		(stroke
			(width 0.05715)
			(type default)
		)
		(layer "In11.Cu")
	)
	(gr_line
		(start 347.995748 -281.057858)
		(end 347.99524 -281.057604)
		(stroke
			(width 0.05715)
			(type default)
		)
		(layer "In11.Cu")
	)
	(gr_line
		(start 348.044516 -422.859708)
		(end 347.384116 -423.096182)
		(stroke
			(width 0.07112)
			(type default)
		)
		(layer "In11.Cu")
	)
	(gr_line
		(start 348.056708 -423.300906)
		(end 347.65488 -423.44467)
		(stroke
			(width 0.07112)
			(type default)
		)
		(layer "In11.Cu")
	)
	(gr_line
		(start 348.0816 -294.824912)
		(end 348.083378 -294.823896)
		(stroke
			(width 0.05715)
			(type default)
		)
		(layer "In11.Cu")
	)
	(gr_line
		(start 348.0816 -293.2049)
		(end 348.083378 -293.203884)
		(stroke
			(width 0.05715)
			(type default)
		)
		(layer "In11.Cu")
	)
	(gr_line
		(start 348.0816 -291.584888)
		(end 348.083378 -291.583872)
		(stroke
			(width 0.05715)
			(type default)
		)
		(layer "In11.Cu")
	)
	(gr_line
		(start 348.0816 -289.964876)
		(end 348.083378 -289.96386)
		(stroke
			(width 0.05715)
			(type default)
		)
		(layer "In11.Cu")
	)
	(gr_line
		(start 348.0816 -285.105094)
		(end 348.083378 -285.104078)
		(stroke
			(width 0.05715)
			(type default)
		)
		(layer "In11.Cu")
	)
	(gr_line
		(start 348.0816 -283.485082)
		(end 348.083378 -283.484066)
		(stroke
			(width 0.05715)
			(type default)
		)
		(layer "In11.Cu")
	)
	(gr_line
		(start 348.0816 -281.86507)
		(end 348.083378 -281.864054)
		(stroke
			(width 0.05715)
			(type default)
		)
		(layer "In11.Cu")
	)
	(gr_line
		(start 348.0816 -278.625046)
		(end 348.083378 -278.62403)
		(stroke
			(width 0.05715)
			(type default)
		)
		(layer "In11.Cu")
	)
	(gr_line
		(start 348.083378 -293.848028)
		(end 348.082108 -293.847266)
		(stroke
			(width 0.05715)
			(type default)
		)
		(layer "In11.Cu")
	)
	(gr_line
		(start 348.083378 -293.203884)
		(end 348.08414 -293.203376)
		(stroke
			(width 0.05715)
			(type default)
		)
		(layer "In11.Cu")
	)
	(gr_line
		(start 348.083378 -292.228016)
		(end 348.082108 -292.227254)
		(stroke
			(width 0.05715)
			(type default)
		)
		(layer "In11.Cu")
	)
	(gr_line
		(start 348.083378 -291.583872)
		(end 348.08414 -291.583364)
		(stroke
			(width 0.05715)
			(type default)
		)
		(layer "In11.Cu")
	)
	(gr_line
		(start 348.083378 -290.608004)
		(end 348.082108 -290.607242)
		(stroke
			(width 0.05715)
			(type default)
		)
		(layer "In11.Cu")
	)
	(gr_line
		(start 348.083378 -289.96386)
		(end 348.08414 -289.963352)
		(stroke
			(width 0.05715)
			(type default)
		)
		(layer "In11.Cu")
	)
	(gr_line
		(start 348.083378 -288.987992)
		(end 348.082108 -288.98723)
		(stroke
			(width 0.05715)
			(type default)
		)
		(layer "In11.Cu")
	)
	(gr_line
		(start 348.083378 -285.748222)
		(end 348.080584 -285.746698)
		(stroke
			(width 0.05715)
			(type default)
		)
		(layer "In11.Cu")
	)
	(gr_line
		(start 348.083378 -285.104078)
		(end 348.08414 -285.10357)
		(stroke
			(width 0.05715)
			(type default)
		)
		(layer "In11.Cu")
	)
	(gr_line
		(start 348.083378 -284.12821)
		(end 348.080584 -284.126686)
		(stroke
			(width 0.05715)
			(type default)
		)
		(layer "In11.Cu")
	)
	(gr_line
		(start 348.083378 -283.484066)
		(end 348.08414 -283.483558)
		(stroke
			(width 0.05715)
			(type default)
		)
		(layer "In11.Cu")
	)
	(gr_line
		(start 348.083378 -282.508198)
		(end 348.080584 -282.506674)
		(stroke
			(width 0.05715)
			(type default)
		)
		(layer "In11.Cu")
	)
	(gr_line
		(start 348.083378 -281.864054)
		(end 348.08414 -281.863546)
		(stroke
			(width 0.05715)
			(type default)
		)
		(layer "In11.Cu")
	)
	(gr_line
		(start 348.083378 -280.888186)
		(end 348.080584 -280.886662)
		(stroke
			(width 0.05715)
			(type default)
		)
		(layer "In11.Cu")
	)
	(gr_line
		(start 348.083378 -278.62403)
		(end 348.08414 -278.623522)
		(stroke
			(width 0.05715)
			(type default)
		)
		(layer "In11.Cu")
	)
	(gr_line
		(start 348.08414 -293.848536)
		(end 348.083378 -293.848028)
		(stroke
			(width 0.05715)
			(type default)
		)
		(layer "In11.Cu")
	)
	(gr_line
		(start 348.08414 -293.203376)
		(end 348.085156 -293.202868)
		(stroke
			(width 0.05715)
			(type default)
		)
		(layer "In11.Cu")
	)
	(gr_line
		(start 348.08414 -292.228524)
		(end 348.083378 -292.228016)
		(stroke
			(width 0.05715)
			(type default)
		)
		(layer "In11.Cu")
	)
	(gr_line
		(start 348.08414 -291.583364)
		(end 348.085156 -291.582856)
		(stroke
			(width 0.05715)
			(type default)
		)
		(layer "In11.Cu")
	)
	(gr_line
		(start 348.08414 -290.608512)
		(end 348.083378 -290.608004)
		(stroke
			(width 0.05715)
			(type default)
		)
		(layer "In11.Cu")
	)
	(gr_line
		(start 348.08414 -289.963352)
		(end 348.085156 -289.962844)
		(stroke
			(width 0.05715)
			(type default)
		)
		(layer "In11.Cu")
	)
	(gr_line
		(start 348.08414 -288.9885)
		(end 348.083378 -288.987992)
		(stroke
			(width 0.05715)
			(type default)
		)
		(layer "In11.Cu")
	)
	(gr_line
		(start 348.08414 -285.74873)
		(end 348.083378 -285.748222)
		(stroke
			(width 0.05715)
			(type default)
		)
		(layer "In11.Cu")
	)
	(gr_line
		(start 348.08414 -285.10357)
		(end 348.085156 -285.103062)
		(stroke
			(width 0.05715)
			(type default)
		)
		(layer "In11.Cu")
	)
	(gr_line
		(start 348.08414 -284.128718)
		(end 348.083378 -284.12821)
		(stroke
			(width 0.05715)
			(type default)
		)
		(layer "In11.Cu")
	)
	(gr_line
		(start 348.08414 -283.483558)
		(end 348.085156 -283.48305)
		(stroke
			(width 0.05715)
			(type default)
		)
		(layer "In11.Cu")
	)
	(gr_line
		(start 348.08414 -282.508706)
		(end 348.083378 -282.508198)
		(stroke
			(width 0.05715)
			(type default)
		)
		(layer "In11.Cu")
	)
	(gr_line
		(start 348.08414 -281.863546)
		(end 348.085156 -281.863038)
		(stroke
			(width 0.05715)
			(type default)
		)
		(layer "In11.Cu")
	)
	(gr_line
		(start 348.08414 -280.888694)
		(end 348.083378 -280.888186)
		(stroke
			(width 0.05715)
			(type default)
		)
		(layer "In11.Cu")
	)
	(gr_line
		(start 348.08414 -278.623522)
		(end 348.085156 -278.623014)
		(stroke
			(width 0.05715)
			(type default)
		)
		(layer "In11.Cu")
	)
	(gr_line
		(start 348.085156 -293.849044)
		(end 348.08414 -293.848536)
		(stroke
			(width 0.05715)
			(type default)
		)
		(layer "In11.Cu")
	)
	(gr_line
		(start 348.085156 -292.229032)
		(end 348.08414 -292.228524)
		(stroke
			(width 0.05715)
			(type default)
		)
		(layer "In11.Cu")
	)
	(gr_line
		(start 348.085156 -290.60902)
		(end 348.08414 -290.608512)
		(stroke
			(width 0.05715)
			(type default)
		)
		(layer "In11.Cu")
	)
	(gr_line
		(start 348.085156 -288.989008)
		(end 348.08414 -288.9885)
		(stroke
			(width 0.05715)
			(type default)
		)
		(layer "In11.Cu")
	)
	(gr_line
		(start 348.085156 -285.749238)
		(end 348.08414 -285.74873)
		(stroke
			(width 0.05715)
			(type default)
		)
		(layer "In11.Cu")
	)
	(gr_line
		(start 348.085156 -284.129226)
		(end 348.08414 -284.128718)
		(stroke
			(width 0.05715)
			(type default)
		)
		(layer "In11.Cu")
	)
	(gr_line
		(start 348.085156 -282.509214)
		(end 348.08414 -282.508706)
		(stroke
			(width 0.05715)
			(type default)
		)
		(layer "In11.Cu")
	)
	(gr_line
		(start 348.085156 -280.889202)
		(end 348.08414 -280.888694)
		(stroke
			(width 0.05715)
			(type default)
		)
		(layer "In11.Cu")
	)
	(gr_line
		(start 348.086934 -293.85006)
		(end 348.085156 -293.849044)
		(stroke
			(width 0.05715)
			(type default)
		)
		(layer "In11.Cu")
	)
	(gr_line
		(start 348.086934 -292.230048)
		(end 348.085156 -292.229032)
		(stroke
			(width 0.05715)
			(type default)
		)
		(layer "In11.Cu")
	)
	(gr_line
		(start 348.086934 -290.610036)
		(end 348.085156 -290.60902)
		(stroke
			(width 0.05715)
			(type default)
		)
		(layer "In11.Cu")
	)
	(gr_line
		(start 348.086934 -288.990024)
		(end 348.085156 -288.989008)
		(stroke
			(width 0.05715)
			(type default)
		)
		(layer "In11.Cu")
	)
	(gr_line
		(start 348.086934 -285.750254)
		(end 348.085156 -285.749238)
		(stroke
			(width 0.05715)
			(type default)
		)
		(layer "In11.Cu")
	)
	(gr_line
		(start 348.086934 -284.130242)
		(end 348.085156 -284.129226)
		(stroke
			(width 0.05715)
			(type default)
		)
		(layer "In11.Cu")
	)
	(gr_line
		(start 348.086934 -282.51023)
		(end 348.085156 -282.509214)
		(stroke
			(width 0.05715)
			(type default)
		)
		(layer "In11.Cu")
	)
	(gr_line
		(start 348.086934 -280.890218)
		(end 348.085156 -280.889202)
		(stroke
			(width 0.05715)
			(type default)
		)
		(layer "In11.Cu")
	)
	(gr_line
		(start 348.089474 -293.851584)
		(end 348.088458 -293.851076)
		(stroke
			(width 0.05715)
			(type default)
		)
		(layer "In11.Cu")
	)
	(gr_line
		(start 348.089474 -292.231572)
		(end 348.088458 -292.231064)
		(stroke
			(width 0.05715)
			(type default)
		)
		(layer "In11.Cu")
	)
	(gr_line
		(start 348.089474 -290.61156)
		(end 348.088458 -290.611052)
		(stroke
			(width 0.05715)
			(type default)
		)
		(layer "In11.Cu")
	)
	(gr_line
		(start 348.089474 -288.991548)
		(end 348.088458 -288.99104)
		(stroke
			(width 0.05715)
			(type default)
		)
		(layer "In11.Cu")
	)
	(gr_line
		(start 348.089474 -285.751778)
		(end 348.088458 -285.75127)
		(stroke
			(width 0.05715)
			(type default)
		)
		(layer "In11.Cu")
	)
	(gr_line
		(start 348.089474 -284.131766)
		(end 348.088458 -284.131258)
		(stroke
			(width 0.05715)
			(type default)
		)
		(layer "In11.Cu")
	)
	(gr_line
		(start 348.089474 -282.511754)
		(end 348.088458 -282.511246)
		(stroke
			(width 0.05715)
			(type default)
		)
		(layer "In11.Cu")
	)
	(gr_line
		(start 348.089474 -280.891742)
		(end 348.088458 -280.891234)
		(stroke
			(width 0.05715)
			(type default)
		)
		(layer "In11.Cu")
	)
	(gr_line
		(start 348.09049 -293.852346)
		(end 348.089474 -293.851584)
		(stroke
			(width 0.05715)
			(type default)
		)
		(layer "In11.Cu")
	)
	(gr_line
		(start 348.09049 -292.232334)
		(end 348.089474 -292.231572)
		(stroke
			(width 0.05715)
			(type default)
		)
		(layer "In11.Cu")
	)
	(gr_line
		(start 348.09049 -290.612322)
		(end 348.089474 -290.61156)
		(stroke
			(width 0.05715)
			(type default)
		)
		(layer "In11.Cu")
	)
	(gr_line
		(start 348.09049 -288.99231)
		(end 348.089474 -288.991548)
		(stroke
			(width 0.05715)
			(type default)
		)
		(layer "In11.Cu")
	)
	(gr_line
		(start 348.09049 -285.75254)
		(end 348.089474 -285.751778)
		(stroke
			(width 0.05715)
			(type default)
		)
		(layer "In11.Cu")
	)
	(gr_line
		(start 348.09049 -284.132528)
		(end 348.089474 -284.131766)
		(stroke
			(width 0.05715)
			(type default)
		)
		(layer "In11.Cu")
	)
	(gr_line
		(start 348.09049 -282.512516)
		(end 348.089474 -282.511754)
		(stroke
			(width 0.05715)
			(type default)
		)
		(layer "In11.Cu")
	)
	(gr_line
		(start 348.09049 -280.892504)
		(end 348.089474 -280.891742)
		(stroke
			(width 0.05715)
			(type default)
		)
		(layer "In11.Cu")
	)
	(gr_line
		(start 348.115636 -293.866824)
		(end 348.115128 -293.86657)
		(stroke
			(width 0.05715)
			(type default)
		)
		(layer "In11.Cu")
	)
	(gr_line
		(start 348.115636 -292.246812)
		(end 348.115128 -292.246558)
		(stroke
			(width 0.05715)
			(type default)
		)
		(layer "In11.Cu")
	)
	(gr_line
		(start 348.115636 -290.6268)
		(end 348.115128 -290.626546)
		(stroke
			(width 0.05715)
			(type default)
		)
		(layer "In11.Cu")
	)
	(gr_line
		(start 348.115636 -289.006788)
		(end 348.115128 -289.006534)
		(stroke
			(width 0.05715)
			(type default)
		)
		(layer "In11.Cu")
	)
	(gr_line
		(start 348.115636 -285.767018)
		(end 348.115128 -285.766764)
		(stroke
			(width 0.05715)
			(type default)
		)
		(layer "In11.Cu")
	)
	(gr_line
		(start 348.115636 -284.147006)
		(end 348.115128 -284.146752)
		(stroke
			(width 0.05715)
			(type default)
		)
		(layer "In11.Cu")
	)
	(gr_line
		(start 348.115636 -282.526994)
		(end 348.115128 -282.52674)
		(stroke
			(width 0.05715)
			(type default)
		)
		(layer "In11.Cu")
	)
	(gr_line
		(start 348.115636 -280.906982)
		(end 348.115128 -280.906728)
		(stroke
			(width 0.05715)
			(type default)
		)
		(layer "In11.Cu")
	)
	(gr_line
		(start 348.116398 -293.867332)
		(end 348.115636 -293.866824)
		(stroke
			(width 0.05715)
			(type default)
		)
		(layer "In11.Cu")
	)
	(gr_line
		(start 348.116398 -292.24732)
		(end 348.115636 -292.246812)
		(stroke
			(width 0.05715)
			(type default)
		)
		(layer "In11.Cu")
	)
	(gr_line
		(start 348.116398 -290.627308)
		(end 348.115636 -290.6268)
		(stroke
			(width 0.05715)
			(type default)
		)
		(layer "In11.Cu")
	)
	(gr_line
		(start 348.116398 -289.007296)
		(end 348.115636 -289.006788)
		(stroke
			(width 0.05715)
			(type default)
		)
		(layer "In11.Cu")
	)
	(gr_line
		(start 348.116398 -285.767526)
		(end 348.115636 -285.767018)
		(stroke
			(width 0.05715)
			(type default)
		)
		(layer "In11.Cu")
	)
	(gr_line
		(start 348.116398 -284.147514)
		(end 348.115636 -284.147006)
		(stroke
			(width 0.05715)
			(type default)
		)
		(layer "In11.Cu")
	)
	(gr_line
		(start 348.116398 -282.527502)
		(end 348.115636 -282.526994)
		(stroke
			(width 0.05715)
			(type default)
		)
		(layer "In11.Cu")
	)
	(gr_line
		(start 348.116398 -280.90749)
		(end 348.115636 -280.906982)
		(stroke
			(width 0.05715)
			(type default)
		)
		(layer "In11.Cu")
	)
	(gr_line
		(start 348.123256 -293.871396)
		(end 348.116398 -293.867332)
		(stroke
			(width 0.05715)
			(type default)
		)
		(layer "In11.Cu")
	)
	(gr_line
		(start 348.123256 -292.251384)
		(end 348.116398 -292.24732)
		(stroke
			(width 0.05715)
			(type default)
		)
		(layer "In11.Cu")
	)
	(gr_line
		(start 348.123256 -290.631372)
		(end 348.116398 -290.627308)
		(stroke
			(width 0.05715)
			(type default)
		)
		(layer "In11.Cu")
	)
	(gr_line
		(start 348.123256 -289.01136)
		(end 348.116398 -289.007296)
		(stroke
			(width 0.05715)
			(type default)
		)
		(layer "In11.Cu")
	)
	(gr_line
		(start 348.123256 -285.77159)
		(end 348.116398 -285.767526)
		(stroke
			(width 0.05715)
			(type default)
		)
		(layer "In11.Cu")
	)
	(gr_line
		(start 348.123256 -284.151578)
		(end 348.116398 -284.147514)
		(stroke
			(width 0.05715)
			(type default)
		)
		(layer "In11.Cu")
	)
	(gr_line
		(start 348.123256 -282.531566)
		(end 348.116398 -282.527502)
		(stroke
			(width 0.05715)
			(type default)
		)
		(layer "In11.Cu")
	)
	(gr_line
		(start 348.123256 -280.911554)
		(end 348.116398 -280.90749)
		(stroke
			(width 0.05715)
			(type default)
		)
		(layer "In11.Cu")
	)
	(gr_line
		(start 348.125288 -296.46372)
		(end 348.125288 -296.435272)
		(stroke
			(width 0.05715)
			(type default)
		)
		(layer "In11.Cu")
	)
	(gr_line
		(start 348.125288 -296.435272)
		(end 348.171008 -296.389552)
		(stroke
			(width 0.05715)
			(type default)
		)
		(layer "In11.Cu")
	)
	(gr_arc
		(start 348.13113 -293.876984)
		(mid 348.127205 -293.874173)
		(end 348.123256 -293.871396)
		(stroke
			(width 0.05715)
			(type default)
		)
		(layer "In11.Cu")
	)
	(gr_arc
		(start 348.13113 -292.256972)
		(mid 348.127205 -292.254161)
		(end 348.123256 -292.251384)
		(stroke
			(width 0.05715)
			(type default)
		)
		(layer "In11.Cu")
	)
	(gr_arc
		(start 348.13113 -290.63696)
		(mid 348.127205 -290.634149)
		(end 348.123256 -290.631372)
		(stroke
			(width 0.05715)
			(type default)
		)
		(layer "In11.Cu")
	)
	(gr_arc
		(start 348.13113 -289.016948)
		(mid 348.127205 -289.014137)
		(end 348.123256 -289.01136)
		(stroke
			(width 0.05715)
			(type default)
		)
		(layer "In11.Cu")
	)
	(gr_arc
		(start 348.13113 -285.777178)
		(mid 348.127205 -285.774367)
		(end 348.123256 -285.77159)
		(stroke
			(width 0.05715)
			(type default)
		)
		(layer "In11.Cu")
	)
	(gr_arc
		(start 348.13113 -284.157166)
		(mid 348.127205 -284.154355)
		(end 348.123256 -284.151578)
		(stroke
			(width 0.05715)
			(type default)
		)
		(layer "In11.Cu")
	)
	(gr_arc
		(start 348.13113 -282.537154)
		(mid 348.127205 -282.534343)
		(end 348.123256 -282.531566)
		(stroke
			(width 0.05715)
			(type default)
		)
		(layer "In11.Cu")
	)
	(gr_arc
		(start 348.13113 -280.917142)
		(mid 348.127205 -280.914331)
		(end 348.123256 -280.911554)
		(stroke
			(width 0.05715)
			(type default)
		)
		(layer "In11.Cu")
	)
	(gr_line
		(start 348.139258 -423.126662)
		(end 348.056708 -423.300906)
		(stroke
			(width 0.07112)
			(type default)
		)
		(layer "In11.Cu")
	)
	(gr_line
		(start 348.318836 -393.69238)
		(end 348.67215 -393.787376)
		(stroke
			(width 0.07112)
			(type default)
		)
		(layer "In11.Cu")
	)
	(gr_line
		(start 348.407228 -296.46372)
		(end 348.407228 -296.435272)
		(stroke
			(width 0.05715)
			(type default)
		)
		(layer "In11.Cu")
	)
	(gr_line
		(start 348.407228 -296.435272)
		(end 348.361508 -296.389552)
		(stroke
			(width 0.05715)
			(type default)
		)
		(layer "In11.Cu")
	)
	(gr_line
		(start 348.649036 -389.58012)
		(end 348.649036 -389.1534)
		(stroke
			(width 0.07112)
			(type default)
		)
		(layer "In11.Cu")
	)
	(gr_line
		(start 348.649036 -389.1534)
		(end 348.784926 -389.01751)
		(stroke
			(width 0.07112)
			(type default)
		)
		(layer "In11.Cu")
	)
	(gr_line
		(start 348.649036 -388.45236)
		(end 348.649036 -388.02564)
		(stroke
			(width 0.07112)
			(type default)
		)
		(layer "In11.Cu")
	)
	(gr_line
		(start 348.649036 -388.02564)
		(end 348.784926 -387.88975)
		(stroke
			(width 0.07112)
			(type default)
		)
		(layer "In11.Cu")
	)
	(gr_line
		(start 348.649036 -387.3246)
		(end 348.649036 -386.89788)
		(stroke
			(width 0.07112)
			(type default)
		)
		(layer "In11.Cu")
	)
	(gr_line
		(start 348.649036 -386.89788)
		(end 348.784926 -386.76199)
		(stroke
			(width 0.07112)
			(type default)
		)
		(layer "In11.Cu")
	)
	(gr_line
		(start 348.67215 -393.787376)
		(end 348.672658 -393.786868)
		(stroke
			(width 0.07112)
			(type default)
		)
		(layer "In11.Cu")
	)
	(gr_line
		(start 348.716854 -423.064432)
		(end 348.54261 -422.982136)
		(stroke
			(width 0.07112)
			(type default)
		)
		(layer "In11.Cu")
	)
	(gr_line
		(start 348.718886 -394.385292)
		(end 348.813628 -394.031724)
		(stroke
			(width 0.07112)
			(type default)
		)
		(layer "In11.Cu")
	)
	(gr_line
		(start 348.784926 -389.71601)
		(end 348.649036 -389.58012)
		(stroke
			(width 0.07112)
			(type default)
		)
		(layer "In11.Cu")
	)
	(gr_line
		(start 348.784926 -388.58825)
		(end 348.649036 -388.45236)
		(stroke
			(width 0.07112)
			(type default)
		)
		(layer "In11.Cu")
	)
	(gr_line
		(start 348.784926 -387.46049)
		(end 348.649036 -387.3246)
		(stroke
			(width 0.07112)
			(type default)
		)
		(layer "In11.Cu")
	)
	(gr_arc
		(start 348.881192 -293.984934)
		(mid 348.885117 -293.987745)
		(end 348.889066 -293.990522)
		(stroke
			(width 0.05715)
			(type default)
		)
		(layer "In11.Cu")
	)
	(gr_arc
		(start 348.881192 -292.364922)
		(mid 348.885117 -292.367733)
		(end 348.889066 -292.37051)
		(stroke
			(width 0.05715)
			(type default)
		)
		(layer "In11.Cu")
	)
	(gr_arc
		(start 348.881192 -290.74491)
		(mid 348.885117 -290.747721)
		(end 348.889066 -290.750498)
		(stroke
			(width 0.05715)
			(type default)
		)
		(layer "In11.Cu")
	)
	(gr_arc
		(start 348.881192 -289.124898)
		(mid 348.885117 -289.127709)
		(end 348.889066 -289.130486)
		(stroke
			(width 0.05715)
			(type default)
		)
		(layer "In11.Cu")
	)
	(gr_arc
		(start 348.881192 -287.504886)
		(mid 348.886378 -287.508599)
		(end 348.891606 -287.512252)
		(stroke
			(width 0.05715)
			(type default)
		)
		(layer "In11.Cu")
	)
	(gr_arc
		(start 348.881192 -285.885128)
		(mid 348.885117 -285.887939)
		(end 348.889066 -285.890716)
		(stroke
			(width 0.05715)
			(type default)
		)
		(layer "In11.Cu")
	)
	(gr_arc
		(start 348.884748 -286.58439)
		(mid 348.881566 -286.586666)
		(end 348.878398 -286.588962)
		(stroke
			(width 0.05715)
			(type default)
		)
		(layer "In11.Cu")
	)
	(gr_arc
		(start 348.889066 -286.581342)
		(mid 348.887285 -286.582608)
		(end 348.88551 -286.583882)
		(stroke
			(width 0.05715)
			(type default)
		)
		(layer "In11.Cu")
	)
	(gr_line
		(start 348.889066 -286.581342)
		(end 348.895162 -286.577786)
		(stroke
			(width 0.05715)
			(type default)
		)
		(layer "In11.Cu")
	)
	(gr_arc
		(start 348.889066 -283.341572)
		(mid 348.885117 -283.344349)
		(end 348.881192 -283.34716)
		(stroke
			(width 0.05715)
			(type default)
		)
		(layer "In11.Cu")
	)
	(gr_line
		(start 348.889066 -283.341572)
		(end 348.89186 -283.33954)
		(stroke
			(width 0.05715)
			(type default)
		)
		(layer "In11.Cu")
	)
	(gr_arc
		(start 348.889828 -285.891224)
		(mid 348.889447 -285.89097)
		(end 348.889066 -285.890716)
		(stroke
			(width 0.05715)
			(type default)
		)
		(layer "In11.Cu")
	)
	(gr_line
		(start 348.89186 -283.33954)
		(end 348.897194 -283.336492)
		(stroke
			(width 0.05715)
			(type default)
		)
		(layer "In11.Cu")
	)
	(gr_line
		(start 348.895162 -286.577786)
		(end 348.895924 -286.577786)
		(stroke
			(width 0.05715)
			(type default)
		)
		(layer "In11.Cu")
	)
	(gr_line
		(start 348.895924 -293.994586)
		(end 348.889066 -293.990522)
		(stroke
			(width 0.05715)
			(type default)
		)
		(layer "In11.Cu")
	)
	(gr_line
		(start 348.895924 -292.374574)
		(end 348.889066 -292.37051)
		(stroke
			(width 0.05715)
			(type default)
		)
		(layer "In11.Cu")
	)
	(gr_line
		(start 348.895924 -290.754562)
		(end 348.889066 -290.750498)
		(stroke
			(width 0.05715)
			(type default)
		)
		(layer "In11.Cu")
	)
	(gr_line
		(start 348.895924 -289.13455)
		(end 348.889066 -289.130486)
		(stroke
			(width 0.05715)
			(type default)
		)
		(layer "In11.Cu")
	)
	(gr_line
		(start 348.895924 -287.514792)
		(end 348.891606 -287.512252)
		(stroke
			(width 0.05715)
			(type default)
		)
		(layer "In11.Cu")
	)
	(gr_line
		(start 348.896686 -293.995094)
		(end 348.895924 -293.994586)
		(stroke
			(width 0.05715)
			(type default)
		)
		(layer "In11.Cu")
	)
	(gr_line
		(start 348.896686 -292.375082)
		(end 348.895924 -292.374574)
		(stroke
			(width 0.05715)
			(type default)
		)
		(layer "In11.Cu")
	)
	(gr_line
		(start 348.896686 -290.75507)
		(end 348.895924 -290.754562)
		(stroke
			(width 0.05715)
			(type default)
		)
		(layer "In11.Cu")
	)
	(gr_line
		(start 348.896686 -289.135058)
		(end 348.895924 -289.13455)
		(stroke
			(width 0.05715)
			(type default)
		)
		(layer "In11.Cu")
	)
	(gr_line
		(start 348.896686 -287.5153)
		(end 348.895924 -287.514792)
		(stroke
			(width 0.05715)
			(type default)
		)
		(layer "In11.Cu")
	)
	(gr_line
		(start 348.897194 -287.515554)
		(end 348.896686 -287.5153)
		(stroke
			(width 0.05715)
			(type default)
		)
		(layer "In11.Cu")
	)
	(gr_line
		(start 348.897448 -293.995602)
		(end 348.896686 -293.995094)
		(stroke
			(width 0.05715)
			(type default)
		)
		(layer "In11.Cu")
	)
	(gr_line
		(start 348.897448 -292.37559)
		(end 348.896686 -292.375082)
		(stroke
			(width 0.05715)
			(type default)
		)
		(layer "In11.Cu")
	)
	(gr_line
		(start 348.897448 -290.755578)
		(end 348.896686 -290.75507)
		(stroke
			(width 0.05715)
			(type default)
		)
		(layer "In11.Cu")
	)
	(gr_line
		(start 348.897448 -289.135566)
		(end 348.896686 -289.135058)
		(stroke
			(width 0.05715)
			(type default)
		)
		(layer "In11.Cu")
	)
	(gr_line
		(start 348.897448 -285.895542)
		(end 348.889828 -285.891224)
		(stroke
			(width 0.05715)
			(type default)
		)
		(layer "In11.Cu")
	)
	(gr_line
		(start 348.922848 -278.463248)
		(end 348.925134 -278.461978)
		(stroke
			(width 0.05715)
			(type default)
		)
		(layer "In11.Cu")
	)
	(gr_line
		(start 348.923356 -287.530794)
		(end 348.922594 -287.530286)
		(stroke
			(width 0.05715)
			(type default)
		)
		(layer "In11.Cu")
	)
	(gr_line
		(start 348.92361 -285.910782)
		(end 348.922848 -285.910274)
		(stroke
			(width 0.05715)
			(type default)
		)
		(layer "In11.Cu")
	)
	(gr_line
		(start 348.924118 -285.911036)
		(end 348.92361 -285.910782)
		(stroke
			(width 0.05715)
			(type default)
		)
		(layer "In11.Cu")
	)
	(gr_line
		(start 348.926912 -287.532826)
		(end 348.923356 -287.530794)
		(stroke
			(width 0.05715)
			(type default)
		)
		(layer "In11.Cu")
	)
	(gr_line
		(start 348.927166 -293.039038)
		(end 348.928182 -293.03853)
		(stroke
			(width 0.05715)
			(type default)
		)
		(layer "In11.Cu")
	)
	(gr_line
		(start 348.927166 -291.419026)
		(end 348.928182 -291.418518)
		(stroke
			(width 0.05715)
			(type default)
		)
		(layer "In11.Cu")
	)
	(gr_line
		(start 348.927166 -289.799014)
		(end 348.928182 -289.798506)
		(stroke
			(width 0.05715)
			(type default)
		)
		(layer "In11.Cu")
	)
	(gr_line
		(start 348.928436 -286.558736)
		(end 348.929198 -286.558228)
		(stroke
			(width 0.05715)
			(type default)
		)
		(layer "In11.Cu")
	)
	(gr_line
		(start 348.928944 -294.01389)
		(end 348.928182 -294.013382)
		(stroke
			(width 0.05715)
			(type default)
		)
		(layer "In11.Cu")
	)
	(gr_line
		(start 348.929452 -285.914084)
		(end 348.92869 -285.913576)
		(stroke
			(width 0.05715)
			(type default)
		)
		(layer "In11.Cu")
	)
	(gr_line
		(start 348.929706 -287.53435)
		(end 348.92869 -287.533842)
		(stroke
			(width 0.05715)
			(type default)
		)
		(layer "In11.Cu")
	)
	(gr_line
		(start 348.931738 -294.015414)
		(end 348.928944 -294.01389)
		(stroke
			(width 0.05715)
			(type default)
		)
		(layer "In11.Cu")
	)
	(gr_line
		(start 348.935294 -393.961112)
		(end 348.988126 -393.930632)
		(stroke
			(width 0.07112)
			(type default)
		)
		(layer "In11.Cu")
	)
	(gr_line
		(start 348.988126 -393.930632)
		(end 349.076264 -393.842494)
		(stroke
			(width 0.07112)
			(type default)
		)
		(layer "In11.Cu")
	)
	(gr_line
		(start 349.019368 -286.726376)
		(end 349.022162 -286.724598)
		(stroke
			(width 0.05715)
			(type default)
		)
		(layer "In11.Cu")
	)
	(gr_line
		(start 349.022162 -293.204646)
		(end 349.023432 -293.203884)
		(stroke
			(width 0.05715)
			(type default)
		)
		(layer "In11.Cu")
	)
	(gr_line
		(start 349.022162 -291.584634)
		(end 349.023432 -291.583872)
		(stroke
			(width 0.05715)
			(type default)
		)
		(layer "In11.Cu")
	)
	(gr_line
		(start 349.022162 -289.964622)
		(end 349.023432 -289.96386)
		(stroke
			(width 0.05715)
			(type default)
		)
		(layer "In11.Cu")
	)
	(gr_line
		(start 349.023432 -293.203884)
		(end 349.024194 -293.203376)
		(stroke
			(width 0.05715)
			(type default)
		)
		(layer "In11.Cu")
	)
	(gr_line
		(start 349.023432 -291.583872)
		(end 349.024194 -291.583364)
		(stroke
			(width 0.05715)
			(type default)
		)
		(layer "In11.Cu")
	)
	(gr_line
		(start 349.023432 -289.96386)
		(end 349.024194 -289.963352)
		(stroke
			(width 0.05715)
			(type default)
		)
		(layer "In11.Cu")
	)
	(gr_line
		(start 349.02394 -287.368742)
		(end 349.024194 -287.368488)
		(stroke
			(width 0.05715)
			(type default)
		)
		(layer "In11.Cu")
	)
	(gr_arc
		(start 349.028512 -277.00097)
		(mid 349.028131 -277.001224)
		(end 349.02775 -277.001478)
		(stroke
			(width 0.05715)
			(type default)
		)
		(layer "In11.Cu")
	)
	(gr_line
		(start 349.03918 -278.136096)
		(end 348.741238 -278.136096)
		(stroke
			(width 0.05715)
			(type default)
		)
		(layer "In11.Cu")
	)
	(gr_line
		(start 349.03918 -276.516084)
		(end 348.741238 -276.516084)
		(stroke
			(width 0.05715)
			(type default)
		)
		(layer "In11.Cu")
	)
	(gr_line
		(start 349.03918 -274.896072)
		(end 348.741238 -274.896072)
		(stroke
			(width 0.05715)
			(type default)
		)
		(layer "In11.Cu")
	)
	(gr_line
		(start 349.046292 -294.810688)
		(end 349.050864 -294.808148)
		(stroke
			(width 0.05715)
			(type default)
		)
		(layer "In11.Cu")
	)
	(gr_line
		(start 349.055182 -281.845766)
		(end 349.058992 -281.84348)
		(stroke
			(width 0.05715)
			(type default)
		)
		(layer "In11.Cu")
	)
	(gr_line
		(start 349.058992 -281.84348)
		(end 349.060516 -281.842464)
		(stroke
			(width 0.05715)
			(type default)
		)
		(layer "In11.Cu")
	)
	(gr_arc
		(start 349.060516 -281.842464)
		(mid 349.067667 -281.837567)
		(end 349.07474 -281.832558)
		(stroke
			(width 0.05715)
			(type default)
		)
		(layer "In11.Cu")
	)
	(gr_line
		(start 349.06204 -294.801544)
		(end 349.078042 -294.790114)
		(stroke
			(width 0.05715)
			(type default)
		)
		(layer "In11.Cu")
	)
	(gr_line
		(start 349.068136 -389.71728)
		(end 349.068136 -389.01624)
		(stroke
			(width 0.07112)
			(type default)
		)
		(layer "In11.Cu")
	)
	(gr_line
		(start 349.068136 -388.58952)
		(end 349.068136 -387.88848)
		(stroke
			(width 0.07112)
			(type default)
		)
		(layer "In11.Cu")
	)
	(gr_line
		(start 349.068136 -387.46176)
		(end 349.068136 -386.76072)
		(stroke
			(width 0.07112)
			(type default)
		)
		(layer "In11.Cu")
	)
	(gr_line
		(start 349.070422 -296.46372)
		(end 349.070422 -296.435272)
		(stroke
			(width 0.05715)
			(type default)
		)
		(layer "In11.Cu")
	)
	(gr_line
		(start 349.070422 -296.435272)
		(end 349.116142 -296.389552)
		(stroke
			(width 0.05715)
			(type default)
		)
		(layer "In11.Cu")
	)
	(gr_line
		(start 349.076264 -393.842494)
		(end 349.076264 -393.716764)
		(stroke
			(width 0.07112)
			(type default)
		)
		(layer "In11.Cu")
	)
	(gr_line
		(start 349.10649 -422.47947)
		(end 348.44609 -422.715944)
		(stroke
			(width 0.07112)
			(type default)
		)
		(layer "In11.Cu")
	)
	(gr_line
		(start 349.108268 -278.205184)
		(end 349.03918 -278.136096)
		(stroke
			(width 0.05715)
			(type default)
		)
		(layer "In11.Cu")
	)
	(gr_line
		(start 349.108268 -276.585172)
		(end 349.03918 -276.516084)
		(stroke
			(width 0.05715)
			(type default)
		)
		(layer "In11.Cu")
	)
	(gr_line
		(start 349.109284 -276.585934)
		(end 349.10903 -276.585934)
		(stroke
			(width 0.05715)
			(type default)
		)
		(layer "In11.Cu")
	)
	(gr_line
		(start 349.118682 -422.920668)
		(end 348.716854 -423.064432)
		(stroke
			(width 0.07112)
			(type default)
		)
		(layer "In11.Cu")
	)
	(gr_line
		(start 349.121984 -274.978876)
		(end 349.03918 -274.896072)
		(stroke
			(width 0.05715)
			(type default)
		)
		(layer "In11.Cu")
	)
	(gr_arc
		(start 349.121984 -274.978876)
		(mid 349.123774 -274.990198)
		(end 349.125794 -275.001482)
		(stroke
			(width 0.05715)
			(type default)
		)
		(layer "In11.Cu")
	)
	(gr_line
		(start 349.201232 -422.746424)
		(end 349.118682 -422.920668)
		(stroke
			(width 0.07112)
			(type default)
		)
		(layer "In11.Cu")
	)
	(gr_arc
		(start 349.296482 -278.241252)
		(mid 349.298498 -278.230095)
		(end 349.300292 -278.2189)
		(stroke
			(width 0.05715)
			(type default)
		)
		(layer "In11.Cu")
	)
	(gr_arc
		(start 349.296482 -276.622002)
		(mid 349.298207 -276.61249)
		(end 349.299784 -276.602952)
		(stroke
			(width 0.05715)
			(type default)
		)
		(layer "In11.Cu")
	)
	(gr_line
		(start 349.299784 -276.602952)
		(end 349.383096 -276.516084)
		(stroke
			(width 0.05715)
			(type default)
		)
		(layer "In11.Cu")
	)
	(gr_line
		(start 349.300292 -278.2189)
		(end 349.383096 -278.136096)
		(stroke
			(width 0.05715)
			(type default)
		)
		(layer "In11.Cu")
	)
	(gr_line
		(start 349.314008 -274.96516)
		(end 349.383096 -274.896072)
		(stroke
			(width 0.05715)
			(type default)
		)
		(layer "In11.Cu")
	)
	(gr_line
		(start 349.352362 -296.46372)
		(end 349.352362 -296.435272)
		(stroke
			(width 0.05715)
			(type default)
		)
		(layer "In11.Cu")
	)
	(gr_line
		(start 349.352362 -296.435272)
		(end 349.306642 -296.389552)
		(stroke
			(width 0.05715)
			(type default)
		)
		(layer "In11.Cu")
	)
	(gr_line
		(start 349.379286 -279.278334)
		(end 349.380556 -279.277064)
		(stroke
			(width 0.05715)
			(type default)
		)
		(layer "In11.Cu")
	)
	(gr_line
		(start 349.380556 -279.277064)
		(end 349.38843 -279.273)
		(stroke
			(width 0.05715)
			(type default)
		)
		(layer "In11.Cu")
	)
	(gr_line
		(start 349.383096 -278.136096)
		(end 349.681038 -278.136096)
		(stroke
			(width 0.05715)
			(type default)
		)
		(layer "In11.Cu")
	)
	(gr_line
		(start 349.383096 -276.516084)
		(end 349.681038 -276.516084)
		(stroke
			(width 0.05715)
			(type default)
		)
		(layer "In11.Cu")
	)
	(gr_line
		(start 349.383096 -274.896072)
		(end 349.681038 -274.896072)
		(stroke
			(width 0.05715)
			(type default)
		)
		(layer "In11.Cu")
	)
	(gr_arc
		(start 349.390208 -275.380704)
		(mid 349.389573 -275.380323)
		(end 349.388938 -275.379942)
		(stroke
			(width 0.05715)
			(type default)
		)
		(layer "In11.Cu")
	)
	(gr_line
		(start 349.39732 -275.384768)
		(end 349.397066 -275.384768)
		(stroke
			(width 0.05715)
			(type default)
		)
		(layer "In11.Cu")
	)
	(gr_line
		(start 349.398336 -279.268174)
		(end 349.398844 -279.268174)
		(stroke
			(width 0.05715)
			(type default)
		)
		(layer "In11.Cu")
	)
	(gr_line
		(start 349.398844 -280.244042)
		(end 349.398082 -280.243534)
		(stroke
			(width 0.05715)
			(type default)
		)
		(layer "In11.Cu")
	)
	(gr_line
		(start 349.398844 -279.268174)
		(end 349.400114 -279.267412)
		(stroke
			(width 0.05715)
			(type default)
		)
		(layer "In11.Cu")
	)
	(gr_line
		(start 349.400876 -275.3868)
		(end 349.398336 -275.385276)
		(stroke
			(width 0.05715)
			(type default)
		)
		(layer "In11.Cu")
	)
	(gr_line
		(start 349.471234 -279.446736)
		(end 349.479108 -279.442164)
		(stroke
			(width 0.05715)
			(type default)
		)
		(layer "In11.Cu")
	)
	(gr_line
		(start 349.483934 -279.43937)
		(end 349.493332 -279.434036)
		(stroke
			(width 0.05715)
			(type default)
		)
		(layer "In11.Cu")
	)
	(gr_line
		(start 349.493332 -280.07818)
		(end 349.490538 -280.076656)
		(stroke
			(width 0.05715)
			(type default)
		)
		(layer "In11.Cu")
	)
	(gr_line
		(start 349.493332 -279.434036)
		(end 349.494094 -279.433528)
		(stroke
			(width 0.05715)
			(type default)
		)
		(layer "In11.Cu")
	)
	(gr_line
		(start 349.494094 -280.078688)
		(end 349.493332 -280.07818)
		(stroke
			(width 0.05715)
			(type default)
		)
		(layer "In11.Cu")
	)
	(gr_line
		(start 349.494094 -279.433528)
		(end 349.49511 -279.43302)
		(stroke
			(width 0.05715)
			(type default)
		)
		(layer "In11.Cu")
	)
	(gr_line
		(start 349.49511 -280.079196)
		(end 349.494094 -280.078688)
		(stroke
			(width 0.05715)
			(type default)
		)
		(layer "In11.Cu")
	)
	(gr_line
		(start 349.497142 -280.080212)
		(end 349.49511 -280.079196)
		(stroke
			(width 0.05715)
			(type default)
		)
		(layer "In11.Cu")
	)
	(gr_line
		(start 349.518732 -393.69238)
		(end 349.872046 -393.787376)
		(stroke
			(width 0.07112)
			(type default)
		)
		(layer "In11.Cu")
	)
	(gr_line
		(start 349.52559 -280.096976)
		(end 349.524828 -280.096468)
		(stroke
			(width 0.05715)
			(type default)
		)
		(layer "In11.Cu")
	)
	(gr_line
		(start 349.526352 -280.097484)
		(end 349.52559 -280.096976)
		(stroke
			(width 0.05715)
			(type default)
		)
		(layer "In11.Cu")
	)
	(gr_line
		(start 349.53321 -280.101548)
		(end 349.526352 -280.097484)
		(stroke
			(width 0.05715)
			(type default)
		)
		(layer "In11.Cu")
	)
	(gr_arc
		(start 349.541084 -280.107136)
		(mid 349.537159 -280.104325)
		(end 349.53321 -280.101548)
		(stroke
			(width 0.05715)
			(type default)
		)
		(layer "In11.Cu")
	)
	(gr_line
		(start 349.613982 -422.26865)
		(end 349.613728 -422.26865)
		(stroke
			(width 0.07112)
			(type default)
		)
		(layer "In11.Cu")
	)
	(gr_line
		(start 349.730822 -422.536366)
		(end 349.730314 -422.53662)
		(stroke
			(width 0.07112)
			(type default)
		)
		(layer "In11.Cu")
	)
	(gr_line
		(start 349.742506 -420.952168)
		(end 350.048576 -421.258238)
		(stroke
			(width 0.07112)
			(type default)
		)
		(layer "In11.Cu")
	)
	(gr_arc
		(start 349.82912 -286.581342)
		(mid 349.824404 -286.584619)
		(end 349.819722 -286.587946)
		(stroke
			(width 0.05715)
			(type default)
		)
		(layer "In11.Cu")
	)
	(gr_line
		(start 349.82912 -286.581342)
		(end 349.831152 -286.579818)
		(stroke
			(width 0.05715)
			(type default)
		)
		(layer "In11.Cu")
	)
	(gr_line
		(start 349.831152 -286.579818)
		(end 349.835978 -286.577024)
		(stroke
			(width 0.05715)
			(type default)
		)
		(layer "In11.Cu")
	)
	(gr_line
		(start 349.872046 -393.787376)
		(end 349.872554 -393.786868)
		(stroke
			(width 0.07112)
			(type default)
		)
		(layer "In11.Cu")
	)
	(gr_line
		(start 349.918782 -394.385292)
		(end 350.013524 -394.031724)
		(stroke
			(width 0.07112)
			(type default)
		)
		(layer "In11.Cu")
	)
	(gr_line
		(start 349.963486 -286.723836)
		(end 349.963994 -286.723582)
		(stroke
			(width 0.05715)
			(type default)
		)
		(layer "In11.Cu")
	)
	(gr_line
		(start 350.015302 -296.419016)
		(end 350.015302 -296.390568)
		(stroke
			(width 0.05715)
			(type default)
		)
		(layer "In11.Cu")
	)
	(gr_line
		(start 350.015302 -296.390568)
		(end 350.061022 -296.344848)
		(stroke
			(width 0.05715)
			(type default)
		)
		(layer "In11.Cu")
	)
	(gr_line
		(start 350.13519 -393.961112)
		(end 350.188022 -393.930632)
		(stroke
			(width 0.07112)
			(type default)
		)
		(layer "In11.Cu")
	)
	(gr_line
		(start 350.188022 -393.930632)
		(end 350.27616 -393.842494)
		(stroke
			(width 0.07112)
			(type default)
		)
		(layer "In11.Cu")
	)
	(gr_line
		(start 350.27616 -393.842494)
		(end 350.27616 -393.716764)
		(stroke
			(width 0.07112)
			(type default)
		)
		(layer "In11.Cu")
	)
	(gr_line
		(start 350.297242 -296.419016)
		(end 350.297242 -296.390568)
		(stroke
			(width 0.05715)
			(type default)
		)
		(layer "In11.Cu")
	)
	(gr_line
		(start 350.297242 -296.390568)
		(end 350.251522 -296.344848)
		(stroke
			(width 0.05715)
			(type default)
		)
		(layer "In11.Cu")
	)
	(gr_arc
		(start 350.331786 -421.738806)
		(mid 350.331786 -421.73906)
		(end 350.331786 -421.739314)
		(stroke
			(width 0.07112)
			(type default)
		)
		(layer "In11.Cu")
	)
	(gr_line
		(start 350.331786 -421.226488)
		(end 350.331786 -421.259508)
		(stroke
			(width 0.07112)
			(type default)
		)
		(layer "In11.Cu")
	)
	(gr_line
		(start 350.33204 -280.239978)
		(end 350.331024 -280.239216)
		(stroke
			(width 0.05715)
			(type default)
		)
		(layer "In11.Cu")
	)
	(gr_line
		(start 350.332294 -279.272238)
		(end 350.335596 -279.270206)
		(stroke
			(width 0.05715)
			(type default)
		)
		(layer "In11.Cu")
	)
	(gr_line
		(start 350.33458 -280.241502)
		(end 350.33204 -280.239978)
		(stroke
			(width 0.05715)
			(type default)
		)
		(layer "In11.Cu")
	)
	(gr_line
		(start 350.335596 -280.24201)
		(end 350.33458 -280.241502)
		(stroke
			(width 0.05715)
			(type default)
		)
		(layer "In11.Cu")
	)
	(gr_line
		(start 350.335596 -279.270206)
		(end 350.33712 -279.26919)
		(stroke
			(width 0.05715)
			(type default)
		)
		(layer "In11.Cu")
	)
	(gr_line
		(start 350.33712 -280.243026)
		(end 350.335596 -280.24201)
		(stroke
			(width 0.05715)
			(type default)
		)
		(layer "In11.Cu")
	)
	(gr_line
		(start 350.33712 -279.26919)
		(end 350.338136 -279.268682)
		(stroke
			(width 0.05715)
			(type default)
		)
		(layer "In11.Cu")
	)
	(gr_line
		(start 350.338136 -280.243534)
		(end 350.33712 -280.243026)
		(stroke
			(width 0.05715)
			(type default)
		)
		(layer "In11.Cu")
	)
	(gr_line
		(start 350.338136 -279.268682)
		(end 350.338898 -279.268174)
		(stroke
			(width 0.05715)
			(type default)
		)
		(layer "In11.Cu")
	)
	(gr_line
		(start 350.338898 -280.244042)
		(end 350.338136 -280.243534)
		(stroke
			(width 0.05715)
			(type default)
		)
		(layer "In11.Cu")
	)
	(gr_line
		(start 350.42983 -280.076148)
		(end 350.428306 -280.075386)
		(stroke
			(width 0.05715)
			(type default)
		)
		(layer "In11.Cu")
	)
	(gr_line
		(start 350.430592 -280.076656)
		(end 350.42983 -280.076148)
		(stroke
			(width 0.05715)
			(type default)
		)
		(layer "In11.Cu")
	)
	(gr_line
		(start 350.431608 -279.435052)
		(end 350.433386 -279.434036)
		(stroke
			(width 0.05715)
			(type default)
		)
		(layer "In11.Cu")
	)
	(gr_line
		(start 350.433386 -280.07818)
		(end 350.432878 -280.077926)
		(stroke
			(width 0.05715)
			(type default)
		)
		(layer "In11.Cu")
	)
	(gr_line
		(start 350.433386 -279.434036)
		(end 350.434148 -279.433528)
		(stroke
			(width 0.05715)
			(type default)
		)
		(layer "In11.Cu")
	)
	(gr_line
		(start 350.434148 -280.078688)
		(end 350.433386 -280.07818)
		(stroke
			(width 0.05715)
			(type default)
		)
		(layer "In11.Cu")
	)
	(gr_line
		(start 350.434148 -279.433528)
		(end 350.435164 -279.43302)
		(stroke
			(width 0.05715)
			(type default)
		)
		(layer "In11.Cu")
	)
	(gr_line
		(start 350.435164 -280.079196)
		(end 350.434148 -280.078688)
		(stroke
			(width 0.05715)
			(type default)
		)
		(layer "In11.Cu")
	)
	(gr_line
		(start 350.436434 -280.079958)
		(end 350.435164 -280.079196)
		(stroke
			(width 0.05715)
			(type default)
		)
		(layer "In11.Cu")
	)
	(gr_line
		(start 350.439228 -280.081482)
		(end 350.438212 -280.080974)
		(stroke
			(width 0.05715)
			(type default)
		)
		(layer "In11.Cu")
	)
	(gr_line
		(start 350.465644 -280.096976)
		(end 350.464882 -280.096468)
		(stroke
			(width 0.05715)
			(type default)
		)
		(layer "In11.Cu")
	)
	(gr_line
		(start 350.466406 -280.097484)
		(end 350.465644 -280.096976)
		(stroke
			(width 0.05715)
			(type default)
		)
		(layer "In11.Cu")
	)
	(gr_line
		(start 350.473264 -280.101548)
		(end 350.466406 -280.097484)
		(stroke
			(width 0.05715)
			(type default)
		)
		(layer "In11.Cu")
	)
	(gr_arc
		(start 350.481138 -280.107136)
		(mid 350.477213 -280.104325)
		(end 350.473264 -280.101548)
		(stroke
			(width 0.05715)
			(type default)
		)
		(layer "In11.Cu")
	)
	(gr_line
		(start 350.606106 -420.952168)
		(end 350.331786 -421.226488)
		(stroke
			(width 0.07112)
			(type default)
		)
		(layer "In11.Cu")
	)
	(gr_line
		(start 350.716342 -295.239694)
		(end 350.716596 -295.23944)
		(stroke
			(width 0.05715)
			(type default)
		)
		(layer "In11.Cu")
	)
	(gr_line
		(start 350.718882 -393.69238)
		(end 351.071942 -393.787376)
		(stroke
			(width 0.07112)
			(type default)
		)
		(layer "In11.Cu")
	)
	(gr_arc
		(start 350.769174 -286.581342)
		(mid 350.764457 -286.584619)
		(end 350.759776 -286.587946)
		(stroke
			(width 0.05715)
			(type default)
		)
		(layer "In11.Cu")
	)
	(gr_line
		(start 350.769174 -286.581342)
		(end 350.771206 -286.579818)
		(stroke
			(width 0.05715)
			(type default)
		)
		(layer "In11.Cu")
	)
	(gr_line
		(start 350.771206 -286.579818)
		(end 350.776032 -286.577024)
		(stroke
			(width 0.05715)
			(type default)
		)
		(layer "In11.Cu")
	)
	(gr_line
		(start 350.90354 -286.723836)
		(end 350.904048 -286.723582)
		(stroke
			(width 0.05715)
			(type default)
		)
		(layer "In11.Cu")
	)
	(gr_arc
		(start 350.955102 -376.114056)
		(mid 350.955483 -376.113675)
		(end 350.955864 -376.113294)
		(stroke
			(width 0.07112)
			(type default)
		)
		(layer "In11.Cu")
	)
	(gr_line
		(start 350.960182 -296.419016)
		(end 350.960182 -296.390568)
		(stroke
			(width 0.05715)
			(type default)
		)
		(layer "In11.Cu")
	)
	(gr_line
		(start 350.960182 -296.390568)
		(end 351.005902 -296.344848)
		(stroke
			(width 0.05715)
			(type default)
		)
		(layer "In11.Cu")
	)
	(gr_line
		(start 351.071942 -393.787376)
		(end 351.07245 -393.786868)
		(stroke
			(width 0.07112)
			(type default)
		)
		(layer "In11.Cu")
	)
	(gr_line
		(start 351.118678 -394.385292)
		(end 351.21342 -394.031724)
		(stroke
			(width 0.07112)
			(type default)
		)
		(layer "In11.Cu")
	)
	(gr_arc
		(start 351.2312 -280.215086)
		(mid 351.235125 -280.217897)
		(end 351.239074 -280.220674)
		(stroke
			(width 0.05715)
			(type default)
		)
		(layer "In11.Cu")
	)
	(gr_arc
		(start 351.239836 -280.221182)
		(mid 351.239455 -280.220928)
		(end 351.239074 -280.220674)
		(stroke
			(width 0.05715)
			(type default)
		)
		(layer "In11.Cu")
	)
	(gr_line
		(start 351.242122 -296.419016)
		(end 351.242122 -296.390568)
		(stroke
			(width 0.05715)
			(type default)
		)
		(layer "In11.Cu")
	)
	(gr_line
		(start 351.242122 -296.390568)
		(end 351.196402 -296.344848)
		(stroke
			(width 0.05715)
			(type default)
		)
		(layer "In11.Cu")
	)
	(gr_line
		(start 351.247456 -280.2255)
		(end 351.239836 -280.221182)
		(stroke
			(width 0.05715)
			(type default)
		)
		(layer "In11.Cu")
	)
	(gr_line
		(start 351.272348 -277.652226)
		(end 351.27565 -277.650194)
		(stroke
			(width 0.05715)
			(type default)
		)
		(layer "In11.Cu")
	)
	(gr_line
		(start 351.27565 -277.650194)
		(end 351.277174 -277.649178)
		(stroke
			(width 0.05715)
			(type default)
		)
		(layer "In11.Cu")
	)
	(gr_line
		(start 351.277174 -277.649178)
		(end 351.27819 -277.64867)
		(stroke
			(width 0.05715)
			(type default)
		)
		(layer "In11.Cu")
	)
	(gr_line
		(start 351.27819 -277.64867)
		(end 351.278698 -277.64867)
		(stroke
			(width 0.05715)
			(type default)
		)
		(layer "In11.Cu")
	)
	(gr_line
		(start 351.278698 -277.64867)
		(end 351.279714 -277.648162)
		(stroke
			(width 0.05715)
			(type default)
		)
		(layer "In11.Cu")
	)
	(gr_line
		(start 351.289874 -279.262078)
		(end 351.29089 -279.261316)
		(stroke
			(width 0.05715)
			(type default)
		)
		(layer "In11.Cu")
	)
	(gr_line
		(start 351.335086 -393.961112)
		(end 351.387918 -393.930632)
		(stroke
			(width 0.07112)
			(type default)
		)
		(layer "In11.Cu")
	)
	(gr_line
		(start 351.371662 -277.81504)
		(end 351.37344 -277.814024)
		(stroke
			(width 0.05715)
			(type default)
		)
		(layer "In11.Cu")
	)
	(gr_line
		(start 351.37344 -277.814024)
		(end 351.374202 -277.813516)
		(stroke
			(width 0.05715)
			(type default)
		)
		(layer "In11.Cu")
	)
	(gr_line
		(start 351.374202 -277.813516)
		(end 351.375726 -277.812754)
		(stroke
			(width 0.05715)
			(type default)
		)
		(layer "In11.Cu")
	)
	(gr_arc
		(start 351.383092 -280.083768)
		(mid 351.383473 -280.084022)
		(end 351.383854 -280.084276)
		(stroke
			(width 0.05715)
			(type default)
		)
		(layer "In11.Cu")
	)
	(gr_line
		(start 351.387918 -393.930632)
		(end 351.476056 -393.842494)
		(stroke
			(width 0.07112)
			(type default)
		)
		(layer "In11.Cu")
	)
	(gr_line
		(start 351.40138 -277.797768)
		(end 351.410524 -277.792434)
		(stroke
			(width 0.05715)
			(type default)
		)
		(layer "In11.Cu")
	)
	(gr_arc
		(start 351.411286 -277.791926)
		(mid 351.415747 -277.788646)
		(end 351.420176 -277.785322)
		(stroke
			(width 0.05715)
			(type default)
		)
		(layer "In11.Cu")
	)
	(gr_line
		(start 351.424494 -389.403082)
		(end 351.598992 -389.013446)
		(stroke
			(width 0.07112)
			(type default)
		)
		(layer "In11.Cu")
	)
	(gr_arc
		(start 351.433892 -277.7744)
		(mid 351.437972 -277.771117)
		(end 351.44202 -277.767796)
		(stroke
			(width 0.05715)
			(type default)
		)
		(layer "In11.Cu")
	)
	(gr_arc
		(start 351.44202 -277.767796)
		(mid 351.445077 -277.764757)
		(end 351.448116 -277.7617)
		(stroke
			(width 0.05715)
			(type default)
		)
		(layer "In11.Cu")
	)
	(gr_line
		(start 351.465896 -295.143936)
		(end 351.465896 -295.14165)
		(stroke
			(width 0.05715)
			(type default)
		)
		(layer "In11.Cu")
	)
	(gr_line
		(start 351.465896 -295.14165)
		(end 351.465896 -295.138856)
		(stroke
			(width 0.05715)
			(type default)
		)
		(layer "In11.Cu")
	)
	(gr_arc
		(start 351.465896 -287.045908)
		(mid 351.465892 -287.048067)
		(end 351.465896 -287.050226)
		(stroke
			(width 0.05715)
			(type default)
		)
		(layer "In11.Cu")
	)
	(gr_arc
		(start 351.465896 -277.310088)
		(mid 351.465896 -277.310342)
		(end 351.465896 -277.310596)
		(stroke
			(width 0.05715)
			(type default)
		)
		(layer "In11.Cu")
	)
	(gr_line
		(start 351.465896 -277.310088)
		(end 351.465896 -277.309834)
		(stroke
			(width 0.05715)
			(type default)
		)
		(layer "In11.Cu")
	)
	(gr_line
		(start 351.465896 -277.309834)
		(end 351.465896 -277.309072)
		(stroke
			(width 0.05715)
			(type default)
		)
		(layer "In11.Cu")
	)
	(gr_line
		(start 351.476056 -393.842494)
		(end 351.476056 -393.716764)
		(stroke
			(width 0.07112)
			(type default)
		)
		(layer "In11.Cu")
	)
	(gr_line
		(start 351.493074 -389.58266)
		(end 351.424494 -389.403082)
		(stroke
			(width 0.07112)
			(type default)
		)
		(layer "In11.Cu")
	)
	(gr_line
		(start 351.570544 -386.421884)
		(end 351.74936 -386.03428)
		(stroke
			(width 0.07112)
			(type default)
		)
		(layer "In11.Cu")
	)
	(gr_line
		(start 351.598992 -389.013446)
		(end 351.778824 -388.94512)
		(stroke
			(width 0.07112)
			(type default)
		)
		(layer "In11.Cu")
	)
	(gr_line
		(start 351.636838 -386.602478)
		(end 351.570544 -386.421884)
		(stroke
			(width 0.07112)
			(type default)
		)
		(layer "In11.Cu")
	)
	(gr_line
		(start 351.648522 -277.38959)
		(end 351.648268 -277.390606)
		(stroke
			(width 0.05715)
			(type default)
		)
		(layer "In11.Cu")
	)
	(gr_line
		(start 351.745804 -281.052016)
		(end 351.745042 -281.051508)
		(stroke
			(width 0.05715)
			(type default)
		)
		(layer "In11.Cu")
	)
	(gr_line
		(start 351.74809 -294.658542)
		(end 351.748598 -294.658288)
		(stroke
			(width 0.05715)
			(type default)
		)
		(layer "In11.Cu")
	)
	(gr_line
		(start 351.74809 -278.458676)
		(end 351.748852 -278.458168)
		(stroke
			(width 0.05715)
			(type default)
		)
		(layer "In11.Cu")
	)
	(gr_line
		(start 351.748344 -293.038276)
		(end 351.748852 -293.038022)
		(stroke
			(width 0.05715)
			(type default)
		)
		(layer "In11.Cu")
	)
	(gr_line
		(start 351.748344 -291.418264)
		(end 351.748852 -291.41801)
		(stroke
			(width 0.05715)
			(type default)
		)
		(layer "In11.Cu")
	)
	(gr_line
		(start 351.748344 -289.798252)
		(end 351.748852 -289.797998)
		(stroke
			(width 0.05715)
			(type default)
		)
		(layer "In11.Cu")
	)
	(gr_line
		(start 351.748344 -284.93847)
		(end 351.748852 -284.938216)
		(stroke
			(width 0.05715)
			(type default)
		)
		(layer "In11.Cu")
	)
	(gr_line
		(start 351.748344 -283.318458)
		(end 351.748852 -283.318204)
		(stroke
			(width 0.05715)
			(type default)
		)
		(layer "In11.Cu")
	)
	(gr_line
		(start 351.748344 -281.698446)
		(end 351.748852 -281.698192)
		(stroke
			(width 0.05715)
			(type default)
		)
		(layer "In11.Cu")
	)
	(gr_line
		(start 351.748852 -294.01389)
		(end 351.74809 -294.013382)
		(stroke
			(width 0.05715)
			(type default)
		)
		(layer "In11.Cu")
	)
	(gr_line
		(start 351.748852 -293.038022)
		(end 351.750122 -293.03726)
		(stroke
			(width 0.05715)
			(type default)
		)
		(layer "In11.Cu")
	)
	(gr_line
		(start 351.748852 -292.393878)
		(end 351.74809 -292.39337)
		(stroke
			(width 0.05715)
			(type default)
		)
		(layer "In11.Cu")
	)
	(gr_line
		(start 351.748852 -291.41801)
		(end 351.750122 -291.417248)
		(stroke
			(width 0.05715)
			(type default)
		)
		(layer "In11.Cu")
	)
	(gr_line
		(start 351.748852 -290.773866)
		(end 351.74809 -290.773358)
		(stroke
			(width 0.05715)
			(type default)
		)
		(layer "In11.Cu")
	)
	(gr_line
		(start 351.748852 -289.797998)
		(end 351.750122 -289.797236)
		(stroke
			(width 0.05715)
			(type default)
		)
		(layer "In11.Cu")
	)
	(gr_line
		(start 351.748852 -285.914084)
		(end 351.74809 -285.913576)
		(stroke
			(width 0.05715)
			(type default)
		)
		(layer "In11.Cu")
	)
	(gr_line
		(start 351.748852 -284.938216)
		(end 351.750122 -284.937454)
		(stroke
			(width 0.05715)
			(type default)
		)
		(layer "In11.Cu")
	)
	(gr_line
		(start 351.748852 -284.294072)
		(end 351.74809 -284.293564)
		(stroke
			(width 0.05715)
			(type default)
		)
		(layer "In11.Cu")
	)
	(gr_line
		(start 351.748852 -283.318204)
		(end 351.750122 -283.317442)
		(stroke
			(width 0.05715)
			(type default)
		)
		(layer "In11.Cu")
	)
	(gr_line
		(start 351.748852 -282.67406)
		(end 351.74809 -282.673552)
		(stroke
			(width 0.05715)
			(type default)
		)
		(layer "In11.Cu")
	)
	(gr_line
		(start 351.748852 -281.698192)
		(end 351.750122 -281.69743)
		(stroke
			(width 0.05715)
			(type default)
		)
		(layer "In11.Cu")
	)
	(gr_line
		(start 351.748852 -281.054048)
		(end 351.745804 -281.052016)
		(stroke
			(width 0.05715)
			(type default)
		)
		(layer "In11.Cu")
	)
	(gr_line
		(start 351.748852 -278.458168)
		(end 351.750122 -278.457406)
		(stroke
			(width 0.05715)
			(type default)
		)
		(layer "In11.Cu")
	)
	(gr_line
		(start 351.74936 -386.03428)
		(end 351.929954 -385.967986)
		(stroke
			(width 0.07112)
			(type default)
		)
		(layer "In11.Cu")
	)
	(gr_line
		(start 351.749614 -281.054556)
		(end 351.748852 -281.054048)
		(stroke
			(width 0.05715)
			(type default)
		)
		(layer "In11.Cu")
	)
	(gr_line
		(start 351.750122 -294.014652)
		(end 351.748852 -294.01389)
		(stroke
			(width 0.05715)
			(type default)
		)
		(layer "In11.Cu")
	)
	(gr_line
		(start 351.750122 -292.39464)
		(end 351.748852 -292.393878)
		(stroke
			(width 0.05715)
			(type default)
		)
		(layer "In11.Cu")
	)
	(gr_line
		(start 351.750122 -290.774628)
		(end 351.748852 -290.773866)
		(stroke
			(width 0.05715)
			(type default)
		)
		(layer "In11.Cu")
	)
	(gr_line
		(start 351.750122 -285.914846)
		(end 351.748852 -285.914084)
		(stroke
			(width 0.05715)
			(type default)
		)
		(layer "In11.Cu")
	)
	(gr_line
		(start 351.750122 -284.294834)
		(end 351.748852 -284.294072)
		(stroke
			(width 0.05715)
			(type default)
		)
		(layer "In11.Cu")
	)
	(gr_line
		(start 351.750122 -282.674822)
		(end 351.748852 -282.67406)
		(stroke
			(width 0.05715)
			(type default)
		)
		(layer "In11.Cu")
	)
	(gr_line
		(start 351.750884 -389.6995)
		(end 352.03765 -389.059674)
		(stroke
			(width 0.07112)
			(type default)
		)
		(layer "In11.Cu")
	)
	(gr_line
		(start 351.754186 -294.016938)
		(end 351.752662 -294.015922)
		(stroke
			(width 0.05715)
			(type default)
		)
		(layer "In11.Cu")
	)
	(gr_line
		(start 351.754186 -292.396926)
		(end 351.752662 -292.39591)
		(stroke
			(width 0.05715)
			(type default)
		)
		(layer "In11.Cu")
	)
	(gr_line
		(start 351.754186 -290.776914)
		(end 351.752662 -290.775898)
		(stroke
			(width 0.05715)
			(type default)
		)
		(layer "In11.Cu")
	)
	(gr_line
		(start 351.754186 -285.917132)
		(end 351.752662 -285.916116)
		(stroke
			(width 0.05715)
			(type default)
		)
		(layer "In11.Cu")
	)
	(gr_line
		(start 351.754186 -284.29712)
		(end 351.752662 -284.296104)
		(stroke
			(width 0.05715)
			(type default)
		)
		(layer "In11.Cu")
	)
	(gr_line
		(start 351.754186 -282.677108)
		(end 351.752662 -282.676092)
		(stroke
			(width 0.05715)
			(type default)
		)
		(layer "In11.Cu")
	)
	(gr_line
		(start 351.754186 -281.057096)
		(end 351.752662 -281.05608)
		(stroke
			(width 0.05715)
			(type default)
		)
		(layer "In11.Cu")
	)
	(gr_line
		(start 351.75571 -294.0177)
		(end 351.754186 -294.016938)
		(stroke
			(width 0.05715)
			(type default)
		)
		(layer "In11.Cu")
	)
	(gr_line
		(start 351.75571 -292.397688)
		(end 351.754186 -292.396926)
		(stroke
			(width 0.05715)
			(type default)
		)
		(layer "In11.Cu")
	)
	(gr_line
		(start 351.75571 -290.777676)
		(end 351.754186 -290.776914)
		(stroke
			(width 0.05715)
			(type default)
		)
		(layer "In11.Cu")
	)
	(gr_line
		(start 351.75571 -285.917894)
		(end 351.754186 -285.917132)
		(stroke
			(width 0.05715)
			(type default)
		)
		(layer "In11.Cu")
	)
	(gr_line
		(start 351.75571 -284.297882)
		(end 351.754186 -284.29712)
		(stroke
			(width 0.05715)
			(type default)
		)
		(layer "In11.Cu")
	)
	(gr_line
		(start 351.75571 -282.67787)
		(end 351.754186 -282.677108)
		(stroke
			(width 0.05715)
			(type default)
		)
		(layer "In11.Cu")
	)
	(gr_line
		(start 351.75571 -281.057858)
		(end 351.754186 -281.057096)
		(stroke
			(width 0.05715)
			(type default)
		)
		(layer "In11.Cu")
	)
	(gr_line
		(start 351.780602 -388.944358)
		(end 351.780348 -388.944358)
		(stroke
			(width 0.07112)
			(type default)
		)
		(layer "In11.Cu")
	)
	(gr_line
		(start 351.840038 -280.886408)
		(end 351.838768 -280.885646)
		(stroke
			(width 0.05715)
			(type default)
		)
		(layer "In11.Cu")
	)
	(gr_line
		(start 351.84334 -280.888186)
		(end 351.840038 -280.886408)
		(stroke
			(width 0.05715)
			(type default)
		)
		(layer "In11.Cu")
	)
	(gr_line
		(start 351.843594 -278.623522)
		(end 351.844102 -278.623522)
		(stroke
			(width 0.05715)
			(type default)
		)
		(layer "In11.Cu")
	)
	(gr_line
		(start 351.844102 -293.203376)
		(end 351.845118 -293.202868)
		(stroke
			(width 0.05715)
			(type default)
		)
		(layer "In11.Cu")
	)
	(gr_line
		(start 351.844102 -291.583364)
		(end 351.845118 -291.582856)
		(stroke
			(width 0.05715)
			(type default)
		)
		(layer "In11.Cu")
	)
	(gr_line
		(start 351.844102 -289.963352)
		(end 351.845118 -289.962844)
		(stroke
			(width 0.05715)
			(type default)
		)
		(layer "In11.Cu")
	)
	(gr_line
		(start 351.844102 -285.10357)
		(end 351.845118 -285.103062)
		(stroke
			(width 0.05715)
			(type default)
		)
		(layer "In11.Cu")
	)
	(gr_line
		(start 351.844102 -283.483558)
		(end 351.845118 -283.48305)
		(stroke
			(width 0.05715)
			(type default)
		)
		(layer "In11.Cu")
	)
	(gr_line
		(start 351.844102 -281.863546)
		(end 351.845118 -281.863038)
		(stroke
			(width 0.05715)
			(type default)
		)
		(layer "In11.Cu")
	)
	(gr_line
		(start 351.844102 -280.888694)
		(end 351.84334 -280.888186)
		(stroke
			(width 0.05715)
			(type default)
		)
		(layer "In11.Cu")
	)
	(gr_line
		(start 351.844102 -278.623522)
		(end 351.845118 -278.623014)
		(stroke
			(width 0.05715)
			(type default)
		)
		(layer "In11.Cu")
	)
	(gr_line
		(start 351.845118 -280.889202)
		(end 351.844102 -280.888694)
		(stroke
			(width 0.05715)
			(type default)
		)
		(layer "In11.Cu")
	)
	(gr_line
		(start 351.846896 -280.890218)
		(end 351.845118 -280.889202)
		(stroke
			(width 0.05715)
			(type default)
		)
		(layer "In11.Cu")
	)
	(gr_line
		(start 351.849182 -293.851584)
		(end 351.84842 -293.851076)
		(stroke
			(width 0.05715)
			(type default)
		)
		(layer "In11.Cu")
	)
	(gr_line
		(start 351.849182 -292.231572)
		(end 351.84842 -292.231064)
		(stroke
			(width 0.05715)
			(type default)
		)
		(layer "In11.Cu")
	)
	(gr_line
		(start 351.849182 -290.61156)
		(end 351.84842 -290.611052)
		(stroke
			(width 0.05715)
			(type default)
		)
		(layer "In11.Cu")
	)
	(gr_line
		(start 351.849182 -285.751778)
		(end 351.84842 -285.75127)
		(stroke
			(width 0.05715)
			(type default)
		)
		(layer "In11.Cu")
	)
	(gr_line
		(start 351.849182 -284.131766)
		(end 351.84842 -284.131258)
		(stroke
			(width 0.05715)
			(type default)
		)
		(layer "In11.Cu")
	)
	(gr_line
		(start 351.849182 -282.511754)
		(end 351.84842 -282.511246)
		(stroke
			(width 0.05715)
			(type default)
		)
		(layer "In11.Cu")
	)
	(gr_line
		(start 351.849182 -280.891742)
		(end 351.84842 -280.891234)
		(stroke
			(width 0.05715)
			(type default)
		)
		(layer "In11.Cu")
	)
	(gr_line
		(start 351.859088 -278.136096)
		(end 351.561146 -278.136096)
		(stroke
			(width 0.05715)
			(type default)
		)
		(layer "In11.Cu")
	)
	(gr_line
		(start 351.859088 -276.516084)
		(end 351.561146 -276.516084)
		(stroke
			(width 0.05715)
			(type default)
		)
		(layer "In11.Cu")
	)
	(gr_line
		(start 351.859088 -274.896072)
		(end 351.561146 -274.896072)
		(stroke
			(width 0.05715)
			(type default)
		)
		(layer "In11.Cu")
	)
	(gr_line
		(start 351.875598 -293.866824)
		(end 351.874836 -293.866316)
		(stroke
			(width 0.05715)
			(type default)
		)
		(layer "In11.Cu")
	)
	(gr_line
		(start 351.875598 -292.246812)
		(end 351.874836 -292.246304)
		(stroke
			(width 0.05715)
			(type default)
		)
		(layer "In11.Cu")
	)
	(gr_line
		(start 351.875598 -290.6268)
		(end 351.874836 -290.626292)
		(stroke
			(width 0.05715)
			(type default)
		)
		(layer "In11.Cu")
	)
	(gr_line
		(start 351.875598 -285.767018)
		(end 351.874836 -285.76651)
		(stroke
			(width 0.05715)
			(type default)
		)
		(layer "In11.Cu")
	)
	(gr_line
		(start 351.875598 -284.147006)
		(end 351.874836 -284.146498)
		(stroke
			(width 0.05715)
			(type default)
		)
		(layer "In11.Cu")
	)
	(gr_line
		(start 351.875598 -282.526994)
		(end 351.874836 -282.526486)
		(stroke
			(width 0.05715)
			(type default)
		)
		(layer "In11.Cu")
	)
	(gr_line
		(start 351.875598 -280.906982)
		(end 351.874836 -280.906474)
		(stroke
			(width 0.05715)
			(type default)
		)
		(layer "In11.Cu")
	)
	(gr_line
		(start 351.87636 -293.867332)
		(end 351.875598 -293.866824)
		(stroke
			(width 0.05715)
			(type default)
		)
		(layer "In11.Cu")
	)
	(gr_line
		(start 351.87636 -292.24732)
		(end 351.875598 -292.246812)
		(stroke
			(width 0.05715)
			(type default)
		)
		(layer "In11.Cu")
	)
	(gr_line
		(start 351.87636 -290.627308)
		(end 351.875598 -290.6268)
		(stroke
			(width 0.05715)
			(type default)
		)
		(layer "In11.Cu")
	)
	(gr_line
		(start 351.87636 -285.767526)
		(end 351.875598 -285.767018)
		(stroke
			(width 0.05715)
			(type default)
		)
		(layer "In11.Cu")
	)
	(gr_line
		(start 351.87636 -284.147514)
		(end 351.875598 -284.147006)
		(stroke
			(width 0.05715)
			(type default)
		)
		(layer "In11.Cu")
	)
	(gr_line
		(start 351.87636 -282.527502)
		(end 351.875598 -282.526994)
		(stroke
			(width 0.05715)
			(type default)
		)
		(layer "In11.Cu")
	)
	(gr_line
		(start 351.87636 -280.90749)
		(end 351.875598 -280.906982)
		(stroke
			(width 0.05715)
			(type default)
		)
		(layer "In11.Cu")
	)
	(gr_line
		(start 351.882456 -289.010852)
		(end 351.875344 -289.006788)
		(stroke
			(width 0.05715)
			(type default)
		)
		(layer "In11.Cu")
	)
	(gr_arc
		(start 351.882456 -289.010852)
		(mid 351.882837 -289.011106)
		(end 351.883218 -289.01136)
		(stroke
			(width 0.05715)
			(type default)
		)
		(layer "In11.Cu")
	)
	(gr_line
		(start 351.883218 -293.871396)
		(end 351.87636 -293.867332)
		(stroke
			(width 0.05715)
			(type default)
		)
		(layer "In11.Cu")
	)
	(gr_line
		(start 351.883218 -292.251384)
		(end 351.87636 -292.24732)
		(stroke
			(width 0.05715)
			(type default)
		)
		(layer "In11.Cu")
	)
	(gr_line
		(start 351.883218 -290.631372)
		(end 351.87636 -290.627308)
		(stroke
			(width 0.05715)
			(type default)
		)
		(layer "In11.Cu")
	)
	(gr_line
		(start 351.883218 -285.77159)
		(end 351.87636 -285.767526)
		(stroke
			(width 0.05715)
			(type default)
		)
		(layer "In11.Cu")
	)
	(gr_line
		(start 351.883218 -284.151578)
		(end 351.87636 -284.147514)
		(stroke
			(width 0.05715)
			(type default)
		)
		(layer "In11.Cu")
	)
	(gr_line
		(start 351.883218 -282.531566)
		(end 351.87636 -282.527502)
		(stroke
			(width 0.05715)
			(type default)
		)
		(layer "In11.Cu")
	)
	(gr_line
		(start 351.883218 -280.911554)
		(end 351.87636 -280.90749)
		(stroke
			(width 0.05715)
			(type default)
		)
		(layer "In11.Cu")
	)
	(gr_line
		(start 351.886012 -388.373874)
		(end 352.06051 -387.984238)
		(stroke
			(width 0.07112)
			(type default)
		)
		(layer "In11.Cu")
	)
	(gr_arc
		(start 351.891092 -293.876984)
		(mid 351.887167 -293.874173)
		(end 351.883218 -293.871396)
		(stroke
			(width 0.05715)
			(type default)
		)
		(layer "In11.Cu")
	)
	(gr_arc
		(start 351.891092 -292.256972)
		(mid 351.887167 -292.254161)
		(end 351.883218 -292.251384)
		(stroke
			(width 0.05715)
			(type default)
		)
		(layer "In11.Cu")
	)
	(gr_arc
		(start 351.891092 -290.63696)
		(mid 351.887167 -290.634149)
		(end 351.883218 -290.631372)
		(stroke
			(width 0.05715)
			(type default)
		)
		(layer "In11.Cu")
	)
	(gr_arc
		(start 351.891092 -289.016948)
		(mid 351.887167 -289.014137)
		(end 351.883218 -289.01136)
		(stroke
			(width 0.05715)
			(type default)
		)
		(layer "In11.Cu")
	)
	(gr_arc
		(start 351.891092 -285.777178)
		(mid 351.887167 -285.774367)
		(end 351.883218 -285.77159)
		(stroke
			(width 0.05715)
			(type default)
		)
		(layer "In11.Cu")
	)
	(gr_arc
		(start 351.891092 -284.157166)
		(mid 351.887167 -284.154355)
		(end 351.883218 -284.151578)
		(stroke
			(width 0.05715)
			(type default)
		)
		(layer "In11.Cu")
	)
	(gr_arc
		(start 351.891092 -282.537154)
		(mid 351.887167 -282.534344)
		(end 351.883218 -282.531566)
		(stroke
			(width 0.05715)
			(type default)
		)
		(layer "In11.Cu")
	)
	(gr_arc
		(start 351.891092 -280.917142)
		(mid 351.887167 -280.914331)
		(end 351.883218 -280.911554)
		(stroke
			(width 0.05715)
			(type default)
		)
		(layer "In11.Cu")
	)
	(gr_line
		(start 351.893378 -386.722366)
		(end 352.18751 -386.085334)
		(stroke
			(width 0.07112)
			(type default)
		)
		(layer "In11.Cu")
	)
	(gr_line
		(start 351.918778 -393.69238)
		(end 352.272092 -393.787376)
		(stroke
			(width 0.07112)
			(type default)
		)
		(layer "In11.Cu")
	)
	(gr_line
		(start 351.92843 -278.205438)
		(end 351.859088 -278.136096)
		(stroke
			(width 0.05715)
			(type default)
		)
		(layer "In11.Cu")
	)
	(gr_line
		(start 351.92843 -276.585426)
		(end 351.859088 -276.516084)
		(stroke
			(width 0.05715)
			(type default)
		)
		(layer "In11.Cu")
	)
	(gr_line
		(start 351.931732 -385.967224)
		(end 351.931478 -385.967224)
		(stroke
			(width 0.07112)
			(type default)
		)
		(layer "In11.Cu")
	)
	(gr_line
		(start 351.941892 -274.978876)
		(end 351.859088 -274.896072)
		(stroke
			(width 0.05715)
			(type default)
		)
		(layer "In11.Cu")
	)
	(gr_arc
		(start 351.941892 -274.978876)
		(mid 351.943679 -274.990326)
		(end 351.945702 -275.001736)
		(stroke
			(width 0.05715)
			(type default)
		)
		(layer "In11.Cu")
	)
	(gr_line
		(start 351.954338 -388.553198)
		(end 351.886012 -388.373874)
		(stroke
			(width 0.07112)
			(type default)
		)
		(layer "In11.Cu")
	)
	(gr_line
		(start 351.954846 -388.554976)
		(end 351.9551 -388.554976)
		(stroke
			(width 0.07112)
			(type default)
		)
		(layer "In11.Cu")
	)
	(gr_line
		(start 351.966784 -296.37101)
		(end 351.966784 -296.342562)
		(stroke
			(width 0.05715)
			(type default)
		)
		(layer "In11.Cu")
	)
	(gr_line
		(start 351.966784 -296.342562)
		(end 352.012504 -296.296842)
		(stroke
			(width 0.05715)
			(type default)
		)
		(layer "In11.Cu")
	)
	(gr_line
		(start 352.043492 -385.39801)
		(end 352.222308 -385.010152)
		(stroke
			(width 0.07112)
			(type default)
		)
		(layer "In11.Cu")
	)
	(gr_line
		(start 352.06051 -387.984238)
		(end 352.240088 -387.915912)
		(stroke
			(width 0.07112)
			(type default)
		)
		(layer "In11.Cu")
	)
	(gr_line
		(start 352.109786 -385.578096)
		(end 352.043492 -385.39801)
		(stroke
			(width 0.07112)
			(type default)
		)
		(layer "In11.Cu")
	)
	(gr_line
		(start 352.110294 -385.579874)
		(end 352.110548 -385.579874)
		(stroke
			(width 0.07112)
			(type default)
		)
		(layer "In11.Cu")
	)
	(gr_arc
		(start 352.116644 -278.24176)
		(mid 352.118666 -278.23035)
		(end 352.120454 -278.2189)
		(stroke
			(width 0.05715)
			(type default)
		)
		(layer "In11.Cu")
	)
	(gr_arc
		(start 352.116644 -276.621748)
		(mid 352.118666 -276.610338)
		(end 352.120454 -276.598888)
		(stroke
			(width 0.05715)
			(type default)
		)
		(layer "In11.Cu")
	)
	(gr_line
		(start 352.120454 -278.2189)
		(end 352.203258 -278.136096)
		(stroke
			(width 0.05715)
			(type default)
		)
		(layer "In11.Cu")
	)
	(gr_line
		(start 352.120454 -276.598888)
		(end 352.203258 -276.516084)
		(stroke
			(width 0.05715)
			(type default)
		)
		(layer "In11.Cu")
	)
	(gr_line
		(start 352.133916 -274.965414)
		(end 352.203258 -274.896072)
		(stroke
			(width 0.05715)
			(type default)
		)
		(layer "In11.Cu")
	)
	(gr_line
		(start 352.203258 -278.136096)
		(end 352.5012 -278.136096)
		(stroke
			(width 0.05715)
			(type default)
		)
		(layer "In11.Cu")
	)
	(gr_line
		(start 352.203258 -276.516084)
		(end 352.5012 -276.516084)
		(stroke
			(width 0.05715)
			(type default)
		)
		(layer "In11.Cu")
	)
	(gr_line
		(start 352.203258 -274.896072)
		(end 352.5012 -274.896072)
		(stroke
			(width 0.05715)
			(type default)
		)
		(layer "In11.Cu")
	)
	(gr_line
		(start 352.212148 -388.670292)
		(end 352.499168 -388.030212)
		(stroke
			(width 0.07112)
			(type default)
		)
		(layer "In11.Cu")
	)
	(gr_line
		(start 352.222308 -385.010152)
		(end 352.402648 -384.943858)
		(stroke
			(width 0.07112)
			(type default)
		)
		(layer "In11.Cu")
	)
	(gr_line
		(start 352.24212 -387.91515)
		(end 352.241866 -387.914896)
		(stroke
			(width 0.07112)
			(type default)
		)
		(layer "In11.Cu")
	)
	(gr_line
		(start 352.248724 -296.37101)
		(end 352.248724 -296.342562)
		(stroke
			(width 0.05715)
			(type default)
		)
		(layer "In11.Cu")
	)
	(gr_line
		(start 352.248724 -296.342562)
		(end 352.203004 -296.296842)
		(stroke
			(width 0.05715)
			(type default)
		)
		(layer "In11.Cu")
	)
	(gr_line
		(start 352.272092 -393.787376)
		(end 352.2726 -393.786868)
		(stroke
			(width 0.07112)
			(type default)
		)
		(layer "In11.Cu")
	)
	(gr_line
		(start 352.318828 -394.385292)
		(end 352.41357 -394.031724)
		(stroke
			(width 0.07112)
			(type default)
		)
		(layer "In11.Cu")
	)
	(gr_line
		(start 352.34753 -387.344666)
		(end 352.522028 -386.95503)
		(stroke
			(width 0.07112)
			(type default)
		)
		(layer "In11.Cu")
	)
	(gr_line
		(start 352.366326 -385.697984)
		(end 352.660458 -385.061206)
		(stroke
			(width 0.07112)
			(type default)
		)
		(layer "In11.Cu")
	)
	(gr_line
		(start 352.40468 -384.943096)
		(end 352.404426 -384.943096)
		(stroke
			(width 0.07112)
			(type default)
		)
		(layer "In11.Cu")
	)
	(gr_line
		(start 352.40595 -295.399968)
		(end 352.405696 -295.399714)
		(stroke
			(width 0.05715)
			(type default)
		)
		(layer "In11.Cu")
	)
	(gr_line
		(start 352.415856 -387.523736)
		(end 352.34753 -387.344666)
		(stroke
			(width 0.07112)
			(type default)
		)
		(layer "In11.Cu")
	)
	(gr_line
		(start 352.41611 -387.525768)
		(end 352.416618 -387.525768)
		(stroke
			(width 0.07112)
			(type default)
		)
		(layer "In11.Cu")
	)
	(gr_line
		(start 352.514662 -376.292618)
		(end 352.514916 -376.29211)
		(stroke
			(width 0.07112)
			(type default)
		)
		(layer "In11.Cu")
	)
	(gr_line
		(start 352.51644 -384.373882)
		(end 352.695256 -383.986024)
		(stroke
			(width 0.07112)
			(type default)
		)
		(layer "In11.Cu")
	)
	(gr_line
		(start 352.522028 -386.95503)
		(end 352.701352 -386.886704)
		(stroke
			(width 0.07112)
			(type default)
		)
		(layer "In11.Cu")
	)
	(gr_line
		(start 352.535236 -393.961112)
		(end 352.588068 -393.930632)
		(stroke
			(width 0.07112)
			(type default)
		)
		(layer "In11.Cu")
	)
	(gr_line
		(start 352.582734 -384.553968)
		(end 352.51644 -384.373882)
		(stroke
			(width 0.07112)
			(type default)
		)
		(layer "In11.Cu")
	)
	(gr_line
		(start 352.583242 -384.555746)
		(end 352.583496 -384.555746)
		(stroke
			(width 0.07112)
			(type default)
		)
		(layer "In11.Cu")
	)
	(gr_line
		(start 352.588068 -393.930632)
		(end 352.676206 -393.842494)
		(stroke
			(width 0.07112)
			(type default)
		)
		(layer "In11.Cu")
	)
	(gr_arc
		(start 352.641154 -287.504886)
		(mid 352.64634 -287.508599)
		(end 352.651568 -287.512252)
		(stroke
			(width 0.05715)
			(type default)
		)
		(layer "In11.Cu")
	)
	(gr_line
		(start 352.65614 -287.515046)
		(end 352.651568 -287.512252)
		(stroke
			(width 0.05715)
			(type default)
		)
		(layer "In11.Cu")
	)
	(gr_line
		(start 352.657156 -287.515554)
		(end 352.65614 -287.515046)
		(stroke
			(width 0.05715)
			(type default)
		)
		(layer "In11.Cu")
	)
	(gr_arc
		(start 352.657918 -378.579126)
		(mid 352.65741 -378.578745)
		(end 352.656902 -378.578364)
		(stroke
			(width 0.07112)
			(type default)
		)
		(layer "In11.Cu")
	)
	(gr_line
		(start 352.673666 -387.641084)
		(end 352.960432 -387.001004)
		(stroke
			(width 0.07112)
			(type default)
		)
		(layer "In11.Cu")
	)
	(gr_line
		(start 352.676206 -393.842494)
		(end 352.676206 -393.716764)
		(stroke
			(width 0.07112)
			(type default)
		)
		(layer "In11.Cu")
	)
	(gr_line
		(start 352.676968 -293.045134)
		(end 352.67773 -293.044626)
		(stroke
			(width 0.05715)
			(type default)
		)
		(layer "In11.Cu")
	)
	(gr_line
		(start 352.676968 -291.425122)
		(end 352.67773 -291.424614)
		(stroke
			(width 0.05715)
			(type default)
		)
		(layer "In11.Cu")
	)
	(gr_line
		(start 352.676968 -289.80511)
		(end 352.67773 -289.804602)
		(stroke
			(width 0.05715)
			(type default)
		)
		(layer "In11.Cu")
	)
	(gr_line
		(start 352.679508 -293.04361)
		(end 352.684588 -293.040562)
		(stroke
			(width 0.05715)
			(type default)
		)
		(layer "In11.Cu")
	)
	(gr_line
		(start 352.679508 -291.423598)
		(end 352.684588 -291.42055)
		(stroke
			(width 0.05715)
			(type default)
		)
		(layer "In11.Cu")
	)
	(gr_line
		(start 352.679508 -289.803586)
		(end 352.684588 -289.800538)
		(stroke
			(width 0.05715)
			(type default)
		)
		(layer "In11.Cu")
	)
	(gr_line
		(start 352.684588 -293.040562)
		(end 352.685604 -293.040054)
		(stroke
			(width 0.05715)
			(type default)
		)
		(layer "In11.Cu")
	)
	(gr_line
		(start 352.684588 -291.42055)
		(end 352.685604 -291.420042)
		(stroke
			(width 0.05715)
			(type default)
		)
		(layer "In11.Cu")
	)
	(gr_line
		(start 352.684588 -289.800538)
		(end 352.685604 -289.80003)
		(stroke
			(width 0.05715)
			(type default)
		)
		(layer "In11.Cu")
	)
	(gr_line
		(start 352.685604 -293.040054)
		(end 352.687636 -293.038784)
		(stroke
			(width 0.05715)
			(type default)
		)
		(layer "In11.Cu")
	)
	(gr_line
		(start 352.685604 -291.420042)
		(end 352.687636 -291.418772)
		(stroke
			(width 0.05715)
			(type default)
		)
		(layer "In11.Cu")
	)
	(gr_line
		(start 352.685604 -289.80003)
		(end 352.687636 -289.79876)
		(stroke
			(width 0.05715)
			(type default)
		)
		(layer "In11.Cu")
	)
	(gr_line
		(start 352.687128 -287.53308)
		(end 352.685604 -287.532064)
		(stroke
			(width 0.05715)
			(type default)
		)
		(layer "In11.Cu")
	)
	(gr_line
		(start 352.688398 -292.393624)
		(end 352.687128 -292.392862)
		(stroke
			(width 0.05715)
			(type default)
		)
		(layer "In11.Cu")
	)
	(gr_line
		(start 352.688398 -290.773612)
		(end 352.687128 -290.77285)
		(stroke
			(width 0.05715)
			(type default)
		)
		(layer "In11.Cu")
	)
	(gr_line
		(start 352.688398 -289.1536)
		(end 352.687128 -289.152838)
		(stroke
			(width 0.05715)
			(type default)
		)
		(layer "In11.Cu")
	)
	(gr_line
		(start 352.689668 -287.53435)
		(end 352.687128 -287.53308)
		(stroke
			(width 0.05715)
			(type default)
		)
		(layer "In11.Cu")
	)
	(gr_line
		(start 352.695256 -383.986024)
		(end 352.875596 -383.91973)
		(stroke
			(width 0.07112)
			(type default)
		)
		(layer "In11.Cu")
	)
	(gr_line
		(start 352.703384 -386.885942)
		(end 352.70313 -386.885688)
		(stroke
			(width 0.07112)
			(type default)
		)
		(layer "In11.Cu")
	)
	(gr_line
		(start 352.720656 -294.639746)
		(end 352.720656 -294.639492)
		(stroke
			(width 0.05715)
			(type default)
		)
		(layer "In11.Cu")
	)
	(gr_line
		(start 352.720656 -294.032432)
		(end 352.720656 -294.032178)
		(stroke
			(width 0.05715)
			(type default)
		)
		(layer "In11.Cu")
	)
	(gr_line
		(start 352.7806 -286.725614)
		(end 352.781362 -286.72536)
		(stroke
			(width 0.05715)
			(type default)
		)
		(layer "In11.Cu")
	)
	(gr_line
		(start 352.78187 -293.204646)
		(end 352.783394 -293.203884)
		(stroke
			(width 0.05715)
			(type default)
		)
		(layer "In11.Cu")
	)
	(gr_line
		(start 352.78187 -291.584634)
		(end 352.783394 -291.583872)
		(stroke
			(width 0.05715)
			(type default)
		)
		(layer "In11.Cu")
	)
	(gr_line
		(start 352.78187 -289.964622)
		(end 352.783394 -289.96386)
		(stroke
			(width 0.05715)
			(type default)
		)
		(layer "In11.Cu")
	)
	(gr_line
		(start 352.782124 -287.367218)
		(end 352.781362 -287.366964)
		(stroke
			(width 0.05715)
			(type default)
		)
		(layer "In11.Cu")
	)
	(gr_line
		(start 352.783394 -293.203884)
		(end 352.784156 -293.203376)
		(stroke
			(width 0.05715)
			(type default)
		)
		(layer "In11.Cu")
	)
	(gr_line
		(start 352.783394 -291.583872)
		(end 352.784156 -291.583364)
		(stroke
			(width 0.05715)
			(type default)
		)
		(layer "In11.Cu")
	)
	(gr_line
		(start 352.783394 -289.96386)
		(end 352.784156 -289.963352)
		(stroke
			(width 0.05715)
			(type default)
		)
		(layer "In11.Cu")
	)
	(gr_line
		(start 352.783394 -287.36798)
		(end 352.782124 -287.367218)
		(stroke
			(width 0.05715)
			(type default)
		)
		(layer "In11.Cu")
	)
	(gr_line
		(start 352.783902 -292.22827)
		(end 352.783394 -292.228016)
		(stroke
			(width 0.05715)
			(type default)
		)
		(layer "In11.Cu")
	)
	(gr_line
		(start 352.783902 -290.608258)
		(end 352.783394 -290.608004)
		(stroke
			(width 0.05715)
			(type default)
		)
		(layer "In11.Cu")
	)
	(gr_line
		(start 352.783902 -288.988246)
		(end 352.783394 -288.987992)
		(stroke
			(width 0.05715)
			(type default)
		)
		(layer "In11.Cu")
	)
	(gr_line
		(start 352.783902 -287.368742)
		(end 352.784156 -287.368488)
		(stroke
			(width 0.05715)
			(type default)
		)
		(layer "In11.Cu")
	)
	(gr_line
		(start 352.784156 -287.368488)
		(end 352.783394 -287.36798)
		(stroke
			(width 0.05715)
			(type default)
		)
		(layer "In11.Cu")
	)
	(gr_line
		(start 352.784664 -287.36925)
		(end 352.783902 -287.368742)
		(stroke
			(width 0.05715)
			(type default)
		)
		(layer "In11.Cu")
	)
	(gr_arc
		(start 352.824542 -286.699706)
		(mid 352.827725 -286.697431)
		(end 352.830892 -286.695134)
		(stroke
			(width 0.05715)
			(type default)
		)
		(layer "In11.Cu")
	)
	(gr_line
		(start 352.83267 -293.878)
		(end 352.826574 -293.873428)
		(stroke
			(width 0.05715)
			(type default)
		)
		(layer "In11.Cu")
	)
	(gr_line
		(start 352.839274 -384.673856)
		(end 353.133406 -384.037078)
		(stroke
			(width 0.07112)
			(type default)
		)
		(layer "In11.Cu")
	)
	(gr_line
		(start 352.877628 -383.918968)
		(end 352.877374 -383.918968)
		(stroke
			(width 0.07112)
			(type default)
		)
		(layer "In11.Cu")
	)
	(gr_line
		(start 352.911918 -296.37101)
		(end 352.911918 -296.342562)
		(stroke
			(width 0.05715)
			(type default)
		)
		(layer "In11.Cu")
	)
	(gr_line
		(start 352.911918 -296.342562)
		(end 352.957638 -296.296842)
		(stroke
			(width 0.05715)
			(type default)
		)
		(layer "In11.Cu")
	)
	(gr_line
		(start 353.06635 -286.229552)
		(end 353.06635 -286.236156)
		(stroke
			(width 0.05715)
			(type default)
		)
		(layer "In11.Cu")
	)
	(gr_arc
		(start 353.103434 -280.20899)
		(mid 353.110504 -280.214632)
		(end 353.117658 -280.220166)
		(stroke
			(width 0.05715)
			(type default)
		)
		(layer "In11.Cu")
	)
	(gr_line
		(start 353.118928 -393.69238)
		(end 353.471988 -393.787376)
		(stroke
			(width 0.07112)
			(type default)
		)
		(layer "In11.Cu")
	)
	(gr_line
		(start 353.157282 -279.268682)
		(end 353.158044 -279.268174)
		(stroke
			(width 0.05715)
			(type default)
		)
		(layer "In11.Cu")
	)
	(gr_line
		(start 353.158044 -279.268174)
		(end 353.16033 -279.267158)
		(stroke
			(width 0.05715)
			(type default)
		)
		(layer "In11.Cu")
	)
	(gr_line
		(start 353.164902 -280.248106)
		(end 353.117658 -280.220166)
		(stroke
			(width 0.05715)
			(type default)
		)
		(layer "In11.Cu")
	)
	(gr_line
		(start 353.187 -280.260806)
		(end 353.186746 -280.260806)
		(stroke
			(width 0.05715)
			(type default)
		)
		(layer "In11.Cu")
	)
	(gr_line
		(start 353.193858 -296.37101)
		(end 353.193858 -296.342562)
		(stroke
			(width 0.05715)
			(type default)
		)
		(layer "In11.Cu")
	)
	(gr_line
		(start 353.193858 -296.342562)
		(end 353.148138 -296.296842)
		(stroke
			(width 0.05715)
			(type default)
		)
		(layer "In11.Cu")
	)
	(gr_line
		(start 353.24796 -279.437084)
		(end 353.253294 -279.434036)
		(stroke
			(width 0.05715)
			(type default)
		)
		(layer "In11.Cu")
	)
	(gr_line
		(start 353.253294 -279.434036)
		(end 353.254056 -279.433528)
		(stroke
			(width 0.05715)
			(type default)
		)
		(layer "In11.Cu")
	)
	(gr_line
		(start 353.254056 -279.433528)
		(end 353.255072 -279.43302)
		(stroke
			(width 0.05715)
			(type default)
		)
		(layer "In11.Cu")
	)
	(gr_line
		(start 353.255072 -279.43302)
		(end 353.256088 -279.432512)
		(stroke
			(width 0.05715)
			(type default)
		)
		(layer "In11.Cu")
	)
	(gr_line
		(start 353.280726 -392.768074)
		(end 353.281996 -392.616944)
		(stroke
			(width 0.07112)
			(type default)
		)
		(layer "In11.Cu")
	)
	(gr_line
		(start 353.281996 -392.616944)
		(end 353.388422 -392.510518)
		(stroke
			(width 0.07112)
			(type default)
		)
		(layer "In11.Cu")
	)
	(gr_line
		(start 353.285044 -280.09723)
		(end 353.28352 -280.096214)
		(stroke
			(width 0.05715)
			(type default)
		)
		(layer "In11.Cu")
	)
	(gr_line
		(start 353.28733 -280.098754)
		(end 353.286314 -280.097992)
		(stroke
			(width 0.05715)
			(type default)
		)
		(layer "In11.Cu")
	)
	(gr_line
		(start 353.301808 -378.513848)
		(end 353.301046 -378.513848)
		(stroke
			(width 0.07112)
			(type default)
		)
		(layer "In11.Cu")
	)
	(gr_line
		(start 353.301808 -378.513848)
		(end 353.303078 -378.513848)
		(stroke
			(width 0.07112)
			(type default)
		)
		(layer "In11.Cu")
	)
	(gr_line
		(start 353.373436 -388.479792)
		(end 353.597464 -388.116572)
		(stroke
			(width 0.07112)
			(type default)
		)
		(layer "In11.Cu")
	)
	(gr_line
		(start 353.417632 -388.66699)
		(end 353.373436 -388.479792)
		(stroke
			(width 0.07112)
			(type default)
		)
		(layer "In11.Cu")
	)
	(gr_line
		(start 353.471988 -393.787376)
		(end 353.472496 -393.786868)
		(stroke
			(width 0.07112)
			(type default)
		)
		(layer "In11.Cu")
	)
	(gr_line
		(start 353.518724 -394.385292)
		(end 353.613466 -394.031724)
		(stroke
			(width 0.07112)
			(type default)
		)
		(layer "In11.Cu")
	)
	(gr_line
		(start 353.597464 -388.116572)
		(end 353.784662 -388.072376)
		(stroke
			(width 0.07112)
			(type default)
		)
		(layer "In11.Cu")
	)
	(gr_arc
		(start 353.597718 -392.702034)
		(mid 353.575304 -392.739976)
		(end 353.563936 -392.782552)
		(stroke
			(width 0.07112)
			(type default)
		)
		(layer "In11.Cu")
	)
	(gr_line
		(start 353.657916 -388.816596)
		(end 354.02647 -388.21995)
		(stroke
			(width 0.07112)
			(type default)
		)
		(layer "In11.Cu")
	)
	(gr_line
		(start 353.72294 -288.344102)
		(end 353.723956 -288.343594)
		(stroke
			(width 0.05715)
			(type default)
		)
		(layer "In11.Cu")
	)
	(gr_line
		(start 353.72294 -286.72409)
		(end 353.723956 -286.723582)
		(stroke
			(width 0.05715)
			(type default)
		)
		(layer "In11.Cu")
	)
	(gr_line
		(start 353.723194 -293.20363)
		(end 353.724464 -293.203122)
		(stroke
			(width 0.05715)
			(type default)
		)
		(layer "In11.Cu")
	)
	(gr_line
		(start 353.723194 -291.583618)
		(end 353.724464 -291.58311)
		(stroke
			(width 0.05715)
			(type default)
		)
		(layer "In11.Cu")
	)
	(gr_line
		(start 353.723194 -289.963606)
		(end 353.724464 -289.963098)
		(stroke
			(width 0.05715)
			(type default)
		)
		(layer "In11.Cu")
	)
	(gr_line
		(start 353.723194 -285.103824)
		(end 353.724464 -285.103316)
		(stroke
			(width 0.05715)
			(type default)
		)
		(layer "In11.Cu")
	)
	(gr_line
		(start 353.723194 -283.483812)
		(end 353.724464 -283.483304)
		(stroke
			(width 0.05715)
			(type default)
		)
		(layer "In11.Cu")
	)
	(gr_line
		(start 353.723194 -281.8638)
		(end 353.724464 -281.863292)
		(stroke
			(width 0.05715)
			(type default)
		)
		(layer "In11.Cu")
	)
	(gr_line
		(start 353.723194 -278.623776)
		(end 353.724464 -278.623268)
		(stroke
			(width 0.05715)
			(type default)
		)
		(layer "In11.Cu")
	)
	(gr_line
		(start 353.723956 -285.74873)
		(end 353.723448 -285.748476)
		(stroke
			(width 0.05715)
			(type default)
		)
		(layer "In11.Cu")
	)
	(gr_line
		(start 353.724972 -293.849044)
		(end 353.723194 -293.848282)
		(stroke
			(width 0.05715)
			(type default)
		)
		(layer "In11.Cu")
	)
	(gr_line
		(start 353.724972 -292.229032)
		(end 353.723194 -292.22827)
		(stroke
			(width 0.05715)
			(type default)
		)
		(layer "In11.Cu")
	)
	(gr_line
		(start 353.724972 -290.60902)
		(end 353.723194 -290.608258)
		(stroke
			(width 0.05715)
			(type default)
		)
		(layer "In11.Cu")
	)
	(gr_line
		(start 353.724972 -288.989008)
		(end 353.723194 -288.988246)
		(stroke
			(width 0.05715)
			(type default)
		)
		(layer "In11.Cu")
	)
	(gr_line
		(start 353.724972 -284.129226)
		(end 353.723194 -284.128464)
		(stroke
			(width 0.05715)
			(type default)
		)
		(layer "In11.Cu")
	)
	(gr_line
		(start 353.724972 -282.509214)
		(end 353.723194 -282.508452)
		(stroke
			(width 0.05715)
			(type default)
		)
		(layer "In11.Cu")
	)
	(gr_line
		(start 353.72929 -280.891742)
		(end 353.725226 -280.889456)
		(stroke
			(width 0.05715)
			(type default)
		)
		(layer "In11.Cu")
	)
	(gr_line
		(start 353.735132 -393.961112)
		(end 353.787964 -393.930632)
		(stroke
			(width 0.07112)
			(type default)
		)
		(layer "In11.Cu")
	)
	(gr_line
		(start 353.754944 -285.766764)
		(end 353.754182 -285.766256)
		(stroke
			(width 0.05715)
			(type default)
		)
		(layer "In11.Cu")
	)
	(gr_line
		(start 353.787964 -393.930632)
		(end 353.876102 -393.842494)
		(stroke
			(width 0.07112)
			(type default)
		)
		(layer "In11.Cu")
	)
	(gr_line
		(start 353.857052 -296.286682)
		(end 353.857052 -296.258234)
		(stroke
			(width 0.05715)
			(type default)
		)
		(layer "In11.Cu")
	)
	(gr_line
		(start 353.857052 -296.258234)
		(end 353.902772 -296.212514)
		(stroke
			(width 0.05715)
			(type default)
		)
		(layer "In11.Cu")
	)
	(gr_line
		(start 353.876102 -393.842494)
		(end 353.876102 -393.716764)
		(stroke
			(width 0.07112)
			(type default)
		)
		(layer "In11.Cu")
	)
	(gr_line
		(start 353.965764 -387.52018)
		(end 354.190046 -387.156706)
		(stroke
			(width 0.07112)
			(type default)
		)
		(layer "In11.Cu")
	)
	(gr_line
		(start 354.00996 -387.707378)
		(end 353.965764 -387.52018)
		(stroke
			(width 0.07112)
			(type default)
		)
		(layer "In11.Cu")
	)
	(gr_line
		(start 354.088192 -280.237692)
		(end 354.087684 -280.237438)
		(stroke
			(width 0.05715)
			(type default)
		)
		(layer "In11.Cu")
	)
	(gr_line
		(start 354.090732 -277.652988)
		(end 354.094034 -277.650956)
		(stroke
			(width 0.05715)
			(type default)
		)
		(layer "In11.Cu")
	)
	(gr_line
		(start 354.094034 -277.650956)
		(end 354.094542 -277.650702)
		(stroke
			(width 0.05715)
			(type default)
		)
		(layer "In11.Cu")
	)
	(gr_line
		(start 354.094542 -280.241502)
		(end 354.090732 -280.239216)
		(stroke
			(width 0.05715)
			(type default)
		)
		(layer "In11.Cu")
	)
	(gr_line
		(start 354.094542 -277.650702)
		(end 354.098098 -277.648162)
		(stroke
			(width 0.05715)
			(type default)
		)
		(layer "In11.Cu")
	)
	(gr_line
		(start 354.095558 -280.24201)
		(end 354.094542 -280.241502)
		(stroke
			(width 0.05715)
			(type default)
		)
		(layer "In11.Cu")
	)
	(gr_line
		(start 354.097082 -280.243026)
		(end 354.095558 -280.24201)
		(stroke
			(width 0.05715)
			(type default)
		)
		(layer "In11.Cu")
	)
	(gr_line
		(start 354.098098 -280.243534)
		(end 354.097082 -280.243026)
		(stroke
			(width 0.05715)
			(type default)
		)
		(layer "In11.Cu")
	)
	(gr_line
		(start 354.098098 -279.268682)
		(end 354.09886 -279.268174)
		(stroke
			(width 0.05715)
			(type default)
		)
		(layer "In11.Cu")
	)
	(gr_line
		(start 354.098098 -277.648162)
		(end 354.099114 -277.647654)
		(stroke
			(width 0.05715)
			(type default)
		)
		(layer "In11.Cu")
	)
	(gr_line
		(start 354.09886 -279.268174)
		(end 354.10013 -279.267412)
		(stroke
			(width 0.05715)
			(type default)
		)
		(layer "In11.Cu")
	)
	(gr_line
		(start 354.10013 -279.267412)
		(end 354.10267 -279.266142)
		(stroke
			(width 0.05715)
			(type default)
		)
		(layer "In11.Cu")
	)
	(gr_line
		(start 354.138992 -296.286682)
		(end 354.138992 -296.258234)
		(stroke
			(width 0.05715)
			(type default)
		)
		(layer "In11.Cu")
	)
	(gr_line
		(start 354.138992 -296.258234)
		(end 354.093272 -296.212514)
		(stroke
			(width 0.05715)
			(type default)
		)
		(layer "In11.Cu")
	)
	(gr_line
		(start 354.18522 -280.073608)
		(end 354.183696 -280.072846)
		(stroke
			(width 0.05715)
			(type default)
		)
		(layer "In11.Cu")
	)
	(gr_line
		(start 354.189792 -277.816056)
		(end 354.190554 -277.815548)
		(stroke
			(width 0.05715)
			(type default)
		)
		(layer "In11.Cu")
	)
	(gr_line
		(start 354.190046 -387.156706)
		(end 354.377244 -387.11251)
		(stroke
			(width 0.07112)
			(type default)
		)
		(layer "In11.Cu")
	)
	(gr_line
		(start 354.190554 -280.076656)
		(end 354.189792 -280.076148)
		(stroke
			(width 0.05715)
			(type default)
		)
		(layer "In11.Cu")
	)
	(gr_line
		(start 354.190554 -277.815548)
		(end 354.193348 -277.814024)
		(stroke
			(width 0.05715)
			(type default)
		)
		(layer "In11.Cu")
	)
	(gr_line
		(start 354.192078 -279.434798)
		(end 354.193348 -279.434036)
		(stroke
			(width 0.05715)
			(type default)
		)
		(layer "In11.Cu")
	)
	(gr_line
		(start 354.193348 -280.07818)
		(end 354.190554 -280.076656)
		(stroke
			(width 0.05715)
			(type default)
		)
		(layer "In11.Cu")
	)
	(gr_line
		(start 354.193348 -279.434036)
		(end 354.19411 -279.433528)
		(stroke
			(width 0.05715)
			(type default)
		)
		(layer "In11.Cu")
	)
	(gr_line
		(start 354.193348 -277.814024)
		(end 354.19411 -277.813516)
		(stroke
			(width 0.05715)
			(type default)
		)
		(layer "In11.Cu")
	)
	(gr_line
		(start 354.19411 -280.078688)
		(end 354.193348 -280.07818)
		(stroke
			(width 0.05715)
			(type default)
		)
		(layer "In11.Cu")
	)
	(gr_line
		(start 354.19411 -279.433528)
		(end 354.195126 -279.43302)
		(stroke
			(width 0.05715)
			(type default)
		)
		(layer "In11.Cu")
	)
	(gr_line
		(start 354.19411 -277.813516)
		(end 354.195126 -277.813008)
		(stroke
			(width 0.05715)
			(type default)
		)
		(layer "In11.Cu")
	)
	(gr_line
		(start 354.195126 -279.43302)
		(end 354.196396 -279.432258)
		(stroke
			(width 0.05715)
			(type default)
		)
		(layer "In11.Cu")
	)
	(gr_line
		(start 354.195126 -277.813008)
		(end 354.19665 -277.811992)
		(stroke
			(width 0.05715)
			(type default)
		)
		(layer "In11.Cu")
	)
	(gr_line
		(start 354.196396 -279.432258)
		(end 354.197158 -279.43175)
		(stroke
			(width 0.05715)
			(type default)
		)
		(layer "In11.Cu")
	)
	(gr_line
		(start 354.19665 -277.811992)
		(end 354.201222 -277.809198)
		(stroke
			(width 0.05715)
			(type default)
		)
		(layer "In11.Cu")
	)
	(gr_line
		(start 354.250498 -387.856984)
		(end 354.619052 -387.25983)
		(stroke
			(width 0.07112)
			(type default)
		)
		(layer "In11.Cu")
	)
	(gr_line
		(start 354.318824 -393.69238)
		(end 354.672138 -393.787376)
		(stroke
			(width 0.07112)
			(type default)
		)
		(layer "In11.Cu")
	)
	(gr_line
		(start 354.378768 -387.112002)
		(end 354.379022 -387.111748)
		(stroke
			(width 0.07112)
			(type default)
		)
		(layer "In11.Cu")
	)
	(gr_line
		(start 354.379022 -387.112002)
		(end 354.378768 -387.112002)
		(stroke
			(width 0.07112)
			(type default)
		)
		(layer "In11.Cu")
	)
	(gr_arc
		(start 354.529136 -286.581342)
		(mid 354.52442 -286.584619)
		(end 354.519738 -286.587946)
		(stroke
			(width 0.05715)
			(type default)
		)
		(layer "In11.Cu")
	)
	(gr_line
		(start 354.529136 -286.581342)
		(end 354.531168 -286.579818)
		(stroke
			(width 0.05715)
			(type default)
		)
		(layer "In11.Cu")
	)
	(gr_line
		(start 354.531168 -286.579818)
		(end 354.535994 -286.577024)
		(stroke
			(width 0.05715)
			(type default)
		)
		(layer "In11.Cu")
	)
	(gr_line
		(start 354.54336 -294.67302)
		(end 354.543868 -294.672766)
		(stroke
			(width 0.05715)
			(type default)
		)
		(layer "In11.Cu")
	)
	(gr_line
		(start 354.558346 -386.560314)
		(end 354.782628 -386.19684)
		(stroke
			(width 0.07112)
			(type default)
		)
		(layer "In11.Cu")
	)
	(gr_line
		(start 354.602542 -386.747258)
		(end 354.558346 -386.560314)
		(stroke
			(width 0.07112)
			(type default)
		)
		(layer "In11.Cu")
	)
	(gr_line
		(start 354.602796 -386.749036)
		(end 354.60305 -386.749036)
		(stroke
			(width 0.07112)
			(type default)
		)
		(layer "In11.Cu")
	)
	(gr_line
		(start 354.663248 -277.003764)
		(end 354.664518 -277.003256)
		(stroke
			(width 0.05715)
			(type default)
		)
		(layer "In11.Cu")
	)
	(gr_line
		(start 354.663502 -286.723836)
		(end 354.66401 -286.723582)
		(stroke
			(width 0.05715)
			(type default)
		)
		(layer "In11.Cu")
	)
	(gr_line
		(start 354.672138 -393.787376)
		(end 354.672646 -393.786868)
		(stroke
			(width 0.07112)
			(type default)
		)
		(layer "In11.Cu")
	)
	(gr_line
		(start 354.678996 -279.756108)
		(end 354.381054 -279.756108)
		(stroke
			(width 0.05715)
			(type default)
		)
		(layer "In11.Cu")
	)
	(gr_line
		(start 354.678996 -278.136096)
		(end 354.381054 -278.136096)
		(stroke
			(width 0.05715)
			(type default)
		)
		(layer "In11.Cu")
	)
	(gr_line
		(start 354.678996 -276.516084)
		(end 354.381054 -276.516084)
		(stroke
			(width 0.05715)
			(type default)
		)
		(layer "In11.Cu")
	)
	(gr_line
		(start 354.678996 -274.896072)
		(end 354.381054 -274.896072)
		(stroke
			(width 0.05715)
			(type default)
		)
		(layer "In11.Cu")
	)
	(gr_line
		(start 354.694744 -294.805608)
		(end 354.701602 -294.801544)
		(stroke
			(width 0.05715)
			(type default)
		)
		(layer "In11.Cu")
	)
	(gr_arc
		(start 354.701602 -294.801544)
		(mid 354.702364 -294.801037)
		(end 354.703126 -294.800528)
		(stroke
			(width 0.05715)
			(type default)
		)
		(layer "In11.Cu")
	)
	(gr_arc
		(start 354.703126 -294.800528)
		(mid 354.706309 -294.798253)
		(end 354.709476 -294.795956)
		(stroke
			(width 0.05715)
			(type default)
		)
		(layer "In11.Cu")
	)
	(gr_line
		(start 354.718874 -394.385292)
		(end 354.81387 -394.031216)
		(stroke
			(width 0.07112)
			(type default)
		)
		(layer "In11.Cu")
	)
	(gr_line
		(start 354.748338 -278.205438)
		(end 354.678996 -278.136096)
		(stroke
			(width 0.05715)
			(type default)
		)
		(layer "In11.Cu")
	)
	(gr_line
		(start 354.748338 -276.585426)
		(end 354.678996 -276.516084)
		(stroke
			(width 0.05715)
			(type default)
		)
		(layer "In11.Cu")
	)
	(gr_line
		(start 354.7618 -279.838912)
		(end 354.678996 -279.756108)
		(stroke
			(width 0.05715)
			(type default)
		)
		(layer "In11.Cu")
	)
	(gr_arc
		(start 354.7618 -279.838912)
		(mid 354.763593 -279.850234)
		(end 354.76561 -279.861518)
		(stroke
			(width 0.05715)
			(type default)
		)
		(layer "In11.Cu")
	)
	(gr_line
		(start 354.7618 -274.978876)
		(end 354.678996 -274.896072)
		(stroke
			(width 0.05715)
			(type default)
		)
		(layer "In11.Cu")
	)
	(gr_arc
		(start 354.7618 -274.978876)
		(mid 354.763592 -274.990198)
		(end 354.76561 -275.001482)
		(stroke
			(width 0.05715)
			(type default)
		)
		(layer "In11.Cu")
	)
	(gr_line
		(start 354.782628 -386.19684)
		(end 354.969826 -386.152644)
		(stroke
			(width 0.07112)
			(type default)
		)
		(layer "In11.Cu")
	)
	(gr_line
		(start 354.84308 -386.897118)
		(end 355.211634 -386.299964)
		(stroke
			(width 0.07112)
			(type default)
		)
		(layer "In11.Cu")
	)
	(gr_arc
		(start 354.936552 -278.24176)
		(mid 354.938574 -278.23035)
		(end 354.940362 -278.2189)
		(stroke
			(width 0.05715)
			(type default)
		)
		(layer "In11.Cu")
	)
	(gr_arc
		(start 354.936552 -276.621748)
		(mid 354.938574 -276.610338)
		(end 354.940362 -276.598888)
		(stroke
			(width 0.05715)
			(type default)
		)
		(layer "In11.Cu")
	)
	(gr_line
		(start 354.940362 -278.2189)
		(end 355.023166 -278.136096)
		(stroke
			(width 0.05715)
			(type default)
		)
		(layer "In11.Cu")
	)
	(gr_line
		(start 354.940362 -276.598888)
		(end 355.023166 -276.516084)
		(stroke
			(width 0.05715)
			(type default)
		)
		(layer "In11.Cu")
	)
	(gr_line
		(start 354.953824 -279.82545)
		(end 355.023166 -279.756108)
		(stroke
			(width 0.05715)
			(type default)
		)
		(layer "In11.Cu")
	)
	(gr_line
		(start 354.953824 -274.965414)
		(end 355.023166 -274.896072)
		(stroke
			(width 0.05715)
			(type default)
		)
		(layer "In11.Cu")
	)
	(gr_line
		(start 354.954332 -296.61231)
		(end 354.954332 -296.583862)
		(stroke
			(width 0.05715)
			(type default)
		)
		(layer "In11.Cu")
	)
	(gr_line
		(start 354.954332 -296.583862)
		(end 355.000052 -296.538142)
		(stroke
			(width 0.05715)
			(type default)
		)
		(layer "In11.Cu")
	)
	(gr_line
		(start 354.971604 -386.152136)
		(end 354.971604 -386.151882)
		(stroke
			(width 0.07112)
			(type default)
		)
		(layer "In11.Cu")
	)
	(gr_line
		(start 354.992432 -295.495726)
		(end 354.99929 -295.4909)
		(stroke
			(width 0.05715)
			(type default)
		)
		(layer "In11.Cu")
	)
	(gr_line
		(start 354.99929 -295.4909)
		(end 354.999544 -295.490646)
		(stroke
			(width 0.05715)
			(type default)
		)
		(layer "In11.Cu")
	)
	(gr_line
		(start 354.999544 -295.490646)
		(end 355.007164 -295.486328)
		(stroke
			(width 0.05715)
			(type default)
		)
		(layer "In11.Cu")
	)
	(gr_line
		(start 355.023166 -279.756108)
		(end 355.321108 -279.756108)
		(stroke
			(width 0.05715)
			(type default)
		)
		(layer "In11.Cu")
	)
	(gr_line
		(start 355.023166 -278.136096)
		(end 355.321108 -278.136096)
		(stroke
			(width 0.05715)
			(type default)
		)
		(layer "In11.Cu")
	)
	(gr_line
		(start 355.023166 -276.516084)
		(end 355.321108 -276.516084)
		(stroke
			(width 0.05715)
			(type default)
		)
		(layer "In11.Cu")
	)
	(gr_line
		(start 355.023166 -274.896072)
		(end 355.321108 -274.896072)
		(stroke
			(width 0.05715)
			(type default)
		)
		(layer "In11.Cu")
	)
	(gr_line
		(start 355.134164 -295.633394)
		(end 355.134164 -295.63314)
		(stroke
			(width 0.05715)
			(type default)
		)
		(layer "In11.Cu")
	)
	(gr_line
		(start 355.161342 -295.617392)
		(end 355.162104 -295.616884)
		(stroke
			(width 0.05715)
			(type default)
		)
		(layer "In11.Cu")
	)
	(gr_line
		(start 355.162104 -295.616884)
		(end 355.170486 -295.612312)
		(stroke
			(width 0.05715)
			(type default)
		)
		(layer "In11.Cu")
	)
	(gr_arc
		(start 355.170486 -295.612312)
		(mid 355.176097 -295.60828)
		(end 355.181662 -295.604184)
		(stroke
			(width 0.05715)
			(type default)
		)
		(layer "In11.Cu")
	)
	(gr_arc
		(start 355.225858 -275.706078)
		(mid 355.226295 -275.71919)
		(end 355.227636 -275.73224)
		(stroke
			(width 0.05715)
			(type default)
		)
		(layer "In11.Cu")
	)
	(gr_line
		(start 355.229414 -287.080452)
		(end 355.22916 -287.079182)
		(stroke
			(width 0.05715)
			(type default)
		)
		(layer "In11.Cu")
	)
	(gr_line
		(start 355.236272 -296.61231)
		(end 355.236272 -296.583862)
		(stroke
			(width 0.05715)
			(type default)
		)
		(layer "In11.Cu")
	)
	(gr_line
		(start 355.236272 -296.583862)
		(end 355.190552 -296.538142)
		(stroke
			(width 0.05715)
			(type default)
		)
		(layer "In11.Cu")
	)
	(gr_arc
		(start 355.416358 -275.706078)
		(mid 355.416368 -275.702776)
		(end 355.416358 -275.699474)
		(stroke
			(width 0.05715)
			(type default)
		)
		(layer "In11.Cu")
	)
	(gr_line
		(start 355.41712 -287.025334)
		(end 355.41712 -287.024572)
		(stroke
			(width 0.05715)
			(type default)
		)
		(layer "In11.Cu")
	)
	(gr_arc
		(start 355.434392 -276.141942)
		(mid 355.437431 -276.144999)
		(end 355.440488 -276.148038)
		(stroke
			(width 0.05715)
			(type default)
		)
		(layer "In11.Cu")
	)
	(gr_arc
		(start 355.440488 -276.148038)
		(mid 355.443401 -276.150461)
		(end 355.44633 -276.152864)
		(stroke
			(width 0.05715)
			(type default)
		)
		(layer "In11.Cu")
	)
	(gr_arc
		(start 355.47173 -286.579564)
		(mid 355.464963 -286.58434)
		(end 355.458268 -286.589216)
		(stroke
			(width 0.05715)
			(type default)
		)
		(layer "In11.Cu")
	)
	(gr_line
		(start 355.47173 -286.579564)
		(end 355.474524 -286.57804)
		(stroke
			(width 0.05715)
			(type default)
		)
		(layer "In11.Cu")
	)
	(gr_line
		(start 355.495098 -288.186114)
		(end 355.49713 -288.184844)
		(stroke
			(width 0.05715)
			(type default)
		)
		(layer "In11.Cu")
	)
	(gr_line
		(start 355.495606 -289.14598)
		(end 355.495098 -289.145726)
		(stroke
			(width 0.05715)
			(type default)
		)
		(layer "In11.Cu")
	)
	(gr_arc
		(start 355.496622 -292.386766)
		(mid 355.499032 -292.388169)
		(end 355.501448 -292.38956)
		(stroke
			(width 0.05715)
			(type default)
		)
		(layer "In11.Cu")
	)
	(gr_arc
		(start 355.496622 -290.766754)
		(mid 355.498778 -290.768029)
		(end 355.50094 -290.769294)
		(stroke
			(width 0.05715)
			(type default)
		)
		(layer "In11.Cu")
	)
	(gr_line
		(start 355.4984 -294.664892)
		(end 355.499162 -294.66413)
		(stroke
			(width 0.05715)
			(type default)
		)
		(layer "In11.Cu")
	)
	(gr_line
		(start 355.50221 -281.050238)
		(end 355.498654 -281.047698)
		(stroke
			(width 0.05715)
			(type default)
		)
		(layer "In11.Cu")
	)
	(gr_line
		(start 355.507798 -291.418772)
		(end 355.508052 -291.418518)
		(stroke
			(width 0.05715)
			(type default)
		)
		(layer "In11.Cu")
	)
	(gr_line
		(start 355.507798 -289.79876)
		(end 355.508052 -289.798506)
		(stroke
			(width 0.05715)
			(type default)
		)
		(layer "In11.Cu")
	)
	(gr_line
		(start 355.508052 -292.39337)
		(end 355.507798 -292.39337)
		(stroke
			(width 0.05715)
			(type default)
		)
		(layer "In11.Cu")
	)
	(gr_line
		(start 355.508052 -290.773358)
		(end 355.507798 -290.773358)
		(stroke
			(width 0.05715)
			(type default)
		)
		(layer "In11.Cu")
	)
	(gr_line
		(start 355.508052 -281.05354)
		(end 355.50221 -281.050238)
		(stroke
			(width 0.05715)
			(type default)
		)
		(layer "In11.Cu")
	)
	(gr_line
		(start 355.508306 -284.93847)
		(end 355.508814 -284.938216)
		(stroke
			(width 0.05715)
			(type default)
		)
		(layer "In11.Cu")
	)
	(gr_line
		(start 355.508306 -283.318458)
		(end 355.508814 -283.318204)
		(stroke
			(width 0.05715)
			(type default)
		)
		(layer "In11.Cu")
	)
	(gr_line
		(start 355.508306 -281.698446)
		(end 355.508814 -281.698192)
		(stroke
			(width 0.05715)
			(type default)
		)
		(layer "In11.Cu")
	)
	(gr_line
		(start 355.508814 -294.01389)
		(end 355.508052 -294.013382)
		(stroke
			(width 0.05715)
			(type default)
		)
		(layer "In11.Cu")
	)
	(gr_line
		(start 355.508814 -285.914084)
		(end 355.508052 -285.913576)
		(stroke
			(width 0.05715)
			(type default)
		)
		(layer "In11.Cu")
	)
	(gr_line
		(start 355.508814 -284.938216)
		(end 355.510084 -284.937454)
		(stroke
			(width 0.05715)
			(type default)
		)
		(layer "In11.Cu")
	)
	(gr_line
		(start 355.508814 -284.294072)
		(end 355.508052 -284.293564)
		(stroke
			(width 0.05715)
			(type default)
		)
		(layer "In11.Cu")
	)
	(gr_line
		(start 355.508814 -283.318204)
		(end 355.510084 -283.317442)
		(stroke
			(width 0.05715)
			(type default)
		)
		(layer "In11.Cu")
	)
	(gr_line
		(start 355.508814 -282.67406)
		(end 355.508052 -282.673552)
		(stroke
			(width 0.05715)
			(type default)
		)
		(layer "In11.Cu")
	)
	(gr_line
		(start 355.508814 -281.698192)
		(end 355.510084 -281.69743)
		(stroke
			(width 0.05715)
			(type default)
		)
		(layer "In11.Cu")
	)
	(gr_line
		(start 355.508814 -281.054048)
		(end 355.508052 -281.05354)
		(stroke
			(width 0.05715)
			(type default)
		)
		(layer "In11.Cu")
	)
	(gr_line
		(start 355.50983 -285.914592)
		(end 355.508814 -285.914084)
		(stroke
			(width 0.05715)
			(type default)
		)
		(layer "In11.Cu")
	)
	(gr_line
		(start 355.50983 -284.29458)
		(end 355.508814 -284.294072)
		(stroke
			(width 0.05715)
			(type default)
		)
		(layer "In11.Cu")
	)
	(gr_line
		(start 355.50983 -282.674568)
		(end 355.508814 -282.67406)
		(stroke
			(width 0.05715)
			(type default)
		)
		(layer "In11.Cu")
	)
	(gr_line
		(start 355.50983 -281.054556)
		(end 355.508814 -281.054048)
		(stroke
			(width 0.05715)
			(type default)
		)
		(layer "In11.Cu")
	)
	(gr_line
		(start 355.510084 -294.014652)
		(end 355.508814 -294.01389)
		(stroke
			(width 0.05715)
			(type default)
		)
		(layer "In11.Cu")
	)
	(gr_line
		(start 355.514148 -294.016938)
		(end 355.512624 -294.015922)
		(stroke
			(width 0.05715)
			(type default)
		)
		(layer "In11.Cu")
	)
	(gr_line
		(start 355.515164 -294.017446)
		(end 355.514148 -294.016938)
		(stroke
			(width 0.05715)
			(type default)
		)
		(layer "In11.Cu")
	)
	(gr_line
		(start 355.515672 -294.0177)
		(end 355.515164 -294.017446)
		(stroke
			(width 0.05715)
			(type default)
		)
		(layer "In11.Cu")
	)
	(gr_line
		(start 355.516688 -292.39845)
		(end 355.514148 -292.396926)
		(stroke
			(width 0.05715)
			(type default)
		)
		(layer "In11.Cu")
	)
	(gr_line
		(start 355.516688 -290.778184)
		(end 355.515926 -290.77793)
		(stroke
			(width 0.05715)
			(type default)
		)
		(layer "In11.Cu")
	)
	(gr_line
		(start 355.517196 -292.398704)
		(end 355.516688 -292.39845)
		(stroke
			(width 0.05715)
			(type default)
		)
		(layer "In11.Cu")
	)
	(gr_line
		(start 355.602032 -281.864816)
		(end 355.603302 -281.864054)
		(stroke
			(width 0.05715)
			(type default)
		)
		(layer "In11.Cu")
	)
	(gr_line
		(start 355.603302 -282.508198)
		(end 355.600508 -282.506674)
		(stroke
			(width 0.05715)
			(type default)
		)
		(layer "In11.Cu")
	)
	(gr_line
		(start 355.603302 -281.864054)
		(end 355.604064 -281.863546)
		(stroke
			(width 0.05715)
			(type default)
		)
		(layer "In11.Cu")
	)
	(gr_line
		(start 355.604064 -285.10357)
		(end 355.60508 -285.103062)
		(stroke
			(width 0.05715)
			(type default)
		)
		(layer "In11.Cu")
	)
	(gr_line
		(start 355.604064 -283.483558)
		(end 355.60508 -283.48305)
		(stroke
			(width 0.05715)
			(type default)
		)
		(layer "In11.Cu")
	)
	(gr_line
		(start 355.604064 -282.508706)
		(end 355.603302 -282.508198)
		(stroke
			(width 0.05715)
			(type default)
		)
		(layer "In11.Cu")
	)
	(gr_line
		(start 355.604064 -281.863546)
		(end 355.60508 -281.863038)
		(stroke
			(width 0.05715)
			(type default)
		)
		(layer "In11.Cu")
	)
	(gr_line
		(start 355.604064 -280.888694)
		(end 355.603302 -280.888186)
		(stroke
			(width 0.05715)
			(type default)
		)
		(layer "In11.Cu")
	)
	(gr_line
		(start 355.60635 -282.509976)
		(end 355.604064 -282.508706)
		(stroke
			(width 0.05715)
			(type default)
		)
		(layer "In11.Cu")
	)
	(gr_line
		(start 355.60635 -280.889964)
		(end 355.604064 -280.888694)
		(stroke
			(width 0.05715)
			(type default)
		)
		(layer "In11.Cu")
	)
	(gr_line
		(start 355.607112 -282.510484)
		(end 355.60635 -282.509976)
		(stroke
			(width 0.05715)
			(type default)
		)
		(layer "In11.Cu")
	)
	(gr_line
		(start 355.607112 -280.890472)
		(end 355.60635 -280.889964)
		(stroke
			(width 0.05715)
			(type default)
		)
		(layer "In11.Cu")
	)
	(gr_line
		(start 355.608636 -292.231064)
		(end 355.604572 -292.228778)
		(stroke
			(width 0.05715)
			(type default)
		)
		(layer "In11.Cu")
	)
	(gr_line
		(start 355.609398 -293.851584)
		(end 355.608382 -293.851076)
		(stroke
			(width 0.05715)
			(type default)
		)
		(layer "In11.Cu")
	)
	(gr_line
		(start 355.609398 -292.231572)
		(end 355.608636 -292.231064)
		(stroke
			(width 0.05715)
			(type default)
		)
		(layer "In11.Cu")
	)
	(gr_line
		(start 355.610414 -293.852346)
		(end 355.609398 -293.851584)
		(stroke
			(width 0.05715)
			(type default)
		)
		(layer "In11.Cu")
	)
	(gr_line
		(start 355.611176 -290.612576)
		(end 355.603556 -290.608258)
		(stroke
			(width 0.05715)
			(type default)
		)
		(layer "In11.Cu")
	)
	(gr_line
		(start 355.612192 -292.23335)
		(end 355.609398 -292.231572)
		(stroke
			(width 0.05715)
			(type default)
		)
		(layer "In11.Cu")
	)
	(gr_line
		(start 355.6127 -290.613592)
		(end 355.611176 -290.612576)
		(stroke
			(width 0.05715)
			(type default)
		)
		(layer "In11.Cu")
	)
	(gr_line
		(start 355.624892 -291.571172)
		(end 355.625146 -291.571172)
		(stroke
			(width 0.05715)
			(type default)
		)
		(layer "In11.Cu")
	)
	(gr_line
		(start 355.624892 -289.95116)
		(end 355.625146 -289.95116)
		(stroke
			(width 0.05715)
			(type default)
		)
		(layer "In11.Cu")
	)
	(gr_line
		(start 355.633528 -291.566346)
		(end 355.635052 -291.56533)
		(stroke
			(width 0.05715)
			(type default)
		)
		(layer "In11.Cu")
	)
	(gr_line
		(start 355.633528 -289.946334)
		(end 355.635052 -289.945318)
		(stroke
			(width 0.05715)
			(type default)
		)
		(layer "In11.Cu")
	)
	(gr_line
		(start 355.635052 -293.185596)
		(end 355.640386 -293.182548)
		(stroke
			(width 0.05715)
			(type default)
		)
		(layer "In11.Cu")
	)
	(gr_line
		(start 355.63556 -293.866824)
		(end 355.635052 -293.86657)
		(stroke
			(width 0.05715)
			(type default)
		)
		(layer "In11.Cu")
	)
	(gr_line
		(start 355.636068 -292.247066)
		(end 355.63429 -292.24605)
		(stroke
			(width 0.05715)
			(type default)
		)
		(layer "In11.Cu")
	)
	(gr_line
		(start 355.636322 -293.867332)
		(end 355.63556 -293.866824)
		(stroke
			(width 0.05715)
			(type default)
		)
		(layer "In11.Cu")
	)
	(gr_line
		(start 355.640386 -293.182548)
		(end 355.64318 -293.180516)
		(stroke
			(width 0.05715)
			(type default)
		)
		(layer "In11.Cu")
	)
	(gr_line
		(start 355.642418 -292.250876)
		(end 355.636068 -292.247066)
		(stroke
			(width 0.05715)
			(type default)
		)
		(layer "In11.Cu")
	)
	(gr_arc
		(start 355.642418 -292.250876)
		(mid 355.642799 -292.25113)
		(end 355.64318 -292.251384)
		(stroke
			(width 0.05715)
			(type default)
		)
		(layer "In11.Cu")
	)
	(gr_line
		(start 355.642418 -290.630864)
		(end 355.635814 -290.627054)
		(stroke
			(width 0.05715)
			(type default)
		)
		(layer "In11.Cu")
	)
	(gr_arc
		(start 355.642418 -290.630864)
		(mid 355.642799 -290.631118)
		(end 355.64318 -290.631372)
		(stroke
			(width 0.05715)
			(type default)
		)
		(layer "In11.Cu")
	)
	(gr_line
		(start 355.642418 -289.010852)
		(end 355.635306 -289.006788)
		(stroke
			(width 0.05715)
			(type default)
		)
		(layer "In11.Cu")
	)
	(gr_arc
		(start 355.642418 -289.010852)
		(mid 355.642799 -289.011106)
		(end 355.64318 -289.01136)
		(stroke
			(width 0.05715)
			(type default)
		)
		(layer "In11.Cu")
	)
	(gr_line
		(start 355.642418 -287.391094)
		(end 355.63302 -287.385506)
		(stroke
			(width 0.05715)
			(type default)
		)
		(layer "In11.Cu")
	)
	(gr_line
		(start 355.642418 -287.39084)
		(end 355.642418 -287.391094)
		(stroke
			(width 0.05715)
			(type default)
		)
		(layer "In11.Cu")
	)
	(gr_line
		(start 355.64318 -293.871396)
		(end 355.636322 -293.867332)
		(stroke
			(width 0.05715)
			(type default)
		)
		(layer "In11.Cu")
	)
	(gr_arc
		(start 355.64318 -293.180516)
		(mid 355.647129 -293.177739)
		(end 355.651054 -293.174928)
		(stroke
			(width 0.05715)
			(type default)
		)
		(layer "In11.Cu")
	)
	(gr_arc
		(start 355.644704 -292.2524)
		(mid 355.643942 -292.251891)
		(end 355.64318 -292.251384)
		(stroke
			(width 0.05715)
			(type default)
		)
		(layer "In11.Cu")
	)
	(gr_arc
		(start 355.651054 -293.876984)
		(mid 355.647129 -293.874173)
		(end 355.64318 -293.871396)
		(stroke
			(width 0.05715)
			(type default)
		)
		(layer "In11.Cu")
	)
	(gr_arc
		(start 355.651054 -292.256972)
		(mid 355.648266 -292.255058)
		(end 355.645466 -292.253162)
		(stroke
			(width 0.05715)
			(type default)
		)
		(layer "In11.Cu")
	)
	(gr_arc
		(start 355.651054 -290.63696)
		(mid 355.647129 -290.634149)
		(end 355.64318 -290.631372)
		(stroke
			(width 0.05715)
			(type default)
		)
		(layer "In11.Cu")
	)
	(gr_arc
		(start 355.651054 -289.016948)
		(mid 355.647129 -289.014137)
		(end 355.64318 -289.01136)
		(stroke
			(width 0.05715)
			(type default)
		)
		(layer "In11.Cu")
	)
	(gr_arc
		(start 355.651308 -287.396936)
		(mid 355.646878 -287.393866)
		(end 355.642418 -287.39084)
		(stroke
			(width 0.05715)
			(type default)
		)
		(layer "In11.Cu")
	)
	(gr_line
		(start 355.695758 -276.516084)
		(end 355.696012 -276.516084)
		(stroke
			(width 0.05715)
			(type default)
		)
		(layer "In11.Cu")
	)
	(gr_line
		(start 356.119938 -295.697148)
		(end 356.119938 -295.6687)
		(stroke
			(width 0.05715)
			(type default)
		)
		(layer "In11.Cu")
	)
	(gr_line
		(start 356.119938 -295.6687)
		(end 356.165658 -295.62298)
		(stroke
			(width 0.05715)
			(type default)
		)
		(layer "In11.Cu")
	)
	(gr_line
		(start 356.356158 -295.423336)
		(end 356.356412 -295.423082)
		(stroke
			(width 0.05715)
			(type default)
		)
		(layer "In11.Cu")
	)
	(gr_line
		(start 356.401878 -295.697148)
		(end 356.401878 -295.6687)
		(stroke
			(width 0.05715)
			(type default)
		)
		(layer "In11.Cu")
	)
	(gr_line
		(start 356.401878 -295.6687)
		(end 356.356158 -295.62298)
		(stroke
			(width 0.05715)
			(type default)
		)
		(layer "In11.Cu")
	)
	(gr_arc
		(start 356.406704 -291.443156)
		(mid 356.403905 -291.445053)
		(end 356.401116 -291.446966)
		(stroke
			(width 0.05715)
			(type default)
		)
		(layer "In11.Cu")
	)
	(gr_arc
		(start 356.406704 -280.103072)
		(mid 356.403903 -280.105095)
		(end 356.401116 -280.107136)
		(stroke
			(width 0.05715)
			(type default)
		)
		(layer "In11.Cu")
	)
	(gr_line
		(start 356.408736 -293.06139)
		(end 356.409498 -293.060882)
		(stroke
			(width 0.05715)
			(type default)
		)
		(layer "In11.Cu")
	)
	(gr_line
		(start 356.408736 -289.821366)
		(end 356.409498 -289.820858)
		(stroke
			(width 0.05715)
			(type default)
		)
		(layer "In11.Cu")
	)
	(gr_arc
		(start 356.40899 -293.06139)
		(mid 356.405041 -293.064167)
		(end 356.401116 -293.066978)
		(stroke
			(width 0.05715)
			(type default)
		)
		(layer "In11.Cu")
	)
	(gr_line
		(start 356.40899 -293.06139)
		(end 356.408736 -293.06139)
		(stroke
			(width 0.05715)
			(type default)
		)
		(layer "In11.Cu")
	)
	(gr_arc
		(start 356.40899 -291.441378)
		(mid 356.408228 -291.441885)
		(end 356.407466 -291.442394)
		(stroke
			(width 0.05715)
			(type default)
		)
		(layer "In11.Cu")
	)
	(gr_line
		(start 356.40899 -291.441378)
		(end 356.417118 -291.436552)
		(stroke
			(width 0.05715)
			(type default)
		)
		(layer "In11.Cu")
	)
	(gr_arc
		(start 356.40899 -289.821366)
		(mid 356.405041 -289.824143)
		(end 356.401116 -289.826954)
		(stroke
			(width 0.05715)
			(type default)
		)
		(layer "In11.Cu")
	)
	(gr_line
		(start 356.40899 -289.821366)
		(end 356.408736 -289.821366)
		(stroke
			(width 0.05715)
			(type default)
		)
		(layer "In11.Cu")
	)
	(gr_arc
		(start 356.40899 -283.341572)
		(mid 356.405041 -283.344349)
		(end 356.401116 -283.34716)
		(stroke
			(width 0.05715)
			(type default)
		)
		(layer "In11.Cu")
	)
	(gr_line
		(start 356.40899 -280.101548)
		(end 356.416864 -280.096976)
		(stroke
			(width 0.05715)
			(type default)
		)
		(layer "In11.Cu")
	)
	(gr_arc
		(start 356.40899 -278.481536)
		(mid 356.405041 -278.484313)
		(end 356.401116 -278.487124)
		(stroke
			(width 0.05715)
			(type default)
		)
		(layer "In11.Cu")
	)
	(gr_line
		(start 356.40899 -278.481536)
		(end 356.409498 -278.481282)
		(stroke
			(width 0.05715)
			(type default)
		)
		(layer "In11.Cu")
	)
	(gr_line
		(start 356.409498 -293.060882)
		(end 356.41661 -293.056818)
		(stroke
			(width 0.05715)
			(type default)
		)
		(layer "In11.Cu")
	)
	(gr_line
		(start 356.409498 -289.820858)
		(end 356.41661 -289.816794)
		(stroke
			(width 0.05715)
			(type default)
		)
		(layer "In11.Cu")
	)
	(gr_line
		(start 356.409498 -283.341318)
		(end 356.41534 -283.337762)
		(stroke
			(width 0.05715)
			(type default)
		)
		(layer "In11.Cu")
	)
	(gr_line
		(start 356.410514 -278.480774)
		(end 356.419912 -278.475186)
		(stroke
			(width 0.05715)
			(type default)
		)
		(layer "In11.Cu")
	)
	(gr_line
		(start 356.41661 -283.337)
		(end 356.418896 -283.33573)
		(stroke
			(width 0.05715)
			(type default)
		)
		(layer "In11.Cu")
	)
	(gr_line
		(start 356.416864 -280.096976)
		(end 356.417626 -280.096468)
		(stroke
			(width 0.05715)
			(type default)
		)
		(layer "In11.Cu")
	)
	(gr_line
		(start 356.417118 -291.436552)
		(end 356.41788 -291.436044)
		(stroke
			(width 0.05715)
			(type default)
		)
		(layer "In11.Cu")
	)
	(gr_line
		(start 356.417626 -280.096468)
		(end 356.418896 -280.095706)
		(stroke
			(width 0.05715)
			(type default)
		)
		(layer "In11.Cu")
	)
	(gr_line
		(start 356.433374 -291.427154)
		(end 356.434136 -291.426646)
		(stroke
			(width 0.05715)
			(type default)
		)
		(layer "In11.Cu")
	)
	(gr_line
		(start 356.434644 -291.426392)
		(end 356.43693 -291.425122)
		(stroke
			(width 0.05715)
			(type default)
		)
		(layer "In11.Cu")
	)
	(gr_line
		(start 356.44074 -281.703018)
		(end 356.441756 -281.70251)
		(stroke
			(width 0.05715)
			(type default)
		)
		(layer "In11.Cu")
	)
	(gr_line
		(start 356.441248 -291.422582)
		(end 356.44455 -291.42055)
		(stroke
			(width 0.05715)
			(type default)
		)
		(layer "In11.Cu")
	)
	(gr_line
		(start 356.441502 -285.909766)
		(end 356.439978 -285.90875)
		(stroke
			(width 0.05715)
			(type default)
		)
		(layer "In11.Cu")
	)
	(gr_line
		(start 356.441502 -284.289754)
		(end 356.439978 -284.288738)
		(stroke
			(width 0.05715)
			(type default)
		)
		(layer "In11.Cu")
	)
	(gr_line
		(start 356.441502 -282.669742)
		(end 356.439978 -282.668726)
		(stroke
			(width 0.05715)
			(type default)
		)
		(layer "In11.Cu")
	)
	(gr_line
		(start 356.441502 -281.04973)
		(end 356.439978 -281.048714)
		(stroke
			(width 0.05715)
			(type default)
		)
		(layer "In11.Cu")
	)
	(gr_line
		(start 356.441502 -279.429718)
		(end 356.439978 -279.428702)
		(stroke
			(width 0.05715)
			(type default)
		)
		(layer "In11.Cu")
	)
	(gr_line
		(start 356.441502 -277.809706)
		(end 356.439978 -277.80869)
		(stroke
			(width 0.05715)
			(type default)
		)
		(layer "In11.Cu")
	)
	(gr_line
		(start 356.442518 -294.661844)
		(end 356.443788 -294.661082)
		(stroke
			(width 0.05715)
			(type default)
		)
		(layer "In11.Cu")
	)
	(gr_line
		(start 356.442518 -281.702002)
		(end 356.44455 -281.700732)
		(stroke
			(width 0.05715)
			(type default)
		)
		(layer "In11.Cu")
	)
	(gr_line
		(start 356.442772 -285.910528)
		(end 356.441502 -285.909766)
		(stroke
			(width 0.05715)
			(type default)
		)
		(layer "In11.Cu")
	)
	(gr_line
		(start 356.442772 -284.290516)
		(end 356.441502 -284.289754)
		(stroke
			(width 0.05715)
			(type default)
		)
		(layer "In11.Cu")
	)
	(gr_line
		(start 356.442772 -282.670504)
		(end 356.441502 -282.669742)
		(stroke
			(width 0.05715)
			(type default)
		)
		(layer "In11.Cu")
	)
	(gr_line
		(start 356.442772 -281.050492)
		(end 356.441502 -281.04973)
		(stroke
			(width 0.05715)
			(type default)
		)
		(layer "In11.Cu")
	)
	(gr_line
		(start 356.442772 -279.43048)
		(end 356.441502 -279.429718)
		(stroke
			(width 0.05715)
			(type default)
		)
		(layer "In11.Cu")
	)
	(gr_line
		(start 356.442772 -277.810468)
		(end 356.441502 -277.809706)
		(stroke
			(width 0.05715)
			(type default)
		)
		(layer "In11.Cu")
	)
	(gr_line
		(start 356.44455 -291.42055)
		(end 356.445566 -291.420042)
		(stroke
			(width 0.05715)
			(type default)
		)
		(layer "In11.Cu")
	)
	(gr_line
		(start 356.44455 -281.700732)
		(end 356.445566 -281.700224)
		(stroke
			(width 0.05715)
			(type default)
		)
		(layer "In11.Cu")
	)
	(gr_line
		(start 356.445566 -294.660066)
		(end 356.44709 -294.65905)
		(stroke
			(width 0.05715)
			(type default)
		)
		(layer "In11.Cu")
	)
	(gr_line
		(start 356.445566 -291.420042)
		(end 356.44709 -291.419026)
		(stroke
			(width 0.05715)
			(type default)
		)
		(layer "In11.Cu")
	)
	(gr_line
		(start 356.445566 -285.912052)
		(end 356.442772 -285.910528)
		(stroke
			(width 0.05715)
			(type default)
		)
		(layer "In11.Cu")
	)
	(gr_line
		(start 356.445566 -284.29204)
		(end 356.442772 -284.290516)
		(stroke
			(width 0.05715)
			(type default)
		)
		(layer "In11.Cu")
	)
	(gr_line
		(start 356.445566 -282.672028)
		(end 356.442772 -282.670504)
		(stroke
			(width 0.05715)
			(type default)
		)
		(layer "In11.Cu")
	)
	(gr_line
		(start 356.445566 -281.700224)
		(end 356.446328 -281.699716)
		(stroke
			(width 0.05715)
			(type default)
		)
		(layer "In11.Cu")
	)
	(gr_line
		(start 356.445566 -281.052016)
		(end 356.442772 -281.050492)
		(stroke
			(width 0.05715)
			(type default)
		)
		(layer "In11.Cu")
	)
	(gr_line
		(start 356.445566 -279.432004)
		(end 356.442772 -279.43048)
		(stroke
			(width 0.05715)
			(type default)
		)
		(layer "In11.Cu")
	)
	(gr_line
		(start 356.445566 -277.811992)
		(end 356.442772 -277.810468)
		(stroke
			(width 0.05715)
			(type default)
		)
		(layer "In11.Cu")
	)
	(gr_line
		(start 356.44709 -294.65905)
		(end 356.448106 -294.658542)
		(stroke
			(width 0.05715)
			(type default)
		)
		(layer "In11.Cu")
	)
	(gr_line
		(start 356.44709 -291.419026)
		(end 356.448106 -291.418518)
		(stroke
			(width 0.05715)
			(type default)
		)
		(layer "In11.Cu")
	)
	(gr_line
		(start 356.44709 -285.913068)
		(end 356.445566 -285.912052)
		(stroke
			(width 0.05715)
			(type default)
		)
		(layer "In11.Cu")
	)
	(gr_line
		(start 356.44709 -284.293056)
		(end 356.445566 -284.29204)
		(stroke
			(width 0.05715)
			(type default)
		)
		(layer "In11.Cu")
	)
	(gr_line
		(start 356.44709 -282.673044)
		(end 356.445566 -282.672028)
		(stroke
			(width 0.05715)
			(type default)
		)
		(layer "In11.Cu")
	)
	(gr_line
		(start 356.44709 -281.053032)
		(end 356.445566 -281.052016)
		(stroke
			(width 0.05715)
			(type default)
		)
		(layer "In11.Cu")
	)
	(gr_line
		(start 356.44709 -279.43302)
		(end 356.445566 -279.432004)
		(stroke
			(width 0.05715)
			(type default)
		)
		(layer "In11.Cu")
	)
	(gr_line
		(start 356.44709 -277.813008)
		(end 356.445566 -277.811992)
		(stroke
			(width 0.05715)
			(type default)
		)
		(layer "In11.Cu")
	)
	(gr_line
		(start 356.448106 -294.658542)
		(end 356.448614 -294.658288)
		(stroke
			(width 0.05715)
			(type default)
		)
		(layer "In11.Cu")
	)
	(gr_line
		(start 356.448106 -291.418518)
		(end 356.448868 -291.41801)
		(stroke
			(width 0.05715)
			(type default)
		)
		(layer "In11.Cu")
	)
	(gr_line
		(start 356.448106 -285.913576)
		(end 356.44709 -285.913068)
		(stroke
			(width 0.05715)
			(type default)
		)
		(layer "In11.Cu")
	)
	(gr_line
		(start 356.448106 -284.293564)
		(end 356.44709 -284.293056)
		(stroke
			(width 0.05715)
			(type default)
		)
		(layer "In11.Cu")
	)
	(gr_line
		(start 356.448106 -282.673552)
		(end 356.44709 -282.673044)
		(stroke
			(width 0.05715)
			(type default)
		)
		(layer "In11.Cu")
	)
	(gr_line
		(start 356.448106 -281.6987)
		(end 356.448868 -281.698192)
		(stroke
			(width 0.05715)
			(type default)
		)
		(layer "In11.Cu")
	)
	(gr_line
		(start 356.448106 -281.05354)
		(end 356.44709 -281.053032)
		(stroke
			(width 0.05715)
			(type default)
		)
		(layer "In11.Cu")
	)
	(gr_line
		(start 356.448106 -279.433528)
		(end 356.44709 -279.43302)
		(stroke
			(width 0.05715)
			(type default)
		)
		(layer "In11.Cu")
	)
	(gr_line
		(start 356.448106 -277.813516)
		(end 356.44709 -277.813008)
		(stroke
			(width 0.05715)
			(type default)
		)
		(layer "In11.Cu")
	)
	(gr_line
		(start 356.448868 -294.01389)
		(end 356.448106 -294.013382)
		(stroke
			(width 0.05715)
			(type default)
		)
		(layer "In11.Cu")
	)
	(gr_line
		(start 356.448868 -292.393878)
		(end 356.448106 -292.39337)
		(stroke
			(width 0.05715)
			(type default)
		)
		(layer "In11.Cu")
	)
	(gr_line
		(start 356.448868 -290.773866)
		(end 356.448106 -290.773358)
		(stroke
			(width 0.05715)
			(type default)
		)
		(layer "In11.Cu")
	)
	(gr_line
		(start 356.448868 -289.153854)
		(end 356.448106 -289.153346)
		(stroke
			(width 0.05715)
			(type default)
		)
		(layer "In11.Cu")
	)
	(gr_line
		(start 356.448868 -285.914084)
		(end 356.448106 -285.913576)
		(stroke
			(width 0.05715)
			(type default)
		)
		(layer "In11.Cu")
	)
	(gr_line
		(start 356.448868 -284.294072)
		(end 356.448106 -284.293564)
		(stroke
			(width 0.05715)
			(type default)
		)
		(layer "In11.Cu")
	)
	(gr_line
		(start 356.448868 -282.67406)
		(end 356.448106 -282.673552)
		(stroke
			(width 0.05715)
			(type default)
		)
		(layer "In11.Cu")
	)
	(gr_line
		(start 356.448868 -281.054048)
		(end 356.448106 -281.05354)
		(stroke
			(width 0.05715)
			(type default)
		)
		(layer "In11.Cu")
	)
	(gr_line
		(start 356.448868 -279.434036)
		(end 356.448106 -279.433528)
		(stroke
			(width 0.05715)
			(type default)
		)
		(layer "In11.Cu")
	)
	(gr_line
		(start 356.448868 -277.814024)
		(end 356.448106 -277.813516)
		(stroke
			(width 0.05715)
			(type default)
		)
		(layer "In11.Cu")
	)
	(gr_line
		(start 356.450138 -294.014652)
		(end 356.448868 -294.01389)
		(stroke
			(width 0.05715)
			(type default)
		)
		(layer "In11.Cu")
	)
	(gr_line
		(start 356.450138 -292.39464)
		(end 356.448868 -292.393878)
		(stroke
			(width 0.05715)
			(type default)
		)
		(layer "In11.Cu")
	)
	(gr_line
		(start 356.450138 -290.774628)
		(end 356.448868 -290.773866)
		(stroke
			(width 0.05715)
			(type default)
		)
		(layer "In11.Cu")
	)
	(gr_line
		(start 356.450138 -289.154616)
		(end 356.448868 -289.153854)
		(stroke
			(width 0.05715)
			(type default)
		)
		(layer "In11.Cu")
	)
	(gr_line
		(start 356.451662 -294.015414)
		(end 356.450138 -294.014652)
		(stroke
			(width 0.05715)
			(type default)
		)
		(layer "In11.Cu")
	)
	(gr_line
		(start 356.451662 -292.395402)
		(end 356.450138 -292.39464)
		(stroke
			(width 0.05715)
			(type default)
		)
		(layer "In11.Cu")
	)
	(gr_line
		(start 356.451662 -290.77539)
		(end 356.450138 -290.774628)
		(stroke
			(width 0.05715)
			(type default)
		)
		(layer "In11.Cu")
	)
	(gr_line
		(start 356.451662 -289.155378)
		(end 356.450138 -289.154616)
		(stroke
			(width 0.05715)
			(type default)
		)
		(layer "In11.Cu")
	)
	(gr_line
		(start 356.451916 -281.696414)
		(end 356.452932 -281.695906)
		(stroke
			(width 0.05715)
			(type default)
		)
		(layer "In11.Cu")
	)
	(gr_line
		(start 356.452424 -294.015922)
		(end 356.451662 -294.015414)
		(stroke
			(width 0.05715)
			(type default)
		)
		(layer "In11.Cu")
	)
	(gr_line
		(start 356.452424 -292.39591)
		(end 356.451662 -292.395402)
		(stroke
			(width 0.05715)
			(type default)
		)
		(layer "In11.Cu")
	)
	(gr_line
		(start 356.452424 -290.775898)
		(end 356.451662 -290.77539)
		(stroke
			(width 0.05715)
			(type default)
		)
		(layer "In11.Cu")
	)
	(gr_line
		(start 356.452424 -289.155886)
		(end 356.451662 -289.155378)
		(stroke
			(width 0.05715)
			(type default)
		)
		(layer "In11.Cu")
	)
	(gr_line
		(start 356.46233 -283.310584)
		(end 356.462838 -283.31033)
		(stroke
			(width 0.05715)
			(type default)
		)
		(layer "In11.Cu")
	)
	(gr_line
		(start 356.479856 -284.920182)
		(end 356.479856 -284.920436)
		(stroke
			(width 0.05715)
			(type default)
		)
		(layer "In11.Cu")
	)
	(gr_line
		(start 356.479856 -278.440134)
		(end 356.479856 -278.440388)
		(stroke
			(width 0.05715)
			(type default)
		)
		(layer "In11.Cu")
	)
	(gr_line
		(start 356.512368 -283.501846)
		(end 356.512622 -283.5021)
		(stroke
			(width 0.05715)
			(type default)
		)
		(layer "In11.Cu")
	)
	(gr_line
		(start 356.512368 -280.261822)
		(end 356.512622 -280.262076)
		(stroke
			(width 0.05715)
			(type default)
		)
		(layer "In11.Cu")
	)
	(gr_line
		(start 356.512368 -278.64181)
		(end 356.512368 -278.642064)
		(stroke
			(width 0.05715)
			(type default)
		)
		(layer "In11.Cu")
	)
	(gr_line
		(start 356.528624 -291.592254)
		(end 356.529386 -291.591746)
		(stroke
			(width 0.05715)
			(type default)
		)
		(layer "In11.Cu")
	)
	(gr_line
		(start 356.529386 -291.591746)
		(end 356.529894 -291.591492)
		(stroke
			(width 0.05715)
			(type default)
		)
		(layer "In11.Cu")
	)
	(gr_line
		(start 356.53091 -291.590984)
		(end 356.532688 -291.589968)
		(stroke
			(width 0.05715)
			(type default)
		)
		(layer "In11.Cu")
	)
	(gr_line
		(start 356.53091 -281.871166)
		(end 356.532688 -281.87015)
		(stroke
			(width 0.05715)
			(type default)
		)
		(layer "In11.Cu")
	)
	(gr_line
		(start 356.533958 -291.589206)
		(end 356.53472 -291.588698)
		(stroke
			(width 0.05715)
			(type default)
		)
		(layer "In11.Cu")
	)
	(gr_line
		(start 356.533958 -281.869388)
		(end 356.53472 -281.86888)
		(stroke
			(width 0.05715)
			(type default)
		)
		(layer "In11.Cu")
	)
	(gr_line
		(start 356.53472 -291.588698)
		(end 356.536244 -291.587936)
		(stroke
			(width 0.05715)
			(type default)
		)
		(layer "In11.Cu")
	)
	(gr_line
		(start 356.53472 -281.86888)
		(end 356.535736 -281.868372)
		(stroke
			(width 0.05715)
			(type default)
		)
		(layer "In11.Cu")
	)
	(gr_line
		(start 356.538022 -285.745174)
		(end 356.537006 -285.744666)
		(stroke
			(width 0.05715)
			(type default)
		)
		(layer "In11.Cu")
	)
	(gr_line
		(start 356.538022 -284.125162)
		(end 356.537006 -284.124654)
		(stroke
			(width 0.05715)
			(type default)
		)
		(layer "In11.Cu")
	)
	(gr_line
		(start 356.538022 -282.50515)
		(end 356.537006 -282.504642)
		(stroke
			(width 0.05715)
			(type default)
		)
		(layer "In11.Cu")
	)
	(gr_line
		(start 356.538022 -280.885138)
		(end 356.537006 -280.88463)
		(stroke
			(width 0.05715)
			(type default)
		)
		(layer "In11.Cu")
	)
	(gr_line
		(start 356.538022 -279.265126)
		(end 356.537006 -279.264618)
		(stroke
			(width 0.05715)
			(type default)
		)
		(layer "In11.Cu")
	)
	(gr_line
		(start 356.538022 -277.645114)
		(end 356.537006 -277.644606)
		(stroke
			(width 0.05715)
			(type default)
		)
		(layer "In11.Cu")
	)
	(gr_line
		(start 356.53853 -294.82669)
		(end 356.540562 -294.82542)
		(stroke
			(width 0.05715)
			(type default)
		)
		(layer "In11.Cu")
	)
	(gr_line
		(start 356.538784 -285.745682)
		(end 356.538022 -285.745174)
		(stroke
			(width 0.05715)
			(type default)
		)
		(layer "In11.Cu")
	)
	(gr_line
		(start 356.538784 -284.12567)
		(end 356.538022 -284.125162)
		(stroke
			(width 0.05715)
			(type default)
		)
		(layer "In11.Cu")
	)
	(gr_line
		(start 356.538784 -282.505658)
		(end 356.538022 -282.50515)
		(stroke
			(width 0.05715)
			(type default)
		)
		(layer "In11.Cu")
	)
	(gr_line
		(start 356.538784 -280.885646)
		(end 356.538022 -280.885138)
		(stroke
			(width 0.05715)
			(type default)
		)
		(layer "In11.Cu")
	)
	(gr_line
		(start 356.538784 -279.265634)
		(end 356.538022 -279.265126)
		(stroke
			(width 0.05715)
			(type default)
		)
		(layer "In11.Cu")
	)
	(gr_line
		(start 356.538784 -277.645622)
		(end 356.538022 -277.645114)
		(stroke
			(width 0.05715)
			(type default)
		)
		(layer "In11.Cu")
	)
	(gr_line
		(start 356.5398 -285.74619)
		(end 356.538784 -285.745682)
		(stroke
			(width 0.05715)
			(type default)
		)
		(layer "In11.Cu")
	)
	(gr_line
		(start 356.5398 -284.126178)
		(end 356.538784 -284.12567)
		(stroke
			(width 0.05715)
			(type default)
		)
		(layer "In11.Cu")
	)
	(gr_line
		(start 356.5398 -282.506166)
		(end 356.538784 -282.505658)
		(stroke
			(width 0.05715)
			(type default)
		)
		(layer "In11.Cu")
	)
	(gr_line
		(start 356.5398 -280.886154)
		(end 356.538784 -280.885646)
		(stroke
			(width 0.05715)
			(type default)
		)
		(layer "In11.Cu")
	)
	(gr_line
		(start 356.5398 -279.266142)
		(end 356.538784 -279.265634)
		(stroke
			(width 0.05715)
			(type default)
		)
		(layer "In11.Cu")
	)
	(gr_line
		(start 356.5398 -277.64613)
		(end 356.538784 -277.645622)
		(stroke
			(width 0.05715)
			(type default)
		)
		(layer "In11.Cu")
	)
	(gr_line
		(start 356.540562 -294.82542)
		(end 356.542086 -294.824658)
		(stroke
			(width 0.05715)
			(type default)
		)
		(layer "In11.Cu")
	)
	(gr_line
		(start 356.541578 -291.584888)
		(end 356.543356 -291.583872)
		(stroke
			(width 0.05715)
			(type default)
		)
		(layer "In11.Cu")
	)
	(gr_line
		(start 356.542086 -294.824658)
		(end 356.543356 -294.823896)
		(stroke
			(width 0.05715)
			(type default)
		)
		(layer "In11.Cu")
	)
	(gr_line
		(start 356.543356 -293.848028)
		(end 356.542086 -293.847266)
		(stroke
			(width 0.05715)
			(type default)
		)
		(layer "In11.Cu")
	)
	(gr_line
		(start 356.543356 -292.228016)
		(end 356.542086 -292.227254)
		(stroke
			(width 0.05715)
			(type default)
		)
		(layer "In11.Cu")
	)
	(gr_line
		(start 356.543356 -290.608004)
		(end 356.542086 -290.607242)
		(stroke
			(width 0.05715)
			(type default)
		)
		(layer "In11.Cu")
	)
	(gr_line
		(start 356.543356 -288.987992)
		(end 356.542086 -288.98723)
		(stroke
			(width 0.05715)
			(type default)
		)
		(layer "In11.Cu")
	)
	(gr_line
		(start 356.543356 -285.748222)
		(end 356.540562 -285.746698)
		(stroke
			(width 0.05715)
			(type default)
		)
		(layer "In11.Cu")
	)
	(gr_line
		(start 356.543356 -284.12821)
		(end 356.540562 -284.126686)
		(stroke
			(width 0.05715)
			(type default)
		)
		(layer "In11.Cu")
	)
	(gr_line
		(start 356.543356 -282.508198)
		(end 356.540562 -282.506674)
		(stroke
			(width 0.05715)
			(type default)
		)
		(layer "In11.Cu")
	)
	(gr_line
		(start 356.543356 -280.888186)
		(end 356.540562 -280.886662)
		(stroke
			(width 0.05715)
			(type default)
		)
		(layer "In11.Cu")
	)
	(gr_line
		(start 356.543356 -279.268174)
		(end 356.540562 -279.26665)
		(stroke
			(width 0.05715)
			(type default)
		)
		(layer "In11.Cu")
	)
	(gr_line
		(start 356.543356 -277.648162)
		(end 356.540562 -277.646638)
		(stroke
			(width 0.05715)
			(type default)
		)
		(layer "In11.Cu")
	)
	(gr_line
		(start 356.544118 -293.848536)
		(end 356.543356 -293.848028)
		(stroke
			(width 0.05715)
			(type default)
		)
		(layer "In11.Cu")
	)
	(gr_line
		(start 356.544118 -292.228524)
		(end 356.543356 -292.228016)
		(stroke
			(width 0.05715)
			(type default)
		)
		(layer "In11.Cu")
	)
	(gr_line
		(start 356.544118 -290.608512)
		(end 356.543356 -290.608004)
		(stroke
			(width 0.05715)
			(type default)
		)
		(layer "In11.Cu")
	)
	(gr_line
		(start 356.544118 -288.9885)
		(end 356.543356 -288.987992)
		(stroke
			(width 0.05715)
			(type default)
		)
		(layer "In11.Cu")
	)
	(gr_line
		(start 356.544118 -285.74873)
		(end 356.543356 -285.748222)
		(stroke
			(width 0.05715)
			(type default)
		)
		(layer "In11.Cu")
	)
	(gr_line
		(start 356.544118 -284.128718)
		(end 356.543356 -284.12821)
		(stroke
			(width 0.05715)
			(type default)
		)
		(layer "In11.Cu")
	)
	(gr_line
		(start 356.544118 -282.508706)
		(end 356.543356 -282.508198)
		(stroke
			(width 0.05715)
			(type default)
		)
		(layer "In11.Cu")
	)
	(gr_line
		(start 356.544118 -280.888694)
		(end 356.543356 -280.888186)
		(stroke
			(width 0.05715)
			(type default)
		)
		(layer "In11.Cu")
	)
	(gr_line
		(start 356.544118 -279.268682)
		(end 356.543356 -279.268174)
		(stroke
			(width 0.05715)
			(type default)
		)
		(layer "In11.Cu")
	)
	(gr_line
		(start 356.544118 -277.64867)
		(end 356.543356 -277.648162)
		(stroke
			(width 0.05715)
			(type default)
		)
		(layer "In11.Cu")
	)
	(gr_line
		(start 356.545134 -293.849044)
		(end 356.544118 -293.848536)
		(stroke
			(width 0.05715)
			(type default)
		)
		(layer "In11.Cu")
	)
	(gr_line
		(start 356.545134 -292.229032)
		(end 356.544118 -292.228524)
		(stroke
			(width 0.05715)
			(type default)
		)
		(layer "In11.Cu")
	)
	(gr_line
		(start 356.545134 -290.60902)
		(end 356.544118 -290.608512)
		(stroke
			(width 0.05715)
			(type default)
		)
		(layer "In11.Cu")
	)
	(gr_line
		(start 356.545134 -288.989008)
		(end 356.544118 -288.9885)
		(stroke
			(width 0.05715)
			(type default)
		)
		(layer "In11.Cu")
	)
	(gr_line
		(start 356.545134 -285.749238)
		(end 356.544118 -285.74873)
		(stroke
			(width 0.05715)
			(type default)
		)
		(layer "In11.Cu")
	)
	(gr_line
		(start 356.545134 -284.129226)
		(end 356.544118 -284.128718)
		(stroke
			(width 0.05715)
			(type default)
		)
		(layer "In11.Cu")
	)
	(gr_line
		(start 356.545134 -282.509214)
		(end 356.544118 -282.508706)
		(stroke
			(width 0.05715)
			(type default)
		)
		(layer "In11.Cu")
	)
	(gr_line
		(start 356.545134 -281.863038)
		(end 356.546658 -281.862022)
		(stroke
			(width 0.05715)
			(type default)
		)
		(layer "In11.Cu")
	)
	(gr_line
		(start 356.545134 -280.889202)
		(end 356.544118 -280.888694)
		(stroke
			(width 0.05715)
			(type default)
		)
		(layer "In11.Cu")
	)
	(gr_line
		(start 356.545134 -279.26919)
		(end 356.544118 -279.268682)
		(stroke
			(width 0.05715)
			(type default)
		)
		(layer "In11.Cu")
	)
	(gr_line
		(start 356.545134 -277.649178)
		(end 356.544118 -277.64867)
		(stroke
			(width 0.05715)
			(type default)
		)
		(layer "In11.Cu")
	)
	(gr_line
		(start 356.545896 -285.749746)
		(end 356.545134 -285.749238)
		(stroke
			(width 0.05715)
			(type default)
		)
		(layer "In11.Cu")
	)
	(gr_line
		(start 356.545896 -284.129734)
		(end 356.545134 -284.129226)
		(stroke
			(width 0.05715)
			(type default)
		)
		(layer "In11.Cu")
	)
	(gr_line
		(start 356.545896 -282.509722)
		(end 356.545134 -282.509214)
		(stroke
			(width 0.05715)
			(type default)
		)
		(layer "In11.Cu")
	)
	(gr_line
		(start 356.545896 -280.88971)
		(end 356.545134 -280.889202)
		(stroke
			(width 0.05715)
			(type default)
		)
		(layer "In11.Cu")
	)
	(gr_line
		(start 356.545896 -279.269698)
		(end 356.545134 -279.26919)
		(stroke
			(width 0.05715)
			(type default)
		)
		(layer "In11.Cu")
	)
	(gr_line
		(start 356.545896 -277.649686)
		(end 356.545134 -277.649178)
		(stroke
			(width 0.05715)
			(type default)
		)
		(layer "In11.Cu")
	)
	(gr_line
		(start 356.547166 -293.850314)
		(end 356.545134 -293.849044)
		(stroke
			(width 0.05715)
			(type default)
		)
		(layer "In11.Cu")
	)
	(gr_line
		(start 356.547166 -292.230302)
		(end 356.545134 -292.229032)
		(stroke
			(width 0.05715)
			(type default)
		)
		(layer "In11.Cu")
	)
	(gr_line
		(start 356.547166 -290.61029)
		(end 356.545134 -290.60902)
		(stroke
			(width 0.05715)
			(type default)
		)
		(layer "In11.Cu")
	)
	(gr_line
		(start 356.547166 -288.990278)
		(end 356.545134 -288.989008)
		(stroke
			(width 0.05715)
			(type default)
		)
		(layer "In11.Cu")
	)
	(gr_line
		(start 356.548436 -281.861006)
		(end 356.549706 -281.860244)
		(stroke
			(width 0.05715)
			(type default)
		)
		(layer "In11.Cu")
	)
	(gr_line
		(start 356.549706 -293.851838)
		(end 356.548436 -293.851076)
		(stroke
			(width 0.05715)
			(type default)
		)
		(layer "In11.Cu")
	)
	(gr_line
		(start 356.549706 -292.231826)
		(end 356.548436 -292.231064)
		(stroke
			(width 0.05715)
			(type default)
		)
		(layer "In11.Cu")
	)
	(gr_line
		(start 356.549706 -290.611814)
		(end 356.548436 -290.611052)
		(stroke
			(width 0.05715)
			(type default)
		)
		(layer "In11.Cu")
	)
	(gr_line
		(start 356.549706 -288.991802)
		(end 356.548436 -288.99104)
		(stroke
			(width 0.05715)
			(type default)
		)
		(layer "In11.Cu")
	)
	(gr_line
		(start 356.549706 -285.751778)
		(end 356.548436 -285.751016)
		(stroke
			(width 0.05715)
			(type default)
		)
		(layer "In11.Cu")
	)
	(gr_line
		(start 356.549706 -284.131766)
		(end 356.548436 -284.131004)
		(stroke
			(width 0.05715)
			(type default)
		)
		(layer "In11.Cu")
	)
	(gr_line
		(start 356.549706 -282.511754)
		(end 356.548436 -282.510992)
		(stroke
			(width 0.05715)
			(type default)
		)
		(layer "In11.Cu")
	)
	(gr_line
		(start 356.549706 -280.891742)
		(end 356.548436 -280.89098)
		(stroke
			(width 0.05715)
			(type default)
		)
		(layer "In11.Cu")
	)
	(gr_line
		(start 356.549706 -279.27173)
		(end 356.548436 -279.270968)
		(stroke
			(width 0.05715)
			(type default)
		)
		(layer "In11.Cu")
	)
	(gr_line
		(start 356.549706 -277.651718)
		(end 356.548436 -277.650956)
		(stroke
			(width 0.05715)
			(type default)
		)
		(layer "In11.Cu")
	)
	(gr_line
		(start 356.550976 -281.859482)
		(end 356.551484 -281.859228)
		(stroke
			(width 0.05715)
			(type default)
		)
		(layer "In11.Cu")
	)
	(gr_line
		(start 356.554024 -281.857704)
		(end 356.554532 -281.85745)
		(stroke
			(width 0.05715)
			(type default)
		)
		(layer "In11.Cu")
	)
	(gr_line
		(start 356.556564 -278.616156)
		(end 356.557326 -278.615902)
		(stroke
			(width 0.05715)
			(type default)
		)
		(layer "In11.Cu")
	)
	(gr_line
		(start 356.563168 -280.232358)
		(end 356.563676 -280.232104)
		(stroke
			(width 0.05715)
			(type default)
		)
		(layer "In11.Cu")
	)
	(gr_line
		(start 356.574852 -285.085536)
		(end 356.57536 -285.085282)
		(stroke
			(width 0.05715)
			(type default)
		)
		(layer "In11.Cu")
	)
	(gr_line
		(start 356.575106 -293.185342)
		(end 356.575868 -293.184834)
		(stroke
			(width 0.05715)
			(type default)
		)
		(layer "In11.Cu")
	)
	(gr_line
		(start 356.575106 -289.945318)
		(end 356.580694 -289.942016)
		(stroke
			(width 0.05715)
			(type default)
		)
		(layer "In11.Cu")
	)
	(gr_line
		(start 356.57536 -285.085282)
		(end 356.583234 -285.08071)
		(stroke
			(width 0.05715)
			(type default)
		)
		(layer "In11.Cu")
	)
	(gr_line
		(start 356.575614 -293.866824)
		(end 356.574344 -293.866062)
		(stroke
			(width 0.05715)
			(type default)
		)
		(layer "In11.Cu")
	)
	(gr_line
		(start 356.575614 -292.246812)
		(end 356.574344 -292.24605)
		(stroke
			(width 0.05715)
			(type default)
		)
		(layer "In11.Cu")
	)
	(gr_line
		(start 356.575614 -290.6268)
		(end 356.574344 -290.626038)
		(stroke
			(width 0.05715)
			(type default)
		)
		(layer "In11.Cu")
	)
	(gr_line
		(start 356.575614 -289.006788)
		(end 356.574344 -289.006026)
		(stroke
			(width 0.05715)
			(type default)
		)
		(layer "In11.Cu")
	)
	(gr_line
		(start 356.575614 -285.767018)
		(end 356.574344 -285.766256)
		(stroke
			(width 0.05715)
			(type default)
		)
		(layer "In11.Cu")
	)
	(gr_line
		(start 356.575614 -284.147006)
		(end 356.574344 -284.146244)
		(stroke
			(width 0.05715)
			(type default)
		)
		(layer "In11.Cu")
	)
	(gr_line
		(start 356.575614 -282.526994)
		(end 356.574344 -282.526232)
		(stroke
			(width 0.05715)
			(type default)
		)
		(layer "In11.Cu")
	)
	(gr_line
		(start 356.575614 -280.906982)
		(end 356.574344 -280.90622)
		(stroke
			(width 0.05715)
			(type default)
		)
		(layer "In11.Cu")
	)
	(gr_line
		(start 356.575614 -279.28697)
		(end 356.574344 -279.286208)
		(stroke
			(width 0.05715)
			(type default)
		)
		(layer "In11.Cu")
	)
	(gr_line
		(start 356.575614 -277.666958)
		(end 356.574344 -277.666196)
		(stroke
			(width 0.05715)
			(type default)
		)
		(layer "In11.Cu")
	)
	(gr_line
		(start 356.575868 -293.184834)
		(end 356.583234 -293.180516)
		(stroke
			(width 0.05715)
			(type default)
		)
		(layer "In11.Cu")
	)
	(gr_line
		(start 356.576376 -293.867332)
		(end 356.575614 -293.866824)
		(stroke
			(width 0.05715)
			(type default)
		)
		(layer "In11.Cu")
	)
	(gr_line
		(start 356.576376 -292.24732)
		(end 356.575614 -292.246812)
		(stroke
			(width 0.05715)
			(type default)
		)
		(layer "In11.Cu")
	)
	(gr_line
		(start 356.576376 -290.627308)
		(end 356.575614 -290.6268)
		(stroke
			(width 0.05715)
			(type default)
		)
		(layer "In11.Cu")
	)
	(gr_line
		(start 356.576376 -289.007296)
		(end 356.575614 -289.006788)
		(stroke
			(width 0.05715)
			(type default)
		)
		(layer "In11.Cu")
	)
	(gr_line
		(start 356.576376 -285.767526)
		(end 356.575614 -285.767018)
		(stroke
			(width 0.05715)
			(type default)
		)
		(layer "In11.Cu")
	)
	(gr_line
		(start 356.576376 -284.147514)
		(end 356.575614 -284.147006)
		(stroke
			(width 0.05715)
			(type default)
		)
		(layer "In11.Cu")
	)
	(gr_line
		(start 356.576376 -282.527502)
		(end 356.575614 -282.526994)
		(stroke
			(width 0.05715)
			(type default)
		)
		(layer "In11.Cu")
	)
	(gr_line
		(start 356.576376 -280.90749)
		(end 356.575614 -280.906982)
		(stroke
			(width 0.05715)
			(type default)
		)
		(layer "In11.Cu")
	)
	(gr_line
		(start 356.576376 -279.287478)
		(end 356.575614 -279.28697)
		(stroke
			(width 0.05715)
			(type default)
		)
		(layer "In11.Cu")
	)
	(gr_line
		(start 356.576376 -277.667466)
		(end 356.575614 -277.666958)
		(stroke
			(width 0.05715)
			(type default)
		)
		(layer "In11.Cu")
	)
	(gr_line
		(start 356.580694 -289.942016)
		(end 356.583234 -289.940492)
		(stroke
			(width 0.05715)
			(type default)
		)
		(layer "In11.Cu")
	)
	(gr_line
		(start 356.583234 -293.871396)
		(end 356.576376 -293.867332)
		(stroke
			(width 0.05715)
			(type default)
		)
		(layer "In11.Cu")
	)
	(gr_arc
		(start 356.583234 -293.180516)
		(mid 356.587183 -293.177739)
		(end 356.591108 -293.174928)
		(stroke
			(width 0.05715)
			(type default)
		)
		(layer "In11.Cu")
	)
	(gr_line
		(start 356.583234 -292.251384)
		(end 356.576376 -292.24732)
		(stroke
			(width 0.05715)
			(type default)
		)
		(layer "In11.Cu")
	)
	(gr_line
		(start 356.583234 -290.631372)
		(end 356.576376 -290.627308)
		(stroke
			(width 0.05715)
			(type default)
		)
		(layer "In11.Cu")
	)
	(gr_arc
		(start 356.583234 -289.940492)
		(mid 356.587183 -289.937715)
		(end 356.591108 -289.934904)
		(stroke
			(width 0.05715)
			(type default)
		)
		(layer "In11.Cu")
	)
	(gr_line
		(start 356.583234 -289.01136)
		(end 356.576376 -289.007296)
		(stroke
			(width 0.05715)
			(type default)
		)
		(layer "In11.Cu")
	)
	(gr_line
		(start 356.583234 -285.77159)
		(end 356.576376 -285.767526)
		(stroke
			(width 0.05715)
			(type default)
		)
		(layer "In11.Cu")
	)
	(gr_line
		(start 356.583234 -284.151578)
		(end 356.576376 -284.147514)
		(stroke
			(width 0.05715)
			(type default)
		)
		(layer "In11.Cu")
	)
	(gr_line
		(start 356.583234 -282.531566)
		(end 356.576376 -282.527502)
		(stroke
			(width 0.05715)
			(type default)
		)
		(layer "In11.Cu")
	)
	(gr_line
		(start 356.583234 -280.911554)
		(end 356.576376 -280.90749)
		(stroke
			(width 0.05715)
			(type default)
		)
		(layer "In11.Cu")
	)
	(gr_line
		(start 356.583234 -279.291542)
		(end 356.576376 -279.287478)
		(stroke
			(width 0.05715)
			(type default)
		)
		(layer "In11.Cu")
	)
	(gr_line
		(start 356.583234 -277.67153)
		(end 356.576376 -277.667466)
		(stroke
			(width 0.05715)
			(type default)
		)
		(layer "In11.Cu")
	)
	(gr_arc
		(start 356.585774 -285.078932)
		(mid 356.588447 -285.077035)
		(end 356.591108 -285.075122)
		(stroke
			(width 0.05715)
			(type default)
		)
		(layer "In11.Cu")
	)
	(gr_arc
		(start 356.591108 -293.876984)
		(mid 356.587183 -293.874173)
		(end 356.583234 -293.871396)
		(stroke
			(width 0.05715)
			(type default)
		)
		(layer "In11.Cu")
	)
	(gr_arc
		(start 356.591108 -292.256972)
		(mid 356.587183 -292.254161)
		(end 356.583234 -292.251384)
		(stroke
			(width 0.05715)
			(type default)
		)
		(layer "In11.Cu")
	)
	(gr_arc
		(start 356.591108 -290.63696)
		(mid 356.587183 -290.634149)
		(end 356.583234 -290.631372)
		(stroke
			(width 0.05715)
			(type default)
		)
		(layer "In11.Cu")
	)
	(gr_arc
		(start 356.591108 -289.016948)
		(mid 356.587183 -289.014137)
		(end 356.583234 -289.01136)
		(stroke
			(width 0.05715)
			(type default)
		)
		(layer "In11.Cu")
	)
	(gr_arc
		(start 356.591108 -285.777178)
		(mid 356.587183 -285.774367)
		(end 356.583234 -285.77159)
		(stroke
			(width 0.05715)
			(type default)
		)
		(layer "In11.Cu")
	)
	(gr_arc
		(start 356.591108 -284.157166)
		(mid 356.587183 -284.154355)
		(end 356.583234 -284.151578)
		(stroke
			(width 0.05715)
			(type default)
		)
		(layer "In11.Cu")
	)
	(gr_arc
		(start 356.591108 -282.537154)
		(mid 356.587183 -282.534343)
		(end 356.583234 -282.531566)
		(stroke
			(width 0.05715)
			(type default)
		)
		(layer "In11.Cu")
	)
	(gr_arc
		(start 356.591108 -280.917142)
		(mid 356.587183 -280.914331)
		(end 356.583234 -280.911554)
		(stroke
			(width 0.05715)
			(type default)
		)
		(layer "In11.Cu")
	)
	(gr_arc
		(start 356.591108 -279.29713)
		(mid 356.587183 -279.294319)
		(end 356.583234 -279.291542)
		(stroke
			(width 0.05715)
			(type default)
		)
		(layer "In11.Cu")
	)
	(gr_arc
		(start 356.591108 -277.677118)
		(mid 356.587183 -277.674307)
		(end 356.583234 -277.67153)
		(stroke
			(width 0.05715)
			(type default)
		)
		(layer "In11.Cu")
	)
	(gr_line
		(start 357.029004 -278.946102)
		(end 356.731062 -278.946102)
		(stroke
			(width 0.05715)
			(type default)
		)
		(layer "In11.Cu")
	)
	(gr_line
		(start 357.029004 -277.32609)
		(end 356.731062 -277.32609)
		(stroke
			(width 0.05715)
			(type default)
		)
		(layer "In11.Cu")
	)
	(gr_line
		(start 357.029004 -275.706078)
		(end 356.731062 -275.706078)
		(stroke
			(width 0.05715)
			(type default)
		)
		(layer "In11.Cu")
	)
	(gr_line
		(start 357.059992 -295.697148)
		(end 357.059992 -295.6687)
		(stroke
			(width 0.05715)
			(type default)
		)
		(layer "In11.Cu")
	)
	(gr_line
		(start 357.059992 -295.6687)
		(end 357.105712 -295.62298)
		(stroke
			(width 0.05715)
			(type default)
		)
		(layer "In11.Cu")
	)
	(gr_line
		(start 357.111808 -279.028906)
		(end 357.029004 -278.946102)
		(stroke
			(width 0.05715)
			(type default)
		)
		(layer "In11.Cu")
	)
	(gr_arc
		(start 357.111808 -279.028906)
		(mid 357.113601 -279.040228)
		(end 357.115618 -279.051512)
		(stroke
			(width 0.05715)
			(type default)
		)
		(layer "In11.Cu")
	)
	(gr_line
		(start 357.111808 -277.408894)
		(end 357.029004 -277.32609)
		(stroke
			(width 0.05715)
			(type default)
		)
		(layer "In11.Cu")
	)
	(gr_arc
		(start 357.111808 -277.408894)
		(mid 357.1136 -277.420216)
		(end 357.115618 -277.4315)
		(stroke
			(width 0.05715)
			(type default)
		)
		(layer "In11.Cu")
	)
	(gr_line
		(start 357.111808 -275.788882)
		(end 357.029004 -275.706078)
		(stroke
			(width 0.05715)
			(type default)
		)
		(layer "In11.Cu")
	)
	(gr_arc
		(start 357.111808 -275.788882)
		(mid 357.1136 -275.800204)
		(end 357.115618 -275.811488)
		(stroke
			(width 0.05715)
			(type default)
		)
		(layer "In11.Cu")
	)
	(gr_line
		(start 357.296212 -295.292018)
		(end 357.296466 -295.291764)
		(stroke
			(width 0.05715)
			(type default)
		)
		(layer "In11.Cu")
	)
	(gr_line
		(start 357.296466 -287.046162)
		(end 357.296212 -287.045908)
		(stroke
			(width 0.05715)
			(type default)
		)
		(layer "In11.Cu")
	)
	(gr_line
		(start 357.303832 -279.015444)
		(end 357.373174 -278.946102)
		(stroke
			(width 0.05715)
			(type default)
		)
		(layer "In11.Cu")
	)
	(gr_line
		(start 357.303832 -277.395432)
		(end 357.373174 -277.32609)
		(stroke
			(width 0.05715)
			(type default)
		)
		(layer "In11.Cu")
	)
	(gr_line
		(start 357.303832 -275.77542)
		(end 357.373174 -275.706078)
		(stroke
			(width 0.05715)
			(type default)
		)
		(layer "In11.Cu")
	)
	(gr_arc
		(start 357.340916 -276.165056)
		(mid 357.344968 -276.167868)
		(end 357.349044 -276.170644)
		(stroke
			(width 0.05715)
			(type default)
		)
		(layer "In11.Cu")
	)
	(gr_arc
		(start 357.34117 -289.124898)
		(mid 357.345095 -289.127709)
		(end 357.349044 -289.130486)
		(stroke
			(width 0.05715)
			(type default)
		)
		(layer "In11.Cu")
	)
	(gr_line
		(start 357.341932 -295.697148)
		(end 357.341932 -295.6687)
		(stroke
			(width 0.05715)
			(type default)
		)
		(layer "In11.Cu")
	)
	(gr_line
		(start 357.341932 -295.6687)
		(end 357.296212 -295.62298)
		(stroke
			(width 0.05715)
			(type default)
		)
		(layer "In11.Cu")
	)
	(gr_arc
		(start 357.349044 -294.681402)
		(mid 357.345095 -294.684179)
		(end 357.34117 -294.68699)
		(stroke
			(width 0.05715)
			(type default)
		)
		(layer "In11.Cu")
	)
	(gr_arc
		(start 357.349044 -294.681402)
		(mid 357.349425 -294.681148)
		(end 357.349806 -294.680894)
		(stroke
			(width 0.05715)
			(type default)
		)
		(layer "In11.Cu")
	)
	(gr_line
		(start 357.349806 -294.680894)
		(end 357.356918 -294.67683)
		(stroke
			(width 0.05715)
			(type default)
		)
		(layer "In11.Cu")
	)
	(gr_arc
		(start 357.349806 -276.171152)
		(mid 357.349425 -276.170898)
		(end 357.349044 -276.170644)
		(stroke
			(width 0.05715)
			(type default)
		)
		(layer "In11.Cu")
	)
	(gr_line
		(start 357.353108 -286.579056)
		(end 357.355648 -286.577532)
		(stroke
			(width 0.05715)
			(type default)
		)
		(layer "In11.Cu")
	)
	(gr_line
		(start 357.355902 -289.13455)
		(end 357.349044 -289.130486)
		(stroke
			(width 0.05715)
			(type default)
		)
		(layer "In11.Cu")
	)
	(gr_line
		(start 357.356156 -276.174962)
		(end 357.349806 -276.171152)
		(stroke
			(width 0.05715)
			(type default)
		)
		(layer "In11.Cu")
	)
	(gr_line
		(start 357.356664 -289.135058)
		(end 357.355902 -289.13455)
		(stroke
			(width 0.05715)
			(type default)
		)
		(layer "In11.Cu")
	)
	(gr_line
		(start 357.356918 -276.17547)
		(end 357.356156 -276.174962)
		(stroke
			(width 0.05715)
			(type default)
		)
		(layer "In11.Cu")
	)
	(gr_line
		(start 357.357172 -289.135312)
		(end 357.356664 -289.135058)
		(stroke
			(width 0.05715)
			(type default)
		)
		(layer "In11.Cu")
	)
	(gr_line
		(start 357.373174 -278.946102)
		(end 357.671116 -278.946102)
		(stroke
			(width 0.05715)
			(type default)
		)
		(layer "In11.Cu")
	)
	(gr_line
		(start 357.373174 -277.32609)
		(end 357.671116 -277.32609)
		(stroke
			(width 0.05715)
			(type default)
		)
		(layer "In11.Cu")
	)
	(gr_line
		(start 357.373174 -275.706078)
		(end 357.671116 -275.706078)
		(stroke
			(width 0.05715)
			(type default)
		)
		(layer "In11.Cu")
	)
	(gr_line
		(start 357.379524 -292.388544)
		(end 357.378508 -292.388036)
		(stroke
			(width 0.05715)
			(type default)
		)
		(layer "In11.Cu")
	)
	(gr_line
		(start 357.380286 -292.389052)
		(end 357.379524 -292.388544)
		(stroke
			(width 0.05715)
			(type default)
		)
		(layer "In11.Cu")
	)
	(gr_line
		(start 357.381556 -292.389814)
		(end 357.380286 -292.389052)
		(stroke
			(width 0.05715)
			(type default)
		)
		(layer "In11.Cu")
	)
	(gr_line
		(start 357.385874 -276.192234)
		(end 357.385112 -276.191726)
		(stroke
			(width 0.05715)
			(type default)
		)
		(layer "In11.Cu")
	)
	(gr_line
		(start 357.387144 -292.392862)
		(end 357.381556 -292.389814)
		(stroke
			(width 0.05715)
			(type default)
		)
		(layer "In11.Cu")
	)
	(gr_line
		(start 357.387144 -291.419026)
		(end 357.38816 -291.418518)
		(stroke
			(width 0.05715)
			(type default)
		)
		(layer "In11.Cu")
	)
	(gr_line
		(start 357.387144 -289.799014)
		(end 357.38816 -289.798506)
		(stroke
			(width 0.05715)
			(type default)
		)
		(layer "In11.Cu")
	)
	(gr_line
		(start 357.387144 -289.152838)
		(end 357.385112 -289.151568)
		(stroke
			(width 0.05715)
			(type default)
		)
		(layer "In11.Cu")
	)
	(gr_line
		(start 357.387906 -276.19325)
		(end 357.385874 -276.192234)
		(stroke
			(width 0.05715)
			(type default)
		)
		(layer "In11.Cu")
	)
	(gr_line
		(start 357.38816 -289.798506)
		(end 357.388922 -289.797998)
		(stroke
			(width 0.05715)
			(type default)
		)
		(layer "In11.Cu")
	)
	(gr_line
		(start 357.38816 -289.153346)
		(end 357.387144 -289.152838)
		(stroke
			(width 0.05715)
			(type default)
		)
		(layer "In11.Cu")
	)
	(gr_line
		(start 357.388922 -289.797998)
		(end 357.390192 -289.797236)
		(stroke
			(width 0.05715)
			(type default)
		)
		(layer "In11.Cu")
	)
	(gr_line
		(start 357.388922 -289.153854)
		(end 357.38816 -289.153346)
		(stroke
			(width 0.05715)
			(type default)
		)
		(layer "In11.Cu")
	)
	(gr_line
		(start 357.3907 -276.194774)
		(end 357.387906 -276.19325)
		(stroke
			(width 0.05715)
			(type default)
		)
		(layer "In11.Cu")
	)
	(gr_line
		(start 357.391716 -289.155378)
		(end 357.388922 -289.153854)
		(stroke
			(width 0.05715)
			(type default)
		)
		(layer "In11.Cu")
	)
	(gr_line
		(start 357.403146 -277.822152)
		(end 357.401114 -277.820882)
		(stroke
			(width 0.05715)
			(type default)
		)
		(layer "In11.Cu")
	)
	(gr_line
		(start 357.40975 -294.025828)
		(end 357.409496 -294.025828)
		(stroke
			(width 0.05715)
			(type default)
		)
		(layer "In11.Cu")
	)
	(gr_line
		(start 357.470964 -293.840916)
		(end 357.465122 -293.837614)
		(stroke
			(width 0.05715)
			(type default)
		)
		(layer "In11.Cu")
	)
	(gr_line
		(start 357.480616 -288.986468)
		(end 357.479854 -288.98596)
		(stroke
			(width 0.05715)
			(type default)
		)
		(layer "In11.Cu")
	)
	(gr_line
		(start 357.48087 -293.2049)
		(end 357.481886 -293.204392)
		(stroke
			(width 0.05715)
			(type default)
		)
		(layer "In11.Cu")
	)
	(gr_line
		(start 357.48087 -292.226746)
		(end 357.480108 -292.226238)
		(stroke
			(width 0.05715)
			(type default)
		)
		(layer "In11.Cu")
	)
	(gr_line
		(start 357.481886 -292.227254)
		(end 357.48087 -292.226746)
		(stroke
			(width 0.05715)
			(type default)
		)
		(layer "In11.Cu")
	)
	(gr_line
		(start 357.48214 -291.584634)
		(end 357.48341 -291.583872)
		(stroke
			(width 0.05715)
			(type default)
		)
		(layer "In11.Cu")
	)
	(gr_line
		(start 357.48214 -289.964622)
		(end 357.48341 -289.96386)
		(stroke
			(width 0.05715)
			(type default)
		)
		(layer "In11.Cu")
	)
	(gr_line
		(start 357.48214 -288.98723)
		(end 357.480616 -288.986468)
		(stroke
			(width 0.05715)
			(type default)
		)
		(layer "In11.Cu")
	)
	(gr_line
		(start 357.482648 -292.227762)
		(end 357.481886 -292.227254)
		(stroke
			(width 0.05715)
			(type default)
		)
		(layer "In11.Cu")
	)
	(gr_line
		(start 357.482902 -288.987738)
		(end 357.48214 -288.98723)
		(stroke
			(width 0.05715)
			(type default)
		)
		(layer "In11.Cu")
	)
	(gr_line
		(start 357.48341 -291.583872)
		(end 357.484172 -291.583364)
		(stroke
			(width 0.05715)
			(type default)
		)
		(layer "In11.Cu")
	)
	(gr_line
		(start 357.48341 -289.96386)
		(end 357.483918 -289.963606)
		(stroke
			(width 0.05715)
			(type default)
		)
		(layer "In11.Cu")
	)
	(gr_line
		(start 357.484172 -290.608512)
		(end 357.483664 -290.608258)
		(stroke
			(width 0.05715)
			(type default)
		)
		(layer "In11.Cu")
	)
	(gr_line
		(start 357.484172 -288.343594)
		(end 357.483918 -288.34334)
		(stroke
			(width 0.05715)
			(type default)
		)
		(layer "In11.Cu")
	)
	(gr_line
		(start 357.485188 -293.202614)
		(end 357.486966 -293.201598)
		(stroke
			(width 0.05715)
			(type default)
		)
		(layer "In11.Cu")
	)
	(gr_line
		(start 357.486204 -276.029928)
		(end 357.48214 -276.027388)
		(stroke
			(width 0.05715)
			(type default)
		)
		(layer "In11.Cu")
	)
	(gr_line
		(start 357.489506 -293.200328)
		(end 357.491792 -293.199058)
		(stroke
			(width 0.05715)
			(type default)
		)
		(layer "In11.Cu")
	)
	(gr_line
		(start 357.491792 -293.199058)
		(end 357.493316 -293.198042)
		(stroke
			(width 0.05715)
			(type default)
		)
		(layer "In11.Cu")
	)
	(gr_line
		(start 357.499158 -277.657306)
		(end 357.499158 -277.657052)
		(stroke
			(width 0.05715)
			(type default)
		)
		(layer "In11.Cu")
	)
	(gr_line
		(start 357.50373 -288.33191)
		(end 357.506778 -288.329878)
		(stroke
			(width 0.05715)
			(type default)
		)
		(layer "In11.Cu")
	)
	(gr_line
		(start 357.504746 -293.860474)
		(end 357.50373 -293.859966)
		(stroke
			(width 0.05715)
			(type default)
		)
		(layer "In11.Cu")
	)
	(gr_line
		(start 357.505508 -293.860982)
		(end 357.504746 -293.860474)
		(stroke
			(width 0.05715)
			(type default)
		)
		(layer "In11.Cu")
	)
	(gr_line
		(start 357.575612 -287.856168)
		(end 357.575866 -287.856422)
		(stroke
			(width 0.05715)
			(type default)
		)
		(layer "In11.Cu")
	)
	(gr_line
		(start 357.766366 -286.229552)
		(end 357.766366 -286.236156)
		(stroke
			(width 0.05715)
			(type default)
		)
		(layer "In11.Cu")
	)
	(gr_line
		(start 357.76662 -278.194008)
		(end 357.766366 -278.194262)
		(stroke
			(width 0.05715)
			(type default)
		)
		(layer "In11.Cu")
	)
	(gr_line
		(start 357.848154 -276.997414)
		(end 357.8479 -276.997414)
		(stroke
			(width 0.05715)
			(type default)
		)
		(layer "In11.Cu")
	)
	(gr_line
		(start 357.856028 -278.622252)
		(end 357.851456 -278.619204)
		(stroke
			(width 0.05715)
			(type default)
		)
		(layer "In11.Cu")
	)
	(gr_line
		(start 357.857298 -278.623014)
		(end 357.856028 -278.622252)
		(stroke
			(width 0.05715)
			(type default)
		)
		(layer "In11.Cu")
	)
	(gr_line
		(start 357.85806 -277.00351)
		(end 357.857552 -277.003256)
		(stroke
			(width 0.05715)
			(type default)
		)
		(layer "In11.Cu")
	)
	(gr_line
		(start 357.858822 -278.62403)
		(end 357.857298 -278.623014)
		(stroke
			(width 0.05715)
			(type default)
		)
		(layer "In11.Cu")
	)
	(gr_line
		(start 357.858822 -277.004018)
		(end 357.85806 -277.00351)
		(stroke
			(width 0.05715)
			(type default)
		)
		(layer "In11.Cu")
	)
	(gr_line
		(start 357.957374 -278.460454)
		(end 357.955088 -278.459184)
		(stroke
			(width 0.05715)
			(type default)
		)
		(layer "In11.Cu")
	)
	(gr_line
		(start 357.985568 -278.476964)
		(end 357.984806 -278.476456)
		(stroke
			(width 0.05715)
			(type default)
		)
		(layer "In11.Cu")
	)
	(gr_line
		(start 357.98633 -278.477472)
		(end 357.985568 -278.476964)
		(stroke
			(width 0.05715)
			(type default)
		)
		(layer "In11.Cu")
	)
	(gr_line
		(start 357.98633 -276.85746)
		(end 357.985568 -276.856952)
		(stroke
			(width 0.05715)
			(type default)
		)
		(layer "In11.Cu")
	)
	(gr_line
		(start 357.993188 -278.481536)
		(end 357.98633 -278.477472)
		(stroke
			(width 0.05715)
			(type default)
		)
		(layer "In11.Cu")
	)
	(gr_line
		(start 357.993188 -276.861524)
		(end 357.98633 -276.85746)
		(stroke
			(width 0.05715)
			(type default)
		)
		(layer "In11.Cu")
	)
	(gr_line
		(start 358.000046 -295.697148)
		(end 358.000046 -295.6687)
		(stroke
			(width 0.05715)
			(type default)
		)
		(layer "In11.Cu")
	)
	(gr_line
		(start 358.000046 -295.6687)
		(end 358.045766 -295.62298)
		(stroke
			(width 0.05715)
			(type default)
		)
		(layer "In11.Cu")
	)
	(gr_arc
		(start 358.001062 -278.487124)
		(mid 357.997137 -278.484313)
		(end 357.993188 -278.481536)
		(stroke
			(width 0.05715)
			(type default)
		)
		(layer "In11.Cu")
	)
	(gr_arc
		(start 358.001062 -276.867112)
		(mid 357.997137 -276.864301)
		(end 357.993188 -276.861524)
		(stroke
			(width 0.05715)
			(type default)
		)
		(layer "In11.Cu")
	)
	(gr_line
		(start 358.281986 -295.697148)
		(end 358.281986 -295.6687)
		(stroke
			(width 0.05715)
			(type default)
		)
		(layer "In11.Cu")
	)
	(gr_line
		(start 358.281986 -295.6687)
		(end 358.236266 -295.62298)
		(stroke
			(width 0.05715)
			(type default)
		)
		(layer "In11.Cu")
	)
	(gr_arc
		(start 358.282748 -290.745926)
		(mid 358.285156 -290.747711)
		(end 358.287574 -290.749482)
		(stroke
			(width 0.05715)
			(type default)
		)
		(layer "In11.Cu")
	)
	(gr_arc
		(start 358.289098 -294.681402)
		(mid 358.285788 -294.683677)
		(end 358.282494 -294.685974)
		(stroke
			(width 0.05715)
			(type default)
		)
		(layer "In11.Cu")
	)
	(gr_arc
		(start 358.290622 -294.680386)
		(mid 358.28986 -294.680893)
		(end 358.289098 -294.681402)
		(stroke
			(width 0.05715)
			(type default)
		)
		(layer "In11.Cu")
	)
	(gr_line
		(start 358.290622 -294.680386)
		(end 358.29748 -294.676322)
		(stroke
			(width 0.05715)
			(type default)
		)
		(layer "In11.Cu")
	)
	(gr_arc
		(start 358.315514 -294.006016)
		(mid 358.317544 -294.007163)
		(end 358.319578 -294.008302)
		(stroke
			(width 0.05715)
			(type default)
		)
		(layer "In11.Cu")
	)
	(gr_line
		(start 358.32796 -293.038784)
		(end 358.328214 -293.03853)
		(stroke
			(width 0.05715)
			(type default)
		)
		(layer "In11.Cu")
	)
	(gr_line
		(start 358.328214 -294.013382)
		(end 358.32796 -294.013382)
		(stroke
			(width 0.05715)
			(type default)
		)
		(layer "In11.Cu")
	)
	(gr_line
		(start 358.328468 -277.813516)
		(end 358.328214 -277.813516)
		(stroke
			(width 0.05715)
			(type default)
		)
		(layer "In11.Cu")
	)
	(gr_line
		(start 358.328976 -285.91383)
		(end 358.32796 -285.913322)
		(stroke
			(width 0.05715)
			(type default)
		)
		(layer "In11.Cu")
	)
	(gr_arc
		(start 358.368346 -286.534098)
		(mid 358.369236 -286.533337)
		(end 358.370124 -286.532574)
		(stroke
			(width 0.05715)
			(type default)
		)
		(layer "In11.Cu")
	)
	(gr_line
		(start 358.393238 -294.841168)
		(end 358.393492 -294.841168)
		(stroke
			(width 0.05715)
			(type default)
		)
		(layer "In11.Cu")
	)
	(gr_line
		(start 358.42321 -277.647908)
		(end 358.420416 -277.646384)
		(stroke
			(width 0.05715)
			(type default)
		)
		(layer "In11.Cu")
	)
	(gr_line
		(start 358.423972 -277.648416)
		(end 358.42321 -277.647908)
		(stroke
			(width 0.05715)
			(type default)
		)
		(layer "In11.Cu")
	)
	(gr_line
		(start 358.424226 -285.748984)
		(end 358.424226 -285.74873)
		(stroke
			(width 0.05715)
			(type default)
		)
		(layer "In11.Cu")
	)
	(gr_line
		(start 358.424226 -285.74873)
		(end 358.423972 -285.74873)
		(stroke
			(width 0.05715)
			(type default)
		)
		(layer "In11.Cu")
	)
	(gr_line
		(start 358.42448 -277.64867)
		(end 358.423972 -277.648416)
		(stroke
			(width 0.05715)
			(type default)
		)
		(layer "In11.Cu")
	)
	(gr_line
		(start 358.445308 -293.19093)
		(end 358.445562 -293.19093)
		(stroke
			(width 0.05715)
			(type default)
		)
		(layer "In11.Cu")
	)
	(gr_line
		(start 358.45496 -277.66645)
		(end 358.45369 -277.665688)
		(stroke
			(width 0.05715)
			(type default)
		)
		(layer "In11.Cu")
	)
	(gr_line
		(start 358.455722 -293.184834)
		(end 358.456484 -293.184326)
		(stroke
			(width 0.05715)
			(type default)
		)
		(layer "In11.Cu")
	)
	(gr_line
		(start 358.456484 -293.184326)
		(end 358.463088 -293.180516)
		(stroke
			(width 0.05715)
			(type default)
		)
		(layer "In11.Cu")
	)
	(gr_line
		(start 358.461564 -293.87038)
		(end 358.45623 -293.867332)
		(stroke
			(width 0.05715)
			(type default)
		)
		(layer "In11.Cu")
	)
	(gr_arc
		(start 358.463088 -293.871396)
		(mid 358.462326 -293.870887)
		(end 358.461564 -293.87038)
		(stroke
			(width 0.05715)
			(type default)
		)
		(layer "In11.Cu")
	)
	(gr_arc
		(start 358.463088 -293.180516)
		(mid 358.464232 -293.179756)
		(end 358.465374 -293.178992)
		(stroke
			(width 0.05715)
			(type default)
		)
		(layer "In11.Cu")
	)
	(gr_arc
		(start 358.466136 -293.178484)
		(mid 358.468937 -293.176461)
		(end 358.471724 -293.17442)
		(stroke
			(width 0.05715)
			(type default)
		)
		(layer "In11.Cu")
	)
	(gr_line
		(start 358.468676 -293.875206)
		(end 358.463088 -293.871396)
		(stroke
			(width 0.05715)
			(type default)
		)
		(layer "In11.Cu")
	)
	(gr_line
		(start 358.475026 -277.678388)
		(end 358.45496 -277.66645)
		(stroke
			(width 0.05715)
			(type default)
		)
		(layer "In11.Cu")
	)
	(gr_arc
		(start 358.480868 -285.067756)
		(mid 358.482521 -285.066489)
		(end 358.48417 -285.065216)
		(stroke
			(width 0.05715)
			(type default)
		)
		(layer "In11.Cu")
	)
	(gr_arc
		(start 358.48417 -285.065216)
		(mid 358.485696 -285.063949)
		(end 358.487218 -285.062676)
		(stroke
			(width 0.05715)
			(type default)
		)
		(layer "In11.Cu")
	)
	(gr_line
		(start 358.492552 -277.69566)
		(end 358.475026 -277.678388)
		(stroke
			(width 0.05715)
			(type default)
		)
		(layer "In11.Cu")
	)
	(gr_line
		(start 358.515412 -292.72992)
		(end 358.515412 -292.728904)
		(stroke
			(width 0.05715)
			(type default)
		)
		(layer "In11.Cu")
	)
	(gr_arc
		(start 358.704896 -287.870392)
		(mid 358.705556 -287.864426)
		(end 358.706166 -287.858454)
		(stroke
			(width 0.05715)
			(type default)
		)
		(layer "In11.Cu")
	)
	(gr_arc
		(start 358.704896 -283.008324)
		(mid 358.705556 -283.002358)
		(end 358.706166 -282.996386)
		(stroke
			(width 0.05715)
			(type default)
		)
		(layer "In11.Cu")
	)
	(gr_line
		(start 358.70515 -282.961588)
		(end 358.70515 -282.962858)
		(stroke
			(width 0.05715)
			(type default)
		)
		(layer "In11.Cu")
	)
	(gr_arc
		(start 358.705912 -292.737032)
		(mid 358.706051 -292.733476)
		(end 358.706166 -292.72992)
		(stroke
			(width 0.05715)
			(type default)
		)
		(layer "In11.Cu")
	)
	(gr_line
		(start 358.706166 -287.845246)
		(end 358.706166 -287.858454)
		(stroke
			(width 0.05715)
			(type default)
		)
		(layer "In11.Cu")
	)
	(gr_line
		(start 358.706166 -282.985464)
		(end 358.706166 -282.996386)
		(stroke
			(width 0.05715)
			(type default)
		)
		(layer "In11.Cu")
	)
	(gr_line
		(start 358.70642 -292.71595)
		(end 358.706166 -292.71595)
		(stroke
			(width 0.05715)
			(type default)
		)
		(layer "In11.Cu")
	)
	(gr_line
		(start 358.77881 -278.31669)
		(end 358.77881 -278.251666)
		(stroke
			(width 0.05715)
			(type default)
		)
		(layer "In11.Cu")
	)
	(gr_line
		(start 358.798876 -278.336756)
		(end 358.77881 -278.31669)
		(stroke
			(width 0.05715)
			(type default)
		)
		(layer "In11.Cu")
	)
	(gr_line
		(start 358.977946 -278.117046)
		(end 358.913684 -278.117046)
		(stroke
			(width 0.05715)
			(type default)
		)
		(layer "In11.Cu")
	)
	(gr_line
		(start 358.998266 -278.137366)
		(end 358.977946 -278.117046)
		(stroke
			(width 0.05715)
			(type default)
		)
		(layer "In11.Cu")
	)
	(gr_arc
		(start 359.116376 -376.770138)
		(mid 359.116621 -376.829068)
		(end 359.117392 -376.887994)
		(stroke
			(width 0.07112)
			(type default)
		)
		(layer "In11.Cu")
	)
	(gr_line
		(start 359.122218 -376.89282)
		(end 359.117392 -376.887994)
		(stroke
			(width 0.07112)
			(type default)
		)
		(layer "In11.Cu")
	)
	(gr_line
		(start 360.693208 -246.063516)
		(end 360.673142 -246.04345)
		(stroke
			(width 0.05715)
			(type default)
		)
		(layer "In11.Cu")
	)
	(gr_line
		(start 360.75747 -246.063516)
		(end 360.693208 -246.063516)
		(stroke
			(width 0.05715)
			(type default)
		)
		(layer "In11.Cu")
	)
	(gr_line
		(start 360.757978 -246.064024)
		(end 360.75747 -246.063516)
		(stroke
			(width 0.05715)
			(type default)
		)
		(layer "In11.Cu")
	)
	(gr_line
		(start 360.798364 -206.653638)
		(end 360.798618 -206.653638)
		(stroke
			(width 0.07112)
			(type default)
		)
		(layer "In11.Cu")
	)
	(gr_line
		(start 360.861356 -375.478294)
		(end 360.861356 -375.47804)
		(stroke
			(width 0.07112)
			(type default)
		)
		(layer "In11.Cu")
	)
	(gr_line
		(start 360.892852 -245.928134)
		(end 360.892852 -245.86438)
		(stroke
			(width 0.05715)
			(type default)
		)
		(layer "In11.Cu")
	)
	(gr_line
		(start 360.892852 -245.86438)
		(end 360.872532 -245.84406)
		(stroke
			(width 0.05715)
			(type default)
		)
		(layer "In11.Cu")
	)
	(gr_line
		(start 361.029504 -229.915466)
		(end 361.029504 -229.904036)
		(stroke
			(width 0.05715)
			(type default)
		)
		(layer "In11.Cu")
	)
	(gr_line
		(start 361.029758 -229.904036)
		(end 361.029504 -229.904036)
		(stroke
			(width 0.05715)
			(type default)
		)
		(layer "In11.Cu")
	)
	(gr_line
		(start 361.029758 -229.904036)
		(end 361.030012 -229.902004)
		(stroke
			(width 0.05715)
			(type default)
		)
		(layer "In11.Cu")
	)
	(gr_line
		(start 361.065826 -389.460486)
		(end 361.06608 -389.460486)
		(stroke
			(width 0.07112)
			(type default)
		)
		(layer "In11.Cu")
	)
	(gr_line
		(start 361.11434 -278.055578)
		(end 361.094274 -278.075644)
		(stroke
			(width 0.05715)
			(type default)
		)
		(layer "In11.Cu")
	)
	(gr_line
		(start 361.178602 -278.055578)
		(end 361.11434 -278.055578)
		(stroke
			(width 0.05715)
			(type default)
		)
		(layer "In11.Cu")
	)
	(gr_line
		(start 361.179364 -278.054816)
		(end 361.178602 -278.055578)
		(stroke
			(width 0.05715)
			(type default)
		)
		(layer "In11.Cu")
	)
	(gr_line
		(start 361.194604 -388.039356)
		(end 361.194604 -387.612636)
		(stroke
			(width 0.07112)
			(type default)
		)
		(layer "In11.Cu")
	)
	(gr_line
		(start 361.194604 -387.612636)
		(end 361.330494 -387.476746)
		(stroke
			(width 0.07112)
			(type default)
		)
		(layer "In11.Cu")
	)
	(gr_line
		(start 361.194604 -386.911596)
		(end 361.194604 -386.484876)
		(stroke
			(width 0.07112)
			(type default)
		)
		(layer "In11.Cu")
	)
	(gr_line
		(start 361.194604 -386.484876)
		(end 361.330494 -386.348986)
		(stroke
			(width 0.07112)
			(type default)
		)
		(layer "In11.Cu")
	)
	(gr_line
		(start 361.194604 -385.251198)
		(end 361.194604 -384.824478)
		(stroke
			(width 0.07112)
			(type default)
		)
		(layer "In11.Cu")
	)
	(gr_line
		(start 361.194604 -384.824478)
		(end 361.330494 -384.688588)
		(stroke
			(width 0.07112)
			(type default)
		)
		(layer "In11.Cu")
	)
	(gr_line
		(start 361.220004 -242.864132)
		(end 361.220258 -242.864132)
		(stroke
			(width 0.05715)
			(type default)
		)
		(layer "In11.Cu")
	)
	(gr_line
		(start 361.220766 -229.90175)
		(end 361.22102 -229.90175)
		(stroke
			(width 0.05715)
			(type default)
		)
		(layer "In11.Cu")
	)
	(gr_line
		(start 361.221528 -242.897406)
		(end 361.221528 -242.896644)
		(stroke
			(width 0.05715)
			(type default)
		)
		(layer "In11.Cu")
	)
	(gr_arc
		(start 361.24515 -229.46106)
		(mid 361.24107 -229.464981)
		(end 361.237022 -229.468934)
		(stroke
			(width 0.05715)
			(type default)
		)
		(layer "In11.Cu")
	)
	(gr_arc
		(start 361.254294 -229.453694)
		(mid 361.249703 -229.457353)
		(end 361.24515 -229.46106)
		(stroke
			(width 0.05715)
			(type default)
		)
		(layer "In11.Cu")
	)
	(gr_line
		(start 361.311698 -246.591328)
		(end 361.311952 -246.591582)
		(stroke
			(width 0.05715)
			(type default)
		)
		(layer "In11.Cu")
	)
	(gr_line
		(start 361.313984 -278.254714)
		(end 361.293918 -278.27478)
		(stroke
			(width 0.05715)
			(type default)
		)
		(layer "In11.Cu")
	)
	(gr_line
		(start 361.313984 -278.19096)
		(end 361.313984 -278.254714)
		(stroke
			(width 0.05715)
			(type default)
		)
		(layer "In11.Cu")
	)
	(gr_line
		(start 361.329478 -286.236156)
		(end 361.329732 -286.236156)
		(stroke
			(width 0.05715)
			(type default)
		)
		(layer "In11.Cu")
	)
	(gr_line
		(start 361.329478 -279.7683)
		(end 361.329478 -279.76068)
		(stroke
			(width 0.05715)
			(type default)
		)
		(layer "In11.Cu")
	)
	(gr_arc
		(start 361.329732 -279.753314)
		(mid 361.329595 -279.756997)
		(end 361.329478 -279.76068)
		(stroke
			(width 0.05715)
			(type default)
		)
		(layer "In11.Cu")
	)
	(gr_arc
		(start 361.329986 -286.215328)
		(mid 361.329847 -286.218884)
		(end 361.329732 -286.22244)
		(stroke
			(width 0.05715)
			(type default)
		)
		(layer "In11.Cu")
	)
	(gr_line
		(start 361.330494 -388.175246)
		(end 361.194604 -388.039356)
		(stroke
			(width 0.07112)
			(type default)
		)
		(layer "In11.Cu")
	)
	(gr_line
		(start 361.330494 -387.047486)
		(end 361.194604 -386.911596)
		(stroke
			(width 0.07112)
			(type default)
		)
		(layer "In11.Cu")
	)
	(gr_line
		(start 361.330494 -385.387088)
		(end 361.194604 -385.251198)
		(stroke
			(width 0.07112)
			(type default)
		)
		(layer "In11.Cu")
	)
	(gr_line
		(start 361.342432 -243.369592)
		(end 361.342432 -243.369338)
		(stroke
			(width 0.05715)
			(type default)
		)
		(layer "In11.Cu")
	)
	(gr_line
		(start 361.342432 -240.129568)
		(end 361.342432 -240.129314)
		(stroke
			(width 0.05715)
			(type default)
		)
		(layer "In11.Cu")
	)
	(gr_line
		(start 361.342432 -238.509556)
		(end 361.342432 -238.509302)
		(stroke
			(width 0.05715)
			(type default)
		)
		(layer "In11.Cu")
	)
	(gr_line
		(start 361.342432 -236.889544)
		(end 361.342432 -236.88929)
		(stroke
			(width 0.05715)
			(type default)
		)
		(layer "In11.Cu")
	)
	(gr_line
		(start 361.342432 -235.269532)
		(end 361.342432 -235.269278)
		(stroke
			(width 0.05715)
			(type default)
		)
		(layer "In11.Cu")
	)
	(gr_line
		(start 361.342432 -233.64952)
		(end 361.342432 -233.649266)
		(stroke
			(width 0.05715)
			(type default)
		)
		(layer "In11.Cu")
	)
	(gr_arc
		(start 361.52836 -291.526214)
		(mid 361.551506 -291.544872)
		(end 361.575604 -291.562282)
		(stroke
			(width 0.05715)
			(type default)
		)
		(layer "In11.Cu")
	)
	(gr_line
		(start 361.575604 -291.562282)
		(end 361.581192 -291.56533)
		(stroke
			(width 0.05715)
			(type default)
		)
		(layer "In11.Cu")
	)
	(gr_line
		(start 361.581192 -291.56533)
		(end 361.60837 -291.581332)
		(stroke
			(width 0.05715)
			(type default)
		)
		(layer "In11.Cu")
	)
	(gr_arc
		(start 361.599226 -285.096204)
		(mid 361.601256 -285.097351)
		(end 361.60329 -285.09849)
		(stroke
			(width 0.05715)
			(type default)
		)
		(layer "In11.Cu")
	)
	(gr_line
		(start 361.603036 -293.198296)
		(end 361.604814 -293.199312)
		(stroke
			(width 0.05715)
			(type default)
		)
		(layer "In11.Cu")
	)
	(gr_line
		(start 361.605576 -293.19982)
		(end 361.613958 -293.204646)
		(stroke
			(width 0.05715)
			(type default)
		)
		(layer "In11.Cu")
	)
	(gr_line
		(start 361.608116 -283.481272)
		(end 361.612688 -283.484066)
		(stroke
			(width 0.05715)
			(type default)
		)
		(layer "In11.Cu")
	)
	(gr_line
		(start 361.608116 -281.86126)
		(end 361.612688 -281.864054)
		(stroke
			(width 0.05715)
			(type default)
		)
		(layer "In11.Cu")
	)
	(gr_line
		(start 361.611672 -285.10357)
		(end 361.611926 -285.10357)
		(stroke
			(width 0.05715)
			(type default)
		)
		(layer "In11.Cu")
	)
	(gr_line
		(start 361.611672 -279.268936)
		(end 361.610148 -279.269952)
		(stroke
			(width 0.05715)
			(type default)
		)
		(layer "In11.Cu")
	)
	(gr_line
		(start 361.611926 -284.128718)
		(end 361.611672 -284.128972)
		(stroke
			(width 0.05715)
			(type default)
		)
		(layer "In11.Cu")
	)
	(gr_line
		(start 361.611926 -282.508706)
		(end 361.608116 -282.510992)
		(stroke
			(width 0.05715)
			(type default)
		)
		(layer "In11.Cu")
	)
	(gr_line
		(start 361.611926 -280.888694)
		(end 361.608116 -280.89098)
		(stroke
			(width 0.05715)
			(type default)
		)
		(layer "In11.Cu")
	)
	(gr_line
		(start 361.611926 -277.64867)
		(end 361.611672 -277.648924)
		(stroke
			(width 0.05715)
			(type default)
		)
		(layer "In11.Cu")
	)
	(gr_line
		(start 361.612688 -283.484066)
		(end 361.613196 -283.48432)
		(stroke
			(width 0.05715)
			(type default)
		)
		(layer "In11.Cu")
	)
	(gr_line
		(start 361.612688 -281.864054)
		(end 361.613196 -281.864308)
		(stroke
			(width 0.05715)
			(type default)
		)
		(layer "In11.Cu")
	)
	(gr_line
		(start 361.612942 -282.508198)
		(end 361.611926 -282.508706)
		(stroke
			(width 0.05715)
			(type default)
		)
		(layer "In11.Cu")
	)
	(gr_line
		(start 361.612942 -280.888186)
		(end 361.611926 -280.888694)
		(stroke
			(width 0.05715)
			(type default)
		)
		(layer "In11.Cu")
	)
	(gr_line
		(start 361.613704 -388.176516)
		(end 361.613704 -387.475476)
		(stroke
			(width 0.07112)
			(type default)
		)
		(layer "In11.Cu")
	)
	(gr_line
		(start 361.613704 -387.048756)
		(end 361.613704 -386.347716)
		(stroke
			(width 0.07112)
			(type default)
		)
		(layer "In11.Cu")
	)
	(gr_line
		(start 361.613704 -385.388358)
		(end 361.613704 -384.687318)
		(stroke
			(width 0.07112)
			(type default)
		)
		(layer "In11.Cu")
	)
	(gr_line
		(start 361.613958 -293.204646)
		(end 361.61472 -293.205154)
		(stroke
			(width 0.05715)
			(type default)
		)
		(layer "In11.Cu")
	)
	(gr_line
		(start 361.61472 -293.205154)
		(end 361.615736 -293.205662)
		(stroke
			(width 0.05715)
			(type default)
		)
		(layer "In11.Cu")
	)
	(gr_line
		(start 361.62615 -288.979864)
		(end 361.623102 -288.981896)
		(stroke
			(width 0.05715)
			(type default)
		)
		(layer "In11.Cu")
	)
	(gr_line
		(start 361.658916 -291.385498)
		(end 361.709716 -291.418518)
		(stroke
			(width 0.05715)
			(type default)
		)
		(layer "In11.Cu")
	)
	(gr_line
		(start 361.689904 -225.854006)
		(end 361.690158 -225.85426)
		(stroke
			(width 0.05715)
			(type default)
		)
		(layer "In11.Cu")
	)
	(gr_line
		(start 361.702858 -292.39591)
		(end 361.700826 -292.39718)
		(stroke
			(width 0.05715)
			(type default)
		)
		(layer "In11.Cu")
	)
	(gr_line
		(start 361.706414 -288.177732)
		(end 361.709462 -288.17951)
		(stroke
			(width 0.05715)
			(type default)
		)
		(layer "In11.Cu")
	)
	(gr_line
		(start 361.7087 -284.293056)
		(end 361.707938 -284.293564)
		(stroke
			(width 0.05715)
			(type default)
		)
		(layer "In11.Cu")
	)
	(gr_line
		(start 361.709716 -293.0398)
		(end 361.710732 -293.040308)
		(stroke
			(width 0.05715)
			(type default)
		)
		(layer "In11.Cu")
	)
	(gr_line
		(start 361.710732 -293.040308)
		(end 361.711494 -293.040816)
		(stroke
			(width 0.05715)
			(type default)
		)
		(layer "In11.Cu")
	)
	(gr_line
		(start 361.712256 -289.150806)
		(end 361.707684 -289.153346)
		(stroke
			(width 0.05715)
			(type default)
		)
		(layer "In11.Cu")
	)
	(gr_line
		(start 361.727242 -289.141408)
		(end 361.726734 -289.141662)
		(stroke
			(width 0.05715)
			(type default)
		)
		(layer "In11.Cu")
	)
	(gr_line
		(start 361.732576 -224.83572)
		(end 361.732576 -224.835974)
		(stroke
			(width 0.05715)
			(type default)
		)
		(layer "In11.Cu")
	)
	(gr_arc
		(start 361.734862 -247.37314)
		(mid 361.738787 -247.375951)
		(end 361.742736 -247.378728)
		(stroke
			(width 0.05715)
			(type default)
		)
		(layer "In11.Cu")
	)
	(gr_line
		(start 361.738164 -283.336492)
		(end 361.745276 -283.340556)
		(stroke
			(width 0.05715)
			(type default)
		)
		(layer "In11.Cu")
	)
	(gr_line
		(start 361.738164 -281.71648)
		(end 361.745276 -281.720544)
		(stroke
			(width 0.05715)
			(type default)
		)
		(layer "In11.Cu")
	)
	(gr_line
		(start 361.738418 -284.956504)
		(end 361.745276 -284.960568)
		(stroke
			(width 0.05715)
			(type default)
		)
		(layer "In11.Cu")
	)
	(gr_line
		(start 361.73918 -293.056818)
		(end 361.746038 -293.060882)
		(stroke
			(width 0.05715)
			(type default)
		)
		(layer "In11.Cu")
	)
	(gr_arc
		(start 361.746038 -293.060882)
		(mid 361.746419 -293.061136)
		(end 361.7468 -293.06139)
		(stroke
			(width 0.05715)
			(type default)
		)
		(layer "In11.Cu")
	)
	(gr_arc
		(start 361.7468 -284.961584)
		(mid 361.746038 -284.961075)
		(end 361.745276 -284.960568)
		(stroke
			(width 0.05715)
			(type default)
		)
		(layer "In11.Cu")
	)
	(gr_arc
		(start 361.7468 -283.341572)
		(mid 361.746038 -283.341063)
		(end 361.745276 -283.340556)
		(stroke
			(width 0.05715)
			(type default)
		)
		(layer "In11.Cu")
	)
	(gr_arc
		(start 361.7468 -281.72156)
		(mid 361.746038 -281.721051)
		(end 361.745276 -281.720544)
		(stroke
			(width 0.05715)
			(type default)
		)
		(layer "In11.Cu")
	)
	(gr_line
		(start 361.749594 -247.382792)
		(end 361.742736 -247.378728)
		(stroke
			(width 0.05715)
			(type default)
		)
		(layer "In11.Cu")
	)
	(gr_line
		(start 361.750356 -247.3833)
		(end 361.749594 -247.382792)
		(stroke
			(width 0.05715)
			(type default)
		)
		(layer "In11.Cu")
	)
	(gr_line
		(start 361.750864 -247.383554)
		(end 361.750356 -247.3833)
		(stroke
			(width 0.05715)
			(type default)
		)
		(layer "In11.Cu")
	)
	(gr_arc
		(start 361.75315 -284.966156)
		(mid 361.749983 -284.963859)
		(end 361.7468 -284.961584)
		(stroke
			(width 0.05715)
			(type default)
		)
		(layer "In11.Cu")
	)
	(gr_arc
		(start 361.75315 -283.346144)
		(mid 361.749983 -283.343847)
		(end 361.7468 -283.341572)
		(stroke
			(width 0.05715)
			(type default)
		)
		(layer "In11.Cu")
	)
	(gr_arc
		(start 361.75315 -281.726132)
		(mid 361.749983 -281.723835)
		(end 361.7468 -281.72156)
		(stroke
			(width 0.05715)
			(type default)
		)
		(layer "In11.Cu")
	)
	(gr_arc
		(start 361.75442 -293.066724)
		(mid 361.750621 -293.064042)
		(end 361.7468 -293.06139)
		(stroke
			(width 0.05715)
			(type default)
		)
		(layer "In11.Cu")
	)
	(gr_line
		(start 361.777534 -247.399048)
		(end 361.775756 -247.398032)
		(stroke
			(width 0.05715)
			(type default)
		)
		(layer "In11.Cu")
	)
	(gr_line
		(start 361.779566 -247.400318)
		(end 361.778804 -247.39981)
		(stroke
			(width 0.05715)
			(type default)
		)
		(layer "In11.Cu")
	)
	(gr_line
		(start 361.780074 -245.78056)
		(end 361.779058 -245.780052)
		(stroke
			(width 0.05715)
			(type default)
		)
		(layer "In11.Cu")
	)
	(gr_line
		(start 361.780836 -247.40108)
		(end 361.779566 -247.400318)
		(stroke
			(width 0.05715)
			(type default)
		)
		(layer "In11.Cu")
	)
	(gr_line
		(start 361.781852 -247.401588)
		(end 361.780836 -247.40108)
		(stroke
			(width 0.05715)
			(type default)
		)
		(layer "In11.Cu")
	)
	(gr_line
		(start 361.782106 -245.78183)
		(end 361.780074 -245.78056)
		(stroke
			(width 0.05715)
			(type default)
		)
		(layer "In11.Cu")
	)
	(gr_line
		(start 361.78236 -247.401588)
		(end 361.781852 -247.401588)
		(stroke
			(width 0.05715)
			(type default)
		)
		(layer "In11.Cu")
	)
	(gr_line
		(start 361.846368 -244.989858)
		(end 361.846114 -244.989858)
		(stroke
			(width 0.05715)
			(type default)
		)
		(layer "In11.Cu")
	)
	(gr_line
		(start 361.875832 -247.235472)
		(end 361.874816 -247.234964)
		(stroke
			(width 0.05715)
			(type default)
		)
		(layer "In11.Cu")
	)
	(gr_line
		(start 361.876086 -245.615714)
		(end 361.875324 -245.615206)
		(stroke
			(width 0.05715)
			(type default)
		)
		(layer "In11.Cu")
	)
	(gr_line
		(start 361.877102 -247.236234)
		(end 361.875832 -247.235472)
		(stroke
			(width 0.05715)
			(type default)
		)
		(layer "In11.Cu")
	)
	(gr_line
		(start 361.877102 -245.616222)
		(end 361.876086 -245.615714)
		(stroke
			(width 0.05715)
			(type default)
		)
		(layer "In11.Cu")
	)
	(gr_line
		(start 361.877864 -247.236742)
		(end 361.877102 -247.236234)
		(stroke
			(width 0.05715)
			(type default)
		)
		(layer "In11.Cu")
	)
	(gr_line
		(start 361.877864 -245.61673)
		(end 361.877102 -245.616222)
		(stroke
			(width 0.05715)
			(type default)
		)
		(layer "In11.Cu")
	)
	(gr_line
		(start 361.878372 -245.616984)
		(end 361.877864 -245.61673)
		(stroke
			(width 0.05715)
			(type default)
		)
		(layer "In11.Cu")
	)
	(gr_arc
		(start 361.881166 -245.618762)
		(mid 361.87977 -245.617871)
		(end 361.878372 -245.616984)
		(stroke
			(width 0.05715)
			(type default)
		)
		(layer "In11.Cu")
	)
	(gr_line
		(start 361.923838 -221.083124)
		(end 361.923838 -221.054676)
		(stroke
			(width 0.05715)
			(type default)
		)
		(layer "In11.Cu")
	)
	(gr_arc
		(start 361.94111 -247.278144)
		(mid 361.937944 -247.275593)
		(end 361.93476 -247.273064)
		(stroke
			(width 0.05715)
			(type default)
		)
		(layer "In11.Cu")
	)
	(gr_arc
		(start 361.946698 -247.283224)
		(mid 361.943911 -247.280676)
		(end 361.94111 -247.278144)
		(stroke
			(width 0.05715)
			(type default)
		)
		(layer "In11.Cu")
	)
	(gr_line
		(start 361.95254 -373.461788)
		(end 362.177838 -373.099076)
		(stroke
			(width 0.07112)
			(type default)
		)
		(layer "In11.Cu")
	)
	(gr_arc
		(start 361.969558 -231.524048)
		(mid 361.969548 -231.52735)
		(end 361.969558 -231.530652)
		(stroke
			(width 0.05715)
			(type default)
		)
		(layer "In11.Cu")
	)
	(gr_line
		(start 361.969558 -221.308676)
		(end 361.969304 -221.30893)
		(stroke
			(width 0.05715)
			(type default)
		)
		(layer "In11.Cu")
	)
	(gr_line
		(start 361.969558 -221.128844)
		(end 361.923838 -221.083124)
		(stroke
			(width 0.05715)
			(type default)
		)
		(layer "In11.Cu")
	)
	(gr_arc
		(start 361.971082 -229.918514)
		(mid 361.972051 -229.926648)
		(end 361.973114 -229.93477)
		(stroke
			(width 0.05715)
			(type default)
		)
		(layer "In11.Cu")
	)
	(gr_arc
		(start 361.97159 -229.901496)
		(mid 361.97128 -229.910003)
		(end 361.971082 -229.918514)
		(stroke
			(width 0.05715)
			(type default)
		)
		(layer "In11.Cu")
	)
	(gr_line
		(start 361.996482 -373.648986)
		(end 361.95254 -373.461788)
		(stroke
			(width 0.07112)
			(type default)
		)
		(layer "In11.Cu")
	)
	(gr_line
		(start 361.996736 -373.650764)
		(end 361.996736 -373.65051)
		(stroke
			(width 0.07112)
			(type default)
		)
		(layer "In11.Cu")
	)
	(gr_line
		(start 362.064808 -248.534174)
		(end 362.36275 -248.534174)
		(stroke
			(width 0.05715)
			(type default)
		)
		(layer "In11.Cu")
	)
	(gr_line
		(start 362.064808 -246.914162)
		(end 362.36275 -246.914162)
		(stroke
			(width 0.05715)
			(type default)
		)
		(layer "In11.Cu")
	)
	(gr_line
		(start 362.064808 -245.29415)
		(end 362.36275 -245.29415)
		(stroke
			(width 0.05715)
			(type default)
		)
		(layer "In11.Cu")
	)
	(gr_line
		(start 362.064808 -243.674138)
		(end 362.36275 -243.674138)
		(stroke
			(width 0.05715)
			(type default)
		)
		(layer "In11.Cu")
	)
	(gr_line
		(start 362.069888 -276.845522)
		(end 362.068364 -276.846284)
		(stroke
			(width 0.05715)
			(type default)
		)
		(layer "In11.Cu")
	)
	(gr_line
		(start 362.072682 -276.843998)
		(end 362.071412 -276.844506)
		(stroke
			(width 0.05715)
			(type default)
		)
		(layer "In11.Cu")
	)
	(gr_line
		(start 362.074714 -276.842728)
		(end 362.074206 -276.842982)
		(stroke
			(width 0.05715)
			(type default)
		)
		(layer "In11.Cu")
	)
	(gr_line
		(start 362.076746 -276.841712)
		(end 362.075984 -276.841966)
		(stroke
			(width 0.05715)
			(type default)
		)
		(layer "In11.Cu")
	)
	(gr_line
		(start 362.079794 -276.839934)
		(end 362.078778 -276.840442)
		(stroke
			(width 0.05715)
			(type default)
		)
		(layer "In11.Cu")
	)
	(gr_line
		(start 362.083858 -276.837394)
		(end 362.082588 -276.838156)
		(stroke
			(width 0.05715)
			(type default)
		)
		(layer "In11.Cu")
	)
	(gr_line
		(start 362.096812 -278.45004)
		(end 362.09478 -278.45131)
		(stroke
			(width 0.05715)
			(type default)
		)
		(layer "In11.Cu")
	)
	(gr_line
		(start 362.09732 -229.545896)
		(end 362.09732 -229.54615)
		(stroke
			(width 0.05715)
			(type default)
		)
		(layer "In11.Cu")
	)
	(gr_line
		(start 362.156502 -247.682766)
		(end 362.156502 -247.683528)
		(stroke
			(width 0.05715)
			(type default)
		)
		(layer "In11.Cu")
	)
	(gr_line
		(start 362.156502 -247.682004)
		(end 362.156502 -247.682766)
		(stroke
			(width 0.05715)
			(type default)
		)
		(layer "In11.Cu")
	)
	(gr_line
		(start 362.159804 -221.804484)
		(end 362.160058 -221.80423)
		(stroke
			(width 0.05715)
			(type default)
		)
		(layer "In11.Cu")
	)
	(gr_line
		(start 362.160058 -221.38767)
		(end 362.159804 -221.387924)
		(stroke
			(width 0.05715)
			(type default)
		)
		(layer "In11.Cu")
	)
	(gr_line
		(start 362.160058 -221.128844)
		(end 362.205778 -221.083124)
		(stroke
			(width 0.05715)
			(type default)
		)
		(layer "In11.Cu")
	)
	(gr_line
		(start 362.161582 -223.452944)
		(end 362.161582 -223.444054)
		(stroke
			(width 0.05715)
			(type default)
		)
		(layer "In11.Cu")
	)
	(gr_line
		(start 362.165138 -277.010622)
		(end 362.164376 -277.01113)
		(stroke
			(width 0.05715)
			(type default)
		)
		(layer "In11.Cu")
	)
	(gr_line
		(start 362.166154 -277.010114)
		(end 362.165138 -277.010622)
		(stroke
			(width 0.05715)
			(type default)
		)
		(layer "In11.Cu")
	)
	(gr_line
		(start 362.168186 -277.009098)
		(end 362.16717 -277.009606)
		(stroke
			(width 0.05715)
			(type default)
		)
		(layer "In11.Cu")
	)
	(gr_line
		(start 362.168948 -277.00859)
		(end 362.168186 -277.009098)
		(stroke
			(width 0.05715)
			(type default)
		)
		(layer "In11.Cu")
	)
	(gr_line
		(start 362.17225 -277.006812)
		(end 362.17098 -277.007574)
		(stroke
			(width 0.05715)
			(type default)
		)
		(layer "In11.Cu")
	)
	(gr_line
		(start 362.173012 -277.006304)
		(end 362.17225 -277.006812)
		(stroke
			(width 0.05715)
			(type default)
		)
		(layer "In11.Cu")
	)
	(gr_line
		(start 362.174282 -277.005542)
		(end 362.173012 -277.006304)
		(stroke
			(width 0.05715)
			(type default)
		)
		(layer "In11.Cu")
	)
	(gr_line
		(start 362.175298 -277.005034)
		(end 362.174282 -277.005542)
		(stroke
			(width 0.05715)
			(type default)
		)
		(layer "In11.Cu")
	)
	(gr_line
		(start 362.177838 -373.099076)
		(end 362.365544 -373.055134)
		(stroke
			(width 0.07112)
			(type default)
		)
		(layer "In11.Cu")
	)
	(gr_line
		(start 362.192824 -278.614886)
		(end 362.192824 -278.61514)
		(stroke
			(width 0.05715)
			(type default)
		)
		(layer "In11.Cu")
	)
	(gr_line
		(start 362.205778 -221.083124)
		(end 362.205778 -221.054676)
		(stroke
			(width 0.05715)
			(type default)
		)
		(layer "In11.Cu")
	)
	(gr_line
		(start 362.223812 -296.432478)
		(end 362.223812 -296.446956)
		(stroke
			(width 0.05715)
			(type default)
		)
		(layer "In11.Cu")
	)
	(gr_arc
		(start 362.234988 -228.762052)
		(mid 362.237903 -228.76384)
		(end 362.24083 -228.765608)
		(stroke
			(width 0.05715)
			(type default)
		)
		(layer "In11.Cu")
	)
	(gr_line
		(start 362.236258 -373.799608)
		(end 362.278676 -373.731282)
		(stroke
			(width 0.07112)
			(type default)
		)
		(layer "In11.Cu")
	)
	(gr_arc
		(start 362.241592 -227.80244)
		(mid 362.238283 -227.804461)
		(end 362.234988 -227.806504)
		(stroke
			(width 0.05715)
			(type default)
		)
		(layer "In11.Cu")
	)
	(gr_line
		(start 362.248704 -222.941642)
		(end 362.253022 -222.939102)
		(stroke
			(width 0.05715)
			(type default)
		)
		(layer "In11.Cu")
	)
	(gr_line
		(start 362.250736 -246.59082)
		(end 362.249466 -246.590058)
		(stroke
			(width 0.05715)
			(type default)
		)
		(layer "In11.Cu")
	)
	(gr_line
		(start 362.251752 -222.291656)
		(end 362.250736 -222.291148)
		(stroke
			(width 0.05715)
			(type default)
		)
		(layer "In11.Cu")
	)
	(gr_line
		(start 362.252006 -242.376452)
		(end 362.252514 -242.376198)
		(stroke
			(width 0.05715)
			(type default)
		)
		(layer "In11.Cu")
	)
	(gr_line
		(start 362.252006 -240.75644)
		(end 362.252514 -240.756186)
		(stroke
			(width 0.05715)
			(type default)
		)
		(layer "In11.Cu")
	)
	(gr_line
		(start 362.252006 -239.136428)
		(end 362.252514 -239.136174)
		(stroke
			(width 0.05715)
			(type default)
		)
		(layer "In11.Cu")
	)
	(gr_line
		(start 362.252006 -237.516416)
		(end 362.252514 -237.516162)
		(stroke
			(width 0.05715)
			(type default)
		)
		(layer "In11.Cu")
	)
	(gr_line
		(start 362.252006 -235.896404)
		(end 362.252514 -235.89615)
		(stroke
			(width 0.05715)
			(type default)
		)
		(layer "In11.Cu")
	)
	(gr_line
		(start 362.252006 -234.276392)
		(end 362.252514 -234.276138)
		(stroke
			(width 0.05715)
			(type default)
		)
		(layer "In11.Cu")
	)
	(gr_line
		(start 362.252006 -232.65638)
		(end 362.252514 -232.656126)
		(stroke
			(width 0.05715)
			(type default)
		)
		(layer "In11.Cu")
	)
	(gr_line
		(start 362.25226 -248.211848)
		(end 362.251752 -248.211594)
		(stroke
			(width 0.05715)
			(type default)
		)
		(layer "In11.Cu")
	)
	(gr_line
		(start 362.25226 -222.29191)
		(end 362.251752 -222.291656)
		(stroke
			(width 0.05715)
			(type default)
		)
		(layer "In11.Cu")
	)
	(gr_line
		(start 362.252514 -243.352066)
		(end 362.252006 -243.351812)
		(stroke
			(width 0.05715)
			(type default)
		)
		(layer "In11.Cu")
	)
	(gr_line
		(start 362.252514 -242.376198)
		(end 362.255308 -242.374674)
		(stroke
			(width 0.05715)
			(type default)
		)
		(layer "In11.Cu")
	)
	(gr_line
		(start 362.252514 -241.732054)
		(end 362.252006 -241.7318)
		(stroke
			(width 0.05715)
			(type default)
		)
		(layer "In11.Cu")
	)
	(gr_line
		(start 362.252514 -240.756186)
		(end 362.255308 -240.754662)
		(stroke
			(width 0.05715)
			(type default)
		)
		(layer "In11.Cu")
	)
	(gr_line
		(start 362.252514 -240.112042)
		(end 362.251752 -240.111534)
		(stroke
			(width 0.05715)
			(type default)
		)
		(layer "In11.Cu")
	)
	(gr_line
		(start 362.252514 -239.136174)
		(end 362.255308 -239.13465)
		(stroke
			(width 0.05715)
			(type default)
		)
		(layer "In11.Cu")
	)
	(gr_line
		(start 362.252514 -238.49203)
		(end 362.251752 -238.491522)
		(stroke
			(width 0.05715)
			(type default)
		)
		(layer "In11.Cu")
	)
	(gr_line
		(start 362.252514 -237.516162)
		(end 362.255308 -237.514638)
		(stroke
			(width 0.05715)
			(type default)
		)
		(layer "In11.Cu")
	)
	(gr_line
		(start 362.252514 -236.872018)
		(end 362.252006 -236.871764)
		(stroke
			(width 0.05715)
			(type default)
		)
		(layer "In11.Cu")
	)
	(gr_line
		(start 362.252514 -235.89615)
		(end 362.255308 -235.894626)
		(stroke
			(width 0.05715)
			(type default)
		)
		(layer "In11.Cu")
	)
	(gr_line
		(start 362.252514 -235.252006)
		(end 362.251752 -235.251498)
		(stroke
			(width 0.05715)
			(type default)
		)
		(layer "In11.Cu")
	)
	(gr_line
		(start 362.252514 -234.276138)
		(end 362.255308 -234.274614)
		(stroke
			(width 0.05715)
			(type default)
		)
		(layer "In11.Cu")
	)
	(gr_line
		(start 362.252514 -233.631994)
		(end 362.251752 -233.631486)
		(stroke
			(width 0.05715)
			(type default)
		)
		(layer "In11.Cu")
	)
	(gr_line
		(start 362.252514 -232.656126)
		(end 362.255308 -232.654602)
		(stroke
			(width 0.05715)
			(type default)
		)
		(layer "In11.Cu")
	)
	(gr_line
		(start 362.252514 -232.011982)
		(end 362.251752 -232.011474)
		(stroke
			(width 0.05715)
			(type default)
		)
		(layer "In11.Cu")
	)
	(gr_line
		(start 362.253784 -243.352828)
		(end 362.252514 -243.352066)
		(stroke
			(width 0.05715)
			(type default)
		)
		(layer "In11.Cu")
	)
	(gr_line
		(start 362.253784 -241.732816)
		(end 362.252514 -241.732054)
		(stroke
			(width 0.05715)
			(type default)
		)
		(layer "In11.Cu")
	)
	(gr_line
		(start 362.253784 -240.112804)
		(end 362.252514 -240.112042)
		(stroke
			(width 0.05715)
			(type default)
		)
		(layer "In11.Cu")
	)
	(gr_line
		(start 362.253784 -238.492792)
		(end 362.252514 -238.49203)
		(stroke
			(width 0.05715)
			(type default)
		)
		(layer "In11.Cu")
	)
	(gr_line
		(start 362.253784 -236.87278)
		(end 362.252514 -236.872018)
		(stroke
			(width 0.05715)
			(type default)
		)
		(layer "In11.Cu")
	)
	(gr_line
		(start 362.253784 -235.252768)
		(end 362.252514 -235.252006)
		(stroke
			(width 0.05715)
			(type default)
		)
		(layer "In11.Cu")
	)
	(gr_line
		(start 362.253784 -233.632756)
		(end 362.252514 -233.631994)
		(stroke
			(width 0.05715)
			(type default)
		)
		(layer "In11.Cu")
	)
	(gr_line
		(start 362.253784 -232.012744)
		(end 362.252514 -232.011982)
		(stroke
			(width 0.05715)
			(type default)
		)
		(layer "In11.Cu")
	)
	(gr_line
		(start 362.253784 -228.772974)
		(end 362.252514 -228.772212)
		(stroke
			(width 0.05715)
			(type default)
		)
		(layer "In11.Cu")
	)
	(gr_line
		(start 362.25607 -227.794312)
		(end 362.25734 -227.79355)
		(stroke
			(width 0.05715)
			(type default)
		)
		(layer "In11.Cu")
	)
	(gr_line
		(start 362.25734 -227.79355)
		(end 362.258356 -227.793042)
		(stroke
			(width 0.05715)
			(type default)
		)
		(layer "In11.Cu")
	)
	(gr_line
		(start 362.258356 -227.793042)
		(end 362.259118 -227.792534)
		(stroke
			(width 0.05715)
			(type default)
		)
		(layer "In11.Cu")
	)
	(gr_line
		(start 362.269278 -295.955974)
		(end 362.269532 -295.95572)
		(stroke
			(width 0.05715)
			(type default)
		)
		(layer "In11.Cu")
	)
	(gr_line
		(start 362.269532 -296.386758)
		(end 362.223812 -296.432478)
		(stroke
			(width 0.05715)
			(type default)
		)
		(layer "In11.Cu")
	)
	(gr_line
		(start 362.269532 -296.372788)
		(end 362.269532 -296.386758)
		(stroke
			(width 0.05715)
			(type default)
		)
		(layer "In11.Cu")
	)
	(gr_line
		(start 362.278676 -373.731536)
		(end 362.60659 -373.203724)
		(stroke
			(width 0.07112)
			(type default)
		)
		(layer "In11.Cu")
	)
	(gr_line
		(start 362.278676 -373.731282)
		(end 362.278676 -373.731536)
		(stroke
			(width 0.07112)
			(type default)
		)
		(layer "In11.Cu")
	)
	(gr_line
		(start 362.285534 -231.017064)
		(end 362.28528 -231.017064)
		(stroke
			(width 0.05715)
			(type default)
		)
		(layer "In11.Cu")
	)
	(gr_arc
		(start 362.344716 -223.106234)
		(mid 362.34497 -223.106107)
		(end 362.345224 -223.10598)
		(stroke
			(width 0.05715)
			(type default)
		)
		(layer "In11.Cu")
	)
	(gr_line
		(start 362.346494 -226.342194)
		(end 362.347256 -226.341686)
		(stroke
			(width 0.05715)
			(type default)
		)
		(layer "In11.Cu")
	)
	(gr_line
		(start 362.347002 -243.186204)
		(end 362.345732 -243.185442)
		(stroke
			(width 0.05715)
			(type default)
		)
		(layer "In11.Cu")
	)
	(gr_line
		(start 362.347002 -241.566192)
		(end 362.345732 -241.56543)
		(stroke
			(width 0.05715)
			(type default)
		)
		(layer "In11.Cu")
	)
	(gr_line
		(start 362.347002 -236.706156)
		(end 362.345732 -236.705394)
		(stroke
			(width 0.05715)
			(type default)
		)
		(layer "In11.Cu")
	)
	(gr_line
		(start 362.347002 -222.126302)
		(end 362.345732 -222.12554)
		(stroke
			(width 0.05715)
			(type default)
		)
		(layer "In11.Cu")
	)
	(gr_line
		(start 362.347764 -243.186712)
		(end 362.347002 -243.186204)
		(stroke
			(width 0.05715)
			(type default)
		)
		(layer "In11.Cu")
	)
	(gr_line
		(start 362.347764 -242.541552)
		(end 362.34878 -242.541044)
		(stroke
			(width 0.05715)
			(type default)
		)
		(layer "In11.Cu")
	)
	(gr_line
		(start 362.347764 -241.5667)
		(end 362.347002 -241.566192)
		(stroke
			(width 0.05715)
			(type default)
		)
		(layer "In11.Cu")
	)
	(gr_line
		(start 362.347764 -240.92154)
		(end 362.34878 -240.921032)
		(stroke
			(width 0.05715)
			(type default)
		)
		(layer "In11.Cu")
	)
	(gr_line
		(start 362.347764 -239.301528)
		(end 362.34878 -239.30102)
		(stroke
			(width 0.05715)
			(type default)
		)
		(layer "In11.Cu")
	)
	(gr_line
		(start 362.347764 -237.681516)
		(end 362.34878 -237.681008)
		(stroke
			(width 0.05715)
			(type default)
		)
		(layer "In11.Cu")
	)
	(gr_line
		(start 362.347764 -236.706664)
		(end 362.347002 -236.706156)
		(stroke
			(width 0.05715)
			(type default)
		)
		(layer "In11.Cu")
	)
	(gr_line
		(start 362.347764 -236.061504)
		(end 362.34878 -236.060996)
		(stroke
			(width 0.05715)
			(type default)
		)
		(layer "In11.Cu")
	)
	(gr_line
		(start 362.347764 -234.441492)
		(end 362.34878 -234.440984)
		(stroke
			(width 0.05715)
			(type default)
		)
		(layer "In11.Cu")
	)
	(gr_line
		(start 362.347764 -232.82148)
		(end 362.34878 -232.820972)
		(stroke
			(width 0.05715)
			(type default)
		)
		(layer "In11.Cu")
	)
	(gr_line
		(start 362.347764 -228.606858)
		(end 362.347256 -228.606604)
		(stroke
			(width 0.05715)
			(type default)
		)
		(layer "In11.Cu")
	)
	(gr_line
		(start 362.348272 -246.42699)
		(end 362.344208 -246.424704)
		(stroke
			(width 0.05715)
			(type default)
		)
		(layer "In11.Cu")
	)
	(gr_line
		(start 362.34878 -243.18722)
		(end 362.347764 -243.186712)
		(stroke
			(width 0.05715)
			(type default)
		)
		(layer "In11.Cu")
	)
	(gr_line
		(start 362.34878 -242.541044)
		(end 362.350304 -242.540028)
		(stroke
			(width 0.05715)
			(type default)
		)
		(layer "In11.Cu")
	)
	(gr_line
		(start 362.34878 -241.567208)
		(end 362.347764 -241.5667)
		(stroke
			(width 0.05715)
			(type default)
		)
		(layer "In11.Cu")
	)
	(gr_line
		(start 362.34878 -240.921032)
		(end 362.350304 -240.920016)
		(stroke
			(width 0.05715)
			(type default)
		)
		(layer "In11.Cu")
	)
	(gr_line
		(start 362.34878 -239.947196)
		(end 362.347764 -239.946688)
		(stroke
			(width 0.05715)
			(type default)
		)
		(layer "In11.Cu")
	)
	(gr_line
		(start 362.34878 -239.30102)
		(end 362.350304 -239.300004)
		(stroke
			(width 0.05715)
			(type default)
		)
		(layer "In11.Cu")
	)
	(gr_line
		(start 362.34878 -238.327184)
		(end 362.347764 -238.326676)
		(stroke
			(width 0.05715)
			(type default)
		)
		(layer "In11.Cu")
	)
	(gr_line
		(start 362.34878 -237.681008)
		(end 362.350304 -237.679992)
		(stroke
			(width 0.05715)
			(type default)
		)
		(layer "In11.Cu")
	)
	(gr_line
		(start 362.34878 -236.707172)
		(end 362.347764 -236.706664)
		(stroke
			(width 0.05715)
			(type default)
		)
		(layer "In11.Cu")
	)
	(gr_line
		(start 362.34878 -236.060996)
		(end 362.350304 -236.05998)
		(stroke
			(width 0.05715)
			(type default)
		)
		(layer "In11.Cu")
	)
	(gr_line
		(start 362.34878 -235.08716)
		(end 362.347764 -235.086652)
		(stroke
			(width 0.05715)
			(type default)
		)
		(layer "In11.Cu")
	)
	(gr_line
		(start 362.34878 -234.440984)
		(end 362.350304 -234.439968)
		(stroke
			(width 0.05715)
			(type default)
		)
		(layer "In11.Cu")
	)
	(gr_line
		(start 362.34878 -233.467148)
		(end 362.347764 -233.46664)
		(stroke
			(width 0.05715)
			(type default)
		)
		(layer "In11.Cu")
	)
	(gr_line
		(start 362.34878 -232.820972)
		(end 362.350304 -232.819956)
		(stroke
			(width 0.05715)
			(type default)
		)
		(layer "In11.Cu")
	)
	(gr_line
		(start 362.34878 -231.847136)
		(end 362.347764 -231.846628)
		(stroke
			(width 0.05715)
			(type default)
		)
		(layer "In11.Cu")
	)
	(gr_line
		(start 362.34878 -228.607366)
		(end 362.347764 -228.606858)
		(stroke
			(width 0.05715)
			(type default)
		)
		(layer "In11.Cu")
	)
	(gr_line
		(start 362.34878 -227.96119)
		(end 362.349542 -227.960682)
		(stroke
			(width 0.05715)
			(type default)
		)
		(layer "In11.Cu")
	)
	(gr_line
		(start 362.349034 -246.427498)
		(end 362.348272 -246.42699)
		(stroke
			(width 0.05715)
			(type default)
		)
		(layer "In11.Cu")
	)
	(gr_line
		(start 362.349288 -223.103694)
		(end 362.349034 -223.103948)
		(stroke
			(width 0.05715)
			(type default)
		)
		(layer "In11.Cu")
	)
	(gr_line
		(start 362.350304 -242.540028)
		(end 362.35132 -242.53952)
		(stroke
			(width 0.05715)
			(type default)
		)
		(layer "In11.Cu")
	)
	(gr_line
		(start 362.350304 -240.920016)
		(end 362.35132 -240.919508)
		(stroke
			(width 0.05715)
			(type default)
		)
		(layer "In11.Cu")
	)
	(gr_line
		(start 362.350304 -239.300004)
		(end 362.35132 -239.299496)
		(stroke
			(width 0.05715)
			(type default)
		)
		(layer "In11.Cu")
	)
	(gr_line
		(start 362.350304 -237.679992)
		(end 362.35132 -237.679484)
		(stroke
			(width 0.05715)
			(type default)
		)
		(layer "In11.Cu")
	)
	(gr_line
		(start 362.350304 -236.05998)
		(end 362.35132 -236.059472)
		(stroke
			(width 0.05715)
			(type default)
		)
		(layer "In11.Cu")
	)
	(gr_line
		(start 362.350304 -234.439968)
		(end 362.35132 -234.43946)
		(stroke
			(width 0.05715)
			(type default)
		)
		(layer "In11.Cu")
	)
	(gr_line
		(start 362.350304 -232.819956)
		(end 362.35132 -232.819448)
		(stroke
			(width 0.05715)
			(type default)
		)
		(layer "In11.Cu")
	)
	(gr_line
		(start 362.35132 -239.299496)
		(end 362.3564 -239.296448)
		(stroke
			(width 0.05715)
			(type default)
		)
		(layer "In11.Cu")
	)
	(gr_line
		(start 362.35132 -237.679484)
		(end 362.3564 -237.676436)
		(stroke
			(width 0.05715)
			(type default)
		)
		(layer "In11.Cu")
	)
	(gr_line
		(start 362.35132 -234.43946)
		(end 362.3564 -234.436412)
		(stroke
			(width 0.05715)
			(type default)
		)
		(layer "In11.Cu")
	)
	(gr_line
		(start 362.35132 -232.819448)
		(end 362.3564 -232.8164)
		(stroke
			(width 0.05715)
			(type default)
		)
		(layer "In11.Cu")
	)
	(gr_line
		(start 362.351828 -226.339146)
		(end 362.352336 -226.338892)
		(stroke
			(width 0.05715)
			(type default)
		)
		(layer "In11.Cu")
	)
	(gr_line
		(start 362.352336 -226.338892)
		(end 362.353098 -226.338384)
		(stroke
			(width 0.05715)
			(type default)
		)
		(layer "In11.Cu")
	)
	(gr_line
		(start 362.354368 -242.537742)
		(end 362.3564 -242.536472)
		(stroke
			(width 0.05715)
			(type default)
		)
		(layer "In11.Cu")
	)
	(gr_line
		(start 362.354368 -240.91773)
		(end 362.3564 -240.91646)
		(stroke
			(width 0.05715)
			(type default)
		)
		(layer "In11.Cu")
	)
	(gr_line
		(start 362.354368 -236.057694)
		(end 362.3564 -236.056424)
		(stroke
			(width 0.05715)
			(type default)
		)
		(layer "In11.Cu")
	)
	(gr_line
		(start 362.355638 -227.957126)
		(end 362.357924 -227.955856)
		(stroke
			(width 0.05715)
			(type default)
		)
		(layer "In11.Cu")
	)
	(gr_line
		(start 362.358686 -227.955602)
		(end 362.359702 -227.95484)
		(stroke
			(width 0.05715)
			(type default)
		)
		(layer "In11.Cu")
	)
	(gr_line
		(start 362.360718 -227.954332)
		(end 362.362242 -227.953316)
		(stroke
			(width 0.05715)
			(type default)
		)
		(layer "In11.Cu")
	)
	(gr_line
		(start 362.362242 -227.953316)
		(end 362.36275 -227.953062)
		(stroke
			(width 0.05715)
			(type default)
		)
		(layer "In11.Cu")
	)
	(gr_line
		(start 362.36275 -248.534174)
		(end 362.432092 -248.464832)
		(stroke
			(width 0.05715)
			(type default)
		)
		(layer "In11.Cu")
	)
	(gr_line
		(start 362.36275 -246.914162)
		(end 362.432092 -246.84482)
		(stroke
			(width 0.05715)
			(type default)
		)
		(layer "In11.Cu")
	)
	(gr_line
		(start 362.36275 -245.29415)
		(end 362.445554 -245.211346)
		(stroke
			(width 0.05715)
			(type default)
		)
		(layer "In11.Cu")
	)
	(gr_line
		(start 362.36275 -243.674138)
		(end 362.432092 -243.604796)
		(stroke
			(width 0.05715)
			(type default)
		)
		(layer "In11.Cu")
	)
	(gr_line
		(start 362.364782 -278.946102)
		(end 362.662724 -278.946102)
		(stroke
			(width 0.05715)
			(type default)
		)
		(layer "In11.Cu")
	)
	(gr_line
		(start 362.364782 -277.32609)
		(end 362.662724 -277.32609)
		(stroke
			(width 0.05715)
			(type default)
		)
		(layer "In11.Cu")
	)
	(gr_line
		(start 362.364782 -275.706078)
		(end 362.662724 -275.706078)
		(stroke
			(width 0.05715)
			(type default)
		)
		(layer "In11.Cu")
	)
	(gr_line
		(start 362.365798 -222.137224)
		(end 362.363766 -222.135954)
		(stroke
			(width 0.05715)
			(type default)
		)
		(layer "In11.Cu")
	)
	(gr_line
		(start 362.378498 -226.323652)
		(end 362.386118 -226.319334)
		(stroke
			(width 0.05715)
			(type default)
		)
		(layer "In11.Cu")
	)
	(gr_line
		(start 362.37926 -227.94341)
		(end 362.386118 -227.939346)
		(stroke
			(width 0.05715)
			(type default)
		)
		(layer "In11.Cu")
	)
	(gr_line
		(start 362.380784 -229.562406)
		(end 362.38053 -229.56266)
		(stroke
			(width 0.05715)
			(type default)
		)
		(layer "In11.Cu")
	)
	(gr_line
		(start 362.380784 -229.562406)
		(end 362.38688 -229.55885)
		(stroke
			(width 0.05715)
			(type default)
		)
		(layer "In11.Cu")
	)
	(gr_line
		(start 362.381546 -231.18191)
		(end 362.38688 -231.178862)
		(stroke
			(width 0.05715)
			(type default)
		)
		(layer "In11.Cu")
	)
	(gr_arc
		(start 362.38688 -231.178862)
		(mid 362.392364 -231.175085)
		(end 362.397802 -231.171242)
		(stroke
			(width 0.05715)
			(type default)
		)
		(layer "In11.Cu")
	)
	(gr_arc
		(start 362.38688 -229.55885)
		(mid 362.388279 -229.557836)
		(end 362.389674 -229.556818)
		(stroke
			(width 0.05715)
			(type default)
		)
		(layer "In11.Cu")
	)
	(gr_arc
		(start 362.38688 -227.938838)
		(mid 362.386499 -227.939092)
		(end 362.386118 -227.939346)
		(stroke
			(width 0.05715)
			(type default)
		)
		(layer "In11.Cu")
	)
	(gr_arc
		(start 362.38688 -227.938838)
		(mid 362.390829 -227.936061)
		(end 362.394754 -227.93325)
		(stroke
			(width 0.05715)
			(type default)
		)
		(layer "In11.Cu")
	)
	(gr_arc
		(start 362.38688 -226.318826)
		(mid 362.386499 -226.31908)
		(end 362.386118 -226.319334)
		(stroke
			(width 0.05715)
			(type default)
		)
		(layer "In11.Cu")
	)
	(gr_arc
		(start 362.38688 -226.318826)
		(mid 362.390829 -226.316049)
		(end 362.394754 -226.313238)
		(stroke
			(width 0.05715)
			(type default)
		)
		(layer "In11.Cu")
	)
	(gr_arc
		(start 362.391198 -229.555802)
		(mid 362.39438 -229.553526)
		(end 362.397548 -229.55123)
		(stroke
			(width 0.05715)
			(type default)
		)
		(layer "In11.Cu")
	)
	(gr_arc
		(start 362.413804 -287.459674)
		(mid 362.412149 -287.461448)
		(end 362.410502 -287.46323)
		(stroke
			(width 0.05715)
			(type default)
		)
		(layer "In11.Cu")
	)
	(gr_arc
		(start 362.418122 -287.455356)
		(mid 362.415953 -287.457505)
		(end 362.413804 -287.459674)
		(stroke
			(width 0.05715)
			(type default)
		)
		(layer "In11.Cu")
	)
	(gr_arc
		(start 362.449364 -245.188486)
		(mid 362.447343 -245.199897)
		(end 362.445554 -245.211346)
		(stroke
			(width 0.05715)
			(type default)
		)
		(layer "In11.Cu")
	)
	(gr_line
		(start 362.460032 -287.856422)
		(end 362.460286 -287.856168)
		(stroke
			(width 0.05715)
			(type default)
		)
		(layer "In11.Cu")
	)
	(gr_line
		(start 362.461302 -296.374058)
		(end 362.505752 -296.418508)
		(stroke
			(width 0.05715)
			(type default)
		)
		(layer "In11.Cu")
	)
	(gr_line
		(start 362.48594 -287.40481)
		(end 362.486448 -287.404556)
		(stroke
			(width 0.05715)
			(type default)
		)
		(layer "In11.Cu")
	)
	(gr_arc
		(start 362.4961 -291.548312)
		(mid 362.497622 -291.549585)
		(end 362.499148 -291.550852)
		(stroke
			(width 0.05715)
			(type default)
		)
		(layer "In11.Cu")
	)
	(gr_arc
		(start 362.499148 -291.550852)
		(mid 362.50067 -291.551998)
		(end 362.502196 -291.553138)
		(stroke
			(width 0.05715)
			(type default)
		)
		(layer "In11.Cu")
	)
	(gr_arc
		(start 362.501688 -290.639246)
		(mid 362.500417 -290.640133)
		(end 362.499148 -290.641024)
		(stroke
			(width 0.05715)
			(type default)
		)
		(layer "In11.Cu")
	)
	(gr_arc
		(start 362.50499 -293.175182)
		(mid 362.508789 -293.177864)
		(end 362.51261 -293.180516)
		(stroke
			(width 0.05715)
			(type default)
		)
		(layer "In11.Cu")
	)
	(gr_line
		(start 362.505752 -296.418508)
		(end 362.505752 -296.446956)
		(stroke
			(width 0.05715)
			(type default)
		)
		(layer "In11.Cu")
	)
	(gr_line
		(start 362.50626 -284.43428)
		(end 362.50626 -284.434534)
		(stroke
			(width 0.05715)
			(type default)
		)
		(layer "In11.Cu")
	)
	(gr_line
		(start 362.506514 -293.865554)
		(end 362.50499 -293.86657)
		(stroke
			(width 0.05715)
			(type default)
		)
		(layer "In11.Cu")
	)
	(gr_line
		(start 362.51261 -293.180516)
		(end 362.519468 -293.18458)
		(stroke
			(width 0.05715)
			(type default)
		)
		(layer "In11.Cu")
	)
	(gr_line
		(start 362.519468 -293.18458)
		(end 362.52023 -293.185088)
		(stroke
			(width 0.05715)
			(type default)
		)
		(layer "In11.Cu")
	)
	(gr_line
		(start 362.535216 -294.813736)
		(end 362.535724 -294.81399)
		(stroke
			(width 0.05715)
			(type default)
		)
		(layer "In11.Cu")
	)
	(gr_line
		(start 362.537756 -289.955224)
		(end 362.571284 -289.974782)
		(stroke
			(width 0.05715)
			(type default)
		)
		(layer "In11.Cu")
	)
	(gr_line
		(start 362.54182 -280.894282)
		(end 362.541058 -280.89479)
		(stroke
			(width 0.05715)
			(type default)
		)
		(layer "In11.Cu")
	)
	(gr_line
		(start 362.544106 -283.47924)
		(end 362.544614 -283.479494)
		(stroke
			(width 0.05715)
			(type default)
		)
		(layer "In11.Cu")
	)
	(gr_arc
		(start 362.545376 -286.720026)
		(mid 362.546138 -286.720408)
		(end 362.5469 -286.720788)
		(stroke
			(width 0.05715)
			(type default)
		)
		(layer "In11.Cu")
	)
	(gr_line
		(start 362.547662 -372.5037)
		(end 362.77296 -372.140988)
		(stroke
			(width 0.07112)
			(type default)
		)
		(layer "In11.Cu")
	)
	(gr_line
		(start 362.552996 -280.243788)
		(end 362.552742 -280.244042)
		(stroke
			(width 0.05715)
			(type default)
		)
		(layer "In11.Cu")
	)
	(gr_line
		(start 362.562394 -280.24963)
		(end 362.563664 -280.250392)
		(stroke
			(width 0.05715)
			(type default)
		)
		(layer "In11.Cu")
	)
	(gr_line
		(start 362.562902 -293.82974)
		(end 362.561632 -293.830502)
		(stroke
			(width 0.05715)
			(type default)
		)
		(layer "In11.Cu")
	)
	(gr_line
		(start 362.573062 -288.976054)
		(end 362.573062 -288.976308)
		(stroke
			(width 0.05715)
			(type default)
		)
		(layer "In11.Cu")
	)
	(gr_line
		(start 362.579412 -287.57118)
		(end 362.578904 -287.57118)
		(stroke
			(width 0.05715)
			(type default)
		)
		(layer "In11.Cu")
	)
	(gr_line
		(start 362.583222 -289.98164)
		(end 362.583476 -289.98164)
		(stroke
			(width 0.05715)
			(type default)
		)
		(layer "In11.Cu")
	)
	(gr_line
		(start 362.583984 -285.122112)
		(end 362.58373 -285.122112)
		(stroke
			(width 0.05715)
			(type default)
		)
		(layer "In11.Cu")
	)
	(gr_line
		(start 362.591604 -372.691152)
		(end 362.547662 -372.5037)
		(stroke
			(width 0.07112)
			(type default)
		)
		(layer "In11.Cu")
	)
	(gr_line
		(start 362.592366 -293.228268)
		(end 362.593128 -293.228776)
		(stroke
			(width 0.05715)
			(type default)
		)
		(layer "In11.Cu")
	)
	(gr_line
		(start 362.593128 -293.228776)
		(end 362.59516 -293.2303)
		(stroke
			(width 0.05715)
			(type default)
		)
		(layer "In11.Cu")
	)
	(gr_arc
		(start 362.59643 -293.231316)
		(mid 362.595796 -293.230807)
		(end 362.59516 -293.2303)
		(stroke
			(width 0.05715)
			(type default)
		)
		(layer "In11.Cu")
	)
	(gr_line
		(start 362.603542 -280.855928)
		(end 362.60278 -280.856436)
		(stroke
			(width 0.05715)
			(type default)
		)
		(layer "In11.Cu")
	)
	(gr_line
		(start 362.614718 -285.70555)
		(end 362.613448 -285.706566)
		(stroke
			(width 0.05715)
			(type default)
		)
		(layer "In11.Cu")
	)
	(gr_line
		(start 362.619798 -285.701232)
		(end 362.619544 -285.701232)
		(stroke
			(width 0.05715)
			(type default)
		)
		(layer "In11.Cu")
	)
	(gr_line
		(start 362.623354 -285.698184)
		(end 362.622592 -285.698692)
		(stroke
			(width 0.05715)
			(type default)
		)
		(layer "In11.Cu")
	)
	(gr_arc
		(start 362.624116 -248.45137)
		(mid 362.622325 -248.440048)
		(end 362.620306 -248.428764)
		(stroke
			(width 0.05715)
			(type default)
		)
		(layer "In11.Cu")
	)
	(gr_arc
		(start 362.624116 -246.831358)
		(mid 362.622325 -246.820036)
		(end 362.620306 -246.808752)
		(stroke
			(width 0.05715)
			(type default)
		)
		(layer "In11.Cu")
	)
	(gr_arc
		(start 362.624116 -243.591334)
		(mid 362.622324 -243.580012)
		(end 362.620306 -243.568728)
		(stroke
			(width 0.05715)
			(type default)
		)
		(layer "In11.Cu")
	)
	(gr_line
		(start 362.636816 -287.313878)
		(end 362.636816 -287.314132)
		(stroke
			(width 0.05715)
			(type default)
		)
		(layer "In11.Cu")
	)
	(gr_line
		(start 362.63707 -289.79114)
		(end 362.638086 -289.79114)
		(stroke
			(width 0.05715)
			(type default)
		)
		(layer "In11.Cu")
	)
	(gr_line
		(start 362.638848 -279.438354)
		(end 362.638594 -279.438354)
		(stroke
			(width 0.05715)
			(type default)
		)
		(layer "In11.Cu")
	)
	(gr_line
		(start 362.64088 -284.934914)
		(end 362.649262 -284.93974)
		(stroke
			(width 0.05715)
			(type default)
		)
		(layer "In11.Cu")
	)
	(gr_arc
		(start 362.641642 -280.075132)
		(mid 362.645061 -280.076929)
		(end 362.6485 -280.078688)
		(stroke
			(width 0.05715)
			(type default)
		)
		(layer "In11.Cu")
	)
	(gr_line
		(start 362.642404 -288.175446)
		(end 362.647992 -288.178748)
		(stroke
			(width 0.05715)
			(type default)
		)
		(layer "In11.Cu")
	)
	(gr_line
		(start 362.643166 -279.436068)
		(end 362.643166 -279.435814)
		(stroke
			(width 0.05715)
			(type default)
		)
		(layer "In11.Cu")
	)
	(gr_arc
		(start 362.644944 -285.914846)
		(mid 362.664083 -285.911385)
		(end 362.680758 -285.901384)
		(stroke
			(width 0.05715)
			(type default)
		)
		(layer "In11.Cu")
	)
	(gr_line
		(start 362.645198 -286.557466)
		(end 362.645706 -286.55772)
		(stroke
			(width 0.05715)
			(type default)
		)
		(layer "In11.Cu")
	)
	(gr_line
		(start 362.647484 -293.03853)
		(end 362.655104 -293.042848)
		(stroke
			(width 0.05715)
			(type default)
		)
		(layer "In11.Cu")
	)
	(gr_line
		(start 362.647484 -292.39337)
		(end 362.641642 -292.396672)
		(stroke
			(width 0.05715)
			(type default)
		)
		(layer "In11.Cu")
	)
	(gr_line
		(start 362.6485 -280.078688)
		(end 362.648754 -280.078688)
		(stroke
			(width 0.05715)
			(type default)
		)
		(layer "In11.Cu")
	)
	(gr_line
		(start 362.648754 -280.078688)
		(end 362.650278 -280.079704)
		(stroke
			(width 0.05715)
			(type default)
		)
		(layer "In11.Cu")
	)
	(gr_line
		(start 362.65739 -280.084276)
		(end 362.657136 -280.084022)
		(stroke
			(width 0.05715)
			(type default)
		)
		(layer "In11.Cu")
	)
	(gr_line
		(start 362.65993 -288.435034)
		(end 362.660438 -288.435796)
		(stroke
			(width 0.05715)
			(type default)
		)
		(layer "In11.Cu")
	)
	(gr_arc
		(start 362.661708 -288.898584)
		(mid 362.663113 -288.896685)
		(end 362.664502 -288.894774)
		(stroke
			(width 0.05715)
			(type default)
		)
		(layer "In11.Cu")
	)
	(gr_line
		(start 362.662724 -278.946102)
		(end 362.732066 -279.015444)
		(stroke
			(width 0.05715)
			(type default)
		)
		(layer "In11.Cu")
	)
	(gr_line
		(start 362.662724 -277.32609)
		(end 362.732066 -277.395432)
		(stroke
			(width 0.05715)
			(type default)
		)
		(layer "In11.Cu")
	)
	(gr_line
		(start 362.662724 -275.706078)
		(end 362.732066 -275.77542)
		(stroke
			(width 0.05715)
			(type default)
		)
		(layer "In11.Cu")
	)
	(gr_arc
		(start 362.664502 -288.894774)
		(mid 362.666032 -288.893001)
		(end 362.66755 -288.891218)
		(stroke
			(width 0.05715)
			(type default)
		)
		(layer "In11.Cu")
	)
	(gr_arc
		(start 362.671868 -289.81146)
		(mid 362.655153 -289.801007)
		(end 362.638086 -289.79114)
		(stroke
			(width 0.05715)
			(type default)
		)
		(layer "In11.Cu")
	)
	(gr_line
		(start 362.67644 -287.51657)
		(end 362.670852 -287.519618)
		(stroke
			(width 0.05715)
			(type default)
		)
		(layer "In11.Cu")
	)
	(gr_line
		(start 362.676948 -287.516316)
		(end 362.67644 -287.51657)
		(stroke
			(width 0.05715)
			(type default)
		)
		(layer "In11.Cu")
	)
	(gr_line
		(start 362.678726 -284.955996)
		(end 362.679996 -284.956758)
		(stroke
			(width 0.05715)
			(type default)
		)
		(layer "In11.Cu")
	)
	(gr_line
		(start 362.679996 -293.057326)
		(end 362.69041 -293.063422)
		(stroke
			(width 0.05715)
			(type default)
		)
		(layer "In11.Cu")
	)
	(gr_line
		(start 362.679996 -284.956758)
		(end 362.693458 -284.966156)
		(stroke
			(width 0.05715)
			(type default)
		)
		(layer "In11.Cu")
	)
	(gr_line
		(start 362.68279 -287.512506)
		(end 362.676948 -287.516316)
		(stroke
			(width 0.05715)
			(type default)
		)
		(layer "In11.Cu")
	)
	(gr_line
		(start 362.684314 -288.200338)
		(end 362.697268 -288.208212)
		(stroke
			(width 0.05715)
			(type default)
		)
		(layer "In11.Cu")
	)
	(gr_line
		(start 362.685838 -288.477198)
		(end 362.686092 -288.477706)
		(stroke
			(width 0.05715)
			(type default)
		)
		(layer "In11.Cu")
	)
	(gr_line
		(start 362.690918 -293.063676)
		(end 362.698538 -293.069264)
		(stroke
			(width 0.05715)
			(type default)
		)
		(layer "In11.Cu")
	)
	(gr_arc
		(start 362.693458 -294.68572)
		(mid 362.691429 -294.684318)
		(end 362.689394 -294.682926)
		(stroke
			(width 0.05715)
			(type default)
		)
		(layer "In11.Cu")
	)
	(gr_line
		(start 362.693458 -294.68572)
		(end 362.693712 -294.685212)
		(stroke
			(width 0.05715)
			(type default)
		)
		(layer "In11.Cu")
	)
	(gr_line
		(start 362.693712 -294.685212)
		(end 362.694728 -294.68699)
		(stroke
			(width 0.05715)
			(type default)
		)
		(layer "In11.Cu")
	)
	(gr_arc
		(start 362.694728 -289.826954)
		(mid 362.687026 -289.821554)
		(end 362.679234 -289.816286)
		(stroke
			(width 0.05715)
			(type default)
		)
		(layer "In11.Cu")
	)
	(gr_line
		(start 362.695744 -284.96768)
		(end 362.696506 -284.968442)
		(stroke
			(width 0.05715)
			(type default)
		)
		(layer "In11.Cu")
	)
	(gr_line
		(start 362.697268 -288.208212)
		(end 362.697268 -288.208974)
		(stroke
			(width 0.05715)
			(type default)
		)
		(layer "In11.Cu")
	)
	(gr_arc
		(start 362.699046 -288.210244)
		(mid 362.698158 -288.209608)
		(end 362.697268 -288.208974)
		(stroke
			(width 0.05715)
			(type default)
		)
		(layer "In11.Cu")
	)
	(gr_line
		(start 362.701332 -293.071296)
		(end 362.701586 -293.07155)
		(stroke
			(width 0.05715)
			(type default)
		)
		(layer "In11.Cu")
	)
	(gr_line
		(start 362.70692 -248.534174)
		(end 362.624116 -248.45137)
		(stroke
			(width 0.05715)
			(type default)
		)
		(layer "In11.Cu")
	)
	(gr_line
		(start 362.70692 -246.914162)
		(end 362.624116 -246.831358)
		(stroke
			(width 0.05715)
			(type default)
		)
		(layer "In11.Cu")
	)
	(gr_line
		(start 362.70692 -245.29415)
		(end 362.637578 -245.224808)
		(stroke
			(width 0.05715)
			(type default)
		)
		(layer "In11.Cu")
	)
	(gr_line
		(start 362.70692 -243.674138)
		(end 362.624116 -243.591334)
		(stroke
			(width 0.05715)
			(type default)
		)
		(layer "In11.Cu")
	)
	(gr_line
		(start 362.732828 -285.855664)
		(end 362.680758 -285.901384)
		(stroke
			(width 0.05715)
			(type default)
		)
		(layer "In11.Cu")
	)
	(gr_line
		(start 362.739178 -287.045908)
		(end 362.739432 -287.045654)
		(stroke
			(width 0.05715)
			(type default)
		)
		(layer "In11.Cu")
	)
	(gr_line
		(start 362.739432 -285.849822)
		(end 362.734098 -285.854648)
		(stroke
			(width 0.05715)
			(type default)
		)
		(layer "In11.Cu")
	)
	(gr_line
		(start 362.741972 -285.84779)
		(end 362.741464 -285.848298)
		(stroke
			(width 0.05715)
			(type default)
		)
		(layer "In11.Cu")
	)
	(gr_line
		(start 362.744004 -285.846012)
		(end 362.741972 -285.84779)
		(stroke
			(width 0.05715)
			(type default)
		)
		(layer "In11.Cu")
	)
	(gr_line
		(start 362.77296 -372.140988)
		(end 362.960666 -372.097046)
		(stroke
			(width 0.07112)
			(type default)
		)
		(layer "In11.Cu")
	)
	(gr_line
		(start 362.804456 -388.107428)
		(end 362.804456 -388.808468)
		(stroke
			(width 0.07112)
			(type default)
		)
		(layer "In11.Cu")
	)
	(gr_line
		(start 362.804456 -386.717794)
		(end 362.804456 -387.418834)
		(stroke
			(width 0.07112)
			(type default)
		)
		(layer "In11.Cu")
	)
	(gr_line
		(start 362.804456 -385.590034)
		(end 362.804456 -386.291074)
		(stroke
			(width 0.07112)
			(type default)
		)
		(layer "In11.Cu")
	)
	(gr_line
		(start 362.80979 -288.317178)
		(end 362.810044 -288.317686)
		(stroke
			(width 0.05715)
			(type default)
		)
		(layer "In11.Cu")
	)
	(gr_line
		(start 362.831634 -372.841266)
		(end 363.201712 -372.245636)
		(stroke
			(width 0.07112)
			(type default)
		)
		(layer "In11.Cu")
	)
	(gr_line
		(start 362.868718 -221.083124)
		(end 362.868718 -221.054676)
		(stroke
			(width 0.05715)
			(type default)
		)
		(layer "In11.Cu")
	)
	(gr_line
		(start 362.914438 -221.128844)
		(end 362.868718 -221.083124)
		(stroke
			(width 0.05715)
			(type default)
		)
		(layer "In11.Cu")
	)
	(gr_arc
		(start 362.92028 -279.051766)
		(mid 362.922302 -279.040356)
		(end 362.92409 -279.028906)
		(stroke
			(width 0.05715)
			(type default)
		)
		(layer "In11.Cu")
	)
	(gr_arc
		(start 362.92028 -277.431754)
		(mid 362.922302 -277.420344)
		(end 362.92409 -277.408894)
		(stroke
			(width 0.05715)
			(type default)
		)
		(layer "In11.Cu")
	)
	(gr_arc
		(start 362.92028 -275.811742)
		(mid 362.922302 -275.800331)
		(end 362.92409 -275.788882)
		(stroke
			(width 0.05715)
			(type default)
		)
		(layer "In11.Cu")
	)
	(gr_line
		(start 363.004862 -248.534174)
		(end 362.70692 -248.534174)
		(stroke
			(width 0.05715)
			(type default)
		)
		(layer "In11.Cu")
	)
	(gr_line
		(start 363.004862 -246.914162)
		(end 362.70692 -246.914162)
		(stroke
			(width 0.05715)
			(type default)
		)
		(layer "In11.Cu")
	)
	(gr_line
		(start 363.004862 -245.29415)
		(end 362.70692 -245.29415)
		(stroke
			(width 0.05715)
			(type default)
		)
		(layer "In11.Cu")
	)
	(gr_line
		(start 363.004862 -243.674138)
		(end 362.70692 -243.674138)
		(stroke
			(width 0.05715)
			(type default)
		)
		(layer "In11.Cu")
	)
	(gr_line
		(start 363.006894 -278.946102)
		(end 362.92409 -279.028906)
		(stroke
			(width 0.05715)
			(type default)
		)
		(layer "In11.Cu")
	)
	(gr_line
		(start 363.006894 -277.32609)
		(end 362.92409 -277.408894)
		(stroke
			(width 0.05715)
			(type default)
		)
		(layer "In11.Cu")
	)
	(gr_line
		(start 363.006894 -275.706078)
		(end 362.92409 -275.788882)
		(stroke
			(width 0.05715)
			(type default)
		)
		(layer "In11.Cu")
	)
	(gr_line
		(start 363.087666 -388.108698)
		(end 363.223556 -388.244588)
		(stroke
			(width 0.07112)
			(type default)
		)
		(layer "In11.Cu")
	)
	(gr_line
		(start 363.087666 -386.719064)
		(end 363.223556 -386.854954)
		(stroke
			(width 0.07112)
			(type default)
		)
		(layer "In11.Cu")
	)
	(gr_line
		(start 363.087666 -385.591304)
		(end 363.223556 -385.727194)
		(stroke
			(width 0.07112)
			(type default)
		)
		(layer "In11.Cu")
	)
	(gr_line
		(start 363.099858 -221.804484)
		(end 363.100112 -221.80423)
		(stroke
			(width 0.05715)
			(type default)
		)
		(layer "In11.Cu")
	)
	(gr_line
		(start 363.104938 -221.128844)
		(end 363.150658 -221.083124)
		(stroke
			(width 0.05715)
			(type default)
		)
		(layer "In11.Cu")
	)
	(gr_line
		(start 363.143038 -371.545612)
		(end 363.368336 -371.1829)
		(stroke
			(width 0.07112)
			(type default)
		)
		(layer "In11.Cu")
	)
	(gr_arc
		(start 363.144562 -223.88322)
		(mid 363.147982 -223.885646)
		(end 363.15142 -223.888046)
		(stroke
			(width 0.05715)
			(type default)
		)
		(layer "In11.Cu")
	)
	(gr_arc
		(start 363.144816 -227.123244)
		(mid 363.148741 -227.126055)
		(end 363.15269 -227.128832)
		(stroke
			(width 0.05715)
			(type default)
		)
		(layer "In11.Cu")
	)
	(gr_line
		(start 363.150658 -221.083124)
		(end 363.150658 -221.054676)
		(stroke
			(width 0.05715)
			(type default)
		)
		(layer "In11.Cu")
	)
	(gr_arc
		(start 363.15142 -223.8883)
		(mid 363.152435 -223.888936)
		(end 363.153452 -223.88957)
		(stroke
			(width 0.05715)
			(type default)
		)
		(layer "In11.Cu")
	)
	(gr_line
		(start 363.15142 -223.888046)
		(end 363.15142 -223.8883)
		(stroke
			(width 0.05715)
			(type default)
		)
		(layer "In11.Cu")
	)
	(gr_arc
		(start 363.15269 -229.43947)
		(mid 363.147334 -229.443249)
		(end 363.142022 -229.44709)
		(stroke
			(width 0.05715)
			(type default)
		)
		(layer "In11.Cu")
	)
	(gr_line
		(start 363.15269 -229.43947)
		(end 363.153198 -229.439216)
		(stroke
			(width 0.05715)
			(type default)
		)
		(layer "In11.Cu")
	)
	(gr_line
		(start 363.153198 -229.439216)
		(end 363.158024 -229.436422)
		(stroke
			(width 0.05715)
			(type default)
		)
		(layer "In11.Cu")
	)
	(gr_line
		(start 363.155484 -227.130864)
		(end 363.15269 -227.128832)
		(stroke
			(width 0.05715)
			(type default)
		)
		(layer "In11.Cu")
	)
	(gr_line
		(start 363.161072 -227.134166)
		(end 363.155484 -227.130864)
		(stroke
			(width 0.05715)
			(type default)
		)
		(layer "In11.Cu")
	)
	(gr_line
		(start 363.161072 -223.893888)
		(end 363.153452 -223.88957)
		(stroke
			(width 0.05715)
			(type default)
		)
		(layer "In11.Cu")
	)
	(gr_line
		(start 363.163358 -296.890948)
		(end 363.163358 -296.891456)
		(stroke
			(width 0.07112)
			(type default)
		)
		(layer "In11.Cu")
	)
	(gr_line
		(start 363.163866 -296.418508)
		(end 363.163866 -296.446956)
		(stroke
			(width 0.05715)
			(type default)
		)
		(layer "In11.Cu")
	)
	(gr_line
		(start 363.18444 -226.181158)
		(end 363.186472 -226.179888)
		(stroke
			(width 0.05715)
			(type default)
		)
		(layer "In11.Cu")
	)
	(gr_line
		(start 363.186472 -226.179888)
		(end 363.189266 -226.178364)
		(stroke
			(width 0.05715)
			(type default)
		)
		(layer "In11.Cu")
	)
	(gr_line
		(start 363.18698 -371.73281)
		(end 363.143038 -371.545612)
		(stroke
			(width 0.07112)
			(type default)
		)
		(layer "In11.Cu")
	)
	(gr_line
		(start 363.188758 -243.998496)
		(end 363.18952 -243.997988)
		(stroke
			(width 0.05715)
			(type default)
		)
		(layer "In11.Cu")
	)
	(gr_line
		(start 363.188758 -242.378484)
		(end 363.18952 -242.377976)
		(stroke
			(width 0.05715)
			(type default)
		)
		(layer "In11.Cu")
	)
	(gr_line
		(start 363.188758 -240.758472)
		(end 363.18952 -240.757964)
		(stroke
			(width 0.05715)
			(type default)
		)
		(layer "In11.Cu")
	)
	(gr_line
		(start 363.188758 -239.13846)
		(end 363.18952 -239.137952)
		(stroke
			(width 0.05715)
			(type default)
		)
		(layer "In11.Cu")
	)
	(gr_line
		(start 363.188758 -237.518448)
		(end 363.18952 -237.51794)
		(stroke
			(width 0.05715)
			(type default)
		)
		(layer "In11.Cu")
	)
	(gr_line
		(start 363.188758 -235.898436)
		(end 363.18952 -235.897928)
		(stroke
			(width 0.05715)
			(type default)
		)
		(layer "In11.Cu")
	)
	(gr_line
		(start 363.188758 -234.278424)
		(end 363.18952 -234.277916)
		(stroke
			(width 0.05715)
			(type default)
		)
		(layer "In11.Cu")
	)
	(gr_line
		(start 363.188758 -232.658412)
		(end 363.18952 -232.657904)
		(stroke
			(width 0.05715)
			(type default)
		)
		(layer "In11.Cu")
	)
	(gr_line
		(start 363.188758 -227.79863)
		(end 363.18952 -227.798122)
		(stroke
			(width 0.05715)
			(type default)
		)
		(layer "In11.Cu")
	)
	(gr_line
		(start 363.189266 -226.178364)
		(end 363.190028 -226.177856)
		(stroke
			(width 0.05715)
			(type default)
		)
		(layer "In11.Cu")
	)
	(gr_line
		(start 363.18952 -243.997988)
		(end 363.19079 -243.997226)
		(stroke
			(width 0.05715)
			(type default)
		)
		(layer "In11.Cu")
	)
	(gr_line
		(start 363.18952 -242.377976)
		(end 363.19079 -242.377214)
		(stroke
			(width 0.05715)
			(type default)
		)
		(layer "In11.Cu")
	)
	(gr_line
		(start 363.18952 -240.757964)
		(end 363.19079 -240.757202)
		(stroke
			(width 0.05715)
			(type default)
		)
		(layer "In11.Cu")
	)
	(gr_line
		(start 363.18952 -239.137952)
		(end 363.19079 -239.13719)
		(stroke
			(width 0.05715)
			(type default)
		)
		(layer "In11.Cu")
	)
	(gr_line
		(start 363.18952 -237.51794)
		(end 363.19079 -237.517178)
		(stroke
			(width 0.05715)
			(type default)
		)
		(layer "In11.Cu")
	)
	(gr_line
		(start 363.18952 -235.897928)
		(end 363.19079 -235.897166)
		(stroke
			(width 0.05715)
			(type default)
		)
		(layer "In11.Cu")
	)
	(gr_line
		(start 363.18952 -234.277916)
		(end 363.19079 -234.277154)
		(stroke
			(width 0.05715)
			(type default)
		)
		(layer "In11.Cu")
	)
	(gr_line
		(start 363.18952 -232.657904)
		(end 363.19079 -232.657142)
		(stroke
			(width 0.05715)
			(type default)
		)
		(layer "In11.Cu")
	)
	(gr_line
		(start 363.18952 -227.798122)
		(end 363.19079 -227.79736)
		(stroke
			(width 0.05715)
			(type default)
		)
		(layer "In11.Cu")
	)
	(gr_line
		(start 363.19079 -243.997226)
		(end 363.191806 -243.996718)
		(stroke
			(width 0.05715)
			(type default)
		)
		(layer "In11.Cu")
	)
	(gr_line
		(start 363.19079 -242.377214)
		(end 363.191806 -242.376706)
		(stroke
			(width 0.05715)
			(type default)
		)
		(layer "In11.Cu")
	)
	(gr_line
		(start 363.19079 -240.757202)
		(end 363.191806 -240.756694)
		(stroke
			(width 0.05715)
			(type default)
		)
		(layer "In11.Cu")
	)
	(gr_line
		(start 363.19079 -239.13719)
		(end 363.191806 -239.136682)
		(stroke
			(width 0.05715)
			(type default)
		)
		(layer "In11.Cu")
	)
	(gr_line
		(start 363.19079 -237.517178)
		(end 363.191806 -237.51667)
		(stroke
			(width 0.05715)
			(type default)
		)
		(layer "In11.Cu")
	)
	(gr_line
		(start 363.19079 -235.897166)
		(end 363.191806 -235.896658)
		(stroke
			(width 0.05715)
			(type default)
		)
		(layer "In11.Cu")
	)
	(gr_line
		(start 363.19079 -234.277154)
		(end 363.191806 -234.276646)
		(stroke
			(width 0.05715)
			(type default)
		)
		(layer "In11.Cu")
	)
	(gr_line
		(start 363.19079 -232.657142)
		(end 363.191806 -232.656634)
		(stroke
			(width 0.05715)
			(type default)
		)
		(layer "In11.Cu")
	)
	(gr_line
		(start 363.19079 -228.771196)
		(end 363.189266 -228.77018)
		(stroke
			(width 0.05715)
			(type default)
		)
		(layer "In11.Cu")
	)
	(gr_line
		(start 363.19079 -227.79736)
		(end 363.191806 -227.796852)
		(stroke
			(width 0.05715)
			(type default)
		)
		(layer "In11.Cu")
	)
	(gr_line
		(start 363.191806 -243.996718)
		(end 363.192568 -243.99621)
		(stroke
			(width 0.05715)
			(type default)
		)
		(layer "In11.Cu")
	)
	(gr_line
		(start 363.191806 -243.351558)
		(end 363.19079 -243.35105)
		(stroke
			(width 0.05715)
			(type default)
		)
		(layer "In11.Cu")
	)
	(gr_line
		(start 363.191806 -242.376706)
		(end 363.192568 -242.376198)
		(stroke
			(width 0.05715)
			(type default)
		)
		(layer "In11.Cu")
	)
	(gr_line
		(start 363.191806 -241.731546)
		(end 363.19079 -241.731038)
		(stroke
			(width 0.05715)
			(type default)
		)
		(layer "In11.Cu")
	)
	(gr_line
		(start 363.191806 -240.756694)
		(end 363.192568 -240.756186)
		(stroke
			(width 0.05715)
			(type default)
		)
		(layer "In11.Cu")
	)
	(gr_line
		(start 363.191806 -240.111534)
		(end 363.19079 -240.111026)
		(stroke
			(width 0.05715)
			(type default)
		)
		(layer "In11.Cu")
	)
	(gr_line
		(start 363.191806 -239.136682)
		(end 363.192568 -239.136174)
		(stroke
			(width 0.05715)
			(type default)
		)
		(layer "In11.Cu")
	)
	(gr_line
		(start 363.191806 -238.491522)
		(end 363.19079 -238.491014)
		(stroke
			(width 0.05715)
			(type default)
		)
		(layer "In11.Cu")
	)
	(gr_line
		(start 363.191806 -237.51667)
		(end 363.192568 -237.516162)
		(stroke
			(width 0.05715)
			(type default)
		)
		(layer "In11.Cu")
	)
	(gr_line
		(start 363.191806 -236.87151)
		(end 363.19079 -236.871002)
		(stroke
			(width 0.05715)
			(type default)
		)
		(layer "In11.Cu")
	)
	(gr_line
		(start 363.191806 -235.896658)
		(end 363.192568 -235.89615)
		(stroke
			(width 0.05715)
			(type default)
		)
		(layer "In11.Cu")
	)
	(gr_line
		(start 363.191806 -235.251498)
		(end 363.19079 -235.25099)
		(stroke
			(width 0.05715)
			(type default)
		)
		(layer "In11.Cu")
	)
	(gr_line
		(start 363.191806 -234.276646)
		(end 363.192568 -234.276138)
		(stroke
			(width 0.05715)
			(type default)
		)
		(layer "In11.Cu")
	)
	(gr_line
		(start 363.191806 -233.631486)
		(end 363.19079 -233.630978)
		(stroke
			(width 0.05715)
			(type default)
		)
		(layer "In11.Cu")
	)
	(gr_line
		(start 363.191806 -232.656634)
		(end 363.192568 -232.656126)
		(stroke
			(width 0.05715)
			(type default)
		)
		(layer "In11.Cu")
	)
	(gr_line
		(start 363.191806 -232.011474)
		(end 363.19079 -232.010966)
		(stroke
			(width 0.05715)
			(type default)
		)
		(layer "In11.Cu")
	)
	(gr_line
		(start 363.191806 -228.771704)
		(end 363.19079 -228.771196)
		(stroke
			(width 0.05715)
			(type default)
		)
		(layer "In11.Cu")
	)
	(gr_line
		(start 363.191806 -227.796852)
		(end 363.192314 -227.796598)
		(stroke
			(width 0.05715)
			(type default)
		)
		(layer "In11.Cu")
	)
	(gr_line
		(start 363.191806 -226.17684)
		(end 363.192568 -226.176332)
		(stroke
			(width 0.05715)
			(type default)
		)
		(layer "In11.Cu")
	)
	(gr_line
		(start 363.191806 -222.291656)
		(end 363.19079 -222.291148)
		(stroke
			(width 0.05715)
			(type default)
		)
		(layer "In11.Cu")
	)
	(gr_line
		(start 363.19206 -224.556574)
		(end 363.192568 -224.55632)
		(stroke
			(width 0.05715)
			(type default)
		)
		(layer "In11.Cu")
	)
	(gr_line
		(start 363.192314 -232.011728)
		(end 363.191806 -232.011474)
		(stroke
			(width 0.05715)
			(type default)
		)
		(layer "In11.Cu")
	)
	(gr_line
		(start 363.192314 -228.771958)
		(end 363.191806 -228.771704)
		(stroke
			(width 0.05715)
			(type default)
		)
		(layer "In11.Cu")
	)
	(gr_line
		(start 363.192568 -243.99621)
		(end 363.194092 -243.995448)
		(stroke
			(width 0.05715)
			(type default)
		)
		(layer "In11.Cu")
	)
	(gr_line
		(start 363.192568 -242.376198)
		(end 363.194092 -242.375436)
		(stroke
			(width 0.05715)
			(type default)
		)
		(layer "In11.Cu")
	)
	(gr_line
		(start 363.192568 -240.756186)
		(end 363.194092 -240.755424)
		(stroke
			(width 0.05715)
			(type default)
		)
		(layer "In11.Cu")
	)
	(gr_line
		(start 363.192568 -239.136174)
		(end 363.194092 -239.135412)
		(stroke
			(width 0.05715)
			(type default)
		)
		(layer "In11.Cu")
	)
	(gr_line
		(start 363.192568 -237.516162)
		(end 363.194092 -237.5154)
		(stroke
			(width 0.05715)
			(type default)
		)
		(layer "In11.Cu")
	)
	(gr_line
		(start 363.192568 -235.89615)
		(end 363.194092 -235.895388)
		(stroke
			(width 0.05715)
			(type default)
		)
		(layer "In11.Cu")
	)
	(gr_line
		(start 363.192568 -234.276138)
		(end 363.194092 -234.275376)
		(stroke
			(width 0.05715)
			(type default)
		)
		(layer "In11.Cu")
	)
	(gr_line
		(start 363.192568 -232.656126)
		(end 363.194092 -232.655364)
		(stroke
			(width 0.05715)
			(type default)
		)
		(layer "In11.Cu")
	)
	(gr_line
		(start 363.192568 -224.55632)
		(end 363.194346 -224.555558)
		(stroke
			(width 0.05715)
			(type default)
		)
		(layer "In11.Cu")
	)
	(gr_line
		(start 363.193076 -222.292418)
		(end 363.191806 -222.291656)
		(stroke
			(width 0.05715)
			(type default)
		)
		(layer "In11.Cu")
	)
	(gr_line
		(start 363.195362 -243.994686)
		(end 363.196124 -243.994178)
		(stroke
			(width 0.05715)
			(type default)
		)
		(layer "In11.Cu")
	)
	(gr_line
		(start 363.195362 -242.374674)
		(end 363.196124 -242.374166)
		(stroke
			(width 0.05715)
			(type default)
		)
		(layer "In11.Cu")
	)
	(gr_line
		(start 363.195362 -240.754662)
		(end 363.196124 -240.754154)
		(stroke
			(width 0.05715)
			(type default)
		)
		(layer "In11.Cu")
	)
	(gr_line
		(start 363.195362 -239.13465)
		(end 363.196124 -239.134142)
		(stroke
			(width 0.05715)
			(type default)
		)
		(layer "In11.Cu")
	)
	(gr_line
		(start 363.195362 -237.514638)
		(end 363.196124 -237.51413)
		(stroke
			(width 0.05715)
			(type default)
		)
		(layer "In11.Cu")
	)
	(gr_line
		(start 363.195362 -235.894626)
		(end 363.196124 -235.894118)
		(stroke
			(width 0.05715)
			(type default)
		)
		(layer "In11.Cu")
	)
	(gr_line
		(start 363.195362 -234.274614)
		(end 363.196124 -234.274106)
		(stroke
			(width 0.05715)
			(type default)
		)
		(layer "In11.Cu")
	)
	(gr_line
		(start 363.195362 -232.654602)
		(end 363.196124 -232.654094)
		(stroke
			(width 0.05715)
			(type default)
		)
		(layer "In11.Cu")
	)
	(gr_line
		(start 363.197648 -243.993416)
		(end 363.198156 -243.993162)
		(stroke
			(width 0.05715)
			(type default)
		)
		(layer "In11.Cu")
	)
	(gr_line
		(start 363.197648 -242.373404)
		(end 363.198156 -242.37315)
		(stroke
			(width 0.05715)
			(type default)
		)
		(layer "In11.Cu")
	)
	(gr_line
		(start 363.197648 -240.753392)
		(end 363.198156 -240.753138)
		(stroke
			(width 0.05715)
			(type default)
		)
		(layer "In11.Cu")
	)
	(gr_line
		(start 363.197648 -239.13338)
		(end 363.198156 -239.133126)
		(stroke
			(width 0.05715)
			(type default)
		)
		(layer "In11.Cu")
	)
	(gr_line
		(start 363.197648 -237.513368)
		(end 363.198156 -237.513114)
		(stroke
			(width 0.05715)
			(type default)
		)
		(layer "In11.Cu")
	)
	(gr_line
		(start 363.197648 -235.893356)
		(end 363.198156 -235.893102)
		(stroke
			(width 0.05715)
			(type default)
		)
		(layer "In11.Cu")
	)
	(gr_line
		(start 363.197648 -234.273344)
		(end 363.198156 -234.27309)
		(stroke
			(width 0.05715)
			(type default)
		)
		(layer "In11.Cu")
	)
	(gr_line
		(start 363.197648 -232.653332)
		(end 363.198156 -232.653078)
		(stroke
			(width 0.05715)
			(type default)
		)
		(layer "In11.Cu")
	)
	(gr_line
		(start 363.200696 -226.17176)
		(end 363.20222 -226.170998)
		(stroke
			(width 0.05715)
			(type default)
		)
		(layer "In11.Cu")
	)
	(gr_line
		(start 363.208316 -296.374058)
		(end 363.163866 -296.418508)
		(stroke
			(width 0.05715)
			(type default)
		)
		(layer "In11.Cu")
	)
	(gr_line
		(start 363.223556 -388.671308)
		(end 363.087666 -388.807198)
		(stroke
			(width 0.07112)
			(type default)
		)
		(layer "In11.Cu")
	)
	(gr_line
		(start 363.223556 -388.244588)
		(end 363.223556 -388.671308)
		(stroke
			(width 0.07112)
			(type default)
		)
		(layer "In11.Cu")
	)
	(gr_line
		(start 363.223556 -387.281674)
		(end 363.087666 -387.417564)
		(stroke
			(width 0.07112)
			(type default)
		)
		(layer "In11.Cu")
	)
	(gr_line
		(start 363.223556 -386.854954)
		(end 363.223556 -387.281674)
		(stroke
			(width 0.07112)
			(type default)
		)
		(layer "In11.Cu")
	)
	(gr_line
		(start 363.223556 -386.153914)
		(end 363.087666 -386.289804)
		(stroke
			(width 0.07112)
			(type default)
		)
		(layer "In11.Cu")
	)
	(gr_line
		(start 363.223556 -385.727194)
		(end 363.223556 -386.153914)
		(stroke
			(width 0.07112)
			(type default)
		)
		(layer "In11.Cu")
	)
	(gr_line
		(start 363.283246 -244.164104)
		(end 363.284008 -244.16385)
		(stroke
			(width 0.05715)
			(type default)
		)
		(layer "In11.Cu")
	)
	(gr_line
		(start 363.283246 -242.544092)
		(end 363.284008 -242.543838)
		(stroke
			(width 0.05715)
			(type default)
		)
		(layer "In11.Cu")
	)
	(gr_line
		(start 363.283246 -240.92408)
		(end 363.284008 -240.923826)
		(stroke
			(width 0.05715)
			(type default)
		)
		(layer "In11.Cu")
	)
	(gr_line
		(start 363.283246 -239.304068)
		(end 363.284008 -239.303814)
		(stroke
			(width 0.05715)
			(type default)
		)
		(layer "In11.Cu")
	)
	(gr_line
		(start 363.283246 -237.684056)
		(end 363.284008 -237.683802)
		(stroke
			(width 0.05715)
			(type default)
		)
		(layer "In11.Cu")
	)
	(gr_line
		(start 363.283246 -236.064044)
		(end 363.284008 -236.06379)
		(stroke
			(width 0.05715)
			(type default)
		)
		(layer "In11.Cu")
	)
	(gr_line
		(start 363.283246 -234.444032)
		(end 363.284008 -234.443778)
		(stroke
			(width 0.05715)
			(type default)
		)
		(layer "In11.Cu")
	)
	(gr_line
		(start 363.283246 -232.82402)
		(end 363.284008 -232.823766)
		(stroke
			(width 0.05715)
			(type default)
		)
		(layer "In11.Cu")
	)
	(gr_line
		(start 363.283246 -228.604064)
		(end 363.281722 -228.603048)
		(stroke
			(width 0.05715)
			(type default)
		)
		(layer "In11.Cu")
	)
	(gr_line
		(start 363.283246 -227.964238)
		(end 363.285786 -227.962968)
		(stroke
			(width 0.05715)
			(type default)
		)
		(layer "In11.Cu")
	)
	(gr_line
		(start 363.2835 -226.344226)
		(end 363.284262 -226.343718)
		(stroke
			(width 0.05715)
			(type default)
		)
		(layer "In11.Cu")
	)
	(gr_line
		(start 363.285786 -227.962968)
		(end 363.287056 -227.962206)
		(stroke
			(width 0.05715)
			(type default)
		)
		(layer "In11.Cu")
	)
	(gr_line
		(start 363.285786 -224.722944)
		(end 363.287056 -224.722182)
		(stroke
			(width 0.05715)
			(type default)
		)
		(layer "In11.Cu")
	)
	(gr_line
		(start 363.287056 -244.162072)
		(end 363.287818 -244.161564)
		(stroke
			(width 0.05715)
			(type default)
		)
		(layer "In11.Cu")
	)
	(gr_line
		(start 363.287056 -243.186204)
		(end 363.285786 -243.185442)
		(stroke
			(width 0.05715)
			(type default)
		)
		(layer "In11.Cu")
	)
	(gr_line
		(start 363.287056 -242.54206)
		(end 363.287818 -242.541552)
		(stroke
			(width 0.05715)
			(type default)
		)
		(layer "In11.Cu")
	)
	(gr_line
		(start 363.287056 -241.566192)
		(end 363.285786 -241.56543)
		(stroke
			(width 0.05715)
			(type default)
		)
		(layer "In11.Cu")
	)
	(gr_line
		(start 363.287056 -240.922048)
		(end 363.287818 -240.92154)
		(stroke
			(width 0.05715)
			(type default)
		)
		(layer "In11.Cu")
	)
	(gr_line
		(start 363.287056 -239.94618)
		(end 363.285786 -239.945418)
		(stroke
			(width 0.05715)
			(type default)
		)
		(layer "In11.Cu")
	)
	(gr_line
		(start 363.287056 -239.302036)
		(end 363.287818 -239.301528)
		(stroke
			(width 0.05715)
			(type default)
		)
		(layer "In11.Cu")
	)
	(gr_line
		(start 363.287056 -238.326168)
		(end 363.285786 -238.325406)
		(stroke
			(width 0.05715)
			(type default)
		)
		(layer "In11.Cu")
	)
	(gr_line
		(start 363.287056 -237.682024)
		(end 363.287818 -237.681516)
		(stroke
			(width 0.05715)
			(type default)
		)
		(layer "In11.Cu")
	)
	(gr_line
		(start 363.287056 -236.706156)
		(end 363.285786 -236.705394)
		(stroke
			(width 0.05715)
			(type default)
		)
		(layer "In11.Cu")
	)
	(gr_line
		(start 363.287056 -236.062012)
		(end 363.287818 -236.061504)
		(stroke
			(width 0.05715)
			(type default)
		)
		(layer "In11.Cu")
	)
	(gr_line
		(start 363.287056 -235.086144)
		(end 363.285786 -235.085382)
		(stroke
			(width 0.05715)
			(type default)
		)
		(layer "In11.Cu")
	)
	(gr_line
		(start 363.287056 -234.442)
		(end 363.287818 -234.441492)
		(stroke
			(width 0.05715)
			(type default)
		)
		(layer "In11.Cu")
	)
	(gr_line
		(start 363.287056 -233.466132)
		(end 363.285786 -233.46537)
		(stroke
			(width 0.05715)
			(type default)
		)
		(layer "In11.Cu")
	)
	(gr_line
		(start 363.287056 -232.821988)
		(end 363.287818 -232.82148)
		(stroke
			(width 0.05715)
			(type default)
		)
		(layer "In11.Cu")
	)
	(gr_line
		(start 363.287056 -231.84612)
		(end 363.285786 -231.845358)
		(stroke
			(width 0.05715)
			(type default)
		)
		(layer "In11.Cu")
	)
	(gr_line
		(start 363.287056 -228.60635)
		(end 363.283246 -228.604064)
		(stroke
			(width 0.05715)
			(type default)
		)
		(layer "In11.Cu")
	)
	(gr_line
		(start 363.287056 -224.722182)
		(end 363.287818 -224.721674)
		(stroke
			(width 0.05715)
			(type default)
		)
		(layer "In11.Cu")
	)
	(gr_line
		(start 363.287056 -222.126302)
		(end 363.285786 -222.12554)
		(stroke
			(width 0.05715)
			(type default)
		)
		(layer "In11.Cu")
	)
	(gr_line
		(start 363.287564 -243.186458)
		(end 363.287056 -243.186204)
		(stroke
			(width 0.05715)
			(type default)
		)
		(layer "In11.Cu")
	)
	(gr_line
		(start 363.287564 -241.566446)
		(end 363.287056 -241.566192)
		(stroke
			(width 0.05715)
			(type default)
		)
		(layer "In11.Cu")
	)
	(gr_line
		(start 363.287564 -239.946434)
		(end 363.287056 -239.94618)
		(stroke
			(width 0.05715)
			(type default)
		)
		(layer "In11.Cu")
	)
	(gr_line
		(start 363.287564 -238.326422)
		(end 363.287056 -238.326168)
		(stroke
			(width 0.05715)
			(type default)
		)
		(layer "In11.Cu")
	)
	(gr_line
		(start 363.287564 -236.70641)
		(end 363.287056 -236.706156)
		(stroke
			(width 0.05715)
			(type default)
		)
		(layer "In11.Cu")
	)
	(gr_line
		(start 363.287564 -235.086398)
		(end 363.287056 -235.086144)
		(stroke
			(width 0.05715)
			(type default)
		)
		(layer "In11.Cu")
	)
	(gr_line
		(start 363.287564 -233.466386)
		(end 363.287056 -233.466132)
		(stroke
			(width 0.05715)
			(type default)
		)
		(layer "In11.Cu")
	)
	(gr_line
		(start 363.287564 -226.986592)
		(end 363.287056 -226.986338)
		(stroke
			(width 0.05715)
			(type default)
		)
		(layer "In11.Cu")
	)
	(gr_line
		(start 363.287818 -226.341686)
		(end 363.288834 -226.341178)
		(stroke
			(width 0.05715)
			(type default)
		)
		(layer "In11.Cu")
	)
	(gr_line
		(start 363.287818 -224.721674)
		(end 363.290104 -224.720404)
		(stroke
			(width 0.05715)
			(type default)
		)
		(layer "In11.Cu")
	)
	(gr_line
		(start 363.288834 -226.341178)
		(end 363.290358 -226.340162)
		(stroke
			(width 0.05715)
			(type default)
		)
		(layer "In11.Cu")
	)
	(gr_arc
		(start 363.290104 -224.720404)
		(mid 363.291121 -224.71977)
		(end 363.292136 -224.719134)
		(stroke
			(width 0.05715)
			(type default)
		)
		(layer "In11.Cu")
	)
	(gr_line
		(start 363.290358 -226.340162)
		(end 363.291374 -226.339654)
		(stroke
			(width 0.05715)
			(type default)
		)
		(layer "In11.Cu")
	)
	(gr_line
		(start 363.291374 -226.339654)
		(end 363.295184 -226.337368)
		(stroke
			(width 0.05715)
			(type default)
		)
		(layer "In11.Cu")
	)
	(gr_line
		(start 363.292136 -244.159024)
		(end 363.293406 -244.158262)
		(stroke
			(width 0.05715)
			(type default)
		)
		(layer "In11.Cu")
	)
	(gr_line
		(start 363.292136 -242.539012)
		(end 363.293406 -242.53825)
		(stroke
			(width 0.05715)
			(type default)
		)
		(layer "In11.Cu")
	)
	(gr_line
		(start 363.292136 -240.919)
		(end 363.293406 -240.918238)
		(stroke
			(width 0.05715)
			(type default)
		)
		(layer "In11.Cu")
	)
	(gr_line
		(start 363.292136 -239.298988)
		(end 363.293406 -239.298226)
		(stroke
			(width 0.05715)
			(type default)
		)
		(layer "In11.Cu")
	)
	(gr_line
		(start 363.292136 -237.678976)
		(end 363.293406 -237.678214)
		(stroke
			(width 0.05715)
			(type default)
		)
		(layer "In11.Cu")
	)
	(gr_line
		(start 363.292136 -236.058964)
		(end 363.293406 -236.058202)
		(stroke
			(width 0.05715)
			(type default)
		)
		(layer "In11.Cu")
	)
	(gr_line
		(start 363.292136 -234.438952)
		(end 363.293406 -234.43819)
		(stroke
			(width 0.05715)
			(type default)
		)
		(layer "In11.Cu")
	)
	(gr_line
		(start 363.292136 -232.81894)
		(end 363.293406 -232.818178)
		(stroke
			(width 0.05715)
			(type default)
		)
		(layer "In11.Cu")
	)
	(gr_line
		(start 363.297724 -226.335844)
		(end 363.298232 -226.33559)
		(stroke
			(width 0.05715)
			(type default)
		)
		(layer "In11.Cu")
	)
	(gr_line
		(start 363.304836 -278.946102)
		(end 363.006894 -278.946102)
		(stroke
			(width 0.05715)
			(type default)
		)
		(layer "In11.Cu")
	)
	(gr_line
		(start 363.304836 -277.32609)
		(end 363.006894 -277.32609)
		(stroke
			(width 0.05715)
			(type default)
		)
		(layer "In11.Cu")
	)
	(gr_line
		(start 363.304836 -275.706078)
		(end 363.006894 -275.706078)
		(stroke
			(width 0.05715)
			(type default)
		)
		(layer "In11.Cu")
	)
	(gr_line
		(start 363.319314 -243.205)
		(end 363.318552 -243.204492)
		(stroke
			(width 0.05715)
			(type default)
		)
		(layer "In11.Cu")
	)
	(gr_line
		(start 363.319314 -241.584988)
		(end 363.318552 -241.58448)
		(stroke
			(width 0.05715)
			(type default)
		)
		(layer "In11.Cu")
	)
	(gr_line
		(start 363.319314 -239.964976)
		(end 363.318552 -239.964468)
		(stroke
			(width 0.05715)
			(type default)
		)
		(layer "In11.Cu")
	)
	(gr_line
		(start 363.319314 -238.344964)
		(end 363.318552 -238.344456)
		(stroke
			(width 0.05715)
			(type default)
		)
		(layer "In11.Cu")
	)
	(gr_line
		(start 363.319314 -236.724952)
		(end 363.318552 -236.724444)
		(stroke
			(width 0.05715)
			(type default)
		)
		(layer "In11.Cu")
	)
	(gr_line
		(start 363.319314 -235.10494)
		(end 363.318552 -235.104432)
		(stroke
			(width 0.05715)
			(type default)
		)
		(layer "In11.Cu")
	)
	(gr_line
		(start 363.319314 -233.484928)
		(end 363.318552 -233.48442)
		(stroke
			(width 0.05715)
			(type default)
		)
		(layer "In11.Cu")
	)
	(gr_line
		(start 363.319314 -227.005134)
		(end 363.318552 -227.004626)
		(stroke
			(width 0.05715)
			(type default)
		)
		(layer "In11.Cu")
	)
	(gr_line
		(start 363.320076 -243.205508)
		(end 363.319314 -243.205)
		(stroke
			(width 0.05715)
			(type default)
		)
		(layer "In11.Cu")
	)
	(gr_line
		(start 363.320076 -241.585496)
		(end 363.319314 -241.584988)
		(stroke
			(width 0.05715)
			(type default)
		)
		(layer "In11.Cu")
	)
	(gr_line
		(start 363.320076 -239.965484)
		(end 363.319314 -239.964976)
		(stroke
			(width 0.05715)
			(type default)
		)
		(layer "In11.Cu")
	)
	(gr_line
		(start 363.320076 -238.345472)
		(end 363.319314 -238.344964)
		(stroke
			(width 0.05715)
			(type default)
		)
		(layer "In11.Cu")
	)
	(gr_line
		(start 363.320076 -236.72546)
		(end 363.319314 -236.724952)
		(stroke
			(width 0.05715)
			(type default)
		)
		(layer "In11.Cu")
	)
	(gr_line
		(start 363.320076 -235.105448)
		(end 363.319314 -235.10494)
		(stroke
			(width 0.05715)
			(type default)
		)
		(layer "In11.Cu")
	)
	(gr_line
		(start 363.320076 -233.485436)
		(end 363.319314 -233.484928)
		(stroke
			(width 0.05715)
			(type default)
		)
		(layer "In11.Cu")
	)
	(gr_line
		(start 363.320076 -227.005642)
		(end 363.319314 -227.005134)
		(stroke
			(width 0.05715)
			(type default)
		)
		(layer "In11.Cu")
	)
	(gr_line
		(start 363.326934 -243.209572)
		(end 363.320076 -243.205508)
		(stroke
			(width 0.05715)
			(type default)
		)
		(layer "In11.Cu")
	)
	(gr_line
		(start 363.326934 -241.58956)
		(end 363.320076 -241.585496)
		(stroke
			(width 0.05715)
			(type default)
		)
		(layer "In11.Cu")
	)
	(gr_line
		(start 363.326934 -239.969548)
		(end 363.320076 -239.965484)
		(stroke
			(width 0.05715)
			(type default)
		)
		(layer "In11.Cu")
	)
	(gr_line
		(start 363.326934 -238.349536)
		(end 363.320076 -238.345472)
		(stroke
			(width 0.05715)
			(type default)
		)
		(layer "In11.Cu")
	)
	(gr_line
		(start 363.326934 -236.729524)
		(end 363.320076 -236.72546)
		(stroke
			(width 0.05715)
			(type default)
		)
		(layer "In11.Cu")
	)
	(gr_line
		(start 363.326934 -235.109512)
		(end 363.320076 -235.105448)
		(stroke
			(width 0.05715)
			(type default)
		)
		(layer "In11.Cu")
	)
	(gr_line
		(start 363.326934 -233.4895)
		(end 363.320076 -233.485436)
		(stroke
			(width 0.05715)
			(type default)
		)
		(layer "In11.Cu")
	)
	(gr_line
		(start 363.326934 -227.009706)
		(end 363.320076 -227.005642)
		(stroke
			(width 0.05715)
			(type default)
		)
		(layer "In11.Cu")
	)
	(gr_arc
		(start 363.334808 -243.21516)
		(mid 363.330883 -243.212349)
		(end 363.326934 -243.209572)
		(stroke
			(width 0.05715)
			(type default)
		)
		(layer "In11.Cu")
	)
	(gr_arc
		(start 363.334808 -241.595148)
		(mid 363.330883 -241.592337)
		(end 363.326934 -241.58956)
		(stroke
			(width 0.05715)
			(type default)
		)
		(layer "In11.Cu")
	)
	(gr_arc
		(start 363.334808 -239.975136)
		(mid 363.330883 -239.972325)
		(end 363.326934 -239.969548)
		(stroke
			(width 0.05715)
			(type default)
		)
		(layer "In11.Cu")
	)
	(gr_arc
		(start 363.334808 -238.355124)
		(mid 363.330883 -238.352313)
		(end 363.326934 -238.349536)
		(stroke
			(width 0.05715)
			(type default)
		)
		(layer "In11.Cu")
	)
	(gr_arc
		(start 363.334808 -236.735112)
		(mid 363.330883 -236.732301)
		(end 363.326934 -236.729524)
		(stroke
			(width 0.05715)
			(type default)
		)
		(layer "In11.Cu")
	)
	(gr_arc
		(start 363.334808 -235.1151)
		(mid 363.330883 -235.112289)
		(end 363.326934 -235.109512)
		(stroke
			(width 0.05715)
			(type default)
		)
		(layer "In11.Cu")
	)
	(gr_arc
		(start 363.334808 -233.495088)
		(mid 363.330883 -233.492277)
		(end 363.326934 -233.4895)
		(stroke
			(width 0.05715)
			(type default)
		)
		(layer "In11.Cu")
	)
	(gr_arc
		(start 363.334808 -227.015294)
		(mid 363.330883 -227.012483)
		(end 363.326934 -227.009706)
		(stroke
			(width 0.05715)
			(type default)
		)
		(layer "In11.Cu")
	)
	(gr_line
		(start 363.341412 -223.780096)
		(end 363.334554 -223.774762)
		(stroke
			(width 0.05715)
			(type default)
		)
		(layer "In11.Cu")
	)
	(gr_line
		(start 363.368336 -371.1829)
		(end 363.555788 -371.138958)
		(stroke
			(width 0.07112)
			(type default)
		)
		(layer "In11.Cu")
	)
	(gr_line
		(start 363.400086 -296.386758)
		(end 363.445806 -296.432478)
		(stroke
			(width 0.05715)
			(type default)
		)
		(layer "In11.Cu")
	)
	(gr_line
		(start 363.400086 -296.372788)
		(end 363.400086 -296.386758)
		(stroke
			(width 0.05715)
			(type default)
		)
		(layer "In11.Cu")
	)
	(gr_line
		(start 363.42701 -371.883178)
		(end 363.797088 -371.287548)
		(stroke
			(width 0.07112)
			(type default)
		)
		(layer "In11.Cu")
	)
	(gr_arc
		(start 363.44479 -294.79494)
		(mid 363.448715 -294.797751)
		(end 363.452664 -294.800528)
		(stroke
			(width 0.05715)
			(type default)
		)
		(layer "In11.Cu")
	)
	(gr_arc
		(start 363.44479 -293.174928)
		(mid 363.448715 -293.177739)
		(end 363.452664 -293.180516)
		(stroke
			(width 0.05715)
			(type default)
		)
		(layer "In11.Cu")
	)
	(gr_arc
		(start 363.44479 -291.554916)
		(mid 363.448715 -291.557727)
		(end 363.452664 -291.560504)
		(stroke
			(width 0.05715)
			(type default)
		)
		(layer "In11.Cu")
	)
	(gr_arc
		(start 363.44479 -285.075122)
		(mid 363.448715 -285.077933)
		(end 363.452664 -285.08071)
		(stroke
			(width 0.05715)
			(type default)
		)
		(layer "In11.Cu")
	)
	(gr_arc
		(start 363.44479 -283.45511)
		(mid 363.448715 -283.457921)
		(end 363.452664 -283.460698)
		(stroke
			(width 0.05715)
			(type default)
		)
		(layer "In11.Cu")
	)
	(gr_arc
		(start 363.44479 -281.835098)
		(mid 363.448715 -281.837909)
		(end 363.452664 -281.840686)
		(stroke
			(width 0.05715)
			(type default)
		)
		(layer "In11.Cu")
	)
	(gr_line
		(start 363.445806 -296.774108)
		(end 363.445806 -296.774616)
		(stroke
			(width 0.07112)
			(type default)
		)
		(layer "In11.Cu")
	)
	(gr_line
		(start 363.445806 -296.432478)
		(end 363.445806 -296.446956)
		(stroke
			(width 0.05715)
			(type default)
		)
		(layer "In11.Cu")
	)
	(gr_line
		(start 363.452664 -294.800528)
		(end 363.459522 -294.804592)
		(stroke
			(width 0.05715)
			(type default)
		)
		(layer "In11.Cu")
	)
	(gr_line
		(start 363.452664 -293.180516)
		(end 363.459522 -293.18458)
		(stroke
			(width 0.05715)
			(type default)
		)
		(layer "In11.Cu")
	)
	(gr_line
		(start 363.452664 -291.560504)
		(end 363.459522 -291.564568)
		(stroke
			(width 0.05715)
			(type default)
		)
		(layer "In11.Cu")
	)
	(gr_line
		(start 363.452664 -285.08071)
		(end 363.459522 -285.084774)
		(stroke
			(width 0.05715)
			(type default)
		)
		(layer "In11.Cu")
	)
	(gr_line
		(start 363.452664 -283.460698)
		(end 363.459522 -283.464762)
		(stroke
			(width 0.05715)
			(type default)
		)
		(layer "In11.Cu")
	)
	(gr_line
		(start 363.452664 -281.840686)
		(end 363.459522 -281.84475)
		(stroke
			(width 0.05715)
			(type default)
		)
		(layer "In11.Cu")
	)
	(gr_line
		(start 363.459522 -294.804592)
		(end 363.460284 -294.8051)
		(stroke
			(width 0.05715)
			(type default)
		)
		(layer "In11.Cu")
	)
	(gr_line
		(start 363.459522 -293.18458)
		(end 363.460284 -293.185088)
		(stroke
			(width 0.05715)
			(type default)
		)
		(layer "In11.Cu")
	)
	(gr_line
		(start 363.459522 -291.564568)
		(end 363.460284 -291.565076)
		(stroke
			(width 0.05715)
			(type default)
		)
		(layer "In11.Cu")
	)
	(gr_line
		(start 363.459522 -285.084774)
		(end 363.460284 -285.085282)
		(stroke
			(width 0.05715)
			(type default)
		)
		(layer "In11.Cu")
	)
	(gr_line
		(start 363.459522 -283.464762)
		(end 363.460284 -283.46527)
		(stroke
			(width 0.05715)
			(type default)
		)
		(layer "In11.Cu")
	)
	(gr_line
		(start 363.459522 -281.84475)
		(end 363.460284 -281.845258)
		(stroke
			(width 0.05715)
			(type default)
		)
		(layer "In11.Cu")
	)
	(gr_line
		(start 363.460284 -294.8051)
		(end 363.461046 -294.805608)
		(stroke
			(width 0.05715)
			(type default)
		)
		(layer "In11.Cu")
	)
	(gr_line
		(start 363.460284 -293.185088)
		(end 363.461046 -293.185596)
		(stroke
			(width 0.05715)
			(type default)
		)
		(layer "In11.Cu")
	)
	(gr_line
		(start 363.460284 -291.565076)
		(end 363.461046 -291.565584)
		(stroke
			(width 0.05715)
			(type default)
		)
		(layer "In11.Cu")
	)
	(gr_line
		(start 363.460284 -285.085282)
		(end 363.461046 -285.08579)
		(stroke
			(width 0.05715)
			(type default)
		)
		(layer "In11.Cu")
	)
	(gr_line
		(start 363.460284 -283.46527)
		(end 363.461046 -283.465778)
		(stroke
			(width 0.05715)
			(type default)
		)
		(layer "In11.Cu")
	)
	(gr_line
		(start 363.460284 -281.845258)
		(end 363.461046 -281.845766)
		(stroke
			(width 0.05715)
			(type default)
		)
		(layer "In11.Cu")
	)
	(gr_line
		(start 363.470444 -381.705612)
		(end 363.470444 -382.406652)
		(stroke
			(width 0.07112)
			(type default)
		)
		(layer "In11.Cu")
	)
	(gr_line
		(start 363.491526 -293.848536)
		(end 363.490764 -293.849044)
		(stroke
			(width 0.05715)
			(type default)
		)
		(layer "In11.Cu")
	)
	(gr_line
		(start 363.491526 -292.228524)
		(end 363.490764 -292.229032)
		(stroke
			(width 0.05715)
			(type default)
		)
		(layer "In11.Cu")
	)
	(gr_line
		(start 363.491526 -290.608512)
		(end 363.490764 -290.60902)
		(stroke
			(width 0.05715)
			(type default)
		)
		(layer "In11.Cu")
	)
	(gr_line
		(start 363.491526 -288.9885)
		(end 363.490764 -288.989008)
		(stroke
			(width 0.05715)
			(type default)
		)
		(layer "In11.Cu")
	)
	(gr_line
		(start 363.491526 -285.74873)
		(end 363.490764 -285.749238)
		(stroke
			(width 0.05715)
			(type default)
		)
		(layer "In11.Cu")
	)
	(gr_line
		(start 363.491526 -284.128718)
		(end 363.490764 -284.129226)
		(stroke
			(width 0.05715)
			(type default)
		)
		(layer "In11.Cu")
	)
	(gr_line
		(start 363.491526 -282.508706)
		(end 363.490764 -282.509214)
		(stroke
			(width 0.05715)
			(type default)
		)
		(layer "In11.Cu")
	)
	(gr_line
		(start 363.491526 -280.888694)
		(end 363.490764 -280.889202)
		(stroke
			(width 0.05715)
			(type default)
		)
		(layer "In11.Cu")
	)
	(gr_line
		(start 363.492034 -294.823642)
		(end 363.492542 -294.823896)
		(stroke
			(width 0.05715)
			(type default)
		)
		(layer "In11.Cu")
	)
	(gr_line
		(start 363.492034 -293.20363)
		(end 363.492542 -293.203884)
		(stroke
			(width 0.05715)
			(type default)
		)
		(layer "In11.Cu")
	)
	(gr_line
		(start 363.492034 -291.583618)
		(end 363.492542 -291.583872)
		(stroke
			(width 0.05715)
			(type default)
		)
		(layer "In11.Cu")
	)
	(gr_line
		(start 363.492034 -285.103824)
		(end 363.492542 -285.104078)
		(stroke
			(width 0.05715)
			(type default)
		)
		(layer "In11.Cu")
	)
	(gr_line
		(start 363.492034 -283.483812)
		(end 363.492542 -283.484066)
		(stroke
			(width 0.05715)
			(type default)
		)
		(layer "In11.Cu")
	)
	(gr_line
		(start 363.492034 -281.8638)
		(end 363.492542 -281.864054)
		(stroke
			(width 0.05715)
			(type default)
		)
		(layer "In11.Cu")
	)
	(gr_line
		(start 363.492542 -294.823896)
		(end 363.493812 -294.824658)
		(stroke
			(width 0.05715)
			(type default)
		)
		(layer "In11.Cu")
	)
	(gr_line
		(start 363.492542 -293.203884)
		(end 363.493812 -293.204646)
		(stroke
			(width 0.05715)
			(type default)
		)
		(layer "In11.Cu")
	)
	(gr_line
		(start 363.492542 -291.583872)
		(end 363.493812 -291.584634)
		(stroke
			(width 0.05715)
			(type default)
		)
		(layer "In11.Cu")
	)
	(gr_line
		(start 363.492542 -289.96386)
		(end 363.493812 -289.964622)
		(stroke
			(width 0.05715)
			(type default)
		)
		(layer "In11.Cu")
	)
	(gr_line
		(start 363.492542 -285.104078)
		(end 363.493812 -285.10484)
		(stroke
			(width 0.05715)
			(type default)
		)
		(layer "In11.Cu")
	)
	(gr_line
		(start 363.492542 -283.484066)
		(end 363.493812 -283.484828)
		(stroke
			(width 0.05715)
			(type default)
		)
		(layer "In11.Cu")
	)
	(gr_line
		(start 363.492542 -281.864054)
		(end 363.493812 -281.864816)
		(stroke
			(width 0.05715)
			(type default)
		)
		(layer "In11.Cu")
	)
	(gr_arc
		(start 363.570012 -224.226374)
		(mid 363.569891 -224.223834)
		(end 363.569758 -224.221294)
		(stroke
			(width 0.05715)
			(type default)
		)
		(layer "In11.Cu")
	)
	(gr_line
		(start 363.570012 -224.226374)
		(end 363.570012 -224.232978)
		(stroke
			(width 0.05715)
			(type default)
		)
		(layer "In11.Cu")
	)
	(gr_line
		(start 363.58703 -294.01389)
		(end 363.58576 -294.014652)
		(stroke
			(width 0.05715)
			(type default)
		)
		(layer "In11.Cu")
	)
	(gr_line
		(start 363.58703 -292.393878)
		(end 363.58576 -292.39464)
		(stroke
			(width 0.05715)
			(type default)
		)
		(layer "In11.Cu")
	)
	(gr_line
		(start 363.58703 -290.773866)
		(end 363.58576 -290.774628)
		(stroke
			(width 0.05715)
			(type default)
		)
		(layer "In11.Cu")
	)
	(gr_line
		(start 363.58703 -289.153854)
		(end 363.58576 -289.154616)
		(stroke
			(width 0.05715)
			(type default)
		)
		(layer "In11.Cu")
	)
	(gr_line
		(start 363.58703 -285.914084)
		(end 363.58576 -285.914846)
		(stroke
			(width 0.05715)
			(type default)
		)
		(layer "In11.Cu")
	)
	(gr_line
		(start 363.58703 -284.294072)
		(end 363.58576 -284.294834)
		(stroke
			(width 0.05715)
			(type default)
		)
		(layer "In11.Cu")
	)
	(gr_line
		(start 363.58703 -282.67406)
		(end 363.58576 -282.674822)
		(stroke
			(width 0.05715)
			(type default)
		)
		(layer "In11.Cu")
	)
	(gr_line
		(start 363.58703 -281.054048)
		(end 363.58576 -281.05481)
		(stroke
			(width 0.05715)
			(type default)
		)
		(layer "In11.Cu")
	)
	(gr_line
		(start 363.587284 -289.798252)
		(end 363.587792 -289.798506)
		(stroke
			(width 0.05715)
			(type default)
		)
		(layer "In11.Cu")
	)
	(gr_line
		(start 363.587538 -294.013636)
		(end 363.58703 -294.01389)
		(stroke
			(width 0.05715)
			(type default)
		)
		(layer "In11.Cu")
	)
	(gr_line
		(start 363.587538 -292.393624)
		(end 363.58703 -292.393878)
		(stroke
			(width 0.05715)
			(type default)
		)
		(layer "In11.Cu")
	)
	(gr_line
		(start 363.587538 -290.773612)
		(end 363.58703 -290.773866)
		(stroke
			(width 0.05715)
			(type default)
		)
		(layer "In11.Cu")
	)
	(gr_line
		(start 363.587538 -289.1536)
		(end 363.58703 -289.153854)
		(stroke
			(width 0.05715)
			(type default)
		)
		(layer "In11.Cu")
	)
	(gr_line
		(start 363.587538 -285.91383)
		(end 363.58703 -285.914084)
		(stroke
			(width 0.05715)
			(type default)
		)
		(layer "In11.Cu")
	)
	(gr_line
		(start 363.587538 -284.293818)
		(end 363.58703 -284.294072)
		(stroke
			(width 0.05715)
			(type default)
		)
		(layer "In11.Cu")
	)
	(gr_line
		(start 363.587538 -282.673806)
		(end 363.58703 -282.67406)
		(stroke
			(width 0.05715)
			(type default)
		)
		(layer "In11.Cu")
	)
	(gr_line
		(start 363.587538 -281.053794)
		(end 363.58703 -281.054048)
		(stroke
			(width 0.05715)
			(type default)
		)
		(layer "In11.Cu")
	)
	(gr_line
		(start 363.587792 -294.658542)
		(end 363.588808 -294.65905)
		(stroke
			(width 0.05715)
			(type default)
		)
		(layer "In11.Cu")
	)
	(gr_line
		(start 363.587792 -293.03853)
		(end 363.588808 -293.039038)
		(stroke
			(width 0.05715)
			(type default)
		)
		(layer "In11.Cu")
	)
	(gr_line
		(start 363.587792 -291.418518)
		(end 363.588808 -291.419026)
		(stroke
			(width 0.05715)
			(type default)
		)
		(layer "In11.Cu")
	)
	(gr_line
		(start 363.587792 -289.798506)
		(end 363.588808 -289.799014)
		(stroke
			(width 0.05715)
			(type default)
		)
		(layer "In11.Cu")
	)
	(gr_line
		(start 363.587792 -284.938724)
		(end 363.588808 -284.939232)
		(stroke
			(width 0.05715)
			(type default)
		)
		(layer "In11.Cu")
	)
	(gr_line
		(start 363.587792 -283.318712)
		(end 363.588808 -283.31922)
		(stroke
			(width 0.05715)
			(type default)
		)
		(layer "In11.Cu")
	)
	(gr_line
		(start 363.587792 -281.6987)
		(end 363.588808 -281.699208)
		(stroke
			(width 0.05715)
			(type default)
		)
		(layer "In11.Cu")
	)
	(gr_line
		(start 363.753654 -381.706882)
		(end 363.889544 -381.842772)
		(stroke
			(width 0.07112)
			(type default)
		)
		(layer "In11.Cu")
	)
	(gr_line
		(start 363.813344 -221.083124)
		(end 363.813344 -221.054676)
		(stroke
			(width 0.05715)
			(type default)
		)
		(layer "In11.Cu")
	)
	(gr_line
		(start 363.849666 -229.904036)
		(end 363.849412 -229.904036)
		(stroke
			(width 0.05715)
			(type default)
		)
		(layer "In11.Cu")
	)
	(gr_line
		(start 363.859064 -221.128844)
		(end 363.813344 -221.083124)
		(stroke
			(width 0.05715)
			(type default)
		)
		(layer "In11.Cu")
	)
	(gr_line
		(start 363.889544 -382.269492)
		(end 363.753654 -382.405382)
		(stroke
			(width 0.07112)
			(type default)
		)
		(layer "In11.Cu")
	)
	(gr_line
		(start 363.889544 -381.842772)
		(end 363.889544 -382.269492)
		(stroke
			(width 0.07112)
			(type default)
		)
		(layer "In11.Cu")
	)
	(gr_line
		(start 363.957616 -277.810722)
		(end 363.961426 -277.813262)
		(stroke
			(width 0.05715)
			(type default)
		)
		(layer "In11.Cu")
	)
	(gr_line
		(start 364.040166 -221.804484)
		(end 364.04042 -221.80423)
		(stroke
			(width 0.05715)
			(type default)
		)
		(layer "In11.Cu")
	)
	(gr_line
		(start 364.049564 -221.128844)
		(end 364.095284 -221.083124)
		(stroke
			(width 0.05715)
			(type default)
		)
		(layer "In11.Cu")
	)
	(gr_arc
		(start 364.086394 -228.744272)
		(mid 364.089561 -228.746569)
		(end 364.092744 -228.748844)
		(stroke
			(width 0.05715)
			(type default)
		)
		(layer "In11.Cu")
	)
	(gr_line
		(start 364.095284 -221.083124)
		(end 364.095284 -221.054676)
		(stroke
			(width 0.05715)
			(type default)
		)
		(layer "In11.Cu")
	)
	(gr_line
		(start 364.095538 -228.750876)
		(end 364.092744 -228.748844)
		(stroke
			(width 0.05715)
			(type default)
		)
		(layer "In11.Cu")
	)
	(gr_line
		(start 364.101634 -228.754432)
		(end 364.095538 -228.750876)
		(stroke
			(width 0.05715)
			(type default)
		)
		(layer "In11.Cu")
	)
	(gr_line
		(start 364.10392 -296.418508)
		(end 364.10392 -296.446956)
		(stroke
			(width 0.05715)
			(type default)
		)
		(layer "In11.Cu")
	)
	(gr_line
		(start 364.126272 -244.00002)
		(end 364.127034 -243.999512)
		(stroke
			(width 0.05715)
			(type default)
		)
		(layer "In11.Cu")
	)
	(gr_line
		(start 364.126272 -240.759996)
		(end 364.127034 -240.759488)
		(stroke
			(width 0.05715)
			(type default)
		)
		(layer "In11.Cu")
	)
	(gr_line
		(start 364.126272 -239.139984)
		(end 364.127034 -239.139476)
		(stroke
			(width 0.05715)
			(type default)
		)
		(layer "In11.Cu")
	)
	(gr_line
		(start 364.126272 -235.89996)
		(end 364.127034 -235.899452)
		(stroke
			(width 0.05715)
			(type default)
		)
		(layer "In11.Cu")
	)
	(gr_line
		(start 364.126272 -234.279948)
		(end 364.127034 -234.27944)
		(stroke
			(width 0.05715)
			(type default)
		)
		(layer "In11.Cu")
	)
	(gr_line
		(start 364.126272 -232.659936)
		(end 364.127034 -232.659428)
		(stroke
			(width 0.05715)
			(type default)
		)
		(layer "In11.Cu")
	)
	(gr_line
		(start 364.128812 -243.998496)
		(end 364.12932 -243.998242)
		(stroke
			(width 0.05715)
			(type default)
		)
		(layer "In11.Cu")
	)
	(gr_line
		(start 364.128812 -240.758472)
		(end 364.12932 -240.758218)
		(stroke
			(width 0.05715)
			(type default)
		)
		(layer "In11.Cu")
	)
	(gr_line
		(start 364.128812 -239.13846)
		(end 364.12932 -239.138206)
		(stroke
			(width 0.05715)
			(type default)
		)
		(layer "In11.Cu")
	)
	(gr_line
		(start 364.128812 -235.898436)
		(end 364.12932 -235.898182)
		(stroke
			(width 0.05715)
			(type default)
		)
		(layer "In11.Cu")
	)
	(gr_line
		(start 364.128812 -234.278424)
		(end 364.12932 -234.27817)
		(stroke
			(width 0.05715)
			(type default)
		)
		(layer "In11.Cu")
	)
	(gr_line
		(start 364.128812 -232.658412)
		(end 364.12932 -232.658158)
		(stroke
			(width 0.05715)
			(type default)
		)
		(layer "In11.Cu")
	)
	(gr_line
		(start 364.129066 -223.910144)
		(end 364.128304 -223.909636)
		(stroke
			(width 0.05715)
			(type default)
		)
		(layer "In11.Cu")
	)
	(gr_line
		(start 364.12932 -243.998242)
		(end 364.130844 -243.997226)
		(stroke
			(width 0.05715)
			(type default)
		)
		(layer "In11.Cu")
	)
	(gr_line
		(start 364.12932 -240.758218)
		(end 364.130844 -240.757202)
		(stroke
			(width 0.05715)
			(type default)
		)
		(layer "In11.Cu")
	)
	(gr_line
		(start 364.12932 -239.138206)
		(end 364.130844 -239.13719)
		(stroke
			(width 0.05715)
			(type default)
		)
		(layer "In11.Cu")
	)
	(gr_line
		(start 364.12932 -235.898182)
		(end 364.130844 -235.897166)
		(stroke
			(width 0.05715)
			(type default)
		)
		(layer "In11.Cu")
	)
	(gr_line
		(start 364.12932 -234.27817)
		(end 364.130844 -234.277154)
		(stroke
			(width 0.05715)
			(type default)
		)
		(layer "In11.Cu")
	)
	(gr_line
		(start 364.12932 -232.658158)
		(end 364.130844 -232.657142)
		(stroke
			(width 0.05715)
			(type default)
		)
		(layer "In11.Cu")
	)
	(gr_line
		(start 364.130844 -243.997226)
		(end 364.13186 -243.996718)
		(stroke
			(width 0.05715)
			(type default)
		)
		(layer "In11.Cu")
	)
	(gr_line
		(start 364.130844 -240.757202)
		(end 364.13186 -240.756694)
		(stroke
			(width 0.05715)
			(type default)
		)
		(layer "In11.Cu")
	)
	(gr_line
		(start 364.130844 -239.13719)
		(end 364.13186 -239.136682)
		(stroke
			(width 0.05715)
			(type default)
		)
		(layer "In11.Cu")
	)
	(gr_line
		(start 364.130844 -235.897166)
		(end 364.13186 -235.896658)
		(stroke
			(width 0.05715)
			(type default)
		)
		(layer "In11.Cu")
	)
	(gr_line
		(start 364.130844 -234.277154)
		(end 364.13186 -234.276646)
		(stroke
			(width 0.05715)
			(type default)
		)
		(layer "In11.Cu")
	)
	(gr_line
		(start 364.130844 -232.657142)
		(end 364.13186 -232.656634)
		(stroke
			(width 0.05715)
			(type default)
		)
		(layer "In11.Cu")
	)
	(gr_line
		(start 364.131606 -223.911668)
		(end 364.13059 -223.91116)
		(stroke
			(width 0.05715)
			(type default)
		)
		(layer "In11.Cu")
	)
	(gr_line
		(start 364.13186 -243.996718)
		(end 364.132622 -243.99621)
		(stroke
			(width 0.05715)
			(type default)
		)
		(layer "In11.Cu")
	)
	(gr_line
		(start 364.13186 -240.756694)
		(end 364.132622 -240.756186)
		(stroke
			(width 0.05715)
			(type default)
		)
		(layer "In11.Cu")
	)
	(gr_line
		(start 364.13186 -239.136682)
		(end 364.132622 -239.136174)
		(stroke
			(width 0.05715)
			(type default)
		)
		(layer "In11.Cu")
	)
	(gr_line
		(start 364.13186 -238.491522)
		(end 364.130844 -238.491014)
		(stroke
			(width 0.05715)
			(type default)
		)
		(layer "In11.Cu")
	)
	(gr_line
		(start 364.13186 -235.896658)
		(end 364.132622 -235.89615)
		(stroke
			(width 0.05715)
			(type default)
		)
		(layer "In11.Cu")
	)
	(gr_line
		(start 364.13186 -234.276646)
		(end 364.132622 -234.276138)
		(stroke
			(width 0.05715)
			(type default)
		)
		(layer "In11.Cu")
	)
	(gr_line
		(start 364.13186 -232.656634)
		(end 364.132622 -232.656126)
		(stroke
			(width 0.05715)
			(type default)
		)
		(layer "In11.Cu")
	)
	(gr_line
		(start 364.132114 -223.911922)
		(end 364.131606 -223.911668)
		(stroke
			(width 0.05715)
			(type default)
		)
		(layer "In11.Cu")
	)
	(gr_line
		(start 364.132368 -238.491776)
		(end 364.13186 -238.491522)
		(stroke
			(width 0.05715)
			(type default)
		)
		(layer "In11.Cu")
	)
	(gr_line
		(start 364.132622 -246.59209)
		(end 364.13186 -246.591582)
		(stroke
			(width 0.05715)
			(type default)
		)
		(layer "In11.Cu")
	)
	(gr_line
		(start 364.132622 -245.616222)
		(end 364.133892 -245.61546)
		(stroke
			(width 0.05715)
			(type default)
		)
		(layer "In11.Cu")
	)
	(gr_line
		(start 364.132622 -244.972078)
		(end 364.13186 -244.97157)
		(stroke
			(width 0.05715)
			(type default)
		)
		(layer "In11.Cu")
	)
	(gr_line
		(start 364.132622 -243.352066)
		(end 364.13186 -243.351558)
		(stroke
			(width 0.05715)
			(type default)
		)
		(layer "In11.Cu")
	)
	(gr_line
		(start 364.132622 -242.376198)
		(end 364.133892 -242.375436)
		(stroke
			(width 0.05715)
			(type default)
		)
		(layer "In11.Cu")
	)
	(gr_line
		(start 364.132622 -241.732054)
		(end 364.13186 -241.731546)
		(stroke
			(width 0.05715)
			(type default)
		)
		(layer "In11.Cu")
	)
	(gr_line
		(start 364.132622 -240.112042)
		(end 364.13186 -240.111534)
		(stroke
			(width 0.05715)
			(type default)
		)
		(layer "In11.Cu")
	)
	(gr_line
		(start 364.132622 -237.516162)
		(end 364.133892 -237.5154)
		(stroke
			(width 0.05715)
			(type default)
		)
		(layer "In11.Cu")
	)
	(gr_line
		(start 364.132622 -236.872018)
		(end 364.13186 -236.87151)
		(stroke
			(width 0.05715)
			(type default)
		)
		(layer "In11.Cu")
	)
	(gr_line
		(start 364.132622 -235.252006)
		(end 364.13186 -235.251498)
		(stroke
			(width 0.05715)
			(type default)
		)
		(layer "In11.Cu")
	)
	(gr_line
		(start 364.132622 -233.631994)
		(end 364.13186 -233.631486)
		(stroke
			(width 0.05715)
			(type default)
		)
		(layer "In11.Cu")
	)
	(gr_line
		(start 364.132622 -232.011982)
		(end 364.13186 -232.011474)
		(stroke
			(width 0.05715)
			(type default)
		)
		(layer "In11.Cu")
	)
	(gr_line
		(start 364.136178 -243.994178)
		(end 364.137194 -243.99367)
		(stroke
			(width 0.05715)
			(type default)
		)
		(layer "In11.Cu")
	)
	(gr_line
		(start 364.136178 -240.754154)
		(end 364.137194 -240.753646)
		(stroke
			(width 0.05715)
			(type default)
		)
		(layer "In11.Cu")
	)
	(gr_line
		(start 364.136178 -239.134142)
		(end 364.137194 -239.133634)
		(stroke
			(width 0.05715)
			(type default)
		)
		(layer "In11.Cu")
	)
	(gr_line
		(start 364.136178 -235.894118)
		(end 364.137194 -235.89361)
		(stroke
			(width 0.05715)
			(type default)
		)
		(layer "In11.Cu")
	)
	(gr_line
		(start 364.136178 -234.274106)
		(end 364.137194 -234.273598)
		(stroke
			(width 0.05715)
			(type default)
		)
		(layer "In11.Cu")
	)
	(gr_line
		(start 364.136178 -232.654094)
		(end 364.137194 -232.653586)
		(stroke
			(width 0.05715)
			(type default)
		)
		(layer "In11.Cu")
	)
	(gr_line
		(start 364.137956 -243.993162)
		(end 364.13948 -243.9924)
		(stroke
			(width 0.05715)
			(type default)
		)
		(layer "In11.Cu")
	)
	(gr_line
		(start 364.137956 -240.753138)
		(end 364.13948 -240.752376)
		(stroke
			(width 0.05715)
			(type default)
		)
		(layer "In11.Cu")
	)
	(gr_line
		(start 364.137956 -239.133126)
		(end 364.13948 -239.132364)
		(stroke
			(width 0.05715)
			(type default)
		)
		(layer "In11.Cu")
	)
	(gr_line
		(start 364.137956 -235.893102)
		(end 364.13948 -235.89234)
		(stroke
			(width 0.05715)
			(type default)
		)
		(layer "In11.Cu")
	)
	(gr_line
		(start 364.137956 -234.27309)
		(end 364.13948 -234.272328)
		(stroke
			(width 0.05715)
			(type default)
		)
		(layer "In11.Cu")
	)
	(gr_line
		(start 364.137956 -232.653078)
		(end 364.13948 -232.652316)
		(stroke
			(width 0.05715)
			(type default)
		)
		(layer "In11.Cu")
	)
	(gr_line
		(start 364.14964 -296.372788)
		(end 364.10392 -296.418508)
		(stroke
			(width 0.05715)
			(type default)
		)
		(layer "In11.Cu")
	)
	(gr_line
		(start 364.151926 -276.50948)
		(end 364.151672 -276.509226)
		(stroke
			(width 0.05715)
			(type default)
		)
		(layer "In11.Cu")
	)
	(gr_line
		(start 364.16361 -222.918528)
		(end 364.16361 -222.918274)
		(stroke
			(width 0.05715)
			(type default)
		)
		(layer "In11.Cu")
	)
	(gr_line
		(start 364.221776 -246.42318)
		(end 364.22076 -246.422672)
		(stroke
			(width 0.05715)
			(type default)
		)
		(layer "In11.Cu")
	)
	(gr_line
		(start 364.221776 -244.803168)
		(end 364.22076 -244.80266)
		(stroke
			(width 0.05715)
			(type default)
		)
		(layer "In11.Cu")
	)
	(gr_line
		(start 364.221776 -243.183156)
		(end 364.22076 -243.182648)
		(stroke
			(width 0.05715)
			(type default)
		)
		(layer "In11.Cu")
	)
	(gr_line
		(start 364.221776 -241.563144)
		(end 364.22076 -241.562636)
		(stroke
			(width 0.05715)
			(type default)
		)
		(layer "In11.Cu")
	)
	(gr_line
		(start 364.221776 -239.943132)
		(end 364.22076 -239.942624)
		(stroke
			(width 0.05715)
			(type default)
		)
		(layer "In11.Cu")
	)
	(gr_line
		(start 364.221776 -236.703108)
		(end 364.22076 -236.7026)
		(stroke
			(width 0.05715)
			(type default)
		)
		(layer "In11.Cu")
	)
	(gr_line
		(start 364.221776 -235.083096)
		(end 364.22076 -235.082588)
		(stroke
			(width 0.05715)
			(type default)
		)
		(layer "In11.Cu")
	)
	(gr_line
		(start 364.221776 -233.463084)
		(end 364.22076 -233.462576)
		(stroke
			(width 0.05715)
			(type default)
		)
		(layer "In11.Cu")
	)
	(gr_line
		(start 364.221776 -231.843072)
		(end 364.22076 -231.842564)
		(stroke
			(width 0.05715)
			(type default)
		)
		(layer "In11.Cu")
	)
	(gr_line
		(start 364.222538 -246.423688)
		(end 364.221776 -246.42318)
		(stroke
			(width 0.05715)
			(type default)
		)
		(layer "In11.Cu")
	)
	(gr_line
		(start 364.222538 -244.803676)
		(end 364.221776 -244.803168)
		(stroke
			(width 0.05715)
			(type default)
		)
		(layer "In11.Cu")
	)
	(gr_line
		(start 364.222538 -244.164612)
		(end 364.223554 -244.164104)
		(stroke
			(width 0.05715)
			(type default)
		)
		(layer "In11.Cu")
	)
	(gr_line
		(start 364.222538 -243.183664)
		(end 364.221776 -243.183156)
		(stroke
			(width 0.05715)
			(type default)
		)
		(layer "In11.Cu")
	)
	(gr_line
		(start 364.222538 -241.563652)
		(end 364.221776 -241.563144)
		(stroke
			(width 0.05715)
			(type default)
		)
		(layer "In11.Cu")
	)
	(gr_line
		(start 364.222538 -240.924588)
		(end 364.223554 -240.92408)
		(stroke
			(width 0.05715)
			(type default)
		)
		(layer "In11.Cu")
	)
	(gr_line
		(start 364.222538 -239.94364)
		(end 364.221776 -239.943132)
		(stroke
			(width 0.05715)
			(type default)
		)
		(layer "In11.Cu")
	)
	(gr_line
		(start 364.222538 -239.304576)
		(end 364.223554 -239.304068)
		(stroke
			(width 0.05715)
			(type default)
		)
		(layer "In11.Cu")
	)
	(gr_line
		(start 364.222538 -236.703616)
		(end 364.221776 -236.703108)
		(stroke
			(width 0.05715)
			(type default)
		)
		(layer "In11.Cu")
	)
	(gr_line
		(start 364.222538 -236.064552)
		(end 364.223554 -236.064044)
		(stroke
			(width 0.05715)
			(type default)
		)
		(layer "In11.Cu")
	)
	(gr_line
		(start 364.222538 -235.083604)
		(end 364.221776 -235.083096)
		(stroke
			(width 0.05715)
			(type default)
		)
		(layer "In11.Cu")
	)
	(gr_line
		(start 364.222538 -234.44454)
		(end 364.223554 -234.444032)
		(stroke
			(width 0.05715)
			(type default)
		)
		(layer "In11.Cu")
	)
	(gr_line
		(start 364.222538 -233.463592)
		(end 364.221776 -233.463084)
		(stroke
			(width 0.05715)
			(type default)
		)
		(layer "In11.Cu")
	)
	(gr_line
		(start 364.222538 -232.824528)
		(end 364.223554 -232.82402)
		(stroke
			(width 0.05715)
			(type default)
		)
		(layer "In11.Cu")
	)
	(gr_line
		(start 364.222538 -231.84358)
		(end 364.221776 -231.843072)
		(stroke
			(width 0.05715)
			(type default)
		)
		(layer "In11.Cu")
	)
	(gr_line
		(start 364.223554 -246.424196)
		(end 364.222538 -246.423688)
		(stroke
			(width 0.05715)
			(type default)
		)
		(layer "In11.Cu")
	)
	(gr_line
		(start 364.223554 -244.804184)
		(end 364.222538 -244.803676)
		(stroke
			(width 0.05715)
			(type default)
		)
		(layer "In11.Cu")
	)
	(gr_line
		(start 364.223554 -244.164104)
		(end 364.224316 -244.163596)
		(stroke
			(width 0.05715)
			(type default)
		)
		(layer "In11.Cu")
	)
	(gr_line
		(start 364.223554 -243.184172)
		(end 364.222538 -243.183664)
		(stroke
			(width 0.05715)
			(type default)
		)
		(layer "In11.Cu")
	)
	(gr_line
		(start 364.223554 -241.56416)
		(end 364.222538 -241.563652)
		(stroke
			(width 0.05715)
			(type default)
		)
		(layer "In11.Cu")
	)
	(gr_line
		(start 364.223554 -240.92408)
		(end 364.224316 -240.923572)
		(stroke
			(width 0.05715)
			(type default)
		)
		(layer "In11.Cu")
	)
	(gr_line
		(start 364.223554 -239.944148)
		(end 364.222538 -239.94364)
		(stroke
			(width 0.05715)
			(type default)
		)
		(layer "In11.Cu")
	)
	(gr_line
		(start 364.223554 -239.304068)
		(end 364.224316 -239.30356)
		(stroke
			(width 0.05715)
			(type default)
		)
		(layer "In11.Cu")
	)
	(gr_line
		(start 364.223554 -236.704124)
		(end 364.222538 -236.703616)
		(stroke
			(width 0.05715)
			(type default)
		)
		(layer "In11.Cu")
	)
	(gr_line
		(start 364.223554 -236.064044)
		(end 364.224316 -236.063536)
		(stroke
			(width 0.05715)
			(type default)
		)
		(layer "In11.Cu")
	)
	(gr_line
		(start 364.223554 -235.084112)
		(end 364.222538 -235.083604)
		(stroke
			(width 0.05715)
			(type default)
		)
		(layer "In11.Cu")
	)
	(gr_line
		(start 364.223554 -234.444032)
		(end 364.224316 -234.443524)
		(stroke
			(width 0.05715)
			(type default)
		)
		(layer "In11.Cu")
	)
	(gr_line
		(start 364.223554 -233.4641)
		(end 364.222538 -233.463592)
		(stroke
			(width 0.05715)
			(type default)
		)
		(layer "In11.Cu")
	)
	(gr_line
		(start 364.223554 -232.82402)
		(end 364.224316 -232.823512)
		(stroke
			(width 0.05715)
			(type default)
		)
		(layer "In11.Cu")
	)
	(gr_line
		(start 364.223554 -231.844088)
		(end 364.222538 -231.84358)
		(stroke
			(width 0.05715)
			(type default)
		)
		(layer "In11.Cu")
	)
	(gr_line
		(start 364.224316 -246.424704)
		(end 364.223554 -246.424196)
		(stroke
			(width 0.05715)
			(type default)
		)
		(layer "In11.Cu")
	)
	(gr_line
		(start 364.224316 -244.804692)
		(end 364.223554 -244.804184)
		(stroke
			(width 0.05715)
			(type default)
		)
		(layer "In11.Cu")
	)
	(gr_line
		(start 364.224316 -244.163596)
		(end 364.22711 -244.162072)
		(stroke
			(width 0.05715)
			(type default)
		)
		(layer "In11.Cu")
	)
	(gr_line
		(start 364.224316 -243.18468)
		(end 364.223554 -243.184172)
		(stroke
			(width 0.05715)
			(type default)
		)
		(layer "In11.Cu")
	)
	(gr_line
		(start 364.224316 -241.564668)
		(end 364.223554 -241.56416)
		(stroke
			(width 0.05715)
			(type default)
		)
		(layer "In11.Cu")
	)
	(gr_line
		(start 364.224316 -240.923572)
		(end 364.22711 -240.922048)
		(stroke
			(width 0.05715)
			(type default)
		)
		(layer "In11.Cu")
	)
	(gr_line
		(start 364.224316 -239.944656)
		(end 364.223554 -239.944148)
		(stroke
			(width 0.05715)
			(type default)
		)
		(layer "In11.Cu")
	)
	(gr_line
		(start 364.224316 -239.30356)
		(end 364.22711 -239.302036)
		(stroke
			(width 0.05715)
			(type default)
		)
		(layer "In11.Cu")
	)
	(gr_line
		(start 364.224316 -236.704632)
		(end 364.223554 -236.704124)
		(stroke
			(width 0.05715)
			(type default)
		)
		(layer "In11.Cu")
	)
	(gr_line
		(start 364.224316 -236.063536)
		(end 364.22711 -236.062012)
		(stroke
			(width 0.05715)
			(type default)
		)
		(layer "In11.Cu")
	)
	(gr_line
		(start 364.224316 -235.08462)
		(end 364.223554 -235.084112)
		(stroke
			(width 0.05715)
			(type default)
		)
		(layer "In11.Cu")
	)
	(gr_line
		(start 364.224316 -234.443524)
		(end 364.22711 -234.442)
		(stroke
			(width 0.05715)
			(type default)
		)
		(layer "In11.Cu")
	)
	(gr_line
		(start 364.224316 -233.464608)
		(end 364.223554 -233.4641)
		(stroke
			(width 0.05715)
			(type default)
		)
		(layer "In11.Cu")
	)
	(gr_line
		(start 364.224316 -232.823512)
		(end 364.22711 -232.821988)
		(stroke
			(width 0.05715)
			(type default)
		)
		(layer "In11.Cu")
	)
	(gr_line
		(start 364.224316 -231.844596)
		(end 364.223554 -231.844088)
		(stroke
			(width 0.05715)
			(type default)
		)
		(layer "In11.Cu")
	)
	(gr_line
		(start 364.225586 -223.745552)
		(end 364.223808 -223.744536)
		(stroke
			(width 0.05715)
			(type default)
		)
		(layer "In11.Cu")
	)
	(gr_line
		(start 364.226856 -223.746314)
		(end 364.225586 -223.745552)
		(stroke
			(width 0.05715)
			(type default)
		)
		(layer "In11.Cu")
	)
	(gr_line
		(start 364.22711 -246.426228)
		(end 364.224316 -246.424704)
		(stroke
			(width 0.05715)
			(type default)
		)
		(layer "In11.Cu")
	)
	(gr_line
		(start 364.22711 -244.806216)
		(end 364.224316 -244.804692)
		(stroke
			(width 0.05715)
			(type default)
		)
		(layer "In11.Cu")
	)
	(gr_line
		(start 364.22711 -244.162072)
		(end 364.227872 -244.161564)
		(stroke
			(width 0.05715)
			(type default)
		)
		(layer "In11.Cu")
	)
	(gr_line
		(start 364.22711 -243.186204)
		(end 364.224316 -243.18468)
		(stroke
			(width 0.05715)
			(type default)
		)
		(layer "In11.Cu")
	)
	(gr_line
		(start 364.22711 -241.566192)
		(end 364.224316 -241.564668)
		(stroke
			(width 0.05715)
			(type default)
		)
		(layer "In11.Cu")
	)
	(gr_line
		(start 364.22711 -240.922048)
		(end 364.227872 -240.92154)
		(stroke
			(width 0.05715)
			(type default)
		)
		(layer "In11.Cu")
	)
	(gr_line
		(start 364.22711 -239.94618)
		(end 364.224316 -239.944656)
		(stroke
			(width 0.05715)
			(type default)
		)
		(layer "In11.Cu")
	)
	(gr_line
		(start 364.22711 -239.302036)
		(end 364.227872 -239.301528)
		(stroke
			(width 0.05715)
			(type default)
		)
		(layer "In11.Cu")
	)
	(gr_line
		(start 364.22711 -238.326168)
		(end 364.22584 -238.325406)
		(stroke
			(width 0.05715)
			(type default)
		)
		(layer "In11.Cu")
	)
	(gr_line
		(start 364.22711 -236.706156)
		(end 364.224316 -236.704632)
		(stroke
			(width 0.05715)
			(type default)
		)
		(layer "In11.Cu")
	)
	(gr_line
		(start 364.22711 -236.062012)
		(end 364.227872 -236.061504)
		(stroke
			(width 0.05715)
			(type default)
		)
		(layer "In11.Cu")
	)
	(gr_line
		(start 364.22711 -235.086144)
		(end 364.224316 -235.08462)
		(stroke
			(width 0.05715)
			(type default)
		)
		(layer "In11.Cu")
	)
	(gr_line
		(start 364.22711 -234.442)
		(end 364.227872 -234.441492)
		(stroke
			(width 0.05715)
			(type default)
		)
		(layer "In11.Cu")
	)
	(gr_line
		(start 364.22711 -233.466132)
		(end 364.224316 -233.464608)
		(stroke
			(width 0.05715)
			(type default)
		)
		(layer "In11.Cu")
	)
	(gr_line
		(start 364.22711 -232.821988)
		(end 364.227872 -232.82148)
		(stroke
			(width 0.05715)
			(type default)
		)
		(layer "In11.Cu")
	)
	(gr_line
		(start 364.22711 -231.84612)
		(end 364.224316 -231.844596)
		(stroke
			(width 0.05715)
			(type default)
		)
		(layer "In11.Cu")
	)
	(gr_line
		(start 364.227364 -245.78183)
		(end 364.227872 -245.781576)
		(stroke
			(width 0.05715)
			(type default)
		)
		(layer "In11.Cu")
	)
	(gr_line
		(start 364.227364 -242.541806)
		(end 364.227872 -242.541552)
		(stroke
			(width 0.05715)
			(type default)
		)
		(layer "In11.Cu")
	)
	(gr_line
		(start 364.227364 -237.68177)
		(end 364.227872 -237.681516)
		(stroke
			(width 0.05715)
			(type default)
		)
		(layer "In11.Cu")
	)
	(gr_line
		(start 364.227872 -246.426736)
		(end 364.22711 -246.426228)
		(stroke
			(width 0.05715)
			(type default)
		)
		(layer "In11.Cu")
	)
	(gr_line
		(start 364.227872 -245.781576)
		(end 364.228888 -245.781068)
		(stroke
			(width 0.05715)
			(type default)
		)
		(layer "In11.Cu")
	)
	(gr_line
		(start 364.227872 -244.806724)
		(end 364.22711 -244.806216)
		(stroke
			(width 0.05715)
			(type default)
		)
		(layer "In11.Cu")
	)
	(gr_line
		(start 364.227872 -244.161564)
		(end 364.228888 -244.161056)
		(stroke
			(width 0.05715)
			(type default)
		)
		(layer "In11.Cu")
	)
	(gr_line
		(start 364.227872 -243.186712)
		(end 364.22711 -243.186204)
		(stroke
			(width 0.05715)
			(type default)
		)
		(layer "In11.Cu")
	)
	(gr_line
		(start 364.227872 -242.541552)
		(end 364.228888 -242.541044)
		(stroke
			(width 0.05715)
			(type default)
		)
		(layer "In11.Cu")
	)
	(gr_line
		(start 364.227872 -241.5667)
		(end 364.22711 -241.566192)
		(stroke
			(width 0.05715)
			(type default)
		)
		(layer "In11.Cu")
	)
	(gr_line
		(start 364.227872 -240.92154)
		(end 364.228888 -240.921032)
		(stroke
			(width 0.05715)
			(type default)
		)
		(layer "In11.Cu")
	)
	(gr_line
		(start 364.227872 -239.946688)
		(end 364.22711 -239.94618)
		(stroke
			(width 0.05715)
			(type default)
		)
		(layer "In11.Cu")
	)
	(gr_line
		(start 364.227872 -239.301528)
		(end 364.228888 -239.30102)
		(stroke
			(width 0.05715)
			(type default)
		)
		(layer "In11.Cu")
	)
	(gr_line
		(start 364.227872 -237.681516)
		(end 364.228888 -237.681008)
		(stroke
			(width 0.05715)
			(type default)
		)
		(layer "In11.Cu")
	)
	(gr_line
		(start 364.227872 -236.706664)
		(end 364.22711 -236.706156)
		(stroke
			(width 0.05715)
			(type default)
		)
		(layer "In11.Cu")
	)
	(gr_line
		(start 364.227872 -236.061504)
		(end 364.228888 -236.060996)
		(stroke
			(width 0.05715)
			(type default)
		)
		(layer "In11.Cu")
	)
	(gr_line
		(start 364.227872 -235.086652)
		(end 364.22711 -235.086144)
		(stroke
			(width 0.05715)
			(type default)
		)
		(layer "In11.Cu")
	)
	(gr_line
		(start 364.227872 -234.441492)
		(end 364.228888 -234.440984)
		(stroke
			(width 0.05715)
			(type default)
		)
		(layer "In11.Cu")
	)
	(gr_line
		(start 364.227872 -233.46664)
		(end 364.22711 -233.466132)
		(stroke
			(width 0.05715)
			(type default)
		)
		(layer "In11.Cu")
	)
	(gr_line
		(start 364.227872 -232.82148)
		(end 364.228888 -232.820972)
		(stroke
			(width 0.05715)
			(type default)
		)
		(layer "In11.Cu")
	)
	(gr_line
		(start 364.227872 -231.846628)
		(end 364.22711 -231.84612)
		(stroke
			(width 0.05715)
			(type default)
		)
		(layer "In11.Cu")
	)
	(gr_line
		(start 364.228888 -246.427244)
		(end 364.227872 -246.426736)
		(stroke
			(width 0.05715)
			(type default)
		)
		(layer "In11.Cu")
	)
	(gr_line
		(start 364.228888 -244.807232)
		(end 364.227872 -244.806724)
		(stroke
			(width 0.05715)
			(type default)
		)
		(layer "In11.Cu")
	)
	(gr_line
		(start 364.228888 -244.161056)
		(end 364.230666 -244.16004)
		(stroke
			(width 0.05715)
			(type default)
		)
		(layer "In11.Cu")
	)
	(gr_line
		(start 364.228888 -243.18722)
		(end 364.227872 -243.186712)
		(stroke
			(width 0.05715)
			(type default)
		)
		(layer "In11.Cu")
	)
	(gr_line
		(start 364.228888 -241.567208)
		(end 364.227872 -241.5667)
		(stroke
			(width 0.05715)
			(type default)
		)
		(layer "In11.Cu")
	)
	(gr_line
		(start 364.228888 -240.921032)
		(end 364.230666 -240.920016)
		(stroke
			(width 0.05715)
			(type default)
		)
		(layer "In11.Cu")
	)
	(gr_line
		(start 364.228888 -239.947196)
		(end 364.227872 -239.946688)
		(stroke
			(width 0.05715)
			(type default)
		)
		(layer "In11.Cu")
	)
	(gr_line
		(start 364.228888 -239.30102)
		(end 364.230666 -239.300004)
		(stroke
			(width 0.05715)
			(type default)
		)
		(layer "In11.Cu")
	)
	(gr_line
		(start 364.228888 -236.707172)
		(end 364.227872 -236.706664)
		(stroke
			(width 0.05715)
			(type default)
		)
		(layer "In11.Cu")
	)
	(gr_line
		(start 364.228888 -236.060996)
		(end 364.230666 -236.05998)
		(stroke
			(width 0.05715)
			(type default)
		)
		(layer "In11.Cu")
	)
	(gr_line
		(start 364.228888 -235.08716)
		(end 364.227872 -235.086652)
		(stroke
			(width 0.05715)
			(type default)
		)
		(layer "In11.Cu")
	)
	(gr_line
		(start 364.228888 -234.440984)
		(end 364.230666 -234.439968)
		(stroke
			(width 0.05715)
			(type default)
		)
		(layer "In11.Cu")
	)
	(gr_line
		(start 364.228888 -233.467148)
		(end 364.227872 -233.46664)
		(stroke
			(width 0.05715)
			(type default)
		)
		(layer "In11.Cu")
	)
	(gr_line
		(start 364.228888 -232.820972)
		(end 364.230666 -232.819956)
		(stroke
			(width 0.05715)
			(type default)
		)
		(layer "In11.Cu")
	)
	(gr_line
		(start 364.228888 -231.847136)
		(end 364.227872 -231.846628)
		(stroke
			(width 0.05715)
			(type default)
		)
		(layer "In11.Cu")
	)
	(gr_line
		(start 364.230158 -246.428006)
		(end 364.228888 -246.427244)
		(stroke
			(width 0.05715)
			(type default)
		)
		(layer "In11.Cu")
	)
	(gr_line
		(start 364.230158 -244.807994)
		(end 364.228888 -244.807232)
		(stroke
			(width 0.05715)
			(type default)
		)
		(layer "In11.Cu")
	)
	(gr_line
		(start 364.230158 -243.187982)
		(end 364.228888 -243.18722)
		(stroke
			(width 0.05715)
			(type default)
		)
		(layer "In11.Cu")
	)
	(gr_line
		(start 364.230158 -241.56797)
		(end 364.228888 -241.567208)
		(stroke
			(width 0.05715)
			(type default)
		)
		(layer "In11.Cu")
	)
	(gr_line
		(start 364.230158 -239.947958)
		(end 364.228888 -239.947196)
		(stroke
			(width 0.05715)
			(type default)
		)
		(layer "In11.Cu")
	)
	(gr_line
		(start 364.230158 -236.707934)
		(end 364.228888 -236.707172)
		(stroke
			(width 0.05715)
			(type default)
		)
		(layer "In11.Cu")
	)
	(gr_line
		(start 364.230158 -235.087922)
		(end 364.228888 -235.08716)
		(stroke
			(width 0.05715)
			(type default)
		)
		(layer "In11.Cu")
	)
	(gr_line
		(start 364.230158 -233.46791)
		(end 364.228888 -233.467148)
		(stroke
			(width 0.05715)
			(type default)
		)
		(layer "In11.Cu")
	)
	(gr_line
		(start 364.230158 -231.847898)
		(end 364.228888 -231.847136)
		(stroke
			(width 0.05715)
			(type default)
		)
		(layer "In11.Cu")
	)
	(gr_line
		(start 364.230666 -246.42826)
		(end 364.230158 -246.428006)
		(stroke
			(width 0.05715)
			(type default)
		)
		(layer "In11.Cu")
	)
	(gr_line
		(start 364.230666 -244.808248)
		(end 364.230158 -244.807994)
		(stroke
			(width 0.05715)
			(type default)
		)
		(layer "In11.Cu")
	)
	(gr_line
		(start 364.230666 -243.188236)
		(end 364.230158 -243.187982)
		(stroke
			(width 0.05715)
			(type default)
		)
		(layer "In11.Cu")
	)
	(gr_line
		(start 364.230666 -241.568224)
		(end 364.230158 -241.56797)
		(stroke
			(width 0.05715)
			(type default)
		)
		(layer "In11.Cu")
	)
	(gr_line
		(start 364.230666 -239.948212)
		(end 364.230158 -239.947958)
		(stroke
			(width 0.05715)
			(type default)
		)
		(layer "In11.Cu")
	)
	(gr_line
		(start 364.230666 -236.708188)
		(end 364.230158 -236.707934)
		(stroke
			(width 0.05715)
			(type default)
		)
		(layer "In11.Cu")
	)
	(gr_line
		(start 364.230666 -235.088176)
		(end 364.230158 -235.087922)
		(stroke
			(width 0.05715)
			(type default)
		)
		(layer "In11.Cu")
	)
	(gr_line
		(start 364.230666 -233.468164)
		(end 364.230158 -233.46791)
		(stroke
			(width 0.05715)
			(type default)
		)
		(layer "In11.Cu")
	)
	(gr_line
		(start 364.230666 -231.848152)
		(end 364.230158 -231.847898)
		(stroke
			(width 0.05715)
			(type default)
		)
		(layer "In11.Cu")
	)
	(gr_line
		(start 364.23219 -244.159024)
		(end 364.233206 -244.158516)
		(stroke
			(width 0.05715)
			(type default)
		)
		(layer "In11.Cu")
	)
	(gr_line
		(start 364.23219 -240.919)
		(end 364.233206 -240.918492)
		(stroke
			(width 0.05715)
			(type default)
		)
		(layer "In11.Cu")
	)
	(gr_line
		(start 364.23219 -239.298988)
		(end 364.233206 -239.29848)
		(stroke
			(width 0.05715)
			(type default)
		)
		(layer "In11.Cu")
	)
	(gr_line
		(start 364.23219 -236.058964)
		(end 364.233206 -236.058456)
		(stroke
			(width 0.05715)
			(type default)
		)
		(layer "In11.Cu")
	)
	(gr_line
		(start 364.23219 -234.438952)
		(end 364.233206 -234.438444)
		(stroke
			(width 0.05715)
			(type default)
		)
		(layer "In11.Cu")
	)
	(gr_line
		(start 364.23219 -232.81894)
		(end 364.233206 -232.818432)
		(stroke
			(width 0.05715)
			(type default)
		)
		(layer "In11.Cu")
	)
	(gr_line
		(start 364.23981 -390.46023)
		(end 364.240572 -390.46023)
		(stroke
			(width 0.07112)
			(type default)
		)
		(layer "In11.Cu")
	)
	(gr_line
		(start 364.240572 -390.46023)
		(end 364.53064 -390.750298)
		(stroke
			(width 0.07112)
			(type default)
		)
		(layer "In11.Cu")
	)
	(gr_line
		(start 364.240572 -390.177528)
		(end 364.53064 -389.88746)
		(stroke
			(width 0.07112)
			(type default)
		)
		(layer "In11.Cu")
	)
	(gr_line
		(start 364.258606 -244.143784)
		(end 364.259368 -244.143276)
		(stroke
			(width 0.05715)
			(type default)
		)
		(layer "In11.Cu")
	)
	(gr_line
		(start 364.258606 -240.90376)
		(end 364.259368 -240.903252)
		(stroke
			(width 0.05715)
			(type default)
		)
		(layer "In11.Cu")
	)
	(gr_line
		(start 364.258606 -239.283748)
		(end 364.259368 -239.28324)
		(stroke
			(width 0.05715)
			(type default)
		)
		(layer "In11.Cu")
	)
	(gr_line
		(start 364.258606 -236.043724)
		(end 364.259368 -236.043216)
		(stroke
			(width 0.05715)
			(type default)
		)
		(layer "In11.Cu")
	)
	(gr_line
		(start 364.258606 -234.423712)
		(end 364.259368 -234.423204)
		(stroke
			(width 0.05715)
			(type default)
		)
		(layer "In11.Cu")
	)
	(gr_line
		(start 364.258606 -232.8037)
		(end 364.259368 -232.803192)
		(stroke
			(width 0.05715)
			(type default)
		)
		(layer "In11.Cu")
	)
	(gr_line
		(start 364.259368 -244.143276)
		(end 364.26013 -244.142768)
		(stroke
			(width 0.05715)
			(type default)
		)
		(layer "In11.Cu")
	)
	(gr_line
		(start 364.259368 -240.903252)
		(end 364.26013 -240.902744)
		(stroke
			(width 0.05715)
			(type default)
		)
		(layer "In11.Cu")
	)
	(gr_line
		(start 364.259368 -239.28324)
		(end 364.26013 -239.282732)
		(stroke
			(width 0.05715)
			(type default)
		)
		(layer "In11.Cu")
	)
	(gr_line
		(start 364.259368 -236.043216)
		(end 364.26013 -236.042708)
		(stroke
			(width 0.05715)
			(type default)
		)
		(layer "In11.Cu")
	)
	(gr_line
		(start 364.259368 -234.423204)
		(end 364.26013 -234.422696)
		(stroke
			(width 0.05715)
			(type default)
		)
		(layer "In11.Cu")
	)
	(gr_line
		(start 364.259368 -232.803192)
		(end 364.26013 -232.802684)
		(stroke
			(width 0.05715)
			(type default)
		)
		(layer "In11.Cu")
	)
	(gr_line
		(start 364.26013 -244.142768)
		(end 364.266988 -244.138704)
		(stroke
			(width 0.05715)
			(type default)
		)
		(layer "In11.Cu")
	)
	(gr_line
		(start 364.26013 -240.902744)
		(end 364.266988 -240.89868)
		(stroke
			(width 0.05715)
			(type default)
		)
		(layer "In11.Cu")
	)
	(gr_line
		(start 364.26013 -239.282732)
		(end 364.266988 -239.278668)
		(stroke
			(width 0.05715)
			(type default)
		)
		(layer "In11.Cu")
	)
	(gr_line
		(start 364.26013 -236.042708)
		(end 364.266988 -236.038644)
		(stroke
			(width 0.05715)
			(type default)
		)
		(layer "In11.Cu")
	)
	(gr_line
		(start 364.26013 -234.422696)
		(end 364.266988 -234.418632)
		(stroke
			(width 0.05715)
			(type default)
		)
		(layer "In11.Cu")
	)
	(gr_line
		(start 364.26013 -232.802684)
		(end 364.266988 -232.79862)
		(stroke
			(width 0.05715)
			(type default)
		)
		(layer "In11.Cu")
	)
	(gr_arc
		(start 364.266988 -244.138704)
		(mid 364.270937 -244.135927)
		(end 364.274862 -244.133116)
		(stroke
			(width 0.05715)
			(type default)
		)
		(layer "In11.Cu")
	)
	(gr_arc
		(start 364.266988 -240.89868)
		(mid 364.270937 -240.895903)
		(end 364.274862 -240.893092)
		(stroke
			(width 0.05715)
			(type default)
		)
		(layer "In11.Cu")
	)
	(gr_arc
		(start 364.266988 -239.278668)
		(mid 364.270937 -239.275891)
		(end 364.274862 -239.27308)
		(stroke
			(width 0.05715)
			(type default)
		)
		(layer "In11.Cu")
	)
	(gr_arc
		(start 364.266988 -236.038644)
		(mid 364.270937 -236.035867)
		(end 364.274862 -236.033056)
		(stroke
			(width 0.05715)
			(type default)
		)
		(layer "In11.Cu")
	)
	(gr_arc
		(start 364.266988 -234.418632)
		(mid 364.270937 -234.415855)
		(end 364.274862 -234.413044)
		(stroke
			(width 0.05715)
			(type default)
		)
		(layer "In11.Cu")
	)
	(gr_arc
		(start 364.266988 -232.79862)
		(mid 364.270937 -232.795843)
		(end 364.274862 -232.793032)
		(stroke
			(width 0.05715)
			(type default)
		)
		(layer "In11.Cu")
	)
	(gr_arc
		(start 364.269528 -223.077024)
		(mid 364.274501 -223.073496)
		(end 364.279434 -223.069912)
		(stroke
			(width 0.05715)
			(type default)
		)
		(layer "In11.Cu")
	)
	(gr_arc
		(start 364.289848 -224.68078)
		(mid 364.292905 -224.678251)
		(end 364.295944 -224.6757)
		(stroke
			(width 0.05715)
			(type default)
		)
		(layer "In11.Cu")
	)
	(gr_arc
		(start 364.295944 -224.6757)
		(mid 364.298618 -224.67304)
		(end 364.301278 -224.670366)
		(stroke
			(width 0.05715)
			(type default)
		)
		(layer "In11.Cu")
	)
	(gr_line
		(start 364.34014 -296.372788)
		(end 364.38586 -296.418508)
		(stroke
			(width 0.05715)
			(type default)
		)
		(layer "In11.Cu")
	)
	(gr_line
		(start 364.34014 -295.955466)
		(end 364.34014 -295.955974)
		(stroke
			(width 0.05715)
			(type default)
		)
		(layer "In11.Cu")
	)
	(gr_arc
		(start 364.384844 -293.174928)
		(mid 364.388769 -293.177739)
		(end 364.392718 -293.180516)
		(stroke
			(width 0.05715)
			(type default)
		)
		(layer "In11.Cu")
	)
	(gr_arc
		(start 364.384844 -291.554916)
		(mid 364.388769 -291.557727)
		(end 364.392718 -291.560504)
		(stroke
			(width 0.05715)
			(type default)
		)
		(layer "In11.Cu")
	)
	(gr_arc
		(start 364.384844 -289.934904)
		(mid 364.388769 -289.937715)
		(end 364.392718 -289.940492)
		(stroke
			(width 0.05715)
			(type default)
		)
		(layer "In11.Cu")
	)
	(gr_arc
		(start 364.384844 -281.835098)
		(mid 364.388769 -281.837909)
		(end 364.392718 -281.840686)
		(stroke
			(width 0.05715)
			(type default)
		)
		(layer "In11.Cu")
	)
	(gr_line
		(start 364.38586 -296.418508)
		(end 364.38586 -296.446956)
		(stroke
			(width 0.05715)
			(type default)
		)
		(layer "In11.Cu")
	)
	(gr_line
		(start 364.392718 -293.180516)
		(end 364.399576 -293.18458)
		(stroke
			(width 0.05715)
			(type default)
		)
		(layer "In11.Cu")
	)
	(gr_line
		(start 364.392718 -291.560504)
		(end 364.399576 -291.564568)
		(stroke
			(width 0.05715)
			(type default)
		)
		(layer "In11.Cu")
	)
	(gr_line
		(start 364.392718 -289.940492)
		(end 364.399576 -289.944556)
		(stroke
			(width 0.05715)
			(type default)
		)
		(layer "In11.Cu")
	)
	(gr_line
		(start 364.392718 -281.840686)
		(end 364.399576 -281.84475)
		(stroke
			(width 0.05715)
			(type default)
		)
		(layer "In11.Cu")
	)
	(gr_arc
		(start 364.395258 -287.389824)
		(mid 364.390031 -287.393478)
		(end 364.384844 -287.39719)
		(stroke
			(width 0.05715)
			(type default)
		)
		(layer "In11.Cu")
	)
	(gr_line
		(start 364.399576 -293.18458)
		(end 364.400338 -293.185088)
		(stroke
			(width 0.05715)
			(type default)
		)
		(layer "In11.Cu")
	)
	(gr_line
		(start 364.399576 -291.564568)
		(end 364.400338 -291.565076)
		(stroke
			(width 0.05715)
			(type default)
		)
		(layer "In11.Cu")
	)
	(gr_line
		(start 364.399576 -289.944556)
		(end 364.400338 -289.945064)
		(stroke
			(width 0.05715)
			(type default)
		)
		(layer "In11.Cu")
	)
	(gr_line
		(start 364.399576 -281.84475)
		(end 364.400338 -281.845258)
		(stroke
			(width 0.05715)
			(type default)
		)
		(layer "In11.Cu")
	)
	(gr_line
		(start 364.400338 -293.185088)
		(end 364.4011 -293.185596)
		(stroke
			(width 0.05715)
			(type default)
		)
		(layer "In11.Cu")
	)
	(gr_line
		(start 364.400338 -291.565076)
		(end 364.4011 -291.565584)
		(stroke
			(width 0.05715)
			(type default)
		)
		(layer "In11.Cu")
	)
	(gr_line
		(start 364.400338 -289.945064)
		(end 364.4011 -289.945572)
		(stroke
			(width 0.05715)
			(type default)
		)
		(layer "In11.Cu")
	)
	(gr_line
		(start 364.400338 -281.845258)
		(end 364.4011 -281.845766)
		(stroke
			(width 0.05715)
			(type default)
		)
		(layer "In11.Cu")
	)
	(gr_line
		(start 364.403386 -287.384998)
		(end 364.395258 -287.389824)
		(stroke
			(width 0.05715)
			(type default)
		)
		(layer "In11.Cu")
	)
	(gr_line
		(start 364.411514 -287.380934)
		(end 364.403386 -287.384998)
		(stroke
			(width 0.05715)
			(type default)
		)
		(layer "In11.Cu")
	)
	(gr_line
		(start 364.41253 -282.520136)
		(end 364.411768 -282.52039)
		(stroke
			(width 0.05715)
			(type default)
		)
		(layer "In11.Cu")
	)
	(gr_line
		(start 364.414816 -247.724168)
		(end 364.712758 -247.724168)
		(stroke
			(width 0.05715)
			(type default)
		)
		(layer "In11.Cu")
	)
	(gr_line
		(start 364.414816 -246.104156)
		(end 364.712758 -246.104156)
		(stroke
			(width 0.05715)
			(type default)
		)
		(layer "In11.Cu")
	)
	(gr_line
		(start 364.414816 -244.484144)
		(end 364.712758 -244.484144)
		(stroke
			(width 0.05715)
			(type default)
		)
		(layer "In11.Cu")
	)
	(gr_arc
		(start 364.417864 -285.095442)
		(mid 364.41964 -285.096461)
		(end 364.42142 -285.097474)
		(stroke
			(width 0.05715)
			(type default)
		)
		(layer "In11.Cu")
	)
	(gr_line
		(start 364.423198 -380.68885)
		(end 364.559088 -380.82474)
		(stroke
			(width 0.07112)
			(type default)
		)
		(layer "In11.Cu")
	)
	(gr_line
		(start 364.423198 -380.26213)
		(end 364.423198 -380.68885)
		(stroke
			(width 0.07112)
			(type default)
		)
		(layer "In11.Cu")
	)
	(gr_line
		(start 364.423198 -379.56109)
		(end 364.559088 -379.69698)
		(stroke
			(width 0.07112)
			(type default)
		)
		(layer "In11.Cu")
	)
	(gr_line
		(start 364.423198 -379.13437)
		(end 364.423198 -379.56109)
		(stroke
			(width 0.07112)
			(type default)
		)
		(layer "In11.Cu")
	)
	(gr_line
		(start 364.428024 -283.481272)
		(end 364.428786 -283.48178)
		(stroke
			(width 0.05715)
			(type default)
		)
		(layer "In11.Cu")
	)
	(gr_line
		(start 364.428786 -294.82288)
		(end 364.442248 -294.836342)
		(stroke
			(width 0.05715)
			(type default)
		)
		(layer "In11.Cu")
	)
	(gr_line
		(start 364.428786 -283.48178)
		(end 364.429802 -283.482288)
		(stroke
			(width 0.05715)
			(type default)
		)
		(layer "In11.Cu")
	)
	(gr_line
		(start 364.429294 -293.85006)
		(end 364.428024 -293.850822)
		(stroke
			(width 0.05715)
			(type default)
		)
		(layer "In11.Cu")
	)
	(gr_line
		(start 364.429802 -283.482288)
		(end 364.430564 -283.482796)
		(stroke
			(width 0.05715)
			(type default)
		)
		(layer "In11.Cu")
	)
	(gr_line
		(start 364.430056 -284.129734)
		(end 364.428532 -284.13075)
		(stroke
			(width 0.05715)
			(type default)
		)
		(layer "In11.Cu")
	)
	(gr_line
		(start 364.430564 -283.482796)
		(end 364.432342 -283.483812)
		(stroke
			(width 0.05715)
			(type default)
		)
		(layer "In11.Cu")
	)
	(gr_line
		(start 364.430818 -293.849044)
		(end 364.429294 -293.85006)
		(stroke
			(width 0.05715)
			(type default)
		)
		(layer "In11.Cu")
	)
	(gr_line
		(start 364.431834 -293.84879)
		(end 364.431834 -293.848536)
		(stroke
			(width 0.05715)
			(type default)
		)
		(layer "In11.Cu")
	)
	(gr_line
		(start 364.431834 -293.848536)
		(end 364.430818 -293.849044)
		(stroke
			(width 0.05715)
			(type default)
		)
		(layer "In11.Cu")
	)
	(gr_line
		(start 364.431834 -292.228778)
		(end 364.431834 -292.228524)
		(stroke
			(width 0.05715)
			(type default)
		)
		(layer "In11.Cu")
	)
	(gr_line
		(start 364.431834 -292.228524)
		(end 364.430818 -292.229032)
		(stroke
			(width 0.05715)
			(type default)
		)
		(layer "In11.Cu")
	)
	(gr_line
		(start 364.431834 -290.608766)
		(end 364.431834 -290.608512)
		(stroke
			(width 0.05715)
			(type default)
		)
		(layer "In11.Cu")
	)
	(gr_line
		(start 364.431834 -290.608512)
		(end 364.430818 -290.60902)
		(stroke
			(width 0.05715)
			(type default)
		)
		(layer "In11.Cu")
	)
	(gr_line
		(start 364.431834 -288.9885)
		(end 364.430818 -288.989008)
		(stroke
			(width 0.05715)
			(type default)
		)
		(layer "In11.Cu")
	)
	(gr_line
		(start 364.431834 -288.34334)
		(end 364.43285 -288.343848)
		(stroke
			(width 0.05715)
			(type default)
		)
		(layer "In11.Cu")
	)
	(gr_line
		(start 364.431834 -286.723074)
		(end 364.432342 -286.723328)
		(stroke
			(width 0.05715)
			(type default)
		)
		(layer "In11.Cu")
	)
	(gr_line
		(start 364.431834 -285.74873)
		(end 364.430818 -285.749238)
		(stroke
			(width 0.05715)
			(type default)
		)
		(layer "In11.Cu")
	)
	(gr_line
		(start 364.431834 -282.508706)
		(end 364.428532 -282.510484)
		(stroke
			(width 0.05715)
			(type default)
		)
		(layer "In11.Cu")
	)
	(gr_line
		(start 364.432342 -293.848536)
		(end 364.431834 -293.84879)
		(stroke
			(width 0.05715)
			(type default)
		)
		(layer "In11.Cu")
	)
	(gr_line
		(start 364.432342 -292.228524)
		(end 364.431834 -292.228778)
		(stroke
			(width 0.05715)
			(type default)
		)
		(layer "In11.Cu")
	)
	(gr_line
		(start 364.432342 -290.608512)
		(end 364.431834 -290.608766)
		(stroke
			(width 0.05715)
			(type default)
		)
		(layer "In11.Cu")
	)
	(gr_line
		(start 364.432342 -283.483812)
		(end 364.433104 -283.48432)
		(stroke
			(width 0.05715)
			(type default)
		)
		(layer "In11.Cu")
	)
	(gr_line
		(start 364.432596 -282.508452)
		(end 364.432596 -282.508198)
		(stroke
			(width 0.05715)
			(type default)
		)
		(layer "In11.Cu")
	)
	(gr_line
		(start 364.433104 -288.987992)
		(end 364.431834 -288.9885)
		(stroke
			(width 0.05715)
			(type default)
		)
		(layer "In11.Cu")
	)
	(gr_line
		(start 364.43412 -284.127702)
		(end 364.430818 -284.129226)
		(stroke
			(width 0.05715)
			(type default)
		)
		(layer "In11.Cu")
	)
	(gr_line
		(start 364.434628 -281.865324)
		(end 364.435136 -281.865324)
		(stroke
			(width 0.05715)
			(type default)
		)
		(layer "In11.Cu")
	)
	(gr_line
		(start 364.43539 -282.506928)
		(end 364.434882 -282.506928)
		(stroke
			(width 0.05715)
			(type default)
		)
		(layer "In11.Cu")
	)
	(gr_line
		(start 364.442248 -294.836342)
		(end 364.449614 -294.836342)
		(stroke
			(width 0.05715)
			(type default)
		)
		(layer "In11.Cu")
	)
	(gr_line
		(start 364.445296 -284.121098)
		(end 364.444788 -284.121352)
		(stroke
			(width 0.05715)
			(type default)
		)
		(layer "In11.Cu")
	)
	(gr_line
		(start 364.446058 -284.12059)
		(end 364.445296 -284.121098)
		(stroke
			(width 0.05715)
			(type default)
		)
		(layer "In11.Cu")
	)
	(gr_line
		(start 364.44682 -284.120082)
		(end 364.446058 -284.12059)
		(stroke
			(width 0.05715)
			(type default)
		)
		(layer "In11.Cu")
	)
	(gr_line
		(start 364.44682 -280.880058)
		(end 364.444534 -280.881328)
		(stroke
			(width 0.05715)
			(type default)
		)
		(layer "In11.Cu")
	)
	(gr_line
		(start 364.44936 -284.118558)
		(end 364.448598 -284.119066)
		(stroke
			(width 0.05715)
			(type default)
		)
		(layer "In11.Cu")
	)
	(gr_line
		(start 364.450122 -284.11805)
		(end 364.44936 -284.118558)
		(stroke
			(width 0.05715)
			(type default)
		)
		(layer "In11.Cu")
	)
	(gr_line
		(start 364.450122 -283.494226)
		(end 364.450376 -283.494226)
		(stroke
			(width 0.05715)
			(type default)
		)
		(layer "In11.Cu")
	)
	(gr_line
		(start 364.45063 -284.11805)
		(end 364.450122 -284.11805)
		(stroke
			(width 0.05715)
			(type default)
		)
		(layer "In11.Cu")
	)
	(gr_line
		(start 364.509812 -224.235518)
		(end 364.509812 -224.234248)
		(stroke
			(width 0.05715)
			(type default)
		)
		(layer "In11.Cu")
	)
	(gr_line
		(start 364.510066 -224.234248)
		(end 364.509812 -224.234248)
		(stroke
			(width 0.05715)
			(type default)
		)
		(layer "In11.Cu")
	)
	(gr_arc
		(start 364.510066 -224.234248)
		(mid 364.509973 -224.227897)
		(end 364.509812 -224.221548)
		(stroke
			(width 0.05715)
			(type default)
		)
		(layer "In11.Cu")
	)
	(gr_line
		(start 364.511082 -287.54451)
		(end 364.508288 -287.546034)
		(stroke
			(width 0.05715)
			(type default)
		)
		(layer "In11.Cu")
	)
	(gr_line
		(start 364.52302 -294.656002)
		(end 364.522512 -294.655748)
		(stroke
			(width 0.05715)
			(type default)
		)
		(layer "In11.Cu")
	)
	(gr_line
		(start 364.52302 -294.656002)
		(end 364.52556 -294.657526)
		(stroke
			(width 0.05715)
			(type default)
		)
		(layer "In11.Cu")
	)
	(gr_line
		(start 364.52302 -288.1757)
		(end 364.527846 -288.178494)
		(stroke
			(width 0.05715)
			(type default)
		)
		(layer "In11.Cu")
	)
	(gr_line
		(start 364.52429 -283.31668)
		(end 364.525052 -283.317188)
		(stroke
			(width 0.05715)
			(type default)
		)
		(layer "In11.Cu")
	)
	(gr_line
		(start 364.524798 -284.936946)
		(end 364.527846 -284.938724)
		(stroke
			(width 0.05715)
			(type default)
		)
		(layer "In11.Cu")
	)
	(gr_line
		(start 364.52556 -294.657526)
		(end 364.525814 -294.657272)
		(stroke
			(width 0.05715)
			(type default)
		)
		(layer "In11.Cu")
	)
	(gr_line
		(start 364.525814 -294.657272)
		(end 364.527084 -294.658034)
		(stroke
			(width 0.05715)
			(type default)
		)
		(layer "In11.Cu")
	)
	(gr_line
		(start 364.526068 -294.014398)
		(end 364.52429 -294.015414)
		(stroke
			(width 0.05715)
			(type default)
		)
		(layer "In11.Cu")
	)
	(gr_line
		(start 364.52683 -286.55772)
		(end 364.527846 -286.558482)
		(stroke
			(width 0.05715)
			(type default)
		)
		(layer "In11.Cu")
	)
	(gr_line
		(start 364.527084 -294.658034)
		(end 364.527846 -294.658542)
		(stroke
			(width 0.05715)
			(type default)
		)
		(layer "In11.Cu")
	)
	(gr_line
		(start 364.527084 -292.393878)
		(end 364.525814 -292.39464)
		(stroke
			(width 0.05715)
			(type default)
		)
		(layer "In11.Cu")
	)
	(gr_line
		(start 364.527084 -290.773866)
		(end 364.525814 -290.774628)
		(stroke
			(width 0.05715)
			(type default)
		)
		(layer "In11.Cu")
	)
	(gr_line
		(start 364.527084 -289.153854)
		(end 364.525814 -289.154616)
		(stroke
			(width 0.05715)
			(type default)
		)
		(layer "In11.Cu")
	)
	(gr_line
		(start 364.527084 -285.914084)
		(end 364.525814 -285.914846)
		(stroke
			(width 0.05715)
			(type default)
		)
		(layer "In11.Cu")
	)
	(gr_line
		(start 364.527592 -285.91383)
		(end 364.527084 -285.914084)
		(stroke
			(width 0.05715)
			(type default)
		)
		(layer "In11.Cu")
	)
	(gr_line
		(start 364.527592 -282.673806)
		(end 364.524036 -282.675584)
		(stroke
			(width 0.05715)
			(type default)
		)
		(layer "In11.Cu")
	)
	(gr_line
		(start 364.527846 -294.658542)
		(end 364.555786 -294.676576)
		(stroke
			(width 0.05715)
			(type default)
		)
		(layer "In11.Cu")
	)
	(gr_line
		(start 364.527846 -294.013382)
		(end 364.527084 -294.01389)
		(stroke
			(width 0.05715)
			(type default)
		)
		(layer "In11.Cu")
	)
	(gr_line
		(start 364.527846 -292.39337)
		(end 364.527084 -292.393878)
		(stroke
			(width 0.05715)
			(type default)
		)
		(layer "In11.Cu")
	)
	(gr_line
		(start 364.527846 -290.773358)
		(end 364.527084 -290.773866)
		(stroke
			(width 0.05715)
			(type default)
		)
		(layer "In11.Cu")
	)
	(gr_line
		(start 364.527846 -288.178494)
		(end 364.528608 -288.179002)
		(stroke
			(width 0.05715)
			(type default)
		)
		(layer "In11.Cu")
	)
	(gr_line
		(start 364.527846 -286.558482)
		(end 364.528354 -286.558736)
		(stroke
			(width 0.05715)
			(type default)
		)
		(layer "In11.Cu")
	)
	(gr_line
		(start 364.527846 -284.293564)
		(end 364.524544 -284.295342)
		(stroke
			(width 0.05715)
			(type default)
		)
		(layer "In11.Cu")
	)
	(gr_line
		(start 364.527846 -282.673552)
		(end 364.527592 -282.673806)
		(stroke
			(width 0.05715)
			(type default)
		)
		(layer "In11.Cu")
	)
	(gr_line
		(start 364.527846 -281.6987)
		(end 364.530894 -281.700478)
		(stroke
			(width 0.05715)
			(type default)
		)
		(layer "In11.Cu")
	)
	(gr_line
		(start 364.528608 -289.152838)
		(end 364.527084 -289.153854)
		(stroke
			(width 0.05715)
			(type default)
		)
		(layer "In11.Cu")
	)
	(gr_line
		(start 364.530132 -284.292294)
		(end 364.527846 -284.293564)
		(stroke
			(width 0.05715)
			(type default)
		)
		(layer "In11.Cu")
	)
	(gr_line
		(start 364.53064 -390.750298)
		(end 364.53064 -390.75106)
		(stroke
			(width 0.07112)
			(type default)
		)
		(layer "In11.Cu")
	)
	(gr_line
		(start 364.530894 -282.671774)
		(end 364.527846 -282.673552)
		(stroke
			(width 0.05715)
			(type default)
		)
		(layer "In11.Cu")
	)
	(gr_line
		(start 364.542832 -281.044904)
		(end 364.542832 -281.045158)
		(stroke
			(width 0.05715)
			(type default)
		)
		(layer "In11.Cu")
	)
	(gr_line
		(start 364.54334 -284.284674)
		(end 364.541562 -284.28569)
		(stroke
			(width 0.05715)
			(type default)
		)
		(layer "In11.Cu")
	)
	(gr_line
		(start 364.543594 -283.327856)
		(end 364.545372 -283.328872)
		(stroke
			(width 0.05715)
			(type default)
		)
		(layer "In11.Cu")
	)
	(gr_line
		(start 364.544102 -284.284166)
		(end 364.54334 -284.284674)
		(stroke
			(width 0.05715)
			(type default)
		)
		(layer "In11.Cu")
	)
	(gr_line
		(start 364.545372 -283.328872)
		(end 364.546134 -283.32938)
		(stroke
			(width 0.05715)
			(type default)
		)
		(layer "In11.Cu")
	)
	(gr_line
		(start 364.546134 -284.282896)
		(end 364.544102 -284.284166)
		(stroke
			(width 0.05715)
			(type default)
		)
		(layer "In11.Cu")
	)
	(gr_line
		(start 364.555278 -287.240726)
		(end 364.555278 -287.24098)
		(stroke
			(width 0.05715)
			(type default)
		)
		(layer "In11.Cu")
	)
	(gr_line
		(start 364.559088 -380.12624)
		(end 364.423198 -380.26213)
		(stroke
			(width 0.07112)
			(type default)
		)
		(layer "In11.Cu")
	)
	(gr_line
		(start 364.559088 -378.99848)
		(end 364.423198 -379.13437)
		(stroke
			(width 0.07112)
			(type default)
		)
		(layer "In11.Cu")
	)
	(gr_arc
		(start 364.562644 -225.389694)
		(mid 364.558695 -225.392471)
		(end 364.55477 -225.395282)
		(stroke
			(width 0.05715)
			(type default)
		)
		(layer "In11.Cu")
	)
	(gr_line
		(start 364.562644 -225.389694)
		(end 364.569502 -225.38563)
		(stroke
			(width 0.05715)
			(type default)
		)
		(layer "In11.Cu")
	)
	(gr_line
		(start 364.569502 -225.38563)
		(end 364.570264 -225.385122)
		(stroke
			(width 0.05715)
			(type default)
		)
		(layer "In11.Cu")
	)
	(gr_line
		(start 364.570264 -225.385122)
		(end 364.571026 -225.384614)
		(stroke
			(width 0.05715)
			(type default)
		)
		(layer "In11.Cu")
	)
	(gr_line
		(start 364.591854 -287.163764)
		(end 364.591854 -287.164272)
		(stroke
			(width 0.05715)
			(type default)
		)
		(layer "In11.Cu")
	)
	(gr_line
		(start 364.602014 -225.36658)
		(end 364.602522 -225.366326)
		(stroke
			(width 0.05715)
			(type default)
		)
		(layer "In11.Cu")
	)
	(gr_line
		(start 364.602522 -225.366326)
		(end 364.603792 -225.365564)
		(stroke
			(width 0.05715)
			(type default)
		)
		(layer "In11.Cu")
	)
	(gr_line
		(start 364.61573 -287.049464)
		(end 364.61573 -287.049718)
		(stroke
			(width 0.05715)
			(type default)
		)
		(layer "In11.Cu")
	)
	(gr_line
		(start 364.697772 -225.53168)
		(end 364.698788 -225.531172)
		(stroke
			(width 0.05715)
			(type default)
		)
		(layer "In11.Cu")
	)
	(gr_line
		(start 364.712758 -247.724168)
		(end 364.7821 -247.654826)
		(stroke
			(width 0.05715)
			(type default)
		)
		(layer "In11.Cu")
	)
	(gr_line
		(start 364.712758 -246.104156)
		(end 364.795562 -246.021352)
		(stroke
			(width 0.05715)
			(type default)
		)
		(layer "In11.Cu")
	)
	(gr_line
		(start 364.712758 -244.484144)
		(end 364.795562 -244.40134)
		(stroke
			(width 0.05715)
			(type default)
		)
		(layer "In11.Cu")
	)
	(gr_line
		(start 364.71479 -279.756108)
		(end 365.012732 -279.756108)
		(stroke
			(width 0.05715)
			(type default)
		)
		(layer "In11.Cu")
	)
	(gr_line
		(start 364.71479 -278.136096)
		(end 365.012732 -278.136096)
		(stroke
			(width 0.05715)
			(type default)
		)
		(layer "In11.Cu")
	)
	(gr_line
		(start 364.71479 -276.516084)
		(end 365.012732 -276.516084)
		(stroke
			(width 0.05715)
			(type default)
		)
		(layer "In11.Cu")
	)
	(gr_line
		(start 364.71479 -274.896072)
		(end 365.012732 -274.896072)
		(stroke
			(width 0.05715)
			(type default)
		)
		(layer "In11.Cu")
	)
	(gr_line
		(start 364.75797 -221.083124)
		(end 364.75797 -221.054676)
		(stroke
			(width 0.05715)
			(type default)
		)
		(layer "In11.Cu")
	)
	(gr_line
		(start 364.778544 -287.202626)
		(end 364.77829 -287.203388)
		(stroke
			(width 0.05715)
			(type default)
		)
		(layer "In11.Cu")
	)
	(gr_arc
		(start 364.799372 -245.998492)
		(mid 364.797351 -246.009903)
		(end 364.795562 -246.021352)
		(stroke
			(width 0.05715)
			(type default)
		)
		(layer "In11.Cu")
	)
	(gr_arc
		(start 364.799372 -244.37848)
		(mid 364.79735 -244.389891)
		(end 364.795562 -244.40134)
		(stroke
			(width 0.05715)
			(type default)
		)
		(layer "In11.Cu")
	)
	(gr_line
		(start 364.80369 -221.128844)
		(end 364.75797 -221.083124)
		(stroke
			(width 0.05715)
			(type default)
		)
		(layer "In11.Cu")
	)
	(gr_line
		(start 364.808008 -286.995616)
		(end 364.808008 -286.996124)
		(stroke
			(width 0.05715)
			(type default)
		)
		(layer "In11.Cu")
	)
	(gr_line
		(start 364.82147 -384.92303)
		(end 364.53064 -385.21386)
		(stroke
			(width 0.07112)
			(type default)
		)
		(layer "In11.Cu")
	)
	(gr_line
		(start 364.82147 -384.64109)
		(end 364.53064 -384.35026)
		(stroke
			(width 0.07112)
			(type default)
		)
		(layer "In11.Cu")
	)
	(gr_line
		(start 364.842298 -380.12497)
		(end 364.842298 -380.82601)
		(stroke
			(width 0.07112)
			(type default)
		)
		(layer "In11.Cu")
	)
	(gr_line
		(start 364.842298 -378.99721)
		(end 364.842298 -379.69825)
		(stroke
			(width 0.07112)
			(type default)
		)
		(layer "In11.Cu")
	)
	(gr_arc
		(start 364.974124 -247.641364)
		(mid 364.972338 -247.629914)
		(end 364.970314 -247.618504)
		(stroke
			(width 0.05715)
			(type default)
		)
		(layer "In11.Cu")
	)
	(gr_line
		(start 364.979966 -221.803976)
		(end 364.98022 -221.80423)
		(stroke
			(width 0.05715)
			(type default)
		)
		(layer "In11.Cu")
	)
	(gr_line
		(start 364.98276 -295.459912)
		(end 364.986316 -295.461944)
		(stroke
			(width 0.05715)
			(type default)
		)
		(layer "In11.Cu")
	)
	(gr_line
		(start 364.99419 -221.128844)
		(end 365.03991 -221.083124)
		(stroke
			(width 0.05715)
			(type default)
		)
		(layer "In11.Cu")
	)
	(gr_line
		(start 364.995206 -275.384768)
		(end 364.99419 -275.38553)
		(stroke
			(width 0.05715)
			(type default)
		)
		(layer "In11.Cu")
	)
	(gr_line
		(start 365.012732 -279.756108)
		(end 365.082074 -279.82545)
		(stroke
			(width 0.05715)
			(type default)
		)
		(layer "In11.Cu")
	)
	(gr_line
		(start 365.012732 -278.136096)
		(end 365.095536 -278.2189)
		(stroke
			(width 0.05715)
			(type default)
		)
		(layer "In11.Cu")
	)
	(gr_line
		(start 365.012732 -276.516084)
		(end 365.095536 -276.598888)
		(stroke
			(width 0.05715)
			(type default)
		)
		(layer "In11.Cu")
	)
	(gr_line
		(start 365.012732 -274.896072)
		(end 365.082074 -274.965414)
		(stroke
			(width 0.05715)
			(type default)
		)
		(layer "In11.Cu")
	)
	(gr_arc
		(start 365.024924 -227.123244)
		(mid 365.028849 -227.126055)
		(end 365.032798 -227.128832)
		(stroke
			(width 0.05715)
			(type default)
		)
		(layer "In11.Cu")
	)
	(gr_arc
		(start 365.02848 -229.442518)
		(mid 365.025298 -229.444794)
		(end 365.02213 -229.44709)
		(stroke
			(width 0.05715)
			(type default)
		)
		(layer "In11.Cu")
	)
	(gr_arc
		(start 365.032798 -245.63959)
		(mid 365.028721 -245.642366)
		(end 365.02467 -245.645178)
		(stroke
			(width 0.05715)
			(type default)
		)
		(layer "In11.Cu")
	)
	(gr_arc
		(start 365.032798 -245.63959)
		(mid 365.033179 -245.639336)
		(end 365.03356 -245.639082)
		(stroke
			(width 0.05715)
			(type default)
		)
		(layer "In11.Cu")
	)
	(gr_arc
		(start 365.032798 -242.399566)
		(mid 365.028849 -242.402343)
		(end 365.024924 -242.405154)
		(stroke
			(width 0.05715)
			(type default)
		)
		(layer "In11.Cu")
	)
	(gr_arc
		(start 365.032798 -242.399566)
		(mid 365.033179 -242.399312)
		(end 365.03356 -242.399058)
		(stroke
			(width 0.05715)
			(type default)
		)
		(layer "In11.Cu")
	)
	(gr_arc
		(start 365.032798 -240.779554)
		(mid 365.028849 -240.782331)
		(end 365.024924 -240.785142)
		(stroke
			(width 0.05715)
			(type default)
		)
		(layer "In11.Cu")
	)
	(gr_arc
		(start 365.032798 -240.779554)
		(mid 365.033179 -240.7793)
		(end 365.03356 -240.779046)
		(stroke
			(width 0.05715)
			(type default)
		)
		(layer "In11.Cu")
	)
	(gr_arc
		(start 365.032798 -239.159542)
		(mid 365.028849 -239.162319)
		(end 365.024924 -239.16513)
		(stroke
			(width 0.05715)
			(type default)
		)
		(layer "In11.Cu")
	)
	(gr_arc
		(start 365.032798 -239.159542)
		(mid 365.033179 -239.159288)
		(end 365.03356 -239.159034)
		(stroke
			(width 0.05715)
			(type default)
		)
		(layer "In11.Cu")
	)
	(gr_arc
		(start 365.032798 -237.53953)
		(mid 365.028849 -237.542307)
		(end 365.024924 -237.545118)
		(stroke
			(width 0.05715)
			(type default)
		)
		(layer "In11.Cu")
	)
	(gr_arc
		(start 365.032798 -237.53953)
		(mid 365.033179 -237.539276)
		(end 365.03356 -237.539022)
		(stroke
			(width 0.05715)
			(type default)
		)
		(layer "In11.Cu")
	)
	(gr_arc
		(start 365.032798 -235.919518)
		(mid 365.028849 -235.922295)
		(end 365.024924 -235.925106)
		(stroke
			(width 0.05715)
			(type default)
		)
		(layer "In11.Cu")
	)
	(gr_arc
		(start 365.032798 -235.919518)
		(mid 365.033179 -235.919264)
		(end 365.03356 -235.91901)
		(stroke
			(width 0.05715)
			(type default)
		)
		(layer "In11.Cu")
	)
	(gr_arc
		(start 365.032798 -234.299506)
		(mid 365.028849 -234.302283)
		(end 365.024924 -234.305094)
		(stroke
			(width 0.05715)
			(type default)
		)
		(layer "In11.Cu")
	)
	(gr_arc
		(start 365.032798 -234.299506)
		(mid 365.033179 -234.299252)
		(end 365.03356 -234.298998)
		(stroke
			(width 0.05715)
			(type default)
		)
		(layer "In11.Cu")
	)
	(gr_line
		(start 365.03356 -245.639082)
		(end 365.04118 -245.634764)
		(stroke
			(width 0.05715)
			(type default)
		)
		(layer "In11.Cu")
	)
	(gr_line
		(start 365.03356 -242.399058)
		(end 365.041434 -242.394486)
		(stroke
			(width 0.05715)
			(type default)
		)
		(layer "In11.Cu")
	)
	(gr_line
		(start 365.03356 -240.779046)
		(end 365.041434 -240.774474)
		(stroke
			(width 0.05715)
			(type default)
		)
		(layer "In11.Cu")
	)
	(gr_line
		(start 365.03356 -239.159034)
		(end 365.041434 -239.154462)
		(stroke
			(width 0.05715)
			(type default)
		)
		(layer "In11.Cu")
	)
	(gr_line
		(start 365.03356 -237.539022)
		(end 365.041434 -237.53445)
		(stroke
			(width 0.05715)
			(type default)
		)
		(layer "In11.Cu")
	)
	(gr_line
		(start 365.03356 -235.91901)
		(end 365.03991 -235.9152)
		(stroke
			(width 0.05715)
			(type default)
		)
		(layer "In11.Cu")
	)
	(gr_line
		(start 365.03356 -234.298998)
		(end 365.036354 -234.296966)
		(stroke
			(width 0.05715)
			(type default)
		)
		(layer "In11.Cu")
	)
	(gr_line
		(start 365.035592 -227.130864)
		(end 365.032798 -227.128832)
		(stroke
			(width 0.05715)
			(type default)
		)
		(layer "In11.Cu")
	)
	(gr_line
		(start 365.036354 -234.296966)
		(end 365.040926 -234.294426)
		(stroke
			(width 0.05715)
			(type default)
		)
		(layer "In11.Cu")
	)
	(gr_line
		(start 365.03991 -235.9152)
		(end 365.040672 -235.914692)
		(stroke
			(width 0.05715)
			(type default)
		)
		(layer "In11.Cu")
	)
	(gr_line
		(start 365.03991 -221.083124)
		(end 365.03991 -221.054676)
		(stroke
			(width 0.05715)
			(type default)
		)
		(layer "In11.Cu")
	)
	(gr_line
		(start 365.040672 -235.914692)
		(end 365.041688 -235.914184)
		(stroke
			(width 0.05715)
			(type default)
		)
		(layer "In11.Cu")
	)
	(gr_line
		(start 365.040926 -227.133912)
		(end 365.035592 -227.130864)
		(stroke
			(width 0.05715)
			(type default)
		)
		(layer "In11.Cu")
	)
	(gr_line
		(start 365.04245 -241.714528)
		(end 365.040926 -241.713512)
		(stroke
			(width 0.05715)
			(type default)
		)
		(layer "In11.Cu")
	)
	(gr_line
		(start 365.04245 -240.094516)
		(end 365.040926 -240.0935)
		(stroke
			(width 0.05715)
			(type default)
		)
		(layer "In11.Cu")
	)
	(gr_line
		(start 365.04245 -238.474504)
		(end 365.040926 -238.473488)
		(stroke
			(width 0.05715)
			(type default)
		)
		(layer "In11.Cu")
	)
	(gr_line
		(start 365.04245 -236.854492)
		(end 365.040926 -236.853476)
		(stroke
			(width 0.05715)
			(type default)
		)
		(layer "In11.Cu")
	)
	(gr_line
		(start 365.04245 -235.23448)
		(end 365.040926 -235.233464)
		(stroke
			(width 0.05715)
			(type default)
		)
		(layer "In11.Cu")
	)
	(gr_line
		(start 365.043974 -296.418508)
		(end 365.043974 -296.446956)
		(stroke
			(width 0.05715)
			(type default)
		)
		(layer "In11.Cu")
	)
	(gr_line
		(start 365.050832 -241.719354)
		(end 365.051086 -241.719354)
		(stroke
			(width 0.05715)
			(type default)
		)
		(layer "In11.Cu")
	)
	(gr_line
		(start 365.050832 -240.099342)
		(end 365.051086 -240.099342)
		(stroke
			(width 0.05715)
			(type default)
		)
		(layer "In11.Cu")
	)
	(gr_line
		(start 365.050832 -238.47933)
		(end 365.051086 -238.47933)
		(stroke
			(width 0.05715)
			(type default)
		)
		(layer "In11.Cu")
	)
	(gr_line
		(start 365.050832 -236.859318)
		(end 365.051086 -236.859318)
		(stroke
			(width 0.05715)
			(type default)
		)
		(layer "In11.Cu")
	)
	(gr_line
		(start 365.050832 -235.239306)
		(end 365.051086 -235.239306)
		(stroke
			(width 0.05715)
			(type default)
		)
		(layer "In11.Cu")
	)
	(gr_line
		(start 365.056928 -247.724168)
		(end 364.974124 -247.641364)
		(stroke
			(width 0.05715)
			(type default)
		)
		(layer "In11.Cu")
	)
	(gr_line
		(start 365.056928 -246.104156)
		(end 364.987586 -246.034814)
		(stroke
			(width 0.05715)
			(type default)
		)
		(layer "In11.Cu")
	)
	(gr_line
		(start 365.056928 -244.484144)
		(end 364.987586 -244.414802)
		(stroke
			(width 0.05715)
			(type default)
		)
		(layer "In11.Cu")
	)
	(gr_line
		(start 365.065564 -242.380262)
		(end 365.06658 -242.379754)
		(stroke
			(width 0.05715)
			(type default)
		)
		(layer "In11.Cu")
	)
	(gr_line
		(start 365.065564 -240.76025)
		(end 365.06658 -240.759742)
		(stroke
			(width 0.05715)
			(type default)
		)
		(layer "In11.Cu")
	)
	(gr_line
		(start 365.065564 -239.140238)
		(end 365.06658 -239.13973)
		(stroke
			(width 0.05715)
			(type default)
		)
		(layer "In11.Cu")
	)
	(gr_line
		(start 365.065564 -237.520226)
		(end 365.06658 -237.519718)
		(stroke
			(width 0.05715)
			(type default)
		)
		(layer "In11.Cu")
	)
	(gr_line
		(start 365.06658 -242.379754)
		(end 365.067342 -242.379246)
		(stroke
			(width 0.05715)
			(type default)
		)
		(layer "In11.Cu")
	)
	(gr_line
		(start 365.06658 -240.759742)
		(end 365.067342 -240.759234)
		(stroke
			(width 0.05715)
			(type default)
		)
		(layer "In11.Cu")
	)
	(gr_line
		(start 365.06658 -239.13973)
		(end 365.067342 -239.139222)
		(stroke
			(width 0.05715)
			(type default)
		)
		(layer "In11.Cu")
	)
	(gr_line
		(start 365.06658 -237.519718)
		(end 365.067342 -237.51921)
		(stroke
			(width 0.05715)
			(type default)
		)
		(layer "In11.Cu")
	)
	(gr_line
		(start 365.067342 -242.379246)
		(end 365.072422 -242.376452)
		(stroke
			(width 0.05715)
			(type default)
		)
		(layer "In11.Cu")
	)
	(gr_line
		(start 365.067342 -240.759234)
		(end 365.072422 -240.75644)
		(stroke
			(width 0.05715)
			(type default)
		)
		(layer "In11.Cu")
	)
	(gr_line
		(start 365.067342 -239.139222)
		(end 365.072422 -239.136428)
		(stroke
			(width 0.05715)
			(type default)
		)
		(layer "In11.Cu")
	)
	(gr_line
		(start 365.067342 -237.51921)
		(end 365.072422 -237.516416)
		(stroke
			(width 0.05715)
			(type default)
		)
		(layer "In11.Cu")
	)
	(gr_line
		(start 365.067342 -235.899198)
		(end 365.068866 -235.898436)
		(stroke
			(width 0.05715)
			(type default)
		)
		(layer "In11.Cu")
	)
	(gr_line
		(start 365.068866 -235.898436)
		(end 365.072422 -235.896404)
		(stroke
			(width 0.05715)
			(type default)
		)
		(layer "In11.Cu")
	)
	(gr_line
		(start 365.069374 -222.290132)
		(end 365.066072 -222.2881)
		(stroke
			(width 0.05715)
			(type default)
		)
		(layer "In11.Cu")
	)
	(gr_line
		(start 365.070898 -222.291148)
		(end 365.069374 -222.290132)
		(stroke
			(width 0.05715)
			(type default)
		)
		(layer "In11.Cu")
	)
	(gr_line
		(start 365.071914 -228.771704)
		(end 365.070898 -228.771196)
		(stroke
			(width 0.05715)
			(type default)
		)
		(layer "In11.Cu")
	)
	(gr_line
		(start 365.071914 -222.291656)
		(end 365.070898 -222.291148)
		(stroke
			(width 0.05715)
			(type default)
		)
		(layer "In11.Cu")
	)
	(gr_line
		(start 365.072422 -222.29191)
		(end 365.071914 -222.291656)
		(stroke
			(width 0.05715)
			(type default)
		)
		(layer "In11.Cu")
	)
	(gr_line
		(start 365.072676 -228.772212)
		(end 365.071914 -228.771704)
		(stroke
			(width 0.05715)
			(type default)
		)
		(layer "In11.Cu")
	)
	(gr_line
		(start 365.073184 -228.772466)
		(end 365.072676 -228.772212)
		(stroke
			(width 0.05715)
			(type default)
		)
		(layer "In11.Cu")
	)
	(gr_line
		(start 365.073946 -230.392986)
		(end 365.072676 -230.392224)
		(stroke
			(width 0.05715)
			(type default)
		)
		(layer "In11.Cu")
	)
	(gr_line
		(start 365.07547 -230.393748)
		(end 365.073946 -230.392986)
		(stroke
			(width 0.05715)
			(type default)
		)
		(layer "In11.Cu")
	)
	(gr_line
		(start 365.089694 -296.372788)
		(end 365.043974 -296.418508)
		(stroke
			(width 0.05715)
			(type default)
		)
		(layer "In11.Cu")
	)
	(gr_arc
		(start 365.095536 -278.2189)
		(mid 365.097329 -278.230222)
		(end 365.099346 -278.241506)
		(stroke
			(width 0.05715)
			(type default)
		)
		(layer "In11.Cu")
	)
	(gr_line
		(start 365.095536 -276.598888)
		(end 365.09579 -276.598888)
		(stroke
			(width 0.05715)
			(type default)
		)
		(layer "In11.Cu")
	)
	(gr_arc
		(start 365.09579 -276.598888)
		(mid 365.097583 -276.610083)
		(end 365.0996 -276.62124)
		(stroke
			(width 0.05715)
			(type default)
		)
		(layer "In11.Cu")
	)
	(gr_line
		(start 365.162084 -236.06506)
		(end 365.163608 -236.064044)
		(stroke
			(width 0.05715)
			(type default)
		)
		(layer "In11.Cu")
	)
	(gr_line
		(start 365.163608 -236.064044)
		(end 365.16437 -236.063536)
		(stroke
			(width 0.05715)
			(type default)
		)
		(layer "In11.Cu")
	)
	(gr_line
		(start 365.166656 -234.442254)
		(end 365.167164 -234.442)
		(stroke
			(width 0.05715)
			(type default)
		)
		(layer "In11.Cu")
	)
	(gr_line
		(start 365.167164 -228.60635)
		(end 365.165894 -228.605588)
		(stroke
			(width 0.05715)
			(type default)
		)
		(layer "In11.Cu")
	)
	(gr_line
		(start 365.167164 -222.126302)
		(end 365.165386 -222.125286)
		(stroke
			(width 0.05715)
			(type default)
		)
		(layer "In11.Cu")
	)
	(gr_line
		(start 365.167418 -232.821734)
		(end 365.167926 -232.82148)
		(stroke
			(width 0.05715)
			(type default)
		)
		(layer "In11.Cu")
	)
	(gr_line
		(start 365.167926 -241.5667)
		(end 365.16818 -241.566954)
		(stroke
			(width 0.05715)
			(type default)
		)
		(layer "In11.Cu")
	)
	(gr_line
		(start 365.167926 -239.946688)
		(end 365.16818 -239.946942)
		(stroke
			(width 0.05715)
			(type default)
		)
		(layer "In11.Cu")
	)
	(gr_line
		(start 365.167926 -238.326676)
		(end 365.16818 -238.32693)
		(stroke
			(width 0.05715)
			(type default)
		)
		(layer "In11.Cu")
	)
	(gr_line
		(start 365.167926 -236.706664)
		(end 365.16818 -236.706918)
		(stroke
			(width 0.05715)
			(type default)
		)
		(layer "In11.Cu")
	)
	(gr_line
		(start 365.167926 -235.086652)
		(end 365.16818 -235.086906)
		(stroke
			(width 0.05715)
			(type default)
		)
		(layer "In11.Cu")
	)
	(gr_line
		(start 365.167926 -230.226616)
		(end 365.167418 -230.226362)
		(stroke
			(width 0.05715)
			(type default)
		)
		(layer "In11.Cu")
	)
	(gr_line
		(start 365.167926 -228.606858)
		(end 365.167164 -228.60635)
		(stroke
			(width 0.05715)
			(type default)
		)
		(layer "In11.Cu")
	)
	(gr_line
		(start 365.16818 -242.541552)
		(end 365.167926 -242.541552)
		(stroke
			(width 0.05715)
			(type default)
		)
		(layer "In11.Cu")
	)
	(gr_line
		(start 365.16818 -240.92154)
		(end 365.167926 -240.92154)
		(stroke
			(width 0.05715)
			(type default)
		)
		(layer "In11.Cu")
	)
	(gr_line
		(start 365.16818 -239.301528)
		(end 365.167926 -239.301528)
		(stroke
			(width 0.05715)
			(type default)
		)
		(layer "In11.Cu")
	)
	(gr_line
		(start 365.16818 -237.681516)
		(end 365.167926 -237.681516)
		(stroke
			(width 0.05715)
			(type default)
		)
		(layer "In11.Cu")
	)
	(gr_line
		(start 365.16818 -236.061504)
		(end 365.167926 -236.061504)
		(stroke
			(width 0.05715)
			(type default)
		)
		(layer "In11.Cu")
	)
	(gr_line
		(start 365.168942 -230.227124)
		(end 365.167926 -230.226616)
		(stroke
			(width 0.05715)
			(type default)
		)
		(layer "In11.Cu")
	)
	(gr_line
		(start 365.170466 -230.22814)
		(end 365.168942 -230.227124)
		(stroke
			(width 0.05715)
			(type default)
		)
		(layer "In11.Cu")
	)
	(gr_arc
		(start 365.17453 -242.537742)
		(mid 365.176947 -242.536351)
		(end 365.179356 -242.534948)
		(stroke
			(width 0.05715)
			(type default)
		)
		(layer "In11.Cu")
	)
	(gr_arc
		(start 365.17453 -240.91773)
		(mid 365.176947 -240.916339)
		(end 365.179356 -240.914936)
		(stroke
			(width 0.05715)
			(type default)
		)
		(layer "In11.Cu")
	)
	(gr_arc
		(start 365.17453 -239.297718)
		(mid 365.176947 -239.296327)
		(end 365.179356 -239.294924)
		(stroke
			(width 0.05715)
			(type default)
		)
		(layer "In11.Cu")
	)
	(gr_arc
		(start 365.17453 -237.677706)
		(mid 365.176947 -237.676315)
		(end 365.179356 -237.674912)
		(stroke
			(width 0.05715)
			(type default)
		)
		(layer "In11.Cu")
	)
	(gr_arc
		(start 365.1758 -236.057186)
		(mid 365.17758 -236.056046)
		(end 365.179356 -236.0549)
		(stroke
			(width 0.05715)
			(type default)
		)
		(layer "In11.Cu")
	)
	(gr_line
		(start 365.198152 -226.32416)
		(end 365.202724 -226.32162)
		(stroke
			(width 0.05715)
			(type default)
		)
		(layer "In11.Cu")
	)
	(gr_line
		(start 365.19993 -230.245158)
		(end 365.198914 -230.24465)
		(stroke
			(width 0.05715)
			(type default)
		)
		(layer "In11.Cu")
	)
	(gr_line
		(start 365.201454 -230.246174)
		(end 365.19993 -230.245158)
		(stroke
			(width 0.05715)
			(type default)
		)
		(layer "In11.Cu")
	)
	(gr_line
		(start 365.201708 -229.561898)
		(end 365.204248 -229.560628)
		(stroke
			(width 0.05715)
			(type default)
		)
		(layer "In11.Cu")
	)
	(gr_line
		(start 365.202724 -226.32162)
		(end 365.204248 -226.320604)
		(stroke
			(width 0.05715)
			(type default)
		)
		(layer "In11.Cu")
	)
	(gr_arc
		(start 365.204248 -229.560628)
		(mid 365.210886 -229.555976)
		(end 365.217456 -229.55123)
		(stroke
			(width 0.05715)
			(type default)
		)
		(layer "In11.Cu")
	)
	(gr_arc
		(start 365.204248 -226.320604)
		(mid 365.208835 -226.317451)
		(end 365.213392 -226.314254)
		(stroke
			(width 0.05715)
			(type default)
		)
		(layer "In11.Cu")
	)
	(gr_arc
		(start 365.218218 -230.257604)
		(mid 365.209888 -230.251813)
		(end 365.201454 -230.246174)
		(stroke
			(width 0.05715)
			(type default)
		)
		(layer "In11.Cu")
	)
	(gr_line
		(start 365.25962 -222.614236)
		(end 365.259366 -222.614236)
		(stroke
			(width 0.05715)
			(type default)
		)
		(layer "In11.Cu")
	)
	(gr_line
		(start 365.267494 -225.79076)
		(end 365.267748 -225.789744)
		(stroke
			(width 0.05715)
			(type default)
		)
		(layer "In11.Cu")
	)
	(gr_arc
		(start 365.270288 -279.861772)
		(mid 365.272311 -279.850362)
		(end 365.274098 -279.838912)
		(stroke
			(width 0.05715)
			(type default)
		)
		(layer "In11.Cu")
	)
	(gr_arc
		(start 365.270288 -275.001736)
		(mid 365.27231 -274.990326)
		(end 365.274098 -274.978876)
		(stroke
			(width 0.05715)
			(type default)
		)
		(layer "In11.Cu")
	)
	(gr_line
		(start 365.280194 -296.372788)
		(end 365.325914 -296.418508)
		(stroke
			(width 0.05715)
			(type default)
		)
		(layer "In11.Cu")
	)
	(gr_arc
		(start 365.322104 -288.313114)
		(mid 365.32527 -288.315413)
		(end 365.328454 -288.317686)
		(stroke
			(width 0.05715)
			(type default)
		)
		(layer "In11.Cu")
	)
	(gr_arc
		(start 365.324644 -278.595074)
		(mid 365.328696 -278.597886)
		(end 365.332772 -278.600662)
		(stroke
			(width 0.05715)
			(type default)
		)
		(layer "In11.Cu")
	)
	(gr_arc
		(start 365.324898 -283.45511)
		(mid 365.328823 -283.457921)
		(end 365.332772 -283.460698)
		(stroke
			(width 0.05715)
			(type default)
		)
		(layer "In11.Cu")
	)
	(gr_line
		(start 365.325914 -296.418508)
		(end 365.325914 -296.446956)
		(stroke
			(width 0.05715)
			(type default)
		)
		(layer "In11.Cu")
	)
	(gr_arc
		(start 365.329216 -288.318194)
		(mid 365.330992 -288.319467)
		(end 365.332772 -288.320734)
		(stroke
			(width 0.05715)
			(type default)
		)
		(layer "In11.Cu")
	)
	(gr_line
		(start 365.332772 -288.320734)
		(end 365.338868 -288.32429)
		(stroke
			(width 0.05715)
			(type default)
		)
		(layer "In11.Cu")
	)
	(gr_line
		(start 365.332772 -283.460698)
		(end 365.33963 -283.464762)
		(stroke
			(width 0.05715)
			(type default)
		)
		(layer "In11.Cu")
	)
	(gr_line
		(start 365.332772 -278.600662)
		(end 365.33963 -278.604726)
		(stroke
			(width 0.05715)
			(type default)
		)
		(layer "In11.Cu")
	)
	(gr_line
		(start 365.338868 -288.32429)
		(end 365.339122 -288.32429)
		(stroke
			(width 0.05715)
			(type default)
		)
		(layer "In11.Cu")
	)
	(gr_line
		(start 365.33963 -283.464762)
		(end 365.340392 -283.46527)
		(stroke
			(width 0.05715)
			(type default)
		)
		(layer "In11.Cu")
	)
	(gr_line
		(start 365.33963 -278.604726)
		(end 365.340392 -278.605234)
		(stroke
			(width 0.05715)
			(type default)
		)
		(layer "In11.Cu")
	)
	(gr_line
		(start 365.340392 -283.46527)
		(end 365.341154 -283.465778)
		(stroke
			(width 0.05715)
			(type default)
		)
		(layer "In11.Cu")
	)
	(gr_line
		(start 365.340392 -278.605234)
		(end 365.341154 -278.605742)
		(stroke
			(width 0.05715)
			(type default)
		)
		(layer "In11.Cu")
	)
	(gr_line
		(start 365.35487 -247.724168)
		(end 365.056928 -247.724168)
		(stroke
			(width 0.05715)
			(type default)
		)
		(layer "In11.Cu")
	)
	(gr_line
		(start 365.35487 -246.104156)
		(end 365.056928 -246.104156)
		(stroke
			(width 0.05715)
			(type default)
		)
		(layer "In11.Cu")
	)
	(gr_line
		(start 365.35487 -244.484144)
		(end 365.056928 -244.484144)
		(stroke
			(width 0.05715)
			(type default)
		)
		(layer "In11.Cu")
	)
	(gr_line
		(start 365.356902 -279.756108)
		(end 365.274098 -279.838912)
		(stroke
			(width 0.05715)
			(type default)
		)
		(layer "In11.Cu")
	)
	(gr_line
		(start 365.356902 -278.136096)
		(end 365.28756 -278.205438)
		(stroke
			(width 0.05715)
			(type default)
		)
		(layer "In11.Cu")
	)
	(gr_line
		(start 365.356902 -276.516084)
		(end 365.287814 -276.585172)
		(stroke
			(width 0.05715)
			(type default)
		)
		(layer "In11.Cu")
	)
	(gr_line
		(start 365.356902 -274.896072)
		(end 365.274098 -274.978876)
		(stroke
			(width 0.05715)
			(type default)
		)
		(layer "In11.Cu")
	)
	(gr_line
		(start 365.372142 -278.623776)
		(end 365.37265 -278.62403)
		(stroke
			(width 0.05715)
			(type default)
		)
		(layer "In11.Cu")
	)
	(gr_line
		(start 365.37265 -291.583872)
		(end 365.37392 -291.584634)
		(stroke
			(width 0.05715)
			(type default)
		)
		(layer "In11.Cu")
	)
	(gr_line
		(start 365.37265 -278.62403)
		(end 365.37265 -278.623776)
		(stroke
			(width 0.05715)
			(type default)
		)
		(layer "In11.Cu")
	)
	(gr_line
		(start 365.374682 -293.205154)
		(end 365.37519 -293.205154)
		(stroke
			(width 0.05715)
			(type default)
		)
		(layer "In11.Cu")
	)
	(gr_line
		(start 365.374682 -289.96513)
		(end 365.37519 -289.96513)
		(stroke
			(width 0.05715)
			(type default)
		)
		(layer "In11.Cu")
	)
	(gr_line
		(start 365.374682 -285.105348)
		(end 365.37519 -285.105348)
		(stroke
			(width 0.05715)
			(type default)
		)
		(layer "In11.Cu")
	)
	(gr_line
		(start 365.374682 -283.485336)
		(end 365.37519 -283.485336)
		(stroke
			(width 0.05715)
			(type default)
		)
		(layer "In11.Cu")
	)
	(gr_line
		(start 365.374682 -281.865324)
		(end 365.37519 -281.865324)
		(stroke
			(width 0.05715)
			(type default)
		)
		(layer "In11.Cu")
	)
	(gr_line
		(start 365.374936 -288.345118)
		(end 365.37519 -288.345118)
		(stroke
			(width 0.05715)
			(type default)
		)
		(layer "In11.Cu")
	)
	(gr_arc
		(start 365.377984 -280.885138)
		(mid 365.37862 -280.884758)
		(end 365.379254 -280.884376)
		(stroke
			(width 0.05715)
			(type default)
		)
		(layer "In11.Cu")
	)
	(gr_line
		(start 365.45012 -225.870516)
		(end 365.45012 -225.871278)
		(stroke
			(width 0.05715)
			(type default)
		)
		(layer "In11.Cu")
	)
	(gr_line
		(start 365.45012 -225.870262)
		(end 365.45012 -225.870516)
		(stroke
			(width 0.05715)
			(type default)
		)
		(layer "In11.Cu")
	)
	(gr_arc
		(start 365.45012 -225.870262)
		(mid 365.45012 -225.870008)
		(end 365.45012 -225.869754)
		(stroke
			(width 0.05715)
			(type default)
		)
		(layer "In11.Cu")
	)
	(gr_line
		(start 365.450374 -222.614236)
		(end 365.45012 -222.614236)
		(stroke
			(width 0.05715)
			(type default)
		)
		(layer "In11.Cu")
	)
	(gr_line
		(start 365.467392 -294.658288)
		(end 365.4679 -294.658542)
		(stroke
			(width 0.05715)
			(type default)
		)
		(layer "In11.Cu")
	)
	(gr_line
		(start 365.467392 -293.038276)
		(end 365.4679 -293.03853)
		(stroke
			(width 0.05715)
			(type default)
		)
		(layer "In11.Cu")
	)
	(gr_line
		(start 365.467392 -291.418264)
		(end 365.4679 -291.418518)
		(stroke
			(width 0.05715)
			(type default)
		)
		(layer "In11.Cu")
	)
	(gr_line
		(start 365.467392 -289.798252)
		(end 365.4679 -289.798506)
		(stroke
			(width 0.05715)
			(type default)
		)
		(layer "In11.Cu")
	)
	(gr_line
		(start 365.467392 -284.93847)
		(end 365.4679 -284.938724)
		(stroke
			(width 0.05715)
			(type default)
		)
		(layer "In11.Cu")
	)
	(gr_line
		(start 365.467392 -281.698446)
		(end 365.4679 -281.6987)
		(stroke
			(width 0.05715)
			(type default)
		)
		(layer "In11.Cu")
	)
	(gr_line
		(start 365.467646 -292.393624)
		(end 365.462312 -292.396672)
		(stroke
			(width 0.05715)
			(type default)
		)
		(layer "In11.Cu")
	)
	(gr_line
		(start 365.4679 -294.658542)
		(end 365.471964 -294.661082)
		(stroke
			(width 0.05715)
			(type default)
		)
		(layer "In11.Cu")
	)
	(gr_line
		(start 365.4679 -293.03853)
		(end 365.470948 -293.040308)
		(stroke
			(width 0.05715)
			(type default)
		)
		(layer "In11.Cu")
	)
	(gr_line
		(start 365.4679 -291.418518)
		(end 365.4679 -291.418772)
		(stroke
			(width 0.05715)
			(type default)
		)
		(layer "In11.Cu")
	)
	(gr_line
		(start 365.4679 -289.798506)
		(end 365.470948 -289.800284)
		(stroke
			(width 0.05715)
			(type default)
		)
		(layer "In11.Cu")
	)
	(gr_line
		(start 365.4679 -284.938724)
		(end 365.470948 -284.940502)
		(stroke
			(width 0.05715)
			(type default)
		)
		(layer "In11.Cu")
	)
	(gr_line
		(start 365.4679 -283.318712)
		(end 365.470948 -283.32049)
		(stroke
			(width 0.05715)
			(type default)
		)
		(layer "In11.Cu")
	)
	(gr_line
		(start 365.4679 -281.6987)
		(end 365.470948 -281.700478)
		(stroke
			(width 0.05715)
			(type default)
		)
		(layer "In11.Cu")
	)
	(gr_line
		(start 365.4679 -281.05354)
		(end 365.467392 -281.053794)
		(stroke
			(width 0.05715)
			(type default)
		)
		(layer "In11.Cu")
	)
	(gr_line
		(start 365.4679 -278.458676)
		(end 365.468916 -278.459184)
		(stroke
			(width 0.05715)
			(type default)
		)
		(layer "In11.Cu")
	)
	(gr_line
		(start 365.470948 -294.011604)
		(end 365.467392 -294.013636)
		(stroke
			(width 0.05715)
			(type default)
		)
		(layer "In11.Cu")
	)
	(gr_line
		(start 365.470948 -290.77158)
		(end 365.467392 -290.773612)
		(stroke
			(width 0.05715)
			(type default)
		)
		(layer "In11.Cu")
	)
	(gr_line
		(start 365.470948 -289.151568)
		(end 365.467392 -289.1536)
		(stroke
			(width 0.05715)
			(type default)
		)
		(layer "In11.Cu")
	)
	(gr_line
		(start 365.470948 -285.911798)
		(end 365.467392 -285.91383)
		(stroke
			(width 0.05715)
			(type default)
		)
		(layer "In11.Cu")
	)
	(gr_line
		(start 365.470948 -284.291786)
		(end 365.467392 -284.293818)
		(stroke
			(width 0.05715)
			(type default)
		)
		(layer "In11.Cu")
	)
	(gr_line
		(start 365.470948 -282.671774)
		(end 365.467392 -282.673806)
		(stroke
			(width 0.05715)
			(type default)
		)
		(layer "In11.Cu")
	)
	(gr_arc
		(start 365.473996 -225.412554)
		(mid 365.470939 -225.415593)
		(end 365.4679 -225.41865)
		(stroke
			(width 0.05715)
			(type default)
		)
		(layer "In11.Cu")
	)
	(gr_line
		(start 365.482124 -278.467058)
		(end 365.482886 -278.467312)
		(stroke
			(width 0.05715)
			(type default)
		)
		(layer "In11.Cu")
	)
	(gr_arc
		(start 365.482124 -225.40595)
		(mid 365.478044 -225.409232)
		(end 365.473996 -225.412554)
		(stroke
			(width 0.05715)
			(type default)
		)
		(layer "In11.Cu")
	)
	(gr_arc
		(start 365.505492 -225.387916)
		(mid 365.500647 -225.391446)
		(end 365.49584 -225.395028)
		(stroke
			(width 0.05715)
			(type default)
		)
		(layer "In11.Cu")
	)
	(gr_line
		(start 365.508032 -225.386392)
		(end 365.518192 -225.38055)
		(stroke
			(width 0.05715)
			(type default)
		)
		(layer "In11.Cu")
	)
	(gr_line
		(start 365.538766 -225.368612)
		(end 365.540036 -225.36785)
		(stroke
			(width 0.05715)
			(type default)
		)
		(layer "In11.Cu")
	)
	(gr_line
		(start 365.540036 -225.36785)
		(end 365.541814 -225.366834)
		(stroke
			(width 0.05715)
			(type default)
		)
		(layer "In11.Cu")
	)
	(gr_line
		(start 365.541814 -225.366834)
		(end 365.542322 -225.36658)
		(stroke
			(width 0.05715)
			(type default)
		)
		(layer "In11.Cu")
	)
	(gr_line
		(start 365.559594 -295.145968)
		(end 365.55934 -295.145968)
		(stroke
			(width 0.05715)
			(type default)
		)
		(layer "In11.Cu")
	)
	(gr_line
		(start 365.605822 -334.657192)
		(end 365.605568 -334.657192)
		(stroke
			(width 0.07112)
			(type default)
		)
		(layer "In11.Cu")
	)
	(gr_line
		(start 365.625634 -244.978428)
		(end 365.62665 -244.97792)
		(stroke
			(width 0.05715)
			(type default)
		)
		(layer "In11.Cu")
	)
	(gr_line
		(start 365.633762 -225.533966)
		(end 365.634524 -225.533458)
		(stroke
			(width 0.05715)
			(type default)
		)
		(layer "In11.Cu")
	)
	(gr_line
		(start 365.636556 -225.532442)
		(end 365.637064 -225.532188)
		(stroke
			(width 0.05715)
			(type default)
		)
		(layer "In11.Cu")
	)
	(gr_line
		(start 365.654844 -279.756108)
		(end 365.356902 -279.756108)
		(stroke
			(width 0.05715)
			(type default)
		)
		(layer "In11.Cu")
	)
	(gr_line
		(start 365.654844 -278.136096)
		(end 365.356902 -278.136096)
		(stroke
			(width 0.05715)
			(type default)
		)
		(layer "In11.Cu")
	)
	(gr_line
		(start 365.654844 -276.516084)
		(end 365.356902 -276.516084)
		(stroke
			(width 0.05715)
			(type default)
		)
		(layer "In11.Cu")
	)
	(gr_line
		(start 365.654844 -274.896072)
		(end 365.356902 -274.896072)
		(stroke
			(width 0.05715)
			(type default)
		)
		(layer "In11.Cu")
	)
	(gr_line
		(start 365.703358 -221.083124)
		(end 365.703358 -221.054676)
		(stroke
			(width 0.05715)
			(type default)
		)
		(layer "In11.Cu")
	)
	(gr_line
		(start 365.749078 -221.128844)
		(end 365.703358 -221.083124)
		(stroke
			(width 0.05715)
			(type default)
		)
		(layer "In11.Cu")
	)
	(gr_line
		(start 365.84255 -295.633902)
		(end 365.845344 -295.635426)
		(stroke
			(width 0.05715)
			(type default)
		)
		(layer "In11.Cu")
	)
	(gr_line
		(start 365.888016 -334.631792)
		(end 365.887762 -334.631792)
		(stroke
			(width 0.07112)
			(type default)
		)
		(layer "In11.Cu")
	)
	(gr_line
		(start 365.924846 -280.2509)
		(end 365.924592 -280.251154)
		(stroke
			(width 0.05715)
			(type default)
		)
		(layer "In11.Cu")
	)
	(gr_line
		(start 365.937292 -295.468294)
		(end 365.9378 -295.468548)
		(stroke
			(width 0.05715)
			(type default)
		)
		(layer "In11.Cu")
	)
	(gr_line
		(start 365.9378 -295.468548)
		(end 365.938816 -295.469056)
		(stroke
			(width 0.05715)
			(type default)
		)
		(layer "In11.Cu")
	)
	(gr_line
		(start 365.9378 -279.268682)
		(end 365.938816 -279.26919)
		(stroke
			(width 0.05715)
			(type default)
		)
		(layer "In11.Cu")
	)
	(gr_line
		(start 365.938816 -295.469056)
		(end 365.94034 -295.470072)
		(stroke
			(width 0.05715)
			(type default)
		)
		(layer "In11.Cu")
	)
	(gr_line
		(start 365.939578 -221.128844)
		(end 365.985298 -221.083124)
		(stroke
			(width 0.05715)
			(type default)
		)
		(layer "In11.Cu")
	)
	(gr_line
		(start 365.94034 -295.470072)
		(end 365.941356 -295.47058)
		(stroke
			(width 0.05715)
			(type default)
		)
		(layer "In11.Cu")
	)
	(gr_line
		(start 365.941356 -295.47058)
		(end 365.946436 -295.473628)
		(stroke
			(width 0.05715)
			(type default)
		)
		(layer "In11.Cu")
	)
	(gr_arc
		(start 365.963708 -223.882966)
		(mid 365.9632 -223.882585)
		(end 365.962692 -223.882204)
		(stroke
			(width 0.05715)
			(type default)
		)
		(layer "In11.Cu")
	)
	(gr_arc
		(start 365.96447 -222.965264)
		(mid 365.960265 -222.968293)
		(end 365.956088 -222.97136)
		(stroke
			(width 0.05715)
			(type default)
		)
		(layer "In11.Cu")
	)
	(gr_line
		(start 365.96447 -222.965264)
		(end 365.972598 -222.959422)
		(stroke
			(width 0.05715)
			(type default)
		)
		(layer "In11.Cu")
	)
	(gr_arc
		(start 365.966502 -228.744272)
		(mid 365.969669 -228.746569)
		(end 365.972852 -228.748844)
		(stroke
			(width 0.05715)
			(type default)
		)
		(layer "In11.Cu")
	)
	(gr_line
		(start 365.972344 -223.889062)
		(end 365.963708 -223.882966)
		(stroke
			(width 0.05715)
			(type default)
		)
		(layer "In11.Cu")
	)
	(gr_line
		(start 365.972598 -222.959422)
		(end 365.97717 -222.956882)
		(stroke
			(width 0.05715)
			(type default)
		)
		(layer "In11.Cu")
	)
	(gr_line
		(start 365.97336 -228.749098)
		(end 365.972852 -228.748844)
		(stroke
			(width 0.05715)
			(type default)
		)
		(layer "In11.Cu")
	)
	(gr_line
		(start 365.97717 -222.956882)
		(end 365.985044 -222.953326)
		(stroke
			(width 0.05715)
			(type default)
		)
		(layer "In11.Cu")
	)
	(gr_line
		(start 365.97971 -223.89338)
		(end 365.972344 -223.889062)
		(stroke
			(width 0.05715)
			(type default)
		)
		(layer "In11.Cu")
	)
	(gr_line
		(start 365.981234 -228.75367)
		(end 365.97336 -228.749098)
		(stroke
			(width 0.05715)
			(type default)
		)
		(layer "In11.Cu")
	)
	(gr_line
		(start 365.984028 -296.418508)
		(end 365.984028 -296.446956)
		(stroke
			(width 0.05715)
			(type default)
		)
		(layer "In11.Cu")
	)
	(gr_arc
		(start 365.985044 -277.677372)
		(mid 365.982382 -277.67546)
		(end 365.97971 -277.673562)
		(stroke
			(width 0.05715)
			(type default)
		)
		(layer "In11.Cu")
	)
	(gr_line
		(start 365.985298 -221.083124)
		(end 365.985298 -221.054676)
		(stroke
			(width 0.05715)
			(type default)
		)
		(layer "In11.Cu")
	)
	(gr_line
		(start 366.011968 -229.41661)
		(end 366.012476 -229.416356)
		(stroke
			(width 0.05715)
			(type default)
		)
		(layer "In11.Cu")
	)
	(gr_line
		(start 366.029748 -296.372788)
		(end 365.984028 -296.418508)
		(stroke
			(width 0.05715)
			(type default)
		)
		(layer "In11.Cu")
	)
	(gr_line
		(start 366.037114 -222.922592)
		(end 366.03813 -222.92183)
		(stroke
			(width 0.05715)
			(type default)
		)
		(layer "In11.Cu")
	)
	(gr_line
		(start 366.074706 -223.728026)
		(end 366.07496 -223.728026)
		(stroke
			(width 0.05715)
			(type default)
		)
		(layer "In11.Cu")
	)
	(gr_line
		(start 366.090962 -222.117158)
		(end 366.089438 -222.116142)
		(stroke
			(width 0.05715)
			(type default)
		)
		(layer "In11.Cu")
	)
	(gr_line
		(start 366.11052 -223.102932)
		(end 366.120172 -223.096582)
		(stroke
			(width 0.05715)
			(type default)
		)
		(layer "In11.Cu")
	)
	(gr_line
		(start 366.136174 -223.763078)
		(end 366.135412 -223.762824)
		(stroke
			(width 0.05715)
			(type default)
		)
		(layer "In11.Cu")
	)
	(gr_line
		(start 366.139984 -229.563168)
		(end 366.14481 -229.560374)
		(stroke
			(width 0.05715)
			(type default)
		)
		(layer "In11.Cu")
	)
	(gr_line
		(start 366.142524 -223.081342)
		(end 366.142524 -223.081596)
		(stroke
			(width 0.05715)
			(type default)
		)
		(layer "In11.Cu")
	)
	(gr_line
		(start 366.144048 -223.76765)
		(end 366.136174 -223.763078)
		(stroke
			(width 0.05715)
			(type default)
		)
		(layer "In11.Cu")
	)
	(gr_line
		(start 366.14481 -229.560374)
		(end 366.146842 -229.55885)
		(stroke
			(width 0.05715)
			(type default)
		)
		(layer "In11.Cu")
	)
	(gr_line
		(start 366.14608 -223.76892)
		(end 366.144048 -223.76765)
		(stroke
			(width 0.05715)
			(type default)
		)
		(layer "In11.Cu")
	)
	(gr_arc
		(start 366.146842 -229.55885)
		(mid 366.151558 -229.555573)
		(end 366.15624 -229.552246)
		(stroke
			(width 0.05715)
			(type default)
		)
		(layer "In11.Cu")
	)
	(gr_line
		(start 366.146842 -223.769682)
		(end 366.14608 -223.76892)
		(stroke
			(width 0.05715)
			(type default)
		)
		(layer "In11.Cu")
	)
	(gr_arc
		(start 366.149128 -223.077024)
		(mid 366.151927 -223.075127)
		(end 366.154716 -223.073214)
		(stroke
			(width 0.05715)
			(type default)
		)
		(layer "In11.Cu")
	)
	(gr_arc
		(start 366.151414 -223.772984)
		(mid 366.149132 -223.771327)
		(end 366.146842 -223.769682)
		(stroke
			(width 0.05715)
			(type default)
		)
		(layer "In11.Cu")
	)
	(gr_line
		(start 366.220248 -296.372788)
		(end 366.265968 -296.418508)
		(stroke
			(width 0.05715)
			(type default)
		)
		(layer "In11.Cu")
	)
	(gr_line
		(start 366.265968 -296.418508)
		(end 366.265968 -296.446956)
		(stroke
			(width 0.05715)
			(type default)
		)
		(layer "In11.Cu")
	)
	(gr_line
		(start 366.39881 -379.597412)
		(end 366.115092 -379.88113)
		(stroke
			(width 0.07112)
			(type default)
		)
		(layer "In11.Cu")
	)
	(gr_line
		(start 366.39881 -379.583188)
		(end 366.39881 -379.597412)
		(stroke
			(width 0.07112)
			(type default)
		)
		(layer "In11.Cu")
	)
	(gr_line
		(start 366.406684 -288.177986)
		(end 366.4077 -288.178494)
		(stroke
			(width 0.05715)
			(type default)
		)
		(layer "In11.Cu")
	)
	(gr_line
		(start 366.406684 -286.557974)
		(end 366.4077 -286.558482)
		(stroke
			(width 0.05715)
			(type default)
		)
		(layer "In11.Cu")
	)
	(gr_line
		(start 366.407192 -294.658288)
		(end 366.4077 -294.658542)
		(stroke
			(width 0.05715)
			(type default)
		)
		(layer "In11.Cu")
	)
	(gr_line
		(start 366.407192 -293.038276)
		(end 366.4077 -293.03853)
		(stroke
			(width 0.05715)
			(type default)
		)
		(layer "In11.Cu")
	)
	(gr_line
		(start 366.407192 -291.418264)
		(end 366.4077 -291.418518)
		(stroke
			(width 0.05715)
			(type default)
		)
		(layer "In11.Cu")
	)
	(gr_line
		(start 366.407192 -289.798252)
		(end 366.4077 -289.798506)
		(stroke
			(width 0.05715)
			(type default)
		)
		(layer "In11.Cu")
	)
	(gr_line
		(start 366.407192 -284.93847)
		(end 366.4077 -284.938724)
		(stroke
			(width 0.05715)
			(type default)
		)
		(layer "In11.Cu")
	)
	(gr_line
		(start 366.407192 -283.318458)
		(end 366.4077 -283.318712)
		(stroke
			(width 0.05715)
			(type default)
		)
		(layer "In11.Cu")
	)
	(gr_line
		(start 366.407192 -281.698446)
		(end 366.4077 -281.6987)
		(stroke
			(width 0.05715)
			(type default)
		)
		(layer "In11.Cu")
	)
	(gr_line
		(start 366.407192 -278.458422)
		(end 366.4077 -278.458676)
		(stroke
			(width 0.05715)
			(type default)
		)
		(layer "In11.Cu")
	)
	(gr_line
		(start 366.4077 -294.658542)
		(end 366.408716 -294.65905)
		(stroke
			(width 0.05715)
			(type default)
		)
		(layer "In11.Cu")
	)
	(gr_line
		(start 366.4077 -294.013382)
		(end 366.407192 -294.013636)
		(stroke
			(width 0.05715)
			(type default)
		)
		(layer "In11.Cu")
	)
	(gr_line
		(start 366.4077 -293.03853)
		(end 366.408716 -293.039038)
		(stroke
			(width 0.05715)
			(type default)
		)
		(layer "In11.Cu")
	)
	(gr_line
		(start 366.4077 -292.39337)
		(end 366.407192 -292.393624)
		(stroke
			(width 0.05715)
			(type default)
		)
		(layer "In11.Cu")
	)
	(gr_line
		(start 366.4077 -291.418518)
		(end 366.408716 -291.419026)
		(stroke
			(width 0.05715)
			(type default)
		)
		(layer "In11.Cu")
	)
	(gr_line
		(start 366.4077 -290.773358)
		(end 366.407192 -290.773612)
		(stroke
			(width 0.05715)
			(type default)
		)
		(layer "In11.Cu")
	)
	(gr_line
		(start 366.4077 -289.798506)
		(end 366.408716 -289.799014)
		(stroke
			(width 0.05715)
			(type default)
		)
		(layer "In11.Cu")
	)
	(gr_line
		(start 366.4077 -289.153346)
		(end 366.407192 -289.1536)
		(stroke
			(width 0.05715)
			(type default)
		)
		(layer "In11.Cu")
	)
	(gr_line
		(start 366.4077 -288.178494)
		(end 366.408716 -288.179002)
		(stroke
			(width 0.05715)
			(type default)
		)
		(layer "In11.Cu")
	)
	(gr_line
		(start 366.4077 -286.558482)
		(end 366.408716 -286.55899)
		(stroke
			(width 0.05715)
			(type default)
		)
		(layer "In11.Cu")
	)
	(gr_line
		(start 366.4077 -285.913576)
		(end 366.407192 -285.91383)
		(stroke
			(width 0.05715)
			(type default)
		)
		(layer "In11.Cu")
	)
	(gr_line
		(start 366.4077 -284.938724)
		(end 366.408716 -284.939232)
		(stroke
			(width 0.05715)
			(type default)
		)
		(layer "In11.Cu")
	)
	(gr_line
		(start 366.4077 -284.293564)
		(end 366.407192 -284.293818)
		(stroke
			(width 0.05715)
			(type default)
		)
		(layer "In11.Cu")
	)
	(gr_line
		(start 366.4077 -283.318712)
		(end 366.408716 -283.31922)
		(stroke
			(width 0.05715)
			(type default)
		)
		(layer "In11.Cu")
	)
	(gr_line
		(start 366.4077 -282.673552)
		(end 366.407192 -282.673806)
		(stroke
			(width 0.05715)
			(type default)
		)
		(layer "In11.Cu")
	)
	(gr_line
		(start 366.4077 -281.6987)
		(end 366.408716 -281.699208)
		(stroke
			(width 0.05715)
			(type default)
		)
		(layer "In11.Cu")
	)
	(gr_line
		(start 366.4077 -281.05354)
		(end 366.407192 -281.053794)
		(stroke
			(width 0.05715)
			(type default)
		)
		(layer "In11.Cu")
	)
	(gr_line
		(start 366.4077 -278.458676)
		(end 366.408716 -278.459184)
		(stroke
			(width 0.05715)
			(type default)
		)
		(layer "In11.Cu")
	)
	(gr_line
		(start 366.408208 -294.013128)
		(end 366.4077 -294.013382)
		(stroke
			(width 0.05715)
			(type default)
		)
		(layer "In11.Cu")
	)
	(gr_line
		(start 366.408208 -292.393116)
		(end 366.4077 -292.39337)
		(stroke
			(width 0.05715)
			(type default)
		)
		(layer "In11.Cu")
	)
	(gr_line
		(start 366.408208 -290.773104)
		(end 366.4077 -290.773358)
		(stroke
			(width 0.05715)
			(type default)
		)
		(layer "In11.Cu")
	)
	(gr_line
		(start 366.408208 -289.153092)
		(end 366.4077 -289.153346)
		(stroke
			(width 0.05715)
			(type default)
		)
		(layer "In11.Cu")
	)
	(gr_line
		(start 366.408208 -285.913322)
		(end 366.4077 -285.913576)
		(stroke
			(width 0.05715)
			(type default)
		)
		(layer "In11.Cu")
	)
	(gr_line
		(start 366.408208 -284.29331)
		(end 366.4077 -284.293564)
		(stroke
			(width 0.05715)
			(type default)
		)
		(layer "In11.Cu")
	)
	(gr_line
		(start 366.408208 -282.673298)
		(end 366.4077 -282.673552)
		(stroke
			(width 0.05715)
			(type default)
		)
		(layer "In11.Cu")
	)
	(gr_line
		(start 366.408208 -281.053286)
		(end 366.4077 -281.05354)
		(stroke
			(width 0.05715)
			(type default)
		)
		(layer "In11.Cu")
	)
	(gr_line
		(start 366.480852 -225.367342)
		(end 366.481868 -225.366834)
		(stroke
			(width 0.05715)
			(type default)
		)
		(layer "In11.Cu")
	)
	(gr_line
		(start 366.481868 -225.366834)
		(end 366.48263 -225.366326)
		(stroke
			(width 0.05715)
			(type default)
		)
		(layer "In11.Cu")
	)
	(gr_line
		(start 366.48263 -225.366326)
		(end 366.4839 -225.365564)
		(stroke
			(width 0.05715)
			(type default)
		)
		(layer "In11.Cu")
	)
	(gr_line
		(start 366.531906 -334.494632)
		(end 366.531906 -334.494124)
		(stroke
			(width 0.07112)
			(type default)
		)
		(layer "In11.Cu")
	)
	(gr_line
		(start 366.575848 -225.53295)
		(end 366.577118 -225.532188)
		(stroke
			(width 0.05715)
			(type default)
		)
		(layer "In11.Cu")
	)
	(gr_line
		(start 366.577118 -225.532188)
		(end 366.57788 -225.53168)
		(stroke
			(width 0.05715)
			(type default)
		)
		(layer "In11.Cu")
	)
	(gr_line
		(start 366.57788 -225.53168)
		(end 366.578896 -225.531172)
		(stroke
			(width 0.05715)
			(type default)
		)
		(layer "In11.Cu")
	)
	(gr_line
		(start 366.578896 -225.531172)
		(end 366.580674 -225.530156)
		(stroke
			(width 0.05715)
			(type default)
		)
		(layer "In11.Cu")
	)
	(gr_line
		(start 366.582198 -225.52914)
		(end 366.584738 -225.527616)
		(stroke
			(width 0.05715)
			(type default)
		)
		(layer "In11.Cu")
	)
	(gr_line
		(start 366.608614 -225.5139)
		(end 366.609376 -225.513392)
		(stroke
			(width 0.05715)
			(type default)
		)
		(layer "In11.Cu")
	)
	(gr_line
		(start 366.609376 -225.513392)
		(end 366.610138 -225.512884)
		(stroke
			(width 0.05715)
			(type default)
		)
		(layer "In11.Cu")
	)
	(gr_line
		(start 366.610138 -225.512884)
		(end 366.616996 -225.50882)
		(stroke
			(width 0.05715)
			(type default)
		)
		(layer "In11.Cu")
	)
	(gr_arc
		(start 366.616996 -225.50882)
		(mid 366.620945 -225.506043)
		(end 366.62487 -225.503232)
		(stroke
			(width 0.05715)
			(type default)
		)
		(layer "In11.Cu")
	)
	(gr_line
		(start 366.640618 -373.946166)
		(end 366.65027 -374.13819)
		(stroke
			(width 0.07112)
			(type default)
		)
		(layer "In11.Cu")
	)
	(gr_line
		(start 366.648238 -221.083124)
		(end 366.648238 -221.054676)
		(stroke
			(width 0.05715)
			(type default)
		)
		(layer "In11.Cu")
	)
	(gr_line
		(start 366.66932 -221.658688)
		(end 366.669574 -221.658942)
		(stroke
			(width 0.05715)
			(type default)
		)
		(layer "In11.Cu")
	)
	(gr_line
		(start 366.669574 -229.904036)
		(end 366.66932 -229.904036)
		(stroke
			(width 0.05715)
			(type default)
		)
		(layer "In11.Cu")
	)
	(gr_arc
		(start 366.669574 -221.80423)
		(mid 366.669564 -221.807532)
		(end 366.669574 -221.810834)
		(stroke
			(width 0.05715)
			(type default)
		)
		(layer "In11.Cu")
	)
	(gr_line
		(start 366.68202 -379.584458)
		(end 366.978692 -379.88113)
		(stroke
			(width 0.07112)
			(type default)
		)
		(layer "In11.Cu")
	)
	(gr_line
		(start 366.693958 -221.128844)
		(end 366.648238 -221.083124)
		(stroke
			(width 0.05715)
			(type default)
		)
		(layer "In11.Cu")
	)
	(gr_arc
		(start 366.734852 -295.604946)
		(mid 366.739156 -295.608014)
		(end 366.743488 -295.611042)
		(stroke
			(width 0.05715)
			(type default)
		)
		(layer "In11.Cu")
	)
	(gr_arc
		(start 366.734852 -277.785068)
		(mid 366.738777 -277.787879)
		(end 366.742726 -277.790656)
		(stroke
			(width 0.05715)
			(type default)
		)
		(layer "In11.Cu")
	)
	(gr_line
		(start 366.742726 -277.790656)
		(end 366.749584 -277.79472)
		(stroke
			(width 0.05715)
			(type default)
		)
		(layer "In11.Cu")
	)
	(gr_line
		(start 366.743488 -295.611042)
		(end 366.745774 -295.612566)
		(stroke
			(width 0.05715)
			(type default)
		)
		(layer "In11.Cu")
	)
	(gr_line
		(start 366.745774 -295.612566)
		(end 366.750346 -295.615106)
		(stroke
			(width 0.05715)
			(type default)
		)
		(layer "In11.Cu")
	)
	(gr_line
		(start 366.749584 -277.79472)
		(end 366.750346 -277.795228)
		(stroke
			(width 0.05715)
			(type default)
		)
		(layer "In11.Cu")
	)
	(gr_line
		(start 366.750346 -277.795228)
		(end 366.751108 -277.795736)
		(stroke
			(width 0.05715)
			(type default)
		)
		(layer "In11.Cu")
	)
	(gr_line
		(start 366.771936 -280.08453)
		(end 366.77219 -280.084276)
		(stroke
			(width 0.05715)
			(type default)
		)
		(layer "In11.Cu")
	)
	(gr_line
		(start 366.781334 -280.078434)
		(end 366.780826 -280.078942)
		(stroke
			(width 0.05715)
			(type default)
		)
		(layer "In11.Cu")
	)
	(gr_line
		(start 366.782096 -277.81377)
		(end 366.782604 -277.814024)
		(stroke
			(width 0.05715)
			(type default)
		)
		(layer "In11.Cu")
	)
	(gr_line
		(start 366.782604 -277.814024)
		(end 366.784382 -277.814786)
		(stroke
			(width 0.05715)
			(type default)
		)
		(layer "In11.Cu")
	)
	(gr_line
		(start 366.796828 -276.830028)
		(end 366.794542 -276.831298)
		(stroke
			(width 0.05715)
			(type default)
		)
		(layer "In11.Cu")
	)
	(gr_line
		(start 366.809528 -334.444848)
		(end 366.809528 -334.444594)
		(stroke
			(width 0.07112)
			(type default)
		)
		(layer "In11.Cu")
	)
	(gr_line
		(start 366.85982 -221.579694)
		(end 366.860074 -221.579948)
		(stroke
			(width 0.05715)
			(type default)
		)
		(layer "In11.Cu")
	)
	(gr_line
		(start 366.86744 -280.24963)
		(end 366.86617 -280.250392)
		(stroke
			(width 0.05715)
			(type default)
		)
		(layer "In11.Cu")
	)
	(gr_line
		(start 366.877092 -279.268174)
		(end 366.877854 -279.268682)
		(stroke
			(width 0.05715)
			(type default)
		)
		(layer "In11.Cu")
	)
	(gr_line
		(start 366.877854 -279.268682)
		(end 366.87887 -279.26919)
		(stroke
			(width 0.05715)
			(type default)
		)
		(layer "In11.Cu")
	)
	(gr_line
		(start 366.877854 -277.64867)
		(end 366.88014 -277.64994)
		(stroke
			(width 0.05715)
			(type default)
		)
		(layer "In11.Cu")
	)
	(gr_line
		(start 366.87887 -279.26919)
		(end 366.879886 -279.269698)
		(stroke
			(width 0.05715)
			(type default)
		)
		(layer "In11.Cu")
	)
	(gr_line
		(start 366.880902 -280.241756)
		(end 366.87887 -280.243026)
		(stroke
			(width 0.05715)
			(type default)
		)
		(layer "In11.Cu")
	)
	(gr_arc
		(start 366.882172 -277.65121)
		(mid 366.881157 -277.650574)
		(end 366.88014 -277.64994)
		(stroke
			(width 0.05715)
			(type default)
		)
		(layer "In11.Cu")
	)
	(gr_line
		(start 366.884458 -221.128844)
		(end 366.930178 -221.083124)
		(stroke
			(width 0.05715)
			(type default)
		)
		(layer "In11.Cu")
	)
	(gr_line
		(start 366.886744 -279.273762)
		(end 366.888522 -279.274778)
		(stroke
			(width 0.05715)
			(type default)
		)
		(layer "In11.Cu")
	)
	(gr_line
		(start 366.89284 -276.994874)
		(end 366.89284 -276.995128)
		(stroke
			(width 0.05715)
			(type default)
		)
		(layer "In11.Cu")
	)
	(gr_arc
		(start 366.906302 -228.744272)
		(mid 366.909469 -228.746569)
		(end 366.912652 -228.748844)
		(stroke
			(width 0.05715)
			(type default)
		)
		(layer "In11.Cu")
	)
	(gr_line
		(start 366.915446 -228.750876)
		(end 366.912652 -228.748844)
		(stroke
			(width 0.05715)
			(type default)
		)
		(layer "In11.Cu")
	)
	(gr_line
		(start 366.921542 -228.754432)
		(end 366.915446 -228.750876)
		(stroke
			(width 0.05715)
			(type default)
		)
		(layer "In11.Cu")
	)
	(gr_line
		(start 366.923828 -296.418508)
		(end 366.923828 -296.446956)
		(stroke
			(width 0.05715)
			(type default)
		)
		(layer "In11.Cu")
	)
	(gr_line
		(start 366.927384 -373.629682)
		(end 366.640618 -373.946166)
		(stroke
			(width 0.07112)
			(type default)
		)
		(layer "In11.Cu")
	)
	(gr_line
		(start 366.930178 -221.083124)
		(end 366.930178 -221.054676)
		(stroke
			(width 0.05715)
			(type default)
		)
		(layer "In11.Cu")
	)
	(gr_line
		(start 366.94618 -244.00002)
		(end 366.947704 -243.999004)
		(stroke
			(width 0.05715)
			(type default)
		)
		(layer "In11.Cu")
	)
	(gr_line
		(start 366.94618 -240.759996)
		(end 366.947704 -240.75898)
		(stroke
			(width 0.05715)
			(type default)
		)
		(layer "In11.Cu")
	)
	(gr_line
		(start 366.94618 -239.139984)
		(end 366.947704 -239.138968)
		(stroke
			(width 0.05715)
			(type default)
		)
		(layer "In11.Cu")
	)
	(gr_line
		(start 366.94618 -235.89996)
		(end 366.947704 -235.898944)
		(stroke
			(width 0.05715)
			(type default)
		)
		(layer "In11.Cu")
	)
	(gr_line
		(start 366.94618 -234.279948)
		(end 366.947704 -234.278932)
		(stroke
			(width 0.05715)
			(type default)
		)
		(layer "In11.Cu")
	)
	(gr_line
		(start 366.94618 -232.659936)
		(end 366.947704 -232.65892)
		(stroke
			(width 0.05715)
			(type default)
		)
		(layer "In11.Cu")
	)
	(gr_line
		(start 366.951768 -246.591582)
		(end 366.950752 -246.591074)
		(stroke
			(width 0.05715)
			(type default)
		)
		(layer "In11.Cu")
	)
	(gr_line
		(start 366.951768 -244.97157)
		(end 366.950752 -244.971062)
		(stroke
			(width 0.05715)
			(type default)
		)
		(layer "In11.Cu")
	)
	(gr_line
		(start 366.951768 -243.351558)
		(end 366.950752 -243.35105)
		(stroke
			(width 0.05715)
			(type default)
		)
		(layer "In11.Cu")
	)
	(gr_line
		(start 366.951768 -241.731546)
		(end 366.950752 -241.731038)
		(stroke
			(width 0.05715)
			(type default)
		)
		(layer "In11.Cu")
	)
	(gr_line
		(start 366.951768 -240.111534)
		(end 366.950752 -240.111026)
		(stroke
			(width 0.05715)
			(type default)
		)
		(layer "In11.Cu")
	)
	(gr_line
		(start 366.951768 -238.491522)
		(end 366.950752 -238.491014)
		(stroke
			(width 0.05715)
			(type default)
		)
		(layer "In11.Cu")
	)
	(gr_line
		(start 366.951768 -236.87151)
		(end 366.950752 -236.871002)
		(stroke
			(width 0.05715)
			(type default)
		)
		(layer "In11.Cu")
	)
	(gr_line
		(start 366.951768 -235.251498)
		(end 366.950752 -235.25099)
		(stroke
			(width 0.05715)
			(type default)
		)
		(layer "In11.Cu")
	)
	(gr_line
		(start 366.951768 -233.631486)
		(end 366.950752 -233.630978)
		(stroke
			(width 0.05715)
			(type default)
		)
		(layer "In11.Cu")
	)
	(gr_line
		(start 366.951768 -232.011474)
		(end 366.950752 -232.010966)
		(stroke
			(width 0.05715)
			(type default)
		)
		(layer "In11.Cu")
	)
	(gr_line
		(start 366.952276 -238.491776)
		(end 366.951768 -238.491522)
		(stroke
			(width 0.05715)
			(type default)
		)
		(layer "In11.Cu")
	)
	(gr_line
		(start 366.95253 -246.59209)
		(end 366.951768 -246.591582)
		(stroke
			(width 0.05715)
			(type default)
		)
		(layer "In11.Cu")
	)
	(gr_line
		(start 366.95253 -245.616222)
		(end 366.9538 -245.61546)
		(stroke
			(width 0.05715)
			(type default)
		)
		(layer "In11.Cu")
	)
	(gr_line
		(start 366.95253 -244.972078)
		(end 366.951768 -244.97157)
		(stroke
			(width 0.05715)
			(type default)
		)
		(layer "In11.Cu")
	)
	(gr_line
		(start 366.95253 -243.352066)
		(end 366.951768 -243.351558)
		(stroke
			(width 0.05715)
			(type default)
		)
		(layer "In11.Cu")
	)
	(gr_line
		(start 366.95253 -242.376198)
		(end 366.9538 -242.375436)
		(stroke
			(width 0.05715)
			(type default)
		)
		(layer "In11.Cu")
	)
	(gr_line
		(start 366.95253 -241.732054)
		(end 366.951768 -241.731546)
		(stroke
			(width 0.05715)
			(type default)
		)
		(layer "In11.Cu")
	)
	(gr_line
		(start 366.95253 -240.112042)
		(end 366.951768 -240.111534)
		(stroke
			(width 0.05715)
			(type default)
		)
		(layer "In11.Cu")
	)
	(gr_line
		(start 366.95253 -237.516162)
		(end 366.9538 -237.5154)
		(stroke
			(width 0.05715)
			(type default)
		)
		(layer "In11.Cu")
	)
	(gr_line
		(start 366.95253 -236.872018)
		(end 366.951768 -236.87151)
		(stroke
			(width 0.05715)
			(type default)
		)
		(layer "In11.Cu")
	)
	(gr_line
		(start 366.95253 -235.252006)
		(end 366.951768 -235.251498)
		(stroke
			(width 0.05715)
			(type default)
		)
		(layer "In11.Cu")
	)
	(gr_line
		(start 366.95253 -233.631994)
		(end 366.951768 -233.631486)
		(stroke
			(width 0.05715)
			(type default)
		)
		(layer "In11.Cu")
	)
	(gr_line
		(start 366.95253 -232.011982)
		(end 366.951768 -232.011474)
		(stroke
			(width 0.05715)
			(type default)
		)
		(layer "In11.Cu")
	)
	(gr_line
		(start 366.955578 -246.593868)
		(end 366.95253 -246.59209)
		(stroke
			(width 0.05715)
			(type default)
		)
		(layer "In11.Cu")
	)
	(gr_line
		(start 366.955578 -244.973856)
		(end 366.95253 -244.972078)
		(stroke
			(width 0.05715)
			(type default)
		)
		(layer "In11.Cu")
	)
	(gr_line
		(start 366.955578 -243.353844)
		(end 366.95253 -243.352066)
		(stroke
			(width 0.05715)
			(type default)
		)
		(layer "In11.Cu")
	)
	(gr_line
		(start 366.955578 -241.733832)
		(end 366.95253 -241.732054)
		(stroke
			(width 0.05715)
			(type default)
		)
		(layer "In11.Cu")
	)
	(gr_line
		(start 366.955578 -240.11382)
		(end 366.95253 -240.112042)
		(stroke
			(width 0.05715)
			(type default)
		)
		(layer "In11.Cu")
	)
	(gr_line
		(start 366.955578 -236.873796)
		(end 366.95253 -236.872018)
		(stroke
			(width 0.05715)
			(type default)
		)
		(layer "In11.Cu")
	)
	(gr_line
		(start 366.955578 -235.253784)
		(end 366.95253 -235.252006)
		(stroke
			(width 0.05715)
			(type default)
		)
		(layer "In11.Cu")
	)
	(gr_line
		(start 366.955578 -233.633772)
		(end 366.95253 -233.631994)
		(stroke
			(width 0.05715)
			(type default)
		)
		(layer "In11.Cu")
	)
	(gr_line
		(start 366.955578 -232.01376)
		(end 366.95253 -232.011982)
		(stroke
			(width 0.05715)
			(type default)
		)
		(layer "In11.Cu")
	)
	(gr_line
		(start 366.960658 -246.596662)
		(end 366.957102 -246.59463)
		(stroke
			(width 0.05715)
			(type default)
		)
		(layer "In11.Cu")
	)
	(gr_line
		(start 366.960658 -244.97665)
		(end 366.957102 -244.974618)
		(stroke
			(width 0.05715)
			(type default)
		)
		(layer "In11.Cu")
	)
	(gr_line
		(start 366.960658 -243.356638)
		(end 366.957102 -243.354606)
		(stroke
			(width 0.05715)
			(type default)
		)
		(layer "In11.Cu")
	)
	(gr_line
		(start 366.960658 -241.736626)
		(end 366.957102 -241.734594)
		(stroke
			(width 0.05715)
			(type default)
		)
		(layer "In11.Cu")
	)
	(gr_line
		(start 366.960658 -240.116614)
		(end 366.957102 -240.114582)
		(stroke
			(width 0.05715)
			(type default)
		)
		(layer "In11.Cu")
	)
	(gr_line
		(start 366.960658 -236.87659)
		(end 366.957102 -236.874558)
		(stroke
			(width 0.05715)
			(type default)
		)
		(layer "In11.Cu")
	)
	(gr_line
		(start 366.960658 -235.256578)
		(end 366.957102 -235.254546)
		(stroke
			(width 0.05715)
			(type default)
		)
		(layer "In11.Cu")
	)
	(gr_line
		(start 366.960658 -233.636566)
		(end 366.957102 -233.634534)
		(stroke
			(width 0.05715)
			(type default)
		)
		(layer "In11.Cu")
	)
	(gr_line
		(start 366.960658 -232.016554)
		(end 366.957102 -232.014522)
		(stroke
			(width 0.05715)
			(type default)
		)
		(layer "In11.Cu")
	)
	(gr_line
		(start 366.969548 -296.372788)
		(end 366.923828 -296.418508)
		(stroke
			(width 0.05715)
			(type default)
		)
		(layer "In11.Cu")
	)
	(gr_line
		(start 367.039398 -244.166136)
		(end 367.041684 -244.16512)
		(stroke
			(width 0.05715)
			(type default)
		)
		(layer "In11.Cu")
	)
	(gr_line
		(start 367.039398 -240.926112)
		(end 367.041684 -240.925096)
		(stroke
			(width 0.05715)
			(type default)
		)
		(layer "In11.Cu")
	)
	(gr_line
		(start 367.039398 -239.3061)
		(end 367.041684 -239.305084)
		(stroke
			(width 0.05715)
			(type default)
		)
		(layer "In11.Cu")
	)
	(gr_line
		(start 367.039398 -236.066076)
		(end 367.041684 -236.06506)
		(stroke
			(width 0.05715)
			(type default)
		)
		(layer "In11.Cu")
	)
	(gr_line
		(start 367.039398 -234.446064)
		(end 367.041684 -234.445048)
		(stroke
			(width 0.05715)
			(type default)
		)
		(layer "In11.Cu")
	)
	(gr_line
		(start 367.039398 -232.826052)
		(end 367.041684 -232.825036)
		(stroke
			(width 0.05715)
			(type default)
		)
		(layer "In11.Cu")
	)
	(gr_line
		(start 367.041684 -244.16512)
		(end 367.044224 -244.163596)
		(stroke
			(width 0.05715)
			(type default)
		)
		(layer "In11.Cu")
	)
	(gr_line
		(start 367.041684 -240.925096)
		(end 367.044224 -240.923572)
		(stroke
			(width 0.05715)
			(type default)
		)
		(layer "In11.Cu")
	)
	(gr_line
		(start 367.041684 -239.305084)
		(end 367.044224 -239.30356)
		(stroke
			(width 0.05715)
			(type default)
		)
		(layer "In11.Cu")
	)
	(gr_line
		(start 367.041684 -236.06506)
		(end 367.044224 -236.063536)
		(stroke
			(width 0.05715)
			(type default)
		)
		(layer "In11.Cu")
	)
	(gr_line
		(start 367.041684 -234.445048)
		(end 367.044224 -234.443524)
		(stroke
			(width 0.05715)
			(type default)
		)
		(layer "In11.Cu")
	)
	(gr_line
		(start 367.041684 -232.825036)
		(end 367.044224 -232.823512)
		(stroke
			(width 0.05715)
			(type default)
		)
		(layer "In11.Cu")
	)
	(gr_line
		(start 367.04651 -223.102424)
		(end 367.04778 -223.101662)
		(stroke
			(width 0.05715)
			(type default)
		)
		(layer "In11.Cu")
	)
	(gr_line
		(start 367.047018 -246.426228)
		(end 367.045748 -246.425466)
		(stroke
			(width 0.05715)
			(type default)
		)
		(layer "In11.Cu")
	)
	(gr_line
		(start 367.047018 -244.806216)
		(end 367.045748 -244.805454)
		(stroke
			(width 0.05715)
			(type default)
		)
		(layer "In11.Cu")
	)
	(gr_line
		(start 367.047018 -244.162072)
		(end 367.04778 -244.161564)
		(stroke
			(width 0.05715)
			(type default)
		)
		(layer "In11.Cu")
	)
	(gr_line
		(start 367.047018 -243.186204)
		(end 367.045748 -243.185442)
		(stroke
			(width 0.05715)
			(type default)
		)
		(layer "In11.Cu")
	)
	(gr_line
		(start 367.047018 -241.566192)
		(end 367.045748 -241.56543)
		(stroke
			(width 0.05715)
			(type default)
		)
		(layer "In11.Cu")
	)
	(gr_line
		(start 367.047018 -240.922048)
		(end 367.04778 -240.92154)
		(stroke
			(width 0.05715)
			(type default)
		)
		(layer "In11.Cu")
	)
	(gr_line
		(start 367.047018 -239.94618)
		(end 367.045748 -239.945418)
		(stroke
			(width 0.05715)
			(type default)
		)
		(layer "In11.Cu")
	)
	(gr_line
		(start 367.047018 -239.302036)
		(end 367.04778 -239.301528)
		(stroke
			(width 0.05715)
			(type default)
		)
		(layer "In11.Cu")
	)
	(gr_line
		(start 367.047018 -238.326168)
		(end 367.045748 -238.325406)
		(stroke
			(width 0.05715)
			(type default)
		)
		(layer "In11.Cu")
	)
	(gr_line
		(start 367.047018 -236.706156)
		(end 367.045748 -236.705394)
		(stroke
			(width 0.05715)
			(type default)
		)
		(layer "In11.Cu")
	)
	(gr_line
		(start 367.047018 -236.062012)
		(end 367.04778 -236.061504)
		(stroke
			(width 0.05715)
			(type default)
		)
		(layer "In11.Cu")
	)
	(gr_line
		(start 367.047018 -235.086144)
		(end 367.045748 -235.085382)
		(stroke
			(width 0.05715)
			(type default)
		)
		(layer "In11.Cu")
	)
	(gr_line
		(start 367.047018 -234.442)
		(end 367.04778 -234.441492)
		(stroke
			(width 0.05715)
			(type default)
		)
		(layer "In11.Cu")
	)
	(gr_line
		(start 367.047018 -233.466132)
		(end 367.045748 -233.46537)
		(stroke
			(width 0.05715)
			(type default)
		)
		(layer "In11.Cu")
	)
	(gr_line
		(start 367.047018 -232.821988)
		(end 367.04778 -232.82148)
		(stroke
			(width 0.05715)
			(type default)
		)
		(layer "In11.Cu")
	)
	(gr_line
		(start 367.047018 -231.84612)
		(end 367.045748 -231.845358)
		(stroke
			(width 0.05715)
			(type default)
		)
		(layer "In11.Cu")
	)
	(gr_line
		(start 367.047272 -245.78183)
		(end 367.04778 -245.781576)
		(stroke
			(width 0.05715)
			(type default)
		)
		(layer "In11.Cu")
	)
	(gr_line
		(start 367.047272 -242.541806)
		(end 367.04778 -242.541552)
		(stroke
			(width 0.05715)
			(type default)
		)
		(layer "In11.Cu")
	)
	(gr_line
		(start 367.047272 -237.68177)
		(end 367.04778 -237.681516)
		(stroke
			(width 0.05715)
			(type default)
		)
		(layer "In11.Cu")
	)
	(gr_line
		(start 367.047526 -246.426482)
		(end 367.047018 -246.426228)
		(stroke
			(width 0.05715)
			(type default)
		)
		(layer "In11.Cu")
	)
	(gr_line
		(start 367.047526 -244.80647)
		(end 367.047018 -244.806216)
		(stroke
			(width 0.05715)
			(type default)
		)
		(layer "In11.Cu")
	)
	(gr_line
		(start 367.047526 -243.186458)
		(end 367.047018 -243.186204)
		(stroke
			(width 0.05715)
			(type default)
		)
		(layer "In11.Cu")
	)
	(gr_line
		(start 367.047526 -241.566446)
		(end 367.047018 -241.566192)
		(stroke
			(width 0.05715)
			(type default)
		)
		(layer "In11.Cu")
	)
	(gr_line
		(start 367.047526 -239.946434)
		(end 367.047018 -239.94618)
		(stroke
			(width 0.05715)
			(type default)
		)
		(layer "In11.Cu")
	)
	(gr_line
		(start 367.047526 -236.70641)
		(end 367.047018 -236.706156)
		(stroke
			(width 0.05715)
			(type default)
		)
		(layer "In11.Cu")
	)
	(gr_line
		(start 367.047526 -235.086398)
		(end 367.047018 -235.086144)
		(stroke
			(width 0.05715)
			(type default)
		)
		(layer "In11.Cu")
	)
	(gr_line
		(start 367.047526 -233.466386)
		(end 367.047018 -233.466132)
		(stroke
			(width 0.05715)
			(type default)
		)
		(layer "In11.Cu")
	)
	(gr_line
		(start 367.047526 -231.846374)
		(end 367.047018 -231.84612)
		(stroke
			(width 0.05715)
			(type default)
		)
		(layer "In11.Cu")
	)
	(gr_line
		(start 367.04778 -245.781576)
		(end 367.048796 -245.781068)
		(stroke
			(width 0.05715)
			(type default)
		)
		(layer "In11.Cu")
	)
	(gr_line
		(start 367.04778 -242.541552)
		(end 367.048796 -242.541044)
		(stroke
			(width 0.05715)
			(type default)
		)
		(layer "In11.Cu")
	)
	(gr_line
		(start 367.04778 -237.681516)
		(end 367.048796 -237.681008)
		(stroke
			(width 0.05715)
			(type default)
		)
		(layer "In11.Cu")
	)
	(gr_line
		(start 367.04778 -222.12681)
		(end 367.047018 -222.126302)
		(stroke
			(width 0.05715)
			(type default)
		)
		(layer "In11.Cu")
	)
	(gr_line
		(start 367.078514 -244.143784)
		(end 367.079276 -244.143276)
		(stroke
			(width 0.05715)
			(type default)
		)
		(layer "In11.Cu")
	)
	(gr_line
		(start 367.078514 -240.90376)
		(end 367.079276 -240.903252)
		(stroke
			(width 0.05715)
			(type default)
		)
		(layer "In11.Cu")
	)
	(gr_line
		(start 367.078514 -239.283748)
		(end 367.079276 -239.28324)
		(stroke
			(width 0.05715)
			(type default)
		)
		(layer "In11.Cu")
	)
	(gr_line
		(start 367.078514 -236.043724)
		(end 367.079276 -236.043216)
		(stroke
			(width 0.05715)
			(type default)
		)
		(layer "In11.Cu")
	)
	(gr_line
		(start 367.078514 -234.423712)
		(end 367.079276 -234.423204)
		(stroke
			(width 0.05715)
			(type default)
		)
		(layer "In11.Cu")
	)
	(gr_line
		(start 367.078514 -232.8037)
		(end 367.079276 -232.803192)
		(stroke
			(width 0.05715)
			(type default)
		)
		(layer "In11.Cu")
	)
	(gr_line
		(start 367.079276 -244.143276)
		(end 367.080038 -244.142768)
		(stroke
			(width 0.05715)
			(type default)
		)
		(layer "In11.Cu")
	)
	(gr_line
		(start 367.079276 -240.903252)
		(end 367.080038 -240.902744)
		(stroke
			(width 0.05715)
			(type default)
		)
		(layer "In11.Cu")
	)
	(gr_line
		(start 367.079276 -239.28324)
		(end 367.080038 -239.282732)
		(stroke
			(width 0.05715)
			(type default)
		)
		(layer "In11.Cu")
	)
	(gr_line
		(start 367.079276 -236.043216)
		(end 367.080038 -236.042708)
		(stroke
			(width 0.05715)
			(type default)
		)
		(layer "In11.Cu")
	)
	(gr_line
		(start 367.079276 -234.423204)
		(end 367.080038 -234.422696)
		(stroke
			(width 0.05715)
			(type default)
		)
		(layer "In11.Cu")
	)
	(gr_line
		(start 367.079276 -232.803192)
		(end 367.080038 -232.802684)
		(stroke
			(width 0.05715)
			(type default)
		)
		(layer "In11.Cu")
	)
	(gr_line
		(start 367.080038 -244.142768)
		(end 367.086896 -244.138704)
		(stroke
			(width 0.05715)
			(type default)
		)
		(layer "In11.Cu")
	)
	(gr_line
		(start 367.080038 -240.902744)
		(end 367.086896 -240.89868)
		(stroke
			(width 0.05715)
			(type default)
		)
		(layer "In11.Cu")
	)
	(gr_line
		(start 367.080038 -239.282732)
		(end 367.086896 -239.278668)
		(stroke
			(width 0.05715)
			(type default)
		)
		(layer "In11.Cu")
	)
	(gr_line
		(start 367.080038 -236.042708)
		(end 367.086896 -236.038644)
		(stroke
			(width 0.05715)
			(type default)
		)
		(layer "In11.Cu")
	)
	(gr_line
		(start 367.080038 -234.422696)
		(end 367.086896 -234.418632)
		(stroke
			(width 0.05715)
			(type default)
		)
		(layer "In11.Cu")
	)
	(gr_line
		(start 367.080038 -232.802684)
		(end 367.086896 -232.79862)
		(stroke
			(width 0.05715)
			(type default)
		)
		(layer "In11.Cu")
	)
	(gr_line
		(start 367.084102 -223.76765)
		(end 367.078006 -223.764094)
		(stroke
			(width 0.05715)
			(type default)
		)
		(layer "In11.Cu")
	)
	(gr_arc
		(start 367.086896 -244.138704)
		(mid 367.090845 -244.135927)
		(end 367.09477 -244.133116)
		(stroke
			(width 0.05715)
			(type default)
		)
		(layer "In11.Cu")
	)
	(gr_arc
		(start 367.086896 -240.89868)
		(mid 367.090845 -240.895903)
		(end 367.09477 -240.893092)
		(stroke
			(width 0.05715)
			(type default)
		)
		(layer "In11.Cu")
	)
	(gr_arc
		(start 367.086896 -239.278668)
		(mid 367.090845 -239.275891)
		(end 367.09477 -239.27308)
		(stroke
			(width 0.05715)
			(type default)
		)
		(layer "In11.Cu")
	)
	(gr_arc
		(start 367.086896 -236.038644)
		(mid 367.090845 -236.035867)
		(end 367.09477 -236.033056)
		(stroke
			(width 0.05715)
			(type default)
		)
		(layer "In11.Cu")
	)
	(gr_arc
		(start 367.086896 -234.418632)
		(mid 367.090845 -234.415855)
		(end 367.09477 -234.413044)
		(stroke
			(width 0.05715)
			(type default)
		)
		(layer "In11.Cu")
	)
	(gr_arc
		(start 367.086896 -232.79862)
		(mid 367.090845 -232.795843)
		(end 367.09477 -232.793032)
		(stroke
			(width 0.05715)
			(type default)
		)
		(layer "In11.Cu")
	)
	(gr_line
		(start 367.086896 -223.769682)
		(end 367.084102 -223.76765)
		(stroke
			(width 0.05715)
			(type default)
		)
		(layer "In11.Cu")
	)
	(gr_arc
		(start 367.093246 -223.774254)
		(mid 367.090079 -223.771957)
		(end 367.086896 -223.769682)
		(stroke
			(width 0.05715)
			(type default)
		)
		(layer "In11.Cu")
	)
	(gr_line
		(start 367.119662 -373.620284)
		(end 366.927384 -373.629682)
		(stroke
			(width 0.07112)
			(type default)
		)
		(layer "In11.Cu")
	)
	(gr_line
		(start 367.160048 -296.372788)
		(end 367.205768 -296.418508)
		(stroke
			(width 0.05715)
			(type default)
		)
		(layer "In11.Cu")
	)
	(gr_line
		(start 367.205768 -296.418508)
		(end 367.205768 -296.446956)
		(stroke
			(width 0.05715)
			(type default)
		)
		(layer "In11.Cu")
	)
	(gr_line
		(start 367.234724 -247.724168)
		(end 367.532666 -247.724168)
		(stroke
			(width 0.05715)
			(type default)
		)
		(layer "In11.Cu")
	)
	(gr_line
		(start 367.234724 -246.104156)
		(end 367.532666 -246.104156)
		(stroke
			(width 0.05715)
			(type default)
		)
		(layer "In11.Cu")
	)
	(gr_line
		(start 367.234724 -244.484144)
		(end 367.532666 -244.484144)
		(stroke
			(width 0.05715)
			(type default)
		)
		(layer "In11.Cu")
	)
	(gr_line
		(start 367.236756 -278.614886)
		(end 367.236502 -278.614886)
		(stroke
			(width 0.05715)
			(type default)
		)
		(layer "In11.Cu")
	)
	(gr_arc
		(start 367.240312 -293.196772)
		(mid 367.242468 -293.198047)
		(end 367.24463 -293.199312)
		(stroke
			(width 0.05715)
			(type default)
		)
		(layer "In11.Cu")
	)
	(gr_line
		(start 367.241328 -278.61768)
		(end 367.243868 -278.61895)
		(stroke
			(width 0.05715)
			(type default)
		)
		(layer "In11.Cu")
	)
	(gr_line
		(start 367.246662 -278.620474)
		(end 367.247424 -278.620982)
		(stroke
			(width 0.05715)
			(type default)
		)
		(layer "In11.Cu")
	)
	(gr_line
		(start 367.247424 -278.620982)
		(end 367.24844 -278.62149)
		(stroke
			(width 0.05715)
			(type default)
		)
		(layer "In11.Cu")
	)
	(gr_line
		(start 367.247932 -286.721296)
		(end 367.24717 -286.721042)
		(stroke
			(width 0.05715)
			(type default)
		)
		(layer "In11.Cu")
	)
	(gr_line
		(start 367.24844 -278.62149)
		(end 367.249202 -278.621998)
		(stroke
			(width 0.05715)
			(type default)
		)
		(layer "In11.Cu")
	)
	(gr_arc
		(start 367.248948 -288.990024)
		(mid 367.24755 -288.990784)
		(end 367.246154 -288.991548)
		(stroke
			(width 0.05715)
			(type default)
		)
		(layer "In11.Cu")
	)
	(gr_arc
		(start 367.248948 -284.127956)
		(mid 367.246913 -284.129221)
		(end 367.244884 -284.130496)
		(stroke
			(width 0.05715)
			(type default)
		)
		(layer "In11.Cu")
	)
	(gr_arc
		(start 367.248948 -282.507944)
		(mid 367.246913 -282.509209)
		(end 367.244884 -282.510484)
		(stroke
			(width 0.05715)
			(type default)
		)
		(layer "In11.Cu")
	)
	(gr_line
		(start 367.249202 -285.75)
		(end 367.249456 -285.75)
		(stroke
			(width 0.05715)
			(type default)
		)
		(layer "In11.Cu")
	)
	(gr_line
		(start 367.249456 -286.722312)
		(end 367.251234 -286.723328)
		(stroke
			(width 0.05715)
			(type default)
		)
		(layer "In11.Cu")
	)
	(gr_arc
		(start 367.249456 -285.75)
		(mid 367.248567 -285.750507)
		(end 367.247678 -285.751016)
		(stroke
			(width 0.05715)
			(type default)
		)
		(layer "In11.Cu")
	)
	(gr_line
		(start 367.249964 -285.749492)
		(end 367.249202 -285.75)
		(stroke
			(width 0.05715)
			(type default)
		)
		(layer "In11.Cu")
	)
	(gr_line
		(start 367.251488 -293.203376)
		(end 367.251742 -293.203376)
		(stroke
			(width 0.05715)
			(type default)
		)
		(layer "In11.Cu")
	)
	(gr_line
		(start 367.251742 -291.583364)
		(end 367.252504 -291.583872)
		(stroke
			(width 0.05715)
			(type default)
		)
		(layer "In11.Cu")
	)
	(gr_line
		(start 367.252504 -291.583872)
		(end 367.253774 -291.584634)
		(stroke
			(width 0.05715)
			(type default)
		)
		(layer "In11.Cu")
	)
	(gr_line
		(start 367.252504 -276.02942)
		(end 367.25225 -276.029674)
		(stroke
			(width 0.05715)
			(type default)
		)
		(layer "In11.Cu")
	)
	(gr_line
		(start 367.252758 -278.62403)
		(end 367.25352 -278.624538)
		(stroke
			(width 0.05715)
			(type default)
		)
		(layer "In11.Cu")
	)
	(gr_line
		(start 367.25352 -278.624538)
		(end 367.254282 -278.624792)
		(stroke
			(width 0.05715)
			(type default)
		)
		(layer "In11.Cu")
	)
	(gr_line
		(start 367.254282 -278.624792)
		(end 367.255044 -278.6253)
		(stroke
			(width 0.05715)
			(type default)
		)
		(layer "In11.Cu")
	)
	(gr_line
		(start 367.255044 -278.6253)
		(end 367.25606 -278.625808)
		(stroke
			(width 0.05715)
			(type default)
		)
		(layer "In11.Cu")
	)
	(gr_line
		(start 367.255552 -287.363916)
		(end 367.250726 -287.36671)
		(stroke
			(width 0.05715)
			(type default)
		)
		(layer "In11.Cu")
	)
	(gr_line
		(start 367.259616 -293.207948)
		(end 367.260378 -293.208202)
		(stroke
			(width 0.05715)
			(type default)
		)
		(layer "In11.Cu")
	)
	(gr_line
		(start 367.330228 -373.809768)
		(end 366.859312 -374.329452)
		(stroke
			(width 0.07112)
			(type default)
		)
		(layer "In11.Cu")
	)
	(gr_line
		(start 367.333784 -278.450802)
		(end 367.334292 -278.451056)
		(stroke
			(width 0.05715)
			(type default)
		)
		(layer "In11.Cu")
	)
	(gr_line
		(start 367.336324 -278.452072)
		(end 367.338864 -278.453596)
		(stroke
			(width 0.05715)
			(type default)
		)
		(layer "In11.Cu")
	)
	(gr_line
		(start 367.338864 -278.453596)
		(end 367.339626 -278.454104)
		(stroke
			(width 0.05715)
			(type default)
		)
		(layer "In11.Cu")
	)
	(gr_line
		(start 367.339626 -278.454104)
		(end 367.340642 -278.454612)
		(stroke
			(width 0.05715)
			(type default)
		)
		(layer "In11.Cu")
	)
	(gr_line
		(start 367.343182 -278.455882)
		(end 367.343944 -278.45639)
		(stroke
			(width 0.05715)
			(type default)
		)
		(layer "In11.Cu")
	)
	(gr_line
		(start 367.343944 -278.45639)
		(end 367.34496 -278.456898)
		(stroke
			(width 0.05715)
			(type default)
		)
		(layer "In11.Cu")
	)
	(gr_line
		(start 367.344706 -289.796728)
		(end 367.347754 -289.798506)
		(stroke
			(width 0.05715)
			(type default)
		)
		(layer "In11.Cu")
	)
	(gr_line
		(start 367.345214 -286.557466)
		(end 367.345976 -286.557974)
		(stroke
			(width 0.05715)
			(type default)
		)
		(layer "In11.Cu")
	)
	(gr_line
		(start 367.345976 -286.557974)
		(end 367.347246 -286.558736)
		(stroke
			(width 0.05715)
			(type default)
		)
		(layer "In11.Cu")
	)
	(gr_line
		(start 367.345976 -278.457406)
		(end 367.346738 -278.457914)
		(stroke
			(width 0.05715)
			(type default)
		)
		(layer "In11.Cu")
	)
	(gr_line
		(start 367.346738 -281.054048)
		(end 367.346484 -281.054048)
		(stroke
			(width 0.05715)
			(type default)
		)
		(layer "In11.Cu")
	)
	(gr_line
		(start 367.346738 -276.195536)
		(end 367.344198 -276.19706)
		(stroke
			(width 0.05715)
			(type default)
		)
		(layer "In11.Cu")
	)
	(gr_line
		(start 367.347246 -293.038276)
		(end 367.354866 -293.042594)
		(stroke
			(width 0.05715)
			(type default)
		)
		(layer "In11.Cu")
	)
	(gr_line
		(start 367.347246 -291.418518)
		(end 367.347754 -291.418518)
		(stroke
			(width 0.05715)
			(type default)
		)
		(layer "In11.Cu")
	)
	(gr_line
		(start 367.347246 -286.558736)
		(end 367.347754 -286.55899)
		(stroke
			(width 0.05715)
			(type default)
		)
		(layer "In11.Cu")
	)
	(gr_arc
		(start 367.347246 -284.291532)
		(mid 367.346611 -284.291913)
		(end 367.345976 -284.292294)
		(stroke
			(width 0.05715)
			(type default)
		)
		(layer "In11.Cu")
	)
	(gr_line
		(start 367.347754 -291.418518)
		(end 367.34877 -291.419026)
		(stroke
			(width 0.05715)
			(type default)
		)
		(layer "In11.Cu")
	)
	(gr_line
		(start 367.347754 -289.798506)
		(end 367.34877 -289.799014)
		(stroke
			(width 0.05715)
			(type default)
		)
		(layer "In11.Cu")
	)
	(gr_line
		(start 367.348516 -281.053032)
		(end 367.348008 -281.053286)
		(stroke
			(width 0.05715)
			(type default)
		)
		(layer "In11.Cu")
	)
	(gr_line
		(start 367.351056 -289.151314)
		(end 367.34496 -289.15487)
		(stroke
			(width 0.05715)
			(type default)
		)
		(layer "In11.Cu")
	)
	(gr_line
		(start 367.351056 -278.460454)
		(end 367.352072 -278.461216)
		(stroke
			(width 0.05715)
			(type default)
		)
		(layer "In11.Cu")
	)
	(gr_line
		(start 367.354866 -293.042594)
		(end 367.35639 -293.04361)
		(stroke
			(width 0.05715)
			(type default)
		)
		(layer "In11.Cu")
	)
	(gr_line
		(start 367.378742 -294.676576)
		(end 367.386108 -294.680894)
		(stroke
			(width 0.05715)
			(type default)
		)
		(layer "In11.Cu")
	)
	(gr_line
		(start 367.379504 -293.057072)
		(end 367.386108 -293.060882)
		(stroke
			(width 0.05715)
			(type default)
		)
		(layer "In11.Cu")
	)
	(gr_arc
		(start 367.382552 -225.389694)
		(mid 367.378603 -225.392471)
		(end 367.374678 -225.395282)
		(stroke
			(width 0.05715)
			(type default)
		)
		(layer "In11.Cu")
	)
	(gr_line
		(start 367.382552 -225.389694)
		(end 367.38941 -225.38563)
		(stroke
			(width 0.05715)
			(type default)
		)
		(layer "In11.Cu")
	)
	(gr_arc
		(start 367.386108 -294.680894)
		(mid 367.386489 -294.681148)
		(end 367.38687 -294.681402)
		(stroke
			(width 0.05715)
			(type default)
		)
		(layer "In11.Cu")
	)
	(gr_arc
		(start 367.386108 -293.060882)
		(mid 367.386489 -293.061136)
		(end 367.38687 -293.06139)
		(stroke
			(width 0.05715)
			(type default)
		)
		(layer "In11.Cu")
	)
	(gr_line
		(start 367.38941 -225.38563)
		(end 367.390172 -225.385122)
		(stroke
			(width 0.05715)
			(type default)
		)
		(layer "In11.Cu")
	)
	(gr_line
		(start 367.390172 -225.385122)
		(end 367.390934 -225.384614)
		(stroke
			(width 0.05715)
			(type default)
		)
		(layer "In11.Cu")
	)
	(gr_arc
		(start 367.394744 -294.68699)
		(mid 367.390819 -294.684179)
		(end 367.38687 -294.681402)
		(stroke
			(width 0.05715)
			(type default)
		)
		(layer "In11.Cu")
	)
	(gr_arc
		(start 367.394744 -293.066978)
		(mid 367.390819 -293.064167)
		(end 367.38687 -293.06139)
		(stroke
			(width 0.05715)
			(type default)
		)
		(layer "In11.Cu")
	)
	(gr_line
		(start 367.421922 -225.36658)
		(end 367.42243 -225.366326)
		(stroke
			(width 0.05715)
			(type default)
		)
		(layer "In11.Cu")
	)
	(gr_line
		(start 367.42243 -225.366326)
		(end 367.4237 -225.365564)
		(stroke
			(width 0.05715)
			(type default)
		)
		(layer "In11.Cu")
	)
	(gr_line
		(start 367.439448 -295.145968)
		(end 367.439702 -295.145968)
		(stroke
			(width 0.05715)
			(type default)
		)
		(layer "In11.Cu")
	)
	(gr_line
		(start 367.51768 -225.53168)
		(end 367.518696 -225.531172)
		(stroke
			(width 0.05715)
			(type default)
		)
		(layer "In11.Cu")
	)
	(gr_line
		(start 367.532666 -247.724168)
		(end 367.602008 -247.654826)
		(stroke
			(width 0.05715)
			(type default)
		)
		(layer "In11.Cu")
	)
	(gr_line
		(start 367.532666 -246.104156)
		(end 367.61547 -246.021352)
		(stroke
			(width 0.05715)
			(type default)
		)
		(layer "In11.Cu")
	)
	(gr_line
		(start 367.532666 -244.484144)
		(end 367.61547 -244.40134)
		(stroke
			(width 0.05715)
			(type default)
		)
		(layer "In11.Cu")
	)
	(gr_line
		(start 367.534698 -278.136096)
		(end 367.83264 -278.136096)
		(stroke
			(width 0.05715)
			(type default)
		)
		(layer "In11.Cu")
	)
	(gr_line
		(start 367.534698 -276.516084)
		(end 367.83264 -276.516084)
		(stroke
			(width 0.05715)
			(type default)
		)
		(layer "In11.Cu")
	)
	(gr_line
		(start 367.534698 -274.896072)
		(end 367.83264 -274.896072)
		(stroke
			(width 0.05715)
			(type default)
		)
		(layer "In11.Cu")
	)
	(gr_line
		(start 367.598452 -221.083124)
		(end 367.598452 -221.054676)
		(stroke
			(width 0.05715)
			(type default)
		)
		(layer "In11.Cu")
	)
	(gr_line
		(start 367.60912 -221.658688)
		(end 367.609374 -221.658942)
		(stroke
			(width 0.05715)
			(type default)
		)
		(layer "In11.Cu")
	)
	(gr_arc
		(start 367.609374 -221.80423)
		(mid 367.60937 -221.806389)
		(end 367.609374 -221.808548)
		(stroke
			(width 0.05715)
			(type default)
		)
		(layer "In11.Cu")
	)
	(gr_arc
		(start 367.61928 -245.998492)
		(mid 367.617259 -246.009903)
		(end 367.61547 -246.021352)
		(stroke
			(width 0.05715)
			(type default)
		)
		(layer "In11.Cu")
	)
	(gr_arc
		(start 367.61928 -244.37848)
		(mid 367.617258 -244.389891)
		(end 367.61547 -244.40134)
		(stroke
			(width 0.05715)
			(type default)
		)
		(layer "In11.Cu")
	)
	(gr_line
		(start 367.644172 -221.128844)
		(end 367.598452 -221.083124)
		(stroke
			(width 0.05715)
			(type default)
		)
		(layer "In11.Cu")
	)
	(gr_line
		(start 367.689384 -295.614344)
		(end 367.692178 -295.616122)
		(stroke
			(width 0.05715)
			(type default)
		)
		(layer "In11.Cu")
	)
	(gr_arc
		(start 367.794032 -247.641364)
		(mid 367.792246 -247.629914)
		(end 367.790222 -247.618504)
		(stroke
			(width 0.05715)
			(type default)
		)
		(layer "In11.Cu")
	)
	(gr_line
		(start 367.79962 -221.579694)
		(end 367.799874 -221.579948)
		(stroke
			(width 0.05715)
			(type default)
		)
		(layer "In11.Cu")
	)
	(gr_line
		(start 367.83264 -278.136096)
		(end 367.915444 -278.2189)
		(stroke
			(width 0.05715)
			(type default)
		)
		(layer "In11.Cu")
	)
	(gr_line
		(start 367.83264 -276.516084)
		(end 367.915444 -276.598888)
		(stroke
			(width 0.05715)
			(type default)
		)
		(layer "In11.Cu")
	)
	(gr_line
		(start 367.83264 -274.896072)
		(end 367.901982 -274.965414)
		(stroke
			(width 0.05715)
			(type default)
		)
		(layer "In11.Cu")
	)
	(gr_line
		(start 367.834672 -221.128844)
		(end 367.880392 -221.083124)
		(stroke
			(width 0.05715)
			(type default)
		)
		(layer "In11.Cu")
	)
	(gr_arc
		(start 367.844832 -227.123244)
		(mid 367.848757 -227.126055)
		(end 367.852706 -227.128832)
		(stroke
			(width 0.05715)
			(type default)
		)
		(layer "In11.Cu")
	)
	(gr_arc
		(start 367.848388 -229.442518)
		(mid 367.845206 -229.444794)
		(end 367.842038 -229.44709)
		(stroke
			(width 0.05715)
			(type default)
		)
		(layer "In11.Cu")
	)
	(gr_arc
		(start 367.852706 -245.63959)
		(mid 367.848629 -245.642366)
		(end 367.844578 -245.645178)
		(stroke
			(width 0.05715)
			(type default)
		)
		(layer "In11.Cu")
	)
	(gr_arc
		(start 367.852706 -245.63959)
		(mid 367.853087 -245.639336)
		(end 367.853468 -245.639082)
		(stroke
			(width 0.05715)
			(type default)
		)
		(layer "In11.Cu")
	)
	(gr_arc
		(start 367.852706 -242.399566)
		(mid 367.848757 -242.402343)
		(end 367.844832 -242.405154)
		(stroke
			(width 0.05715)
			(type default)
		)
		(layer "In11.Cu")
	)
	(gr_arc
		(start 367.852706 -242.399566)
		(mid 367.853087 -242.399312)
		(end 367.853468 -242.399058)
		(stroke
			(width 0.05715)
			(type default)
		)
		(layer "In11.Cu")
	)
	(gr_arc
		(start 367.852706 -240.779554)
		(mid 367.848757 -240.782331)
		(end 367.844832 -240.785142)
		(stroke
			(width 0.05715)
			(type default)
		)
		(layer "In11.Cu")
	)
	(gr_arc
		(start 367.852706 -240.779554)
		(mid 367.853087 -240.7793)
		(end 367.853468 -240.779046)
		(stroke
			(width 0.05715)
			(type default)
		)
		(layer "In11.Cu")
	)
	(gr_arc
		(start 367.852706 -239.159542)
		(mid 367.848757 -239.162319)
		(end 367.844832 -239.16513)
		(stroke
			(width 0.05715)
			(type default)
		)
		(layer "In11.Cu")
	)
	(gr_arc
		(start 367.852706 -239.159542)
		(mid 367.853087 -239.159288)
		(end 367.853468 -239.159034)
		(stroke
			(width 0.05715)
			(type default)
		)
		(layer "In11.Cu")
	)
	(gr_arc
		(start 367.852706 -237.53953)
		(mid 367.848757 -237.542307)
		(end 367.844832 -237.545118)
		(stroke
			(width 0.05715)
			(type default)
		)
		(layer "In11.Cu")
	)
	(gr_arc
		(start 367.852706 -237.53953)
		(mid 367.853087 -237.539276)
		(end 367.853468 -237.539022)
		(stroke
			(width 0.05715)
			(type default)
		)
		(layer "In11.Cu")
	)
	(gr_arc
		(start 367.852706 -235.919518)
		(mid 367.848757 -235.922295)
		(end 367.844832 -235.925106)
		(stroke
			(width 0.05715)
			(type default)
		)
		(layer "In11.Cu")
	)
	(gr_arc
		(start 367.852706 -235.919518)
		(mid 367.853087 -235.919264)
		(end 367.853468 -235.91901)
		(stroke
			(width 0.05715)
			(type default)
		)
		(layer "In11.Cu")
	)
	(gr_arc
		(start 367.852706 -234.299506)
		(mid 367.848757 -234.302283)
		(end 367.844832 -234.305094)
		(stroke
			(width 0.05715)
			(type default)
		)
		(layer "In11.Cu")
	)
	(gr_arc
		(start 367.852706 -234.299506)
		(mid 367.853087 -234.299252)
		(end 367.853468 -234.298998)
		(stroke
			(width 0.05715)
			(type default)
		)
		(layer "In11.Cu")
	)
	(gr_arc
		(start 367.852706 -224.579688)
		(mid 367.849523 -224.581963)
		(end 367.846356 -224.58426)
		(stroke
			(width 0.05715)
			(type default)
		)
		(layer "In11.Cu")
	)
	(gr_line
		(start 367.852706 -224.579688)
		(end 367.8555 -224.577656)
		(stroke
			(width 0.05715)
			(type default)
		)
		(layer "In11.Cu")
	)
	(gr_arc
		(start 367.852706 -222.959676)
		(mid 367.849523 -222.961951)
		(end 367.846356 -222.964248)
		(stroke
			(width 0.05715)
			(type default)
		)
		(layer "In11.Cu")
	)
	(gr_line
		(start 367.853468 -245.639082)
		(end 367.861088 -245.634764)
		(stroke
			(width 0.05715)
			(type default)
		)
		(layer "In11.Cu")
	)
	(gr_line
		(start 367.853468 -242.399058)
		(end 367.861342 -242.394486)
		(stroke
			(width 0.05715)
			(type default)
		)
		(layer "In11.Cu")
	)
	(gr_line
		(start 367.853468 -240.779046)
		(end 367.861342 -240.774474)
		(stroke
			(width 0.05715)
			(type default)
		)
		(layer "In11.Cu")
	)
	(gr_line
		(start 367.853468 -239.159034)
		(end 367.861342 -239.154462)
		(stroke
			(width 0.05715)
			(type default)
		)
		(layer "In11.Cu")
	)
	(gr_line
		(start 367.853468 -237.539022)
		(end 367.861342 -237.53445)
		(stroke
			(width 0.05715)
			(type default)
		)
		(layer "In11.Cu")
	)
	(gr_line
		(start 367.853468 -235.91901)
		(end 367.859818 -235.9152)
		(stroke
			(width 0.05715)
			(type default)
		)
		(layer "In11.Cu")
	)
	(gr_line
		(start 367.853468 -234.298998)
		(end 367.856262 -234.296966)
		(stroke
			(width 0.05715)
			(type default)
		)
		(layer "In11.Cu")
	)
	(gr_arc
		(start 367.85423 -222.95866)
		(mid 367.853468 -222.959167)
		(end 367.852706 -222.959676)
		(stroke
			(width 0.05715)
			(type default)
		)
		(layer "In11.Cu")
	)
	(gr_line
		(start 367.85423 -222.95866)
		(end 367.861088 -222.954596)
		(stroke
			(width 0.05715)
			(type default)
		)
		(layer "In11.Cu")
	)
	(gr_line
		(start 367.8555 -227.130864)
		(end 367.852706 -227.128832)
		(stroke
			(width 0.05715)
			(type default)
		)
		(layer "In11.Cu")
	)
	(gr_line
		(start 367.8555 -224.577656)
		(end 367.861596 -224.5741)
		(stroke
			(width 0.05715)
			(type default)
		)
		(layer "In11.Cu")
	)
	(gr_line
		(start 367.856262 -234.296966)
		(end 367.860834 -234.294426)
		(stroke
			(width 0.05715)
			(type default)
		)
		(layer "In11.Cu")
	)
	(gr_line
		(start 367.859818 -235.9152)
		(end 367.86058 -235.914692)
		(stroke
			(width 0.05715)
			(type default)
		)
		(layer "In11.Cu")
	)
	(gr_line
		(start 367.86058 -235.914692)
		(end 367.861596 -235.914184)
		(stroke
			(width 0.05715)
			(type default)
		)
		(layer "In11.Cu")
	)
	(gr_line
		(start 367.860834 -227.133912)
		(end 367.8555 -227.130864)
		(stroke
			(width 0.05715)
			(type default)
		)
		(layer "In11.Cu")
	)
	(gr_line
		(start 367.862358 -241.714528)
		(end 367.860834 -241.713512)
		(stroke
			(width 0.05715)
			(type default)
		)
		(layer "In11.Cu")
	)
	(gr_line
		(start 367.862358 -240.094516)
		(end 367.860834 -240.0935)
		(stroke
			(width 0.05715)
			(type default)
		)
		(layer "In11.Cu")
	)
	(gr_line
		(start 367.862358 -238.474504)
		(end 367.860834 -238.473488)
		(stroke
			(width 0.05715)
			(type default)
		)
		(layer "In11.Cu")
	)
	(gr_line
		(start 367.862358 -236.854492)
		(end 367.860834 -236.853476)
		(stroke
			(width 0.05715)
			(type default)
		)
		(layer "In11.Cu")
	)
	(gr_line
		(start 367.862358 -235.23448)
		(end 367.860834 -235.233464)
		(stroke
			(width 0.05715)
			(type default)
		)
		(layer "In11.Cu")
	)
	(gr_line
		(start 367.863882 -296.583862)
		(end 367.863882 -296.61231)
		(stroke
			(width 0.05715)
			(type default)
		)
		(layer "In11.Cu")
	)
	(gr_line
		(start 367.86566 -372.594632)
		(end 367.875058 -372.78691)
		(stroke
			(width 0.07112)
			(type default)
		)
		(layer "In11.Cu")
	)
	(gr_line
		(start 367.87074 -241.719354)
		(end 367.870994 -241.719354)
		(stroke
			(width 0.05715)
			(type default)
		)
		(layer "In11.Cu")
	)
	(gr_line
		(start 367.87074 -240.099342)
		(end 367.870994 -240.099342)
		(stroke
			(width 0.05715)
			(type default)
		)
		(layer "In11.Cu")
	)
	(gr_line
		(start 367.87074 -238.47933)
		(end 367.870994 -238.47933)
		(stroke
			(width 0.05715)
			(type default)
		)
		(layer "In11.Cu")
	)
	(gr_line
		(start 367.87074 -236.859318)
		(end 367.870994 -236.859318)
		(stroke
			(width 0.05715)
			(type default)
		)
		(layer "In11.Cu")
	)
	(gr_line
		(start 367.87074 -235.239306)
		(end 367.870994 -235.239306)
		(stroke
			(width 0.05715)
			(type default)
		)
		(layer "In11.Cu")
	)
	(gr_line
		(start 367.876836 -247.724168)
		(end 367.794032 -247.641364)
		(stroke
			(width 0.05715)
			(type default)
		)
		(layer "In11.Cu")
	)
	(gr_line
		(start 367.876836 -246.104156)
		(end 367.807494 -246.034814)
		(stroke
			(width 0.05715)
			(type default)
		)
		(layer "In11.Cu")
	)
	(gr_line
		(start 367.876836 -244.484144)
		(end 367.807494 -244.414802)
		(stroke
			(width 0.05715)
			(type default)
		)
		(layer "In11.Cu")
	)
	(gr_line
		(start 367.880392 -221.083124)
		(end 367.880392 -221.054676)
		(stroke
			(width 0.05715)
			(type default)
		)
		(layer "In11.Cu")
	)
	(gr_line
		(start 367.883694 -228.767132)
		(end 367.88217 -228.766116)
		(stroke
			(width 0.05715)
			(type default)
		)
		(layer "In11.Cu")
	)
	(gr_line
		(start 367.885472 -242.380262)
		(end 367.886488 -242.379754)
		(stroke
			(width 0.05715)
			(type default)
		)
		(layer "In11.Cu")
	)
	(gr_line
		(start 367.885472 -240.76025)
		(end 367.886488 -240.759742)
		(stroke
			(width 0.05715)
			(type default)
		)
		(layer "In11.Cu")
	)
	(gr_line
		(start 367.885472 -239.140238)
		(end 367.886488 -239.13973)
		(stroke
			(width 0.05715)
			(type default)
		)
		(layer "In11.Cu")
	)
	(gr_line
		(start 367.885472 -237.520226)
		(end 367.886488 -237.519718)
		(stroke
			(width 0.05715)
			(type default)
		)
		(layer "In11.Cu")
	)
	(gr_line
		(start 367.886488 -242.379754)
		(end 367.88725 -242.379246)
		(stroke
			(width 0.05715)
			(type default)
		)
		(layer "In11.Cu")
	)
	(gr_line
		(start 367.886488 -240.759742)
		(end 367.88725 -240.759234)
		(stroke
			(width 0.05715)
			(type default)
		)
		(layer "In11.Cu")
	)
	(gr_line
		(start 367.886488 -239.13973)
		(end 367.88725 -239.139222)
		(stroke
			(width 0.05715)
			(type default)
		)
		(layer "In11.Cu")
	)
	(gr_line
		(start 367.886488 -237.519718)
		(end 367.88725 -237.51921)
		(stroke
			(width 0.05715)
			(type default)
		)
		(layer "In11.Cu")
	)
	(gr_line
		(start 367.88725 -242.379246)
		(end 367.89233 -242.376452)
		(stroke
			(width 0.05715)
			(type default)
		)
		(layer "In11.Cu")
	)
	(gr_line
		(start 367.88725 -240.759234)
		(end 367.89233 -240.75644)
		(stroke
			(width 0.05715)
			(type default)
		)
		(layer "In11.Cu")
	)
	(gr_line
		(start 367.88725 -239.139222)
		(end 367.89233 -239.136428)
		(stroke
			(width 0.05715)
			(type default)
		)
		(layer "In11.Cu")
	)
	(gr_line
		(start 367.88725 -237.51921)
		(end 367.89233 -237.516416)
		(stroke
			(width 0.05715)
			(type default)
		)
		(layer "In11.Cu")
	)
	(gr_line
		(start 367.88725 -235.899198)
		(end 367.888774 -235.898436)
		(stroke
			(width 0.05715)
			(type default)
		)
		(layer "In11.Cu")
	)
	(gr_line
		(start 367.888266 -243.349526)
		(end 367.883186 -243.346478)
		(stroke
			(width 0.05715)
			(type default)
		)
		(layer "In11.Cu")
	)
	(gr_line
		(start 367.888266 -233.629454)
		(end 367.883186 -233.626406)
		(stroke
			(width 0.05715)
			(type default)
		)
		(layer "In11.Cu")
	)
	(gr_line
		(start 367.888266 -232.009442)
		(end 367.883186 -232.006394)
		(stroke
			(width 0.05715)
			(type default)
		)
		(layer "In11.Cu")
	)
	(gr_line
		(start 367.888774 -235.898436)
		(end 367.89233 -235.896404)
		(stroke
			(width 0.05715)
			(type default)
		)
		(layer "In11.Cu")
	)
	(gr_line
		(start 367.889282 -243.350034)
		(end 367.888266 -243.349526)
		(stroke
			(width 0.05715)
			(type default)
		)
		(layer "In11.Cu")
	)
	(gr_line
		(start 367.889282 -233.629962)
		(end 367.888266 -233.629454)
		(stroke
			(width 0.05715)
			(type default)
		)
		(layer "In11.Cu")
	)
	(gr_line
		(start 367.889282 -232.00995)
		(end 367.888266 -232.009442)
		(stroke
			(width 0.05715)
			(type default)
		)
		(layer "In11.Cu")
	)
	(gr_line
		(start 367.889282 -228.77018)
		(end 367.883694 -228.767132)
		(stroke
			(width 0.05715)
			(type default)
		)
		(layer "In11.Cu")
	)
	(gr_line
		(start 367.890806 -243.997226)
		(end 367.891822 -243.996718)
		(stroke
			(width 0.05715)
			(type default)
		)
		(layer "In11.Cu")
	)
	(gr_line
		(start 367.890806 -243.35105)
		(end 367.889282 -243.350034)
		(stroke
			(width 0.05715)
			(type default)
		)
		(layer "In11.Cu")
	)
	(gr_line
		(start 367.890806 -233.630978)
		(end 367.889282 -233.629962)
		(stroke
			(width 0.05715)
			(type default)
		)
		(layer "In11.Cu")
	)
	(gr_line
		(start 367.890806 -232.010966)
		(end 367.889282 -232.00995)
		(stroke
			(width 0.05715)
			(type default)
		)
		(layer "In11.Cu")
	)
	(gr_line
		(start 367.890806 -228.771196)
		(end 367.889282 -228.77018)
		(stroke
			(width 0.05715)
			(type default)
		)
		(layer "In11.Cu")
	)
	(gr_line
		(start 367.890806 -227.79736)
		(end 367.891822 -227.796852)
		(stroke
			(width 0.05715)
			(type default)
		)
		(layer "In11.Cu")
	)
	(gr_line
		(start 367.891822 -243.351558)
		(end 367.890806 -243.35105)
		(stroke
			(width 0.05715)
			(type default)
		)
		(layer "In11.Cu")
	)
	(gr_line
		(start 367.891822 -233.631486)
		(end 367.890806 -233.630978)
		(stroke
			(width 0.05715)
			(type default)
		)
		(layer "In11.Cu")
	)
	(gr_line
		(start 367.891822 -232.011474)
		(end 367.890806 -232.010966)
		(stroke
			(width 0.05715)
			(type default)
		)
		(layer "In11.Cu")
	)
	(gr_line
		(start 367.891822 -228.771704)
		(end 367.890806 -228.771196)
		(stroke
			(width 0.05715)
			(type default)
		)
		(layer "In11.Cu")
	)
	(gr_line
		(start 367.892584 -228.772212)
		(end 367.891822 -228.771704)
		(stroke
			(width 0.05715)
			(type default)
		)
		(layer "In11.Cu")
	)
	(gr_line
		(start 367.893092 -228.772466)
		(end 367.892584 -228.772212)
		(stroke
			(width 0.05715)
			(type default)
		)
		(layer "In11.Cu")
	)
	(gr_line
		(start 367.893854 -230.392986)
		(end 367.892584 -230.392224)
		(stroke
			(width 0.05715)
			(type default)
		)
		(layer "In11.Cu")
	)
	(gr_line
		(start 367.893854 -223.912938)
		(end 367.892584 -223.912176)
		(stroke
			(width 0.05715)
			(type default)
		)
		(layer "In11.Cu")
	)
	(gr_line
		(start 367.895378 -230.393748)
		(end 367.893854 -230.392986)
		(stroke
			(width 0.05715)
			(type default)
		)
		(layer "In11.Cu")
	)
	(gr_line
		(start 367.909602 -296.538142)
		(end 367.863882 -296.583862)
		(stroke
			(width 0.05715)
			(type default)
		)
		(layer "In11.Cu")
	)
	(gr_arc
		(start 367.915444 -278.2189)
		(mid 367.917237 -278.230222)
		(end 367.919254 -278.241506)
		(stroke
			(width 0.05715)
			(type default)
		)
		(layer "In11.Cu")
	)
	(gr_arc
		(start 367.915444 -276.598888)
		(mid 367.917236 -276.61021)
		(end 367.919254 -276.621494)
		(stroke
			(width 0.05715)
			(type default)
		)
		(layer "In11.Cu")
	)
	(gr_line
		(start 367.981738 -228.603302)
		(end 367.980722 -228.602794)
		(stroke
			(width 0.05715)
			(type default)
		)
		(layer "In11.Cu")
	)
	(gr_line
		(start 367.981992 -236.06506)
		(end 367.983516 -236.064044)
		(stroke
			(width 0.05715)
			(type default)
		)
		(layer "In11.Cu")
	)
	(gr_line
		(start 367.9825 -228.60381)
		(end 367.981738 -228.603302)
		(stroke
			(width 0.05715)
			(type default)
		)
		(layer "In11.Cu")
	)
	(gr_line
		(start 367.983516 -236.064044)
		(end 367.984278 -236.063536)
		(stroke
			(width 0.05715)
			(type default)
		)
		(layer "In11.Cu")
	)
	(gr_line
		(start 367.983516 -228.604318)
		(end 367.9825 -228.60381)
		(stroke
			(width 0.05715)
			(type default)
		)
		(layer "In11.Cu")
	)
	(gr_line
		(start 367.984278 -228.604826)
		(end 367.983516 -228.604318)
		(stroke
			(width 0.05715)
			(type default)
		)
		(layer "In11.Cu")
	)
	(gr_line
		(start 367.985802 -244.162834)
		(end 367.987072 -244.162072)
		(stroke
			(width 0.05715)
			(type default)
		)
		(layer "In11.Cu")
	)
	(gr_line
		(start 367.985802 -227.962968)
		(end 367.987072 -227.962206)
		(stroke
			(width 0.05715)
			(type default)
		)
		(layer "In11.Cu")
	)
	(gr_line
		(start 367.986564 -234.442254)
		(end 367.987072 -234.442)
		(stroke
			(width 0.05715)
			(type default)
		)
		(layer "In11.Cu")
	)
	(gr_line
		(start 367.987072 -244.162072)
		(end 367.987834 -244.161564)
		(stroke
			(width 0.05715)
			(type default)
		)
		(layer "In11.Cu")
	)
	(gr_line
		(start 367.987072 -243.186204)
		(end 367.984278 -243.18468)
		(stroke
			(width 0.05715)
			(type default)
		)
		(layer "In11.Cu")
	)
	(gr_line
		(start 367.987072 -233.466132)
		(end 367.984278 -233.464608)
		(stroke
			(width 0.05715)
			(type default)
		)
		(layer "In11.Cu")
	)
	(gr_line
		(start 367.987072 -231.84612)
		(end 367.984278 -231.844596)
		(stroke
			(width 0.05715)
			(type default)
		)
		(layer "In11.Cu")
	)
	(gr_line
		(start 367.987072 -228.60635)
		(end 367.984278 -228.604826)
		(stroke
			(width 0.05715)
			(type default)
		)
		(layer "In11.Cu")
	)
	(gr_line
		(start 367.987072 -227.962206)
		(end 367.987834 -227.961698)
		(stroke
			(width 0.05715)
			(type default)
		)
		(layer "In11.Cu")
	)
	(gr_line
		(start 367.987326 -232.821734)
		(end 367.987834 -232.82148)
		(stroke
			(width 0.05715)
			(type default)
		)
		(layer "In11.Cu")
	)
	(gr_line
		(start 367.98758 -243.186458)
		(end 367.987072 -243.186204)
		(stroke
			(width 0.05715)
			(type default)
		)
		(layer "In11.Cu")
	)
	(gr_line
		(start 367.98758 -233.466386)
		(end 367.987072 -233.466132)
		(stroke
			(width 0.05715)
			(type default)
		)
		(layer "In11.Cu")
	)
	(gr_line
		(start 367.98758 -231.846374)
		(end 367.987072 -231.84612)
		(stroke
			(width 0.05715)
			(type default)
		)
		(layer "In11.Cu")
	)
	(gr_line
		(start 367.98758 -222.12681)
		(end 367.987834 -222.127064)
		(stroke
			(width 0.05715)
			(type default)
		)
		(layer "In11.Cu")
	)
	(gr_line
		(start 367.987834 -241.5667)
		(end 367.988088 -241.566954)
		(stroke
			(width 0.05715)
			(type default)
		)
		(layer "In11.Cu")
	)
	(gr_line
		(start 367.987834 -239.946688)
		(end 367.988088 -239.946942)
		(stroke
			(width 0.05715)
			(type default)
		)
		(layer "In11.Cu")
	)
	(gr_line
		(start 367.987834 -238.326676)
		(end 367.988088 -238.32693)
		(stroke
			(width 0.05715)
			(type default)
		)
		(layer "In11.Cu")
	)
	(gr_line
		(start 367.987834 -236.706664)
		(end 367.988088 -236.706918)
		(stroke
			(width 0.05715)
			(type default)
		)
		(layer "In11.Cu")
	)
	(gr_line
		(start 367.987834 -235.086652)
		(end 367.988088 -235.086906)
		(stroke
			(width 0.05715)
			(type default)
		)
		(layer "In11.Cu")
	)
	(gr_line
		(start 367.987834 -230.226616)
		(end 367.987326 -230.226362)
		(stroke
			(width 0.05715)
			(type default)
		)
		(layer "In11.Cu")
	)
	(gr_line
		(start 367.987834 -228.606858)
		(end 367.987072 -228.60635)
		(stroke
			(width 0.05715)
			(type default)
		)
		(layer "In11.Cu")
	)
	(gr_line
		(start 367.987834 -223.746822)
		(end 367.987326 -223.746568)
		(stroke
			(width 0.05715)
			(type default)
		)
		(layer "In11.Cu")
	)
	(gr_line
		(start 367.987834 -223.101662)
		(end 367.98758 -223.101662)
		(stroke
			(width 0.05715)
			(type default)
		)
		(layer "In11.Cu")
	)
	(gr_line
		(start 367.988088 -242.541552)
		(end 367.987834 -242.541552)
		(stroke
			(width 0.05715)
			(type default)
		)
		(layer "In11.Cu")
	)
	(gr_line
		(start 367.988088 -240.92154)
		(end 367.987834 -240.92154)
		(stroke
			(width 0.05715)
			(type default)
		)
		(layer "In11.Cu")
	)
	(gr_line
		(start 367.988088 -239.301528)
		(end 367.987834 -239.301528)
		(stroke
			(width 0.05715)
			(type default)
		)
		(layer "In11.Cu")
	)
	(gr_line
		(start 367.988088 -237.681516)
		(end 367.987834 -237.681516)
		(stroke
			(width 0.05715)
			(type default)
		)
		(layer "In11.Cu")
	)
	(gr_line
		(start 367.988088 -236.061504)
		(end 367.987834 -236.061504)
		(stroke
			(width 0.05715)
			(type default)
		)
		(layer "In11.Cu")
	)
	(gr_line
		(start 367.98885 -230.227124)
		(end 367.987834 -230.226616)
		(stroke
			(width 0.05715)
			(type default)
		)
		(layer "In11.Cu")
	)
	(gr_line
		(start 367.98885 -223.74733)
		(end 367.987834 -223.746822)
		(stroke
			(width 0.05715)
			(type default)
		)
		(layer "In11.Cu")
	)
	(gr_line
		(start 367.990374 -230.22814)
		(end 367.98885 -230.227124)
		(stroke
			(width 0.05715)
			(type default)
		)
		(layer "In11.Cu")
	)
	(gr_arc
		(start 367.994438 -242.537742)
		(mid 367.996855 -242.536351)
		(end 367.999264 -242.534948)
		(stroke
			(width 0.05715)
			(type default)
		)
		(layer "In11.Cu")
	)
	(gr_arc
		(start 367.994438 -240.91773)
		(mid 367.996855 -240.916339)
		(end 367.999264 -240.914936)
		(stroke
			(width 0.05715)
			(type default)
		)
		(layer "In11.Cu")
	)
	(gr_arc
		(start 367.994438 -239.297718)
		(mid 367.996855 -239.296327)
		(end 367.999264 -239.294924)
		(stroke
			(width 0.05715)
			(type default)
		)
		(layer "In11.Cu")
	)
	(gr_arc
		(start 367.994438 -237.677706)
		(mid 367.996855 -237.676315)
		(end 367.999264 -237.674912)
		(stroke
			(width 0.05715)
			(type default)
		)
		(layer "In11.Cu")
	)
	(gr_arc
		(start 367.995708 -236.057186)
		(mid 367.997488 -236.056046)
		(end 367.999264 -236.0549)
		(stroke
			(width 0.05715)
			(type default)
		)
		(layer "In11.Cu")
	)
	(gr_arc
		(start 367.996216 -223.096582)
		(mid 367.99825 -223.095443)
		(end 368.00028 -223.094296)
		(stroke
			(width 0.05715)
			(type default)
		)
		(layer "In11.Cu")
	)
	(gr_line
		(start 368.01806 -226.32416)
		(end 368.022632 -226.32162)
		(stroke
			(width 0.05715)
			(type default)
		)
		(layer "In11.Cu")
	)
	(gr_line
		(start 368.019838 -230.245158)
		(end 368.018822 -230.24465)
		(stroke
			(width 0.05715)
			(type default)
		)
		(layer "In11.Cu")
	)
	(gr_line
		(start 368.021362 -230.246174)
		(end 368.019838 -230.245158)
		(stroke
			(width 0.05715)
			(type default)
		)
		(layer "In11.Cu")
	)
	(gr_line
		(start 368.021616 -229.561898)
		(end 368.024156 -229.560628)
		(stroke
			(width 0.05715)
			(type default)
		)
		(layer "In11.Cu")
	)
	(gr_line
		(start 368.022632 -226.32162)
		(end 368.024156 -226.320604)
		(stroke
			(width 0.05715)
			(type default)
		)
		(layer "In11.Cu")
	)
	(gr_arc
		(start 368.024156 -229.560628)
		(mid 368.030794 -229.555976)
		(end 368.037364 -229.55123)
		(stroke
			(width 0.05715)
			(type default)
		)
		(layer "In11.Cu")
	)
	(gr_arc
		(start 368.024156 -226.320604)
		(mid 368.028743 -226.317451)
		(end 368.0333 -226.314254)
		(stroke
			(width 0.05715)
			(type default)
		)
		(layer "In11.Cu")
	)
	(gr_arc
		(start 368.038126 -230.257604)
		(mid 368.029796 -230.251813)
		(end 368.021362 -230.246174)
		(stroke
			(width 0.05715)
			(type default)
		)
		(layer "In11.Cu")
	)
	(gr_line
		(start 368.087402 -225.79076)
		(end 368.087656 -225.789744)
		(stroke
			(width 0.05715)
			(type default)
		)
		(layer "In11.Cu")
	)
	(gr_arc
		(start 368.090196 -275.001736)
		(mid 368.092218 -274.990326)
		(end 368.094006 -274.978876)
		(stroke
			(width 0.05715)
			(type default)
		)
		(layer "In11.Cu")
	)
	(gr_line
		(start 368.100102 -296.538142)
		(end 368.145822 -296.583862)
		(stroke
			(width 0.05715)
			(type default)
		)
		(layer "In11.Cu")
	)
	(gr_line
		(start 368.107722 -377.1265)
		(end 367.816892 -377.41733)
		(stroke
			(width 0.07112)
			(type default)
		)
		(layer "In11.Cu")
	)
	(gr_arc
		(start 368.142012 -288.313114)
		(mid 368.145178 -288.315412)
		(end 368.148362 -288.317686)
		(stroke
			(width 0.05715)
			(type default)
		)
		(layer "In11.Cu")
	)
	(gr_arc
		(start 368.144552 -278.595074)
		(mid 368.148604 -278.597886)
		(end 368.15268 -278.600662)
		(stroke
			(width 0.05715)
			(type default)
		)
		(layer "In11.Cu")
	)
	(gr_arc
		(start 368.144552 -276.975062)
		(mid 368.148604 -276.977874)
		(end 368.15268 -276.98065)
		(stroke
			(width 0.05715)
			(type default)
		)
		(layer "In11.Cu")
	)
	(gr_arc
		(start 368.144806 -283.45511)
		(mid 368.148731 -283.457921)
		(end 368.15268 -283.460698)
		(stroke
			(width 0.05715)
			(type default)
		)
		(layer "In11.Cu")
	)
	(gr_line
		(start 368.145822 -296.583862)
		(end 368.145822 -296.61231)
		(stroke
			(width 0.05715)
			(type default)
		)
		(layer "In11.Cu")
	)
	(gr_arc
		(start 368.149124 -288.318194)
		(mid 368.1509 -288.319467)
		(end 368.15268 -288.320734)
		(stroke
			(width 0.05715)
			(type default)
		)
		(layer "In11.Cu")
	)
	(gr_line
		(start 368.152426 -372.278402)
		(end 367.86566 -372.594632)
		(stroke
			(width 0.07112)
			(type default)
		)
		(layer "In11.Cu")
	)
	(gr_line
		(start 368.15268 -288.320734)
		(end 368.158776 -288.32429)
		(stroke
			(width 0.05715)
			(type default)
		)
		(layer "In11.Cu")
	)
	(gr_line
		(start 368.15268 -283.460698)
		(end 368.159538 -283.464762)
		(stroke
			(width 0.05715)
			(type default)
		)
		(layer "In11.Cu")
	)
	(gr_line
		(start 368.15268 -278.600662)
		(end 368.159538 -278.604726)
		(stroke
			(width 0.05715)
			(type default)
		)
		(layer "In11.Cu")
	)
	(gr_line
		(start 368.15268 -276.98065)
		(end 368.159538 -276.984714)
		(stroke
			(width 0.05715)
			(type default)
		)
		(layer "In11.Cu")
	)
	(gr_line
		(start 368.158776 -288.32429)
		(end 368.15903 -288.32429)
		(stroke
			(width 0.05715)
			(type default)
		)
		(layer "In11.Cu")
	)
	(gr_line
		(start 368.159538 -283.464762)
		(end 368.1603 -283.46527)
		(stroke
			(width 0.05715)
			(type default)
		)
		(layer "In11.Cu")
	)
	(gr_line
		(start 368.159538 -278.604726)
		(end 368.1603 -278.605234)
		(stroke
			(width 0.05715)
			(type default)
		)
		(layer "In11.Cu")
	)
	(gr_line
		(start 368.159538 -276.984714)
		(end 368.1603 -276.985222)
		(stroke
			(width 0.05715)
			(type default)
		)
		(layer "In11.Cu")
	)
	(gr_line
		(start 368.1603 -283.46527)
		(end 368.161062 -283.465778)
		(stroke
			(width 0.05715)
			(type default)
		)
		(layer "In11.Cu")
	)
	(gr_line
		(start 368.1603 -278.605234)
		(end 368.161062 -278.605742)
		(stroke
			(width 0.05715)
			(type default)
		)
		(layer "In11.Cu")
	)
	(gr_line
		(start 368.1603 -276.985222)
		(end 368.161062 -276.98573)
		(stroke
			(width 0.05715)
			(type default)
		)
		(layer "In11.Cu")
	)
	(gr_line
		(start 368.174778 -247.724168)
		(end 367.876836 -247.724168)
		(stroke
			(width 0.05715)
			(type default)
		)
		(layer "In11.Cu")
	)
	(gr_line
		(start 368.174778 -246.104156)
		(end 367.876836 -246.104156)
		(stroke
			(width 0.05715)
			(type default)
		)
		(layer "In11.Cu")
	)
	(gr_line
		(start 368.174778 -244.484144)
		(end 367.876836 -244.484144)
		(stroke
			(width 0.05715)
			(type default)
		)
		(layer "In11.Cu")
	)
	(gr_line
		(start 368.17681 -278.136096)
		(end 368.107468 -278.205438)
		(stroke
			(width 0.05715)
			(type default)
		)
		(layer "In11.Cu")
	)
	(gr_line
		(start 368.17681 -276.516084)
		(end 368.107468 -276.585426)
		(stroke
			(width 0.05715)
			(type default)
		)
		(layer "In11.Cu")
	)
	(gr_line
		(start 368.17681 -274.896072)
		(end 368.094006 -274.978876)
		(stroke
			(width 0.05715)
			(type default)
		)
		(layer "In11.Cu")
	)
	(gr_line
		(start 368.191796 -277.00351)
		(end 368.19205 -277.003764)
		(stroke
			(width 0.05715)
			(type default)
		)
		(layer "In11.Cu")
	)
	(gr_line
		(start 368.19205 -278.623776)
		(end 368.192558 -278.62403)
		(stroke
			(width 0.05715)
			(type default)
		)
		(layer "In11.Cu")
	)
	(gr_line
		(start 368.19205 -277.003764)
		(end 368.192558 -277.004018)
		(stroke
			(width 0.05715)
			(type default)
		)
		(layer "In11.Cu")
	)
	(gr_line
		(start 368.192558 -291.583872)
		(end 368.193828 -291.584634)
		(stroke
			(width 0.05715)
			(type default)
		)
		(layer "In11.Cu")
	)
	(gr_line
		(start 368.192558 -278.62403)
		(end 368.192558 -278.623776)
		(stroke
			(width 0.05715)
			(type default)
		)
		(layer "In11.Cu")
	)
	(gr_line
		(start 368.192558 -277.004018)
		(end 368.195352 -277.005542)
		(stroke
			(width 0.05715)
			(type default)
		)
		(layer "In11.Cu")
	)
	(gr_line
		(start 368.19459 -293.205154)
		(end 368.195098 -293.205154)
		(stroke
			(width 0.05715)
			(type default)
		)
		(layer "In11.Cu")
	)
	(gr_line
		(start 368.19459 -289.96513)
		(end 368.195098 -289.96513)
		(stroke
			(width 0.05715)
			(type default)
		)
		(layer "In11.Cu")
	)
	(gr_line
		(start 368.19459 -285.105348)
		(end 368.195098 -285.105348)
		(stroke
			(width 0.05715)
			(type default)
		)
		(layer "In11.Cu")
	)
	(gr_line
		(start 368.19459 -283.485336)
		(end 368.195098 -283.485336)
		(stroke
			(width 0.05715)
			(type default)
		)
		(layer "In11.Cu")
	)
	(gr_line
		(start 368.19459 -281.865324)
		(end 368.195098 -281.865324)
		(stroke
			(width 0.05715)
			(type default)
		)
		(layer "In11.Cu")
	)
	(gr_line
		(start 368.194844 -288.345118)
		(end 368.195098 -288.345118)
		(stroke
			(width 0.05715)
			(type default)
		)
		(layer "In11.Cu")
	)
	(gr_line
		(start 368.195352 -277.005542)
		(end 368.19586 -277.005796)
		(stroke
			(width 0.05715)
			(type default)
		)
		(layer "In11.Cu")
	)
	(gr_arc
		(start 368.197892 -280.885138)
		(mid 368.198528 -280.884758)
		(end 368.199162 -280.884376)
		(stroke
			(width 0.05715)
			(type default)
		)
		(layer "In11.Cu")
	)
	(gr_line
		(start 368.270028 -225.870516)
		(end 368.270028 -225.871278)
		(stroke
			(width 0.05715)
			(type default)
		)
		(layer "In11.Cu")
	)
	(gr_line
		(start 368.270028 -225.870262)
		(end 368.270028 -225.870516)
		(stroke
			(width 0.05715)
			(type default)
		)
		(layer "In11.Cu")
	)
	(gr_arc
		(start 368.270028 -225.870262)
		(mid 368.270028 -225.870008)
		(end 368.270028 -225.869754)
		(stroke
			(width 0.05715)
			(type default)
		)
		(layer "In11.Cu")
	)
	(gr_line
		(start 368.2873 -294.658288)
		(end 368.287808 -294.658542)
		(stroke
			(width 0.05715)
			(type default)
		)
		(layer "In11.Cu")
	)
	(gr_line
		(start 368.2873 -293.038276)
		(end 368.287808 -293.03853)
		(stroke
			(width 0.05715)
			(type default)
		)
		(layer "In11.Cu")
	)
	(gr_line
		(start 368.2873 -291.418264)
		(end 368.287808 -291.418518)
		(stroke
			(width 0.05715)
			(type default)
		)
		(layer "In11.Cu")
	)
	(gr_line
		(start 368.2873 -289.798252)
		(end 368.287808 -289.798506)
		(stroke
			(width 0.05715)
			(type default)
		)
		(layer "In11.Cu")
	)
	(gr_line
		(start 368.2873 -284.93847)
		(end 368.287808 -284.938724)
		(stroke
			(width 0.05715)
			(type default)
		)
		(layer "In11.Cu")
	)
	(gr_line
		(start 368.2873 -281.698446)
		(end 368.287808 -281.6987)
		(stroke
			(width 0.05715)
			(type default)
		)
		(layer "In11.Cu")
	)
	(gr_line
		(start 368.287554 -292.393624)
		(end 368.28222 -292.396672)
		(stroke
			(width 0.05715)
			(type default)
		)
		(layer "In11.Cu")
	)
	(gr_line
		(start 368.287808 -294.658542)
		(end 368.291872 -294.661082)
		(stroke
			(width 0.05715)
			(type default)
		)
		(layer "In11.Cu")
	)
	(gr_line
		(start 368.287808 -293.03853)
		(end 368.290856 -293.040308)
		(stroke
			(width 0.05715)
			(type default)
		)
		(layer "In11.Cu")
	)
	(gr_line
		(start 368.287808 -291.418518)
		(end 368.287808 -291.418772)
		(stroke
			(width 0.05715)
			(type default)
		)
		(layer "In11.Cu")
	)
	(gr_line
		(start 368.287808 -289.798506)
		(end 368.290856 -289.800284)
		(stroke
			(width 0.05715)
			(type default)
		)
		(layer "In11.Cu")
	)
	(gr_line
		(start 368.287808 -284.938724)
		(end 368.290856 -284.940502)
		(stroke
			(width 0.05715)
			(type default)
		)
		(layer "In11.Cu")
	)
	(gr_line
		(start 368.287808 -283.318712)
		(end 368.290856 -283.32049)
		(stroke
			(width 0.05715)
			(type default)
		)
		(layer "In11.Cu")
	)
	(gr_line
		(start 368.287808 -281.6987)
		(end 368.290856 -281.700478)
		(stroke
			(width 0.05715)
			(type default)
		)
		(layer "In11.Cu")
	)
	(gr_line
		(start 368.287808 -281.05354)
		(end 368.2873 -281.053794)
		(stroke
			(width 0.05715)
			(type default)
		)
		(layer "In11.Cu")
	)
	(gr_line
		(start 368.287808 -278.458676)
		(end 368.288824 -278.459184)
		(stroke
			(width 0.05715)
			(type default)
		)
		(layer "In11.Cu")
	)
	(gr_line
		(start 368.287808 -276.838664)
		(end 368.29111 -276.840696)
		(stroke
			(width 0.05715)
			(type default)
		)
		(layer "In11.Cu")
	)
	(gr_line
		(start 368.290856 -294.011604)
		(end 368.2873 -294.013636)
		(stroke
			(width 0.05715)
			(type default)
		)
		(layer "In11.Cu")
	)
	(gr_line
		(start 368.290856 -290.77158)
		(end 368.2873 -290.773612)
		(stroke
			(width 0.05715)
			(type default)
		)
		(layer "In11.Cu")
	)
	(gr_line
		(start 368.290856 -289.151568)
		(end 368.2873 -289.1536)
		(stroke
			(width 0.05715)
			(type default)
		)
		(layer "In11.Cu")
	)
	(gr_line
		(start 368.290856 -285.911798)
		(end 368.2873 -285.91383)
		(stroke
			(width 0.05715)
			(type default)
		)
		(layer "In11.Cu")
	)
	(gr_line
		(start 368.290856 -284.291786)
		(end 368.2873 -284.293818)
		(stroke
			(width 0.05715)
			(type default)
		)
		(layer "In11.Cu")
	)
	(gr_line
		(start 368.290856 -282.671774)
		(end 368.2873 -282.673806)
		(stroke
			(width 0.05715)
			(type default)
		)
		(layer "In11.Cu")
	)
	(gr_arc
		(start 368.293904 -225.412554)
		(mid 368.290847 -225.415593)
		(end 368.287808 -225.41865)
		(stroke
			(width 0.05715)
			(type default)
		)
		(layer "In11.Cu")
	)
	(gr_line
		(start 368.302032 -278.467058)
		(end 368.302794 -278.467312)
		(stroke
			(width 0.05715)
			(type default)
		)
		(layer "In11.Cu")
	)
	(gr_arc
		(start 368.302032 -225.40595)
		(mid 368.297952 -225.409233)
		(end 368.293904 -225.412554)
		(stroke
			(width 0.05715)
			(type default)
		)
		(layer "In11.Cu")
	)
	(gr_arc
		(start 368.3254 -225.387916)
		(mid 368.320555 -225.391446)
		(end 368.315748 -225.395028)
		(stroke
			(width 0.05715)
			(type default)
		)
		(layer "In11.Cu")
	)
	(gr_line
		(start 368.32794 -225.386392)
		(end 368.3381 -225.38055)
		(stroke
			(width 0.05715)
			(type default)
		)
		(layer "In11.Cu")
	)
	(gr_line
		(start 368.34445 -372.26875)
		(end 368.152426 -372.278402)
		(stroke
			(width 0.07112)
			(type default)
		)
		(layer "In11.Cu")
	)
	(gr_line
		(start 368.358674 -225.368612)
		(end 368.359944 -225.36785)
		(stroke
			(width 0.05715)
			(type default)
		)
		(layer "In11.Cu")
	)
	(gr_line
		(start 368.359944 -225.36785)
		(end 368.361722 -225.366834)
		(stroke
			(width 0.05715)
			(type default)
		)
		(layer "In11.Cu")
	)
	(gr_line
		(start 368.361722 -225.366834)
		(end 368.36223 -225.36658)
		(stroke
			(width 0.05715)
			(type default)
		)
		(layer "In11.Cu")
	)
	(gr_line
		(start 368.389662 -377.1265)
		(end 368.680492 -377.41733)
		(stroke
			(width 0.07112)
			(type default)
		)
		(layer "In11.Cu")
	)
	(gr_line
		(start 368.445542 -244.978428)
		(end 368.446558 -244.97792)
		(stroke
			(width 0.05715)
			(type default)
		)
		(layer "In11.Cu")
	)
	(gr_line
		(start 368.45367 -225.533966)
		(end 368.454432 -225.533458)
		(stroke
			(width 0.05715)
			(type default)
		)
		(layer "In11.Cu")
	)
	(gr_line
		(start 368.456464 -225.532442)
		(end 368.456972 -225.532188)
		(stroke
			(width 0.05715)
			(type default)
		)
		(layer "In11.Cu")
	)
	(gr_line
		(start 368.474752 -278.136096)
		(end 368.17681 -278.136096)
		(stroke
			(width 0.05715)
			(type default)
		)
		(layer "In11.Cu")
	)
	(gr_line
		(start 368.474752 -276.516084)
		(end 368.17681 -276.516084)
		(stroke
			(width 0.05715)
			(type default)
		)
		(layer "In11.Cu")
	)
	(gr_line
		(start 368.474752 -274.896072)
		(end 368.17681 -274.896072)
		(stroke
			(width 0.05715)
			(type default)
		)
		(layer "In11.Cu")
	)
	(gr_line
		(start 368.55527 -372.458234)
		(end 368.0841 -372.977918)
		(stroke
			(width 0.07112)
			(type default)
		)
		(layer "In11.Cu")
	)
	(gr_line
		(start 368.570002 -295.145968)
		(end 368.570256 -295.145968)
		(stroke
			(width 0.05715)
			(type default)
		)
		(layer "In11.Cu")
	)
	(gr_line
		(start 368.646202 -295.62425)
		(end 368.646456 -295.62425)
		(stroke
			(width 0.05715)
			(type default)
		)
		(layer "In11.Cu")
	)
	(gr_line
		(start 368.693192 -277.831804)
		(end 368.693446 -277.831804)
		(stroke
			(width 0.05715)
			(type default)
		)
		(layer "In11.Cu")
	)
	(gr_line
		(start 368.742722 -295.459912)
		(end 368.74323 -295.460166)
		(stroke
			(width 0.05715)
			(type default)
		)
		(layer "In11.Cu")
	)
	(gr_line
		(start 368.744754 -280.2509)
		(end 368.7445 -280.251154)
		(stroke
			(width 0.05715)
			(type default)
		)
		(layer "In11.Cu")
	)
	(gr_line
		(start 368.757708 -279.268682)
		(end 368.758724 -279.26919)
		(stroke
			(width 0.05715)
			(type default)
		)
		(layer "In11.Cu")
	)
	(gr_arc
		(start 368.78641 -228.744272)
		(mid 368.789577 -228.746569)
		(end 368.79276 -228.748844)
		(stroke
			(width 0.05715)
			(type default)
		)
		(layer "In11.Cu")
	)
	(gr_line
		(start 368.793268 -228.749098)
		(end 368.79276 -228.748844)
		(stroke
			(width 0.05715)
			(type default)
		)
		(layer "In11.Cu")
	)
	(gr_line
		(start 368.801142 -228.75367)
		(end 368.793268 -228.749098)
		(stroke
			(width 0.05715)
			(type default)
		)
		(layer "In11.Cu")
	)
	(gr_line
		(start 368.831876 -229.41661)
		(end 368.832384 -229.416356)
		(stroke
			(width 0.05715)
			(type default)
		)
		(layer "In11.Cu")
	)
	(gr_line
		(start 368.849402 -295.955974)
		(end 368.849656 -295.95572)
		(stroke
			(width 0.05715)
			(type default)
		)
		(layer "In11.Cu")
	)
	(gr_line
		(start 368.88039 -296.61231)
		(end 368.88039 -296.612818)
		(stroke
			(width 0.07112)
			(type default)
		)
		(layer "In11.Cu")
	)
	(gr_line
		(start 368.88039 -296.583862)
		(end 368.88039 -296.61231)
		(stroke
			(width 0.05715)
			(type default)
		)
		(layer "In11.Cu")
	)
	(gr_line
		(start 368.92611 -296.538142)
		(end 368.88039 -296.583862)
		(stroke
			(width 0.05715)
			(type default)
		)
		(layer "In11.Cu")
	)
	(gr_line
		(start 368.959892 -229.563168)
		(end 368.964718 -229.560374)
		(stroke
			(width 0.05715)
			(type default)
		)
		(layer "In11.Cu")
	)
	(gr_line
		(start 368.964718 -229.560374)
		(end 368.96675 -229.55885)
		(stroke
			(width 0.05715)
			(type default)
		)
		(layer "In11.Cu")
	)
	(gr_arc
		(start 368.96675 -229.55885)
		(mid 368.971466 -229.555573)
		(end 368.976148 -229.552246)
		(stroke
			(width 0.05715)
			(type default)
		)
		(layer "In11.Cu")
	)
	(gr_line
		(start 369.11661 -296.538142)
		(end 369.16233 -296.583862)
		(stroke
			(width 0.05715)
			(type default)
		)
		(layer "In11.Cu")
	)
	(gr_line
		(start 369.16233 -296.583862)
		(end 369.16233 -296.61231)
		(stroke
			(width 0.05715)
			(type default)
		)
		(layer "In11.Cu")
	)
	(gr_line
		(start 369.162838 -296.659554)
		(end 369.162838 -296.660062)
		(stroke
			(width 0.07112)
			(type default)
		)
		(layer "In11.Cu")
	)
	(gr_line
		(start 369.30076 -225.367342)
		(end 369.301776 -225.366834)
		(stroke
			(width 0.05715)
			(type default)
		)
		(layer "In11.Cu")
	)
	(gr_line
		(start 369.301776 -225.366834)
		(end 369.302538 -225.366326)
		(stroke
			(width 0.05715)
			(type default)
		)
		(layer "In11.Cu")
	)
	(gr_line
		(start 369.302538 -225.366326)
		(end 369.303808 -225.365564)
		(stroke
			(width 0.05715)
			(type default)
		)
		(layer "In11.Cu")
	)
	(gr_line
		(start 369.302538 -222.126302)
		(end 369.309904 -222.122238)
		(stroke
			(width 0.05715)
			(type default)
		)
		(layer "In11.Cu")
	)
	(gr_line
		(start 369.306094 -225.364294)
		(end 369.30711 -225.363786)
		(stroke
			(width 0.05715)
			(type default)
		)
		(layer "In11.Cu")
	)
	(gr_line
		(start 369.30711 -225.363786)
		(end 369.307872 -225.363278)
		(stroke
			(width 0.05715)
			(type default)
		)
		(layer "In11.Cu")
	)
	(gr_line
		(start 369.307872 -225.363278)
		(end 369.308888 -225.36277)
		(stroke
			(width 0.05715)
			(type default)
		)
		(layer "In11.Cu")
	)
	(gr_line
		(start 369.308888 -225.36277)
		(end 369.309396 -225.362516)
		(stroke
			(width 0.05715)
			(type default)
		)
		(layer "In11.Cu")
	)
	(gr_line
		(start 369.319302 -295.145968)
		(end 369.319556 -295.145968)
		(stroke
			(width 0.05715)
			(type default)
		)
		(layer "In11.Cu")
	)
	(gr_line
		(start 369.395756 -225.53295)
		(end 369.397026 -225.532188)
		(stroke
			(width 0.05715)
			(type default)
		)
		(layer "In11.Cu")
	)
	(gr_line
		(start 369.397026 -225.532188)
		(end 369.397788 -225.53168)
		(stroke
			(width 0.05715)
			(type default)
		)
		(layer "In11.Cu")
	)
	(gr_line
		(start 369.397788 -225.53168)
		(end 369.398804 -225.531172)
		(stroke
			(width 0.05715)
			(type default)
		)
		(layer "In11.Cu")
	)
	(gr_line
		(start 369.398804 -225.531172)
		(end 369.400582 -225.530156)
		(stroke
			(width 0.05715)
			(type default)
		)
		(layer "In11.Cu")
	)
	(gr_line
		(start 369.402106 -225.52914)
		(end 369.403122 -225.528632)
		(stroke
			(width 0.05715)
			(type default)
		)
		(layer "In11.Cu")
	)
	(gr_line
		(start 369.402106 -222.289116)
		(end 369.402868 -222.288608)
		(stroke
			(width 0.05715)
			(type default)
		)
		(layer "In11.Cu")
	)
	(gr_line
		(start 369.402868 -222.288608)
		(end 369.403884 -222.2881)
		(stroke
			(width 0.05715)
			(type default)
		)
		(layer "In11.Cu")
	)
	(gr_line
		(start 369.403122 -225.528632)
		(end 369.404138 -225.52787)
		(stroke
			(width 0.05715)
			(type default)
		)
		(layer "In11.Cu")
	)
	(gr_line
		(start 369.403884 -222.2881)
		(end 369.405662 -222.287084)
		(stroke
			(width 0.05715)
			(type default)
		)
		(layer "In11.Cu")
	)
	(gr_line
		(start 369.428776 -225.513646)
		(end 369.429284 -225.513392)
		(stroke
			(width 0.05715)
			(type default)
		)
		(layer "In11.Cu")
	)
	(gr_line
		(start 369.429284 -225.513392)
		(end 369.430046 -225.512884)
		(stroke
			(width 0.05715)
			(type default)
		)
		(layer "In11.Cu")
	)
	(gr_line
		(start 369.430046 -225.512884)
		(end 369.436904 -225.50882)
		(stroke
			(width 0.05715)
			(type default)
		)
		(layer "In11.Cu")
	)
	(gr_arc
		(start 369.436904 -225.50882)
		(mid 369.440853 -225.506043)
		(end 369.444778 -225.503232)
		(stroke
			(width 0.05715)
			(type default)
		)
		(layer "In11.Cu")
	)
	(gr_line
		(start 369.443762 -221.083124)
		(end 369.443762 -221.054676)
		(stroke
			(width 0.05715)
			(type default)
		)
		(layer "In11.Cu")
	)
	(gr_line
		(start 369.489482 -221.128844)
		(end 369.443762 -221.083124)
		(stroke
			(width 0.05715)
			(type default)
		)
		(layer "In11.Cu")
	)
	(gr_arc
		(start 369.55476 -279.40508)
		(mid 369.558685 -279.407891)
		(end 369.562634 -279.410668)
		(stroke
			(width 0.05715)
			(type default)
		)
		(layer "In11.Cu")
	)
	(gr_line
		(start 369.562634 -279.410668)
		(end 369.569492 -279.414732)
		(stroke
			(width 0.05715)
			(type default)
		)
		(layer "In11.Cu")
	)
	(gr_line
		(start 369.569492 -279.414732)
		(end 369.570254 -279.41524)
		(stroke
			(width 0.05715)
			(type default)
		)
		(layer "In11.Cu")
	)
	(gr_line
		(start 369.570254 -279.41524)
		(end 369.571016 -279.415748)
		(stroke
			(width 0.05715)
			(type default)
		)
		(layer "In11.Cu")
	)
	(gr_line
		(start 369.601496 -280.078688)
		(end 369.600734 -280.079196)
		(stroke
			(width 0.05715)
			(type default)
		)
		(layer "In11.Cu")
	)
	(gr_line
		(start 369.602004 -279.433782)
		(end 369.602512 -279.434036)
		(stroke
			(width 0.05715)
			(type default)
		)
		(layer "In11.Cu")
	)
	(gr_line
		(start 369.602512 -279.434036)
		(end 369.605306 -279.43556)
		(stroke
			(width 0.05715)
			(type default)
		)
		(layer "In11.Cu")
	)
	(gr_line
		(start 369.679982 -221.128844)
		(end 369.725702 -221.083124)
		(stroke
			(width 0.05715)
			(type default)
		)
		(layer "In11.Cu")
	)
	(gr_line
		(start 369.697 -280.244042)
		(end 369.69573 -280.244804)
		(stroke
			(width 0.05715)
			(type default)
		)
		(layer "In11.Cu")
	)
	(gr_line
		(start 369.697508 -280.243788)
		(end 369.697 -280.244042)
		(stroke
			(width 0.05715)
			(type default)
		)
		(layer "In11.Cu")
	)
	(gr_line
		(start 369.697762 -279.268682)
		(end 369.698778 -279.26919)
		(stroke
			(width 0.05715)
			(type default)
		)
		(layer "In11.Cu")
	)
	(gr_line
		(start 369.698778 -279.26919)
		(end 369.700302 -279.270206)
		(stroke
			(width 0.05715)
			(type default)
		)
		(layer "In11.Cu")
	)
	(gr_line
		(start 369.700302 -279.270206)
		(end 369.701318 -279.270714)
		(stroke
			(width 0.05715)
			(type default)
		)
		(layer "In11.Cu")
	)
	(gr_line
		(start 369.701318 -279.270714)
		(end 369.706398 -279.273762)
		(stroke
			(width 0.05715)
			(type default)
		)
		(layer "In11.Cu")
	)
	(gr_line
		(start 369.725702 -221.083124)
		(end 369.725702 -221.054676)
		(stroke
			(width 0.05715)
			(type default)
		)
		(layer "In11.Cu")
	)
	(gr_arc
		(start 369.726464 -228.744272)
		(mid 369.729631 -228.746569)
		(end 369.732814 -228.748844)
		(stroke
			(width 0.05715)
			(type default)
		)
		(layer "In11.Cu")
	)
	(gr_line
		(start 369.733322 -228.749098)
		(end 369.732814 -228.748844)
		(stroke
			(width 0.05715)
			(type default)
		)
		(layer "In11.Cu")
	)
	(gr_line
		(start 369.741196 -228.75367)
		(end 369.733322 -228.749098)
		(stroke
			(width 0.05715)
			(type default)
		)
		(layer "In11.Cu")
	)
	(gr_line
		(start 369.770914 -243.997226)
		(end 369.77193 -243.996718)
		(stroke
			(width 0.05715)
			(type default)
		)
		(layer "In11.Cu")
	)
	(gr_line
		(start 369.770914 -240.757202)
		(end 369.77193 -240.756694)
		(stroke
			(width 0.05715)
			(type default)
		)
		(layer "In11.Cu")
	)
	(gr_line
		(start 369.770914 -239.13719)
		(end 369.77193 -239.136682)
		(stroke
			(width 0.05715)
			(type default)
		)
		(layer "In11.Cu")
	)
	(gr_line
		(start 369.770914 -235.897166)
		(end 369.77193 -235.896658)
		(stroke
			(width 0.05715)
			(type default)
		)
		(layer "In11.Cu")
	)
	(gr_line
		(start 369.770914 -234.277154)
		(end 369.77193 -234.276646)
		(stroke
			(width 0.05715)
			(type default)
		)
		(layer "In11.Cu")
	)
	(gr_line
		(start 369.770914 -232.657142)
		(end 369.77193 -232.656634)
		(stroke
			(width 0.05715)
			(type default)
		)
		(layer "In11.Cu")
	)
	(gr_line
		(start 369.77193 -246.591582)
		(end 369.770914 -246.591074)
		(stroke
			(width 0.05715)
			(type default)
		)
		(layer "In11.Cu")
	)
	(gr_line
		(start 369.77193 -244.97157)
		(end 369.770914 -244.971062)
		(stroke
			(width 0.05715)
			(type default)
		)
		(layer "In11.Cu")
	)
	(gr_line
		(start 369.77193 -243.996718)
		(end 369.772692 -243.99621)
		(stroke
			(width 0.05715)
			(type default)
		)
		(layer "In11.Cu")
	)
	(gr_line
		(start 369.77193 -243.351558)
		(end 369.770914 -243.35105)
		(stroke
			(width 0.05715)
			(type default)
		)
		(layer "In11.Cu")
	)
	(gr_line
		(start 369.77193 -241.731546)
		(end 369.770914 -241.731038)
		(stroke
			(width 0.05715)
			(type default)
		)
		(layer "In11.Cu")
	)
	(gr_line
		(start 369.77193 -240.756694)
		(end 369.772692 -240.756186)
		(stroke
			(width 0.05715)
			(type default)
		)
		(layer "In11.Cu")
	)
	(gr_line
		(start 369.77193 -240.111534)
		(end 369.770914 -240.111026)
		(stroke
			(width 0.05715)
			(type default)
		)
		(layer "In11.Cu")
	)
	(gr_line
		(start 369.77193 -239.136682)
		(end 369.772692 -239.136174)
		(stroke
			(width 0.05715)
			(type default)
		)
		(layer "In11.Cu")
	)
	(gr_line
		(start 369.77193 -238.491522)
		(end 369.770914 -238.491014)
		(stroke
			(width 0.05715)
			(type default)
		)
		(layer "In11.Cu")
	)
	(gr_line
		(start 369.77193 -236.87151)
		(end 369.770914 -236.871002)
		(stroke
			(width 0.05715)
			(type default)
		)
		(layer "In11.Cu")
	)
	(gr_line
		(start 369.77193 -235.896658)
		(end 369.772692 -235.89615)
		(stroke
			(width 0.05715)
			(type default)
		)
		(layer "In11.Cu")
	)
	(gr_line
		(start 369.77193 -235.251498)
		(end 369.770914 -235.25099)
		(stroke
			(width 0.05715)
			(type default)
		)
		(layer "In11.Cu")
	)
	(gr_line
		(start 369.77193 -234.276646)
		(end 369.772692 -234.276138)
		(stroke
			(width 0.05715)
			(type default)
		)
		(layer "In11.Cu")
	)
	(gr_line
		(start 369.77193 -233.631486)
		(end 369.770914 -233.630978)
		(stroke
			(width 0.05715)
			(type default)
		)
		(layer "In11.Cu")
	)
	(gr_line
		(start 369.77193 -232.656634)
		(end 369.772692 -232.656126)
		(stroke
			(width 0.05715)
			(type default)
		)
		(layer "In11.Cu")
	)
	(gr_line
		(start 369.77193 -232.011474)
		(end 369.770914 -232.010966)
		(stroke
			(width 0.05715)
			(type default)
		)
		(layer "In11.Cu")
	)
	(gr_line
		(start 369.77193 -229.41661)
		(end 369.772438 -229.416356)
		(stroke
			(width 0.05715)
			(type default)
		)
		(layer "In11.Cu")
	)
	(gr_line
		(start 369.772438 -238.491776)
		(end 369.77193 -238.491522)
		(stroke
			(width 0.05715)
			(type default)
		)
		(layer "In11.Cu")
	)
	(gr_line
		(start 369.772692 -246.59209)
		(end 369.77193 -246.591582)
		(stroke
			(width 0.05715)
			(type default)
		)
		(layer "In11.Cu")
	)
	(gr_line
		(start 369.772692 -245.616222)
		(end 369.773962 -245.61546)
		(stroke
			(width 0.05715)
			(type default)
		)
		(layer "In11.Cu")
	)
	(gr_line
		(start 369.772692 -244.972078)
		(end 369.77193 -244.97157)
		(stroke
			(width 0.05715)
			(type default)
		)
		(layer "In11.Cu")
	)
	(gr_line
		(start 369.772692 -243.99621)
		(end 369.773962 -243.995448)
		(stroke
			(width 0.05715)
			(type default)
		)
		(layer "In11.Cu")
	)
	(gr_line
		(start 369.772692 -243.352066)
		(end 369.77193 -243.351558)
		(stroke
			(width 0.05715)
			(type default)
		)
		(layer "In11.Cu")
	)
	(gr_line
		(start 369.772692 -242.376198)
		(end 369.773962 -242.375436)
		(stroke
			(width 0.05715)
			(type default)
		)
		(layer "In11.Cu")
	)
	(gr_line
		(start 369.772692 -241.732054)
		(end 369.77193 -241.731546)
		(stroke
			(width 0.05715)
			(type default)
		)
		(layer "In11.Cu")
	)
	(gr_line
		(start 369.772692 -240.756186)
		(end 369.773962 -240.755424)
		(stroke
			(width 0.05715)
			(type default)
		)
		(layer "In11.Cu")
	)
	(gr_line
		(start 369.772692 -240.112042)
		(end 369.77193 -240.111534)
		(stroke
			(width 0.05715)
			(type default)
		)
		(layer "In11.Cu")
	)
	(gr_line
		(start 369.772692 -239.136174)
		(end 369.773962 -239.135412)
		(stroke
			(width 0.05715)
			(type default)
		)
		(layer "In11.Cu")
	)
	(gr_line
		(start 369.772692 -237.516162)
		(end 369.773962 -237.5154)
		(stroke
			(width 0.05715)
			(type default)
		)
		(layer "In11.Cu")
	)
	(gr_line
		(start 369.772692 -236.872018)
		(end 369.77193 -236.87151)
		(stroke
			(width 0.05715)
			(type default)
		)
		(layer "In11.Cu")
	)
	(gr_line
		(start 369.772692 -235.89615)
		(end 369.773962 -235.895388)
		(stroke
			(width 0.05715)
			(type default)
		)
		(layer "In11.Cu")
	)
	(gr_line
		(start 369.772692 -235.252006)
		(end 369.77193 -235.251498)
		(stroke
			(width 0.05715)
			(type default)
		)
		(layer "In11.Cu")
	)
	(gr_line
		(start 369.772692 -234.276138)
		(end 369.773962 -234.275376)
		(stroke
			(width 0.05715)
			(type default)
		)
		(layer "In11.Cu")
	)
	(gr_line
		(start 369.772692 -233.631994)
		(end 369.77193 -233.631486)
		(stroke
			(width 0.05715)
			(type default)
		)
		(layer "In11.Cu")
	)
	(gr_line
		(start 369.772692 -232.656126)
		(end 369.773962 -232.655364)
		(stroke
			(width 0.05715)
			(type default)
		)
		(layer "In11.Cu")
	)
	(gr_line
		(start 369.772692 -232.011982)
		(end 369.77193 -232.011474)
		(stroke
			(width 0.05715)
			(type default)
		)
		(layer "In11.Cu")
	)
	(gr_line
		(start 369.773962 -246.592852)
		(end 369.772692 -246.59209)
		(stroke
			(width 0.05715)
			(type default)
		)
		(layer "In11.Cu")
	)
	(gr_line
		(start 369.773962 -244.97284)
		(end 369.772692 -244.972078)
		(stroke
			(width 0.05715)
			(type default)
		)
		(layer "In11.Cu")
	)
	(gr_line
		(start 369.773962 -243.352828)
		(end 369.772692 -243.352066)
		(stroke
			(width 0.05715)
			(type default)
		)
		(layer "In11.Cu")
	)
	(gr_line
		(start 369.773962 -241.732816)
		(end 369.772692 -241.732054)
		(stroke
			(width 0.05715)
			(type default)
		)
		(layer "In11.Cu")
	)
	(gr_line
		(start 369.773962 -240.112804)
		(end 369.772692 -240.112042)
		(stroke
			(width 0.05715)
			(type default)
		)
		(layer "In11.Cu")
	)
	(gr_line
		(start 369.773962 -236.87278)
		(end 369.772692 -236.872018)
		(stroke
			(width 0.05715)
			(type default)
		)
		(layer "In11.Cu")
	)
	(gr_line
		(start 369.773962 -235.252768)
		(end 369.772692 -235.252006)
		(stroke
			(width 0.05715)
			(type default)
		)
		(layer "In11.Cu")
	)
	(gr_line
		(start 369.773962 -233.632756)
		(end 369.772692 -233.631994)
		(stroke
			(width 0.05715)
			(type default)
		)
		(layer "In11.Cu")
	)
	(gr_line
		(start 369.773962 -232.012744)
		(end 369.772692 -232.011982)
		(stroke
			(width 0.05715)
			(type default)
		)
		(layer "In11.Cu")
	)
	(gr_line
		(start 369.826032 -296.583862)
		(end 369.826032 -296.61231)
		(stroke
			(width 0.05715)
			(type default)
		)
		(layer "In11.Cu")
	)
	(gr_arc
		(start 369.85194 -295.597834)
		(mid 369.849536 -295.595032)
		(end 369.847114 -295.592246)
		(stroke
			(width 0.05715)
			(type default)
		)
		(layer "In11.Cu")
	)
	(gr_line
		(start 369.86591 -244.162834)
		(end 369.86718 -244.162072)
		(stroke
			(width 0.05715)
			(type default)
		)
		(layer "In11.Cu")
	)
	(gr_line
		(start 369.86591 -240.92281)
		(end 369.86718 -240.922048)
		(stroke
			(width 0.05715)
			(type default)
		)
		(layer "In11.Cu")
	)
	(gr_line
		(start 369.86591 -239.302798)
		(end 369.86718 -239.302036)
		(stroke
			(width 0.05715)
			(type default)
		)
		(layer "In11.Cu")
	)
	(gr_line
		(start 369.86591 -236.062774)
		(end 369.86718 -236.062012)
		(stroke
			(width 0.05715)
			(type default)
		)
		(layer "In11.Cu")
	)
	(gr_line
		(start 369.86591 -234.442762)
		(end 369.86718 -234.442)
		(stroke
			(width 0.05715)
			(type default)
		)
		(layer "In11.Cu")
	)
	(gr_line
		(start 369.86591 -232.82275)
		(end 369.86718 -232.821988)
		(stroke
			(width 0.05715)
			(type default)
		)
		(layer "In11.Cu")
	)
	(gr_line
		(start 369.86718 -246.426228)
		(end 369.86591 -246.425466)
		(stroke
			(width 0.05715)
			(type default)
		)
		(layer "In11.Cu")
	)
	(gr_line
		(start 369.86718 -244.806216)
		(end 369.86591 -244.805454)
		(stroke
			(width 0.05715)
			(type default)
		)
		(layer "In11.Cu")
	)
	(gr_line
		(start 369.86718 -244.162072)
		(end 369.867942 -244.161564)
		(stroke
			(width 0.05715)
			(type default)
		)
		(layer "In11.Cu")
	)
	(gr_line
		(start 369.86718 -243.186204)
		(end 369.86591 -243.185442)
		(stroke
			(width 0.05715)
			(type default)
		)
		(layer "In11.Cu")
	)
	(gr_line
		(start 369.86718 -241.566192)
		(end 369.86591 -241.56543)
		(stroke
			(width 0.05715)
			(type default)
		)
		(layer "In11.Cu")
	)
	(gr_line
		(start 369.86718 -240.922048)
		(end 369.867942 -240.92154)
		(stroke
			(width 0.05715)
			(type default)
		)
		(layer "In11.Cu")
	)
	(gr_line
		(start 369.86718 -239.94618)
		(end 369.86591 -239.945418)
		(stroke
			(width 0.05715)
			(type default)
		)
		(layer "In11.Cu")
	)
	(gr_line
		(start 369.86718 -239.302036)
		(end 369.867942 -239.301528)
		(stroke
			(width 0.05715)
			(type default)
		)
		(layer "In11.Cu")
	)
	(gr_line
		(start 369.86718 -238.326168)
		(end 369.86591 -238.325406)
		(stroke
			(width 0.05715)
			(type default)
		)
		(layer "In11.Cu")
	)
	(gr_line
		(start 369.86718 -236.706156)
		(end 369.86591 -236.705394)
		(stroke
			(width 0.05715)
			(type default)
		)
		(layer "In11.Cu")
	)
	(gr_line
		(start 369.86718 -236.062012)
		(end 369.867942 -236.061504)
		(stroke
			(width 0.05715)
			(type default)
		)
		(layer "In11.Cu")
	)
	(gr_line
		(start 369.86718 -235.086144)
		(end 369.86591 -235.085382)
		(stroke
			(width 0.05715)
			(type default)
		)
		(layer "In11.Cu")
	)
	(gr_line
		(start 369.86718 -234.442)
		(end 369.867942 -234.441492)
		(stroke
			(width 0.05715)
			(type default)
		)
		(layer "In11.Cu")
	)
	(gr_line
		(start 369.86718 -233.466132)
		(end 369.86591 -233.46537)
		(stroke
			(width 0.05715)
			(type default)
		)
		(layer "In11.Cu")
	)
	(gr_line
		(start 369.86718 -232.821988)
		(end 369.867942 -232.82148)
		(stroke
			(width 0.05715)
			(type default)
		)
		(layer "In11.Cu")
	)
	(gr_line
		(start 369.86718 -231.84612)
		(end 369.86591 -231.845358)
		(stroke
			(width 0.05715)
			(type default)
		)
		(layer "In11.Cu")
	)
	(gr_line
		(start 369.867434 -245.78183)
		(end 369.867942 -245.781576)
		(stroke
			(width 0.05715)
			(type default)
		)
		(layer "In11.Cu")
	)
	(gr_line
		(start 369.867434 -242.541806)
		(end 369.867942 -242.541552)
		(stroke
			(width 0.05715)
			(type default)
		)
		(layer "In11.Cu")
	)
	(gr_line
		(start 369.867434 -237.68177)
		(end 369.867942 -237.681516)
		(stroke
			(width 0.05715)
			(type default)
		)
		(layer "In11.Cu")
	)
	(gr_line
		(start 369.867942 -246.426736)
		(end 369.86718 -246.426228)
		(stroke
			(width 0.05715)
			(type default)
		)
		(layer "In11.Cu")
	)
	(gr_line
		(start 369.867942 -245.781576)
		(end 369.868958 -245.781068)
		(stroke
			(width 0.05715)
			(type default)
		)
		(layer "In11.Cu")
	)
	(gr_line
		(start 369.867942 -244.806724)
		(end 369.86718 -244.806216)
		(stroke
			(width 0.05715)
			(type default)
		)
		(layer "In11.Cu")
	)
	(gr_line
		(start 369.867942 -244.161564)
		(end 369.868958 -244.161056)
		(stroke
			(width 0.05715)
			(type default)
		)
		(layer "In11.Cu")
	)
	(gr_line
		(start 369.867942 -243.186712)
		(end 369.86718 -243.186204)
		(stroke
			(width 0.05715)
			(type default)
		)
		(layer "In11.Cu")
	)
	(gr_line
		(start 369.867942 -242.541552)
		(end 369.868958 -242.541044)
		(stroke
			(width 0.05715)
			(type default)
		)
		(layer "In11.Cu")
	)
	(gr_line
		(start 369.867942 -241.5667)
		(end 369.86718 -241.566192)
		(stroke
			(width 0.05715)
			(type default)
		)
		(layer "In11.Cu")
	)
	(gr_line
		(start 369.867942 -240.92154)
		(end 369.868958 -240.921032)
		(stroke
			(width 0.05715)
			(type default)
		)
		(layer "In11.Cu")
	)
	(gr_line
		(start 369.867942 -239.946688)
		(end 369.86718 -239.94618)
		(stroke
			(width 0.05715)
			(type default)
		)
		(layer "In11.Cu")
	)
	(gr_line
		(start 369.867942 -239.301528)
		(end 369.868958 -239.30102)
		(stroke
			(width 0.05715)
			(type default)
		)
		(layer "In11.Cu")
	)
	(gr_line
		(start 369.867942 -237.681516)
		(end 369.868958 -237.681008)
		(stroke
			(width 0.05715)
			(type default)
		)
		(layer "In11.Cu")
	)
	(gr_line
		(start 369.867942 -236.706664)
		(end 369.86718 -236.706156)
		(stroke
			(width 0.05715)
			(type default)
		)
		(layer "In11.Cu")
	)
	(gr_line
		(start 369.867942 -236.061504)
		(end 369.868958 -236.060996)
		(stroke
			(width 0.05715)
			(type default)
		)
		(layer "In11.Cu")
	)
	(gr_line
		(start 369.867942 -235.086652)
		(end 369.86718 -235.086144)
		(stroke
			(width 0.05715)
			(type default)
		)
		(layer "In11.Cu")
	)
	(gr_line
		(start 369.867942 -234.441492)
		(end 369.868958 -234.440984)
		(stroke
			(width 0.05715)
			(type default)
		)
		(layer "In11.Cu")
	)
	(gr_line
		(start 369.867942 -233.46664)
		(end 369.86718 -233.466132)
		(stroke
			(width 0.05715)
			(type default)
		)
		(layer "In11.Cu")
	)
	(gr_line
		(start 369.867942 -232.82148)
		(end 369.868958 -232.820972)
		(stroke
			(width 0.05715)
			(type default)
		)
		(layer "In11.Cu")
	)
	(gr_line
		(start 369.867942 -231.846628)
		(end 369.86718 -231.84612)
		(stroke
			(width 0.05715)
			(type default)
		)
		(layer "In11.Cu")
	)
	(gr_line
		(start 369.868958 -246.427244)
		(end 369.867942 -246.426736)
		(stroke
			(width 0.05715)
			(type default)
		)
		(layer "In11.Cu")
	)
	(gr_line
		(start 369.868958 -244.807232)
		(end 369.867942 -244.806724)
		(stroke
			(width 0.05715)
			(type default)
		)
		(layer "In11.Cu")
	)
	(gr_line
		(start 369.868958 -243.18722)
		(end 369.867942 -243.186712)
		(stroke
			(width 0.05715)
			(type default)
		)
		(layer "In11.Cu")
	)
	(gr_line
		(start 369.868958 -241.567208)
		(end 369.867942 -241.5667)
		(stroke
			(width 0.05715)
			(type default)
		)
		(layer "In11.Cu")
	)
	(gr_line
		(start 369.868958 -239.947196)
		(end 369.867942 -239.946688)
		(stroke
			(width 0.05715)
			(type default)
		)
		(layer "In11.Cu")
	)
	(gr_line
		(start 369.868958 -236.707172)
		(end 369.867942 -236.706664)
		(stroke
			(width 0.05715)
			(type default)
		)
		(layer "In11.Cu")
	)
	(gr_line
		(start 369.868958 -235.08716)
		(end 369.867942 -235.086652)
		(stroke
			(width 0.05715)
			(type default)
		)
		(layer "In11.Cu")
	)
	(gr_line
		(start 369.868958 -233.467148)
		(end 369.867942 -233.46664)
		(stroke
			(width 0.05715)
			(type default)
		)
		(layer "In11.Cu")
	)
	(gr_line
		(start 369.868958 -231.847136)
		(end 369.867942 -231.846628)
		(stroke
			(width 0.05715)
			(type default)
		)
		(layer "In11.Cu")
	)
	(gr_line
		(start 369.871752 -296.538142)
		(end 369.826032 -296.583862)
		(stroke
			(width 0.05715)
			(type default)
		)
		(layer "In11.Cu")
	)
	(gr_line
		(start 369.899946 -229.563168)
		(end 369.904772 -229.560374)
		(stroke
			(width 0.05715)
			(type default)
		)
		(layer "In11.Cu")
	)
	(gr_line
		(start 369.904772 -229.560374)
		(end 369.906804 -229.55885)
		(stroke
			(width 0.05715)
			(type default)
		)
		(layer "In11.Cu")
	)
	(gr_arc
		(start 369.906804 -229.55885)
		(mid 369.91152 -229.555572)
		(end 369.916202 -229.552246)
		(stroke
			(width 0.05715)
			(type default)
		)
		(layer "In11.Cu")
	)
	(gr_arc
		(start 369.98021 -295.955974)
		(mid 369.980225 -295.952037)
		(end 369.98021 -295.9481)
		(stroke
			(width 0.05715)
			(type default)
		)
		(layer "In11.Cu")
	)
	(gr_arc
		(start 370.024914 -294.79494)
		(mid 370.028839 -294.797751)
		(end 370.032788 -294.800528)
		(stroke
			(width 0.05715)
			(type default)
		)
		(layer "In11.Cu")
	)
	(gr_arc
		(start 370.024914 -293.174928)
		(mid 370.028839 -293.177739)
		(end 370.032788 -293.180516)
		(stroke
			(width 0.05715)
			(type default)
		)
		(layer "In11.Cu")
	)
	(gr_arc
		(start 370.024914 -289.934904)
		(mid 370.028839 -289.937715)
		(end 370.032788 -289.940492)
		(stroke
			(width 0.05715)
			(type default)
		)
		(layer "In11.Cu")
	)
	(gr_arc
		(start 370.024914 -281.835098)
		(mid 370.028839 -281.837909)
		(end 370.032788 -281.840686)
		(stroke
			(width 0.05715)
			(type default)
		)
		(layer "In11.Cu")
	)
	(gr_arc
		(start 370.024914 -278.595074)
		(mid 370.028839 -278.597885)
		(end 370.032788 -278.600662)
		(stroke
			(width 0.05715)
			(type default)
		)
		(layer "In11.Cu")
	)
	(gr_arc
		(start 370.024914 -276.975062)
		(mid 370.028839 -276.977873)
		(end 370.032788 -276.98065)
		(stroke
			(width 0.05715)
			(type default)
		)
		(layer "In11.Cu")
	)
	(gr_line
		(start 370.032788 -294.800528)
		(end 370.039646 -294.804592)
		(stroke
			(width 0.05715)
			(type default)
		)
		(layer "In11.Cu")
	)
	(gr_line
		(start 370.032788 -293.180516)
		(end 370.039646 -293.18458)
		(stroke
			(width 0.05715)
			(type default)
		)
		(layer "In11.Cu")
	)
	(gr_line
		(start 370.032788 -289.940492)
		(end 370.039646 -289.944556)
		(stroke
			(width 0.05715)
			(type default)
		)
		(layer "In11.Cu")
	)
	(gr_line
		(start 370.032788 -281.840686)
		(end 370.039646 -281.84475)
		(stroke
			(width 0.05715)
			(type default)
		)
		(layer "In11.Cu")
	)
	(gr_line
		(start 370.032788 -278.600662)
		(end 370.039646 -278.604726)
		(stroke
			(width 0.05715)
			(type default)
		)
		(layer "In11.Cu")
	)
	(gr_line
		(start 370.032788 -276.98065)
		(end 370.039646 -276.984714)
		(stroke
			(width 0.05715)
			(type default)
		)
		(layer "In11.Cu")
	)
	(gr_line
		(start 370.039646 -294.804592)
		(end 370.040408 -294.8051)
		(stroke
			(width 0.05715)
			(type default)
		)
		(layer "In11.Cu")
	)
	(gr_line
		(start 370.039646 -293.18458)
		(end 370.040408 -293.185088)
		(stroke
			(width 0.05715)
			(type default)
		)
		(layer "In11.Cu")
	)
	(gr_line
		(start 370.039646 -289.944556)
		(end 370.040408 -289.945064)
		(stroke
			(width 0.05715)
			(type default)
		)
		(layer "In11.Cu")
	)
	(gr_line
		(start 370.039646 -281.84475)
		(end 370.040408 -281.845258)
		(stroke
			(width 0.05715)
			(type default)
		)
		(layer "In11.Cu")
	)
	(gr_line
		(start 370.039646 -278.604726)
		(end 370.040408 -278.605234)
		(stroke
			(width 0.05715)
			(type default)
		)
		(layer "In11.Cu")
	)
	(gr_line
		(start 370.039646 -276.984714)
		(end 370.040408 -276.985222)
		(stroke
			(width 0.05715)
			(type default)
		)
		(layer "In11.Cu")
	)
	(gr_line
		(start 370.040408 -294.8051)
		(end 370.04117 -294.805608)
		(stroke
			(width 0.05715)
			(type default)
		)
		(layer "In11.Cu")
	)
	(gr_line
		(start 370.040408 -293.185088)
		(end 370.04117 -293.185596)
		(stroke
			(width 0.05715)
			(type default)
		)
		(layer "In11.Cu")
	)
	(gr_line
		(start 370.040408 -289.945064)
		(end 370.04117 -289.945572)
		(stroke
			(width 0.05715)
			(type default)
		)
		(layer "In11.Cu")
	)
	(gr_line
		(start 370.040408 -281.845258)
		(end 370.04117 -281.845766)
		(stroke
			(width 0.05715)
			(type default)
		)
		(layer "In11.Cu")
	)
	(gr_line
		(start 370.040408 -278.605234)
		(end 370.04117 -278.605742)
		(stroke
			(width 0.05715)
			(type default)
		)
		(layer "In11.Cu")
	)
	(gr_line
		(start 370.040408 -276.985222)
		(end 370.04117 -276.98573)
		(stroke
			(width 0.05715)
			(type default)
		)
		(layer "In11.Cu")
	)
	(gr_line
		(start 370.054886 -247.724168)
		(end 370.352828 -247.724168)
		(stroke
			(width 0.05715)
			(type default)
		)
		(layer "In11.Cu")
	)
	(gr_line
		(start 370.054886 -246.104156)
		(end 370.352828 -246.104156)
		(stroke
			(width 0.05715)
			(type default)
		)
		(layer "In11.Cu")
	)
	(gr_line
		(start 370.054886 -244.484144)
		(end 370.352828 -244.484144)
		(stroke
			(width 0.05715)
			(type default)
		)
		(layer "In11.Cu")
	)
	(gr_line
		(start 370.062252 -296.538142)
		(end 370.107972 -296.583862)
		(stroke
			(width 0.05715)
			(type default)
		)
		(layer "In11.Cu")
	)
	(gr_line
		(start 370.065808 -292.23208)
		(end 370.064792 -292.232842)
		(stroke
			(width 0.05715)
			(type default)
		)
		(layer "In11.Cu")
	)
	(gr_line
		(start 370.065808 -290.612068)
		(end 370.064792 -290.61283)
		(stroke
			(width 0.05715)
			(type default)
		)
		(layer "In11.Cu")
	)
	(gr_line
		(start 370.065808 -288.992056)
		(end 370.064792 -288.992818)
		(stroke
			(width 0.05715)
			(type default)
		)
		(layer "In11.Cu")
	)
	(gr_line
		(start 370.065808 -285.752286)
		(end 370.064792 -285.753048)
		(stroke
			(width 0.05715)
			(type default)
		)
		(layer "In11.Cu")
	)
	(gr_line
		(start 370.065808 -284.132274)
		(end 370.064792 -284.133036)
		(stroke
			(width 0.05715)
			(type default)
		)
		(layer "In11.Cu")
	)
	(gr_line
		(start 370.065808 -282.512262)
		(end 370.064792 -282.513024)
		(stroke
			(width 0.05715)
			(type default)
		)
		(layer "In11.Cu")
	)
	(gr_line
		(start 370.065808 -280.89225)
		(end 370.064792 -280.893012)
		(stroke
			(width 0.05715)
			(type default)
		)
		(layer "In11.Cu")
	)
	(gr_line
		(start 370.065808 -277.652226)
		(end 370.064792 -277.652988)
		(stroke
			(width 0.05715)
			(type default)
		)
		(layer "In11.Cu")
	)
	(gr_line
		(start 370.065808 -276.032214)
		(end 370.064792 -276.032976)
		(stroke
			(width 0.05715)
			(type default)
		)
		(layer "In11.Cu")
	)
	(gr_line
		(start 370.067586 -292.231064)
		(end 370.065808 -292.23208)
		(stroke
			(width 0.05715)
			(type default)
		)
		(layer "In11.Cu")
	)
	(gr_line
		(start 370.067586 -290.611052)
		(end 370.065808 -290.612068)
		(stroke
			(width 0.05715)
			(type default)
		)
		(layer "In11.Cu")
	)
	(gr_line
		(start 370.067586 -288.99104)
		(end 370.065808 -288.992056)
		(stroke
			(width 0.05715)
			(type default)
		)
		(layer "In11.Cu")
	)
	(gr_line
		(start 370.067586 -285.75127)
		(end 370.065808 -285.752286)
		(stroke
			(width 0.05715)
			(type default)
		)
		(layer "In11.Cu")
	)
	(gr_line
		(start 370.067586 -284.131258)
		(end 370.065808 -284.132274)
		(stroke
			(width 0.05715)
			(type default)
		)
		(layer "In11.Cu")
	)
	(gr_line
		(start 370.067586 -282.511246)
		(end 370.065808 -282.512262)
		(stroke
			(width 0.05715)
			(type default)
		)
		(layer "In11.Cu")
	)
	(gr_line
		(start 370.067586 -280.891234)
		(end 370.065808 -280.89225)
		(stroke
			(width 0.05715)
			(type default)
		)
		(layer "In11.Cu")
	)
	(gr_line
		(start 370.067586 -277.65121)
		(end 370.065808 -277.652226)
		(stroke
			(width 0.05715)
			(type default)
		)
		(layer "In11.Cu")
	)
	(gr_line
		(start 370.067586 -276.031198)
		(end 370.065808 -276.032214)
		(stroke
			(width 0.05715)
			(type default)
		)
		(layer "In11.Cu")
	)
	(gr_line
		(start 370.070888 -292.229032)
		(end 370.069364 -292.230048)
		(stroke
			(width 0.05715)
			(type default)
		)
		(layer "In11.Cu")
	)
	(gr_line
		(start 370.070888 -290.60902)
		(end 370.069364 -290.610036)
		(stroke
			(width 0.05715)
			(type default)
		)
		(layer "In11.Cu")
	)
	(gr_line
		(start 370.070888 -288.989008)
		(end 370.069364 -288.990024)
		(stroke
			(width 0.05715)
			(type default)
		)
		(layer "In11.Cu")
	)
	(gr_line
		(start 370.070888 -285.749238)
		(end 370.069364 -285.750254)
		(stroke
			(width 0.05715)
			(type default)
		)
		(layer "In11.Cu")
	)
	(gr_line
		(start 370.070888 -284.129226)
		(end 370.069364 -284.130242)
		(stroke
			(width 0.05715)
			(type default)
		)
		(layer "In11.Cu")
	)
	(gr_line
		(start 370.070888 -282.509214)
		(end 370.069364 -282.51023)
		(stroke
			(width 0.05715)
			(type default)
		)
		(layer "In11.Cu")
	)
	(gr_line
		(start 370.070888 -280.889202)
		(end 370.069364 -280.890218)
		(stroke
			(width 0.05715)
			(type default)
		)
		(layer "In11.Cu")
	)
	(gr_line
		(start 370.070888 -277.649178)
		(end 370.069364 -277.650194)
		(stroke
			(width 0.05715)
			(type default)
		)
		(layer "In11.Cu")
	)
	(gr_line
		(start 370.070888 -276.029166)
		(end 370.069364 -276.030182)
		(stroke
			(width 0.05715)
			(type default)
		)
		(layer "In11.Cu")
	)
	(gr_line
		(start 370.071904 -293.848536)
		(end 370.070888 -293.849044)
		(stroke
			(width 0.05715)
			(type default)
		)
		(layer "In11.Cu")
	)
	(gr_line
		(start 370.071904 -292.228524)
		(end 370.070888 -292.229032)
		(stroke
			(width 0.05715)
			(type default)
		)
		(layer "In11.Cu")
	)
	(gr_line
		(start 370.071904 -290.608512)
		(end 370.070888 -290.60902)
		(stroke
			(width 0.05715)
			(type default)
		)
		(layer "In11.Cu")
	)
	(gr_line
		(start 370.071904 -288.9885)
		(end 370.070888 -288.989008)
		(stroke
			(width 0.05715)
			(type default)
		)
		(layer "In11.Cu")
	)
	(gr_line
		(start 370.071904 -285.74873)
		(end 370.070888 -285.749238)
		(stroke
			(width 0.05715)
			(type default)
		)
		(layer "In11.Cu")
	)
	(gr_line
		(start 370.071904 -284.128718)
		(end 370.070888 -284.129226)
		(stroke
			(width 0.05715)
			(type default)
		)
		(layer "In11.Cu")
	)
	(gr_line
		(start 370.071904 -282.508706)
		(end 370.070888 -282.509214)
		(stroke
			(width 0.05715)
			(type default)
		)
		(layer "In11.Cu")
	)
	(gr_line
		(start 370.071904 -280.888694)
		(end 370.070888 -280.889202)
		(stroke
			(width 0.05715)
			(type default)
		)
		(layer "In11.Cu")
	)
	(gr_line
		(start 370.071904 -277.64867)
		(end 370.070888 -277.649178)
		(stroke
			(width 0.05715)
			(type default)
		)
		(layer "In11.Cu")
	)
	(gr_line
		(start 370.071904 -276.028658)
		(end 370.070888 -276.029166)
		(stroke
			(width 0.05715)
			(type default)
		)
		(layer "In11.Cu")
	)
	(gr_line
		(start 370.072158 -294.823642)
		(end 370.072666 -294.823896)
		(stroke
			(width 0.05715)
			(type default)
		)
		(layer "In11.Cu")
	)
	(gr_line
		(start 370.072158 -293.20363)
		(end 370.072666 -293.203884)
		(stroke
			(width 0.05715)
			(type default)
		)
		(layer "In11.Cu")
	)
	(gr_line
		(start 370.072158 -289.963606)
		(end 370.072666 -289.96386)
		(stroke
			(width 0.05715)
			(type default)
		)
		(layer "In11.Cu")
	)
	(gr_line
		(start 370.072158 -281.8638)
		(end 370.072666 -281.864054)
		(stroke
			(width 0.05715)
			(type default)
		)
		(layer "In11.Cu")
	)
	(gr_line
		(start 370.072158 -278.623776)
		(end 370.072666 -278.62403)
		(stroke
			(width 0.05715)
			(type default)
		)
		(layer "In11.Cu")
	)
	(gr_line
		(start 370.072158 -277.003764)
		(end 370.072666 -277.004018)
		(stroke
			(width 0.05715)
			(type default)
		)
		(layer "In11.Cu")
	)
	(gr_line
		(start 370.072412 -293.848282)
		(end 370.071904 -293.848536)
		(stroke
			(width 0.05715)
			(type default)
		)
		(layer "In11.Cu")
	)
	(gr_line
		(start 370.072412 -292.22827)
		(end 370.071904 -292.228524)
		(stroke
			(width 0.05715)
			(type default)
		)
		(layer "In11.Cu")
	)
	(gr_line
		(start 370.072412 -290.608258)
		(end 370.071904 -290.608512)
		(stroke
			(width 0.05715)
			(type default)
		)
		(layer "In11.Cu")
	)
	(gr_line
		(start 370.072412 -288.988246)
		(end 370.071904 -288.9885)
		(stroke
			(width 0.05715)
			(type default)
		)
		(layer "In11.Cu")
	)
	(gr_line
		(start 370.072412 -285.748476)
		(end 370.071904 -285.74873)
		(stroke
			(width 0.05715)
			(type default)
		)
		(layer "In11.Cu")
	)
	(gr_line
		(start 370.072412 -284.128464)
		(end 370.071904 -284.128718)
		(stroke
			(width 0.05715)
			(type default)
		)
		(layer "In11.Cu")
	)
	(gr_line
		(start 370.072412 -282.508452)
		(end 370.071904 -282.508706)
		(stroke
			(width 0.05715)
			(type default)
		)
		(layer "In11.Cu")
	)
	(gr_line
		(start 370.072412 -280.88844)
		(end 370.071904 -280.888694)
		(stroke
			(width 0.05715)
			(type default)
		)
		(layer "In11.Cu")
	)
	(gr_line
		(start 370.072412 -277.648416)
		(end 370.071904 -277.64867)
		(stroke
			(width 0.05715)
			(type default)
		)
		(layer "In11.Cu")
	)
	(gr_line
		(start 370.072412 -276.028404)
		(end 370.071904 -276.028658)
		(stroke
			(width 0.05715)
			(type default)
		)
		(layer "In11.Cu")
	)
	(gr_line
		(start 370.072666 -294.823896)
		(end 370.073936 -294.824658)
		(stroke
			(width 0.05715)
			(type default)
		)
		(layer "In11.Cu")
	)
	(gr_line
		(start 370.072666 -293.203884)
		(end 370.073936 -293.204646)
		(stroke
			(width 0.05715)
			(type default)
		)
		(layer "In11.Cu")
	)
	(gr_line
		(start 370.072666 -291.583872)
		(end 370.073936 -291.584634)
		(stroke
			(width 0.05715)
			(type default)
		)
		(layer "In11.Cu")
	)
	(gr_line
		(start 370.072666 -289.96386)
		(end 370.073936 -289.964622)
		(stroke
			(width 0.05715)
			(type default)
		)
		(layer "In11.Cu")
	)
	(gr_line
		(start 370.072666 -285.104078)
		(end 370.073936 -285.10484)
		(stroke
			(width 0.05715)
			(type default)
		)
		(layer "In11.Cu")
	)
	(gr_line
		(start 370.072666 -283.484066)
		(end 370.073936 -283.484828)
		(stroke
			(width 0.05715)
			(type default)
		)
		(layer "In11.Cu")
	)
	(gr_line
		(start 370.072666 -281.864054)
		(end 370.073936 -281.864816)
		(stroke
			(width 0.05715)
			(type default)
		)
		(layer "In11.Cu")
	)
	(gr_line
		(start 370.072666 -278.62403)
		(end 370.073936 -278.624792)
		(stroke
			(width 0.05715)
			(type default)
		)
		(layer "In11.Cu")
	)
	(gr_line
		(start 370.072666 -277.004018)
		(end 370.073936 -277.00478)
		(stroke
			(width 0.05715)
			(type default)
		)
		(layer "In11.Cu")
	)
	(gr_line
		(start 370.073936 -294.824658)
		(end 370.07546 -294.82542)
		(stroke
			(width 0.05715)
			(type default)
		)
		(layer "In11.Cu")
	)
	(gr_line
		(start 370.073936 -293.204646)
		(end 370.07546 -293.205408)
		(stroke
			(width 0.05715)
			(type default)
		)
		(layer "In11.Cu")
	)
	(gr_line
		(start 370.073936 -289.964622)
		(end 370.07546 -289.965384)
		(stroke
			(width 0.05715)
			(type default)
		)
		(layer "In11.Cu")
	)
	(gr_line
		(start 370.073936 -281.864816)
		(end 370.07546 -281.865578)
		(stroke
			(width 0.05715)
			(type default)
		)
		(layer "In11.Cu")
	)
	(gr_line
		(start 370.073936 -278.624792)
		(end 370.07546 -278.625554)
		(stroke
			(width 0.05715)
			(type default)
		)
		(layer "In11.Cu")
	)
	(gr_line
		(start 370.073936 -277.00478)
		(end 370.07546 -277.005542)
		(stroke
			(width 0.05715)
			(type default)
		)
		(layer "In11.Cu")
	)
	(gr_line
		(start 370.107972 -296.583862)
		(end 370.107972 -296.61231)
		(stroke
			(width 0.05715)
			(type default)
		)
		(layer "In11.Cu")
	)
	(gr_line
		(start 370.163598 -292.39591)
		(end 370.162074 -292.396672)
		(stroke
			(width 0.05715)
			(type default)
		)
		(layer "In11.Cu")
	)
	(gr_line
		(start 370.163598 -290.775898)
		(end 370.162074 -290.77666)
		(stroke
			(width 0.05715)
			(type default)
		)
		(layer "In11.Cu")
	)
	(gr_line
		(start 370.163598 -289.155886)
		(end 370.162074 -289.156648)
		(stroke
			(width 0.05715)
			(type default)
		)
		(layer "In11.Cu")
	)
	(gr_line
		(start 370.163598 -285.916116)
		(end 370.162074 -285.916878)
		(stroke
			(width 0.05715)
			(type default)
		)
		(layer "In11.Cu")
	)
	(gr_line
		(start 370.163598 -284.296104)
		(end 370.162074 -284.296866)
		(stroke
			(width 0.05715)
			(type default)
		)
		(layer "In11.Cu")
	)
	(gr_line
		(start 370.163598 -282.676092)
		(end 370.162074 -282.676854)
		(stroke
			(width 0.05715)
			(type default)
		)
		(layer "In11.Cu")
	)
	(gr_line
		(start 370.163598 -281.05608)
		(end 370.162074 -281.056842)
		(stroke
			(width 0.05715)
			(type default)
		)
		(layer "In11.Cu")
	)
	(gr_line
		(start 370.163598 -277.816056)
		(end 370.162074 -277.816818)
		(stroke
			(width 0.05715)
			(type default)
		)
		(layer "In11.Cu")
	)
	(gr_line
		(start 370.163598 -276.196044)
		(end 370.162074 -276.196806)
		(stroke
			(width 0.05715)
			(type default)
		)
		(layer "In11.Cu")
	)
	(gr_line
		(start 370.16436 -292.395402)
		(end 370.163598 -292.39591)
		(stroke
			(width 0.05715)
			(type default)
		)
		(layer "In11.Cu")
	)
	(gr_line
		(start 370.16436 -290.77539)
		(end 370.163598 -290.775898)
		(stroke
			(width 0.05715)
			(type default)
		)
		(layer "In11.Cu")
	)
	(gr_line
		(start 370.16436 -289.155378)
		(end 370.163598 -289.155886)
		(stroke
			(width 0.05715)
			(type default)
		)
		(layer "In11.Cu")
	)
	(gr_line
		(start 370.16436 -285.915608)
		(end 370.163598 -285.916116)
		(stroke
			(width 0.05715)
			(type default)
		)
		(layer "In11.Cu")
	)
	(gr_line
		(start 370.16436 -284.295596)
		(end 370.163598 -284.296104)
		(stroke
			(width 0.05715)
			(type default)
		)
		(layer "In11.Cu")
	)
	(gr_line
		(start 370.16436 -282.675584)
		(end 370.163598 -282.676092)
		(stroke
			(width 0.05715)
			(type default)
		)
		(layer "In11.Cu")
	)
	(gr_line
		(start 370.16436 -281.055572)
		(end 370.163598 -281.05608)
		(stroke
			(width 0.05715)
			(type default)
		)
		(layer "In11.Cu")
	)
	(gr_line
		(start 370.16436 -277.815548)
		(end 370.163598 -277.816056)
		(stroke
			(width 0.05715)
			(type default)
		)
		(layer "In11.Cu")
	)
	(gr_line
		(start 370.16436 -276.195536)
		(end 370.163598 -276.196044)
		(stroke
			(width 0.05715)
			(type default)
		)
		(layer "In11.Cu")
	)
	(gr_line
		(start 370.165884 -292.39464)
		(end 370.16436 -292.395402)
		(stroke
			(width 0.05715)
			(type default)
		)
		(layer "In11.Cu")
	)
	(gr_line
		(start 370.165884 -290.774628)
		(end 370.16436 -290.77539)
		(stroke
			(width 0.05715)
			(type default)
		)
		(layer "In11.Cu")
	)
	(gr_line
		(start 370.165884 -289.154616)
		(end 370.16436 -289.155378)
		(stroke
			(width 0.05715)
			(type default)
		)
		(layer "In11.Cu")
	)
	(gr_line
		(start 370.165884 -285.914846)
		(end 370.16436 -285.915608)
		(stroke
			(width 0.05715)
			(type default)
		)
		(layer "In11.Cu")
	)
	(gr_line
		(start 370.165884 -284.294834)
		(end 370.16436 -284.295596)
		(stroke
			(width 0.05715)
			(type default)
		)
		(layer "In11.Cu")
	)
	(gr_line
		(start 370.165884 -282.674822)
		(end 370.16436 -282.675584)
		(stroke
			(width 0.05715)
			(type default)
		)
		(layer "In11.Cu")
	)
	(gr_line
		(start 370.165884 -281.05481)
		(end 370.16436 -281.055572)
		(stroke
			(width 0.05715)
			(type default)
		)
		(layer "In11.Cu")
	)
	(gr_line
		(start 370.165884 -277.814786)
		(end 370.16436 -277.815548)
		(stroke
			(width 0.05715)
			(type default)
		)
		(layer "In11.Cu")
	)
	(gr_line
		(start 370.165884 -276.194774)
		(end 370.16436 -276.195536)
		(stroke
			(width 0.05715)
			(type default)
		)
		(layer "In11.Cu")
	)
	(gr_line
		(start 370.167154 -294.01389)
		(end 370.165884 -294.014652)
		(stroke
			(width 0.05715)
			(type default)
		)
		(layer "In11.Cu")
	)
	(gr_line
		(start 370.167154 -292.393878)
		(end 370.165884 -292.39464)
		(stroke
			(width 0.05715)
			(type default)
		)
		(layer "In11.Cu")
	)
	(gr_line
		(start 370.167154 -290.773866)
		(end 370.165884 -290.774628)
		(stroke
			(width 0.05715)
			(type default)
		)
		(layer "In11.Cu")
	)
	(gr_line
		(start 370.167154 -289.153854)
		(end 370.165884 -289.154616)
		(stroke
			(width 0.05715)
			(type default)
		)
		(layer "In11.Cu")
	)
	(gr_line
		(start 370.167154 -285.914084)
		(end 370.165884 -285.914846)
		(stroke
			(width 0.05715)
			(type default)
		)
		(layer "In11.Cu")
	)
	(gr_line
		(start 370.167154 -284.294072)
		(end 370.165884 -284.294834)
		(stroke
			(width 0.05715)
			(type default)
		)
		(layer "In11.Cu")
	)
	(gr_line
		(start 370.167154 -282.67406)
		(end 370.165884 -282.674822)
		(stroke
			(width 0.05715)
			(type default)
		)
		(layer "In11.Cu")
	)
	(gr_line
		(start 370.167154 -281.054048)
		(end 370.165884 -281.05481)
		(stroke
			(width 0.05715)
			(type default)
		)
		(layer "In11.Cu")
	)
	(gr_line
		(start 370.167154 -277.814024)
		(end 370.165884 -277.814786)
		(stroke
			(width 0.05715)
			(type default)
		)
		(layer "In11.Cu")
	)
	(gr_line
		(start 370.167154 -276.194012)
		(end 370.165884 -276.194774)
		(stroke
			(width 0.05715)
			(type default)
		)
		(layer "In11.Cu")
	)
	(gr_line
		(start 370.167408 -291.418264)
		(end 370.167916 -291.418518)
		(stroke
			(width 0.05715)
			(type default)
		)
		(layer "In11.Cu")
	)
	(gr_line
		(start 370.167408 -284.93847)
		(end 370.167916 -284.938724)
		(stroke
			(width 0.05715)
			(type default)
		)
		(layer "In11.Cu")
	)
	(gr_line
		(start 370.167408 -283.318458)
		(end 370.167916 -283.318712)
		(stroke
			(width 0.05715)
			(type default)
		)
		(layer "In11.Cu")
	)
	(gr_line
		(start 370.167916 -294.658542)
		(end 370.168932 -294.65905)
		(stroke
			(width 0.05715)
			(type default)
		)
		(layer "In11.Cu")
	)
	(gr_line
		(start 370.167916 -293.03853)
		(end 370.168932 -293.039038)
		(stroke
			(width 0.05715)
			(type default)
		)
		(layer "In11.Cu")
	)
	(gr_line
		(start 370.167916 -292.39337)
		(end 370.167154 -292.393878)
		(stroke
			(width 0.05715)
			(type default)
		)
		(layer "In11.Cu")
	)
	(gr_line
		(start 370.167916 -291.418518)
		(end 370.168932 -291.419026)
		(stroke
			(width 0.05715)
			(type default)
		)
		(layer "In11.Cu")
	)
	(gr_line
		(start 370.167916 -290.773358)
		(end 370.167154 -290.773866)
		(stroke
			(width 0.05715)
			(type default)
		)
		(layer "In11.Cu")
	)
	(gr_line
		(start 370.167916 -289.798506)
		(end 370.168932 -289.799014)
		(stroke
			(width 0.05715)
			(type default)
		)
		(layer "In11.Cu")
	)
	(gr_line
		(start 370.167916 -289.153346)
		(end 370.167154 -289.153854)
		(stroke
			(width 0.05715)
			(type default)
		)
		(layer "In11.Cu")
	)
	(gr_line
		(start 370.167916 -285.913576)
		(end 370.167154 -285.914084)
		(stroke
			(width 0.05715)
			(type default)
		)
		(layer "In11.Cu")
	)
	(gr_line
		(start 370.167916 -284.938724)
		(end 370.168932 -284.939232)
		(stroke
			(width 0.05715)
			(type default)
		)
		(layer "In11.Cu")
	)
	(gr_line
		(start 370.167916 -284.293564)
		(end 370.167154 -284.294072)
		(stroke
			(width 0.05715)
			(type default)
		)
		(layer "In11.Cu")
	)
	(gr_line
		(start 370.167916 -283.318712)
		(end 370.168932 -283.31922)
		(stroke
			(width 0.05715)
			(type default)
		)
		(layer "In11.Cu")
	)
	(gr_line
		(start 370.167916 -282.673552)
		(end 370.167154 -282.67406)
		(stroke
			(width 0.05715)
			(type default)
		)
		(layer "In11.Cu")
	)
	(gr_line
		(start 370.167916 -281.6987)
		(end 370.168932 -281.699208)
		(stroke
			(width 0.05715)
			(type default)
		)
		(layer "In11.Cu")
	)
	(gr_line
		(start 370.167916 -281.05354)
		(end 370.167154 -281.054048)
		(stroke
			(width 0.05715)
			(type default)
		)
		(layer "In11.Cu")
	)
	(gr_line
		(start 370.167916 -278.458676)
		(end 370.168932 -278.459184)
		(stroke
			(width 0.05715)
			(type default)
		)
		(layer "In11.Cu")
	)
	(gr_line
		(start 370.167916 -277.813516)
		(end 370.167154 -277.814024)
		(stroke
			(width 0.05715)
			(type default)
		)
		(layer "In11.Cu")
	)
	(gr_line
		(start 370.167916 -276.838664)
		(end 370.168932 -276.839172)
		(stroke
			(width 0.05715)
			(type default)
		)
		(layer "In11.Cu")
	)
	(gr_line
		(start 370.167916 -276.193504)
		(end 370.167154 -276.194012)
		(stroke
			(width 0.05715)
			(type default)
		)
		(layer "In11.Cu")
	)
	(gr_line
		(start 370.168932 -294.65905)
		(end 370.170456 -294.660066)
		(stroke
			(width 0.05715)
			(type default)
		)
		(layer "In11.Cu")
	)
	(gr_line
		(start 370.168932 -293.039038)
		(end 370.170456 -293.040054)
		(stroke
			(width 0.05715)
			(type default)
		)
		(layer "In11.Cu")
	)
	(gr_line
		(start 370.168932 -292.392862)
		(end 370.167916 -292.39337)
		(stroke
			(width 0.05715)
			(type default)
		)
		(layer "In11.Cu")
	)
	(gr_line
		(start 370.168932 -290.77285)
		(end 370.167916 -290.773358)
		(stroke
			(width 0.05715)
			(type default)
		)
		(layer "In11.Cu")
	)
	(gr_line
		(start 370.168932 -289.799014)
		(end 370.170456 -289.80003)
		(stroke
			(width 0.05715)
			(type default)
		)
		(layer "In11.Cu")
	)
	(gr_line
		(start 370.168932 -289.152838)
		(end 370.167916 -289.153346)
		(stroke
			(width 0.05715)
			(type default)
		)
		(layer "In11.Cu")
	)
	(gr_line
		(start 370.168932 -285.913068)
		(end 370.167916 -285.913576)
		(stroke
			(width 0.05715)
			(type default)
		)
		(layer "In11.Cu")
	)
	(gr_line
		(start 370.168932 -284.293056)
		(end 370.167916 -284.293564)
		(stroke
			(width 0.05715)
			(type default)
		)
		(layer "In11.Cu")
	)
	(gr_line
		(start 370.168932 -282.673044)
		(end 370.167916 -282.673552)
		(stroke
			(width 0.05715)
			(type default)
		)
		(layer "In11.Cu")
	)
	(gr_line
		(start 370.168932 -281.699208)
		(end 370.170456 -281.700224)
		(stroke
			(width 0.05715)
			(type default)
		)
		(layer "In11.Cu")
	)
	(gr_line
		(start 370.168932 -281.053032)
		(end 370.167916 -281.05354)
		(stroke
			(width 0.05715)
			(type default)
		)
		(layer "In11.Cu")
	)
	(gr_line
		(start 370.168932 -278.459184)
		(end 370.170456 -278.4602)
		(stroke
			(width 0.05715)
			(type default)
		)
		(layer "In11.Cu")
	)
	(gr_line
		(start 370.168932 -277.813008)
		(end 370.167916 -277.813516)
		(stroke
			(width 0.05715)
			(type default)
		)
		(layer "In11.Cu")
	)
	(gr_line
		(start 370.168932 -276.839172)
		(end 370.170456 -276.840188)
		(stroke
			(width 0.05715)
			(type default)
		)
		(layer "In11.Cu")
	)
	(gr_line
		(start 370.168932 -276.192996)
		(end 370.167916 -276.193504)
		(stroke
			(width 0.05715)
			(type default)
		)
		(layer "In11.Cu")
	)
	(gr_line
		(start 370.172234 -294.661082)
		(end 370.173504 -294.661844)
		(stroke
			(width 0.05715)
			(type default)
		)
		(layer "In11.Cu")
	)
	(gr_line
		(start 370.172234 -293.04107)
		(end 370.173504 -293.041832)
		(stroke
			(width 0.05715)
			(type default)
		)
		(layer "In11.Cu")
	)
	(gr_line
		(start 370.172234 -289.801046)
		(end 370.173504 -289.801808)
		(stroke
			(width 0.05715)
			(type default)
		)
		(layer "In11.Cu")
	)
	(gr_line
		(start 370.172234 -281.70124)
		(end 370.173504 -281.702002)
		(stroke
			(width 0.05715)
			(type default)
		)
		(layer "In11.Cu")
	)
	(gr_line
		(start 370.172234 -278.461216)
		(end 370.173504 -278.461978)
		(stroke
			(width 0.05715)
			(type default)
		)
		(layer "In11.Cu")
	)
	(gr_line
		(start 370.172234 -276.841204)
		(end 370.173504 -276.841966)
		(stroke
			(width 0.05715)
			(type default)
		)
		(layer "In11.Cu")
	)
	(gr_line
		(start 370.174774 -294.662606)
		(end 370.176552 -294.663622)
		(stroke
			(width 0.05715)
			(type default)
		)
		(layer "In11.Cu")
	)
	(gr_line
		(start 370.174774 -293.042594)
		(end 370.176552 -293.04361)
		(stroke
			(width 0.05715)
			(type default)
		)
		(layer "In11.Cu")
	)
	(gr_line
		(start 370.174774 -289.80257)
		(end 370.176552 -289.803586)
		(stroke
			(width 0.05715)
			(type default)
		)
		(layer "In11.Cu")
	)
	(gr_line
		(start 370.174774 -281.702764)
		(end 370.176552 -281.70378)
		(stroke
			(width 0.05715)
			(type default)
		)
		(layer "In11.Cu")
	)
	(gr_line
		(start 370.174774 -278.46274)
		(end 370.176552 -278.463756)
		(stroke
			(width 0.05715)
			(type default)
		)
		(layer "In11.Cu")
	)
	(gr_line
		(start 370.174774 -276.842728)
		(end 370.176552 -276.843744)
		(stroke
			(width 0.05715)
			(type default)
		)
		(layer "In11.Cu")
	)
	(gr_line
		(start 370.240814 -225.367342)
		(end 370.24183 -225.366834)
		(stroke
			(width 0.05715)
			(type default)
		)
		(layer "In11.Cu")
	)
	(gr_line
		(start 370.24183 -225.366834)
		(end 370.242592 -225.366326)
		(stroke
			(width 0.05715)
			(type default)
		)
		(layer "In11.Cu")
	)
	(gr_line
		(start 370.25961 -295.145968)
		(end 370.259356 -295.145968)
		(stroke
			(width 0.05715)
			(type default)
		)
		(layer "In11.Cu")
	)
	(gr_line
		(start 370.273072 -222.108776)
		(end 370.272818 -222.108776)
		(stroke
			(width 0.05715)
			(type default)
		)
		(layer "In11.Cu")
	)
	(gr_line
		(start 370.33581 -225.53295)
		(end 370.33708 -225.532188)
		(stroke
			(width 0.05715)
			(type default)
		)
		(layer "In11.Cu")
	)
	(gr_line
		(start 370.33708 -225.532188)
		(end 370.337842 -225.53168)
		(stroke
			(width 0.05715)
			(type default)
		)
		(layer "In11.Cu")
	)
	(gr_line
		(start 370.337842 -225.53168)
		(end 370.338858 -225.531172)
		(stroke
			(width 0.05715)
			(type default)
		)
		(layer "In11.Cu")
	)
	(gr_line
		(start 370.338858 -225.531172)
		(end 370.34089 -225.530156)
		(stroke
			(width 0.05715)
			(type default)
		)
		(layer "In11.Cu")
	)
	(gr_line
		(start 370.352828 -247.724168)
		(end 370.42217 -247.654826)
		(stroke
			(width 0.05715)
			(type default)
		)
		(layer "In11.Cu")
	)
	(gr_line
		(start 370.352828 -246.104156)
		(end 370.435632 -246.021352)
		(stroke
			(width 0.05715)
			(type default)
		)
		(layer "In11.Cu")
	)
	(gr_line
		(start 370.352828 -244.484144)
		(end 370.435632 -244.40134)
		(stroke
			(width 0.05715)
			(type default)
		)
		(layer "In11.Cu")
	)
	(gr_line
		(start 370.35486 -278.136096)
		(end 370.652802 -278.136096)
		(stroke
			(width 0.05715)
			(type default)
		)
		(layer "In11.Cu")
	)
	(gr_line
		(start 370.35486 -276.516084)
		(end 370.652802 -276.516084)
		(stroke
			(width 0.05715)
			(type default)
		)
		(layer "In11.Cu")
	)
	(gr_line
		(start 370.35486 -274.896072)
		(end 370.652802 -274.896072)
		(stroke
			(width 0.05715)
			(type default)
		)
		(layer "In11.Cu")
	)
	(gr_line
		(start 370.36883 -222.273622)
		(end 370.374164 -222.270574)
		(stroke
			(width 0.05715)
			(type default)
		)
		(layer "In11.Cu")
	)
	(gr_line
		(start 370.369338 -225.513392)
		(end 370.3701 -225.512884)
		(stroke
			(width 0.05715)
			(type default)
		)
		(layer "In11.Cu")
	)
	(gr_line
		(start 370.3701 -225.512884)
		(end 370.376958 -225.50882)
		(stroke
			(width 0.05715)
			(type default)
		)
		(layer "In11.Cu")
	)
	(gr_line
		(start 370.374164 -222.270574)
		(end 370.37518 -222.270066)
		(stroke
			(width 0.05715)
			(type default)
		)
		(layer "In11.Cu")
	)
	(gr_line
		(start 370.37518 -222.270066)
		(end 370.376196 -222.269304)
		(stroke
			(width 0.05715)
			(type default)
		)
		(layer "In11.Cu")
	)
	(gr_arc
		(start 370.376196 -222.269304)
		(mid 370.380145 -222.266527)
		(end 370.38407 -222.263716)
		(stroke
			(width 0.05715)
			(type default)
		)
		(layer "In11.Cu")
	)
	(gr_arc
		(start 370.376958 -225.50882)
		(mid 370.380907 -225.506043)
		(end 370.384832 -225.503232)
		(stroke
			(width 0.05715)
			(type default)
		)
		(layer "In11.Cu")
	)
	(gr_line
		(start 370.414804 -221.083124)
		(end 370.414804 -221.054676)
		(stroke
			(width 0.05715)
			(type default)
		)
		(layer "In11.Cu")
	)
	(gr_arc
		(start 370.439442 -245.998492)
		(mid 370.437421 -246.009903)
		(end 370.435632 -246.021352)
		(stroke
			(width 0.05715)
			(type default)
		)
		(layer "In11.Cu")
	)
	(gr_arc
		(start 370.439442 -244.37848)
		(mid 370.43742 -244.389891)
		(end 370.435632 -244.40134)
		(stroke
			(width 0.05715)
			(type default)
		)
		(layer "In11.Cu")
	)
	(gr_line
		(start 370.450364 -295.145968)
		(end 370.45011 -295.145968)
		(stroke
			(width 0.05715)
			(type default)
		)
		(layer "In11.Cu")
	)
	(gr_line
		(start 370.460524 -221.128844)
		(end 370.414804 -221.083124)
		(stroke
			(width 0.05715)
			(type default)
		)
		(layer "In11.Cu")
	)
	(gr_line
		(start 370.542566 -295.633902)
		(end 370.54536 -295.635426)
		(stroke
			(width 0.05715)
			(type default)
		)
		(layer "In11.Cu")
	)
	(gr_arc
		(start 370.614194 -247.641364)
		(mid 370.612408 -247.629914)
		(end 370.610384 -247.618504)
		(stroke
			(width 0.05715)
			(type default)
		)
		(layer "In11.Cu")
	)
	(gr_line
		(start 370.637308 -295.468294)
		(end 370.637816 -295.468548)
		(stroke
			(width 0.05715)
			(type default)
		)
		(layer "In11.Cu")
	)
	(gr_line
		(start 370.637816 -295.468548)
		(end 370.638832 -295.469056)
		(stroke
			(width 0.05715)
			(type default)
		)
		(layer "In11.Cu")
	)
	(gr_line
		(start 370.638832 -295.469056)
		(end 370.640356 -295.470072)
		(stroke
			(width 0.05715)
			(type default)
		)
		(layer "In11.Cu")
	)
	(gr_line
		(start 370.640356 -295.470072)
		(end 370.641372 -295.47058)
		(stroke
			(width 0.05715)
			(type default)
		)
		(layer "In11.Cu")
	)
	(gr_line
		(start 370.641372 -295.47058)
		(end 370.646452 -295.473628)
		(stroke
			(width 0.05715)
			(type default)
		)
		(layer "In11.Cu")
	)
	(gr_line
		(start 370.651024 -221.128844)
		(end 370.696744 -221.083124)
		(stroke
			(width 0.05715)
			(type default)
		)
		(layer "In11.Cu")
	)
	(gr_line
		(start 370.652802 -278.136096)
		(end 370.735606 -278.2189)
		(stroke
			(width 0.05715)
			(type default)
		)
		(layer "In11.Cu")
	)
	(gr_line
		(start 370.652802 -276.516084)
		(end 370.735606 -276.598888)
		(stroke
			(width 0.05715)
			(type default)
		)
		(layer "In11.Cu")
	)
	(gr_line
		(start 370.652802 -274.896072)
		(end 370.722144 -274.965414)
		(stroke
			(width 0.05715)
			(type default)
		)
		(layer "In11.Cu")
	)
	(gr_arc
		(start 370.664994 -230.363014)
		(mid 370.67018 -230.366727)
		(end 370.675408 -230.37038)
		(stroke
			(width 0.05715)
			(type default)
		)
		(layer "In11.Cu")
	)
	(gr_arc
		(start 370.664994 -227.123244)
		(mid 370.668919 -227.126055)
		(end 370.672868 -227.128832)
		(stroke
			(width 0.05715)
			(type default)
		)
		(layer "In11.Cu")
	)
	(gr_arc
		(start 370.66855 -229.442518)
		(mid 370.665368 -229.444794)
		(end 370.6622 -229.44709)
		(stroke
			(width 0.05715)
			(type default)
		)
		(layer "In11.Cu")
	)
	(gr_arc
		(start 370.671344 -224.580704)
		(mid 370.668926 -224.582476)
		(end 370.666518 -224.58426)
		(stroke
			(width 0.05715)
			(type default)
		)
		(layer "In11.Cu")
	)
	(gr_arc
		(start 370.672868 -245.63959)
		(mid 370.668792 -245.642366)
		(end 370.66474 -245.645178)
		(stroke
			(width 0.05715)
			(type default)
		)
		(layer "In11.Cu")
	)
	(gr_arc
		(start 370.672868 -245.63959)
		(mid 370.673249 -245.639336)
		(end 370.67363 -245.639082)
		(stroke
			(width 0.05715)
			(type default)
		)
		(layer "In11.Cu")
	)
	(gr_arc
		(start 370.672868 -242.399566)
		(mid 370.668919 -242.402343)
		(end 370.664994 -242.405154)
		(stroke
			(width 0.05715)
			(type default)
		)
		(layer "In11.Cu")
	)
	(gr_arc
		(start 370.672868 -242.399566)
		(mid 370.673249 -242.399312)
		(end 370.67363 -242.399058)
		(stroke
			(width 0.05715)
			(type default)
		)
		(layer "In11.Cu")
	)
	(gr_arc
		(start 370.672868 -240.779554)
		(mid 370.668919 -240.782331)
		(end 370.664994 -240.785142)
		(stroke
			(width 0.05715)
			(type default)
		)
		(layer "In11.Cu")
	)
	(gr_arc
		(start 370.672868 -240.779554)
		(mid 370.673249 -240.7793)
		(end 370.67363 -240.779046)
		(stroke
			(width 0.05715)
			(type default)
		)
		(layer "In11.Cu")
	)
	(gr_arc
		(start 370.672868 -239.159542)
		(mid 370.668919 -239.162319)
		(end 370.664994 -239.16513)
		(stroke
			(width 0.05715)
			(type default)
		)
		(layer "In11.Cu")
	)
	(gr_arc
		(start 370.672868 -239.159542)
		(mid 370.673249 -239.159288)
		(end 370.67363 -239.159034)
		(stroke
			(width 0.05715)
			(type default)
		)
		(layer "In11.Cu")
	)
	(gr_arc
		(start 370.672868 -237.53953)
		(mid 370.668919 -237.542307)
		(end 370.664994 -237.545118)
		(stroke
			(width 0.05715)
			(type default)
		)
		(layer "In11.Cu")
	)
	(gr_arc
		(start 370.672868 -237.53953)
		(mid 370.673249 -237.539276)
		(end 370.67363 -237.539022)
		(stroke
			(width 0.05715)
			(type default)
		)
		(layer "In11.Cu")
	)
	(gr_arc
		(start 370.672868 -235.919518)
		(mid 370.668919 -235.922295)
		(end 370.664994 -235.925106)
		(stroke
			(width 0.05715)
			(type default)
		)
		(layer "In11.Cu")
	)
	(gr_arc
		(start 370.672868 -235.919518)
		(mid 370.673249 -235.919264)
		(end 370.67363 -235.91901)
		(stroke
			(width 0.05715)
			(type default)
		)
		(layer "In11.Cu")
	)
	(gr_arc
		(start 370.672868 -234.299506)
		(mid 370.668919 -234.302283)
		(end 370.664994 -234.305094)
		(stroke
			(width 0.05715)
			(type default)
		)
		(layer "In11.Cu")
	)
	(gr_arc
		(start 370.672868 -234.299506)
		(mid 370.673249 -234.299252)
		(end 370.67363 -234.298998)
		(stroke
			(width 0.05715)
			(type default)
		)
		(layer "In11.Cu")
	)
	(gr_line
		(start 370.67363 -245.639082)
		(end 370.68125 -245.634764)
		(stroke
			(width 0.05715)
			(type default)
		)
		(layer "In11.Cu")
	)
	(gr_line
		(start 370.67363 -242.399058)
		(end 370.681504 -242.394486)
		(stroke
			(width 0.05715)
			(type default)
		)
		(layer "In11.Cu")
	)
	(gr_line
		(start 370.67363 -240.779046)
		(end 370.681504 -240.774474)
		(stroke
			(width 0.05715)
			(type default)
		)
		(layer "In11.Cu")
	)
	(gr_line
		(start 370.67363 -239.159034)
		(end 370.681504 -239.154462)
		(stroke
			(width 0.05715)
			(type default)
		)
		(layer "In11.Cu")
	)
	(gr_line
		(start 370.67363 -237.539022)
		(end 370.681504 -237.53445)
		(stroke
			(width 0.05715)
			(type default)
		)
		(layer "In11.Cu")
	)
	(gr_line
		(start 370.67363 -235.91901)
		(end 370.67998 -235.9152)
		(stroke
			(width 0.05715)
			(type default)
		)
		(layer "In11.Cu")
	)
	(gr_line
		(start 370.67363 -234.298998)
		(end 370.676424 -234.296966)
		(stroke
			(width 0.05715)
			(type default)
		)
		(layer "In11.Cu")
	)
	(gr_line
		(start 370.675662 -227.130864)
		(end 370.672868 -227.128832)
		(stroke
			(width 0.05715)
			(type default)
		)
		(layer "In11.Cu")
	)
	(gr_line
		(start 370.676424 -234.296966)
		(end 370.680996 -234.294426)
		(stroke
			(width 0.05715)
			(type default)
		)
		(layer "In11.Cu")
	)
	(gr_line
		(start 370.678456 -322.055236)
		(end 370.659914 -322.032884)
		(stroke
			(width 0.07112)
			(type default)
		)
		(layer "In11.Cu")
	)
	(gr_line
		(start 370.67998 -235.9152)
		(end 370.680742 -235.914692)
		(stroke
			(width 0.05715)
			(type default)
		)
		(layer "In11.Cu")
	)
	(gr_line
		(start 370.67998 -230.373174)
		(end 370.675408 -230.37038)
		(stroke
			(width 0.05715)
			(type default)
		)
		(layer "In11.Cu")
	)
	(gr_line
		(start 370.680742 -235.914692)
		(end 370.681758 -235.914184)
		(stroke
			(width 0.05715)
			(type default)
		)
		(layer "In11.Cu")
	)
	(gr_line
		(start 370.680996 -227.133912)
		(end 370.675662 -227.130864)
		(stroke
			(width 0.05715)
			(type default)
		)
		(layer "In11.Cu")
	)
	(gr_line
		(start 370.68125 -230.373936)
		(end 370.67998 -230.373174)
		(stroke
			(width 0.05715)
			(type default)
		)
		(layer "In11.Cu")
	)
	(gr_line
		(start 370.68252 -241.714528)
		(end 370.680996 -241.713512)
		(stroke
			(width 0.05715)
			(type default)
		)
		(layer "In11.Cu")
	)
	(gr_line
		(start 370.68252 -240.094516)
		(end 370.680996 -240.0935)
		(stroke
			(width 0.05715)
			(type default)
		)
		(layer "In11.Cu")
	)
	(gr_line
		(start 370.68252 -238.474504)
		(end 370.680996 -238.473488)
		(stroke
			(width 0.05715)
			(type default)
		)
		(layer "In11.Cu")
	)
	(gr_line
		(start 370.68252 -236.854492)
		(end 370.680996 -236.853476)
		(stroke
			(width 0.05715)
			(type default)
		)
		(layer "In11.Cu")
	)
	(gr_line
		(start 370.68252 -235.23448)
		(end 370.680996 -235.233464)
		(stroke
			(width 0.05715)
			(type default)
		)
		(layer "In11.Cu")
	)
	(gr_line
		(start 370.690902 -241.719354)
		(end 370.691156 -241.719354)
		(stroke
			(width 0.05715)
			(type default)
		)
		(layer "In11.Cu")
	)
	(gr_line
		(start 370.690902 -240.099342)
		(end 370.691156 -240.099342)
		(stroke
			(width 0.05715)
			(type default)
		)
		(layer "In11.Cu")
	)
	(gr_line
		(start 370.690902 -238.47933)
		(end 370.691156 -238.47933)
		(stroke
			(width 0.05715)
			(type default)
		)
		(layer "In11.Cu")
	)
	(gr_line
		(start 370.690902 -236.859318)
		(end 370.691156 -236.859318)
		(stroke
			(width 0.05715)
			(type default)
		)
		(layer "In11.Cu")
	)
	(gr_line
		(start 370.690902 -235.239306)
		(end 370.691156 -235.239306)
		(stroke
			(width 0.05715)
			(type default)
		)
		(layer "In11.Cu")
	)
	(gr_line
		(start 370.691918 -322.081144)
		(end 370.691918 -322.08089)
		(stroke
			(width 0.07112)
			(type default)
		)
		(layer "In11.Cu")
	)
	(gr_line
		(start 370.691918 -322.08089)
		(end 370.678456 -322.055236)
		(stroke
			(width 0.07112)
			(type default)
		)
		(layer "In11.Cu")
	)
	(gr_line
		(start 370.696744 -221.083124)
		(end 370.696744 -221.054676)
		(stroke
			(width 0.05715)
			(type default)
		)
		(layer "In11.Cu")
	)
	(gr_line
		(start 370.696998 -247.724168)
		(end 370.614194 -247.641364)
		(stroke
			(width 0.05715)
			(type default)
		)
		(layer "In11.Cu")
	)
	(gr_line
		(start 370.696998 -246.104156)
		(end 370.627656 -246.034814)
		(stroke
			(width 0.05715)
			(type default)
		)
		(layer "In11.Cu")
	)
	(gr_line
		(start 370.696998 -244.484144)
		(end 370.627656 -244.414802)
		(stroke
			(width 0.05715)
			(type default)
		)
		(layer "In11.Cu")
	)
	(gr_line
		(start 370.705634 -242.380262)
		(end 370.70665 -242.379754)
		(stroke
			(width 0.05715)
			(type default)
		)
		(layer "In11.Cu")
	)
	(gr_line
		(start 370.705634 -240.76025)
		(end 370.70665 -240.759742)
		(stroke
			(width 0.05715)
			(type default)
		)
		(layer "In11.Cu")
	)
	(gr_line
		(start 370.705634 -239.140238)
		(end 370.70665 -239.13973)
		(stroke
			(width 0.05715)
			(type default)
		)
		(layer "In11.Cu")
	)
	(gr_line
		(start 370.705634 -237.520226)
		(end 370.70665 -237.519718)
		(stroke
			(width 0.05715)
			(type default)
		)
		(layer "In11.Cu")
	)
	(gr_line
		(start 370.70665 -242.379754)
		(end 370.707412 -242.379246)
		(stroke
			(width 0.05715)
			(type default)
		)
		(layer "In11.Cu")
	)
	(gr_line
		(start 370.70665 -240.759742)
		(end 370.707412 -240.759234)
		(stroke
			(width 0.05715)
			(type default)
		)
		(layer "In11.Cu")
	)
	(gr_line
		(start 370.70665 -239.13973)
		(end 370.707412 -239.139222)
		(stroke
			(width 0.05715)
			(type default)
		)
		(layer "In11.Cu")
	)
	(gr_line
		(start 370.70665 -237.519718)
		(end 370.707412 -237.51921)
		(stroke
			(width 0.05715)
			(type default)
		)
		(layer "In11.Cu")
	)
	(gr_line
		(start 370.707412 -242.379246)
		(end 370.712492 -242.376452)
		(stroke
			(width 0.05715)
			(type default)
		)
		(layer "In11.Cu")
	)
	(gr_line
		(start 370.707412 -240.759234)
		(end 370.712492 -240.75644)
		(stroke
			(width 0.05715)
			(type default)
		)
		(layer "In11.Cu")
	)
	(gr_line
		(start 370.707412 -239.139222)
		(end 370.712492 -239.136428)
		(stroke
			(width 0.05715)
			(type default)
		)
		(layer "In11.Cu")
	)
	(gr_line
		(start 370.707412 -237.51921)
		(end 370.712492 -237.516416)
		(stroke
			(width 0.05715)
			(type default)
		)
		(layer "In11.Cu")
	)
	(gr_line
		(start 370.707412 -235.899198)
		(end 370.708936 -235.898436)
		(stroke
			(width 0.05715)
			(type default)
		)
		(layer "In11.Cu")
	)
	(gr_line
		(start 370.708936 -235.898436)
		(end 370.712492 -235.896404)
		(stroke
			(width 0.05715)
			(type default)
		)
		(layer "In11.Cu")
	)
	(gr_line
		(start 370.709444 -228.77018)
		(end 370.704872 -228.767386)
		(stroke
			(width 0.05715)
			(type default)
		)
		(layer "In11.Cu")
	)
	(gr_line
		(start 370.710968 -243.997226)
		(end 370.711984 -243.996718)
		(stroke
			(width 0.05715)
			(type default)
		)
		(layer "In11.Cu")
	)
	(gr_line
		(start 370.710968 -230.391208)
		(end 370.709698 -230.390446)
		(stroke
			(width 0.05715)
			(type default)
		)
		(layer "In11.Cu")
	)
	(gr_line
		(start 370.710968 -228.771196)
		(end 370.709444 -228.77018)
		(stroke
			(width 0.05715)
			(type default)
		)
		(layer "In11.Cu")
	)
	(gr_line
		(start 370.710968 -227.79736)
		(end 370.711984 -227.796852)
		(stroke
			(width 0.05715)
			(type default)
		)
		(layer "In11.Cu")
	)
	(gr_line
		(start 370.711984 -243.351558)
		(end 370.710968 -243.35105)
		(stroke
			(width 0.05715)
			(type default)
		)
		(layer "In11.Cu")
	)
	(gr_line
		(start 370.711984 -233.631486)
		(end 370.710968 -233.630978)
		(stroke
			(width 0.05715)
			(type default)
		)
		(layer "In11.Cu")
	)
	(gr_line
		(start 370.711984 -232.011474)
		(end 370.710968 -232.010966)
		(stroke
			(width 0.05715)
			(type default)
		)
		(layer "In11.Cu")
	)
	(gr_line
		(start 370.711984 -230.391716)
		(end 370.710968 -230.391208)
		(stroke
			(width 0.05715)
			(type default)
		)
		(layer "In11.Cu")
	)
	(gr_line
		(start 370.711984 -228.771704)
		(end 370.710968 -228.771196)
		(stroke
			(width 0.05715)
			(type default)
		)
		(layer "In11.Cu")
	)
	(gr_line
		(start 370.712746 -230.392224)
		(end 370.711984 -230.391716)
		(stroke
			(width 0.05715)
			(type default)
		)
		(layer "In11.Cu")
	)
	(gr_line
		(start 370.712746 -228.772212)
		(end 370.711984 -228.771704)
		(stroke
			(width 0.05715)
			(type default)
		)
		(layer "In11.Cu")
	)
	(gr_line
		(start 370.713254 -228.772466)
		(end 370.712746 -228.772212)
		(stroke
			(width 0.05715)
			(type default)
		)
		(layer "In11.Cu")
	)
	(gr_line
		(start 370.714016 -230.392986)
		(end 370.712746 -230.392224)
		(stroke
			(width 0.05715)
			(type default)
		)
		(layer "In11.Cu")
	)
	(gr_line
		(start 370.71554 -230.393748)
		(end 370.714016 -230.392986)
		(stroke
			(width 0.05715)
			(type default)
		)
		(layer "In11.Cu")
	)
	(gr_arc
		(start 370.735606 -278.2189)
		(mid 370.737399 -278.230222)
		(end 370.739416 -278.241506)
		(stroke
			(width 0.05715)
			(type default)
		)
		(layer "In11.Cu")
	)
	(gr_arc
		(start 370.735606 -276.598888)
		(mid 370.737398 -276.61021)
		(end 370.739416 -276.621494)
		(stroke
			(width 0.05715)
			(type default)
		)
		(layer "In11.Cu")
	)
	(gr_line
		(start 370.770658 -296.583862)
		(end 370.770658 -296.61231)
		(stroke
			(width 0.05715)
			(type default)
		)
		(layer "In11.Cu")
	)
	(gr_line
		(start 370.787168 -295.591738)
		(end 370.786914 -295.591738)
		(stroke
			(width 0.05715)
			(type default)
		)
		(layer "In11.Cu")
	)
	(gr_line
		(start 370.802154 -236.06506)
		(end 370.803678 -236.064044)
		(stroke
			(width 0.05715)
			(type default)
		)
		(layer "In11.Cu")
	)
	(gr_line
		(start 370.803678 -236.064044)
		(end 370.80444 -236.063536)
		(stroke
			(width 0.05715)
			(type default)
		)
		(layer "In11.Cu")
	)
	(gr_line
		(start 370.805964 -244.162834)
		(end 370.807234 -244.162072)
		(stroke
			(width 0.05715)
			(type default)
		)
		(layer "In11.Cu")
	)
	(gr_line
		(start 370.805964 -227.962968)
		(end 370.807234 -227.962206)
		(stroke
			(width 0.05715)
			(type default)
		)
		(layer "In11.Cu")
	)
	(gr_line
		(start 370.806726 -234.442254)
		(end 370.807234 -234.442)
		(stroke
			(width 0.05715)
			(type default)
		)
		(layer "In11.Cu")
	)
	(gr_line
		(start 370.807234 -244.162072)
		(end 370.807996 -244.161564)
		(stroke
			(width 0.05715)
			(type default)
		)
		(layer "In11.Cu")
	)
	(gr_line
		(start 370.807234 -243.186204)
		(end 370.805964 -243.185442)
		(stroke
			(width 0.05715)
			(type default)
		)
		(layer "In11.Cu")
	)
	(gr_line
		(start 370.807234 -233.466132)
		(end 370.805964 -233.46537)
		(stroke
			(width 0.05715)
			(type default)
		)
		(layer "In11.Cu")
	)
	(gr_line
		(start 370.807234 -231.84612)
		(end 370.805964 -231.845358)
		(stroke
			(width 0.05715)
			(type default)
		)
		(layer "In11.Cu")
	)
	(gr_line
		(start 370.807234 -228.60635)
		(end 370.805456 -228.605334)
		(stroke
			(width 0.05715)
			(type default)
		)
		(layer "In11.Cu")
	)
	(gr_line
		(start 370.807234 -227.962206)
		(end 370.807996 -227.961698)
		(stroke
			(width 0.05715)
			(type default)
		)
		(layer "In11.Cu")
	)
	(gr_line
		(start 370.807488 -232.821734)
		(end 370.807996 -232.82148)
		(stroke
			(width 0.05715)
			(type default)
		)
		(layer "In11.Cu")
	)
	(gr_line
		(start 370.807742 -243.186458)
		(end 370.807234 -243.186204)
		(stroke
			(width 0.05715)
			(type default)
		)
		(layer "In11.Cu")
	)
	(gr_line
		(start 370.807742 -233.466386)
		(end 370.807234 -233.466132)
		(stroke
			(width 0.05715)
			(type default)
		)
		(layer "In11.Cu")
	)
	(gr_line
		(start 370.807742 -231.846374)
		(end 370.807234 -231.84612)
		(stroke
			(width 0.05715)
			(type default)
		)
		(layer "In11.Cu")
	)
	(gr_line
		(start 370.807996 -241.5667)
		(end 370.80825 -241.566954)
		(stroke
			(width 0.05715)
			(type default)
		)
		(layer "In11.Cu")
	)
	(gr_line
		(start 370.807996 -239.946688)
		(end 370.80825 -239.946942)
		(stroke
			(width 0.05715)
			(type default)
		)
		(layer "In11.Cu")
	)
	(gr_line
		(start 370.807996 -238.326676)
		(end 370.80825 -238.32693)
		(stroke
			(width 0.05715)
			(type default)
		)
		(layer "In11.Cu")
	)
	(gr_line
		(start 370.807996 -236.706664)
		(end 370.80825 -236.706918)
		(stroke
			(width 0.05715)
			(type default)
		)
		(layer "In11.Cu")
	)
	(gr_line
		(start 370.807996 -235.086652)
		(end 370.80825 -235.086906)
		(stroke
			(width 0.05715)
			(type default)
		)
		(layer "In11.Cu")
	)
	(gr_line
		(start 370.807996 -230.226616)
		(end 370.804694 -230.224584)
		(stroke
			(width 0.05715)
			(type default)
		)
		(layer "In11.Cu")
	)
	(gr_line
		(start 370.807996 -228.606858)
		(end 370.807234 -228.60635)
		(stroke
			(width 0.05715)
			(type default)
		)
		(layer "In11.Cu")
	)
	(gr_line
		(start 370.80825 -242.541552)
		(end 370.807996 -242.541552)
		(stroke
			(width 0.05715)
			(type default)
		)
		(layer "In11.Cu")
	)
	(gr_line
		(start 370.80825 -240.92154)
		(end 370.807996 -240.92154)
		(stroke
			(width 0.05715)
			(type default)
		)
		(layer "In11.Cu")
	)
	(gr_line
		(start 370.80825 -239.301528)
		(end 370.807996 -239.301528)
		(stroke
			(width 0.05715)
			(type default)
		)
		(layer "In11.Cu")
	)
	(gr_line
		(start 370.80825 -237.681516)
		(end 370.807996 -237.681516)
		(stroke
			(width 0.05715)
			(type default)
		)
		(layer "In11.Cu")
	)
	(gr_line
		(start 370.80825 -236.061504)
		(end 370.807996 -236.061504)
		(stroke
			(width 0.05715)
			(type default)
		)
		(layer "In11.Cu")
	)
	(gr_line
		(start 370.810536 -230.22814)
		(end 370.809012 -230.227124)
		(stroke
			(width 0.05715)
			(type default)
		)
		(layer "In11.Cu")
	)
	(gr_arc
		(start 370.8146 -242.537742)
		(mid 370.817017 -242.536351)
		(end 370.819426 -242.534948)
		(stroke
			(width 0.05715)
			(type default)
		)
		(layer "In11.Cu")
	)
	(gr_arc
		(start 370.8146 -240.91773)
		(mid 370.817017 -240.916339)
		(end 370.819426 -240.914936)
		(stroke
			(width 0.05715)
			(type default)
		)
		(layer "In11.Cu")
	)
	(gr_arc
		(start 370.8146 -239.297718)
		(mid 370.817017 -239.296327)
		(end 370.819426 -239.294924)
		(stroke
			(width 0.05715)
			(type default)
		)
		(layer "In11.Cu")
	)
	(gr_arc
		(start 370.8146 -237.677706)
		(mid 370.817017 -237.676315)
		(end 370.819426 -237.674912)
		(stroke
			(width 0.05715)
			(type default)
		)
		(layer "In11.Cu")
	)
	(gr_arc
		(start 370.81587 -236.057186)
		(mid 370.81765 -236.056046)
		(end 370.819426 -236.0549)
		(stroke
			(width 0.05715)
			(type default)
		)
		(layer "In11.Cu")
	)
	(gr_line
		(start 370.816378 -296.538142)
		(end 370.770658 -296.583862)
		(stroke
			(width 0.05715)
			(type default)
		)
		(layer "In11.Cu")
	)
	(gr_line
		(start 370.838222 -226.32416)
		(end 370.842794 -226.32162)
		(stroke
			(width 0.05715)
			(type default)
		)
		(layer "In11.Cu")
	)
	(gr_line
		(start 370.84 -230.245158)
		(end 370.838984 -230.24465)
		(stroke
			(width 0.05715)
			(type default)
		)
		(layer "In11.Cu")
	)
	(gr_line
		(start 370.841524 -230.246174)
		(end 370.84 -230.245158)
		(stroke
			(width 0.05715)
			(type default)
		)
		(layer "In11.Cu")
	)
	(gr_line
		(start 370.841778 -229.561898)
		(end 370.844318 -229.560628)
		(stroke
			(width 0.05715)
			(type default)
		)
		(layer "In11.Cu")
	)
	(gr_line
		(start 370.842794 -226.32162)
		(end 370.844318 -226.320604)
		(stroke
			(width 0.05715)
			(type default)
		)
		(layer "In11.Cu")
	)
	(gr_arc
		(start 370.844318 -229.560628)
		(mid 370.850956 -229.555977)
		(end 370.857526 -229.55123)
		(stroke
			(width 0.05715)
			(type default)
		)
		(layer "In11.Cu")
	)
	(gr_arc
		(start 370.844318 -226.320604)
		(mid 370.848905 -226.317451)
		(end 370.853462 -226.314254)
		(stroke
			(width 0.05715)
			(type default)
		)
		(layer "In11.Cu")
	)
	(gr_arc
		(start 370.858288 -230.257604)
		(mid 370.849957 -230.251814)
		(end 370.841524 -230.246174)
		(stroke
			(width 0.05715)
			(type default)
		)
		(layer "In11.Cu")
	)
	(gr_line
		(start 370.894102 -420.952168)
		(end 371.184932 -421.242998)
		(stroke
			(width 0.07112)
			(type default)
		)
		(layer "In11.Cu")
	)
	(gr_line
		(start 370.907564 -225.79076)
		(end 370.907818 -225.789744)
		(stroke
			(width 0.05715)
			(type default)
		)
		(layer "In11.Cu")
	)
	(gr_arc
		(start 370.910358 -275.001736)
		(mid 370.91238 -274.990325)
		(end 370.914168 -274.978876)
		(stroke
			(width 0.05715)
			(type default)
		)
		(layer "In11.Cu")
	)
	(gr_arc
		(start 370.962174 -288.313114)
		(mid 370.96534 -288.315412)
		(end 370.968524 -288.317686)
		(stroke
			(width 0.05715)
			(type default)
		)
		(layer "In11.Cu")
	)
	(gr_arc
		(start 370.964714 -278.595074)
		(mid 370.968766 -278.597886)
		(end 370.972842 -278.600662)
		(stroke
			(width 0.05715)
			(type default)
		)
		(layer "In11.Cu")
	)
	(gr_arc
		(start 370.964714 -276.975062)
		(mid 370.968766 -276.977874)
		(end 370.972842 -276.98065)
		(stroke
			(width 0.05715)
			(type default)
		)
		(layer "In11.Cu")
	)
	(gr_arc
		(start 370.964968 -283.45511)
		(mid 370.968893 -283.457921)
		(end 370.972842 -283.460698)
		(stroke
			(width 0.05715)
			(type default)
		)
		(layer "In11.Cu")
	)
	(gr_arc
		(start 370.969286 -288.318194)
		(mid 370.971062 -288.319467)
		(end 370.972842 -288.320734)
		(stroke
			(width 0.05715)
			(type default)
		)
		(layer "In11.Cu")
	)
	(gr_line
		(start 370.972842 -288.320734)
		(end 370.978938 -288.32429)
		(stroke
			(width 0.05715)
			(type default)
		)
		(layer "In11.Cu")
	)
	(gr_line
		(start 370.972842 -283.460698)
		(end 370.9797 -283.464762)
		(stroke
			(width 0.05715)
			(type default)
		)
		(layer "In11.Cu")
	)
	(gr_line
		(start 370.972842 -278.600662)
		(end 370.9797 -278.604726)
		(stroke
			(width 0.05715)
			(type default)
		)
		(layer "In11.Cu")
	)
	(gr_line
		(start 370.972842 -276.98065)
		(end 370.9797 -276.984714)
		(stroke
			(width 0.05715)
			(type default)
		)
		(layer "In11.Cu")
	)
	(gr_line
		(start 370.978938 -288.32429)
		(end 370.979192 -288.32429)
		(stroke
			(width 0.05715)
			(type default)
		)
		(layer "In11.Cu")
	)
	(gr_line
		(start 370.9797 -283.464762)
		(end 370.980462 -283.46527)
		(stroke
			(width 0.05715)
			(type default)
		)
		(layer "In11.Cu")
	)
	(gr_line
		(start 370.9797 -278.604726)
		(end 370.980462 -278.605234)
		(stroke
			(width 0.05715)
			(type default)
		)
		(layer "In11.Cu")
	)
	(gr_line
		(start 370.9797 -276.984714)
		(end 370.980462 -276.985222)
		(stroke
			(width 0.05715)
			(type default)
		)
		(layer "In11.Cu")
	)
	(gr_line
		(start 370.980462 -283.46527)
		(end 370.981224 -283.465778)
		(stroke
			(width 0.05715)
			(type default)
		)
		(layer "In11.Cu")
	)
	(gr_line
		(start 370.980462 -278.605234)
		(end 370.981224 -278.605742)
		(stroke
			(width 0.05715)
			(type default)
		)
		(layer "In11.Cu")
	)
	(gr_line
		(start 370.980462 -276.985222)
		(end 370.981224 -276.98573)
		(stroke
			(width 0.05715)
			(type default)
		)
		(layer "In11.Cu")
	)
	(gr_line
		(start 370.994686 -247.724168)
		(end 370.696998 -247.724168)
		(stroke
			(width 0.05715)
			(type default)
		)
		(layer "In11.Cu")
	)
	(gr_line
		(start 370.994686 -246.104156)
		(end 370.696998 -246.104156)
		(stroke
			(width 0.05715)
			(type default)
		)
		(layer "In11.Cu")
	)
	(gr_line
		(start 370.994686 -244.484144)
		(end 370.696998 -244.484144)
		(stroke
			(width 0.05715)
			(type default)
		)
		(layer "In11.Cu")
	)
	(gr_line
		(start 370.996972 -278.136096)
		(end 370.92763 -278.205438)
		(stroke
			(width 0.05715)
			(type default)
		)
		(layer "In11.Cu")
	)
	(gr_line
		(start 370.996972 -276.516084)
		(end 370.92763 -276.585426)
		(stroke
			(width 0.05715)
			(type default)
		)
		(layer "In11.Cu")
	)
	(gr_line
		(start 370.996972 -274.896072)
		(end 370.914168 -274.978876)
		(stroke
			(width 0.05715)
			(type default)
		)
		(layer "In11.Cu")
	)
	(gr_line
		(start 371.006878 -296.538142)
		(end 371.052598 -296.583862)
		(stroke
			(width 0.05715)
			(type default)
		)
		(layer "In11.Cu")
	)
	(gr_line
		(start 371.011958 -277.00351)
		(end 371.012212 -277.003764)
		(stroke
			(width 0.05715)
			(type default)
		)
		(layer "In11.Cu")
	)
	(gr_line
		(start 371.012212 -278.623776)
		(end 371.01272 -278.62403)
		(stroke
			(width 0.05715)
			(type default)
		)
		(layer "In11.Cu")
	)
	(gr_line
		(start 371.012212 -277.003764)
		(end 371.01272 -277.004018)
		(stroke
			(width 0.05715)
			(type default)
		)
		(layer "In11.Cu")
	)
	(gr_line
		(start 371.01272 -291.583872)
		(end 371.01399 -291.584634)
		(stroke
			(width 0.05715)
			(type default)
		)
		(layer "In11.Cu")
	)
	(gr_line
		(start 371.01272 -278.62403)
		(end 371.01272 -278.623776)
		(stroke
			(width 0.05715)
			(type default)
		)
		(layer "In11.Cu")
	)
	(gr_line
		(start 371.01272 -277.004018)
		(end 371.015514 -277.005542)
		(stroke
			(width 0.05715)
			(type default)
		)
		(layer "In11.Cu")
	)
	(gr_line
		(start 371.014752 -293.205154)
		(end 371.01526 -293.205154)
		(stroke
			(width 0.05715)
			(type default)
		)
		(layer "In11.Cu")
	)
	(gr_line
		(start 371.014752 -289.96513)
		(end 371.01526 -289.96513)
		(stroke
			(width 0.05715)
			(type default)
		)
		(layer "In11.Cu")
	)
	(gr_line
		(start 371.014752 -285.105348)
		(end 371.01526 -285.105348)
		(stroke
			(width 0.05715)
			(type default)
		)
		(layer "In11.Cu")
	)
	(gr_line
		(start 371.014752 -283.485336)
		(end 371.01526 -283.485336)
		(stroke
			(width 0.05715)
			(type default)
		)
		(layer "In11.Cu")
	)
	(gr_line
		(start 371.014752 -281.865324)
		(end 371.01526 -281.865324)
		(stroke
			(width 0.05715)
			(type default)
		)
		(layer "In11.Cu")
	)
	(gr_line
		(start 371.015006 -288.345118)
		(end 371.01526 -288.345118)
		(stroke
			(width 0.05715)
			(type default)
		)
		(layer "In11.Cu")
	)
	(gr_line
		(start 371.015514 -277.005542)
		(end 371.016022 -277.005796)
		(stroke
			(width 0.05715)
			(type default)
		)
		(layer "In11.Cu")
	)
	(gr_arc
		(start 371.018054 -280.885138)
		(mid 371.01869 -280.884758)
		(end 371.019324 -280.884376)
		(stroke
			(width 0.05715)
			(type default)
		)
		(layer "In11.Cu")
	)
	(gr_line
		(start 371.052598 -296.583862)
		(end 371.052598 -296.61231)
		(stroke
			(width 0.05715)
			(type default)
		)
		(layer "In11.Cu")
	)
	(gr_line
		(start 371.09019 -225.870516)
		(end 371.09019 -225.871278)
		(stroke
			(width 0.05715)
			(type default)
		)
		(layer "In11.Cu")
	)
	(gr_line
		(start 371.09019 -225.870262)
		(end 371.09019 -225.870516)
		(stroke
			(width 0.05715)
			(type default)
		)
		(layer "In11.Cu")
	)
	(gr_arc
		(start 371.09019 -225.870262)
		(mid 371.09019 -225.870008)
		(end 371.09019 -225.869754)
		(stroke
			(width 0.05715)
			(type default)
		)
		(layer "In11.Cu")
	)
	(gr_line
		(start 371.107462 -294.658288)
		(end 371.10797 -294.658542)
		(stroke
			(width 0.05715)
			(type default)
		)
		(layer "In11.Cu")
	)
	(gr_line
		(start 371.107462 -293.038276)
		(end 371.10797 -293.03853)
		(stroke
			(width 0.05715)
			(type default)
		)
		(layer "In11.Cu")
	)
	(gr_line
		(start 371.107462 -291.418264)
		(end 371.10797 -291.418518)
		(stroke
			(width 0.05715)
			(type default)
		)
		(layer "In11.Cu")
	)
	(gr_line
		(start 371.107462 -289.798252)
		(end 371.10797 -289.798506)
		(stroke
			(width 0.05715)
			(type default)
		)
		(layer "In11.Cu")
	)
	(gr_line
		(start 371.107462 -284.93847)
		(end 371.10797 -284.938724)
		(stroke
			(width 0.05715)
			(type default)
		)
		(layer "In11.Cu")
	)
	(gr_line
		(start 371.107462 -281.698446)
		(end 371.10797 -281.6987)
		(stroke
			(width 0.05715)
			(type default)
		)
		(layer "In11.Cu")
	)
	(gr_line
		(start 371.107716 -292.393624)
		(end 371.102382 -292.396672)
		(stroke
			(width 0.05715)
			(type default)
		)
		(layer "In11.Cu")
	)
	(gr_line
		(start 371.10797 -294.658542)
		(end 371.112034 -294.661082)
		(stroke
			(width 0.05715)
			(type default)
		)
		(layer "In11.Cu")
	)
	(gr_line
		(start 371.10797 -293.03853)
		(end 371.111018 -293.040308)
		(stroke
			(width 0.05715)
			(type default)
		)
		(layer "In11.Cu")
	)
	(gr_line
		(start 371.10797 -291.418518)
		(end 371.10797 -291.418772)
		(stroke
			(width 0.05715)
			(type default)
		)
		(layer "In11.Cu")
	)
	(gr_line
		(start 371.10797 -289.798506)
		(end 371.111018 -289.800284)
		(stroke
			(width 0.05715)
			(type default)
		)
		(layer "In11.Cu")
	)
	(gr_line
		(start 371.10797 -284.938724)
		(end 371.111018 -284.940502)
		(stroke
			(width 0.05715)
			(type default)
		)
		(layer "In11.Cu")
	)
	(gr_line
		(start 371.10797 -283.318712)
		(end 371.111018 -283.32049)
		(stroke
			(width 0.05715)
			(type default)
		)
		(layer "In11.Cu")
	)
	(gr_line
		(start 371.10797 -281.6987)
		(end 371.111018 -281.700478)
		(stroke
			(width 0.05715)
			(type default)
		)
		(layer "In11.Cu")
	)
	(gr_line
		(start 371.10797 -281.05354)
		(end 371.107462 -281.053794)
		(stroke
			(width 0.05715)
			(type default)
		)
		(layer "In11.Cu")
	)
	(gr_line
		(start 371.10797 -278.458676)
		(end 371.108986 -278.459184)
		(stroke
			(width 0.05715)
			(type default)
		)
		(layer "In11.Cu")
	)
	(gr_line
		(start 371.10797 -276.838664)
		(end 371.111272 -276.840696)
		(stroke
			(width 0.05715)
			(type default)
		)
		(layer "In11.Cu")
	)
	(gr_line
		(start 371.111018 -294.011604)
		(end 371.107462 -294.013636)
		(stroke
			(width 0.05715)
			(type default)
		)
		(layer "In11.Cu")
	)
	(gr_line
		(start 371.111018 -290.77158)
		(end 371.107462 -290.773612)
		(stroke
			(width 0.05715)
			(type default)
		)
		(layer "In11.Cu")
	)
	(gr_line
		(start 371.111018 -289.151568)
		(end 371.107462 -289.1536)
		(stroke
			(width 0.05715)
			(type default)
		)
		(layer "In11.Cu")
	)
	(gr_line
		(start 371.111018 -285.911798)
		(end 371.107462 -285.91383)
		(stroke
			(width 0.05715)
			(type default)
		)
		(layer "In11.Cu")
	)
	(gr_line
		(start 371.111018 -284.291786)
		(end 371.107462 -284.293818)
		(stroke
			(width 0.05715)
			(type default)
		)
		(layer "In11.Cu")
	)
	(gr_line
		(start 371.111018 -282.671774)
		(end 371.107462 -282.673806)
		(stroke
			(width 0.05715)
			(type default)
		)
		(layer "In11.Cu")
	)
	(gr_arc
		(start 371.114066 -225.412554)
		(mid 371.111009 -225.415593)
		(end 371.10797 -225.41865)
		(stroke
			(width 0.05715)
			(type default)
		)
		(layer "In11.Cu")
	)
	(gr_line
		(start 371.122194 -278.467058)
		(end 371.122956 -278.467312)
		(stroke
			(width 0.05715)
			(type default)
		)
		(layer "In11.Cu")
	)
	(gr_arc
		(start 371.122194 -225.40595)
		(mid 371.118114 -225.409232)
		(end 371.114066 -225.412554)
		(stroke
			(width 0.05715)
			(type default)
		)
		(layer "In11.Cu")
	)
	(gr_arc
		(start 371.145562 -225.387916)
		(mid 371.140717 -225.391447)
		(end 371.13591 -225.395028)
		(stroke
			(width 0.05715)
			(type default)
		)
		(layer "In11.Cu")
	)
	(gr_line
		(start 371.148102 -225.386392)
		(end 371.158262 -225.38055)
		(stroke
			(width 0.05715)
			(type default)
		)
		(layer "In11.Cu")
	)
	(gr_line
		(start 371.178836 -225.368612)
		(end 371.180106 -225.36785)
		(stroke
			(width 0.05715)
			(type default)
		)
		(layer "In11.Cu")
	)
	(gr_line
		(start 371.180106 -225.36785)
		(end 371.181884 -225.366834)
		(stroke
			(width 0.05715)
			(type default)
		)
		(layer "In11.Cu")
	)
	(gr_line
		(start 371.181884 -225.366834)
		(end 371.182392 -225.36658)
		(stroke
			(width 0.05715)
			(type default)
		)
		(layer "In11.Cu")
	)
	(gr_line
		(start 371.199664 -295.145968)
		(end 371.19941 -295.145968)
		(stroke
			(width 0.05715)
			(type default)
		)
		(layer "In11.Cu")
	)
	(gr_line
		(start 371.24259 -333.702152)
		(end 371.242844 -333.702152)
		(stroke
			(width 0.07112)
			(type default)
		)
		(layer "In11.Cu")
	)
	(gr_line
		(start 371.265704 -244.978428)
		(end 371.26672 -244.97792)
		(stroke
			(width 0.05715)
			(type default)
		)
		(layer "In11.Cu")
	)
	(gr_line
		(start 371.273832 -225.533966)
		(end 371.274594 -225.533458)
		(stroke
			(width 0.05715)
			(type default)
		)
		(layer "In11.Cu")
	)
	(gr_line
		(start 371.276626 -225.532442)
		(end 371.277134 -225.532188)
		(stroke
			(width 0.05715)
			(type default)
		)
		(layer "In11.Cu")
	)
	(gr_line
		(start 371.294914 -278.136096)
		(end 370.996972 -278.136096)
		(stroke
			(width 0.05715)
			(type default)
		)
		(layer "In11.Cu")
	)
	(gr_line
		(start 371.294914 -276.516084)
		(end 370.996972 -276.516084)
		(stroke
			(width 0.05715)
			(type default)
		)
		(layer "In11.Cu")
	)
	(gr_line
		(start 371.294914 -274.896072)
		(end 370.996972 -274.896072)
		(stroke
			(width 0.05715)
			(type default)
		)
		(layer "In11.Cu")
	)
	(gr_line
		(start 371.464078 -382.101344)
		(end 371.220492 -382.34493)
		(stroke
			(width 0.07112)
			(type default)
		)
		(layer "In11.Cu")
	)
	(gr_arc
		(start 371.464078 -382.101344)
		(mid 371.495511 -382.056931)
		(end 371.510306 -382.00457)
		(stroke
			(width 0.07112)
			(type default)
		)
		(layer "In11.Cu")
	)
	(gr_line
		(start 371.513354 -277.831804)
		(end 371.513608 -277.831804)
		(stroke
			(width 0.05715)
			(type default)
		)
		(layer "In11.Cu")
	)
	(gr_line
		(start 371.564916 -280.2509)
		(end 371.564662 -280.251154)
		(stroke
			(width 0.05715)
			(type default)
		)
		(layer "In11.Cu")
	)
	(gr_line
		(start 371.577362 -295.468294)
		(end 371.57787 -295.468548)
		(stroke
			(width 0.05715)
			(type default)
		)
		(layer "In11.Cu")
	)
	(gr_line
		(start 371.57787 -279.268682)
		(end 371.578886 -279.26919)
		(stroke
			(width 0.05715)
			(type default)
		)
		(layer "In11.Cu")
	)
	(gr_arc
		(start 371.606572 -228.744272)
		(mid 371.609739 -228.746569)
		(end 371.612922 -228.748844)
		(stroke
			(width 0.05715)
			(type default)
		)
		(layer "In11.Cu")
	)
	(gr_arc
		(start 371.611398 -224.580704)
		(mid 371.608981 -224.582476)
		(end 371.606572 -224.58426)
		(stroke
			(width 0.05715)
			(type default)
		)
		(layer "In11.Cu")
	)
	(gr_line
		(start 371.61343 -228.749098)
		(end 371.612922 -228.748844)
		(stroke
			(width 0.05715)
			(type default)
		)
		(layer "In11.Cu")
	)
	(gr_line
		(start 371.621304 -228.75367)
		(end 371.61343 -228.749098)
		(stroke
			(width 0.05715)
			(type default)
		)
		(layer "In11.Cu")
	)
	(gr_line
		(start 371.650768 -222.937324)
		(end 371.651784 -222.936816)
		(stroke
			(width 0.05715)
			(type default)
		)
		(layer "In11.Cu")
	)
	(gr_line
		(start 371.651784 -222.936816)
		(end 371.652546 -222.936308)
		(stroke
			(width 0.05715)
			(type default)
		)
		(layer "In11.Cu")
	)
	(gr_line
		(start 371.652038 -229.41661)
		(end 371.652546 -229.416356)
		(stroke
			(width 0.05715)
			(type default)
		)
		(layer "In11.Cu")
	)
	(gr_line
		(start 371.652546 -222.936308)
		(end 371.654324 -222.935292)
		(stroke
			(width 0.05715)
			(type default)
		)
		(layer "In11.Cu")
	)
	(gr_line
		(start 371.747034 -223.10217)
		(end 371.747796 -223.101662)
		(stroke
			(width 0.05715)
			(type default)
		)
		(layer "In11.Cu")
	)
	(gr_line
		(start 371.747796 -223.101662)
		(end 371.748812 -223.101154)
		(stroke
			(width 0.05715)
			(type default)
		)
		(layer "In11.Cu")
	)
	(gr_line
		(start 371.748812 -223.101154)
		(end 371.750336 -223.100138)
		(stroke
			(width 0.05715)
			(type default)
		)
		(layer "In11.Cu")
	)
	(gr_line
		(start 371.750336 -223.100138)
		(end 371.751098 -223.09963)
		(stroke
			(width 0.05715)
			(type default)
		)
		(layer "In11.Cu")
	)
	(gr_line
		(start 371.757702 -420.952168)
		(end 371.466872 -421.242998)
		(stroke
			(width 0.07112)
			(type default)
		)
		(layer "In11.Cu")
	)
	(gr_line
		(start 371.780054 -229.563168)
		(end 371.78488 -229.560374)
		(stroke
			(width 0.05715)
			(type default)
		)
		(layer "In11.Cu")
	)
	(gr_line
		(start 371.78488 -229.560374)
		(end 371.786912 -229.55885)
		(stroke
			(width 0.05715)
			(type default)
		)
		(layer "In11.Cu")
	)
	(gr_arc
		(start 371.786912 -229.55885)
		(mid 371.791628 -229.555572)
		(end 371.79631 -229.552246)
		(stroke
			(width 0.05715)
			(type default)
		)
		(layer "In11.Cu")
	)
	(gr_arc
		(start 371.794278 -382.00457)
		(mid 371.809132 -382.056904)
		(end 371.840506 -382.101344)
		(stroke
			(width 0.07112)
			(type default)
		)
		(layer "In11.Cu")
	)
	(gr_line
		(start 371.840506 -382.101344)
		(end 372.084092 -382.34493)
		(stroke
			(width 0.07112)
			(type default)
		)
		(layer "In11.Cu")
	)
	(gr_line
		(start 371.867938 -296.876216)
		(end 371.867938 -296.876724)
		(stroke
			(width 0.07112)
			(type default)
		)
		(layer "In11.Cu")
	)
	(gr_line
		(start 371.867938 -296.837862)
		(end 371.867938 -296.86631)
		(stroke
			(width 0.05715)
			(type default)
		)
		(layer "In11.Cu")
	)
	(gr_line
		(start 371.913658 -296.792142)
		(end 371.867938 -296.837862)
		(stroke
			(width 0.05715)
			(type default)
		)
		(layer "In11.Cu")
	)
	(gr_line
		(start 371.984016 -56.280558)
		(end 371.987826 -56.275478)
		(stroke
			(width 0.07112)
			(type default)
		)
		(layer "In11.Cu")
	)
	(gr_line
		(start 371.987826 -56.275478)
		(end 371.988588 -56.27497)
		(stroke
			(width 0.07112)
			(type default)
		)
		(layer "In11.Cu")
	)
	(gr_line
		(start 371.988588 -56.27497)
		(end 371.992652 -56.268874)
		(stroke
			(width 0.07112)
			(type default)
		)
		(layer "In11.Cu")
	)
	(gr_line
		(start 372.104158 -296.792142)
		(end 372.149878 -296.837862)
		(stroke
			(width 0.05715)
			(type default)
		)
		(layer "In11.Cu")
	)
	(gr_line
		(start 372.121938 -225.366834)
		(end 372.1227 -225.366326)
		(stroke
			(width 0.05715)
			(type default)
		)
		(layer "In11.Cu")
	)
	(gr_line
		(start 372.1227 -225.366326)
		(end 372.12397 -225.365564)
		(stroke
			(width 0.05715)
			(type default)
		)
		(layer "In11.Cu")
	)
	(gr_line
		(start 372.12397 -225.365564)
		(end 372.124986 -225.365056)
		(stroke
			(width 0.05715)
			(type default)
		)
		(layer "In11.Cu")
	)
	(gr_line
		(start 372.149878 -296.837862)
		(end 372.149878 -296.86631)
		(stroke
			(width 0.05715)
			(type default)
		)
		(layer "In11.Cu")
	)
	(gr_line
		(start 372.150386 -296.905172)
		(end 372.150386 -296.90568)
		(stroke
			(width 0.07112)
			(type default)
		)
		(layer "In11.Cu")
	)
	(gr_line
		(start 372.215918 -225.53295)
		(end 372.217188 -225.532188)
		(stroke
			(width 0.05715)
			(type default)
		)
		(layer "In11.Cu")
	)
	(gr_line
		(start 372.217188 -225.532188)
		(end 372.21795 -225.53168)
		(stroke
			(width 0.05715)
			(type default)
		)
		(layer "In11.Cu")
	)
	(gr_line
		(start 372.21795 -225.53168)
		(end 372.218966 -225.531172)
		(stroke
			(width 0.05715)
			(type default)
		)
		(layer "In11.Cu")
	)
	(gr_line
		(start 372.218966 -225.531172)
		(end 372.220236 -225.53041)
		(stroke
			(width 0.05715)
			(type default)
		)
		(layer "In11.Cu")
	)
	(gr_line
		(start 372.220236 -225.53041)
		(end 372.220998 -225.529902)
		(stroke
			(width 0.05715)
			(type default)
		)
		(layer "In11.Cu")
	)
	(gr_line
		(start 372.222268 -225.52914)
		(end 372.224046 -225.528124)
		(stroke
			(width 0.05715)
			(type default)
		)
		(layer "In11.Cu")
	)
	(gr_line
		(start 372.248938 -225.513646)
		(end 372.249446 -225.513392)
		(stroke
			(width 0.05715)
			(type default)
		)
		(layer "In11.Cu")
	)
	(gr_line
		(start 372.249446 -225.513392)
		(end 372.250208 -225.512884)
		(stroke
			(width 0.05715)
			(type default)
		)
		(layer "In11.Cu")
	)
	(gr_line
		(start 372.250208 -225.512884)
		(end 372.257066 -225.50882)
		(stroke
			(width 0.05715)
			(type default)
		)
		(layer "In11.Cu")
	)
	(gr_arc
		(start 372.257066 -225.50882)
		(mid 372.261015 -225.506043)
		(end 372.26494 -225.503232)
		(stroke
			(width 0.05715)
			(type default)
		)
		(layer "In11.Cu")
	)
	(gr_line
		(start 372.26367 -221.202758)
		(end 372.26367 -221.17431)
		(stroke
			(width 0.05715)
			(type default)
		)
		(layer "In11.Cu")
	)
	(gr_line
		(start 372.30939 -221.248478)
		(end 372.26367 -221.202758)
		(stroke
			(width 0.05715)
			(type default)
		)
		(layer "In11.Cu")
	)
	(gr_arc
		(start 372.374922 -279.40508)
		(mid 372.378847 -279.407891)
		(end 372.382796 -279.410668)
		(stroke
			(width 0.05715)
			(type default)
		)
		(layer "In11.Cu")
	)
	(gr_line
		(start 372.382796 -279.410668)
		(end 372.389654 -279.414732)
		(stroke
			(width 0.05715)
			(type default)
		)
		(layer "In11.Cu")
	)
	(gr_line
		(start 372.389654 -279.414732)
		(end 372.390416 -279.41524)
		(stroke
			(width 0.05715)
			(type default)
		)
		(layer "In11.Cu")
	)
	(gr_line
		(start 372.390416 -279.41524)
		(end 372.391178 -279.415748)
		(stroke
			(width 0.05715)
			(type default)
		)
		(layer "In11.Cu")
	)
	(gr_line
		(start 372.421658 -280.078688)
		(end 372.420896 -280.079196)
		(stroke
			(width 0.05715)
			(type default)
		)
		(layer "In11.Cu")
	)
	(gr_line
		(start 372.422166 -279.433782)
		(end 372.422674 -279.434036)
		(stroke
			(width 0.05715)
			(type default)
		)
		(layer "In11.Cu")
	)
	(gr_line
		(start 372.422674 -279.434036)
		(end 372.425468 -279.43556)
		(stroke
			(width 0.05715)
			(type default)
		)
		(layer "In11.Cu")
	)
	(gr_line
		(start 372.49989 -221.248478)
		(end 372.54561 -221.202758)
		(stroke
			(width 0.05715)
			(type default)
		)
		(layer "In11.Cu")
	)
	(gr_line
		(start 372.517162 -280.244042)
		(end 372.515892 -280.244804)
		(stroke
			(width 0.05715)
			(type default)
		)
		(layer "In11.Cu")
	)
	(gr_line
		(start 372.51767 -280.243788)
		(end 372.517162 -280.244042)
		(stroke
			(width 0.05715)
			(type default)
		)
		(layer "In11.Cu")
	)
	(gr_line
		(start 372.517924 -279.268682)
		(end 372.51894 -279.26919)
		(stroke
			(width 0.05715)
			(type default)
		)
		(layer "In11.Cu")
	)
	(gr_line
		(start 372.51894 -279.26919)
		(end 372.520464 -279.270206)
		(stroke
			(width 0.05715)
			(type default)
		)
		(layer "In11.Cu")
	)
	(gr_line
		(start 372.520464 -279.270206)
		(end 372.52148 -279.270714)
		(stroke
			(width 0.05715)
			(type default)
		)
		(layer "In11.Cu")
	)
	(gr_line
		(start 372.52148 -279.270714)
		(end 372.52656 -279.273762)
		(stroke
			(width 0.05715)
			(type default)
		)
		(layer "In11.Cu")
	)
	(gr_arc
		(start 372.544848 -227.123244)
		(mid 372.548773 -227.126055)
		(end 372.552722 -227.128832)
		(stroke
			(width 0.05715)
			(type default)
		)
		(layer "In11.Cu")
	)
	(gr_line
		(start 372.54561 -221.202758)
		(end 372.54561 -221.17431)
		(stroke
			(width 0.05715)
			(type default)
		)
		(layer "In11.Cu")
	)
	(gr_line
		(start 372.546118 -330.266802)
		(end 372.545864 -330.266802)
		(stroke
			(width 0.07112)
			(type default)
		)
		(layer "In11.Cu")
	)
	(gr_arc
		(start 372.551452 -224.580704)
		(mid 372.549034 -224.582476)
		(end 372.546626 -224.58426)
		(stroke
			(width 0.05715)
			(type default)
		)
		(layer "In11.Cu")
	)
	(gr_arc
		(start 372.552722 -229.43947)
		(mid 372.547366 -229.443249)
		(end 372.542054 -229.44709)
		(stroke
			(width 0.05715)
			(type default)
		)
		(layer "In11.Cu")
	)
	(gr_line
		(start 372.552722 -229.43947)
		(end 372.55323 -229.439216)
		(stroke
			(width 0.05715)
			(type default)
		)
		(layer "In11.Cu")
	)
	(gr_arc
		(start 372.552722 -226.1997)
		(mid 372.548773 -226.202477)
		(end 372.544848 -226.205288)
		(stroke
			(width 0.05715)
			(type default)
		)
		(layer "In11.Cu")
	)
	(gr_line
		(start 372.552722 -226.1997)
		(end 372.55958 -226.195636)
		(stroke
			(width 0.05715)
			(type default)
		)
		(layer "In11.Cu")
	)
	(gr_arc
		(start 372.552722 -222.959676)
		(mid 372.548773 -222.962453)
		(end 372.544848 -222.965264)
		(stroke
			(width 0.05715)
			(type default)
		)
		(layer "In11.Cu")
	)
	(gr_line
		(start 372.552722 -222.959676)
		(end 372.555516 -222.957644)
		(stroke
			(width 0.05715)
			(type default)
		)
		(layer "In11.Cu")
	)
	(gr_line
		(start 372.55323 -229.439216)
		(end 372.558056 -229.436422)
		(stroke
			(width 0.05715)
			(type default)
		)
		(layer "In11.Cu")
	)
	(gr_line
		(start 372.555516 -227.130864)
		(end 372.552722 -227.128832)
		(stroke
			(width 0.05715)
			(type default)
		)
		(layer "In11.Cu")
	)
	(gr_line
		(start 372.555516 -222.957644)
		(end 372.56085 -222.954596)
		(stroke
			(width 0.05715)
			(type default)
		)
		(layer "In11.Cu")
	)
	(gr_line
		(start 372.55958 -226.195636)
		(end 372.560342 -226.195128)
		(stroke
			(width 0.05715)
			(type default)
		)
		(layer "In11.Cu")
	)
	(gr_line
		(start 372.560342 -226.195128)
		(end 372.561104 -226.19462)
		(stroke
			(width 0.05715)
			(type default)
		)
		(layer "In11.Cu")
	)
	(gr_line
		(start 372.561104 -227.134166)
		(end 372.555516 -227.130864)
		(stroke
			(width 0.05715)
			(type default)
		)
		(layer "In11.Cu")
	)
	(gr_line
		(start 372.585742 -228.768148)
		(end 372.584726 -228.767386)
		(stroke
			(width 0.05715)
			(type default)
		)
		(layer "In11.Cu")
	)
	(gr_line
		(start 372.588282 -228.769672)
		(end 372.585742 -228.768148)
		(stroke
			(width 0.05715)
			(type default)
		)
		(layer "In11.Cu")
	)
	(gr_line
		(start 372.58879 -243.998496)
		(end 372.589552 -243.997988)
		(stroke
			(width 0.05715)
			(type default)
		)
		(layer "In11.Cu")
	)
	(gr_line
		(start 372.58879 -240.758472)
		(end 372.589552 -240.757964)
		(stroke
			(width 0.05715)
			(type default)
		)
		(layer "In11.Cu")
	)
	(gr_line
		(start 372.58879 -239.13846)
		(end 372.589552 -239.137952)
		(stroke
			(width 0.05715)
			(type default)
		)
		(layer "In11.Cu")
	)
	(gr_line
		(start 372.58879 -235.898436)
		(end 372.589552 -235.897928)
		(stroke
			(width 0.05715)
			(type default)
		)
		(layer "In11.Cu")
	)
	(gr_line
		(start 372.58879 -234.278424)
		(end 372.589552 -234.277916)
		(stroke
			(width 0.05715)
			(type default)
		)
		(layer "In11.Cu")
	)
	(gr_line
		(start 372.58879 -232.658412)
		(end 372.589552 -232.657904)
		(stroke
			(width 0.05715)
			(type default)
		)
		(layer "In11.Cu")
	)
	(gr_line
		(start 372.58879 -227.79863)
		(end 372.589552 -227.798122)
		(stroke
			(width 0.05715)
			(type default)
		)
		(layer "In11.Cu")
	)
	(gr_line
		(start 372.589298 -228.77018)
		(end 372.588282 -228.769672)
		(stroke
			(width 0.05715)
			(type default)
		)
		(layer "In11.Cu")
	)
	(gr_line
		(start 372.589552 -243.997988)
		(end 372.590822 -243.997226)
		(stroke
			(width 0.05715)
			(type default)
		)
		(layer "In11.Cu")
	)
	(gr_line
		(start 372.589552 -240.757964)
		(end 372.590822 -240.757202)
		(stroke
			(width 0.05715)
			(type default)
		)
		(layer "In11.Cu")
	)
	(gr_line
		(start 372.589552 -239.137952)
		(end 372.590822 -239.13719)
		(stroke
			(width 0.05715)
			(type default)
		)
		(layer "In11.Cu")
	)
	(gr_line
		(start 372.589552 -235.897928)
		(end 372.590822 -235.897166)
		(stroke
			(width 0.05715)
			(type default)
		)
		(layer "In11.Cu")
	)
	(gr_line
		(start 372.589552 -234.277916)
		(end 372.590822 -234.277154)
		(stroke
			(width 0.05715)
			(type default)
		)
		(layer "In11.Cu")
	)
	(gr_line
		(start 372.589552 -232.657904)
		(end 372.590822 -232.657142)
		(stroke
			(width 0.05715)
			(type default)
		)
		(layer "In11.Cu")
	)
	(gr_line
		(start 372.589552 -227.798122)
		(end 372.590822 -227.79736)
		(stroke
			(width 0.05715)
			(type default)
		)
		(layer "In11.Cu")
	)
	(gr_line
		(start 372.590822 -243.997226)
		(end 372.591838 -243.996718)
		(stroke
			(width 0.05715)
			(type default)
		)
		(layer "In11.Cu")
	)
	(gr_line
		(start 372.590822 -240.757202)
		(end 372.591838 -240.756694)
		(stroke
			(width 0.05715)
			(type default)
		)
		(layer "In11.Cu")
	)
	(gr_line
		(start 372.590822 -239.13719)
		(end 372.591838 -239.136682)
		(stroke
			(width 0.05715)
			(type default)
		)
		(layer "In11.Cu")
	)
	(gr_line
		(start 372.590822 -235.897166)
		(end 372.591838 -235.896658)
		(stroke
			(width 0.05715)
			(type default)
		)
		(layer "In11.Cu")
	)
	(gr_line
		(start 372.590822 -234.277154)
		(end 372.591838 -234.276646)
		(stroke
			(width 0.05715)
			(type default)
		)
		(layer "In11.Cu")
	)
	(gr_line
		(start 372.590822 -232.657142)
		(end 372.591838 -232.656634)
		(stroke
			(width 0.05715)
			(type default)
		)
		(layer "In11.Cu")
	)
	(gr_line
		(start 372.590822 -228.771196)
		(end 372.589298 -228.77018)
		(stroke
			(width 0.05715)
			(type default)
		)
		(layer "In11.Cu")
	)
	(gr_line
		(start 372.590822 -227.79736)
		(end 372.591838 -227.796852)
		(stroke
			(width 0.05715)
			(type default)
		)
		(layer "In11.Cu")
	)
	(gr_line
		(start 372.591838 -246.591582)
		(end 372.590822 -246.591074)
		(stroke
			(width 0.05715)
			(type default)
		)
		(layer "In11.Cu")
	)
	(gr_line
		(start 372.591838 -244.97157)
		(end 372.590822 -244.971062)
		(stroke
			(width 0.05715)
			(type default)
		)
		(layer "In11.Cu")
	)
	(gr_line
		(start 372.591838 -243.996718)
		(end 372.5926 -243.99621)
		(stroke
			(width 0.05715)
			(type default)
		)
		(layer "In11.Cu")
	)
	(gr_line
		(start 372.591838 -243.351558)
		(end 372.590822 -243.35105)
		(stroke
			(width 0.05715)
			(type default)
		)
		(layer "In11.Cu")
	)
	(gr_line
		(start 372.591838 -241.731546)
		(end 372.590822 -241.731038)
		(stroke
			(width 0.05715)
			(type default)
		)
		(layer "In11.Cu")
	)
	(gr_line
		(start 372.591838 -240.756694)
		(end 372.5926 -240.756186)
		(stroke
			(width 0.05715)
			(type default)
		)
		(layer "In11.Cu")
	)
	(gr_line
		(start 372.591838 -240.111534)
		(end 372.590822 -240.111026)
		(stroke
			(width 0.05715)
			(type default)
		)
		(layer "In11.Cu")
	)
	(gr_line
		(start 372.591838 -239.136682)
		(end 372.5926 -239.136174)
		(stroke
			(width 0.05715)
			(type default)
		)
		(layer "In11.Cu")
	)
	(gr_line
		(start 372.591838 -238.491522)
		(end 372.590822 -238.491014)
		(stroke
			(width 0.05715)
			(type default)
		)
		(layer "In11.Cu")
	)
	(gr_line
		(start 372.591838 -236.87151)
		(end 372.590822 -236.871002)
		(stroke
			(width 0.05715)
			(type default)
		)
		(layer "In11.Cu")
	)
	(gr_line
		(start 372.591838 -235.896658)
		(end 372.5926 -235.89615)
		(stroke
			(width 0.05715)
			(type default)
		)
		(layer "In11.Cu")
	)
	(gr_line
		(start 372.591838 -235.251498)
		(end 372.590822 -235.25099)
		(stroke
			(width 0.05715)
			(type default)
		)
		(layer "In11.Cu")
	)
	(gr_line
		(start 372.591838 -234.276646)
		(end 372.5926 -234.276138)
		(stroke
			(width 0.05715)
			(type default)
		)
		(layer "In11.Cu")
	)
	(gr_line
		(start 372.591838 -233.631486)
		(end 372.590822 -233.630978)
		(stroke
			(width 0.05715)
			(type default)
		)
		(layer "In11.Cu")
	)
	(gr_line
		(start 372.591838 -232.656634)
		(end 372.5926 -232.656126)
		(stroke
			(width 0.05715)
			(type default)
		)
		(layer "In11.Cu")
	)
	(gr_line
		(start 372.591838 -232.011474)
		(end 372.590822 -232.010966)
		(stroke
			(width 0.05715)
			(type default)
		)
		(layer "In11.Cu")
	)
	(gr_line
		(start 372.591838 -228.771704)
		(end 372.590822 -228.771196)
		(stroke
			(width 0.05715)
			(type default)
		)
		(layer "In11.Cu")
	)
	(gr_line
		(start 372.591838 -227.796852)
		(end 372.592346 -227.796598)
		(stroke
			(width 0.05715)
			(type default)
		)
		(layer "In11.Cu")
	)
	(gr_line
		(start 372.592092 -226.176586)
		(end 372.5926 -226.176332)
		(stroke
			(width 0.05715)
			(type default)
		)
		(layer "In11.Cu")
	)
	(gr_line
		(start 372.592346 -238.491776)
		(end 372.591838 -238.491522)
		(stroke
			(width 0.05715)
			(type default)
		)
		(layer "In11.Cu")
	)
	(gr_line
		(start 372.592346 -228.771958)
		(end 372.591838 -228.771704)
		(stroke
			(width 0.05715)
			(type default)
		)
		(layer "In11.Cu")
	)
	(gr_line
		(start 372.5926 -245.616222)
		(end 372.59387 -245.61546)
		(stroke
			(width 0.05715)
			(type default)
		)
		(layer "In11.Cu")
	)
	(gr_line
		(start 372.5926 -243.99621)
		(end 372.59387 -243.995448)
		(stroke
			(width 0.05715)
			(type default)
		)
		(layer "In11.Cu")
	)
	(gr_line
		(start 372.5926 -242.376198)
		(end 372.59387 -242.375436)
		(stroke
			(width 0.05715)
			(type default)
		)
		(layer "In11.Cu")
	)
	(gr_line
		(start 372.5926 -240.756186)
		(end 372.59387 -240.755424)
		(stroke
			(width 0.05715)
			(type default)
		)
		(layer "In11.Cu")
	)
	(gr_line
		(start 372.5926 -239.136174)
		(end 372.59387 -239.135412)
		(stroke
			(width 0.05715)
			(type default)
		)
		(layer "In11.Cu")
	)
	(gr_line
		(start 372.5926 -237.516162)
		(end 372.59387 -237.5154)
		(stroke
			(width 0.05715)
			(type default)
		)
		(layer "In11.Cu")
	)
	(gr_line
		(start 372.5926 -235.89615)
		(end 372.59387 -235.895388)
		(stroke
			(width 0.05715)
			(type default)
		)
		(layer "In11.Cu")
	)
	(gr_line
		(start 372.5926 -234.276138)
		(end 372.59387 -234.275376)
		(stroke
			(width 0.05715)
			(type default)
		)
		(layer "In11.Cu")
	)
	(gr_line
		(start 372.5926 -232.656126)
		(end 372.59387 -232.655364)
		(stroke
			(width 0.05715)
			(type default)
		)
		(layer "In11.Cu")
	)
	(gr_line
		(start 372.5926 -227.1522)
		(end 372.591838 -227.151692)
		(stroke
			(width 0.05715)
			(type default)
		)
		(layer "In11.Cu")
	)
	(gr_line
		(start 372.5926 -226.176332)
		(end 372.599966 -226.172268)
		(stroke
			(width 0.05715)
			(type default)
		)
		(layer "In11.Cu")
	)
	(gr_line
		(start 372.594886 -227.15347)
		(end 372.5926 -227.1522)
		(stroke
			(width 0.05715)
			(type default)
		)
		(layer "In11.Cu")
	)
	(gr_line
		(start 372.609618 -295.955974)
		(end 372.609364 -295.956228)
		(stroke
			(width 0.05715)
			(type default)
		)
		(layer "In11.Cu")
	)
	(gr_line
		(start 372.681246 -228.603048)
		(end 372.68023 -228.60254)
		(stroke
			(width 0.05715)
			(type default)
		)
		(layer "In11.Cu")
	)
	(gr_line
		(start 372.682008 -228.603556)
		(end 372.681246 -228.603048)
		(stroke
			(width 0.05715)
			(type default)
		)
		(layer "In11.Cu")
	)
	(gr_line
		(start 372.683278 -244.164104)
		(end 372.685818 -244.162834)
		(stroke
			(width 0.05715)
			(type default)
		)
		(layer "In11.Cu")
	)
	(gr_line
		(start 372.683278 -240.92408)
		(end 372.685818 -240.92281)
		(stroke
			(width 0.05715)
			(type default)
		)
		(layer "In11.Cu")
	)
	(gr_line
		(start 372.683278 -239.304068)
		(end 372.685818 -239.302798)
		(stroke
			(width 0.05715)
			(type default)
		)
		(layer "In11.Cu")
	)
	(gr_line
		(start 372.683278 -236.064044)
		(end 372.685818 -236.062774)
		(stroke
			(width 0.05715)
			(type default)
		)
		(layer "In11.Cu")
	)
	(gr_line
		(start 372.683278 -234.444032)
		(end 372.685818 -234.442762)
		(stroke
			(width 0.05715)
			(type default)
		)
		(layer "In11.Cu")
	)
	(gr_line
		(start 372.683278 -232.82402)
		(end 372.685818 -232.82275)
		(stroke
			(width 0.05715)
			(type default)
		)
		(layer "In11.Cu")
	)
	(gr_line
		(start 372.683278 -227.964238)
		(end 372.685818 -227.962968)
		(stroke
			(width 0.05715)
			(type default)
		)
		(layer "In11.Cu")
	)
	(gr_line
		(start 372.683532 -228.604318)
		(end 372.682008 -228.603556)
		(stroke
			(width 0.05715)
			(type default)
		)
		(layer "In11.Cu")
	)
	(gr_line
		(start 372.684294 -228.604826)
		(end 372.683532 -228.604318)
		(stroke
			(width 0.05715)
			(type default)
		)
		(layer "In11.Cu")
	)
	(gr_line
		(start 372.685818 -244.162834)
		(end 372.687088 -244.162072)
		(stroke
			(width 0.05715)
			(type default)
		)
		(layer "In11.Cu")
	)
	(gr_line
		(start 372.685818 -240.92281)
		(end 372.687088 -240.922048)
		(stroke
			(width 0.05715)
			(type default)
		)
		(layer "In11.Cu")
	)
	(gr_line
		(start 372.685818 -239.302798)
		(end 372.687088 -239.302036)
		(stroke
			(width 0.05715)
			(type default)
		)
		(layer "In11.Cu")
	)
	(gr_line
		(start 372.685818 -236.062774)
		(end 372.687088 -236.062012)
		(stroke
			(width 0.05715)
			(type default)
		)
		(layer "In11.Cu")
	)
	(gr_line
		(start 372.685818 -234.442762)
		(end 372.687088 -234.442)
		(stroke
			(width 0.05715)
			(type default)
		)
		(layer "In11.Cu")
	)
	(gr_line
		(start 372.685818 -232.82275)
		(end 372.687088 -232.821988)
		(stroke
			(width 0.05715)
			(type default)
		)
		(layer "In11.Cu")
	)
	(gr_line
		(start 372.685818 -227.962968)
		(end 372.687088 -227.962206)
		(stroke
			(width 0.05715)
			(type default)
		)
		(layer "In11.Cu")
	)
	(gr_line
		(start 372.687088 -246.426228)
		(end 372.685818 -246.425466)
		(stroke
			(width 0.05715)
			(type default)
		)
		(layer "In11.Cu")
	)
	(gr_line
		(start 372.687088 -244.806216)
		(end 372.685818 -244.805454)
		(stroke
			(width 0.05715)
			(type default)
		)
		(layer "In11.Cu")
	)
	(gr_line
		(start 372.687088 -244.162072)
		(end 372.68785 -244.161564)
		(stroke
			(width 0.05715)
			(type default)
		)
		(layer "In11.Cu")
	)
	(gr_line
		(start 372.687088 -243.186204)
		(end 372.685818 -243.185442)
		(stroke
			(width 0.05715)
			(type default)
		)
		(layer "In11.Cu")
	)
	(gr_line
		(start 372.687088 -241.566192)
		(end 372.685818 -241.56543)
		(stroke
			(width 0.05715)
			(type default)
		)
		(layer "In11.Cu")
	)
	(gr_line
		(start 372.687088 -240.922048)
		(end 372.68785 -240.92154)
		(stroke
			(width 0.05715)
			(type default)
		)
		(layer "In11.Cu")
	)
	(gr_line
		(start 372.687088 -239.94618)
		(end 372.685818 -239.945418)
		(stroke
			(width 0.05715)
			(type default)
		)
		(layer "In11.Cu")
	)
	(gr_line
		(start 372.687088 -239.302036)
		(end 372.68785 -239.301528)
		(stroke
			(width 0.05715)
			(type default)
		)
		(layer "In11.Cu")
	)
	(gr_line
		(start 372.687088 -238.326168)
		(end 372.685818 -238.325406)
		(stroke
			(width 0.05715)
			(type default)
		)
		(layer "In11.Cu")
	)
	(gr_line
		(start 372.687088 -236.706156)
		(end 372.685818 -236.705394)
		(stroke
			(width 0.05715)
			(type default)
		)
		(layer "In11.Cu")
	)
	(gr_line
		(start 372.687088 -236.062012)
		(end 372.68785 -236.061504)
		(stroke
			(width 0.05715)
			(type default)
		)
		(layer "In11.Cu")
	)
	(gr_line
		(start 372.687088 -235.086144)
		(end 372.685818 -235.085382)
		(stroke
			(width 0.05715)
			(type default)
		)
		(layer "In11.Cu")
	)
	(gr_line
		(start 372.687088 -234.442)
		(end 372.68785 -234.441492)
		(stroke
			(width 0.05715)
			(type default)
		)
		(layer "In11.Cu")
	)
	(gr_line
		(start 372.687088 -233.466132)
		(end 372.685818 -233.46537)
		(stroke
			(width 0.05715)
			(type default)
		)
		(layer "In11.Cu")
	)
	(gr_line
		(start 372.687088 -232.821988)
		(end 372.68785 -232.82148)
		(stroke
			(width 0.05715)
			(type default)
		)
		(layer "In11.Cu")
	)
	(gr_line
		(start 372.687088 -231.84612)
		(end 372.685818 -231.845358)
		(stroke
			(width 0.05715)
			(type default)
		)
		(layer "In11.Cu")
	)
	(gr_line
		(start 372.687088 -228.60635)
		(end 372.68658 -228.606096)
		(stroke
			(width 0.05715)
			(type default)
		)
		(layer "In11.Cu")
	)
	(gr_line
		(start 372.687342 -245.78183)
		(end 372.68785 -245.781576)
		(stroke
			(width 0.05715)
			(type default)
		)
		(layer "In11.Cu")
	)
	(gr_line
		(start 372.687342 -242.541806)
		(end 372.68785 -242.541552)
		(stroke
			(width 0.05715)
			(type default)
		)
		(layer "In11.Cu")
	)
	(gr_line
		(start 372.687342 -237.68177)
		(end 372.68785 -237.681516)
		(stroke
			(width 0.05715)
			(type default)
		)
		(layer "In11.Cu")
	)
	(gr_line
		(start 372.687596 -246.426482)
		(end 372.687088 -246.426228)
		(stroke
			(width 0.05715)
			(type default)
		)
		(layer "In11.Cu")
	)
	(gr_line
		(start 372.687596 -244.80647)
		(end 372.687088 -244.806216)
		(stroke
			(width 0.05715)
			(type default)
		)
		(layer "In11.Cu")
	)
	(gr_line
		(start 372.687596 -243.186458)
		(end 372.687088 -243.186204)
		(stroke
			(width 0.05715)
			(type default)
		)
		(layer "In11.Cu")
	)
	(gr_line
		(start 372.687596 -241.566446)
		(end 372.687088 -241.566192)
		(stroke
			(width 0.05715)
			(type default)
		)
		(layer "In11.Cu")
	)
	(gr_line
		(start 372.687596 -239.946434)
		(end 372.687088 -239.94618)
		(stroke
			(width 0.05715)
			(type default)
		)
		(layer "In11.Cu")
	)
	(gr_line
		(start 372.687596 -236.70641)
		(end 372.687088 -236.706156)
		(stroke
			(width 0.05715)
			(type default)
		)
		(layer "In11.Cu")
	)
	(gr_line
		(start 372.687596 -235.086398)
		(end 372.687088 -235.086144)
		(stroke
			(width 0.05715)
			(type default)
		)
		(layer "In11.Cu")
	)
	(gr_line
		(start 372.687596 -233.466386)
		(end 372.687088 -233.466132)
		(stroke
			(width 0.05715)
			(type default)
		)
		(layer "In11.Cu")
	)
	(gr_line
		(start 372.687596 -231.846374)
		(end 372.687088 -231.84612)
		(stroke
			(width 0.05715)
			(type default)
		)
		(layer "In11.Cu")
	)
	(gr_line
		(start 372.68785 -245.781576)
		(end 372.688866 -245.781068)
		(stroke
			(width 0.05715)
			(type default)
		)
		(layer "In11.Cu")
	)
	(gr_line
		(start 372.68785 -242.541552)
		(end 372.688866 -242.541044)
		(stroke
			(width 0.05715)
			(type default)
		)
		(layer "In11.Cu")
	)
	(gr_line
		(start 372.68785 -237.681516)
		(end 372.688866 -237.681008)
		(stroke
			(width 0.05715)
			(type default)
		)
		(layer "In11.Cu")
	)
	(gr_line
		(start 372.688866 -226.987354)
		(end 372.68785 -226.986846)
		(stroke
			(width 0.05715)
			(type default)
		)
		(layer "In11.Cu")
	)
	(gr_line
		(start 372.69039 -226.98837)
		(end 372.688866 -226.987354)
		(stroke
			(width 0.05715)
			(type default)
		)
		(layer "In11.Cu")
	)
	(gr_line
		(start 372.691406 -226.988878)
		(end 372.69039 -226.98837)
		(stroke
			(width 0.05715)
			(type default)
		)
		(layer "In11.Cu")
	)
	(gr_line
		(start 372.692168 -226.339146)
		(end 372.69293 -226.338638)
		(stroke
			(width 0.05715)
			(type default)
		)
		(layer "In11.Cu")
	)
	(gr_line
		(start 372.69293 -226.338638)
		(end 372.693946 -226.33813)
		(stroke
			(width 0.05715)
			(type default)
		)
		(layer "In11.Cu")
	)
	(gr_line
		(start 372.693946 -226.33813)
		(end 372.695724 -226.337114)
		(stroke
			(width 0.05715)
			(type default)
		)
		(layer "In11.Cu")
	)
	(gr_line
		(start 372.696486 -226.991926)
		(end 372.691406 -226.988878)
		(stroke
			(width 0.05715)
			(type default)
		)
		(layer "In11.Cu")
	)
	(gr_line
		(start 372.701058 -224.48266)
		(end 372.701566 -224.482406)
		(stroke
			(width 0.05715)
			(type default)
		)
		(layer "In11.Cu")
	)
	(gr_line
		(start 372.719346 -246.445024)
		(end 372.718584 -246.444516)
		(stroke
			(width 0.05715)
			(type default)
		)
		(layer "In11.Cu")
	)
	(gr_line
		(start 372.719346 -244.825012)
		(end 372.718584 -244.824504)
		(stroke
			(width 0.05715)
			(type default)
		)
		(layer "In11.Cu")
	)
	(gr_line
		(start 372.719346 -243.205)
		(end 372.718584 -243.204492)
		(stroke
			(width 0.05715)
			(type default)
		)
		(layer "In11.Cu")
	)
	(gr_line
		(start 372.719346 -241.584988)
		(end 372.718584 -241.58448)
		(stroke
			(width 0.05715)
			(type default)
		)
		(layer "In11.Cu")
	)
	(gr_line
		(start 372.719346 -239.964976)
		(end 372.718584 -239.964468)
		(stroke
			(width 0.05715)
			(type default)
		)
		(layer "In11.Cu")
	)
	(gr_line
		(start 372.719346 -236.724952)
		(end 372.718584 -236.724444)
		(stroke
			(width 0.05715)
			(type default)
		)
		(layer "In11.Cu")
	)
	(gr_line
		(start 372.719346 -235.10494)
		(end 372.718584 -235.104432)
		(stroke
			(width 0.05715)
			(type default)
		)
		(layer "In11.Cu")
	)
	(gr_line
		(start 372.719346 -233.484928)
		(end 372.718584 -233.48442)
		(stroke
			(width 0.05715)
			(type default)
		)
		(layer "In11.Cu")
	)
	(gr_line
		(start 372.719346 -231.864916)
		(end 372.718584 -231.864408)
		(stroke
			(width 0.05715)
			(type default)
		)
		(layer "In11.Cu")
	)
	(gr_line
		(start 372.720108 -246.445532)
		(end 372.719346 -246.445024)
		(stroke
			(width 0.05715)
			(type default)
		)
		(layer "In11.Cu")
	)
	(gr_line
		(start 372.720108 -244.82552)
		(end 372.719346 -244.825012)
		(stroke
			(width 0.05715)
			(type default)
		)
		(layer "In11.Cu")
	)
	(gr_line
		(start 372.720108 -243.205508)
		(end 372.719346 -243.205)
		(stroke
			(width 0.05715)
			(type default)
		)
		(layer "In11.Cu")
	)
	(gr_line
		(start 372.720108 -241.585496)
		(end 372.719346 -241.584988)
		(stroke
			(width 0.05715)
			(type default)
		)
		(layer "In11.Cu")
	)
	(gr_line
		(start 372.720108 -239.965484)
		(end 372.719346 -239.964976)
		(stroke
			(width 0.05715)
			(type default)
		)
		(layer "In11.Cu")
	)
	(gr_line
		(start 372.720108 -236.72546)
		(end 372.719346 -236.724952)
		(stroke
			(width 0.05715)
			(type default)
		)
		(layer "In11.Cu")
	)
	(gr_line
		(start 372.720108 -235.105448)
		(end 372.719346 -235.10494)
		(stroke
			(width 0.05715)
			(type default)
		)
		(layer "In11.Cu")
	)
	(gr_line
		(start 372.720108 -233.485436)
		(end 372.719346 -233.484928)
		(stroke
			(width 0.05715)
			(type default)
		)
		(layer "In11.Cu")
	)
	(gr_line
		(start 372.720108 -231.865424)
		(end 372.719346 -231.864916)
		(stroke
			(width 0.05715)
			(type default)
		)
		(layer "In11.Cu")
	)
	(gr_line
		(start 372.726966 -246.449596)
		(end 372.720108 -246.445532)
		(stroke
			(width 0.05715)
			(type default)
		)
		(layer "In11.Cu")
	)
	(gr_line
		(start 372.726966 -244.829584)
		(end 372.720108 -244.82552)
		(stroke
			(width 0.05715)
			(type default)
		)
		(layer "In11.Cu")
	)
	(gr_line
		(start 372.726966 -243.209572)
		(end 372.720108 -243.205508)
		(stroke
			(width 0.05715)
			(type default)
		)
		(layer "In11.Cu")
	)
	(gr_line
		(start 372.726966 -241.58956)
		(end 372.720108 -241.585496)
		(stroke
			(width 0.05715)
			(type default)
		)
		(layer "In11.Cu")
	)
	(gr_line
		(start 372.726966 -239.969548)
		(end 372.720108 -239.965484)
		(stroke
			(width 0.05715)
			(type default)
		)
		(layer "In11.Cu")
	)
	(gr_line
		(start 372.726966 -236.729524)
		(end 372.720108 -236.72546)
		(stroke
			(width 0.05715)
			(type default)
		)
		(layer "In11.Cu")
	)
	(gr_line
		(start 372.726966 -235.109512)
		(end 372.720108 -235.105448)
		(stroke
			(width 0.05715)
			(type default)
		)
		(layer "In11.Cu")
	)
	(gr_line
		(start 372.726966 -233.4895)
		(end 372.720108 -233.485436)
		(stroke
			(width 0.05715)
			(type default)
		)
		(layer "In11.Cu")
	)
	(gr_line
		(start 372.726966 -231.869488)
		(end 372.720108 -231.865424)
		(stroke
			(width 0.05715)
			(type default)
		)
		(layer "In11.Cu")
	)
	(gr_arc
		(start 372.73484 -246.455184)
		(mid 372.730915 -246.452373)
		(end 372.726966 -246.449596)
		(stroke
			(width 0.05715)
			(type default)
		)
		(layer "In11.Cu")
	)
	(gr_arc
		(start 372.73484 -244.835172)
		(mid 372.730915 -244.832361)
		(end 372.726966 -244.829584)
		(stroke
			(width 0.05715)
			(type default)
		)
		(layer "In11.Cu")
	)
	(gr_arc
		(start 372.73484 -243.21516)
		(mid 372.730915 -243.212349)
		(end 372.726966 -243.209572)
		(stroke
			(width 0.05715)
			(type default)
		)
		(layer "In11.Cu")
	)
	(gr_arc
		(start 372.73484 -241.595148)
		(mid 372.730915 -241.592337)
		(end 372.726966 -241.58956)
		(stroke
			(width 0.05715)
			(type default)
		)
		(layer "In11.Cu")
	)
	(gr_arc
		(start 372.73484 -239.975136)
		(mid 372.730915 -239.972325)
		(end 372.726966 -239.969548)
		(stroke
			(width 0.05715)
			(type default)
		)
		(layer "In11.Cu")
	)
	(gr_arc
		(start 372.73484 -236.735112)
		(mid 372.730915 -236.732301)
		(end 372.726966 -236.729524)
		(stroke
			(width 0.05715)
			(type default)
		)
		(layer "In11.Cu")
	)
	(gr_arc
		(start 372.73484 -235.1151)
		(mid 372.730915 -235.112289)
		(end 372.726966 -235.109512)
		(stroke
			(width 0.05715)
			(type default)
		)
		(layer "In11.Cu")
	)
	(gr_arc
		(start 372.73484 -233.495088)
		(mid 372.730915 -233.492277)
		(end 372.726966 -233.4895)
		(stroke
			(width 0.05715)
			(type default)
		)
		(layer "In11.Cu")
	)
	(gr_arc
		(start 372.73484 -231.875076)
		(mid 372.730915 -231.872265)
		(end 372.726966 -231.869488)
		(stroke
			(width 0.05715)
			(type default)
		)
		(layer "In11.Cu")
	)
	(gr_line
		(start 372.779544 -224.233232)
		(end 372.779544 -224.227644)
		(stroke
			(width 0.05715)
			(type default)
		)
		(layer "In11.Cu")
	)
	(gr_arc
		(start 372.779544 -222.607632)
		(mid 372.779534 -222.610934)
		(end 372.779544 -222.614236)
		(stroke
			(width 0.05715)
			(type default)
		)
		(layer "In11.Cu")
	)
	(gr_arc
		(start 372.779798 -224.223834)
		(mid 372.779668 -224.225739)
		(end 372.779544 -224.227644)
		(stroke
			(width 0.05715)
			(type default)
		)
		(layer "In11.Cu")
	)
	(gr_line
		(start 372.800118 -296.128694)
		(end 372.799864 -296.128694)
		(stroke
			(width 0.05715)
			(type default)
		)
		(layer "In11.Cu")
	)
	(gr_line
		(start 372.812818 -296.876216)
		(end 372.812818 -296.876724)
		(stroke
			(width 0.07112)
			(type default)
		)
		(layer "In11.Cu")
	)
	(gr_line
		(start 372.812818 -296.837862)
		(end 372.812818 -296.86631)
		(stroke
			(width 0.05715)
			(type default)
		)
		(layer "In11.Cu")
	)
	(gr_arc
		(start 372.844822 -294.79494)
		(mid 372.848747 -294.797751)
		(end 372.852696 -294.800528)
		(stroke
			(width 0.05715)
			(type default)
		)
		(layer "In11.Cu")
	)
	(gr_arc
		(start 372.844822 -293.174928)
		(mid 372.848747 -293.177739)
		(end 372.852696 -293.180516)
		(stroke
			(width 0.05715)
			(type default)
		)
		(layer "In11.Cu")
	)
	(gr_arc
		(start 372.844822 -289.934904)
		(mid 372.848747 -289.937715)
		(end 372.852696 -289.940492)
		(stroke
			(width 0.05715)
			(type default)
		)
		(layer "In11.Cu")
	)
	(gr_arc
		(start 372.844822 -281.835098)
		(mid 372.848747 -281.837909)
		(end 372.852696 -281.840686)
		(stroke
			(width 0.05715)
			(type default)
		)
		(layer "In11.Cu")
	)
	(gr_arc
		(start 372.844822 -278.595074)
		(mid 372.848747 -278.597885)
		(end 372.852696 -278.600662)
		(stroke
			(width 0.05715)
			(type default)
		)
		(layer "In11.Cu")
	)
	(gr_arc
		(start 372.844822 -276.975062)
		(mid 372.848747 -276.977873)
		(end 372.852696 -276.98065)
		(stroke
			(width 0.05715)
			(type default)
		)
		(layer "In11.Cu")
	)
	(gr_line
		(start 372.852696 -294.800528)
		(end 372.859554 -294.804592)
		(stroke
			(width 0.05715)
			(type default)
		)
		(layer "In11.Cu")
	)
	(gr_line
		(start 372.852696 -293.180516)
		(end 372.859554 -293.18458)
		(stroke
			(width 0.05715)
			(type default)
		)
		(layer "In11.Cu")
	)
	(gr_line
		(start 372.852696 -289.940492)
		(end 372.859554 -289.944556)
		(stroke
			(width 0.05715)
			(type default)
		)
		(layer "In11.Cu")
	)
	(gr_line
		(start 372.852696 -281.840686)
		(end 372.859554 -281.84475)
		(stroke
			(width 0.05715)
			(type default)
		)
		(layer "In11.Cu")
	)
	(gr_line
		(start 372.852696 -278.600662)
		(end 372.859554 -278.604726)
		(stroke
			(width 0.05715)
			(type default)
		)
		(layer "In11.Cu")
	)
	(gr_line
		(start 372.852696 -276.98065)
		(end 372.859554 -276.984714)
		(stroke
			(width 0.05715)
			(type default)
		)
		(layer "In11.Cu")
	)
	(gr_line
		(start 372.858538 -296.792142)
		(end 372.812818 -296.837862)
		(stroke
			(width 0.05715)
			(type default)
		)
		(layer "In11.Cu")
	)
	(gr_line
		(start 372.859554 -294.804592)
		(end 372.860316 -294.8051)
		(stroke
			(width 0.05715)
			(type default)
		)
		(layer "In11.Cu")
	)
	(gr_line
		(start 372.859554 -293.18458)
		(end 372.860316 -293.185088)
		(stroke
			(width 0.05715)
			(type default)
		)
		(layer "In11.Cu")
	)
	(gr_line
		(start 372.859554 -289.944556)
		(end 372.860316 -289.945064)
		(stroke
			(width 0.05715)
			(type default)
		)
		(layer "In11.Cu")
	)
	(gr_line
		(start 372.859554 -281.84475)
		(end 372.860316 -281.845258)
		(stroke
			(width 0.05715)
			(type default)
		)
		(layer "In11.Cu")
	)
	(gr_line
		(start 372.859554 -278.604726)
		(end 372.860316 -278.605234)
		(stroke
			(width 0.05715)
			(type default)
		)
		(layer "In11.Cu")
	)
	(gr_line
		(start 372.859554 -276.984714)
		(end 372.860316 -276.985222)
		(stroke
			(width 0.05715)
			(type default)
		)
		(layer "In11.Cu")
	)
	(gr_line
		(start 372.860316 -294.8051)
		(end 372.861078 -294.805608)
		(stroke
			(width 0.05715)
			(type default)
		)
		(layer "In11.Cu")
	)
	(gr_line
		(start 372.860316 -293.185088)
		(end 372.861078 -293.185596)
		(stroke
			(width 0.05715)
			(type default)
		)
		(layer "In11.Cu")
	)
	(gr_line
		(start 372.860316 -289.945064)
		(end 372.861078 -289.945572)
		(stroke
			(width 0.05715)
			(type default)
		)
		(layer "In11.Cu")
	)
	(gr_line
		(start 372.860316 -281.845258)
		(end 372.861078 -281.845766)
		(stroke
			(width 0.05715)
			(type default)
		)
		(layer "In11.Cu")
	)
	(gr_line
		(start 372.860316 -278.605234)
		(end 372.861078 -278.605742)
		(stroke
			(width 0.05715)
			(type default)
		)
		(layer "In11.Cu")
	)
	(gr_line
		(start 372.860316 -276.985222)
		(end 372.861078 -276.98573)
		(stroke
			(width 0.05715)
			(type default)
		)
		(layer "In11.Cu")
	)
	(gr_line
		(start 372.874794 -247.724168)
		(end 373.172736 -247.724168)
		(stroke
			(width 0.05715)
			(type default)
		)
		(layer "In11.Cu")
	)
	(gr_line
		(start 372.874794 -246.104156)
		(end 373.172736 -246.104156)
		(stroke
			(width 0.05715)
			(type default)
		)
		(layer "In11.Cu")
	)
	(gr_line
		(start 372.874794 -244.484144)
		(end 373.172736 -244.484144)
		(stroke
			(width 0.05715)
			(type default)
		)
		(layer "In11.Cu")
	)
	(gr_line
		(start 372.885716 -292.23208)
		(end 372.8847 -292.232842)
		(stroke
			(width 0.05715)
			(type default)
		)
		(layer "In11.Cu")
	)
	(gr_line
		(start 372.885716 -290.612068)
		(end 372.8847 -290.61283)
		(stroke
			(width 0.05715)
			(type default)
		)
		(layer "In11.Cu")
	)
	(gr_line
		(start 372.885716 -288.992056)
		(end 372.8847 -288.992818)
		(stroke
			(width 0.05715)
			(type default)
		)
		(layer "In11.Cu")
	)
	(gr_line
		(start 372.885716 -285.752286)
		(end 372.8847 -285.753048)
		(stroke
			(width 0.05715)
			(type default)
		)
		(layer "In11.Cu")
	)
	(gr_line
		(start 372.885716 -284.132274)
		(end 372.8847 -284.133036)
		(stroke
			(width 0.05715)
			(type default)
		)
		(layer "In11.Cu")
	)
	(gr_line
		(start 372.885716 -282.512262)
		(end 372.8847 -282.513024)
		(stroke
			(width 0.05715)
			(type default)
		)
		(layer "In11.Cu")
	)
	(gr_line
		(start 372.885716 -280.89225)
		(end 372.8847 -280.893012)
		(stroke
			(width 0.05715)
			(type default)
		)
		(layer "In11.Cu")
	)
	(gr_line
		(start 372.885716 -277.652226)
		(end 372.8847 -277.652988)
		(stroke
			(width 0.05715)
			(type default)
		)
		(layer "In11.Cu")
	)
	(gr_line
		(start 372.885716 -276.032214)
		(end 372.8847 -276.032976)
		(stroke
			(width 0.05715)
			(type default)
		)
		(layer "In11.Cu")
	)
	(gr_line
		(start 372.887494 -292.231064)
		(end 372.885716 -292.23208)
		(stroke
			(width 0.05715)
			(type default)
		)
		(layer "In11.Cu")
	)
	(gr_line
		(start 372.887494 -290.611052)
		(end 372.885716 -290.612068)
		(stroke
			(width 0.05715)
			(type default)
		)
		(layer "In11.Cu")
	)
	(gr_line
		(start 372.887494 -288.99104)
		(end 372.885716 -288.992056)
		(stroke
			(width 0.05715)
			(type default)
		)
		(layer "In11.Cu")
	)
	(gr_line
		(start 372.887494 -285.75127)
		(end 372.885716 -285.752286)
		(stroke
			(width 0.05715)
			(type default)
		)
		(layer "In11.Cu")
	)
	(gr_line
		(start 372.887494 -284.131258)
		(end 372.885716 -284.132274)
		(stroke
			(width 0.05715)
			(type default)
		)
		(layer "In11.Cu")
	)
	(gr_line
		(start 372.887494 -282.511246)
		(end 372.885716 -282.512262)
		(stroke
			(width 0.05715)
			(type default)
		)
		(layer "In11.Cu")
	)
	(gr_line
		(start 372.887494 -280.891234)
		(end 372.885716 -280.89225)
		(stroke
			(width 0.05715)
			(type default)
		)
		(layer "In11.Cu")
	)
	(gr_line
		(start 372.887494 -277.65121)
		(end 372.885716 -277.652226)
		(stroke
			(width 0.05715)
			(type default)
		)
		(layer "In11.Cu")
	)
	(gr_line
		(start 372.887494 -276.031198)
		(end 372.885716 -276.032214)
		(stroke
			(width 0.05715)
			(type default)
		)
		(layer "In11.Cu")
	)
	(gr_line
		(start 372.890796 -292.229032)
		(end 372.889272 -292.230048)
		(stroke
			(width 0.05715)
			(type default)
		)
		(layer "In11.Cu")
	)
	(gr_line
		(start 372.890796 -290.60902)
		(end 372.889272 -290.610036)
		(stroke
			(width 0.05715)
			(type default)
		)
		(layer "In11.Cu")
	)
	(gr_line
		(start 372.890796 -288.989008)
		(end 372.889272 -288.990024)
		(stroke
			(width 0.05715)
			(type default)
		)
		(layer "In11.Cu")
	)
	(gr_line
		(start 372.890796 -285.749238)
		(end 372.889272 -285.750254)
		(stroke
			(width 0.05715)
			(type default)
		)
		(layer "In11.Cu")
	)
	(gr_line
		(start 372.890796 -284.129226)
		(end 372.889272 -284.130242)
		(stroke
			(width 0.05715)
			(type default)
		)
		(layer "In11.Cu")
	)
	(gr_line
		(start 372.890796 -282.509214)
		(end 372.889272 -282.51023)
		(stroke
			(width 0.05715)
			(type default)
		)
		(layer "In11.Cu")
	)
	(gr_line
		(start 372.890796 -280.889202)
		(end 372.889272 -280.890218)
		(stroke
			(width 0.05715)
			(type default)
		)
		(layer "In11.Cu")
	)
	(gr_line
		(start 372.890796 -277.649178)
		(end 372.889272 -277.650194)
		(stroke
			(width 0.05715)
			(type default)
		)
		(layer "In11.Cu")
	)
	(gr_line
		(start 372.890796 -276.029166)
		(end 372.889272 -276.030182)
		(stroke
			(width 0.05715)
			(type default)
		)
		(layer "In11.Cu")
	)
	(gr_line
		(start 372.891558 -292.228524)
		(end 372.890796 -292.229032)
		(stroke
			(width 0.05715)
			(type default)
		)
		(layer "In11.Cu")
	)
	(gr_line
		(start 372.891558 -290.608512)
		(end 372.890796 -290.60902)
		(stroke
			(width 0.05715)
			(type default)
		)
		(layer "In11.Cu")
	)
	(gr_line
		(start 372.891558 -288.9885)
		(end 372.890796 -288.989008)
		(stroke
			(width 0.05715)
			(type default)
		)
		(layer "In11.Cu")
	)
	(gr_line
		(start 372.891558 -285.74873)
		(end 372.890796 -285.749238)
		(stroke
			(width 0.05715)
			(type default)
		)
		(layer "In11.Cu")
	)
	(gr_line
		(start 372.891558 -284.128718)
		(end 372.890796 -284.129226)
		(stroke
			(width 0.05715)
			(type default)
		)
		(layer "In11.Cu")
	)
	(gr_line
		(start 372.891558 -282.508706)
		(end 372.890796 -282.509214)
		(stroke
			(width 0.05715)
			(type default)
		)
		(layer "In11.Cu")
	)
	(gr_line
		(start 372.891558 -280.888694)
		(end 372.890796 -280.889202)
		(stroke
			(width 0.05715)
			(type default)
		)
		(layer "In11.Cu")
	)
	(gr_line
		(start 372.891558 -277.64867)
		(end 372.890796 -277.649178)
		(stroke
			(width 0.05715)
			(type default)
		)
		(layer "In11.Cu")
	)
	(gr_line
		(start 372.891558 -276.028658)
		(end 372.890796 -276.029166)
		(stroke
			(width 0.05715)
			(type default)
		)
		(layer "In11.Cu")
	)
	(gr_line
		(start 372.891812 -293.848536)
		(end 372.890796 -293.849044)
		(stroke
			(width 0.05715)
			(type default)
		)
		(layer "In11.Cu")
	)
	(gr_line
		(start 372.892066 -294.823642)
		(end 372.892574 -294.823896)
		(stroke
			(width 0.05715)
			(type default)
		)
		(layer "In11.Cu")
	)
	(gr_line
		(start 372.892066 -293.20363)
		(end 372.892574 -293.203884)
		(stroke
			(width 0.05715)
			(type default)
		)
		(layer "In11.Cu")
	)
	(gr_line
		(start 372.892066 -289.963606)
		(end 372.892574 -289.96386)
		(stroke
			(width 0.05715)
			(type default)
		)
		(layer "In11.Cu")
	)
	(gr_line
		(start 372.892066 -281.8638)
		(end 372.892574 -281.864054)
		(stroke
			(width 0.05715)
			(type default)
		)
		(layer "In11.Cu")
	)
	(gr_line
		(start 372.892066 -278.623776)
		(end 372.892574 -278.62403)
		(stroke
			(width 0.05715)
			(type default)
		)
		(layer "In11.Cu")
	)
	(gr_line
		(start 372.892066 -277.003764)
		(end 372.892574 -277.004018)
		(stroke
			(width 0.05715)
			(type default)
		)
		(layer "In11.Cu")
	)
	(gr_line
		(start 372.89232 -293.848282)
		(end 372.891812 -293.848536)
		(stroke
			(width 0.05715)
			(type default)
		)
		(layer "In11.Cu")
	)
	(gr_line
		(start 372.892574 -294.823896)
		(end 372.893844 -294.824658)
		(stroke
			(width 0.05715)
			(type default)
		)
		(layer "In11.Cu")
	)
	(gr_line
		(start 372.892574 -293.203884)
		(end 372.893844 -293.204646)
		(stroke
			(width 0.05715)
			(type default)
		)
		(layer "In11.Cu")
	)
	(gr_line
		(start 372.892574 -291.583872)
		(end 372.893844 -291.584634)
		(stroke
			(width 0.05715)
			(type default)
		)
		(layer "In11.Cu")
	)
	(gr_line
		(start 372.892574 -289.96386)
		(end 372.893844 -289.964622)
		(stroke
			(width 0.05715)
			(type default)
		)
		(layer "In11.Cu")
	)
	(gr_line
		(start 372.892574 -285.104078)
		(end 372.893844 -285.10484)
		(stroke
			(width 0.05715)
			(type default)
		)
		(layer "In11.Cu")
	)
	(gr_line
		(start 372.892574 -283.484066)
		(end 372.893844 -283.484828)
		(stroke
			(width 0.05715)
			(type default)
		)
		(layer "In11.Cu")
	)
	(gr_line
		(start 372.892574 -281.864054)
		(end 372.893844 -281.864816)
		(stroke
			(width 0.05715)
			(type default)
		)
		(layer "In11.Cu")
	)
	(gr_line
		(start 372.892574 -278.62403)
		(end 372.893844 -278.624792)
		(stroke
			(width 0.05715)
			(type default)
		)
		(layer "In11.Cu")
	)
	(gr_line
		(start 372.892574 -277.004018)
		(end 372.893844 -277.00478)
		(stroke
			(width 0.05715)
			(type default)
		)
		(layer "In11.Cu")
	)
	(gr_line
		(start 372.893844 -294.824658)
		(end 372.895368 -294.82542)
		(stroke
			(width 0.05715)
			(type default)
		)
		(layer "In11.Cu")
	)
	(gr_line
		(start 372.893844 -293.204646)
		(end 372.895368 -293.205408)
		(stroke
			(width 0.05715)
			(type default)
		)
		(layer "In11.Cu")
	)
	(gr_line
		(start 372.893844 -289.964622)
		(end 372.895368 -289.965384)
		(stroke
			(width 0.05715)
			(type default)
		)
		(layer "In11.Cu")
	)
	(gr_line
		(start 372.893844 -281.864816)
		(end 372.895368 -281.865578)
		(stroke
			(width 0.05715)
			(type default)
		)
		(layer "In11.Cu")
	)
	(gr_line
		(start 372.893844 -278.624792)
		(end 372.895368 -278.625554)
		(stroke
			(width 0.05715)
			(type default)
		)
		(layer "In11.Cu")
	)
	(gr_line
		(start 372.893844 -277.00478)
		(end 372.895368 -277.005542)
		(stroke
			(width 0.05715)
			(type default)
		)
		(layer "In11.Cu")
	)
	(gr_arc
		(start 372.970044 -222.62084)
		(mid 372.970054 -222.617538)
		(end 372.970044 -222.614236)
		(stroke
			(width 0.05715)
			(type default)
		)
		(layer "In11.Cu")
	)
	(gr_line
		(start 372.983506 -292.39591)
		(end 372.981982 -292.396672)
		(stroke
			(width 0.05715)
			(type default)
		)
		(layer "In11.Cu")
	)
	(gr_line
		(start 372.983506 -290.775898)
		(end 372.981982 -290.77666)
		(stroke
			(width 0.05715)
			(type default)
		)
		(layer "In11.Cu")
	)
	(gr_line
		(start 372.983506 -289.155886)
		(end 372.981982 -289.156648)
		(stroke
			(width 0.05715)
			(type default)
		)
		(layer "In11.Cu")
	)
	(gr_line
		(start 372.983506 -285.916116)
		(end 372.981982 -285.916878)
		(stroke
			(width 0.05715)
			(type default)
		)
		(layer "In11.Cu")
	)
	(gr_line
		(start 372.983506 -284.296104)
		(end 372.981982 -284.296866)
		(stroke
			(width 0.05715)
			(type default)
		)
		(layer "In11.Cu")
	)
	(gr_line
		(start 372.983506 -282.676092)
		(end 372.981982 -282.676854)
		(stroke
			(width 0.05715)
			(type default)
		)
		(layer "In11.Cu")
	)
	(gr_line
		(start 372.983506 -281.05608)
		(end 372.981982 -281.056842)
		(stroke
			(width 0.05715)
			(type default)
		)
		(layer "In11.Cu")
	)
	(gr_line
		(start 372.983506 -277.816056)
		(end 372.981982 -277.816818)
		(stroke
			(width 0.05715)
			(type default)
		)
		(layer "In11.Cu")
	)
	(gr_line
		(start 372.983506 -276.196044)
		(end 372.981982 -276.196806)
		(stroke
			(width 0.05715)
			(type default)
		)
		(layer "In11.Cu")
	)
	(gr_line
		(start 372.984268 -292.395402)
		(end 372.983506 -292.39591)
		(stroke
			(width 0.05715)
			(type default)
		)
		(layer "In11.Cu")
	)
	(gr_line
		(start 372.984268 -290.77539)
		(end 372.983506 -290.775898)
		(stroke
			(width 0.05715)
			(type default)
		)
		(layer "In11.Cu")
	)
	(gr_line
		(start 372.984268 -289.155378)
		(end 372.983506 -289.155886)
		(stroke
			(width 0.05715)
			(type default)
		)
		(layer "In11.Cu")
	)
	(gr_line
		(start 372.984268 -285.915608)
		(end 372.983506 -285.916116)
		(stroke
			(width 0.05715)
			(type default)
		)
		(layer "In11.Cu")
	)
	(gr_line
		(start 372.984268 -284.295596)
		(end 372.983506 -284.296104)
		(stroke
			(width 0.05715)
			(type default)
		)
		(layer "In11.Cu")
	)
	(gr_line
		(start 372.984268 -282.675584)
		(end 372.983506 -282.676092)
		(stroke
			(width 0.05715)
			(type default)
		)
		(layer "In11.Cu")
	)
	(gr_line
		(start 372.984268 -281.055572)
		(end 372.983506 -281.05608)
		(stroke
			(width 0.05715)
			(type default)
		)
		(layer "In11.Cu")
	)
	(gr_line
		(start 372.984268 -277.815548)
		(end 372.983506 -277.816056)
		(stroke
			(width 0.05715)
			(type default)
		)
		(layer "In11.Cu")
	)
	(gr_line
		(start 372.984268 -276.195536)
		(end 372.983506 -276.196044)
		(stroke
			(width 0.05715)
			(type default)
		)
		(layer "In11.Cu")
	)
	(gr_line
		(start 372.985792 -292.39464)
		(end 372.984268 -292.395402)
		(stroke
			(width 0.05715)
			(type default)
		)
		(layer "In11.Cu")
	)
	(gr_line
		(start 372.985792 -290.774628)
		(end 372.984268 -290.77539)
		(stroke
			(width 0.05715)
			(type default)
		)
		(layer "In11.Cu")
	)
	(gr_line
		(start 372.985792 -289.154616)
		(end 372.984268 -289.155378)
		(stroke
			(width 0.05715)
			(type default)
		)
		(layer "In11.Cu")
	)
	(gr_line
		(start 372.985792 -285.914846)
		(end 372.984268 -285.915608)
		(stroke
			(width 0.05715)
			(type default)
		)
		(layer "In11.Cu")
	)
	(gr_line
		(start 372.985792 -284.294834)
		(end 372.984268 -284.295596)
		(stroke
			(width 0.05715)
			(type default)
		)
		(layer "In11.Cu")
	)
	(gr_line
		(start 372.985792 -282.674822)
		(end 372.984268 -282.675584)
		(stroke
			(width 0.05715)
			(type default)
		)
		(layer "In11.Cu")
	)
	(gr_line
		(start 372.985792 -281.05481)
		(end 372.984268 -281.055572)
		(stroke
			(width 0.05715)
			(type default)
		)
		(layer "In11.Cu")
	)
	(gr_line
		(start 372.985792 -277.814786)
		(end 372.984268 -277.815548)
		(stroke
			(width 0.05715)
			(type default)
		)
		(layer "In11.Cu")
	)
	(gr_line
		(start 372.985792 -276.194774)
		(end 372.984268 -276.195536)
		(stroke
			(width 0.05715)
			(type default)
		)
		(layer "In11.Cu")
	)
	(gr_line
		(start 372.987062 -294.01389)
		(end 372.985792 -294.014652)
		(stroke
			(width 0.05715)
			(type default)
		)
		(layer "In11.Cu")
	)
	(gr_line
		(start 372.987062 -292.393878)
		(end 372.985792 -292.39464)
		(stroke
			(width 0.05715)
			(type default)
		)
		(layer "In11.Cu")
	)
	(gr_line
		(start 372.987062 -290.773866)
		(end 372.985792 -290.774628)
		(stroke
			(width 0.05715)
			(type default)
		)
		(layer "In11.Cu")
	)
	(gr_line
		(start 372.987062 -289.153854)
		(end 372.985792 -289.154616)
		(stroke
			(width 0.05715)
			(type default)
		)
		(layer "In11.Cu")
	)
	(gr_line
		(start 372.987062 -285.914084)
		(end 372.985792 -285.914846)
		(stroke
			(width 0.05715)
			(type default)
		)
		(layer "In11.Cu")
	)
	(gr_line
		(start 372.987062 -284.294072)
		(end 372.985792 -284.294834)
		(stroke
			(width 0.05715)
			(type default)
		)
		(layer "In11.Cu")
	)
	(gr_line
		(start 372.987062 -282.67406)
		(end 372.985792 -282.674822)
		(stroke
			(width 0.05715)
			(type default)
		)
		(layer "In11.Cu")
	)
	(gr_line
		(start 372.987062 -281.054048)
		(end 372.985792 -281.05481)
		(stroke
			(width 0.05715)
			(type default)
		)
		(layer "In11.Cu")
	)
	(gr_line
		(start 372.987062 -277.814024)
		(end 372.985792 -277.814786)
		(stroke
			(width 0.05715)
			(type default)
		)
		(layer "In11.Cu")
	)
	(gr_line
		(start 372.987062 -276.194012)
		(end 372.985792 -276.194774)
		(stroke
			(width 0.05715)
			(type default)
		)
		(layer "In11.Cu")
	)
	(gr_line
		(start 372.987316 -291.418264)
		(end 372.987824 -291.418518)
		(stroke
			(width 0.05715)
			(type default)
		)
		(layer "In11.Cu")
	)
	(gr_line
		(start 372.987316 -284.93847)
		(end 372.987824 -284.938724)
		(stroke
			(width 0.05715)
			(type default)
		)
		(layer "In11.Cu")
	)
	(gr_line
		(start 372.987316 -283.318458)
		(end 372.987824 -283.318712)
		(stroke
			(width 0.05715)
			(type default)
		)
		(layer "In11.Cu")
	)
	(gr_line
		(start 372.98757 -292.393624)
		(end 372.987062 -292.393878)
		(stroke
			(width 0.05715)
			(type default)
		)
		(layer "In11.Cu")
	)
	(gr_line
		(start 372.98757 -290.773612)
		(end 372.987062 -290.773866)
		(stroke
			(width 0.05715)
			(type default)
		)
		(layer "In11.Cu")
	)
	(gr_line
		(start 372.98757 -289.1536)
		(end 372.987062 -289.153854)
		(stroke
			(width 0.05715)
			(type default)
		)
		(layer "In11.Cu")
	)
	(gr_line
		(start 372.98757 -285.91383)
		(end 372.987062 -285.914084)
		(stroke
			(width 0.05715)
			(type default)
		)
		(layer "In11.Cu")
	)
	(gr_line
		(start 372.98757 -284.293818)
		(end 372.987062 -284.294072)
		(stroke
			(width 0.05715)
			(type default)
		)
		(layer "In11.Cu")
	)
	(gr_line
		(start 372.98757 -282.673806)
		(end 372.987062 -282.67406)
		(stroke
			(width 0.05715)
			(type default)
		)
		(layer "In11.Cu")
	)
	(gr_line
		(start 372.98757 -281.053794)
		(end 372.987062 -281.054048)
		(stroke
			(width 0.05715)
			(type default)
		)
		(layer "In11.Cu")
	)
	(gr_line
		(start 372.98757 -277.81377)
		(end 372.987062 -277.814024)
		(stroke
			(width 0.05715)
			(type default)
		)
		(layer "In11.Cu")
	)
	(gr_line
		(start 372.98757 -276.193758)
		(end 372.987062 -276.194012)
		(stroke
			(width 0.05715)
			(type default)
		)
		(layer "In11.Cu")
	)
	(gr_line
		(start 372.987824 -294.658542)
		(end 372.98884 -294.65905)
		(stroke
			(width 0.05715)
			(type default)
		)
		(layer "In11.Cu")
	)
	(gr_line
		(start 372.987824 -293.03853)
		(end 372.98884 -293.039038)
		(stroke
			(width 0.05715)
			(type default)
		)
		(layer "In11.Cu")
	)
	(gr_line
		(start 372.987824 -291.418518)
		(end 372.98884 -291.419026)
		(stroke
			(width 0.05715)
			(type default)
		)
		(layer "In11.Cu")
	)
	(gr_line
		(start 372.987824 -289.798506)
		(end 372.98884 -289.799014)
		(stroke
			(width 0.05715)
			(type default)
		)
		(layer "In11.Cu")
	)
	(gr_line
		(start 372.987824 -284.938724)
		(end 372.98884 -284.939232)
		(stroke
			(width 0.05715)
			(type default)
		)
		(layer "In11.Cu")
	)
	(gr_line
		(start 372.987824 -283.318712)
		(end 372.98884 -283.31922)
		(stroke
			(width 0.05715)
			(type default)
		)
		(layer "In11.Cu")
	)
	(gr_line
		(start 372.987824 -281.6987)
		(end 372.98884 -281.699208)
		(stroke
			(width 0.05715)
			(type default)
		)
		(layer "In11.Cu")
	)
	(gr_line
		(start 372.987824 -278.458676)
		(end 372.98884 -278.459184)
		(stroke
			(width 0.05715)
			(type default)
		)
		(layer "In11.Cu")
	)
	(gr_line
		(start 372.987824 -276.838664)
		(end 372.98884 -276.839172)
		(stroke
			(width 0.05715)
			(type default)
		)
		(layer "In11.Cu")
	)
	(gr_line
		(start 372.98884 -294.65905)
		(end 372.990364 -294.660066)
		(stroke
			(width 0.05715)
			(type default)
		)
		(layer "In11.Cu")
	)
	(gr_line
		(start 372.98884 -293.039038)
		(end 372.990364 -293.040054)
		(stroke
			(width 0.05715)
			(type default)
		)
		(layer "In11.Cu")
	)
	(gr_line
		(start 372.98884 -289.799014)
		(end 372.990364 -289.80003)
		(stroke
			(width 0.05715)
			(type default)
		)
		(layer "In11.Cu")
	)
	(gr_line
		(start 372.98884 -281.699208)
		(end 372.990364 -281.700224)
		(stroke
			(width 0.05715)
			(type default)
		)
		(layer "In11.Cu")
	)
	(gr_line
		(start 372.98884 -278.459184)
		(end 372.990364 -278.4602)
		(stroke
			(width 0.05715)
			(type default)
		)
		(layer "In11.Cu")
	)
	(gr_line
		(start 372.98884 -276.839172)
		(end 372.990364 -276.840188)
		(stroke
			(width 0.05715)
			(type default)
		)
		(layer "In11.Cu")
	)
	(gr_line
		(start 372.992142 -294.661082)
		(end 372.993412 -294.661844)
		(stroke
			(width 0.05715)
			(type default)
		)
		(layer "In11.Cu")
	)
	(gr_line
		(start 372.992142 -293.04107)
		(end 372.993412 -293.041832)
		(stroke
			(width 0.05715)
			(type default)
		)
		(layer "In11.Cu")
	)
	(gr_line
		(start 372.992142 -289.801046)
		(end 372.993412 -289.801808)
		(stroke
			(width 0.05715)
			(type default)
		)
		(layer "In11.Cu")
	)
	(gr_line
		(start 372.992142 -281.70124)
		(end 372.993412 -281.702002)
		(stroke
			(width 0.05715)
			(type default)
		)
		(layer "In11.Cu")
	)
	(gr_line
		(start 372.992142 -278.461216)
		(end 372.993412 -278.461978)
		(stroke
			(width 0.05715)
			(type default)
		)
		(layer "In11.Cu")
	)
	(gr_line
		(start 372.992142 -276.841204)
		(end 372.993412 -276.841966)
		(stroke
			(width 0.05715)
			(type default)
		)
		(layer "In11.Cu")
	)
	(gr_line
		(start 372.994682 -294.662606)
		(end 372.99646 -294.663622)
		(stroke
			(width 0.05715)
			(type default)
		)
		(layer "In11.Cu")
	)
	(gr_line
		(start 372.994682 -293.042594)
		(end 372.99646 -293.04361)
		(stroke
			(width 0.05715)
			(type default)
		)
		(layer "In11.Cu")
	)
	(gr_line
		(start 372.994682 -289.80257)
		(end 372.99646 -289.803586)
		(stroke
			(width 0.05715)
			(type default)
		)
		(layer "In11.Cu")
	)
	(gr_line
		(start 372.994682 -281.702764)
		(end 372.99646 -281.70378)
		(stroke
			(width 0.05715)
			(type default)
		)
		(layer "In11.Cu")
	)
	(gr_line
		(start 372.994682 -278.46274)
		(end 372.99646 -278.463756)
		(stroke
			(width 0.05715)
			(type default)
		)
		(layer "In11.Cu")
	)
	(gr_line
		(start 372.994682 -276.842728)
		(end 372.99646 -276.843744)
		(stroke
			(width 0.05715)
			(type default)
		)
		(layer "In11.Cu")
	)
	(gr_line
		(start 373.049038 -296.792142)
		(end 373.094758 -296.837862)
		(stroke
			(width 0.05715)
			(type default)
		)
		(layer "In11.Cu")
	)
	(gr_line
		(start 373.094758 -296.837862)
		(end 373.094758 -296.86631)
		(stroke
			(width 0.05715)
			(type default)
		)
		(layer "In11.Cu")
	)
	(gr_line
		(start 373.095266 -296.89044)
		(end 373.095266 -296.890948)
		(stroke
			(width 0.07112)
			(type default)
		)
		(layer "In11.Cu")
	)
	(gr_line
		(start 373.172736 -247.724168)
		(end 373.242078 -247.654826)
		(stroke
			(width 0.05715)
			(type default)
		)
		(layer "In11.Cu")
	)
	(gr_line
		(start 373.172736 -246.104156)
		(end 373.25554 -246.021352)
		(stroke
			(width 0.05715)
			(type default)
		)
		(layer "In11.Cu")
	)
	(gr_line
		(start 373.172736 -244.484144)
		(end 373.25554 -244.40134)
		(stroke
			(width 0.05715)
			(type default)
		)
		(layer "In11.Cu")
	)
	(gr_line
		(start 373.174768 -278.136096)
		(end 373.47271 -278.136096)
		(stroke
			(width 0.05715)
			(type default)
		)
		(layer "In11.Cu")
	)
	(gr_line
		(start 373.174768 -276.516084)
		(end 373.47271 -276.516084)
		(stroke
			(width 0.05715)
			(type default)
		)
		(layer "In11.Cu")
	)
	(gr_line
		(start 373.174768 -274.896072)
		(end 373.47271 -274.896072)
		(stroke
			(width 0.05715)
			(type default)
		)
		(layer "In11.Cu")
	)
	(gr_line
		(start 373.203724 -221.202758)
		(end 373.203724 -221.17431)
		(stroke
			(width 0.05715)
			(type default)
		)
		(layer "In11.Cu")
	)
	(gr_line
		(start 373.213122 -379.5903)
		(end 372.922292 -379.88113)
		(stroke
			(width 0.07112)
			(type default)
		)
		(layer "In11.Cu")
	)
	(gr_arc
		(start 373.249444 -223.417638)
		(mid 373.249434 -223.42094)
		(end 373.249444 -223.424242)
		(stroke
			(width 0.05715)
			(type default)
		)
		(layer "In11.Cu")
	)
	(gr_line
		(start 373.249444 -221.248478)
		(end 373.203724 -221.202758)
		(stroke
			(width 0.05715)
			(type default)
		)
		(layer "In11.Cu")
	)
	(gr_arc
		(start 373.25935 -245.998492)
		(mid 373.257329 -246.009903)
		(end 373.25554 -246.021352)
		(stroke
			(width 0.05715)
			(type default)
		)
		(layer "In11.Cu")
	)
	(gr_arc
		(start 373.25935 -244.37848)
		(mid 373.257328 -244.389891)
		(end 373.25554 -244.40134)
		(stroke
			(width 0.05715)
			(type default)
		)
		(layer "In11.Cu")
	)
	(gr_line
		(start 373.361712 -295.633394)
		(end 373.361966 -295.633394)
		(stroke
			(width 0.05715)
			(type default)
		)
		(layer "In11.Cu")
	)
	(gr_line
		(start 373.374158 -334.87614)
		(end 373.374412 -334.87614)
		(stroke
			(width 0.07112)
			(type default)
		)
		(layer "In11.Cu")
	)
	(gr_arc
		(start 373.434102 -247.641364)
		(mid 373.432316 -247.629914)
		(end 373.430292 -247.618504)
		(stroke
			(width 0.05715)
			(type default)
		)
		(layer "In11.Cu")
	)
	(gr_arc
		(start 373.439944 -223.430846)
		(mid 373.439954 -223.427544)
		(end 373.439944 -223.424242)
		(stroke
			(width 0.05715)
			(type default)
		)
		(layer "In11.Cu")
	)
	(gr_line
		(start 373.439944 -221.248478)
		(end 373.485664 -221.202758)
		(stroke
			(width 0.05715)
			(type default)
		)
		(layer "In11.Cu")
	)
	(gr_line
		(start 373.47271 -278.136096)
		(end 373.555514 -278.2189)
		(stroke
			(width 0.05715)
			(type default)
		)
		(layer "In11.Cu")
	)
	(gr_line
		(start 373.47271 -276.516084)
		(end 373.555514 -276.598888)
		(stroke
			(width 0.05715)
			(type default)
		)
		(layer "In11.Cu")
	)
	(gr_line
		(start 373.47271 -274.896072)
		(end 373.542052 -274.965414)
		(stroke
			(width 0.05715)
			(type default)
		)
		(layer "In11.Cu")
	)
	(gr_arc
		(start 373.484902 -230.363014)
		(mid 373.490088 -230.366727)
		(end 373.495316 -230.37038)
		(stroke
			(width 0.05715)
			(type default)
		)
		(layer "In11.Cu")
	)
	(gr_arc
		(start 373.484902 -227.123244)
		(mid 373.488827 -227.126055)
		(end 373.492776 -227.128832)
		(stroke
			(width 0.05715)
			(type default)
		)
		(layer "In11.Cu")
	)
	(gr_line
		(start 373.485664 -221.202758)
		(end 373.485664 -221.17431)
		(stroke
			(width 0.05715)
			(type default)
		)
		(layer "In11.Cu")
	)
	(gr_arc
		(start 373.488458 -229.442518)
		(mid 373.485276 -229.444794)
		(end 373.482108 -229.44709)
		(stroke
			(width 0.05715)
			(type default)
		)
		(layer "In11.Cu")
	)
	(gr_arc
		(start 373.492776 -245.63959)
		(mid 373.4887 -245.642366)
		(end 373.484648 -245.645178)
		(stroke
			(width 0.05715)
			(type default)
		)
		(layer "In11.Cu")
	)
	(gr_arc
		(start 373.492776 -245.63959)
		(mid 373.493157 -245.639336)
		(end 373.493538 -245.639082)
		(stroke
			(width 0.05715)
			(type default)
		)
		(layer "In11.Cu")
	)
	(gr_arc
		(start 373.492776 -242.399566)
		(mid 373.488827 -242.402343)
		(end 373.484902 -242.405154)
		(stroke
			(width 0.05715)
			(type default)
		)
		(layer "In11.Cu")
	)
	(gr_arc
		(start 373.492776 -242.399566)
		(mid 373.493157 -242.399312)
		(end 373.493538 -242.399058)
		(stroke
			(width 0.05715)
			(type default)
		)
		(layer "In11.Cu")
	)
	(gr_arc
		(start 373.492776 -240.779554)
		(mid 373.488827 -240.782331)
		(end 373.484902 -240.785142)
		(stroke
			(width 0.05715)
			(type default)
		)
		(layer "In11.Cu")
	)
	(gr_arc
		(start 373.492776 -240.779554)
		(mid 373.493157 -240.7793)
		(end 373.493538 -240.779046)
		(stroke
			(width 0.05715)
			(type default)
		)
		(layer "In11.Cu")
	)
	(gr_arc
		(start 373.492776 -239.159542)
		(mid 373.488827 -239.162319)
		(end 373.484902 -239.16513)
		(stroke
			(width 0.05715)
			(type default)
		)
		(layer "In11.Cu")
	)
	(gr_arc
		(start 373.492776 -239.159542)
		(mid 373.493157 -239.159288)
		(end 373.493538 -239.159034)
		(stroke
			(width 0.05715)
			(type default)
		)
		(layer "In11.Cu")
	)
	(gr_arc
		(start 373.492776 -237.53953)
		(mid 373.488827 -237.542307)
		(end 373.484902 -237.545118)
		(stroke
			(width 0.05715)
			(type default)
		)
		(layer "In11.Cu")
	)
	(gr_arc
		(start 373.492776 -237.53953)
		(mid 373.493157 -237.539276)
		(end 373.493538 -237.539022)
		(stroke
			(width 0.05715)
			(type default)
		)
		(layer "In11.Cu")
	)
	(gr_arc
		(start 373.492776 -235.919518)
		(mid 373.488827 -235.922295)
		(end 373.484902 -235.925106)
		(stroke
			(width 0.05715)
			(type default)
		)
		(layer "In11.Cu")
	)
	(gr_arc
		(start 373.492776 -235.919518)
		(mid 373.493157 -235.919264)
		(end 373.493538 -235.91901)
		(stroke
			(width 0.05715)
			(type default)
		)
		(layer "In11.Cu")
	)
	(gr_arc
		(start 373.492776 -234.299506)
		(mid 373.488827 -234.302283)
		(end 373.484902 -234.305094)
		(stroke
			(width 0.05715)
			(type default)
		)
		(layer "In11.Cu")
	)
	(gr_arc
		(start 373.492776 -234.299506)
		(mid 373.493157 -234.299252)
		(end 373.493538 -234.298998)
		(stroke
			(width 0.05715)
			(type default)
		)
		(layer "In11.Cu")
	)
	(gr_arc
		(start 373.492776 -224.579688)
		(mid 373.488827 -224.582465)
		(end 373.484902 -224.585276)
		(stroke
			(width 0.05715)
			(type default)
		)
		(layer "In11.Cu")
	)
	(gr_line
		(start 373.492776 -224.579688)
		(end 373.493792 -224.578926)
		(stroke
			(width 0.05715)
			(type default)
		)
		(layer "In11.Cu")
	)
	(gr_line
		(start 373.493538 -245.639082)
		(end 373.501158 -245.634764)
		(stroke
			(width 0.05715)
			(type default)
		)
		(layer "In11.Cu")
	)
	(gr_line
		(start 373.493538 -242.399058)
		(end 373.501412 -242.394486)
		(stroke
			(width 0.05715)
			(type default)
		)
		(layer "In11.Cu")
	)
	(gr_line
		(start 373.493538 -240.779046)
		(end 373.501412 -240.774474)
		(stroke
			(width 0.05715)
			(type default)
		)
		(layer "In11.Cu")
	)
	(gr_line
		(start 373.493538 -239.159034)
		(end 373.501412 -239.154462)
		(stroke
			(width 0.05715)
			(type default)
		)
		(layer "In11.Cu")
	)
	(gr_line
		(start 373.493538 -237.539022)
		(end 373.501412 -237.53445)
		(stroke
			(width 0.05715)
			(type default)
		)
		(layer "In11.Cu")
	)
	(gr_line
		(start 373.493538 -235.91901)
		(end 373.499888 -235.9152)
		(stroke
			(width 0.05715)
			(type default)
		)
		(layer "In11.Cu")
	)
	(gr_line
		(start 373.493538 -234.298998)
		(end 373.496332 -234.296966)
		(stroke
			(width 0.05715)
			(type default)
		)
		(layer "In11.Cu")
	)
	(gr_line
		(start 373.493792 -224.578926)
		(end 373.500904 -224.574862)
		(stroke
			(width 0.05715)
			(type default)
		)
		(layer "In11.Cu")
	)
	(gr_line
		(start 373.495062 -379.5903)
		(end 373.785892 -379.88113)
		(stroke
			(width 0.07112)
			(type default)
		)
		(layer "In11.Cu")
	)
	(gr_line
		(start 373.49557 -227.130864)
		(end 373.492776 -227.128832)
		(stroke
			(width 0.05715)
			(type default)
		)
		(layer "In11.Cu")
	)
	(gr_line
		(start 373.496332 -234.296966)
		(end 373.500904 -234.294426)
		(stroke
			(width 0.05715)
			(type default)
		)
		(layer "In11.Cu")
	)
	(gr_line
		(start 373.499888 -235.9152)
		(end 373.50065 -235.914692)
		(stroke
			(width 0.05715)
			(type default)
		)
		(layer "In11.Cu")
	)
	(gr_line
		(start 373.499888 -230.373174)
		(end 373.495316 -230.37038)
		(stroke
			(width 0.05715)
			(type default)
		)
		(layer "In11.Cu")
	)
	(gr_line
		(start 373.50065 -235.914692)
		(end 373.501666 -235.914184)
		(stroke
			(width 0.05715)
			(type default)
		)
		(layer "In11.Cu")
	)
	(gr_line
		(start 373.500904 -227.133912)
		(end 373.49557 -227.130864)
		(stroke
			(width 0.05715)
			(type default)
		)
		(layer "In11.Cu")
	)
	(gr_line
		(start 373.501158 -230.373936)
		(end 373.499888 -230.373174)
		(stroke
			(width 0.05715)
			(type default)
		)
		(layer "In11.Cu")
	)
	(gr_line
		(start 373.502428 -241.714528)
		(end 373.500904 -241.713512)
		(stroke
			(width 0.05715)
			(type default)
		)
		(layer "In11.Cu")
	)
	(gr_line
		(start 373.502428 -240.094516)
		(end 373.500904 -240.0935)
		(stroke
			(width 0.05715)
			(type default)
		)
		(layer "In11.Cu")
	)
	(gr_line
		(start 373.502428 -238.474504)
		(end 373.500904 -238.473488)
		(stroke
			(width 0.05715)
			(type default)
		)
		(layer "In11.Cu")
	)
	(gr_line
		(start 373.502428 -236.854492)
		(end 373.500904 -236.853476)
		(stroke
			(width 0.05715)
			(type default)
		)
		(layer "In11.Cu")
	)
	(gr_line
		(start 373.502428 -235.23448)
		(end 373.500904 -235.233464)
		(stroke
			(width 0.05715)
			(type default)
		)
		(layer "In11.Cu")
	)
	(gr_line
		(start 373.51081 -241.719354)
		(end 373.511064 -241.719354)
		(stroke
			(width 0.05715)
			(type default)
		)
		(layer "In11.Cu")
	)
	(gr_line
		(start 373.51081 -240.099342)
		(end 373.511064 -240.099342)
		(stroke
			(width 0.05715)
			(type default)
		)
		(layer "In11.Cu")
	)
	(gr_line
		(start 373.51081 -238.47933)
		(end 373.511064 -238.47933)
		(stroke
			(width 0.05715)
			(type default)
		)
		(layer "In11.Cu")
	)
	(gr_line
		(start 373.51081 -236.859318)
		(end 373.511064 -236.859318)
		(stroke
			(width 0.05715)
			(type default)
		)
		(layer "In11.Cu")
	)
	(gr_line
		(start 373.51081 -235.239306)
		(end 373.511064 -235.239306)
		(stroke
			(width 0.05715)
			(type default)
		)
		(layer "In11.Cu")
	)
	(gr_line
		(start 373.516906 -247.724168)
		(end 373.434102 -247.641364)
		(stroke
			(width 0.05715)
			(type default)
		)
		(layer "In11.Cu")
	)
	(gr_line
		(start 373.516906 -246.104156)
		(end 373.447564 -246.034814)
		(stroke
			(width 0.05715)
			(type default)
		)
		(layer "In11.Cu")
	)
	(gr_line
		(start 373.516906 -244.484144)
		(end 373.447564 -244.414802)
		(stroke
			(width 0.05715)
			(type default)
		)
		(layer "In11.Cu")
	)
	(gr_line
		(start 373.525542 -242.380262)
		(end 373.526558 -242.379754)
		(stroke
			(width 0.05715)
			(type default)
		)
		(layer "In11.Cu")
	)
	(gr_line
		(start 373.525542 -240.76025)
		(end 373.526558 -240.759742)
		(stroke
			(width 0.05715)
			(type default)
		)
		(layer "In11.Cu")
	)
	(gr_line
		(start 373.525542 -239.140238)
		(end 373.526558 -239.13973)
		(stroke
			(width 0.05715)
			(type default)
		)
		(layer "In11.Cu")
	)
	(gr_line
		(start 373.525542 -237.520226)
		(end 373.526558 -237.519718)
		(stroke
			(width 0.05715)
			(type default)
		)
		(layer "In11.Cu")
	)
	(gr_line
		(start 373.525796 -228.768148)
		(end 373.52478 -228.767386)
		(stroke
			(width 0.05715)
			(type default)
		)
		(layer "In11.Cu")
	)
	(gr_line
		(start 373.526558 -242.379754)
		(end 373.52732 -242.379246)
		(stroke
			(width 0.05715)
			(type default)
		)
		(layer "In11.Cu")
	)
	(gr_line
		(start 373.526558 -240.759742)
		(end 373.52732 -240.759234)
		(stroke
			(width 0.05715)
			(type default)
		)
		(layer "In11.Cu")
	)
	(gr_line
		(start 373.526558 -239.13973)
		(end 373.52732 -239.139222)
		(stroke
			(width 0.05715)
			(type default)
		)
		(layer "In11.Cu")
	)
	(gr_line
		(start 373.526558 -237.519718)
		(end 373.52732 -237.51921)
		(stroke
			(width 0.05715)
			(type default)
		)
		(layer "In11.Cu")
	)
	(gr_line
		(start 373.52732 -242.379246)
		(end 373.5324 -242.376452)
		(stroke
			(width 0.05715)
			(type default)
		)
		(layer "In11.Cu")
	)
	(gr_line
		(start 373.52732 -240.759234)
		(end 373.5324 -240.75644)
		(stroke
			(width 0.05715)
			(type default)
		)
		(layer "In11.Cu")
	)
	(gr_line
		(start 373.52732 -239.139222)
		(end 373.5324 -239.136428)
		(stroke
			(width 0.05715)
			(type default)
		)
		(layer "In11.Cu")
	)
	(gr_line
		(start 373.52732 -237.51921)
		(end 373.5324 -237.516416)
		(stroke
			(width 0.05715)
			(type default)
		)
		(layer "In11.Cu")
	)
	(gr_line
		(start 373.52732 -235.899198)
		(end 373.528844 -235.898436)
		(stroke
			(width 0.05715)
			(type default)
		)
		(layer "In11.Cu")
	)
	(gr_line
		(start 373.528336 -228.769672)
		(end 373.525796 -228.768148)
		(stroke
			(width 0.05715)
			(type default)
		)
		(layer "In11.Cu")
	)
	(gr_line
		(start 373.528844 -235.898436)
		(end 373.5324 -235.896404)
		(stroke
			(width 0.05715)
			(type default)
		)
		(layer "In11.Cu")
	)
	(gr_line
		(start 373.529352 -228.77018)
		(end 373.528336 -228.769672)
		(stroke
			(width 0.05715)
			(type default)
		)
		(layer "In11.Cu")
	)
	(gr_line
		(start 373.530876 -243.997226)
		(end 373.531892 -243.996718)
		(stroke
			(width 0.05715)
			(type default)
		)
		(layer "In11.Cu")
	)
	(gr_line
		(start 373.530876 -230.391208)
		(end 373.529606 -230.390446)
		(stroke
			(width 0.05715)
			(type default)
		)
		(layer "In11.Cu")
	)
	(gr_line
		(start 373.530876 -228.771196)
		(end 373.529352 -228.77018)
		(stroke
			(width 0.05715)
			(type default)
		)
		(layer "In11.Cu")
	)
	(gr_line
		(start 373.530876 -227.79736)
		(end 373.531892 -227.796852)
		(stroke
			(width 0.05715)
			(type default)
		)
		(layer "In11.Cu")
	)
	(gr_line
		(start 373.531892 -243.351558)
		(end 373.530876 -243.35105)
		(stroke
			(width 0.05715)
			(type default)
		)
		(layer "In11.Cu")
	)
	(gr_line
		(start 373.531892 -233.631486)
		(end 373.530876 -233.630978)
		(stroke
			(width 0.05715)
			(type default)
		)
		(layer "In11.Cu")
	)
	(gr_line
		(start 373.531892 -232.011474)
		(end 373.530876 -232.010966)
		(stroke
			(width 0.05715)
			(type default)
		)
		(layer "In11.Cu")
	)
	(gr_line
		(start 373.531892 -230.391716)
		(end 373.530876 -230.391208)
		(stroke
			(width 0.05715)
			(type default)
		)
		(layer "In11.Cu")
	)
	(gr_line
		(start 373.531892 -228.771704)
		(end 373.530876 -228.771196)
		(stroke
			(width 0.05715)
			(type default)
		)
		(layer "In11.Cu")
	)
	(gr_line
		(start 373.532654 -230.392224)
		(end 373.531892 -230.391716)
		(stroke
			(width 0.05715)
			(type default)
		)
		(layer "In11.Cu")
	)
	(gr_line
		(start 373.532654 -228.772212)
		(end 373.531892 -228.771704)
		(stroke
			(width 0.05715)
			(type default)
		)
		(layer "In11.Cu")
	)
	(gr_line
		(start 373.533162 -228.772466)
		(end 373.532654 -228.772212)
		(stroke
			(width 0.05715)
			(type default)
		)
		(layer "In11.Cu")
	)
	(gr_line
		(start 373.533924 -230.392986)
		(end 373.532654 -230.392224)
		(stroke
			(width 0.05715)
			(type default)
		)
		(layer "In11.Cu")
	)
	(gr_line
		(start 373.535448 -230.393748)
		(end 373.533924 -230.392986)
		(stroke
			(width 0.05715)
			(type default)
		)
		(layer "In11.Cu")
	)
	(gr_arc
		(start 373.555514 -278.2189)
		(mid 373.557307 -278.230222)
		(end 373.559324 -278.241506)
		(stroke
			(width 0.05715)
			(type default)
		)
		(layer "In11.Cu")
	)
	(gr_arc
		(start 373.555514 -276.598888)
		(mid 373.557306 -276.61021)
		(end 373.559324 -276.621494)
		(stroke
			(width 0.05715)
			(type default)
		)
		(layer "In11.Cu")
	)
	(gr_line
		(start 373.6213 -228.603048)
		(end 373.620284 -228.60254)
		(stroke
			(width 0.05715)
			(type default)
		)
		(layer "In11.Cu")
	)
	(gr_line
		(start 373.622062 -236.06506)
		(end 373.623586 -236.064044)
		(stroke
			(width 0.05715)
			(type default)
		)
		(layer "In11.Cu")
	)
	(gr_line
		(start 373.622062 -228.603556)
		(end 373.6213 -228.603048)
		(stroke
			(width 0.05715)
			(type default)
		)
		(layer "In11.Cu")
	)
	(gr_line
		(start 373.623586 -236.064044)
		(end 373.624348 -236.063536)
		(stroke
			(width 0.05715)
			(type default)
		)
		(layer "In11.Cu")
	)
	(gr_line
		(start 373.623586 -228.604318)
		(end 373.622062 -228.603556)
		(stroke
			(width 0.05715)
			(type default)
		)
		(layer "In11.Cu")
	)
	(gr_line
		(start 373.624348 -228.604826)
		(end 373.623586 -228.604318)
		(stroke
			(width 0.05715)
			(type default)
		)
		(layer "In11.Cu")
	)
	(gr_line
		(start 373.625872 -244.162834)
		(end 373.627142 -244.162072)
		(stroke
			(width 0.05715)
			(type default)
		)
		(layer "In11.Cu")
	)
	(gr_line
		(start 373.625872 -227.962968)
		(end 373.627142 -227.962206)
		(stroke
			(width 0.05715)
			(type default)
		)
		(layer "In11.Cu")
	)
	(gr_line
		(start 373.626634 -234.442254)
		(end 373.627142 -234.442)
		(stroke
			(width 0.05715)
			(type default)
		)
		(layer "In11.Cu")
	)
	(gr_line
		(start 373.627142 -244.162072)
		(end 373.627904 -244.161564)
		(stroke
			(width 0.05715)
			(type default)
		)
		(layer "In11.Cu")
	)
	(gr_line
		(start 373.627142 -243.186204)
		(end 373.625872 -243.185442)
		(stroke
			(width 0.05715)
			(type default)
		)
		(layer "In11.Cu")
	)
	(gr_line
		(start 373.627142 -233.466132)
		(end 373.625872 -233.46537)
		(stroke
			(width 0.05715)
			(type default)
		)
		(layer "In11.Cu")
	)
	(gr_line
		(start 373.627142 -231.84612)
		(end 373.625872 -231.845358)
		(stroke
			(width 0.05715)
			(type default)
		)
		(layer "In11.Cu")
	)
	(gr_line
		(start 373.627142 -228.60635)
		(end 373.626634 -228.606096)
		(stroke
			(width 0.05715)
			(type default)
		)
		(layer "In11.Cu")
	)
	(gr_line
		(start 373.627142 -227.962206)
		(end 373.627904 -227.961698)
		(stroke
			(width 0.05715)
			(type default)
		)
		(layer "In11.Cu")
	)
	(gr_line
		(start 373.627396 -232.821734)
		(end 373.627904 -232.82148)
		(stroke
			(width 0.05715)
			(type default)
		)
		(layer "In11.Cu")
	)
	(gr_line
		(start 373.62765 -243.186458)
		(end 373.627142 -243.186204)
		(stroke
			(width 0.05715)
			(type default)
		)
		(layer "In11.Cu")
	)
	(gr_line
		(start 373.62765 -233.466386)
		(end 373.627142 -233.466132)
		(stroke
			(width 0.05715)
			(type default)
		)
		(layer "In11.Cu")
	)
	(gr_line
		(start 373.62765 -231.846374)
		(end 373.627142 -231.84612)
		(stroke
			(width 0.05715)
			(type default)
		)
		(layer "In11.Cu")
	)
	(gr_line
		(start 373.627904 -241.5667)
		(end 373.628158 -241.566954)
		(stroke
			(width 0.05715)
			(type default)
		)
		(layer "In11.Cu")
	)
	(gr_line
		(start 373.627904 -239.946688)
		(end 373.628158 -239.946942)
		(stroke
			(width 0.05715)
			(type default)
		)
		(layer "In11.Cu")
	)
	(gr_line
		(start 373.627904 -238.326676)
		(end 373.628158 -238.32693)
		(stroke
			(width 0.05715)
			(type default)
		)
		(layer "In11.Cu")
	)
	(gr_line
		(start 373.627904 -236.706664)
		(end 373.628158 -236.706918)
		(stroke
			(width 0.05715)
			(type default)
		)
		(layer "In11.Cu")
	)
	(gr_line
		(start 373.627904 -235.086652)
		(end 373.628158 -235.086906)
		(stroke
			(width 0.05715)
			(type default)
		)
		(layer "In11.Cu")
	)
	(gr_line
		(start 373.627904 -230.226616)
		(end 373.624602 -230.224584)
		(stroke
			(width 0.05715)
			(type default)
		)
		(layer "In11.Cu")
	)
	(gr_line
		(start 373.627904 -228.606858)
		(end 373.627142 -228.60635)
		(stroke
			(width 0.05715)
			(type default)
		)
		(layer "In11.Cu")
	)
	(gr_line
		(start 373.628158 -242.541552)
		(end 373.627904 -242.541552)
		(stroke
			(width 0.05715)
			(type default)
		)
		(layer "In11.Cu")
	)
	(gr_line
		(start 373.628158 -240.92154)
		(end 373.627904 -240.92154)
		(stroke
			(width 0.05715)
			(type default)
		)
		(layer "In11.Cu")
	)
	(gr_line
		(start 373.628158 -239.301528)
		(end 373.627904 -239.301528)
		(stroke
			(width 0.05715)
			(type default)
		)
		(layer "In11.Cu")
	)
	(gr_line
		(start 373.628158 -237.681516)
		(end 373.627904 -237.681516)
		(stroke
			(width 0.05715)
			(type default)
		)
		(layer "In11.Cu")
	)
	(gr_line
		(start 373.628158 -236.061504)
		(end 373.627904 -236.061504)
		(stroke
			(width 0.05715)
			(type default)
		)
		(layer "In11.Cu")
	)
	(gr_line
		(start 373.630444 -230.22814)
		(end 373.62892 -230.227124)
		(stroke
			(width 0.05715)
			(type default)
		)
		(layer "In11.Cu")
	)
	(gr_arc
		(start 373.634508 -242.537742)
		(mid 373.636925 -242.536351)
		(end 373.639334 -242.534948)
		(stroke
			(width 0.05715)
			(type default)
		)
		(layer "In11.Cu")
	)
	(gr_arc
		(start 373.634508 -240.91773)
		(mid 373.636925 -240.916339)
		(end 373.639334 -240.914936)
		(stroke
			(width 0.05715)
			(type default)
		)
		(layer "In11.Cu")
	)
	(gr_arc
		(start 373.634508 -239.297718)
		(mid 373.636925 -239.296327)
		(end 373.639334 -239.294924)
		(stroke
			(width 0.05715)
			(type default)
		)
		(layer "In11.Cu")
	)
	(gr_arc
		(start 373.634508 -237.677706)
		(mid 373.636925 -237.676315)
		(end 373.639334 -237.674912)
		(stroke
			(width 0.05715)
			(type default)
		)
		(layer "In11.Cu")
	)
	(gr_arc
		(start 373.635778 -236.057186)
		(mid 373.637558 -236.056046)
		(end 373.639334 -236.0549)
		(stroke
			(width 0.05715)
			(type default)
		)
		(layer "In11.Cu")
	)
	(gr_line
		(start 373.65813 -226.32416)
		(end 373.662702 -226.32162)
		(stroke
			(width 0.05715)
			(type default)
		)
		(layer "In11.Cu")
	)
	(gr_line
		(start 373.658638 -223.083882)
		(end 373.663972 -223.080834)
		(stroke
			(width 0.05715)
			(type default)
		)
		(layer "In11.Cu")
	)
	(gr_line
		(start 373.659908 -230.245158)
		(end 373.658892 -230.24465)
		(stroke
			(width 0.05715)
			(type default)
		)
		(layer "In11.Cu")
	)
	(gr_line
		(start 373.661432 -230.246174)
		(end 373.659908 -230.245158)
		(stroke
			(width 0.05715)
			(type default)
		)
		(layer "In11.Cu")
	)
	(gr_line
		(start 373.661686 -229.561898)
		(end 373.664226 -229.560628)
		(stroke
			(width 0.05715)
			(type default)
		)
		(layer "In11.Cu")
	)
	(gr_line
		(start 373.662702 -226.32162)
		(end 373.664226 -226.320604)
		(stroke
			(width 0.05715)
			(type default)
		)
		(layer "In11.Cu")
	)
	(gr_line
		(start 373.663972 -223.080834)
		(end 373.666766 -223.078802)
		(stroke
			(width 0.05715)
			(type default)
		)
		(layer "In11.Cu")
	)
	(gr_arc
		(start 373.664226 -229.560628)
		(mid 373.670864 -229.555977)
		(end 373.677434 -229.55123)
		(stroke
			(width 0.05715)
			(type default)
		)
		(layer "In11.Cu")
	)
	(gr_arc
		(start 373.664226 -226.320604)
		(mid 373.668813 -226.317451)
		(end 373.67337 -226.314254)
		(stroke
			(width 0.05715)
			(type default)
		)
		(layer "In11.Cu")
	)
	(gr_arc
		(start 373.666766 -223.078802)
		(mid 373.670715 -223.076025)
		(end 373.67464 -223.073214)
		(stroke
			(width 0.05715)
			(type default)
		)
		(layer "In11.Cu")
	)
	(gr_arc
		(start 373.678196 -230.257604)
		(mid 373.669865 -230.251814)
		(end 373.661432 -230.246174)
		(stroke
			(width 0.05715)
			(type default)
		)
		(layer "In11.Cu")
	)
	(gr_line
		(start 373.727472 -225.79076)
		(end 373.727726 -225.789744)
		(stroke
			(width 0.05715)
			(type default)
		)
		(layer "In11.Cu")
	)
	(gr_arc
		(start 373.730266 -275.001736)
		(mid 373.732288 -274.990325)
		(end 373.734076 -274.978876)
		(stroke
			(width 0.05715)
			(type default)
		)
		(layer "In11.Cu")
	)
	(gr_line
		(start 373.778272 -296.876216)
		(end 373.778272 -296.876724)
		(stroke
			(width 0.07112)
			(type default)
		)
		(layer "In11.Cu")
	)
	(gr_line
		(start 373.778272 -296.837862)
		(end 373.778272 -296.86631)
		(stroke
			(width 0.05715)
			(type default)
		)
		(layer "In11.Cu")
	)
	(gr_arc
		(start 373.782082 -288.313114)
		(mid 373.785248 -288.315412)
		(end 373.788432 -288.317686)
		(stroke
			(width 0.05715)
			(type default)
		)
		(layer "In11.Cu")
	)
	(gr_arc
		(start 373.784622 -278.595074)
		(mid 373.788674 -278.597886)
		(end 373.79275 -278.600662)
		(stroke
			(width 0.05715)
			(type default)
		)
		(layer "In11.Cu")
	)
	(gr_arc
		(start 373.784622 -276.975062)
		(mid 373.788674 -276.977874)
		(end 373.79275 -276.98065)
		(stroke
			(width 0.05715)
			(type default)
		)
		(layer "In11.Cu")
	)
	(gr_arc
		(start 373.784876 -283.45511)
		(mid 373.788801 -283.457921)
		(end 373.79275 -283.460698)
		(stroke
			(width 0.05715)
			(type default)
		)
		(layer "In11.Cu")
	)
	(gr_arc
		(start 373.789194 -288.318194)
		(mid 373.79097 -288.319467)
		(end 373.79275 -288.320734)
		(stroke
			(width 0.05715)
			(type default)
		)
		(layer "In11.Cu")
	)
	(gr_line
		(start 373.79275 -288.320734)
		(end 373.798846 -288.32429)
		(stroke
			(width 0.05715)
			(type default)
		)
		(layer "In11.Cu")
	)
	(gr_line
		(start 373.79275 -283.460698)
		(end 373.799608 -283.464762)
		(stroke
			(width 0.05715)
			(type default)
		)
		(layer "In11.Cu")
	)
	(gr_line
		(start 373.79275 -278.600662)
		(end 373.799608 -278.604726)
		(stroke
			(width 0.05715)
			(type default)
		)
		(layer "In11.Cu")
	)
	(gr_line
		(start 373.79275 -276.98065)
		(end 373.799608 -276.984714)
		(stroke
			(width 0.05715)
			(type default)
		)
		(layer "In11.Cu")
	)
	(gr_line
		(start 373.798846 -288.32429)
		(end 373.7991 -288.32429)
		(stroke
			(width 0.05715)
			(type default)
		)
		(layer "In11.Cu")
	)
	(gr_line
		(start 373.799608 -283.464762)
		(end 373.80037 -283.46527)
		(stroke
			(width 0.05715)
			(type default)
		)
		(layer "In11.Cu")
	)
	(gr_line
		(start 373.799608 -278.604726)
		(end 373.80037 -278.605234)
		(stroke
			(width 0.05715)
			(type default)
		)
		(layer "In11.Cu")
	)
	(gr_line
		(start 373.799608 -276.984714)
		(end 373.80037 -276.985222)
		(stroke
			(width 0.05715)
			(type default)
		)
		(layer "In11.Cu")
	)
	(gr_line
		(start 373.80037 -283.46527)
		(end 373.801132 -283.465778)
		(stroke
			(width 0.05715)
			(type default)
		)
		(layer "In11.Cu")
	)
	(gr_line
		(start 373.80037 -278.605234)
		(end 373.801132 -278.605742)
		(stroke
			(width 0.05715)
			(type default)
		)
		(layer "In11.Cu")
	)
	(gr_line
		(start 373.80037 -276.985222)
		(end 373.801132 -276.98573)
		(stroke
			(width 0.05715)
			(type default)
		)
		(layer "In11.Cu")
	)
	(gr_line
		(start 373.814848 -247.724168)
		(end 373.516906 -247.724168)
		(stroke
			(width 0.05715)
			(type default)
		)
		(layer "In11.Cu")
	)
	(gr_line
		(start 373.814848 -246.104156)
		(end 373.516906 -246.104156)
		(stroke
			(width 0.05715)
			(type default)
		)
		(layer "In11.Cu")
	)
	(gr_line
		(start 373.814848 -244.484144)
		(end 373.516906 -244.484144)
		(stroke
			(width 0.05715)
			(type default)
		)
		(layer "In11.Cu")
	)
	(gr_line
		(start 373.81688 -278.136096)
		(end 373.747538 -278.205438)
		(stroke
			(width 0.05715)
			(type default)
		)
		(layer "In11.Cu")
	)
	(gr_line
		(start 373.81688 -276.516084)
		(end 373.747538 -276.585426)
		(stroke
			(width 0.05715)
			(type default)
		)
		(layer "In11.Cu")
	)
	(gr_line
		(start 373.81688 -274.896072)
		(end 373.734076 -274.978876)
		(stroke
			(width 0.05715)
			(type default)
		)
		(layer "In11.Cu")
	)
	(gr_line
		(start 373.823992 -296.792142)
		(end 373.778272 -296.837862)
		(stroke
			(width 0.05715)
			(type default)
		)
		(layer "In11.Cu")
	)
	(gr_line
		(start 373.83212 -278.623776)
		(end 373.832628 -278.62403)
		(stroke
			(width 0.05715)
			(type default)
		)
		(layer "In11.Cu")
	)
	(gr_line
		(start 373.83212 -277.003764)
		(end 373.831866 -277.00351)
		(stroke
			(width 0.05715)
			(type default)
		)
		(layer "In11.Cu")
	)
	(gr_line
		(start 373.83212 -277.003764)
		(end 373.832628 -277.004018)
		(stroke
			(width 0.05715)
			(type default)
		)
		(layer "In11.Cu")
	)
	(gr_line
		(start 373.832628 -294.823896)
		(end 373.83339 -294.82415)
		(stroke
			(width 0.05715)
			(type default)
		)
		(layer "In11.Cu")
	)
	(gr_line
		(start 373.832628 -291.583872)
		(end 373.833898 -291.584634)
		(stroke
			(width 0.05715)
			(type default)
		)
		(layer "In11.Cu")
	)
	(gr_line
		(start 373.832628 -278.62403)
		(end 373.832628 -278.623776)
		(stroke
			(width 0.05715)
			(type default)
		)
		(layer "In11.Cu")
	)
	(gr_line
		(start 373.832628 -277.004018)
		(end 373.835422 -277.005542)
		(stroke
			(width 0.05715)
			(type default)
		)
		(layer "In11.Cu")
	)
	(gr_line
		(start 373.83466 -293.205154)
		(end 373.835168 -293.205154)
		(stroke
			(width 0.05715)
			(type default)
		)
		(layer "In11.Cu")
	)
	(gr_line
		(start 373.83466 -289.96513)
		(end 373.835168 -289.96513)
		(stroke
			(width 0.05715)
			(type default)
		)
		(layer "In11.Cu")
	)
	(gr_line
		(start 373.83466 -285.105348)
		(end 373.835168 -285.105348)
		(stroke
			(width 0.05715)
			(type default)
		)
		(layer "In11.Cu")
	)
	(gr_line
		(start 373.83466 -283.485336)
		(end 373.835168 -283.485336)
		(stroke
			(width 0.05715)
			(type default)
		)
		(layer "In11.Cu")
	)
	(gr_line
		(start 373.83466 -281.865324)
		(end 373.835168 -281.865324)
		(stroke
			(width 0.05715)
			(type default)
		)
		(layer "In11.Cu")
	)
	(gr_line
		(start 373.834914 -288.345118)
		(end 373.835168 -288.345118)
		(stroke
			(width 0.05715)
			(type default)
		)
		(layer "In11.Cu")
	)
	(gr_line
		(start 373.835422 -277.005542)
		(end 373.83593 -277.005796)
		(stroke
			(width 0.05715)
			(type default)
		)
		(layer "In11.Cu")
	)
	(gr_arc
		(start 373.837962 -280.885138)
		(mid 373.838598 -280.884758)
		(end 373.839232 -280.884376)
		(stroke
			(width 0.05715)
			(type default)
		)
		(layer "In11.Cu")
	)
	(gr_line
		(start 373.910098 -225.870516)
		(end 373.910098 -225.871278)
		(stroke
			(width 0.05715)
			(type default)
		)
		(layer "In11.Cu")
	)
	(gr_line
		(start 373.910098 -225.870262)
		(end 373.910098 -225.870516)
		(stroke
			(width 0.05715)
			(type default)
		)
		(layer "In11.Cu")
	)
	(gr_arc
		(start 373.910098 -225.870262)
		(mid 373.910098 -225.870008)
		(end 373.910098 -225.869754)
		(stroke
			(width 0.05715)
			(type default)
		)
		(layer "In11.Cu")
	)
	(gr_line
		(start 373.92737 -294.658288)
		(end 373.927878 -294.658542)
		(stroke
			(width 0.05715)
			(type default)
		)
		(layer "In11.Cu")
	)
	(gr_line
		(start 373.92737 -293.038276)
		(end 373.927878 -293.03853)
		(stroke
			(width 0.05715)
			(type default)
		)
		(layer "In11.Cu")
	)
	(gr_line
		(start 373.92737 -291.418264)
		(end 373.927878 -291.418518)
		(stroke
			(width 0.05715)
			(type default)
		)
		(layer "In11.Cu")
	)
	(gr_line
		(start 373.92737 -289.798252)
		(end 373.927878 -289.798506)
		(stroke
			(width 0.05715)
			(type default)
		)
		(layer "In11.Cu")
	)
	(gr_line
		(start 373.92737 -284.93847)
		(end 373.927878 -284.938724)
		(stroke
			(width 0.05715)
			(type default)
		)
		(layer "In11.Cu")
	)
	(gr_line
		(start 373.92737 -281.698446)
		(end 373.927878 -281.6987)
		(stroke
			(width 0.05715)
			(type default)
		)
		(layer "In11.Cu")
	)
	(gr_line
		(start 373.927624 -292.393624)
		(end 373.92229 -292.396672)
		(stroke
			(width 0.05715)
			(type default)
		)
		(layer "In11.Cu")
	)
	(gr_line
		(start 373.927878 -294.658542)
		(end 373.931434 -294.660574)
		(stroke
			(width 0.05715)
			(type default)
		)
		(layer "In11.Cu")
	)
	(gr_line
		(start 373.927878 -293.03853)
		(end 373.930926 -293.040308)
		(stroke
			(width 0.05715)
			(type default)
		)
		(layer "In11.Cu")
	)
	(gr_line
		(start 373.927878 -291.418518)
		(end 373.927878 -291.418772)
		(stroke
			(width 0.05715)
			(type default)
		)
		(layer "In11.Cu")
	)
	(gr_line
		(start 373.927878 -289.798506)
		(end 373.930926 -289.800284)
		(stroke
			(width 0.05715)
			(type default)
		)
		(layer "In11.Cu")
	)
	(gr_line
		(start 373.927878 -284.938724)
		(end 373.930926 -284.940502)
		(stroke
			(width 0.05715)
			(type default)
		)
		(layer "In11.Cu")
	)
	(gr_line
		(start 373.927878 -283.318712)
		(end 373.930926 -283.32049)
		(stroke
			(width 0.05715)
			(type default)
		)
		(layer "In11.Cu")
	)
	(gr_line
		(start 373.927878 -281.6987)
		(end 373.930926 -281.700478)
		(stroke
			(width 0.05715)
			(type default)
		)
		(layer "In11.Cu")
	)
	(gr_line
		(start 373.927878 -281.05354)
		(end 373.92737 -281.053794)
		(stroke
			(width 0.05715)
			(type default)
		)
		(layer "In11.Cu")
	)
	(gr_line
		(start 373.927878 -278.458676)
		(end 373.928894 -278.459184)
		(stroke
			(width 0.05715)
			(type default)
		)
		(layer "In11.Cu")
	)
	(gr_line
		(start 373.927878 -276.838664)
		(end 373.93118 -276.840696)
		(stroke
			(width 0.05715)
			(type default)
		)
		(layer "In11.Cu")
	)
	(gr_line
		(start 373.930926 -294.011604)
		(end 373.92737 -294.013636)
		(stroke
			(width 0.05715)
			(type default)
		)
		(layer "In11.Cu")
	)
	(gr_line
		(start 373.930926 -290.77158)
		(end 373.92737 -290.773612)
		(stroke
			(width 0.05715)
			(type default)
		)
		(layer "In11.Cu")
	)
	(gr_line
		(start 373.930926 -289.151568)
		(end 373.92737 -289.1536)
		(stroke
			(width 0.05715)
			(type default)
		)
		(layer "In11.Cu")
	)
	(gr_line
		(start 373.930926 -285.911798)
		(end 373.92737 -285.91383)
		(stroke
			(width 0.05715)
			(type default)
		)
		(layer "In11.Cu")
	)
	(gr_line
		(start 373.930926 -284.291786)
		(end 373.92737 -284.293818)
		(stroke
			(width 0.05715)
			(type default)
		)
		(layer "In11.Cu")
	)
	(gr_line
		(start 373.930926 -282.671774)
		(end 373.92737 -282.673806)
		(stroke
			(width 0.05715)
			(type default)
		)
		(layer "In11.Cu")
	)
	(gr_line
		(start 373.931434 -294.660574)
		(end 373.932196 -294.661082)
		(stroke
			(width 0.05715)
			(type default)
		)
		(layer "In11.Cu")
	)
	(gr_arc
		(start 373.933974 -225.412554)
		(mid 373.930917 -225.415593)
		(end 373.927878 -225.41865)
		(stroke
			(width 0.05715)
			(type default)
		)
		(layer "In11.Cu")
	)
	(gr_line
		(start 373.942102 -278.467058)
		(end 373.942864 -278.467312)
		(stroke
			(width 0.05715)
			(type default)
		)
		(layer "In11.Cu")
	)
	(gr_arc
		(start 373.942102 -225.40595)
		(mid 373.938022 -225.409232)
		(end 373.933974 -225.412554)
		(stroke
			(width 0.05715)
			(type default)
		)
		(layer "In11.Cu")
	)
	(gr_line
		(start 373.957342 -420.952168)
		(end 374.248172 -421.242998)
		(stroke
			(width 0.07112)
			(type default)
		)
		(layer "In11.Cu")
	)
	(gr_arc
		(start 373.96547 -225.387916)
		(mid 373.960625 -225.391447)
		(end 373.955818 -225.395028)
		(stroke
			(width 0.05715)
			(type default)
		)
		(layer "In11.Cu")
	)
	(gr_line
		(start 373.96801 -225.386392)
		(end 373.97817 -225.38055)
		(stroke
			(width 0.05715)
			(type default)
		)
		(layer "In11.Cu")
	)
	(gr_line
		(start 373.998744 -225.368612)
		(end 374.000014 -225.36785)
		(stroke
			(width 0.05715)
			(type default)
		)
		(layer "In11.Cu")
	)
	(gr_line
		(start 374.000014 -225.36785)
		(end 374.001792 -225.366834)
		(stroke
			(width 0.05715)
			(type default)
		)
		(layer "In11.Cu")
	)
	(gr_line
		(start 374.001792 -225.366834)
		(end 374.0023 -225.36658)
		(stroke
			(width 0.05715)
			(type default)
		)
		(layer "In11.Cu")
	)
	(gr_line
		(start 374.014492 -296.792142)
		(end 374.060212 -296.837862)
		(stroke
			(width 0.05715)
			(type default)
		)
		(layer "In11.Cu")
	)
	(gr_line
		(start 374.060212 -296.837862)
		(end 374.060212 -296.86631)
		(stroke
			(width 0.05715)
			(type default)
		)
		(layer "In11.Cu")
	)
	(gr_line
		(start 374.06072 -296.934382)
		(end 374.06072 -296.93489)
		(stroke
			(width 0.07112)
			(type default)
		)
		(layer "In11.Cu")
	)
	(gr_line
		(start 374.07342 -223.926654)
		(end 374.073674 -223.926908)
		(stroke
			(width 0.05715)
			(type default)
		)
		(layer "In11.Cu")
	)
	(gr_line
		(start 374.085612 -244.978428)
		(end 374.086628 -244.97792)
		(stroke
			(width 0.05715)
			(type default)
		)
		(layer "In11.Cu")
	)
	(gr_line
		(start 374.09374 -225.533966)
		(end 374.094502 -225.533458)
		(stroke
			(width 0.05715)
			(type default)
		)
		(layer "In11.Cu")
	)
	(gr_line
		(start 374.096534 -225.532442)
		(end 374.097042 -225.532188)
		(stroke
			(width 0.05715)
			(type default)
		)
		(layer "In11.Cu")
	)
	(gr_line
		(start 374.114822 -278.136096)
		(end 373.81688 -278.136096)
		(stroke
			(width 0.05715)
			(type default)
		)
		(layer "In11.Cu")
	)
	(gr_line
		(start 374.114822 -276.516084)
		(end 373.81688 -276.516084)
		(stroke
			(width 0.05715)
			(type default)
		)
		(layer "In11.Cu")
	)
	(gr_line
		(start 374.114822 -274.896072)
		(end 373.81688 -274.896072)
		(stroke
			(width 0.05715)
			(type default)
		)
		(layer "In11.Cu")
	)
	(gr_line
		(start 374.143778 -221.202758)
		(end 374.143778 -221.17431)
		(stroke
			(width 0.05715)
			(type default)
		)
		(layer "In11.Cu")
	)
	(gr_line
		(start 374.189498 -221.248478)
		(end 374.143778 -221.202758)
		(stroke
			(width 0.05715)
			(type default)
		)
		(layer "In11.Cu")
	)
	(gr_line
		(start 374.19407 -223.351344)
		(end 374.194324 -223.34982)
		(stroke
			(width 0.05715)
			(type default)
		)
		(layer "In11.Cu")
	)
	(gr_line
		(start 374.204992 -223.795844)
		(end 374.204738 -223.796352)
		(stroke
			(width 0.05715)
			(type default)
		)
		(layer "In11.Cu")
	)
	(gr_line
		(start 374.220994 -333.38262)
		(end 374.22074 -333.38262)
		(stroke
			(width 0.07112)
			(type default)
		)
		(layer "In11.Cu")
	)
	(gr_line
		(start 374.303798 -295.63441)
		(end 374.304814 -295.634918)
		(stroke
			(width 0.05715)
			(type default)
		)
		(layer "In11.Cu")
	)
	(gr_line
		(start 374.313704 -323.556376)
		(end 374.313704 -323.55663)
		(stroke
			(width 0.07112)
			(type default)
		)
		(layer "In11.Cu")
	)
	(gr_line
		(start 374.333516 -277.831804)
		(end 374.333262 -277.831804)
		(stroke
			(width 0.05715)
			(type default)
		)
		(layer "In11.Cu")
	)
	(gr_line
		(start 374.379998 -221.248478)
		(end 374.425718 -221.202758)
		(stroke
			(width 0.05715)
			(type default)
		)
		(layer "In11.Cu")
	)
	(gr_line
		(start 374.384824 -280.2509)
		(end 374.38457 -280.251154)
		(stroke
			(width 0.05715)
			(type default)
		)
		(layer "In11.Cu")
	)
	(gr_line
		(start 374.397778 -279.268682)
		(end 374.398794 -279.26919)
		(stroke
			(width 0.05715)
			(type default)
		)
		(layer "In11.Cu")
	)
	(gr_line
		(start 374.401334 -295.714674)
		(end 374.401588 -295.714928)
		(stroke
			(width 0.05715)
			(type default)
		)
		(layer "In11.Cu")
	)
	(gr_line
		(start 374.425718 -221.202758)
		(end 374.425718 -221.17431)
		(stroke
			(width 0.05715)
			(type default)
		)
		(layer "In11.Cu")
	)
	(gr_arc
		(start 374.42648 -228.744272)
		(mid 374.429647 -228.746569)
		(end 374.43283 -228.748844)
		(stroke
			(width 0.05715)
			(type default)
		)
		(layer "In11.Cu")
	)
	(gr_arc
		(start 374.43283 -224.579688)
		(mid 374.429647 -224.581963)
		(end 374.42648 -224.58426)
		(stroke
			(width 0.05715)
			(type default)
		)
		(layer "In11.Cu")
	)
	(gr_line
		(start 374.43283 -224.579688)
		(end 374.435624 -224.577656)
		(stroke
			(width 0.05715)
			(type default)
		)
		(layer "In11.Cu")
	)
	(gr_line
		(start 374.433338 -228.749098)
		(end 374.43283 -228.748844)
		(stroke
			(width 0.05715)
			(type default)
		)
		(layer "In11.Cu")
	)
	(gr_line
		(start 374.435624 -224.577656)
		(end 374.442482 -224.573846)
		(stroke
			(width 0.05715)
			(type default)
		)
		(layer "In11.Cu")
	)
	(gr_line
		(start 374.441212 -228.75367)
		(end 374.433338 -228.749098)
		(stroke
			(width 0.05715)
			(type default)
		)
		(layer "In11.Cu")
	)
	(gr_line
		(start 374.471946 -229.41661)
		(end 374.472454 -229.416356)
		(stroke
			(width 0.05715)
			(type default)
		)
		(layer "In11.Cu")
	)
	(gr_line
		(start 374.582944 -224.713038)
		(end 374.582944 -224.713292)
		(stroke
			(width 0.05715)
			(type default)
		)
		(layer "In11.Cu")
	)
	(gr_line
		(start 374.599962 -229.563168)
		(end 374.604788 -229.560374)
		(stroke
			(width 0.05715)
			(type default)
		)
		(layer "In11.Cu")
	)
	(gr_line
		(start 374.604788 -229.560374)
		(end 374.60682 -229.55885)
		(stroke
			(width 0.05715)
			(type default)
		)
		(layer "In11.Cu")
	)
	(gr_arc
		(start 374.60682 -229.55885)
		(mid 374.611537 -229.555573)
		(end 374.616218 -229.552246)
		(stroke
			(width 0.05715)
			(type default)
		)
		(layer "In11.Cu")
	)
	(gr_line
		(start 374.723152 -296.837862)
		(end 374.723152 -296.86631)
		(stroke
			(width 0.05715)
			(type default)
		)
		(layer "In11.Cu")
	)
	(gr_line
		(start 374.768872 -296.792142)
		(end 374.723152 -296.837862)
		(stroke
			(width 0.05715)
			(type default)
		)
		(layer "In11.Cu")
	)
	(gr_line
		(start 374.788176 -422.422066)
		(end 375.283984 -422.917874)
		(stroke
			(width 0.07112)
			(type default)
		)
		(layer "In11.Cu")
	)
	(gr_line
		(start 374.820942 -420.952168)
		(end 374.530112 -421.242998)
		(stroke
			(width 0.07112)
			(type default)
		)
		(layer "In11.Cu")
	)
	(gr_line
		(start 374.914922 -377.1265)
		(end 374.624092 -377.41733)
		(stroke
			(width 0.07112)
			(type default)
		)
		(layer "In11.Cu")
	)
	(gr_line
		(start 374.941846 -225.366834)
		(end 374.942608 -225.366326)
		(stroke
			(width 0.05715)
			(type default)
		)
		(layer "In11.Cu")
	)
	(gr_line
		(start 374.942608 -225.366326)
		(end 374.943878 -225.365564)
		(stroke
			(width 0.05715)
			(type default)
		)
		(layer "In11.Cu")
	)
	(gr_line
		(start 374.943878 -225.365564)
		(end 374.944894 -225.365056)
		(stroke
			(width 0.05715)
			(type default)
		)
		(layer "In11.Cu")
	)
	(gr_line
		(start 374.959372 -296.792142)
		(end 375.005092 -296.837862)
		(stroke
			(width 0.05715)
			(type default)
		)
		(layer "In11.Cu")
	)
	(gr_line
		(start 374.989344 -422.222676)
		(end 375.181368 -422.222676)
		(stroke
			(width 0.07112)
			(type default)
		)
		(layer "In11.Cu")
	)
	(gr_line
		(start 375.005092 -296.837862)
		(end 375.005092 -296.86631)
		(stroke
			(width 0.05715)
			(type default)
		)
		(layer "In11.Cu")
	)
	(gr_line
		(start 375.01957 -319.571116)
		(end 375.019824 -319.571116)
		(stroke
			(width 0.07112)
			(type default)
		)
		(layer "In11.Cu")
	)
	(gr_line
		(start 375.035826 -225.53295)
		(end 375.037096 -225.532188)
		(stroke
			(width 0.05715)
			(type default)
		)
		(layer "In11.Cu")
	)
	(gr_line
		(start 375.037096 -225.532188)
		(end 375.037858 -225.53168)
		(stroke
			(width 0.05715)
			(type default)
		)
		(layer "In11.Cu")
	)
	(gr_line
		(start 375.037858 -225.53168)
		(end 375.038874 -225.531172)
		(stroke
			(width 0.05715)
			(type default)
		)
		(layer "In11.Cu")
	)
	(gr_line
		(start 375.038874 -225.531172)
		(end 375.040144 -225.53041)
		(stroke
			(width 0.05715)
			(type default)
		)
		(layer "In11.Cu")
	)
	(gr_line
		(start 375.040144 -225.53041)
		(end 375.040906 -225.529902)
		(stroke
			(width 0.05715)
			(type default)
		)
		(layer "In11.Cu")
	)
	(gr_line
		(start 375.042176 -225.52914)
		(end 375.043954 -225.528124)
		(stroke
			(width 0.05715)
			(type default)
		)
		(layer "In11.Cu")
	)
	(gr_line
		(start 375.068846 -225.513646)
		(end 375.069354 -225.513392)
		(stroke
			(width 0.05715)
			(type default)
		)
		(layer "In11.Cu")
	)
	(gr_line
		(start 375.068846 -222.273622)
		(end 375.07418 -222.270574)
		(stroke
			(width 0.05715)
			(type default)
		)
		(layer "In11.Cu")
	)
	(gr_line
		(start 375.069354 -225.513392)
		(end 375.070116 -225.512884)
		(stroke
			(width 0.05715)
			(type default)
		)
		(layer "In11.Cu")
	)
	(gr_line
		(start 375.070116 -225.512884)
		(end 375.076974 -225.50882)
		(stroke
			(width 0.05715)
			(type default)
		)
		(layer "In11.Cu")
	)
	(gr_line
		(start 375.07418 -222.270574)
		(end 375.075196 -222.270066)
		(stroke
			(width 0.05715)
			(type default)
		)
		(layer "In11.Cu")
	)
	(gr_line
		(start 375.075196 -222.270066)
		(end 375.076212 -222.269304)
		(stroke
			(width 0.05715)
			(type default)
		)
		(layer "In11.Cu")
	)
	(gr_arc
		(start 375.076212 -222.269304)
		(mid 375.080544 -222.266276)
		(end 375.084848 -222.263208)
		(stroke
			(width 0.05715)
			(type default)
		)
		(layer "In11.Cu")
	)
	(gr_arc
		(start 375.076974 -225.50882)
		(mid 375.080923 -225.506043)
		(end 375.084848 -225.503232)
		(stroke
			(width 0.05715)
			(type default)
		)
		(layer "In11.Cu")
	)
	(gr_line
		(start 375.083832 -221.202758)
		(end 375.083832 -221.17431)
		(stroke
			(width 0.05715)
			(type default)
		)
		(layer "In11.Cu")
	)
	(gr_line
		(start 375.129552 -221.248478)
		(end 375.083832 -221.202758)
		(stroke
			(width 0.05715)
			(type default)
		)
		(layer "In11.Cu")
	)
	(gr_line
		(start 375.147332 -333.195422)
		(end 375.147586 -333.195168)
		(stroke
			(width 0.07112)
			(type default)
		)
		(layer "In11.Cu")
	)
	(gr_line
		(start 375.181368 -422.222676)
		(end 375.483374 -422.524682)
		(stroke
			(width 0.07112)
			(type default)
		)
		(layer "In11.Cu")
	)
	(gr_arc
		(start 375.19483 -279.40508)
		(mid 375.198755 -279.407891)
		(end 375.202704 -279.410668)
		(stroke
			(width 0.05715)
			(type default)
		)
		(layer "In11.Cu")
	)
	(gr_line
		(start 375.196862 -377.1265)
		(end 375.487692 -377.41733)
		(stroke
			(width 0.07112)
			(type default)
		)
		(layer "In11.Cu")
	)
	(gr_line
		(start 375.202704 -279.410668)
		(end 375.209562 -279.414732)
		(stroke
			(width 0.05715)
			(type default)
		)
		(layer "In11.Cu")
	)
	(gr_line
		(start 375.209562 -279.414732)
		(end 375.210324 -279.41524)
		(stroke
			(width 0.05715)
			(type default)
		)
		(layer "In11.Cu")
	)
	(gr_line
		(start 375.210324 -279.41524)
		(end 375.211086 -279.415748)
		(stroke
			(width 0.05715)
			(type default)
		)
		(layer "In11.Cu")
	)
	(gr_line
		(start 375.237756 -319.392046)
		(end 375.246646 -319.402968)
		(stroke
			(width 0.07112)
			(type default)
		)
		(layer "In11.Cu")
	)
	(gr_line
		(start 375.24182 -280.078688)
		(end 375.240804 -280.079196)
		(stroke
			(width 0.05715)
			(type default)
		)
		(layer "In11.Cu")
	)
	(gr_line
		(start 375.242074 -279.433782)
		(end 375.242582 -279.434036)
		(stroke
			(width 0.05715)
			(type default)
		)
		(layer "In11.Cu")
	)
	(gr_line
		(start 375.242328 -280.078434)
		(end 375.24182 -280.078688)
		(stroke
			(width 0.05715)
			(type default)
		)
		(layer "In11.Cu")
	)
	(gr_line
		(start 375.242582 -295.633902)
		(end 375.245376 -295.635426)
		(stroke
			(width 0.05715)
			(type default)
		)
		(layer "In11.Cu")
	)
	(gr_line
		(start 375.242582 -279.434036)
		(end 375.245376 -279.43556)
		(stroke
			(width 0.05715)
			(type default)
		)
		(layer "In11.Cu")
	)
	(gr_line
		(start 375.246646 -319.402968)
		(end 375.254266 -319.414398)
		(stroke
			(width 0.07112)
			(type default)
		)
		(layer "In11.Cu")
	)
	(gr_line
		(start 375.255536 -295.642538)
		(end 375.282206 -295.668954)
		(stroke
			(width 0.05715)
			(type default)
		)
		(layer "In11.Cu")
	)
	(gr_line
		(start 375.299732 -349.140526)
		(end 375.299986 -349.140272)
		(stroke
			(width 0.07112)
			(type default)
		)
		(layer "In11.Cu")
	)
	(gr_arc
		(start 375.319798 -223.434656)
		(mid 375.319928 -223.432751)
		(end 375.320052 -223.430846)
		(stroke
			(width 0.05715)
			(type default)
		)
		(layer "In11.Cu")
	)
	(gr_line
		(start 375.320052 -223.425258)
		(end 375.320052 -223.430846)
		(stroke
			(width 0.05715)
			(type default)
		)
		(layer "In11.Cu")
	)
	(gr_line
		(start 375.320052 -221.248478)
		(end 375.365772 -221.202758)
		(stroke
			(width 0.05715)
			(type default)
		)
		(layer "In11.Cu")
	)
	(gr_line
		(start 375.333768 -295.720516)
		(end 375.3358 -295.722548)
		(stroke
			(width 0.05715)
			(type default)
		)
		(layer "In11.Cu")
	)
	(gr_line
		(start 375.33707 -280.244042)
		(end 375.3358 -280.244804)
		(stroke
			(width 0.05715)
			(type default)
		)
		(layer "In11.Cu")
	)
	(gr_line
		(start 375.337324 -295.468294)
		(end 375.337832 -295.468548)
		(stroke
			(width 0.05715)
			(type default)
		)
		(layer "In11.Cu")
	)
	(gr_line
		(start 375.337578 -280.243788)
		(end 375.33707 -280.244042)
		(stroke
			(width 0.05715)
			(type default)
		)
		(layer "In11.Cu")
	)
	(gr_line
		(start 375.337832 -295.468548)
		(end 375.338848 -295.469056)
		(stroke
			(width 0.05715)
			(type default)
		)
		(layer "In11.Cu")
	)
	(gr_line
		(start 375.337832 -279.268682)
		(end 375.338848 -279.26919)
		(stroke
			(width 0.05715)
			(type default)
		)
		(layer "In11.Cu")
	)
	(gr_line
		(start 375.338848 -295.469056)
		(end 375.340372 -295.470072)
		(stroke
			(width 0.05715)
			(type default)
		)
		(layer "In11.Cu")
	)
	(gr_line
		(start 375.338848 -279.26919)
		(end 375.340372 -279.270206)
		(stroke
			(width 0.05715)
			(type default)
		)
		(layer "In11.Cu")
	)
	(gr_line
		(start 375.340372 -295.470072)
		(end 375.341388 -295.47058)
		(stroke
			(width 0.05715)
			(type default)
		)
		(layer "In11.Cu")
	)
	(gr_line
		(start 375.340372 -279.270206)
		(end 375.341388 -279.270714)
		(stroke
			(width 0.05715)
			(type default)
		)
		(layer "In11.Cu")
	)
	(gr_line
		(start 375.341388 -295.47058)
		(end 375.346468 -295.473628)
		(stroke
			(width 0.05715)
			(type default)
		)
		(layer "In11.Cu")
	)
	(gr_line
		(start 375.341388 -279.270714)
		(end 375.346468 -279.273762)
		(stroke
			(width 0.05715)
			(type default)
		)
		(layer "In11.Cu")
	)
	(gr_line
		(start 375.348754 -295.474898)
		(end 375.351294 -295.476422)
		(stroke
			(width 0.05715)
			(type default)
		)
		(layer "In11.Cu")
	)
	(gr_line
		(start 375.352056 -295.47693)
		(end 375.35358 -295.477692)
		(stroke
			(width 0.05715)
			(type default)
		)
		(layer "In11.Cu")
	)
	(gr_line
		(start 375.354342 -295.4782)
		(end 375.376948 -295.491408)
		(stroke
			(width 0.05715)
			(type default)
		)
		(layer "In11.Cu")
	)
	(gr_line
		(start 375.365772 -221.202758)
		(end 375.365772 -221.17431)
		(stroke
			(width 0.05715)
			(type default)
		)
		(layer "In11.Cu")
	)
	(gr_arc
		(start 375.372884 -224.579688)
		(mid 375.369701 -224.581963)
		(end 375.366534 -224.58426)
		(stroke
			(width 0.05715)
			(type default)
		)
		(layer "In11.Cu")
	)
	(gr_line
		(start 375.373138 -224.579434)
		(end 375.37517 -224.57791)
		(stroke
			(width 0.05715)
			(type default)
		)
		(layer "In11.Cu")
	)
	(gr_line
		(start 375.37517 -224.57791)
		(end 375.383298 -224.573338)
		(stroke
			(width 0.05715)
			(type default)
		)
		(layer "In11.Cu")
	)
	(gr_line
		(start 375.376948 -295.491408)
		(end 375.418604 -295.534334)
		(stroke
			(width 0.05715)
			(type default)
		)
		(layer "In11.Cu")
	)
	(gr_line
		(start 375.483374 -422.524682)
		(end 375.483374 -422.716706)
		(stroke
			(width 0.07112)
			(type default)
		)
		(layer "In11.Cu")
	)
	(gr_line
		(start 375.506996 -224.721928)
		(end 375.507504 -224.721674)
		(stroke
			(width 0.05715)
			(type default)
		)
		(layer "In11.Cu")
	)
	(gr_line
		(start 375.560336 -349.248476)
		(end 375.581926 -349.19666)
		(stroke
			(width 0.07112)
			(type default)
		)
		(layer "In11.Cu")
	)
	(gr_line
		(start 375.581926 -349.19666)
		(end 375.581926 -349.140272)
		(stroke
			(width 0.07112)
			(type default)
		)
		(layer "In11.Cu")
	)
	(gr_line
		(start 375.668032 -296.809414)
		(end 375.668032 -296.837862)
		(stroke
			(width 0.05715)
			(type default)
		)
		(layer "In11.Cu")
	)
	(gr_line
		(start 375.670064 -423.303954)
		(end 376.165872 -423.799762)
		(stroke
			(width 0.07112)
			(type default)
		)
		(layer "In11.Cu")
	)
	(gr_line
		(start 375.713752 -296.763694)
		(end 375.668032 -296.809414)
		(stroke
			(width 0.05715)
			(type default)
		)
		(layer "In11.Cu")
	)
	(gr_line
		(start 375.871232 -423.104564)
		(end 376.063256 -423.104564)
		(stroke
			(width 0.07112)
			(type default)
		)
		(layer "In11.Cu")
	)
	(gr_line
		(start 375.904252 -296.763694)
		(end 375.949972 -296.809414)
		(stroke
			(width 0.05715)
			(type default)
		)
		(layer "In11.Cu")
	)
	(gr_line
		(start 375.949972 -296.809414)
		(end 375.949972 -296.837862)
		(stroke
			(width 0.05715)
			(type default)
		)
		(layer "In11.Cu")
	)
	(gr_line
		(start 376.008392 -222.273876)
		(end 376.01398 -222.270574)
		(stroke
			(width 0.05715)
			(type default)
		)
		(layer "In11.Cu")
	)
	(gr_line
		(start 376.014234 -222.270574)
		(end 376.01398 -222.270574)
		(stroke
			(width 0.05715)
			(type default)
		)
		(layer "In11.Cu")
	)
	(gr_line
		(start 376.014234 -222.270574)
		(end 376.01525 -222.269812)
		(stroke
			(width 0.05715)
			(type default)
		)
		(layer "In11.Cu")
	)
	(gr_arc
		(start 376.01525 -222.269812)
		(mid 376.019199 -222.267035)
		(end 376.023124 -222.264224)
		(stroke
			(width 0.05715)
			(type default)
		)
		(layer "In11.Cu")
	)
	(gr_line
		(start 376.023632 -221.202758)
		(end 376.023632 -221.17431)
		(stroke
			(width 0.05715)
			(type default)
		)
		(layer "In11.Cu")
	)
	(gr_line
		(start 376.063256 -423.104564)
		(end 376.365262 -423.40657)
		(stroke
			(width 0.07112)
			(type default)
		)
		(layer "In11.Cu")
	)
	(gr_line
		(start 376.069352 -221.248478)
		(end 376.023632 -221.202758)
		(stroke
			(width 0.05715)
			(type default)
		)
		(layer "In11.Cu")
	)
	(gr_line
		(start 376.165872 -425.872656)
		(end 376.664982 -426.36567)
		(stroke
			(width 0.07112)
			(type default)
		)
		(layer "In11.Cu")
	)
	(gr_line
		(start 376.244612 -349.586804)
		(end 376.244866 -349.58655)
		(stroke
			(width 0.07112)
			(type default)
		)
		(layer "In11.Cu")
	)
	(gr_line
		(start 376.259852 -221.248478)
		(end 376.305572 -221.202758)
		(stroke
			(width 0.05715)
			(type default)
		)
		(layer "In11.Cu")
	)
	(gr_line
		(start 376.305572 -221.202758)
		(end 376.305572 -221.17431)
		(stroke
			(width 0.05715)
			(type default)
		)
		(layer "In11.Cu")
	)
	(gr_line
		(start 376.348752 -222.938594)
		(end 376.349514 -222.938086)
		(stroke
			(width 0.05715)
			(type default)
		)
		(layer "In11.Cu")
	)
	(gr_line
		(start 376.349514 -222.938086)
		(end 376.350784 -222.937324)
		(stroke
			(width 0.05715)
			(type default)
		)
		(layer "In11.Cu")
	)
	(gr_line
		(start 376.350784 -222.937324)
		(end 376.3518 -222.936816)
		(stroke
			(width 0.05715)
			(type default)
		)
		(layer "In11.Cu")
	)
	(gr_line
		(start 376.3518 -222.936816)
		(end 376.352562 -222.936308)
		(stroke
			(width 0.05715)
			(type default)
		)
		(layer "In11.Cu")
	)
	(gr_line
		(start 376.352562 -222.936308)
		(end 376.355356 -222.934784)
		(stroke
			(width 0.05715)
			(type default)
		)
		(layer "In11.Cu")
	)
	(gr_line
		(start 376.365262 -423.40657)
		(end 376.365262 -423.598594)
		(stroke
			(width 0.07112)
			(type default)
		)
		(layer "In11.Cu")
	)
	(gr_line
		(start 376.36577 -425.671996)
		(end 376.558048 -425.67098)
		(stroke
			(width 0.07112)
			(type default)
		)
		(layer "In11.Cu")
	)
	(gr_line
		(start 376.44324 -223.104202)
		(end 376.444002 -223.103948)
		(stroke
			(width 0.05715)
			(type default)
		)
		(layer "In11.Cu")
	)
	(gr_line
		(start 376.44705 -223.10217)
		(end 376.447812 -223.101662)
		(stroke
			(width 0.05715)
			(type default)
		)
		(layer "In11.Cu")
	)
	(gr_line
		(start 376.448828 -223.101154)
		(end 376.450352 -223.100138)
		(stroke
			(width 0.05715)
			(type default)
		)
		(layer "In11.Cu")
	)
	(gr_line
		(start 376.450352 -223.100138)
		(end 376.451368 -223.09963)
		(stroke
			(width 0.05715)
			(type default)
		)
		(layer "In11.Cu")
	)
	(gr_line
		(start 376.451368 -223.09963)
		(end 376.453146 -223.098614)
		(stroke
			(width 0.05715)
			(type default)
		)
		(layer "In11.Cu")
	)
	(gr_line
		(start 376.455686 -223.09709)
		(end 376.456448 -223.096582)
		(stroke
			(width 0.05715)
			(type default)
		)
		(layer "In11.Cu")
	)
	(gr_line
		(start 376.505216 -349.694754)
		(end 376.526806 -349.642938)
		(stroke
			(width 0.07112)
			(type default)
		)
		(layer "In11.Cu")
	)
	(gr_line
		(start 376.511566 -305.353212)
		(end 376.51182 -305.353466)
		(stroke
			(width 0.07112)
			(type default)
		)
		(layer "In11.Cu")
	)
	(gr_line
		(start 376.526806 -349.642938)
		(end 376.526806 -349.58655)
		(stroke
			(width 0.07112)
			(type default)
		)
		(layer "In11.Cu")
	)
	(gr_line
		(start 376.558048 -425.67098)
		(end 376.862086 -425.970954)
		(stroke
			(width 0.07112)
			(type default)
		)
		(layer "In11.Cu")
	)
	(gr_line
		(start 376.862086 -425.970954)
		(end 376.863102 -426.163232)
		(stroke
			(width 0.07112)
			(type default)
		)
		(layer "In11.Cu")
	)
	(gr_line
		(start 376.96394 -221.202758)
		(end 376.96394 -221.17431)
		(stroke
			(width 0.05715)
			(type default)
		)
		(layer "In11.Cu")
	)
	(gr_line
		(start 376.98934 -352.927666)
		(end 376.98934 -352.927412)
		(stroke
			(width 0.07112)
			(type default)
		)
		(layer "In11.Cu")
	)
	(gr_line
		(start 377.00966 -221.248478)
		(end 376.96394 -221.202758)
		(stroke
			(width 0.05715)
			(type default)
		)
		(layer "In11.Cu")
	)
	(gr_line
		(start 377.020582 -420.952168)
		(end 377.311412 -421.242998)
		(stroke
			(width 0.07112)
			(type default)
		)
		(layer "In11.Cu")
	)
	(gr_line
		(start 377.20016 -221.248478)
		(end 377.24588 -221.202758)
		(stroke
			(width 0.05715)
			(type default)
		)
		(layer "In11.Cu")
	)
	(gr_line
		(start 377.210066 -349.819976)
		(end 377.21032 -349.819722)
		(stroke
			(width 0.07112)
			(type default)
		)
		(layer "In11.Cu")
	)
	(gr_line
		(start 377.24588 -221.202758)
		(end 377.24588 -221.17431)
		(stroke
			(width 0.05715)
			(type default)
		)
		(layer "In11.Cu")
	)
	(gr_line
		(start 377.311412 -421.72763)
		(end 377.311412 -422.42867)
		(stroke
			(width 0.07112)
			(type default)
		)
		(layer "In11.Cu")
	)
	(gr_line
		(start 377.38177 -329.483212)
		(end 377.381516 -329.483212)
		(stroke
			(width 0.07112)
			(type default)
		)
		(layer "In11.Cu")
	)
	(gr_line
		(start 377.47067 -349.927926)
		(end 377.49226 -349.87611)
		(stroke
			(width 0.07112)
			(type default)
		)
		(layer "In11.Cu")
	)
	(gr_line
		(start 377.49226 -349.87611)
		(end 377.49226 -349.819722)
		(stroke
			(width 0.07112)
			(type default)
		)
		(layer "In11.Cu")
	)
	(gr_line
		(start 377.51131 -363.611922)
		(end 377.511564 -363.611922)
		(stroke
			(width 0.07112)
			(type default)
		)
		(layer "In11.Cu")
	)
	(gr_arc
		(start 377.524772 -372.989856)
		(mid 377.524518 -372.99011)
		(end 377.524264 -372.990364)
		(stroke
			(width 0.07112)
			(type default)
		)
		(layer "In11.Cu")
	)
	(gr_line
		(start 377.594622 -421.7289)
		(end 377.730512 -421.86479)
		(stroke
			(width 0.07112)
			(type default)
		)
		(layer "In11.Cu")
	)
	(gr_line
		(start 377.730512 -422.29151)
		(end 377.594622 -422.4274)
		(stroke
			(width 0.07112)
			(type default)
		)
		(layer "In11.Cu")
	)
	(gr_line
		(start 377.730512 -421.86479)
		(end 377.730512 -422.29151)
		(stroke
			(width 0.07112)
			(type default)
		)
		(layer "In11.Cu")
	)
	(gr_line
		(start 377.884182 -420.952168)
		(end 377.593352 -421.242998)
		(stroke
			(width 0.07112)
			(type default)
		)
		(layer "In11.Cu")
	)
	(gr_line
		(start 378.154946 -350.113092)
		(end 378.1552 -350.112838)
		(stroke
			(width 0.07112)
			(type default)
		)
		(layer "In11.Cu")
	)
	(gr_line
		(start 378.18695 -427.868842)
		(end 378.685806 -428.361856)
		(stroke
			(width 0.07112)
			(type default)
		)
		(layer "In11.Cu")
	)
	(gr_line
		(start 378.252482 -307.474366)
		(end 378.252482 -307.47462)
		(stroke
			(width 0.07112)
			(type default)
		)
		(layer "In11.Cu")
	)
	(gr_line
		(start 378.258578 -423.264584)
		(end 378.959618 -423.264584)
		(stroke
			(width 0.07112)
			(type default)
		)
		(layer "In11.Cu")
	)
	(gr_line
		(start 378.259848 -422.981374)
		(end 378.395738 -422.845484)
		(stroke
			(width 0.07112)
			(type default)
		)
		(layer "In11.Cu")
	)
	(gr_line
		(start 378.318522 -382.0541)
		(end 378.027692 -382.34493)
		(stroke
			(width 0.07112)
			(type default)
		)
		(layer "In11.Cu")
	)
	(gr_line
		(start 378.386594 -427.668182)
		(end 378.578872 -427.667166)
		(stroke
			(width 0.07112)
			(type default)
		)
		(layer "In11.Cu")
	)
	(gr_line
		(start 378.395738 -422.845484)
		(end 378.822458 -422.845484)
		(stroke
			(width 0.07112)
			(type default)
		)
		(layer "In11.Cu")
	)
	(gr_line
		(start 378.41555 -350.221042)
		(end 378.43714 -350.169226)
		(stroke
			(width 0.07112)
			(type default)
		)
		(layer "In11.Cu")
	)
	(gr_line
		(start 378.43714 -350.169226)
		(end 378.43714 -350.112838)
		(stroke
			(width 0.07112)
			(type default)
		)
		(layer "In11.Cu")
	)
	(gr_line
		(start 378.578872 -427.667166)
		(end 378.88291 -427.96714)
		(stroke
			(width 0.07112)
			(type default)
		)
		(layer "In11.Cu")
	)
	(gr_line
		(start 378.600462 -382.0541)
		(end 378.891292 -382.34493)
		(stroke
			(width 0.07112)
			(type default)
		)
		(layer "In11.Cu")
	)
	(gr_line
		(start 378.685806 -428.361856)
		(end 378.742702 -428.41799)
		(stroke
			(width 0.07112)
			(type default)
		)
		(layer "In11.Cu")
	)
	(gr_line
		(start 378.822458 -422.845484)
		(end 378.958348 -422.981374)
		(stroke
			(width 0.07112)
			(type default)
		)
		(layer "In11.Cu")
	)
	(gr_line
		(start 378.88291 -427.96714)
		(end 378.883926 -428.159418)
		(stroke
			(width 0.07112)
			(type default)
		)
		(layer "In11.Cu")
	)
	(gr_line
		(start 378.883926 -428.161196)
		(end 378.940822 -428.21733)
		(stroke
			(width 0.07112)
			(type default)
		)
		(layer "In11.Cu")
	)
	(gr_line
		(start 378.989336 -428.661576)
		(end 379.488192 -429.15459)
		(stroke
			(width 0.07112)
			(type default)
		)
		(layer "In11.Cu")
	)
	(gr_line
		(start 379.189234 -428.460916)
		(end 379.381258 -428.4599)
		(stroke
			(width 0.07112)
			(type default)
		)
		(layer "In11.Cu")
	)
	(gr_line
		(start 379.381258 -428.4599)
		(end 379.685296 -428.759874)
		(stroke
			(width 0.07112)
			(type default)
		)
		(layer "In11.Cu")
	)
	(gr_line
		(start 379.386338 -423.264584)
		(end 380.087378 -423.264584)
		(stroke
			(width 0.07112)
			(type default)
		)
		(layer "In11.Cu")
	)
	(gr_line
		(start 379.387608 -422.981374)
		(end 379.523498 -422.845484)
		(stroke
			(width 0.07112)
			(type default)
		)
		(layer "In11.Cu")
	)
	(gr_line
		(start 379.488192 -429.15459)
		(end 379.791722 -429.45431)
		(stroke
			(width 0.07112)
			(type default)
		)
		(layer "In11.Cu")
	)
	(gr_line
		(start 379.523498 -422.845484)
		(end 379.950218 -422.845484)
		(stroke
			(width 0.07112)
			(type default)
		)
		(layer "In11.Cu")
	)
	(gr_line
		(start 379.685296 -428.759874)
		(end 379.686312 -428.951898)
		(stroke
			(width 0.07112)
			(type default)
		)
		(layer "In11.Cu")
	)
	(gr_line
		(start 379.686312 -428.95393)
		(end 379.989842 -429.25365)
		(stroke
			(width 0.07112)
			(type default)
		)
		(layer "In11.Cu")
	)
	(gr_line
		(start 379.791722 -429.45431)
		(end 380.290578 -429.94707)
		(stroke
			(width 0.07112)
			(type default)
		)
		(layer "In11.Cu")
	)
	(gr_line
		(start 379.950218 -422.845484)
		(end 380.086108 -422.981374)
		(stroke
			(width 0.07112)
			(type default)
		)
		(layer "In11.Cu")
	)
	(gr_line
		(start 379.99162 -429.25365)
		(end 380.183898 -429.25238)
		(stroke
			(width 0.07112)
			(type default)
		)
		(layer "In11.Cu")
	)
	(gr_line
		(start 380.020322 -379.5903)
		(end 379.729492 -379.88113)
		(stroke
			(width 0.07112)
			(type default)
		)
		(layer "In11.Cu")
	)
	(gr_line
		(start 380.083822 -420.952168)
		(end 380.374652 -421.242998)
		(stroke
			(width 0.07112)
			(type default)
		)
		(layer "In11.Cu")
	)
	(gr_line
		(start 380.183898 -429.25238)
		(end 380.487682 -429.552354)
		(stroke
			(width 0.07112)
			(type default)
		)
		(layer "In11.Cu")
	)
	(gr_line
		(start 380.302262 -379.5903)
		(end 380.593092 -379.88113)
		(stroke
			(width 0.07112)
			(type default)
		)
		(layer "In11.Cu")
	)
	(gr_line
		(start 380.406148 -368.866166)
		(end 380.406402 -368.866166)
		(stroke
			(width 0.07112)
			(type default)
		)
		(layer "In11.Cu")
	)
	(gr_line
		(start 380.487682 -429.552354)
		(end 380.488952 -429.744886)
		(stroke
			(width 0.07112)
			(type default)
		)
		(layer "In11.Cu")
	)
	(gr_line
		(start 380.947422 -420.952168)
		(end 380.656592 -421.242998)
		(stroke
			(width 0.07112)
			(type default)
		)
		(layer "In11.Cu")
	)
	(gr_line
		(start 381.29083 -430.43094)
		(end 381.749808 -430.889918)
		(stroke
			(width 0.07112)
			(type default)
		)
		(layer "In11.Cu")
	)
	(gr_line
		(start 381.29083 -430.148746)
		(end 381.749808 -429.689768)
		(stroke
			(width 0.07112)
			(type default)
		)
		(layer "In11.Cu")
	)
	(gr_line
		(start 381.391922 -422.320212)
		(end 382.092962 -422.320212)
		(stroke
			(width 0.07112)
			(type default)
		)
		(layer "In11.Cu")
	)
	(gr_line
		(start 381.393192 -422.037002)
		(end 381.529082 -421.901112)
		(stroke
			(width 0.07112)
			(type default)
		)
		(layer "In11.Cu")
	)
	(gr_line
		(start 381.529082 -421.901112)
		(end 381.955802 -421.901112)
		(stroke
			(width 0.07112)
			(type default)
		)
		(layer "In11.Cu")
	)
	(gr_line
		(start 381.722122 -377.1265)
		(end 381.431292 -377.41733)
		(stroke
			(width 0.07112)
			(type default)
		)
		(layer "In11.Cu")
	)
	(gr_line
		(start 381.955802 -421.901112)
		(end 382.091692 -422.037002)
		(stroke
			(width 0.07112)
			(type default)
		)
		(layer "In11.Cu")
	)
	(gr_line
		(start 382.004062 -377.1265)
		(end 382.294892 -377.41733)
		(stroke
			(width 0.07112)
			(type default)
		)
		(layer "In11.Cu")
	)
	(gr_line
		(start 382.171448 -424.047158)
		(end 382.171448 -424.046904)
		(stroke
			(width 0.07112)
			(type default)
		)
		(layer "In11.Cu")
	)
	(gr_line
		(start 383.136902 -359.445052)
		(end 383.137156 -359.445052)
		(stroke
			(width 0.07112)
			(type default)
		)
		(layer "In11.Cu")
	)
	(gr_line
		(start 383.147062 -420.952168)
		(end 383.44221 -421.247316)
		(stroke
			(width 0.07112)
			(type default)
		)
		(layer "In11.Cu")
	)
	(gr_line
		(start 383.400554 -359.54589)
		(end 383.399792 -359.547922)
		(stroke
			(width 0.07112)
			(type default)
		)
		(layer "In11.Cu")
	)
	(gr_line
		(start 383.401316 -359.544112)
		(end 383.400554 -359.54589)
		(stroke
			(width 0.07112)
			(type default)
		)
		(layer "In11.Cu")
	)
	(gr_line
		(start 383.607564 -431.430938)
		(end 383.749804 -431.573178)
		(stroke
			(width 0.07112)
			(type default)
		)
		(layer "In11.Cu")
	)
	(gr_line
		(start 383.607564 -431.148998)
		(end 383.749804 -431.006758)
		(stroke
			(width 0.07112)
			(type default)
		)
		(layer "In11.Cu")
	)
	(gr_line
		(start 383.72542 -421.23741)
		(end 383.72542 -421.248586)
		(stroke
			(width 0.07112)
			(type default)
		)
		(layer "In11.Cu")
	)
	(gr_line
		(start 383.749804 -431.573178)
		(end 383.749804 -431.889916)
		(stroke
			(width 0.07112)
			(type default)
		)
		(layer "In11.Cu")
	)
	(gr_line
		(start 383.749804 -431.006758)
		(end 383.749804 -430.689766)
		(stroke
			(width 0.07112)
			(type default)
		)
		(layer "In11.Cu")
	)
	(gr_line
		(start 384.010662 -420.952168)
		(end 383.72542 -421.23741)
		(stroke
			(width 0.07112)
			(type default)
		)
		(layer "In11.Cu")
	)
	(gr_line
		(start 384.198876 -347.507814)
		(end 384.198622 -347.50756)
		(stroke
			(width 0.07112)
			(type default)
		)
		(layer "In11.Cu")
	)
	(gr_line
		(start 384.419856 -312.80227)
		(end 384.419856 -312.802524)
		(stroke
			(width 0.07112)
			(type default)
		)
		(layer "In11.Cu")
	)
	(gr_line
		(start 384.537458 -422.246298)
		(end 385.238498 -422.246298)
		(stroke
			(width 0.07112)
			(type default)
		)
		(layer "In11.Cu")
	)
	(gr_line
		(start 384.538728 -421.963088)
		(end 384.674618 -421.827198)
		(stroke
			(width 0.07112)
			(type default)
		)
		(layer "In11.Cu")
	)
	(gr_line
		(start 384.674618 -421.827198)
		(end 385.101338 -421.827198)
		(stroke
			(width 0.07112)
			(type default)
		)
		(layer "In11.Cu")
	)
	(gr_line
		(start 385.078478 -382.101344)
		(end 384.834892 -382.34493)
		(stroke
			(width 0.07112)
			(type default)
		)
		(layer "In11.Cu")
	)
	(gr_arc
		(start 385.078478 -382.101344)
		(mid 385.109911 -382.056931)
		(end 385.124706 -382.00457)
		(stroke
			(width 0.07112)
			(type default)
		)
		(layer "In11.Cu")
	)
	(gr_line
		(start 385.101338 -421.827198)
		(end 385.237228 -421.963088)
		(stroke
			(width 0.07112)
			(type default)
		)
		(layer "In11.Cu")
	)
	(gr_line
		(start 385.131564 -348.284546)
		(end 385.13131 -348.284292)
		(stroke
			(width 0.07112)
			(type default)
		)
		(layer "In11.Cu")
	)
	(gr_line
		(start 385.194556 -361.7468)
		(end 385.194302 -361.747308)
		(stroke
			(width 0.07112)
			(type default)
		)
		(layer "In11.Cu")
	)
	(gr_line
		(start 385.22402 -423.43959)
		(end 385.68249 -423.89806)
		(stroke
			(width 0.07112)
			(type default)
		)
		(layer "In11.Cu")
	)
	(gr_arc
		(start 385.408678 -382.00457)
		(mid 385.423532 -382.056904)
		(end 385.454906 -382.101344)
		(stroke
			(width 0.07112)
			(type default)
		)
		(layer "In11.Cu")
	)
	(gr_line
		(start 385.425188 -423.2402)
		(end 385.580382 -423.2402)
		(stroke
			(width 0.07112)
			(type default)
		)
		(layer "In11.Cu")
	)
	(gr_line
		(start 385.454906 -382.101344)
		(end 385.698492 -382.34493)
		(stroke
			(width 0.07112)
			(type default)
		)
		(layer "In11.Cu")
	)
	(gr_line
		(start 385.580382 -423.2402)
		(end 385.88188 -423.541698)
		(stroke
			(width 0.07112)
			(type default)
		)
		(layer "In11.Cu")
	)
	(gr_line
		(start 385.60248 -430.435766)
		(end 385.61264 -430.435766)
		(stroke
			(width 0.07112)
			(type default)
		)
		(layer "In11.Cu")
	)
	(gr_line
		(start 385.60375 -430.152556)
		(end 385.7498 -430.006506)
		(stroke
			(width 0.07112)
			(type default)
		)
		(layer "In11.Cu")
	)
	(gr_line
		(start 385.61264 -430.435766)
		(end 385.7498 -430.572926)
		(stroke
			(width 0.07112)
			(type default)
		)
		(layer "In11.Cu")
	)
	(gr_line
		(start 385.650232 -422.38676)
		(end 386.120894 -422.857422)
		(stroke
			(width 0.07112)
			(type default)
		)
		(layer "In11.Cu")
	)
	(gr_line
		(start 385.7498 -430.572926)
		(end 385.7498 -430.889918)
		(stroke
			(width 0.07112)
			(type default)
		)
		(layer "In11.Cu")
	)
	(gr_line
		(start 385.7498 -430.006506)
		(end 385.7498 -429.689768)
		(stroke
			(width 0.07112)
			(type default)
		)
		(layer "In11.Cu")
	)
	(gr_line
		(start 385.8514 -422.18737)
		(end 386.018532 -422.18737)
		(stroke
			(width 0.07112)
			(type default)
		)
		(layer "In11.Cu")
	)
	(gr_line
		(start 385.88188 -423.541698)
		(end 385.88188 -423.696892)
		(stroke
			(width 0.07112)
			(type default)
		)
		(layer "In11.Cu")
	)
	(gr_line
		(start 386.014976 -424.230546)
		(end 386.473954 -424.689524)
		(stroke
			(width 0.07112)
			(type default)
		)
		(layer "In11.Cu")
	)
	(gr_line
		(start 386.018532 -422.18737)
		(end 386.320284 -422.489122)
		(stroke
			(width 0.07112)
			(type default)
		)
		(layer "In11.Cu")
	)
	(gr_line
		(start 386.210302 -420.952168)
		(end 386.501132 -421.242998)
		(stroke
			(width 0.07112)
			(type default)
		)
		(layer "In11.Cu")
	)
	(gr_line
		(start 386.216144 -424.031156)
		(end 386.371846 -424.031156)
		(stroke
			(width 0.07112)
			(type default)
		)
		(layer "In11.Cu")
	)
	(gr_line
		(start 386.320284 -422.489122)
		(end 386.320284 -422.656254)
		(stroke
			(width 0.07112)
			(type default)
		)
		(layer "In11.Cu")
	)
	(gr_line
		(start 386.371846 -424.031156)
		(end 386.673344 -424.332654)
		(stroke
			(width 0.07112)
			(type default)
		)
		(layer "In11.Cu")
	)
	(gr_line
		(start 386.381498 -423.118026)
		(end 386.87756 -423.614088)
		(stroke
			(width 0.07112)
			(type default)
		)
		(layer "In11.Cu")
	)
	(gr_line
		(start 386.582666 -422.918636)
		(end 386.774944 -422.918636)
		(stroke
			(width 0.07112)
			(type default)
		)
		(layer "In11.Cu")
	)
	(gr_line
		(start 386.673344 -424.332654)
		(end 386.673344 -424.488356)
		(stroke
			(width 0.07112)
			(type default)
		)
		(layer "In11.Cu")
	)
	(gr_line
		(start 386.774944 -422.918636)
		(end 387.07695 -423.220642)
		(stroke
			(width 0.07112)
			(type default)
		)
		(layer "In11.Cu")
	)
	(gr_line
		(start 386.827522 -379.5903)
		(end 386.536692 -379.88113)
		(stroke
			(width 0.07112)
			(type default)
		)
		(layer "In11.Cu")
	)
	(gr_line
		(start 387.073902 -420.952168)
		(end 386.783072 -421.242998)
		(stroke
			(width 0.07112)
			(type default)
		)
		(layer "In11.Cu")
	)
	(gr_line
		(start 387.07695 -423.220642)
		(end 387.07695 -423.41292)
		(stroke
			(width 0.07112)
			(type default)
		)
		(layer "In11.Cu")
	)
	(gr_line
		(start 387.109462 -379.5903)
		(end 387.400292 -379.88113)
		(stroke
			(width 0.07112)
			(type default)
		)
		(layer "In11.Cu")
	)
	(gr_line
		(start 387.11886 -340.952836)
		(end 387.119114 -340.952582)
		(stroke
			(width 0.07112)
			(type default)
		)
		(layer "In11.Cu")
	)
	(gr_line
		(start 387.388608 -340.826598)
		(end 387.388608 -340.827106)
		(stroke
			(width 0.07112)
			(type default)
		)
		(layer "In11.Cu")
	)
	(gr_line
		(start 387.607556 -431.430938)
		(end 387.749796 -431.573178)
		(stroke
			(width 0.07112)
			(type default)
		)
		(layer "In11.Cu")
	)
	(gr_line
		(start 387.607556 -431.148998)
		(end 387.749796 -431.006758)
		(stroke
			(width 0.07112)
			(type default)
		)
		(layer "In11.Cu")
	)
	(gr_line
		(start 387.692138 -56.27497)
		(end 387.694678 -56.271668)
		(stroke
			(width 0.07112)
			(type default)
		)
		(layer "In11.Cu")
	)
	(gr_line
		(start 387.749796 -431.573178)
		(end 387.749796 -431.889916)
		(stroke
			(width 0.07112)
			(type default)
		)
		(layer "In11.Cu")
	)
	(gr_line
		(start 387.749796 -431.006758)
		(end 387.749796 -430.689766)
		(stroke
			(width 0.07112)
			(type default)
		)
		(layer "In11.Cu")
	)
	(gr_arc
		(start 387.998716 -316.915292)
		(mid 387.987805 -316.894)
		(end 387.97611 -316.873128)
		(stroke
			(width 0.07112)
			(type default)
		)
		(layer "In11.Cu")
	)
	(gr_line
		(start 388.19074 -54.222396)
		(end 388.192518 -54.220364)
		(stroke
			(width 0.07112)
			(type default)
		)
		(layer "In11.Cu")
	)
	(gr_line
		(start 388.215886 -316.722252)
		(end 388.240524 -316.759082)
		(stroke
			(width 0.07112)
			(type default)
		)
		(layer "In11.Cu")
	)
	(gr_line
		(start 388.240524 -316.759082)
		(end 388.257288 -316.799468)
		(stroke
			(width 0.07112)
			(type default)
		)
		(layer "In11.Cu")
	)
	(gr_line
		(start 388.529322 -377.1265)
		(end 388.238492 -377.41733)
		(stroke
			(width 0.07112)
			(type default)
		)
		(layer "In11.Cu")
	)
	(gr_line
		(start 388.811262 -377.1265)
		(end 389.102092 -377.41733)
		(stroke
			(width 0.07112)
			(type default)
		)
		(layer "In11.Cu")
	)
	(gr_line
		(start 388.835646 -423.010838)
		(end 389.3312 -423.507154)
		(stroke
			(width 0.07112)
			(type default)
		)
		(layer "In11.Cu")
	)
	(gr_line
		(start 389.036814 -422.811448)
		(end 389.229092 -422.811448)
		(stroke
			(width 0.07112)
			(type default)
		)
		(layer "In11.Cu")
	)
	(gr_line
		(start 389.229092 -422.811448)
		(end 389.530844 -423.113708)
		(stroke
			(width 0.07112)
			(type default)
		)
		(layer "In11.Cu")
	)
	(gr_line
		(start 389.273542 -420.952168)
		(end 389.564372 -421.242998)
		(stroke
			(width 0.07112)
			(type default)
		)
		(layer "In11.Cu")
	)
	(gr_line
		(start 389.530844 -423.113708)
		(end 389.530844 -423.30624)
		(stroke
			(width 0.07112)
			(type default)
		)
		(layer "In11.Cu")
	)
	(gr_line
		(start 389.622792 -430.459896)
		(end 389.749792 -430.586896)
		(stroke
			(width 0.07112)
			(type default)
		)
		(layer "In11.Cu")
	)
	(gr_line
		(start 389.622792 -430.177702)
		(end 389.749792 -430.050702)
		(stroke
			(width 0.07112)
			(type default)
		)
		(layer "In11.Cu")
	)
	(gr_line
		(start 389.747252 -423.923714)
		(end 390.24306 -424.42003)
		(stroke
			(width 0.07112)
			(type default)
		)
		(layer "In11.Cu")
	)
	(gr_line
		(start 389.749792 -430.586896)
		(end 389.749792 -430.889918)
		(stroke
			(width 0.07112)
			(type default)
		)
		(layer "In11.Cu")
	)
	(gr_line
		(start 389.749792 -430.050702)
		(end 389.749792 -429.689768)
		(stroke
			(width 0.07112)
			(type default)
		)
		(layer "In11.Cu")
	)
	(gr_line
		(start 389.94842 -423.724324)
		(end 390.140952 -423.724324)
		(stroke
			(width 0.07112)
			(type default)
		)
		(layer "In11.Cu")
	)
	(gr_line
		(start 390.044178 -422.43502)
		(end 390.623044 -422.822116)
		(stroke
			(width 0.07112)
			(type default)
		)
		(layer "In11.Cu")
	)
	(gr_line
		(start 390.137142 -420.952168)
		(end 389.846312 -421.242998)
		(stroke
			(width 0.07112)
			(type default)
		)
		(layer "In11.Cu")
	)
	(gr_line
		(start 390.140952 -423.724324)
		(end 390.442704 -424.026584)
		(stroke
			(width 0.07112)
			(type default)
		)
		(layer "In11.Cu")
	)
	(gr_line
		(start 390.20242 -422.200324)
		(end 390.387586 -422.163494)
		(stroke
			(width 0.07112)
			(type default)
		)
		(layer "In11.Cu")
	)
	(gr_arc
		(start 390.305036 -322.495418)
		(mid 390.298039 -322.470629)
		(end 390.29005 -322.446142)
		(stroke
			(width 0.07112)
			(type default)
		)
		(layer "In11.Cu")
	)
	(gr_line
		(start 390.387586 -422.163494)
		(end 390.742678 -422.40073)
		(stroke
			(width 0.07112)
			(type default)
		)
		(layer "In11.Cu")
	)
	(gr_line
		(start 390.442704 -424.026584)
		(end 390.442704 -424.219116)
		(stroke
			(width 0.07112)
			(type default)
		)
		(layer "In11.Cu")
	)
	(gr_line
		(start 390.554464 -322.344542)
		(end 390.572498 -322.387976)
		(stroke
			(width 0.07112)
			(type default)
		)
		(layer "In11.Cu")
	)
	(gr_line
		(start 390.572498 -322.387976)
		(end 390.581388 -322.43268)
		(stroke
			(width 0.07112)
			(type default)
		)
		(layer "In11.Cu")
	)
	(gr_line
		(start 390.742678 -422.40073)
		(end 390.779508 -422.585896)
		(stroke
			(width 0.07112)
			(type default)
		)
		(layer "In11.Cu")
	)
	(gr_line
		(start 390.977628 -423.058844)
		(end 391.556494 -423.44594)
		(stroke
			(width 0.07112)
			(type default)
		)
		(layer "In11.Cu")
	)
	(gr_arc
		(start 391.085832 -425.033186)
		(mid 391.085832 -425.03344)
		(end 391.085832 -425.033694)
		(stroke
			(width 0.07112)
			(type default)
		)
		(layer "In11.Cu")
	)
	(gr_line
		(start 391.13587 -422.824148)
		(end 391.321036 -422.787318)
		(stroke
			(width 0.07112)
			(type default)
		)
		(layer "In11.Cu")
	)
	(gr_line
		(start 391.230866 8.548878)
		(end 390.940036 8.258048)
		(stroke
			(width 0.07112)
			(type default)
		)
		(layer "In11.Cu")
	)
	(gr_line
		(start 391.230866 8.830818)
		(end 390.940036 9.121648)
		(stroke
			(width 0.07112)
			(type default)
		)
		(layer "In11.Cu")
	)
	(gr_line
		(start 391.321036 -422.787318)
		(end 391.676128 -423.024554)
		(stroke
			(width 0.07112)
			(type default)
		)
		(layer "In11.Cu")
	)
	(gr_line
		(start 391.607548 -431.430938)
		(end 391.749788 -431.573178)
		(stroke
			(width 0.07112)
			(type default)
		)
		(layer "In11.Cu")
	)
	(gr_line
		(start 391.607548 -431.148998)
		(end 391.749788 -431.006758)
		(stroke
			(width 0.07112)
			(type default)
		)
		(layer "In11.Cu")
	)
	(gr_line
		(start 391.676128 -423.024554)
		(end 391.712958 -423.20972)
		(stroke
			(width 0.07112)
			(type default)
		)
		(layer "In11.Cu")
	)
	(gr_line
		(start 391.749788 -431.573178)
		(end 391.749788 -431.889916)
		(stroke
			(width 0.07112)
			(type default)
		)
		(layer "In11.Cu")
	)
	(gr_line
		(start 391.749788 -431.006758)
		(end 391.749788 -430.689766)
		(stroke
			(width 0.07112)
			(type default)
		)
		(layer "In11.Cu")
	)
	(gr_line
		(start 391.911078 -423.682922)
		(end 392.489944 -424.069764)
		(stroke
			(width 0.07112)
			(type default)
		)
		(layer "In11.Cu")
	)
	(gr_line
		(start 391.932922 -377.1265)
		(end 391.642092 -377.41733)
		(stroke
			(width 0.07112)
			(type default)
		)
		(layer "In11.Cu")
	)
	(gr_line
		(start 392.06932 -423.447972)
		(end 392.254486 -423.411142)
		(stroke
			(width 0.07112)
			(type default)
		)
		(layer "In11.Cu")
	)
	(gr_line
		(start 392.214862 -377.1265)
		(end 392.505692 -377.41733)
		(stroke
			(width 0.07112)
			(type default)
		)
		(layer "In11.Cu")
	)
	(gr_line
		(start 392.254486 -423.411142)
		(end 392.609578 -423.648378)
		(stroke
			(width 0.07112)
			(type default)
		)
		(layer "In11.Cu")
	)
	(gr_line
		(start 392.336782 -420.952168)
		(end 392.627612 -421.242998)
		(stroke
			(width 0.07112)
			(type default)
		)
		(layer "In11.Cu")
	)
	(gr_line
		(start 392.609578 -423.648378)
		(end 392.646408 -423.833544)
		(stroke
			(width 0.07112)
			(type default)
		)
		(layer "In11.Cu")
	)
	(gr_line
		(start 392.912092 -422.266364)
		(end 393.298934 -422.845484)
		(stroke
			(width 0.07112)
			(type default)
		)
		(layer "In11.Cu")
	)
	(gr_line
		(start 393.148058 -422.1099)
		(end 393.333224 -422.146984)
		(stroke
			(width 0.07112)
			(type default)
		)
		(layer "In11.Cu")
	)
	(gr_line
		(start 393.200382 -420.952168)
		(end 392.909552 -421.242998)
		(stroke
			(width 0.07112)
			(type default)
		)
		(layer "In11.Cu")
	)
	(gr_line
		(start 393.218162 -383.864358)
		(end 393.217908 -383.864104)
		(stroke
			(width 0.07112)
			(type default)
		)
		(layer "In11.Cu")
	)
	(gr_line
		(start 393.298934 -422.845484)
		(end 393.419076 -423.025062)
		(stroke
			(width 0.07112)
			(type default)
		)
		(layer "In11.Cu")
	)
	(gr_line
		(start 393.333224 -422.146984)
		(end 393.57046 -422.501822)
		(stroke
			(width 0.07112)
			(type default)
		)
		(layer "In11.Cu")
	)
	(gr_line
		(start 393.533376 -422.688766)
		(end 393.653518 -422.868598)
		(stroke
			(width 0.07112)
			(type default)
		)
		(layer "In11.Cu")
	)
	(gr_line
		(start 393.535916 -423.200068)
		(end 393.922758 -423.778934)
		(stroke
			(width 0.07112)
			(type default)
		)
		(layer "In11.Cu")
	)
	(gr_line
		(start 393.57046 -422.501822)
		(end 393.53363 -422.686988)
		(stroke
			(width 0.07112)
			(type default)
		)
		(layer "In11.Cu")
	)
	(gr_line
		(start 393.59332 -430.44491)
		(end 393.607036 -430.44491)
		(stroke
			(width 0.07112)
			(type default)
		)
		(layer "In11.Cu")
	)
	(gr_line
		(start 393.59459 -430.1617)
		(end 393.749784 -430.006506)
		(stroke
			(width 0.07112)
			(type default)
		)
		(layer "In11.Cu")
	)
	(gr_line
		(start 393.607036 -430.44491)
		(end 393.749784 -430.587658)
		(stroke
			(width 0.07112)
			(type default)
		)
		(layer "In11.Cu")
	)
	(gr_line
		(start 393.749784 -430.587658)
		(end 393.749784 -430.889918)
		(stroke
			(width 0.07112)
			(type default)
		)
		(layer "In11.Cu")
	)
	(gr_line
		(start 393.749784 -430.006506)
		(end 393.749784 -429.689768)
		(stroke
			(width 0.07112)
			(type default)
		)
		(layer "In11.Cu")
	)
	(gr_line
		(start 393.772136 -423.043604)
		(end 393.957048 -423.080688)
		(stroke
			(width 0.07112)
			(type default)
		)
		(layer "In11.Cu")
	)
	(gr_line
		(start 393.806426 -7.015988)
		(end 393.515596 -6.725158)
		(stroke
			(width 0.07112)
			(type default)
		)
		(layer "In11.Cu")
	)
	(gr_arc
		(start 393.81557 -340.163404)
		(mid 393.814123 -340.147254)
		(end 393.812268 -340.131146)
		(stroke
			(width 0.07112)
			(type default)
		)
		(layer "In11.Cu")
	)
	(gr_line
		(start 393.922758 -423.779188)
		(end 393.922758 -423.778934)
		(stroke
			(width 0.07112)
			(type default)
		)
		(layer "In11.Cu")
	)
	(gr_line
		(start 393.957048 -423.080688)
		(end 394.194284 -423.435526)
		(stroke
			(width 0.07112)
			(type default)
		)
		(layer "In11.Cu")
	)
	(gr_line
		(start 394.086842 -385.047998)
		(end 394.377672 -385.338828)
		(stroke
			(width 0.07112)
			(type default)
		)
		(layer "In11.Cu")
	)
	(gr_line
		(start 394.086842 -384.766058)
		(end 394.377672 -384.475228)
		(stroke
			(width 0.07112)
			(type default)
		)
		(layer "In11.Cu")
	)
	(gr_line
		(start 394.088366 -7.015988)
		(end 394.379196 -6.725158)
		(stroke
			(width 0.07112)
			(type default)
		)
		(layer "In11.Cu")
	)
	(gr_arc
		(start 394.098018 -340.144862)
		(mid 394.096008 -340.118775)
		(end 394.092938 -340.092792)
		(stroke
			(width 0.07112)
			(type default)
		)
		(layer "In11.Cu")
	)
	(gr_line
		(start 394.194284 -423.435526)
		(end 394.157454 -423.620692)
		(stroke
			(width 0.07112)
			(type default)
		)
		(layer "In11.Cu")
	)
	(gr_line
		(start 394.668502 -388.451598)
		(end 394.377672 -388.742428)
		(stroke
			(width 0.07112)
			(type default)
		)
		(layer "In11.Cu")
	)
	(gr_line
		(start 394.668502 -388.169658)
		(end 394.377672 -387.878828)
		(stroke
			(width 0.07112)
			(type default)
		)
		(layer "In11.Cu")
	)
	(gr_line
		(start 395.400022 -420.952168)
		(end 395.690852 -421.242998)
		(stroke
			(width 0.07112)
			(type default)
		)
		(layer "In11.Cu")
	)
	(gr_line
		(start 395.53642 -378.501656)
		(end 395.53642 -379.203966)
		(stroke
			(width 0.07112)
			(type default)
		)
		(layer "In11.Cu")
	)
	(gr_line
		(start 395.53642 -377.373896)
		(end 395.53642 -378.074936)
		(stroke
			(width 0.07112)
			(type default)
		)
		(layer "In11.Cu")
	)
	(gr_line
		(start 395.53642 -375.804684)
		(end 395.53642 -376.505724)
		(stroke
			(width 0.07112)
			(type default)
		)
		(layer "In11.Cu")
	)
	(gr_line
		(start 395.53642 -374.34901)
		(end 395.53642 -375.05005)
		(stroke
			(width 0.07112)
			(type default)
		)
		(layer "In11.Cu")
	)
	(gr_line
		(start 395.60754 -431.430938)
		(end 395.74978 -431.573178)
		(stroke
			(width 0.07112)
			(type default)
		)
		(layer "In11.Cu")
	)
	(gr_line
		(start 395.60754 -431.148998)
		(end 395.74978 -431.006758)
		(stroke
			(width 0.07112)
			(type default)
		)
		(layer "In11.Cu")
	)
	(gr_line
		(start 395.611096 -5.254244)
		(end 395.320266 -4.963414)
		(stroke
			(width 0.07112)
			(type default)
		)
		(layer "In11.Cu")
	)
	(gr_line
		(start 395.650212 -15.145258)
		(end 395.650466 -15.145258)
		(stroke
			(width 0.07112)
			(type default)
		)
		(layer "In11.Cu")
	)
	(gr_line
		(start 395.74978 -431.573178)
		(end 395.74978 -431.889916)
		(stroke
			(width 0.07112)
			(type default)
		)
		(layer "In11.Cu")
	)
	(gr_line
		(start 395.74978 -431.006758)
		(end 395.74978 -430.689766)
		(stroke
			(width 0.07112)
			(type default)
		)
		(layer "In11.Cu")
	)
	(gr_line
		(start 395.81963 -378.502926)
		(end 395.95552 -378.638816)
		(stroke
			(width 0.07112)
			(type default)
		)
		(layer "In11.Cu")
	)
	(gr_line
		(start 395.81963 -377.375166)
		(end 395.95552 -377.511056)
		(stroke
			(width 0.07112)
			(type default)
		)
		(layer "In11.Cu")
	)
	(gr_line
		(start 395.81963 -375.805954)
		(end 395.95552 -375.941844)
		(stroke
			(width 0.07112)
			(type default)
		)
		(layer "In11.Cu")
	)
	(gr_line
		(start 395.81963 -374.35028)
		(end 395.95552 -374.48617)
		(stroke
			(width 0.07112)
			(type default)
		)
		(layer "In11.Cu")
	)
	(gr_line
		(start 395.876272 -422.159938)
		(end 395.920976 -422.268142)
		(stroke
			(width 0.07112)
			(type default)
		)
		(layer "In11.Cu")
	)
	(gr_line
		(start 395.893036 -5.254244)
		(end 396.183866 -4.963414)
		(stroke
			(width 0.07112)
			(type default)
		)
		(layer "In11.Cu")
	)
	(gr_line
		(start 395.920976 -422.270174)
		(end 396.143734 -422.807892)
		(stroke
			(width 0.07112)
			(type default)
		)
		(layer "In11.Cu")
	)
	(gr_line
		(start 395.920976 -422.268142)
		(end 395.921992 -422.26865)
		(stroke
			(width 0.07112)
			(type default)
		)
		(layer "In11.Cu")
	)
	(gr_line
		(start 395.921992 -422.26865)
		(end 395.920976 -422.270174)
		(stroke
			(width 0.07112)
			(type default)
		)
		(layer "In11.Cu")
	)
	(gr_line
		(start 395.95552 -379.065536)
		(end 395.81963 -379.201426)
		(stroke
			(width 0.07112)
			(type default)
		)
		(layer "In11.Cu")
	)
	(gr_line
		(start 395.95552 -378.638816)
		(end 395.95552 -379.065536)
		(stroke
			(width 0.07112)
			(type default)
		)
		(layer "In11.Cu")
	)
	(gr_line
		(start 395.95552 -377.937776)
		(end 395.81963 -378.073666)
		(stroke
			(width 0.07112)
			(type default)
		)
		(layer "In11.Cu")
	)
	(gr_line
		(start 395.95552 -377.511056)
		(end 395.95552 -377.937776)
		(stroke
			(width 0.07112)
			(type default)
		)
		(layer "In11.Cu")
	)
	(gr_line
		(start 395.95552 -376.368564)
		(end 395.81963 -376.504454)
		(stroke
			(width 0.07112)
			(type default)
		)
		(layer "In11.Cu")
	)
	(gr_line
		(start 395.95552 -375.941844)
		(end 395.95552 -376.368564)
		(stroke
			(width 0.07112)
			(type default)
		)
		(layer "In11.Cu")
	)
	(gr_line
		(start 395.95552 -374.91289)
		(end 395.81963 -375.04878)
		(stroke
			(width 0.07112)
			(type default)
		)
		(layer "In11.Cu")
	)
	(gr_line
		(start 395.95552 -374.48617)
		(end 395.95552 -374.91289)
		(stroke
			(width 0.07112)
			(type default)
		)
		(layer "In11.Cu")
	)
	(gr_line
		(start 396.1384 -422.053004)
		(end 396.315438 -422.126156)
		(stroke
			(width 0.07112)
			(type default)
		)
		(layer "In11.Cu")
	)
	(gr_line
		(start 396.263622 -420.952168)
		(end 395.972792 -421.242998)
		(stroke
			(width 0.07112)
			(type default)
		)
		(layer "In11.Cu")
	)
	(gr_line
		(start 396.307056 -423.201846)
		(end 396.57528 -423.849038)
		(stroke
			(width 0.07112)
			(type default)
		)
		(layer "In11.Cu")
	)
	(gr_line
		(start 396.315438 -422.126156)
		(end 396.47876 -422.520618)
		(stroke
			(width 0.07112)
			(type default)
		)
		(layer "In11.Cu")
	)
	(gr_line
		(start 396.47876 -422.520618)
		(end 396.4051 -422.698672)
		(stroke
			(width 0.07112)
			(type default)
		)
		(layer "In11.Cu")
	)
	(gr_line
		(start 396.569184 -423.094912)
		(end 396.747238 -423.168318)
		(stroke
			(width 0.07112)
			(type default)
		)
		(layer "In11.Cu")
	)
	(gr_line
		(start 396.57528 -423.849038)
		(end 396.576042 -423.849292)
		(stroke
			(width 0.07112)
			(type default)
		)
		(layer "In11.Cu")
	)
	(gr_line
		(start 396.740888 -424.245024)
		(end 396.785592 -424.353482)
		(stroke
			(width 0.07112)
			(type default)
		)
		(layer "In11.Cu")
	)
	(gr_line
		(start 396.747238 -423.168318)
		(end 396.91056 -423.56278)
		(stroke
			(width 0.07112)
			(type default)
		)
		(layer "In11.Cu")
	)
	(gr_line
		(start 396.784576 -424.355006)
		(end 397.00708 -424.892216)
		(stroke
			(width 0.07112)
			(type default)
		)
		(layer "In11.Cu")
	)
	(gr_line
		(start 396.785592 -424.353482)
		(end 396.784576 -424.355006)
		(stroke
			(width 0.07112)
			(type default)
		)
		(layer "In11.Cu")
	)
	(gr_line
		(start 396.837154 -423.739818)
		(end 396.83817 -423.742104)
		(stroke
			(width 0.07112)
			(type default)
		)
		(layer "In11.Cu")
	)
	(gr_line
		(start 396.861538 -377.823984)
		(end 396.997428 -377.959874)
		(stroke
			(width 0.07112)
			(type default)
		)
		(layer "In11.Cu")
	)
	(gr_line
		(start 396.861538 -377.397264)
		(end 396.861538 -377.823984)
		(stroke
			(width 0.07112)
			(type default)
		)
		(layer "In11.Cu")
	)
	(gr_line
		(start 396.861538 -376.696224)
		(end 396.997428 -376.832114)
		(stroke
			(width 0.07112)
			(type default)
		)
		(layer "In11.Cu")
	)
	(gr_line
		(start 396.861538 -376.269504)
		(end 396.861538 -376.696224)
		(stroke
			(width 0.07112)
			(type default)
		)
		(layer "In11.Cu")
	)
	(gr_line
		(start 396.861538 -375.568464)
		(end 396.997428 -375.704354)
		(stroke
			(width 0.07112)
			(type default)
		)
		(layer "In11.Cu")
	)
	(gr_line
		(start 396.861538 -375.141744)
		(end 396.861538 -375.568464)
		(stroke
			(width 0.07112)
			(type default)
		)
		(layer "In11.Cu")
	)
	(gr_line
		(start 396.861538 -374.440704)
		(end 396.997428 -374.576594)
		(stroke
			(width 0.07112)
			(type default)
		)
		(layer "In11.Cu")
	)
	(gr_line
		(start 396.861538 -374.013984)
		(end 396.861538 -374.440704)
		(stroke
			(width 0.07112)
			(type default)
		)
		(layer "In11.Cu")
	)
	(gr_line
		(start 396.91056 -423.56278)
		(end 396.837154 -423.739818)
		(stroke
			(width 0.07112)
			(type default)
		)
		(layer "In11.Cu")
	)
	(gr_line
		(start 396.997428 -377.261374)
		(end 396.861538 -377.397264)
		(stroke
			(width 0.07112)
			(type default)
		)
		(layer "In11.Cu")
	)
	(gr_line
		(start 396.997428 -376.133614)
		(end 396.861538 -376.269504)
		(stroke
			(width 0.07112)
			(type default)
		)
		(layer "In11.Cu")
	)
	(gr_line
		(start 396.997428 -375.005854)
		(end 396.861538 -375.141744)
		(stroke
			(width 0.07112)
			(type default)
		)
		(layer "In11.Cu")
	)
	(gr_line
		(start 396.997428 -373.878094)
		(end 396.861538 -374.013984)
		(stroke
			(width 0.07112)
			(type default)
		)
		(layer "In11.Cu")
	)
	(gr_line
		(start 397.003016 -424.137836)
		(end 397.178784 -424.21048)
		(stroke
			(width 0.07112)
			(type default)
		)
		(layer "In11.Cu")
	)
	(gr_line
		(start 397.170402 -425.28617)
		(end 397.43888 -425.934378)
		(stroke
			(width 0.07112)
			(type default)
		)
		(layer "In11.Cu")
	)
	(gr_line
		(start 397.178784 -424.21048)
		(end 397.342106 -424.604942)
		(stroke
			(width 0.07112)
			(type default)
		)
		(layer "In11.Cu")
	)
	(gr_line
		(start 397.280638 -377.260104)
		(end 397.280638 -377.961144)
		(stroke
			(width 0.07112)
			(type default)
		)
		(layer "In11.Cu")
	)
	(gr_line
		(start 397.280638 -376.132344)
		(end 397.280638 -376.833384)
		(stroke
			(width 0.07112)
			(type default)
		)
		(layer "In11.Cu")
	)
	(gr_line
		(start 397.280638 -375.004584)
		(end 397.280638 -375.705624)
		(stroke
			(width 0.07112)
			(type default)
		)
		(layer "In11.Cu")
	)
	(gr_line
		(start 397.280638 -373.876824)
		(end 397.280638 -374.577864)
		(stroke
			(width 0.07112)
			(type default)
		)
		(layer "In11.Cu")
	)
	(gr_line
		(start 397.342106 -424.604942)
		(end 397.268446 -424.782996)
		(stroke
			(width 0.07112)
			(type default)
		)
		(layer "In11.Cu")
	)
	(gr_line
		(start 397.406368 -7.015988)
		(end 397.115538 -6.725158)
		(stroke
			(width 0.07112)
			(type default)
		)
		(layer "In11.Cu")
	)
	(gr_line
		(start 397.43253 -425.179236)
		(end 397.610584 -425.252642)
		(stroke
			(width 0.07112)
			(type default)
		)
		(layer "In11.Cu")
	)
	(gr_line
		(start 397.610584 -425.252642)
		(end 397.773906 -425.647104)
		(stroke
			(width 0.07112)
			(type default)
		)
		(layer "In11.Cu")
	)
	(gr_line
		(start 397.635222 -18.388076)
		(end 397.643858 -18.375122)
		(stroke
			(width 0.07112)
			(type default)
		)
		(layer "In11.Cu")
	)
	(gr_line
		(start 397.643604 -18.375122)
		(end 397.643858 -18.375122)
		(stroke
			(width 0.07112)
			(type default)
		)
		(layer "In11.Cu")
	)
	(gr_line
		(start 397.643604 -18.375122)
		(end 397.650208 -18.36293)
		(stroke
			(width 0.07112)
			(type default)
		)
		(layer "In11.Cu")
	)
	(gr_line
		(start 397.688308 -7.015988)
		(end 397.979138 -6.725158)
		(stroke
			(width 0.07112)
			(type default)
		)
		(layer "In11.Cu")
	)
	(gr_line
		(start 397.773906 -425.647104)
		(end 397.700246 -425.824904)
		(stroke
			(width 0.07112)
			(type default)
		)
		(layer "In11.Cu")
	)
	(gr_line
		(start 398.463262 -420.952168)
		(end 398.754092 -421.242998)
		(stroke
			(width 0.07112)
			(type default)
		)
		(layer "In11.Cu")
	)
	(gr_line
		(start 398.606772 -430.149)
		(end 398.607788 -430.149)
		(stroke
			(width 0.07112)
			(type default)
		)
		(layer "In11.Cu")
	)
	(gr_line
		(start 398.607788 -430.431956)
		(end 398.750028 -430.574196)
		(stroke
			(width 0.07112)
			(type default)
		)
		(layer "In11.Cu")
	)
	(gr_line
		(start 398.607788 -430.149)
		(end 398.750028 -430.00676)
		(stroke
			(width 0.07112)
			(type default)
		)
		(layer "In11.Cu")
	)
	(gr_line
		(start 398.750028 -430.574196)
		(end 398.750028 -430.889918)
		(stroke
			(width 0.07112)
			(type default)
		)
		(layer "In11.Cu")
	)
	(gr_line
		(start 398.750028 -430.00676)
		(end 398.750028 -429.689768)
		(stroke
			(width 0.07112)
			(type default)
		)
		(layer "In11.Cu")
	)
	(gr_line
		(start 398.889728 -422.352724)
		(end 399.059146 -422.911524)
		(stroke
			(width 0.07112)
			(type default)
		)
		(layer "In11.Cu")
	)
	(gr_line
		(start 399.057876 -422.914318)
		(end 399.091912 -423.026332)
		(stroke
			(width 0.07112)
			(type default)
		)
		(layer "In11.Cu")
	)
	(gr_line
		(start 399.059146 -422.911524)
		(end 399.057876 -422.914318)
		(stroke
			(width 0.07112)
			(type default)
		)
		(layer "In11.Cu")
	)
	(gr_line
		(start 399.161254 -422.271698)
		(end 399.330926 -422.362376)
		(stroke
			(width 0.07112)
			(type default)
		)
		(layer "In11.Cu")
	)
	(gr_line
		(start 399.211038 -5.254244)
		(end 398.920208 -4.963414)
		(stroke
			(width 0.07112)
			(type default)
		)
		(layer "In11.Cu")
	)
	(gr_line
		(start 399.214594 -423.430954)
		(end 399.248376 -423.542968)
		(stroke
			(width 0.07112)
			(type default)
		)
		(layer "In11.Cu")
	)
	(gr_line
		(start 399.248376 -423.542968)
		(end 399.25117 -423.544492)
		(stroke
			(width 0.07112)
			(type default)
		)
		(layer "In11.Cu")
	)
	(gr_line
		(start 399.25117 -423.544492)
		(end 399.420588 -424.103546)
		(stroke
			(width 0.07112)
			(type default)
		)
		(layer "In11.Cu")
	)
	(gr_line
		(start 399.326862 -420.952168)
		(end 399.036032 -421.242998)
		(stroke
			(width 0.07112)
			(type default)
		)
		(layer "In11.Cu")
	)
	(gr_line
		(start 399.330926 -422.362376)
		(end 399.454878 -422.771062)
		(stroke
			(width 0.07112)
			(type default)
		)
		(layer "In11.Cu")
	)
	(gr_line
		(start 399.454878 -422.771062)
		(end 399.362676 -422.943274)
		(stroke
			(width 0.07112)
			(type default)
		)
		(layer "In11.Cu")
	)
	(gr_line
		(start 399.485866 -423.349674)
		(end 399.658078 -423.441876)
		(stroke
			(width 0.07112)
			(type default)
		)
		(layer "In11.Cu")
	)
	(gr_line
		(start 399.492978 -5.254244)
		(end 399.783808 -4.963414)
		(stroke
			(width 0.07112)
			(type default)
		)
		(layer "In11.Cu")
	)
	(gr_line
		(start 399.658078 -423.441876)
		(end 399.78203 -423.850562)
		(stroke
			(width 0.07112)
			(type default)
		)
		(layer "In11.Cu")
	)
	(gr_line
		(start 399.78203 -423.850562)
		(end 399.691352 -424.020234)
		(stroke
			(width 0.07112)
			(type default)
		)
		(layer "In11.Cu")
	)
	(gr_line
		(start 400.607784 -431.430938)
		(end 400.750024 -431.573178)
		(stroke
			(width 0.07112)
			(type default)
		)
		(layer "In11.Cu")
	)
	(gr_line
		(start 400.607784 -431.148998)
		(end 400.750024 -431.006758)
		(stroke
			(width 0.07112)
			(type default)
		)
		(layer "In11.Cu")
	)
	(gr_line
		(start 400.750024 -431.573178)
		(end 400.750024 -431.889916)
		(stroke
			(width 0.07112)
			(type default)
		)
		(layer "In11.Cu")
	)
	(gr_line
		(start 400.750024 -431.006758)
		(end 400.750024 -430.689766)
		(stroke
			(width 0.07112)
			(type default)
		)
		(layer "In11.Cu")
	)
	(gr_line
		(start 401.00631 -7.015988)
		(end 400.71548 -6.725158)
		(stroke
			(width 0.07112)
			(type default)
		)
		(layer "In11.Cu")
	)
	(gr_line
		(start 401.28825 -7.015988)
		(end 401.57908 -6.725158)
		(stroke
			(width 0.07112)
			(type default)
		)
		(layer "In11.Cu")
	)
	(gr_line
		(start 401.526502 -420.952168)
		(end 401.799044 -421.22471)
		(stroke
			(width 0.07112)
			(type default)
		)
		(layer "In11.Cu")
	)
	(gr_line
		(start 401.738592 -43.704256)
		(end 401.819364 -43.615102)
		(stroke
			(width 0.07112)
			(type default)
		)
		(layer "In11.Cu")
	)
	(gr_line
		(start 401.738846 -43.706796)
		(end 401.738592 -43.704256)
		(stroke
			(width 0.07112)
			(type default)
		)
		(layer "In11.Cu")
	)
	(gr_line
		(start 401.799044 -423.943526)
		(end 401.799044 -424.644566)
		(stroke
			(width 0.07112)
			(type default)
		)
		(layer "In11.Cu")
	)
	(gr_line
		(start 401.799044 -422.815766)
		(end 401.799044 -423.516806)
		(stroke
			(width 0.07112)
			(type default)
		)
		(layer "In11.Cu")
	)
	(gr_line
		(start 401.799044 -421.688006)
		(end 401.799044 -422.389046)
		(stroke
			(width 0.07112)
			(type default)
		)
		(layer "In11.Cu")
	)
	(gr_line
		(start 401.799044 -421.22471)
		(end 401.799044 -421.261286)
		(stroke
			(width 0.07112)
			(type default)
		)
		(layer "In11.Cu")
	)
	(gr_line
		(start 401.819364 -43.615102)
		(end 401.820888 -43.613324)
		(stroke
			(width 0.07112)
			(type default)
		)
		(layer "In11.Cu")
	)
	(gr_line
		(start 401.947126 -43.897042)
		(end 401.948396 -43.895772)
		(stroke
			(width 0.07112)
			(type default)
		)
		(layer "In11.Cu")
	)
	(gr_line
		(start 401.948396 -43.895772)
		(end 402.030184 -43.80611)
		(stroke
			(width 0.07112)
			(type default)
		)
		(layer "In11.Cu")
	)
	(gr_line
		(start 402.030184 -43.80611)
		(end 402.02993 -43.803062)
		(stroke
			(width 0.07112)
			(type default)
		)
		(layer "In11.Cu")
	)
	(gr_line
		(start 402.082254 -423.944796)
		(end 402.218144 -424.080686)
		(stroke
			(width 0.07112)
			(type default)
		)
		(layer "In11.Cu")
	)
	(gr_line
		(start 402.082254 -422.817036)
		(end 402.218144 -422.952926)
		(stroke
			(width 0.07112)
			(type default)
		)
		(layer "In11.Cu")
	)
	(gr_line
		(start 402.082254 -421.689276)
		(end 402.218144 -421.825166)
		(stroke
			(width 0.07112)
			(type default)
		)
		(layer "In11.Cu")
	)
	(gr_line
		(start 402.218144 -424.507406)
		(end 402.082254 -424.643296)
		(stroke
			(width 0.07112)
			(type default)
		)
		(layer "In11.Cu")
	)
	(gr_line
		(start 402.218144 -424.080686)
		(end 402.218144 -424.507406)
		(stroke
			(width 0.07112)
			(type default)
		)
		(layer "In11.Cu")
	)
	(gr_line
		(start 402.218144 -423.379646)
		(end 402.082254 -423.515536)
		(stroke
			(width 0.07112)
			(type default)
		)
		(layer "In11.Cu")
	)
	(gr_line
		(start 402.218144 -422.952926)
		(end 402.218144 -423.379646)
		(stroke
			(width 0.07112)
			(type default)
		)
		(layer "In11.Cu")
	)
	(gr_line
		(start 402.218144 -422.251886)
		(end 402.082254 -422.387776)
		(stroke
			(width 0.07112)
			(type default)
		)
		(layer "In11.Cu")
	)
	(gr_line
		(start 402.218144 -421.825166)
		(end 402.218144 -422.251886)
		(stroke
			(width 0.07112)
			(type default)
		)
		(layer "In11.Cu")
	)
	(gr_line
		(start 402.390102 -420.952168)
		(end 402.082254 -421.260016)
		(stroke
			(width 0.07112)
			(type default)
		)
		(layer "In11.Cu")
	)
	(gr_line
		(start 402.583396 -430.148746)
		(end 402.60778 -430.148746)
		(stroke
			(width 0.07112)
			(type default)
		)
		(layer "In11.Cu")
	)
	(gr_line
		(start 402.584666 -430.431956)
		(end 402.75002 -430.59731)
		(stroke
			(width 0.07112)
			(type default)
		)
		(layer "In11.Cu")
	)
	(gr_line
		(start 402.60778 -430.148746)
		(end 402.75002 -430.006506)
		(stroke
			(width 0.07112)
			(type default)
		)
		(layer "In11.Cu")
	)
	(gr_line
		(start 402.75002 -430.59731)
		(end 402.75002 -430.889918)
		(stroke
			(width 0.07112)
			(type default)
		)
		(layer "In11.Cu")
	)
	(gr_line
		(start 402.75002 -430.006506)
		(end 402.75002 -429.689768)
		(stroke
			(width 0.07112)
			(type default)
		)
		(layer "In11.Cu")
	)
	(gr_line
		(start 402.81098 -5.254244)
		(end 402.52015 -4.963414)
		(stroke
			(width 0.07112)
			(type default)
		)
		(layer "In11.Cu")
	)
	(gr_line
		(start 403.09292 -5.254244)
		(end 403.38375 -4.963414)
		(stroke
			(width 0.07112)
			(type default)
		)
		(layer "In11.Cu")
	)
	(gr_line
		(start 403.225 -18.385028)
		(end 403.231604 -18.375122)
		(stroke
			(width 0.07112)
			(type default)
		)
		(layer "In11.Cu")
	)
	(gr_line
		(start 403.231604 -18.375122)
		(end 403.237954 -18.363184)
		(stroke
			(width 0.07112)
			(type default)
		)
		(layer "In11.Cu")
	)
	(gr_line
		(start 403.460204 -17.948402)
		(end 403.45995 -17.948402)
		(stroke
			(width 0.07112)
			(type default)
		)
		(layer "In11.Cu")
	)
	(gr_line
		(start 403.460204 -17.948402)
		(end 403.467062 -17.935448)
		(stroke
			(width 0.07112)
			(type default)
		)
		(layer "In11.Cu")
	)
	(gr_line
		(start 403.467062 -17.935448)
		(end 403.472396 -17.922494)
		(stroke
			(width 0.07112)
			(type default)
		)
		(layer "In11.Cu")
	)
	(gr_line
		(start 403.493732 -17.871186)
		(end 403.493478 -17.871186)
		(stroke
			(width 0.07112)
			(type default)
		)
		(layer "In11.Cu")
	)
	(gr_line
		(start 403.51456 -17.820132)
		(end 403.53742 -17.76476)
		(stroke
			(width 0.07112)
			(type default)
		)
		(layer "In11.Cu")
	)
	(gr_line
		(start 403.53742 -17.76476)
		(end 403.53742 -17.708626)
		(stroke
			(width 0.07112)
			(type default)
		)
		(layer "In11.Cu")
	)
	(gr_line
		(start 403.80412 -430.909222)
		(end 403.803866 -430.909222)
		(stroke
			(width 0.07112)
			(type default)
		)
		(layer "In11.Cu")
	)
	(gr_arc
		(start 403.924008 -431.198782)
		(mid 403.9235 -431.198274)
		(end 403.922992 -431.197766)
		(stroke
			(width 0.07112)
			(type default)
		)
		(layer "In11.Cu")
	)
	(gr_line
		(start 404.08606 -430.909476)
		(end 404.086314 -430.909476)
		(stroke
			(width 0.07112)
			(type default)
		)
		(layer "In11.Cu")
	)
	(gr_line
		(start 404.30704 -422.978834)
		(end 404.038562 -423.626534)
		(stroke
			(width 0.07112)
			(type default)
		)
		(layer "In11.Cu")
	)
	(gr_line
		(start 404.470362 -422.584626)
		(end 404.410164 -422.72966)
		(stroke
			(width 0.07112)
			(type default)
		)
		(layer "In11.Cu")
	)
	(gr_line
		(start 404.47849 -423.660062)
		(end 404.30069 -423.733722)
		(stroke
			(width 0.07112)
			(type default)
		)
		(layer "In11.Cu")
	)
	(gr_line
		(start 404.568152 -423.088054)
		(end 404.641812 -423.2656)
		(stroke
			(width 0.07112)
			(type default)
		)
		(layer "In11.Cu")
	)
	(gr_line
		(start 404.589742 -420.952168)
		(end 404.880572 -421.242998)
		(stroke
			(width 0.07112)
			(type default)
		)
		(layer "In11.Cu")
	)
	(gr_line
		(start 404.606506 -7.015988)
		(end 404.315676 -6.725158)
		(stroke
			(width 0.07112)
			(type default)
		)
		(layer "In11.Cu")
	)
	(gr_line
		(start 404.607776 -431.430938)
		(end 404.750016 -431.573178)
		(stroke
			(width 0.07112)
			(type default)
		)
		(layer "In11.Cu")
	)
	(gr_line
		(start 404.607776 -431.148998)
		(end 404.750016 -431.006758)
		(stroke
			(width 0.07112)
			(type default)
		)
		(layer "In11.Cu")
	)
	(gr_line
		(start 404.641812 -423.2656)
		(end 404.47849 -423.660062)
		(stroke
			(width 0.07112)
			(type default)
		)
		(layer "In11.Cu")
	)
	(gr_line
		(start 404.730712 -422.692322)
		(end 404.670514 -422.83761)
		(stroke
			(width 0.07112)
			(type default)
		)
		(layer "In11.Cu")
	)
	(gr_line
		(start 404.738586 -421.936418)
		(end 404.470362 -422.584626)
		(stroke
			(width 0.07112)
			(type default)
		)
		(layer "In11.Cu")
	)
	(gr_line
		(start 404.750016 -431.573178)
		(end 404.750016 -431.889916)
		(stroke
			(width 0.07112)
			(type default)
		)
		(layer "In11.Cu")
	)
	(gr_line
		(start 404.750016 -431.006758)
		(end 404.750016 -430.689766)
		(stroke
			(width 0.07112)
			(type default)
		)
		(layer "In11.Cu")
	)
	(gr_line
		(start 404.888446 -7.015988)
		(end 405.179276 -6.725158)
		(stroke
			(width 0.07112)
			(type default)
		)
		(layer "In11.Cu")
	)
	(gr_line
		(start 404.91029 -422.6179)
		(end 404.73249 -422.69156)
		(stroke
			(width 0.07112)
			(type default)
		)
		(layer "In11.Cu")
	)
	(gr_line
		(start 404.999952 -422.045638)
		(end 405.073612 -422.223438)
		(stroke
			(width 0.07112)
			(type default)
		)
		(layer "In11.Cu")
	)
	(gr_line
		(start 405.073612 -422.223438)
		(end 404.91029 -422.6179)
		(stroke
			(width 0.07112)
			(type default)
		)
		(layer "In11.Cu")
	)
	(gr_line
		(start 405.453342 -420.952168)
		(end 405.162512 -421.242998)
		(stroke
			(width 0.07112)
			(type default)
		)
		(layer "In11.Cu")
	)
	(gr_line
		(start 405.859742 -424.284902)
		(end 405.795734 -424.36288)
		(stroke
			(width 0.07112)
			(type default)
		)
		(layer "In11.Cu")
	)
	(gr_line
		(start 406.08377 -424.011852)
		(end 405.859742 -424.284902)
		(stroke
			(width 0.07112)
			(type default)
		)
		(layer "In11.Cu")
	)
	(gr_line
		(start 406.301702 -424.190668)
		(end 406.077674 -424.463718)
		(stroke
			(width 0.07112)
			(type default)
		)
		(layer "In11.Cu")
	)
	(gr_line
		(start 406.411176 -5.254244)
		(end 406.120346 -4.963414)
		(stroke
			(width 0.07112)
			(type default)
		)
		(layer "In11.Cu")
	)
	(gr_line
		(start 406.479248 -424.173142)
		(end 406.30348 -424.190414)
		(stroke
			(width 0.07112)
			(type default)
		)
		(layer "In11.Cu")
	)
	(gr_line
		(start 406.514808 -423.48658)
		(end 406.08377 -424.011852)
		(stroke
			(width 0.07112)
			(type default)
		)
		(layer "In11.Cu")
	)
	(gr_line
		(start 406.552908 -430.170336)
		(end 406.586182 -430.170336)
		(stroke
			(width 0.07112)
			(type default)
		)
		(layer "In11.Cu")
	)
	(gr_line
		(start 406.554178 -430.453546)
		(end 406.750012 -430.64938)
		(stroke
			(width 0.07112)
			(type default)
		)
		(layer "In11.Cu")
	)
	(gr_line
		(start 406.586182 -430.170336)
		(end 406.750012 -430.006506)
		(stroke
			(width 0.07112)
			(type default)
		)
		(layer "In11.Cu")
	)
	(gr_line
		(start 406.693116 -5.254244)
		(end 406.983946 -4.963414)
		(stroke
			(width 0.07112)
			(type default)
		)
		(layer "In11.Cu")
	)
	(gr_line
		(start 406.732994 -423.667174)
		(end 406.750266 -423.842942)
		(stroke
			(width 0.07112)
			(type default)
		)
		(layer "In11.Cu")
	)
	(gr_line
		(start 406.750012 -430.64938)
		(end 406.750012 -430.889918)
		(stroke
			(width 0.07112)
			(type default)
		)
		(layer "In11.Cu")
	)
	(gr_line
		(start 406.750012 -430.006506)
		(end 406.750012 -429.689768)
		(stroke
			(width 0.07112)
			(type default)
		)
		(layer "In11.Cu")
	)
	(gr_line
		(start 406.750266 -423.842942)
		(end 406.479248 -424.173142)
		(stroke
			(width 0.07112)
			(type default)
		)
		(layer "In11.Cu")
	)
	(gr_line
		(start 407.163524 -423.357548)
		(end 406.9715 -423.376344)
		(stroke
			(width 0.07112)
			(type default)
		)
		(layer "In11.Cu")
	)
	(gr_line
		(start 407.197306 -422.654476)
		(end 406.75179 -423.197782)
		(stroke
			(width 0.07112)
			(type default)
		)
		(layer "In11.Cu")
	)
	(gr_line
		(start 407.415746 -422.83507)
		(end 407.434542 -423.027348)
		(stroke
			(width 0.07112)
			(type default)
		)
		(layer "In11.Cu")
	)
	(gr_line
		(start 407.434542 -423.027348)
		(end 407.163524 -423.357548)
		(stroke
			(width 0.07112)
			(type default)
		)
		(layer "In11.Cu")
	)
	(gr_line
		(start 407.652982 -420.952168)
		(end 407.943812 -421.242998)
		(stroke
			(width 0.07112)
			(type default)
		)
		(layer "In11.Cu")
	)
	(gr_line
		(start 407.774394 -421.951404)
		(end 407.40076 -422.406572)
		(stroke
			(width 0.07112)
			(type default)
		)
		(layer "In11.Cu")
	)
	(gr_line
		(start 407.774394 -421.950642)
		(end 407.774394 -421.951404)
		(stroke
			(width 0.07112)
			(type default)
		)
		(layer "In11.Cu")
	)
	(gr_line
		(start 407.825702 -422.565068)
		(end 407.62047 -422.585388)
		(stroke
			(width 0.07112)
			(type default)
		)
		(layer "In11.Cu")
	)
	(gr_line
		(start 407.942542 -421.745664)
		(end 407.774394 -421.950642)
		(stroke
			(width 0.07112)
			(type default)
		)
		(layer "In11.Cu")
	)
	(gr_line
		(start 408.028902 -422.092628)
		(end 408.048714 -422.293542)
		(stroke
			(width 0.07112)
			(type default)
		)
		(layer "In11.Cu")
	)
	(gr_line
		(start 408.048714 -422.293542)
		(end 407.825702 -422.565068)
		(stroke
			(width 0.07112)
			(type default)
		)
		(layer "In11.Cu")
	)
	(gr_line
		(start 408.225752 -421.852852)
		(end 408.028902 -422.092628)
		(stroke
			(width 0.07112)
			(type default)
		)
		(layer "In11.Cu")
	)
	(gr_line
		(start 408.225752 -421.74414)
		(end 408.225752 -421.852852)
		(stroke
			(width 0.07112)
			(type default)
		)
		(layer "In11.Cu")
	)
	(gr_line
		(start 408.516582 -420.952168)
		(end 408.225752 -421.242998)
		(stroke
			(width 0.07112)
			(type default)
		)
		(layer "In11.Cu")
	)
	(gr_line
		(start 408.59202 -431.446686)
		(end 408.623008 -431.446686)
		(stroke
			(width 0.07112)
			(type default)
		)
		(layer "In11.Cu")
	)
	(gr_line
		(start 408.59329 -431.163476)
		(end 408.750008 -431.006758)
		(stroke
			(width 0.07112)
			(type default)
		)
		(layer "In11.Cu")
	)
	(gr_line
		(start 408.623008 -431.446686)
		(end 408.750008 -431.573686)
		(stroke
			(width 0.07112)
			(type default)
		)
		(layer "In11.Cu")
	)
	(gr_line
		(start 408.750008 -431.573686)
		(end 408.750008 -431.889916)
		(stroke
			(width 0.07112)
			(type default)
		)
		(layer "In11.Cu")
	)
	(gr_line
		(start 408.750008 -431.006758)
		(end 408.750008 -430.689766)
		(stroke
			(width 0.07112)
			(type default)
		)
		(layer "In11.Cu")
	)
	(gr_line
		(start 408.770074 -423.837354)
		(end 408.581352 -423.799762)
		(stroke
			(width 0.07112)
			(type default)
		)
		(layer "In11.Cu")
	)
	(gr_line
		(start 409.00604 -423.17543)
		(end 408.42311 -423.564812)
		(stroke
			(width 0.07112)
			(type default)
		)
		(layer "In11.Cu")
	)
	(gr_line
		(start 409.124912 -423.600118)
		(end 408.770074 -423.837354)
		(stroke
			(width 0.07112)
			(type default)
		)
		(layer "In11.Cu")
	)
	(gr_line
		(start 409.162504 -423.411396)
		(end 409.124912 -423.600118)
		(stroke
			(width 0.07112)
			(type default)
		)
		(layer "In11.Cu")
	)
	(gr_line
		(start 409.707588 -423.210736)
		(end 409.518866 -423.173144)
		(stroke
			(width 0.07112)
			(type default)
		)
		(layer "In11.Cu")
	)
	(gr_line
		(start 409.943808 -422.548812)
		(end 409.360624 -422.938448)
		(stroke
			(width 0.07112)
			(type default)
		)
		(layer "In11.Cu")
	)
	(gr_line
		(start 410.06268 -422.9735)
		(end 409.707588 -423.210736)
		(stroke
			(width 0.07112)
			(type default)
		)
		(layer "In11.Cu")
	)
	(gr_line
		(start 410.100272 -422.784778)
		(end 410.06268 -422.9735)
		(stroke
			(width 0.07112)
			(type default)
		)
		(layer "In11.Cu")
	)
	(gr_line
		(start 410.607764 -430.430686)
		(end 410.750004 -430.572926)
		(stroke
			(width 0.07112)
			(type default)
		)
		(layer "In11.Cu")
	)
	(gr_line
		(start 410.607764 -430.148746)
		(end 410.750004 -430.006506)
		(stroke
			(width 0.07112)
			(type default)
		)
		(layer "In11.Cu")
	)
	(gr_line
		(start 410.716222 -420.952168)
		(end 411.007052 -421.242998)
		(stroke
			(width 0.07112)
			(type default)
		)
		(layer "In11.Cu")
	)
	(gr_line
		(start 410.72435 -424.114722)
		(end 410.532072 -424.114722)
		(stroke
			(width 0.07112)
			(type default)
		)
		(layer "In11.Cu")
	)
	(gr_line
		(start 410.750004 -430.572926)
		(end 410.750004 -430.889918)
		(stroke
			(width 0.07112)
			(type default)
		)
		(layer "In11.Cu")
	)
	(gr_line
		(start 410.750004 -430.006506)
		(end 410.750004 -429.689768)
		(stroke
			(width 0.07112)
			(type default)
		)
		(layer "In11.Cu")
	)
	(gr_line
		(start 410.826966 -423.41927)
		(end 410.330904 -423.915332)
		(stroke
			(width 0.07112)
			(type default)
		)
		(layer "In11.Cu")
	)
	(gr_line
		(start 411.026356 -423.812716)
		(end 410.72435 -424.114722)
		(stroke
			(width 0.07112)
			(type default)
		)
		(layer "In11.Cu")
	)
	(gr_line
		(start 411.026356 -423.620438)
		(end 411.026356 -423.812716)
		(stroke
			(width 0.07112)
			(type default)
		)
		(layer "In11.Cu")
	)
	(gr_line
		(start 411.579822 -420.952168)
		(end 411.288992 -421.242998)
		(stroke
			(width 0.07112)
			(type default)
		)
		(layer "In11.Cu")
	)
	(gr_arc
		(start 412.055818 -424.08729)
		(mid 412.05429 -424.089319)
		(end 412.05277 -424.091354)
		(stroke
			(width 0.07112)
			(type default)
		)
		(layer "In11.Cu")
	)
	(gr_line
		(start 412.086298 -424.846496)
		(end 412.086044 -424.846242)
		(stroke
			(width 0.07112)
			(type default)
		)
		(layer "In11.Cu")
	)
	(gr_line
		(start 412.16453 -423.119296)
		(end 411.98673 -423.045636)
		(stroke
			(width 0.07112)
			(type default)
		)
		(layer "In11.Cu")
	)
	(gr_line
		(start 412.33471 -422.59504)
		(end 411.877256 -422.784524)
		(stroke
			(width 0.07112)
			(type default)
		)
		(layer "In11.Cu")
	)
	(gr_line
		(start 412.525464 -422.516046)
		(end 412.33471 -422.59504)
		(stroke
			(width 0.07112)
			(type default)
		)
		(layer "In11.Cu")
	)
	(gr_line
		(start 412.558992 -422.956228)
		(end 412.16453 -423.119296)
		(stroke
			(width 0.07112)
			(type default)
		)
		(layer "In11.Cu")
	)
	(gr_line
		(start 412.60776 -431.430938)
		(end 412.75 -431.573178)
		(stroke
			(width 0.07112)
			(type default)
		)
		(layer "In11.Cu")
	)
	(gr_line
		(start 412.60776 -431.148998)
		(end 412.75 -431.006758)
		(stroke
			(width 0.07112)
			(type default)
		)
		(layer "In11.Cu")
	)
	(gr_line
		(start 412.632398 -422.778174)
		(end 412.558992 -422.956228)
		(stroke
			(width 0.07112)
			(type default)
		)
		(layer "In11.Cu")
	)
	(gr_line
		(start 412.75 -431.573178)
		(end 412.75 -431.889916)
		(stroke
			(width 0.07112)
			(type default)
		)
		(layer "In11.Cu")
	)
	(gr_line
		(start 412.75 -431.006758)
		(end 412.75 -430.689766)
		(stroke
			(width 0.07112)
			(type default)
		)
		(layer "In11.Cu")
	)
	(gr_line
		(start 413.206692 -422.68775)
		(end 413.028892 -422.61409)
		(stroke
			(width 0.07112)
			(type default)
		)
		(layer "In11.Cu")
	)
	(gr_line
		(start 413.567626 -422.084754)
		(end 412.919672 -422.352978)
		(stroke
			(width 0.07112)
			(type default)
		)
		(layer "In11.Cu")
	)
	(gr_line
		(start 413.601154 -422.524682)
		(end 413.206692 -422.68775)
		(stroke
			(width 0.07112)
			(type default)
		)
		(layer "In11.Cu")
	)
	(gr_line
		(start 413.67456 -422.346882)
		(end 413.601154 -422.524682)
		(stroke
			(width 0.07112)
			(type default)
		)
		(layer "In11.Cu")
	)
	(gr_line
		(start 413.71647 -11.564874)
		(end 413.716216 -11.565128)
		(stroke
			(width 0.07112)
			(type default)
		)
		(layer "In11.Cu")
	)
	(gr_line
		(start 413.71647 -7.015988)
		(end 413.42564 -6.725158)
		(stroke
			(width 0.07112)
			(type default)
		)
		(layer "In11.Cu")
	)
	(gr_line
		(start 413.779462 -420.952168)
		(end 414.070292 -421.242998)
		(stroke
			(width 0.07112)
			(type default)
		)
		(layer "In11.Cu")
	)
	(gr_line
		(start 413.909764 -421.943022)
		(end 413.567626 -422.084754)
		(stroke
			(width 0.07112)
			(type default)
		)
		(layer "In11.Cu")
	)
	(gr_line
		(start 413.993076 -11.620246)
		(end 413.99841 -11.593068)
		(stroke
			(width 0.07112)
			(type default)
		)
		(layer "In11.Cu")
	)
	(gr_line
		(start 413.99841 -11.593068)
		(end 413.99841 -11.564874)
		(stroke
			(width 0.07112)
			(type default)
		)
		(layer "In11.Cu")
	)
	(gr_line
		(start 413.99841 -7.015988)
		(end 414.28924 -6.725158)
		(stroke
			(width 0.07112)
			(type default)
		)
		(layer "In11.Cu")
	)
	(gr_line
		(start 414.017714 -422.203626)
		(end 413.675322 -422.345104)
		(stroke
			(width 0.07112)
			(type default)
		)
		(layer "In11.Cu")
	)
	(gr_line
		(start 414.484312 -423.096182)
		(end 414.484312 -423.096436)
		(stroke
			(width 0.07112)
			(type default)
		)
		(layer "In11.Cu")
	)
	(gr_line
		(start 414.643062 -420.952168)
		(end 414.352232 -421.242998)
		(stroke
			(width 0.07112)
			(type default)
		)
		(layer "In11.Cu")
	)
	(gr_line
		(start 414.755076 -423.44467)
		(end 414.580832 -423.362374)
		(stroke
			(width 0.07112)
			(type default)
		)
		(layer "In11.Cu")
	)
	(gr_line
		(start 415.144712 -422.859708)
		(end 414.484312 -423.096182)
		(stroke
			(width 0.07112)
			(type default)
		)
		(layer "In11.Cu")
	)
	(gr_line
		(start 415.156904 -423.300906)
		(end 414.755076 -423.44467)
		(stroke
			(width 0.07112)
			(type default)
		)
		(layer "In11.Cu")
	)
	(gr_line
		(start 415.239454 -423.126662)
		(end 415.156904 -423.300906)
		(stroke
			(width 0.07112)
			(type default)
		)
		(layer "In11.Cu")
	)
	(gr_line
		(start 415.52114 -5.254244)
		(end 415.23031 -4.963414)
		(stroke
			(width 0.07112)
			(type default)
		)
		(layer "In11.Cu")
	)
	(gr_line
		(start 415.80308 -5.254244)
		(end 416.09391 -4.963414)
		(stroke
			(width 0.07112)
			(type default)
		)
		(layer "In11.Cu")
	)
	(gr_line
		(start 415.81705 -423.064432)
		(end 415.642806 -422.982136)
		(stroke
			(width 0.07112)
			(type default)
		)
		(layer "In11.Cu")
	)
	(gr_line
		(start 416.206686 -422.47947)
		(end 415.546286 -422.715944)
		(stroke
			(width 0.07112)
			(type default)
		)
		(layer "In11.Cu")
	)
	(gr_line
		(start 416.218878 -422.920668)
		(end 415.81705 -423.064432)
		(stroke
			(width 0.07112)
			(type default)
		)
		(layer "In11.Cu")
	)
	(gr_line
		(start 416.301428 -422.746424)
		(end 416.218878 -422.920668)
		(stroke
			(width 0.07112)
			(type default)
		)
		(layer "In11.Cu")
	)
	(gr_line
		(start 416.714178 -422.26865)
		(end 416.713924 -422.26865)
		(stroke
			(width 0.07112)
			(type default)
		)
		(layer "In11.Cu")
	)
	(gr_line
		(start 416.831018 -422.536366)
		(end 416.83051 -422.53662)
		(stroke
			(width 0.07112)
			(type default)
		)
		(layer "In11.Cu")
	)
	(gr_line
		(start 416.842702 -420.952168)
		(end 417.148772 -421.258238)
		(stroke
			(width 0.07112)
			(type default)
		)
		(layer "In11.Cu")
	)
	(gr_line
		(start 417.316412 -7.015988)
		(end 417.025582 -6.725158)
		(stroke
			(width 0.07112)
			(type default)
		)
		(layer "In11.Cu")
	)
	(gr_arc
		(start 417.431982 -421.738806)
		(mid 417.431982 -421.73906)
		(end 417.431982 -421.739314)
		(stroke
			(width 0.07112)
			(type default)
		)
		(layer "In11.Cu")
	)
	(gr_line
		(start 417.431982 -421.226488)
		(end 417.431982 -421.259508)
		(stroke
			(width 0.07112)
			(type default)
		)
		(layer "In11.Cu")
	)
	(gr_line
		(start 417.598352 -7.015988)
		(end 417.889182 -6.725158)
		(stroke
			(width 0.07112)
			(type default)
		)
		(layer "In11.Cu")
	)
	(gr_line
		(start 417.706302 -420.952168)
		(end 417.431982 -421.226488)
		(stroke
			(width 0.07112)
			(type default)
		)
		(layer "In11.Cu")
	)
	(gr_line
		(start 419.121082 -5.254244)
		(end 418.830252 -4.963414)
		(stroke
			(width 0.07112)
			(type default)
		)
		(layer "In11.Cu")
	)
	(gr_line
		(start 419.403022 -5.254244)
		(end 419.693852 -4.963414)
		(stroke
			(width 0.07112)
			(type default)
		)
		(layer "In11.Cu")
	)
	(gr_line
		(start 419.977316 -18.382742)
		(end 419.977062 -18.382742)
		(stroke
			(width 0.07112)
			(type default)
		)
		(layer "In11.Cu")
	)
	(gr_line
		(start 420.211758 -18.53946)
		(end 420.219378 -18.52803)
		(stroke
			(width 0.07112)
			(type default)
		)
		(layer "In11.Cu")
	)
	(gr_line
		(start 420.219378 -18.52803)
		(end 420.225982 -18.515838)
		(stroke
			(width 0.07112)
			(type default)
		)
		(layer "In11.Cu")
	)
	(gr_line
		(start 420.584376 -17.820386)
		(end 420.607236 -17.76476)
		(stroke
			(width 0.07112)
			(type default)
		)
		(layer "In11.Cu")
	)
	(gr_line
		(start 420.607236 -17.76476)
		(end 420.607236 -17.708626)
		(stroke
			(width 0.07112)
			(type default)
		)
		(layer "In11.Cu")
	)
	(gr_line
		(start 424.926506 -7.015988)
		(end 424.635676 -6.725158)
		(stroke
			(width 0.07112)
			(type default)
		)
		(layer "In11.Cu")
	)
	(gr_line
		(start 425.208446 -7.015988)
		(end 425.499276 -6.725158)
		(stroke
			(width 0.07112)
			(type default)
		)
		(layer "In11.Cu")
	)
	(gr_line
		(start 426.184568 -17.790414)
		(end 426.195236 -17.76476)
		(stroke
			(width 0.07112)
			(type default)
		)
		(layer "In11.Cu")
	)
	(gr_line
		(start 426.195236 -17.76476)
		(end 426.195236 -17.764252)
		(stroke
			(width 0.07112)
			(type default)
		)
		(layer "In11.Cu")
	)
	(gr_line
		(start 426.195236 -17.764252)
		(end 426.20057 -17.73809)
		(stroke
			(width 0.07112)
			(type default)
		)
		(layer "In11.Cu")
	)
	(gr_line
		(start 426.731176 -5.254244)
		(end 426.440346 -4.963414)
		(stroke
			(width 0.07112)
			(type default)
		)
		(layer "In11.Cu")
	)
	(gr_line
		(start 427.013116 -5.254244)
		(end 427.303946 -4.963414)
		(stroke
			(width 0.07112)
			(type default)
		)
		(layer "In11.Cu")
	)
	(gr_line
		(start 428.526448 -7.015988)
		(end 428.235618 -6.725158)
		(stroke
			(width 0.07112)
			(type default)
		)
		(layer "In11.Cu")
	)
	(gr_line
		(start 428.744634 -19.183096)
		(end 428.74438 -19.18335)
		(stroke
			(width 0.07112)
			(type default)
		)
		(layer "In11.Cu")
	)
	(gr_line
		(start 428.808388 -7.015988)
		(end 429.099218 -6.725158)
		(stroke
			(width 0.07112)
			(type default)
		)
		(layer "In11.Cu")
	)
	(gr_line
		(start 428.994824 -18.916396)
		(end 428.984156 -18.890742)
		(stroke
			(width 0.07112)
			(type default)
		)
		(layer "In11.Cu")
	)
	(gr_line
		(start 429.000412 -18.944082)
		(end 428.994824 -18.916396)
		(stroke
			(width 0.07112)
			(type default)
		)
		(layer "In11.Cu")
	)
	(gr_line
		(start 429.012096 -19.272758)
		(end 429.026574 -19.229324)
		(stroke
			(width 0.07112)
			(type default)
		)
		(layer "In11.Cu")
	)
	(gr_line
		(start 429.026574 -19.229324)
		(end 429.026574 -19.183096)
		(stroke
			(width 0.07112)
			(type default)
		)
		(layer "In11.Cu")
	)
	(gr_line
		(start 430.331118 -5.254244)
		(end 430.040288 -4.963414)
		(stroke
			(width 0.07112)
			(type default)
		)
		(layer "In11.Cu")
	)
	(gr_line
		(start 430.613058 -5.254244)
		(end 430.903888 -4.963414)
		(stroke
			(width 0.07112)
			(type default)
		)
		(layer "In11.Cu")
	)
	(gr_line
		(start 430.837086 -18.881852)
		(end 430.836832 -18.881852)
		(stroke
			(width 0.07112)
			(type default)
		)
		(layer "In11.Cu")
	)
	(gr_line
		(start 430.839372 -18.876264)
		(end 430.84369 -18.866104)
		(stroke
			(width 0.07112)
			(type default)
		)
		(layer "In11.Cu")
	)
	(gr_line
		(start 430.84369 -18.866104)
		(end 430.858676 -18.843498)
		(stroke
			(width 0.07112)
			(type default)
		)
		(layer "In11.Cu")
	)
	(gr_line
		(start 431.070258 -19.040348)
		(end 431.085498 -19.017996)
		(stroke
			(width 0.07112)
			(type default)
		)
		(layer "In11.Cu")
	)
	(gr_line
		(start 431.085498 -19.017996)
		(end 431.08626 -19.01698)
		(stroke
			(width 0.07112)
			(type default)
		)
		(layer "In11.Cu")
	)
	(gr_line
		(start 431.08626 -19.01698)
		(end 431.09134 -19.005296)
		(stroke
			(width 0.07112)
			(type default)
		)
		(layer "In11.Cu")
	)
	(gr_line
		(start 431.794158 -17.820894)
		(end 431.817272 -17.765014)
		(stroke
			(width 0.07112)
			(type default)
		)
		(layer "In11.Cu")
	)
	(gr_line
		(start 431.817272 -17.765014)
		(end 431.817272 -17.70888)
		(stroke
			(width 0.07112)
			(type default)
		)
		(layer "In11.Cu")
	)
	(gr_line
		(start 439.307478 8.258048)
		(end 439.016648 8.548878)
		(stroke
			(width 0.07112)
			(type default)
		)
		(layer "In11.Cu")
	)
	(gr_line
		(start 439.307478 9.121648)
		(end 439.016648 8.830818)
		(stroke
			(width 0.07112)
			(type default)
		)
		(layer "In11.Cu")
	)
	(gr_line
		(start 0 -77.671676)
		(end 0 -13.780008)
		(stroke
			(width 0.05)
			(type default)
		)
		(layer "Edge.Cuts")
	)
	(gr_arc
		(start 0 -77.671676)
		(mid 0.152237 -78.436936)
		(end 0.585724 -79.085694)
		(stroke
			(width 0.05)
			(type default)
		)
		(layer "Edge.Cuts")
	)
	(gr_line
		(start 1.414272 -79.914242)
		(end 0.585724 -79.085694)
		(stroke
			(width 0.05)
			(type default)
		)
		(layer "Edge.Cuts")
	)
	(gr_line
		(start 1.999996 -403.371558)
		(end 1.999996 -81.328514)
		(stroke
			(width 0.05)
			(type default)
		)
		(layer "Edge.Cuts")
	)
	(gr_arc
		(start 1.999996 -403.371558)
		(mid 2.152159 -404.136965)
		(end 2.58572 -404.78583)
		(stroke
			(width 0.05)
			(type default)
		)
		(layer "Edge.Cuts")
	)
	(gr_arc
		(start 1.999996 -81.328514)
		(mid 1.847755 -80.563149)
		(end 1.414272 -79.914242)
		(stroke
			(width 0.05)
			(type default)
		)
		(layer "Edge.Cuts")
	)
	(gr_arc
		(start 1.999996 -11.780012)
		(mid 0.585785 -12.365797)
		(end 0 -13.780008)
		(stroke
			(width 0.05)
			(type default)
		)
		(layer "Edge.Cuts")
	)
	(gr_line
		(start 1.999996 -11.780012)
		(end 11.102086 -11.780012)
		(stroke
			(width 0.05)
			(type default)
		)
		(layer "Edge.Cuts")
	)
	(gr_line
		(start 5.914136 -408.114246)
		(end 2.58572 -404.78583)
		(stroke
			(width 0.05)
			(type default)
		)
		(layer "Edge.Cuts")
	)
	(gr_line
		(start 6.500114 -439.989976)
		(end 6.500114 -409.528518)
		(stroke
			(width 0.05)
			(type default)
		)
		(layer "Edge.Cuts")
	)
	(gr_arc
		(start 6.500114 -439.989976)
		(mid 7.085891 -441.404199)
		(end 8.50011 -441.989972)
		(stroke
			(width 0.05)
			(type default)
		)
		(layer "Edge.Cuts")
	)
	(gr_arc
		(start 6.500114 -409.528518)
		(mid 6.347771 -408.763109)
		(end 5.914136 -408.114246)
		(stroke
			(width 0.05)
			(type default)
		)
		(layer "Edge.Cuts")
	)
	(gr_arc
		(start 11.102086 -11.780012)
		(mid 12.516297 -11.194227)
		(end 13.102082 -9.780016)
		(stroke
			(width 0.05)
			(type default)
		)
		(layer "Edge.Cuts")
	)
	(gr_line
		(start 13.102082 -9.780016)
		(end 13.102082 -0.500126)
		(stroke
			(width 0.05)
			(type default)
		)
		(layer "Edge.Cuts")
	)
	(gr_arc
		(start 13.601954 0)
		(mid 13.24848 -0.146572)
		(end 13.102082 -0.500126)
		(stroke
			(width 0.05)
			(type default)
		)
		(layer "Edge.Cuts")
	)
	(gr_line
		(start 13.601954 0)
		(end 81.202022 0)
		(stroke
			(width 0.05)
			(type default)
		)
		(layer "Edge.Cuts")
	)
	(gr_arc
		(start 81.701894 -9.780016)
		(mid 82.287679 -11.194227)
		(end 83.70189 -11.780012)
		(stroke
			(width 0.05)
			(type default)
		)
		(layer "Edge.Cuts")
	)
	(gr_arc
		(start 81.701894 -0.500126)
		(mid 81.555625 -0.146451)
		(end 81.202022 0)
		(stroke
			(width 0.05)
			(type default)
		)
		(layer "Edge.Cuts")
	)
	(gr_line
		(start 81.701894 -0.500126)
		(end 81.701894 -9.780016)
		(stroke
			(width 0.05)
			(type default)
		)
		(layer "Edge.Cuts")
	)
	(gr_line
		(start 83.70189 -11.780012)
		(end 124.102114 -11.780012)
		(stroke
			(width 0.05)
			(type default)
		)
		(layer "Edge.Cuts")
	)
	(gr_arc
		(start 124.102114 -11.780012)
		(mid 125.516325 -11.194227)
		(end 126.10211 -9.780016)
		(stroke
			(width 0.05)
			(type default)
		)
		(layer "Edge.Cuts")
	)
	(gr_line
		(start 126.10211 -9.780016)
		(end 126.10211 -5.780024)
		(stroke
			(width 0.05)
			(type default)
		)
		(layer "Edge.Cuts")
	)
	(gr_arc
		(start 126.601982 -5.279898)
		(mid 126.248489 -5.42646)
		(end 126.10211 -5.780024)
		(stroke
			(width 0.05)
			(type default)
		)
		(layer "Edge.Cuts")
	)
	(gr_line
		(start 126.601982 -5.279898)
		(end 194.20205 -5.279898)
		(stroke
			(width 0.05)
			(type default)
		)
		(layer "Edge.Cuts")
	)
	(gr_line
		(start 194.505072 -441.989972)
		(end 8.50011 -441.989972)
		(stroke
			(width 0.05)
			(type default)
		)
		(layer "Edge.Cuts")
	)
	(gr_arc
		(start 194.505072 -441.989972)
		(mid 194.858553 -441.843573)
		(end 195.004944 -441.4901)
		(stroke
			(width 0.05)
			(type default)
		)
		(layer "Edge.Cuts")
	)
	(gr_arc
		(start 194.701922 -9.780016)
		(mid 195.287707 -11.194227)
		(end 196.701918 -11.780012)
		(stroke
			(width 0.05)
			(type default)
		)
		(layer "Edge.Cuts")
	)
	(gr_arc
		(start 194.701922 -5.780024)
		(mid 194.555654 -5.42634)
		(end 194.20205 -5.279898)
		(stroke
			(width 0.05)
			(type default)
		)
		(layer "Edge.Cuts")
	)
	(gr_line
		(start 194.701922 -5.780024)
		(end 194.701922 -9.780016)
		(stroke
			(width 0.05)
			(type default)
		)
		(layer "Edge.Cuts")
	)
	(gr_line
		(start 195.004944 -441.17006)
		(end 195.004944 -441.4901)
		(stroke
			(width 0.05)
			(type default)
		)
		(layer "Edge.Cuts")
	)
	(gr_arc
		(start 195.50507 -440.669934)
		(mid 195.151428 -440.816418)
		(end 195.004944 -441.17006)
		(stroke
			(width 0.05)
			(type default)
		)
		(layer "Edge.Cuts")
	)
	(gr_line
		(start 196.701918 -11.780012)
		(end 221.30004 -11.780012)
		(stroke
			(width 0.05)
			(type default)
		)
		(layer "Edge.Cuts")
	)
	(gr_arc
		(start 223.300036 -34.120074)
		(mid 223.885821 -35.534285)
		(end 225.300032 -36.12007)
		(stroke
			(width 0.05)
			(type default)
		)
		(layer "Edge.Cuts")
	)
	(gr_arc
		(start 223.300036 -13.780008)
		(mid 222.714256 -12.365778)
		(end 221.30004 -11.780012)
		(stroke
			(width 0.05)
			(type default)
		)
		(layer "Edge.Cuts")
	)
	(gr_line
		(start 223.300036 -13.780008)
		(end 223.300036 -34.120074)
		(stroke
			(width 0.05)
			(type default)
		)
		(layer "Edge.Cuts")
	)
	(gr_line
		(start 225.300032 -36.12007)
		(end 256.800096 -36.12007)
		(stroke
			(width 0.05)
			(type default)
		)
		(layer "Edge.Cuts")
	)
	(gr_arc
		(start 256.800096 -36.12007)
		(mid 258.214307 -35.534285)
		(end 258.800092 -34.120074)
		(stroke
			(width 0.05)
			(type default)
		)
		(layer "Edge.Cuts")
	)
	(gr_line
		(start 258.800092 -34.120074)
		(end 258.800092 -13.780008)
		(stroke
			(width 0.05)
			(type default)
		)
		(layer "Edge.Cuts")
	)
	(gr_arc
		(start 260.800088 -11.780012)
		(mid 259.385888 -12.365802)
		(end 258.800092 -13.780008)
		(stroke
			(width 0.05)
			(type default)
		)
		(layer "Edge.Cuts")
	)
	(gr_line
		(start 260.800088 -11.780012)
		(end 385.601972 -11.780012)
		(stroke
			(width 0.05)
			(type default)
		)
		(layer "Edge.Cuts")
	)
	(gr_line
		(start 276.314916 -440.669934)
		(end 195.50507 -440.669934)
		(stroke
			(width 0.05)
			(type default)
		)
		(layer "Edge.Cuts")
	)
	(gr_line
		(start 276.815042 -441.4901)
		(end 276.815042 -441.17006)
		(stroke
			(width 0.05)
			(type default)
		)
		(layer "Edge.Cuts")
	)
	(gr_arc
		(start 276.815042 -441.4901)
		(mid 276.961452 -441.843558)
		(end 277.314914 -441.989972)
		(stroke
			(width 0.05)
			(type default)
		)
		(layer "Edge.Cuts")
	)
	(gr_arc
		(start 276.815042 -441.17006)
		(mid 276.668558 -440.816418)
		(end 276.314916 -440.669934)
		(stroke
			(width 0.05)
			(type default)
		)
		(layer "Edge.Cuts")
	)
	(gr_arc
		(start 385.601972 -11.780012)
		(mid 387.016183 -11.194227)
		(end 387.601968 -9.780016)
		(stroke
			(width 0.05)
			(type default)
		)
		(layer "Edge.Cuts")
	)
	(gr_line
		(start 387.601968 -9.780016)
		(end 387.601968 -0.500126)
		(stroke
			(width 0.05)
			(type default)
		)
		(layer "Edge.Cuts")
	)
	(gr_arc
		(start 388.102094 0)
		(mid 387.748465 -0.146487)
		(end 387.601968 -0.500126)
		(stroke
			(width 0.05)
			(type default)
		)
		(layer "Edge.Cuts")
	)
	(gr_line
		(start 388.102094 0)
		(end 455.701908 0)
		(stroke
			(width 0.05)
			(type default)
		)
		(layer "Edge.Cuts")
	)
	(gr_arc
		(start 456.202034 -9.780016)
		(mid 456.787819 -11.194227)
		(end 458.20203 -11.780012)
		(stroke
			(width 0.05)
			(type default)
		)
		(layer "Edge.Cuts")
	)
	(gr_arc
		(start 456.202034 -0.500126)
		(mid 456.05556 -0.146464)
		(end 455.701908 0)
		(stroke
			(width 0.05)
			(type default)
		)
		(layer "Edge.Cuts")
	)
	(gr_line
		(start 456.202034 -0.500126)
		(end 456.202034 -9.780016)
		(stroke
			(width 0.05)
			(type default)
		)
		(layer "Edge.Cuts")
	)
	(gr_line
		(start 458.20203 -11.780012)
		(end 469.799924 -11.780012)
		(stroke
			(width 0.05)
			(type default)
		)
		(layer "Edge.Cuts")
	)
	(gr_line
		(start 463.300064 -441.989972)
		(end 277.314914 -441.989972)
		(stroke
			(width 0.05)
			(type default)
		)
		(layer "Edge.Cuts")
	)
	(gr_arc
		(start 463.300064 -441.989972)
		(mid 464.71429 -441.404198)
		(end 465.30006 -439.989976)
		(stroke
			(width 0.05)
			(type default)
		)
		(layer "Edge.Cuts")
	)
	(gr_line
		(start 465.30006 -409.528518)
		(end 465.30006 -439.989976)
		(stroke
			(width 0.05)
			(type default)
		)
		(layer "Edge.Cuts")
	)
	(gr_arc
		(start 465.885784 -408.114246)
		(mid 465.452221 -408.76312)
		(end 465.30006 -409.528518)
		(stroke
			(width 0.05)
			(type default)
		)
		(layer "Edge.Cuts")
	)
	(gr_line
		(start 467.71433 -406.2857)
		(end 465.885784 -408.114246)
		(stroke
			(width 0.05)
			(type default)
		)
		(layer "Edge.Cuts")
	)
	(gr_arc
		(start 467.71433 -406.2857)
		(mid 468.147828 -405.636947)
		(end 468.300054 -404.871682)
		(stroke
			(width 0.05)
			(type default)
		)
		(layer "Edge.Cuts")
	)
	(gr_line
		(start 468.300054 -82.828384)
		(end 468.300054 -404.871682)
		(stroke
			(width 0.05)
			(type default)
		)
		(layer "Edge.Cuts")
	)
	(gr_arc
		(start 468.885778 -81.414112)
		(mid 468.452215 -82.062986)
		(end 468.300054 -82.828384)
		(stroke
			(width 0.05)
			(type default)
		)
		(layer "Edge.Cuts")
	)
	(gr_line
		(start 471.214196 -79.085694)
		(end 468.885778 -81.414112)
		(stroke
			(width 0.05)
			(type default)
		)
		(layer "Edge.Cuts")
	)
	(gr_arc
		(start 471.214196 -79.085694)
		(mid 471.6477 -78.436942)
		(end 471.79992 -77.671676)
		(stroke
			(width 0.05)
			(type default)
		)
		(layer "Edge.Cuts")
	)
	(gr_arc
		(start 471.79992 -13.780008)
		(mid 471.214139 -12.365784)
		(end 469.799924 -11.780012)
		(stroke
			(width 0.05)
			(type default)
		)
		(layer "Edge.Cuts")
	)
	(gr_line
		(start 471.79992 -13.780008)
		(end 471.79992 -77.671676)
		(stroke
			(width 0.05)
			(type default)
		)
		(layer "Edge.Cuts")
	)
	(gr_line
		(start 0 -77.671676)
		(end 0 -13.780008)
		(stroke
			(width 1.016)
			(type default)
		)
		(layer "In12.Cu")
	)
	(gr_arc
		(start 0 -77.671676)
		(mid 0.152237 -78.436936)
		(end 0.585724 -79.085694)
		(stroke
			(width 1.016)
			(type default)
		)
		(layer "In12.Cu")
	)
	(gr_poly
		(pts
			(arc
				(start 279.248108 -392.23696)
				(mid 279.284029 -392.222081)
				(end 279.298908 -392.18616)
			)
			(arc
				(start 279.298908 -383.93116)
				(mid 279.284029 -383.895239)
				(end 279.248108 -383.88036)
			)
			(arc
				(start 275.026374 -383.88036)
				(mid 275.006851 -383.884261)
				(end 274.990306 -383.895346)
			)
			(arc
				(start 274.766278 -384.119374)
				(mid 274.755167 -384.135908)
				(end 274.751292 -384.155442)
			)
			(arc
				(start 274.751292 -392.107928)
				(mid 274.755193 -392.127451)
				(end 274.766278 -392.143996)
			)
			(arc
				(start 274.844256 -392.221974)
				(mid 274.86079 -392.233085)
				(end 274.880324 -392.23696)
			)
		)
		(stroke
			(width 0)
			(type solid)
		)
		(fill yes)
		(layer "In12.Cu")
		(net "P12V_MAIN_R_0")
	)
	(gr_poly
		(pts
			(arc
				(start 98.184208 -273.276314)
				(mid 97.777808 -273.276314)
				(end 98.184208 -273.276314)
			)
		)
		(stroke
			(width 0)
			(type solid)
		)
		(fill yes)
		(layer "In12.Cu")
		(net "P5E_CPU1_P0_RX_DN<1>")
	)
	(gr_poly
		(pts
			(arc
				(start 98.184208 -271.656302)
				(mid 97.777808 -271.656302)
				(end 98.184208 -271.656302)
			)
		)
		(stroke
			(width 0)
			(type solid)
		)
		(fill yes)
		(layer "In12.Cu")
		(net "P5E_CPU1_P0_RX_DN<0>")
	)
	(gr_poly
		(pts
			(arc
				(start 98.184208 -270.03629)
				(mid 97.777808 -270.03629)
				(end 98.184208 -270.03629)
			)
		)
		(stroke
			(width 0)
			(type solid)
		)
		(fill yes)
		(layer "In12.Cu")
		(net "P5E_CPU1_P0_RX_DN<2>")
	)
	(gr_poly
		(pts
			(arc
				(start 99.124262 -273.276314)
				(mid 98.717862 -273.276314)
				(end 99.124262 -273.276314)
			)
		)
		(stroke
			(width 0)
			(type solid)
		)
		(fill yes)
		(layer "In12.Cu")
		(net "P5E_CPU1_P0_RX_DP<1>")
	)
	(gr_poly
		(pts
			(arc
				(start 99.124262 -271.656302)
				(mid 98.717862 -271.656302)
				(end 99.124262 -271.656302)
			)
		)
		(stroke
			(width 0)
			(type solid)
		)
		(fill yes)
		(layer "In12.Cu")
		(net "P5E_CPU1_P0_RX_DP<0>")
	)
	(gr_poly
		(pts
			(arc
				(start 99.124262 -270.03629)
				(mid 98.717862 -270.03629)
				(end 99.124262 -270.03629)
			)
		)
		(stroke
			(width 0)
			(type solid)
		)
		(fill yes)
		(layer "In12.Cu")
		(net "P5E_CPU1_P0_RX_DP<2>")
	)
	(gr_poly
		(pts
			(arc
				(start 101.004116 -273.276314)
				(mid 100.597716 -273.276314)
				(end 101.004116 -273.276314)
			)
		)
		(stroke
			(width 0)
			(type solid)
		)
		(fill yes)
		(layer "In12.Cu")
		(net "P5E_CPU1_P0_RX_DN<4>")
	)
	(gr_poly
		(pts
			(arc
				(start 101.004116 -271.656302)
				(mid 100.597716 -271.656302)
				(end 101.004116 -271.656302)
			)
		)
		(stroke
			(width 0)
			(type solid)
		)
		(fill yes)
		(layer "In12.Cu")
		(net "P5E_CPU1_P0_RX_DN<3>")
	)
	(gr_poly
		(pts
			(arc
				(start 101.004116 -270.03629)
				(mid 100.597716 -270.03629)
				(end 101.004116 -270.03629)
			)
		)
		(stroke
			(width 0)
			(type solid)
		)
		(fill yes)
		(layer "In12.Cu")
		(net "P5E_CPU1_P0_RX_DN<5>")
	)
	(gr_poly
		(pts
			(arc
				(start 101.94417 -273.276314)
				(mid 101.53777 -273.276314)
				(end 101.94417 -273.276314)
			)
		)
		(stroke
			(width 0)
			(type solid)
		)
		(fill yes)
		(layer "In12.Cu")
		(net "P5E_CPU1_P0_RX_DP<4>")
	)
	(gr_poly
		(pts
			(arc
				(start 101.94417 -271.656302)
				(mid 101.53777 -271.656302)
				(end 101.94417 -271.656302)
			)
		)
		(stroke
			(width 0)
			(type solid)
		)
		(fill yes)
		(layer "In12.Cu")
		(net "P5E_CPU1_P0_RX_DP<3>")
	)
	(gr_poly
		(pts
			(arc
				(start 101.94417 -270.03629)
				(mid 101.53777 -270.03629)
				(end 101.94417 -270.03629)
			)
		)
		(stroke
			(width 0)
			(type solid)
		)
		(fill yes)
		(layer "In12.Cu")
		(net "P5E_CPU1_P0_RX_DP<5>")
	)
	(gr_poly
		(pts
			(arc
				(start 103.824278 -273.276314)
				(mid 103.417878 -273.276314)
				(end 103.824278 -273.276314)
			)
		)
		(stroke
			(width 0)
			(type solid)
		)
		(fill yes)
		(layer "In12.Cu")
		(net "P5E_CPU1_P0_RX_DN<7>")
	)
	(gr_poly
		(pts
			(arc
				(start 103.824278 -271.656302)
				(mid 103.417878 -271.656302)
				(end 103.824278 -271.656302)
			)
		)
		(stroke
			(width 0)
			(type solid)
		)
		(fill yes)
		(layer "In12.Cu")
		(net "P5E_CPU1_P0_RX_DN<6>")
	)
	(gr_poly
		(pts
			(arc
				(start 103.824278 -270.03629)
				(mid 103.417878 -270.03629)
				(end 103.824278 -270.03629)
			)
		)
		(stroke
			(width 0)
			(type solid)
		)
		(fill yes)
		(layer "In12.Cu")
		(net "P5E_CPU1_P0_RX_DN<8>")
	)
	(gr_poly
		(pts
			(arc
				(start 104.764332 -273.276314)
				(mid 104.357932 -273.276314)
				(end 104.764332 -273.276314)
			)
		)
		(stroke
			(width 0)
			(type solid)
		)
		(fill yes)
		(layer "In12.Cu")
		(net "P5E_CPU1_P0_RX_DP<7>")
	)
	(gr_poly
		(pts
			(arc
				(start 104.764332 -271.656302)
				(mid 104.357932 -271.656302)
				(end 104.764332 -271.656302)
			)
		)
		(stroke
			(width 0)
			(type solid)
		)
		(fill yes)
		(layer "In12.Cu")
		(net "P5E_CPU1_P0_RX_DP<6>")
	)
	(gr_poly
		(pts
			(arc
				(start 104.764332 -270.03629)
				(mid 104.357932 -270.03629)
				(end 104.764332 -270.03629)
			)
		)
		(stroke
			(width 0)
			(type solid)
		)
		(fill yes)
		(layer "In12.Cu")
		(net "P5E_CPU1_P0_RX_DP<8>")
	)
	(gr_poly
		(pts
			(arc
				(start 106.644186 -273.276314)
				(mid 106.237786 -273.276314)
				(end 106.644186 -273.276314)
			)
		)
		(stroke
			(width 0)
			(type solid)
		)
		(fill yes)
		(layer "In12.Cu")
		(net "P5E_CPU1_P0_RX_DN<10>")
	)
	(gr_poly
		(pts
			(arc
				(start 106.644186 -271.656302)
				(mid 106.237786 -271.656302)
				(end 106.644186 -271.656302)
			)
		)
		(stroke
			(width 0)
			(type solid)
		)
		(fill yes)
		(layer "In12.Cu")
		(net "P5E_CPU1_P0_RX_DN<9>")
	)
	(gr_poly
		(pts
			(arc
				(start 106.644186 -270.03629)
				(mid 106.237786 -270.03629)
				(end 106.644186 -270.03629)
			)
		)
		(stroke
			(width 0)
			(type solid)
		)
		(fill yes)
		(layer "In12.Cu")
		(net "P5E_CPU1_P0_RX_DN<11>")
	)
	(gr_poly
		(pts
			(arc
				(start 107.58424 -273.276314)
				(mid 107.17784 -273.276314)
				(end 107.58424 -273.276314)
			)
		)
		(stroke
			(width 0)
			(type solid)
		)
		(fill yes)
		(layer "In12.Cu")
		(net "P5E_CPU1_P0_RX_DP<10>")
	)
	(gr_poly
		(pts
			(arc
				(start 107.58424 -271.656302)
				(mid 107.17784 -271.656302)
				(end 107.58424 -271.656302)
			)
		)
		(stroke
			(width 0)
			(type solid)
		)
		(fill yes)
		(layer "In12.Cu")
		(net "P5E_CPU1_P0_RX_DP<9>")
	)
	(gr_poly
		(pts
			(arc
				(start 107.58424 -270.03629)
				(mid 107.17784 -270.03629)
				(end 107.58424 -270.03629)
			)
		)
		(stroke
			(width 0)
			(type solid)
		)
		(fill yes)
		(layer "In12.Cu")
		(net "P5E_CPU1_P0_RX_DP<11>")
	)
	(gr_poly
		(pts
			(arc
				(start 108.994194 -274.08632)
				(mid 108.587794 -274.08632)
				(end 108.994194 -274.08632)
			)
		)
		(stroke
			(width 0)
			(type solid)
		)
		(fill yes)
		(layer "In12.Cu")
		(net "P5E_CPU1_P0_RX_DN<13>")
	)
	(gr_poly
		(pts
			(arc
				(start 108.994194 -272.466308)
				(mid 108.587794 -272.466308)
				(end 108.994194 -272.466308)
			)
		)
		(stroke
			(width 0)
			(type solid)
		)
		(fill yes)
		(layer "In12.Cu")
		(net "P5E_CPU1_P0_RX_DN<12>")
	)
	(gr_poly
		(pts
			(arc
				(start 108.994194 -270.846296)
				(mid 108.587794 -270.846296)
				(end 108.994194 -270.846296)
			)
		)
		(stroke
			(width 0)
			(type solid)
		)
		(fill yes)
		(layer "In12.Cu")
		(net "P5E_CPU1_P0_RX_DN<14>")
	)
	(gr_poly
		(pts
			(arc
				(start 108.994194 -269.226284)
				(mid 108.587794 -269.226284)
				(end 108.994194 -269.226284)
			)
		)
		(stroke
			(width 0)
			(type solid)
		)
		(fill yes)
		(layer "In12.Cu")
		(net "P5E_CPU1_P0_RX_DN<15>")
	)
	(gr_poly
		(pts
			(arc
				(start 109.934248 -274.08632)
				(mid 109.527848 -274.08632)
				(end 109.934248 -274.08632)
			)
		)
		(stroke
			(width 0)
			(type solid)
		)
		(fill yes)
		(layer "In12.Cu")
		(net "P5E_CPU1_P0_RX_DP<13>")
	)
	(gr_poly
		(pts
			(arc
				(start 109.934248 -272.466308)
				(mid 109.527848 -272.466308)
				(end 109.934248 -272.466308)
			)
		)
		(stroke
			(width 0)
			(type solid)
		)
		(fill yes)
		(layer "In12.Cu")
		(net "P5E_CPU1_P0_RX_DP<12>")
	)
	(gr_poly
		(pts
			(arc
				(start 109.934248 -270.846296)
				(mid 109.527848 -270.846296)
				(end 109.934248 -270.846296)
			)
		)
		(stroke
			(width 0)
			(type solid)
		)
		(fill yes)
		(layer "In12.Cu")
		(net "P5E_CPU1_P0_RX_DP<14>")
	)
	(gr_poly
		(pts
			(arc
				(start 109.934248 -269.226284)
				(mid 109.527848 -269.226284)
				(end 109.934248 -269.226284)
			)
		)
		(stroke
			(width 0)
			(type solid)
		)
		(fill yes)
		(layer "In12.Cu")
		(net "P5E_CPU1_P0_RX_DP<15>")
	)
	(gr_poly
		(pts
			(arc
				(start 114.627914 -274.08632)
				(mid 114.221514 -274.08632)
				(end 114.627914 -274.08632)
			)
		)
		(stroke
			(width 0)
			(type solid)
		)
		(fill yes)
		(layer "In12.Cu")
		(net "P5E_CPU1_P2_TX_DP<2>")
	)
	(gr_poly
		(pts
			(arc
				(start 114.627914 -272.466308)
				(mid 114.221514 -272.466308)
				(end 114.627914 -272.466308)
			)
		)
		(stroke
			(width 0)
			(type solid)
		)
		(fill yes)
		(layer "In12.Cu")
		(net "P5E_CPU1_P2_TX_DP<3>")
	)
	(gr_poly
		(pts
			(arc
				(start 114.627914 -270.846296)
				(mid 114.221514 -270.846296)
				(end 114.627914 -270.846296)
			)
		)
		(stroke
			(width 0)
			(type solid)
		)
		(fill yes)
		(layer "In12.Cu")
		(net "P5E_CPU1_P2_TX_DP<1>")
	)
	(gr_poly
		(pts
			(arc
				(start 114.627914 -269.226284)
				(mid 114.221514 -269.226284)
				(end 114.627914 -269.226284)
			)
		)
		(stroke
			(width 0)
			(type solid)
		)
		(fill yes)
		(layer "In12.Cu")
		(net "P5E_CPU1_P2_TX_DP<0>")
	)
	(gr_poly
		(pts
			(arc
				(start 115.567968 -274.08632)
				(mid 115.161568 -274.08632)
				(end 115.567968 -274.08632)
			)
		)
		(stroke
			(width 0)
			(type solid)
		)
		(fill yes)
		(layer "In12.Cu")
		(net "P5E_CPU1_P2_TX_DN<2>")
	)
	(gr_poly
		(pts
			(arc
				(start 115.567968 -272.466308)
				(mid 115.161568 -272.466308)
				(end 115.567968 -272.466308)
			)
		)
		(stroke
			(width 0)
			(type solid)
		)
		(fill yes)
		(layer "In12.Cu")
		(net "P5E_CPU1_P2_TX_DN<3>")
	)
	(gr_poly
		(pts
			(arc
				(start 115.567968 -270.846296)
				(mid 115.161568 -270.846296)
				(end 115.567968 -270.846296)
			)
		)
		(stroke
			(width 0)
			(type solid)
		)
		(fill yes)
		(layer "In12.Cu")
		(net "P5E_CPU1_P2_TX_DN<1>")
	)
	(gr_poly
		(pts
			(arc
				(start 115.567968 -269.226284)
				(mid 115.161568 -269.226284)
				(end 115.567968 -269.226284)
			)
		)
		(stroke
			(width 0)
			(type solid)
		)
		(fill yes)
		(layer "In12.Cu")
		(net "P5E_CPU1_P2_TX_DN<0>")
	)
	(gr_poly
		(pts
			(arc
				(start 116.977922 -273.276314)
				(mid 116.571522 -273.276314)
				(end 116.977922 -273.276314)
			)
		)
		(stroke
			(width 0)
			(type solid)
		)
		(fill yes)
		(layer "In12.Cu")
		(net "P5E_CPU1_P2_TX_DP<5>")
	)
	(gr_poly
		(pts
			(arc
				(start 116.977922 -271.656302)
				(mid 116.571522 -271.656302)
				(end 116.977922 -271.656302)
			)
		)
		(stroke
			(width 0)
			(type solid)
		)
		(fill yes)
		(layer "In12.Cu")
		(net "P5E_CPU1_P2_TX_DP<6>")
	)
	(gr_poly
		(pts
			(arc
				(start 116.977922 -270.03629)
				(mid 116.571522 -270.03629)
				(end 116.977922 -270.03629)
			)
		)
		(stroke
			(width 0)
			(type solid)
		)
		(fill yes)
		(layer "In12.Cu")
		(net "P5E_CPU1_P2_TX_DP<4>")
	)
	(gr_poly
		(pts
			(arc
				(start 117.917976 -273.276314)
				(mid 117.511576 -273.276314)
				(end 117.917976 -273.276314)
			)
		)
		(stroke
			(width 0)
			(type solid)
		)
		(fill yes)
		(layer "In12.Cu")
		(net "P5E_CPU1_P2_TX_DN<5>")
	)
	(gr_poly
		(pts
			(arc
				(start 117.917976 -271.656302)
				(mid 117.511576 -271.656302)
				(end 117.917976 -271.656302)
			)
		)
		(stroke
			(width 0)
			(type solid)
		)
		(fill yes)
		(layer "In12.Cu")
		(net "P5E_CPU1_P2_TX_DN<6>")
	)
	(gr_poly
		(pts
			(arc
				(start 117.917976 -270.03629)
				(mid 117.511576 -270.03629)
				(end 117.917976 -270.03629)
			)
		)
		(stroke
			(width 0)
			(type solid)
		)
		(fill yes)
		(layer "In12.Cu")
		(net "P5E_CPU1_P2_TX_DN<4>")
	)
	(gr_poly
		(pts
			(arc
				(start 119.79783 -273.276314)
				(mid 119.39143 -273.276314)
				(end 119.79783 -273.276314)
			)
		)
		(stroke
			(width 0)
			(type solid)
		)
		(fill yes)
		(layer "In12.Cu")
		(net "P5E_CPU1_P2_TX_DP<8>")
	)
	(gr_poly
		(pts
			(arc
				(start 119.79783 -271.656302)
				(mid 119.39143 -271.656302)
				(end 119.79783 -271.656302)
			)
		)
		(stroke
			(width 0)
			(type solid)
		)
		(fill yes)
		(layer "In12.Cu")
		(net "P5E_CPU1_P2_TX_DP<9>")
	)
	(gr_poly
		(pts
			(arc
				(start 119.79783 -270.03629)
				(mid 119.39143 -270.03629)
				(end 119.79783 -270.03629)
			)
		)
		(stroke
			(width 0)
			(type solid)
		)
		(fill yes)
		(layer "In12.Cu")
		(net "P5E_CPU1_P2_TX_DP<7>")
	)
	(gr_poly
		(pts
			(arc
				(start 120.737884 -273.276314)
				(mid 120.331484 -273.276314)
				(end 120.737884 -273.276314)
			)
		)
		(stroke
			(width 0)
			(type solid)
		)
		(fill yes)
		(layer "In12.Cu")
		(net "P5E_CPU1_P2_TX_DN<8>")
	)
	(gr_poly
		(pts
			(arc
				(start 120.737884 -271.656302)
				(mid 120.331484 -271.656302)
				(end 120.737884 -271.656302)
			)
		)
		(stroke
			(width 0)
			(type solid)
		)
		(fill yes)
		(layer "In12.Cu")
		(net "P5E_CPU1_P2_TX_DN<9>")
	)
	(gr_poly
		(pts
			(arc
				(start 120.737884 -270.03629)
				(mid 120.331484 -270.03629)
				(end 120.737884 -270.03629)
			)
		)
		(stroke
			(width 0)
			(type solid)
		)
		(fill yes)
		(layer "In12.Cu")
		(net "P5E_CPU1_P2_TX_DN<7>")
	)
	(gr_poly
		(pts
			(arc
				(start 122.617992 -273.276314)
				(mid 122.211592 -273.276314)
				(end 122.617992 -273.276314)
			)
		)
		(stroke
			(width 0)
			(type solid)
		)
		(fill yes)
		(layer "In12.Cu")
		(net "P5E_CPU1_P2_TX_DP<11>")
	)
	(gr_poly
		(pts
			(arc
				(start 122.617992 -271.656302)
				(mid 122.211592 -271.656302)
				(end 122.617992 -271.656302)
			)
		)
		(stroke
			(width 0)
			(type solid)
		)
		(fill yes)
		(layer "In12.Cu")
		(net "P5E_CPU1_P2_TX_DP<12>")
	)
	(gr_poly
		(pts
			(arc
				(start 122.617992 -270.03629)
				(mid 122.211592 -270.03629)
				(end 122.617992 -270.03629)
			)
		)
		(stroke
			(width 0)
			(type solid)
		)
		(fill yes)
		(layer "In12.Cu")
		(net "P5E_CPU1_P2_TX_DP<10>")
	)
	(gr_poly
		(pts
			(arc
				(start 123.558046 -273.276314)
				(mid 123.151646 -273.276314)
				(end 123.558046 -273.276314)
			)
		)
		(stroke
			(width 0)
			(type solid)
		)
		(fill yes)
		(layer "In12.Cu")
		(net "P5E_CPU1_P2_TX_DN<11>")
	)
	(gr_poly
		(pts
			(arc
				(start 123.558046 -271.656302)
				(mid 123.151646 -271.656302)
				(end 123.558046 -271.656302)
			)
		)
		(stroke
			(width 0)
			(type solid)
		)
		(fill yes)
		(layer "In12.Cu")
		(net "P5E_CPU1_P2_TX_DN<12>")
	)
	(gr_poly
		(pts
			(arc
				(start 123.558046 -270.03629)
				(mid 123.151646 -270.03629)
				(end 123.558046 -270.03629)
			)
		)
		(stroke
			(width 0)
			(type solid)
		)
		(fill yes)
		(layer "In12.Cu")
		(net "P5E_CPU1_P2_TX_DN<10>")
	)
	(gr_poly
		(pts
			(arc
				(start 125.4379 -273.276314)
				(mid 125.0315 -273.276314)
				(end 125.4379 -273.276314)
			)
		)
		(stroke
			(width 0)
			(type solid)
		)
		(fill yes)
		(layer "In12.Cu")
		(net "P5E_CPU1_P2_TX_DP<14>")
	)
	(gr_poly
		(pts
			(arc
				(start 125.4379 -271.656302)
				(mid 125.0315 -271.656302)
				(end 125.4379 -271.656302)
			)
		)
		(stroke
			(width 0)
			(type solid)
		)
		(fill yes)
		(layer "In12.Cu")
		(net "P5E_CPU1_P2_TX_DP<15>")
	)
	(gr_poly
		(pts
			(arc
				(start 125.4379 -270.03629)
				(mid 125.0315 -270.03629)
				(end 125.4379 -270.03629)
			)
		)
		(stroke
			(width 0)
			(type solid)
		)
		(fill yes)
		(layer "In12.Cu")
		(net "P5E_CPU1_P2_TX_DP<13>")
	)
	(gr_poly
		(pts
			(arc
				(start 126.377954 -273.276314)
				(mid 125.971554 -273.276314)
				(end 126.377954 -273.276314)
			)
		)
		(stroke
			(width 0)
			(type solid)
		)
		(fill yes)
		(layer "In12.Cu")
		(net "P5E_CPU1_P2_TX_DN<14>")
	)
	(gr_poly
		(pts
			(arc
				(start 126.377954 -271.656302)
				(mid 125.971554 -271.656302)
				(end 126.377954 -271.656302)
			)
		)
		(stroke
			(width 0)
			(type solid)
		)
		(fill yes)
		(layer "In12.Cu")
		(net "P5E_CPU1_P2_TX_DN<15>")
	)
	(gr_poly
		(pts
			(arc
				(start 126.377954 -270.03629)
				(mid 125.971554 -270.03629)
				(end 126.377954 -270.03629)
			)
		)
		(stroke
			(width 0)
			(type solid)
		)
		(fill yes)
		(layer "In12.Cu")
		(net "P5E_CPU1_P2_TX_DN<13>")
	)
	(gr_poly
		(pts
			(arc
				(start 346.124276 -273.27606)
				(mid 345.717876 -273.27606)
				(end 346.124276 -273.27606)
			)
		)
		(stroke
			(width 0)
			(type solid)
		)
		(fill yes)
		(layer "In12.Cu")
		(net "P5E_CPU0_P0_RX_DN<1>")
	)
	(gr_poly
		(pts
			(arc
				(start 346.124276 -271.656048)
				(mid 345.717876 -271.656048)
				(end 346.124276 -271.656048)
			)
		)
		(stroke
			(width 0)
			(type solid)
		)
		(fill yes)
		(layer "In12.Cu")
		(net "P5E_CPU0_P0_RX_DN<0>")
	)
	(gr_poly
		(pts
			(arc
				(start 346.124276 -270.036036)
				(mid 345.717876 -270.036036)
				(end 346.124276 -270.036036)
			)
		)
		(stroke
			(width 0)
			(type solid)
		)
		(fill yes)
		(layer "In12.Cu")
		(net "P5E_CPU0_P0_RX_DN<2>")
	)
	(gr_poly
		(pts
			(arc
				(start 347.06433 -273.27606)
				(mid 346.65793 -273.27606)
				(end 347.06433 -273.27606)
			)
		)
		(stroke
			(width 0)
			(type solid)
		)
		(fill yes)
		(layer "In12.Cu")
		(net "P5E_CPU0_P0_RX_DP<1>")
	)
	(gr_poly
		(pts
			(arc
				(start 347.06433 -271.656048)
				(mid 346.65793 -271.656048)
				(end 347.06433 -271.656048)
			)
		)
		(stroke
			(width 0)
			(type solid)
		)
		(fill yes)
		(layer "In12.Cu")
		(net "P5E_CPU0_P0_RX_DP<0>")
	)
	(gr_poly
		(pts
			(arc
				(start 347.06433 -270.036036)
				(mid 346.65793 -270.036036)
				(end 347.06433 -270.036036)
			)
		)
		(stroke
			(width 0)
			(type solid)
		)
		(fill yes)
		(layer "In12.Cu")
		(net "P5E_CPU0_P0_RX_DP<2>")
	)
	(gr_poly
		(pts
			(arc
				(start 348.944184 -273.27606)
				(mid 348.537784 -273.27606)
				(end 348.944184 -273.27606)
			)
		)
		(stroke
			(width 0)
			(type solid)
		)
		(fill yes)
		(layer "In12.Cu")
		(net "P5E_CPU0_P0_RX_DN<4>")
	)
	(gr_poly
		(pts
			(arc
				(start 348.944184 -271.656048)
				(mid 348.537784 -271.656048)
				(end 348.944184 -271.656048)
			)
		)
		(stroke
			(width 0)
			(type solid)
		)
		(fill yes)
		(layer "In12.Cu")
		(net "P5E_CPU0_P0_RX_DN<3>")
	)
	(gr_poly
		(pts
			(arc
				(start 348.944184 -270.036036)
				(mid 348.537784 -270.036036)
				(end 348.944184 -270.036036)
			)
		)
		(stroke
			(width 0)
			(type solid)
		)
		(fill yes)
		(layer "In12.Cu")
		(net "P5E_CPU0_P0_RX_DN<5>")
	)
	(gr_poly
		(pts
			(arc
				(start 349.884238 -273.27606)
				(mid 349.477838 -273.27606)
				(end 349.884238 -273.27606)
			)
		)
		(stroke
			(width 0)
			(type solid)
		)
		(fill yes)
		(layer "In12.Cu")
		(net "P5E_CPU0_P0_RX_DP<4>")
	)
	(gr_poly
		(pts
			(arc
				(start 349.884238 -271.656048)
				(mid 349.477838 -271.656048)
				(end 349.884238 -271.656048)
			)
		)
		(stroke
			(width 0)
			(type solid)
		)
		(fill yes)
		(layer "In12.Cu")
		(net "P5E_CPU0_P0_RX_DP<3>")
	)
	(gr_poly
		(pts
			(arc
				(start 349.884238 -270.036036)
				(mid 349.477838 -270.036036)
				(end 349.884238 -270.036036)
			)
		)
		(stroke
			(width 0)
			(type solid)
		)
		(fill yes)
		(layer "In12.Cu")
		(net "P5E_CPU0_P0_RX_DP<5>")
	)
	(gr_poly
		(pts
			(arc
				(start 351.764346 -273.27606)
				(mid 351.357946 -273.27606)
				(end 351.764346 -273.27606)
			)
		)
		(stroke
			(width 0)
			(type solid)
		)
		(fill yes)
		(layer "In12.Cu")
		(net "P5E_CPU0_P0_RX_DN<7>")
	)
	(gr_poly
		(pts
			(arc
				(start 351.764346 -271.656048)
				(mid 351.357946 -271.656048)
				(end 351.764346 -271.656048)
			)
		)
		(stroke
			(width 0)
			(type solid)
		)
		(fill yes)
		(layer "In12.Cu")
		(net "P5E_CPU0_P0_RX_DN<6>")
	)
	(gr_poly
		(pts
			(arc
				(start 351.764346 -270.036036)
				(mid 351.357946 -270.036036)
				(end 351.764346 -270.036036)
			)
		)
		(stroke
			(width 0)
			(type solid)
		)
		(fill yes)
		(layer "In12.Cu")
		(net "P5E_CPU0_P0_RX_DN<8>")
	)
	(gr_poly
		(pts
			(arc
				(start 352.7044 -273.27606)
				(mid 352.298 -273.27606)
				(end 352.7044 -273.27606)
			)
		)
		(stroke
			(width 0)
			(type solid)
		)
		(fill yes)
		(layer "In12.Cu")
		(net "P5E_CPU0_P0_RX_DP<7>")
	)
	(gr_poly
		(pts
			(arc
				(start 352.7044 -271.656048)
				(mid 352.298 -271.656048)
				(end 352.7044 -271.656048)
			)
		)
		(stroke
			(width 0)
			(type solid)
		)
		(fill yes)
		(layer "In12.Cu")
		(net "P5E_CPU0_P0_RX_DP<6>")
	)
	(gr_poly
		(pts
			(arc
				(start 352.7044 -270.036036)
				(mid 352.298 -270.036036)
				(end 352.7044 -270.036036)
			)
		)
		(stroke
			(width 0)
			(type solid)
		)
		(fill yes)
		(layer "In12.Cu")
		(net "P5E_CPU0_P0_RX_DP<8>")
	)
	(gr_poly
		(pts
			(arc
				(start 354.584254 -273.27606)
				(mid 354.177854 -273.27606)
				(end 354.584254 -273.27606)
			)
		)
		(stroke
			(width 0)
			(type solid)
		)
		(fill yes)
		(layer "In12.Cu")
		(net "P5E_CPU0_P0_RX_DN<10>")
	)
	(gr_poly
		(pts
			(arc
				(start 354.584254 -271.656048)
				(mid 354.177854 -271.656048)
				(end 354.584254 -271.656048)
			)
		)
		(stroke
			(width 0)
			(type solid)
		)
		(fill yes)
		(layer "In12.Cu")
		(net "P5E_CPU0_P0_RX_DN<9>")
	)
	(gr_poly
		(pts
			(arc
				(start 354.584254 -270.036036)
				(mid 354.177854 -270.036036)
				(end 354.584254 -270.036036)
			)
		)
		(stroke
			(width 0)
			(type solid)
		)
		(fill yes)
		(layer "In12.Cu")
		(net "P5E_CPU0_P0_RX_DN<11>")
	)
	(gr_poly
		(pts
			(arc
				(start 355.524308 -273.27606)
				(mid 355.117908 -273.27606)
				(end 355.524308 -273.27606)
			)
		)
		(stroke
			(width 0)
			(type solid)
		)
		(fill yes)
		(layer "In12.Cu")
		(net "P5E_CPU0_P0_RX_DP<10>")
	)
	(gr_poly
		(pts
			(arc
				(start 355.524308 -271.656048)
				(mid 355.117908 -271.656048)
				(end 355.524308 -271.656048)
			)
		)
		(stroke
			(width 0)
			(type solid)
		)
		(fill yes)
		(layer "In12.Cu")
		(net "P5E_CPU0_P0_RX_DP<9>")
	)
	(gr_poly
		(pts
			(arc
				(start 355.524308 -270.036036)
				(mid 355.117908 -270.036036)
				(end 355.524308 -270.036036)
			)
		)
		(stroke
			(width 0)
			(type solid)
		)
		(fill yes)
		(layer "In12.Cu")
		(net "P5E_CPU0_P0_RX_DP<11>")
	)
	(gr_poly
		(pts
			(arc
				(start 356.934262 -274.086066)
				(mid 356.527862 -274.086066)
				(end 356.934262 -274.086066)
			)
		)
		(stroke
			(width 0)
			(type solid)
		)
		(fill yes)
		(layer "In12.Cu")
		(net "P5E_CPU0_P0_RX_DN<13>")
	)
	(gr_poly
		(pts
			(arc
				(start 356.934262 -272.466054)
				(mid 356.527862 -272.466054)
				(end 356.934262 -272.466054)
			)
		)
		(stroke
			(width 0)
			(type solid)
		)
		(fill yes)
		(layer "In12.Cu")
		(net "P5E_CPU0_P0_RX_DN<12>")
	)
	(gr_poly
		(pts
			(arc
				(start 356.934262 -270.846042)
				(mid 356.527862 -270.846042)
				(end 356.934262 -270.846042)
			)
		)
		(stroke
			(width 0)
			(type solid)
		)
		(fill yes)
		(layer "In12.Cu")
		(net "P5E_CPU0_P0_RX_DN<14>")
	)
	(gr_poly
		(pts
			(arc
				(start 356.934262 -269.22603)
				(mid 356.527862 -269.22603)
				(end 356.934262 -269.22603)
			)
		)
		(stroke
			(width 0)
			(type solid)
		)
		(fill yes)
		(layer "In12.Cu")
		(net "P5E_CPU0_P0_RX_DN<15>")
	)
	(gr_poly
		(pts
			(arc
				(start 357.874316 -274.086066)
				(mid 357.467916 -274.086066)
				(end 357.874316 -274.086066)
			)
		)
		(stroke
			(width 0)
			(type solid)
		)
		(fill yes)
		(layer "In12.Cu")
		(net "P5E_CPU0_P0_RX_DP<13>")
	)
	(gr_poly
		(pts
			(arc
				(start 357.874316 -272.466054)
				(mid 357.467916 -272.466054)
				(end 357.874316 -272.466054)
			)
		)
		(stroke
			(width 0)
			(type solid)
		)
		(fill yes)
		(layer "In12.Cu")
		(net "P5E_CPU0_P0_RX_DP<12>")
	)
	(gr_poly
		(pts
			(arc
				(start 357.874316 -270.846042)
				(mid 357.467916 -270.846042)
				(end 357.874316 -270.846042)
			)
		)
		(stroke
			(width 0)
			(type solid)
		)
		(fill yes)
		(layer "In12.Cu")
		(net "P5E_CPU0_P0_RX_DP<14>")
	)
	(gr_poly
		(pts
			(arc
				(start 357.874316 -269.22603)
				(mid 357.467916 -269.22603)
				(end 357.874316 -269.22603)
			)
		)
		(stroke
			(width 0)
			(type solid)
		)
		(fill yes)
		(layer "In12.Cu")
		(net "P5E_CPU0_P0_RX_DP<15>")
	)
	(gr_poly
		(pts
			(arc
				(start 362.567982 -274.086066)
				(mid 362.161582 -274.086066)
				(end 362.567982 -274.086066)
			)
		)
		(stroke
			(width 0)
			(type solid)
		)
		(fill yes)
		(layer "In12.Cu")
		(net "P5E_CPU0_P2_TX_DP<2>")
	)
	(gr_poly
		(pts
			(arc
				(start 362.567982 -272.466054)
				(mid 362.161582 -272.466054)
				(end 362.567982 -272.466054)
			)
		)
		(stroke
			(width 0)
			(type solid)
		)
		(fill yes)
		(layer "In12.Cu")
		(net "P5E_CPU0_P2_TX_DP<3>")
	)
	(gr_poly
		(pts
			(arc
				(start 362.567982 -270.846042)
				(mid 362.161582 -270.846042)
				(end 362.567982 -270.846042)
			)
		)
		(stroke
			(width 0)
			(type solid)
		)
		(fill yes)
		(layer "In12.Cu")
		(net "P5E_CPU0_P2_TX_DP<1>")
	)
	(gr_poly
		(pts
			(arc
				(start 362.567982 -269.22603)
				(mid 362.161582 -269.22603)
				(end 362.567982 -269.22603)
			)
		)
		(stroke
			(width 0)
			(type solid)
		)
		(fill yes)
		(layer "In12.Cu")
		(net "P5E_CPU0_P2_TX_DP<0>")
	)
	(gr_poly
		(pts
			(arc
				(start 363.508036 -274.086066)
				(mid 363.101636 -274.086066)
				(end 363.508036 -274.086066)
			)
		)
		(stroke
			(width 0)
			(type solid)
		)
		(fill yes)
		(layer "In12.Cu")
		(net "P5E_CPU0_P2_TX_DN<2>")
	)
	(gr_poly
		(pts
			(arc
				(start 363.508036 -272.466054)
				(mid 363.101636 -272.466054)
				(end 363.508036 -272.466054)
			)
		)
		(stroke
			(width 0)
			(type solid)
		)
		(fill yes)
		(layer "In12.Cu")
		(net "P5E_CPU0_P2_TX_DN<3>")
	)
	(gr_poly
		(pts
			(arc
				(start 363.508036 -270.846042)
				(mid 363.101636 -270.846042)
				(end 363.508036 -270.846042)
			)
		)
		(stroke
			(width 0)
			(type solid)
		)
		(fill yes)
		(layer "In12.Cu")
		(net "P5E_CPU0_P2_TX_DN<1>")
	)
	(gr_poly
		(pts
			(arc
				(start 363.508036 -269.22603)
				(mid 363.101636 -269.22603)
				(end 363.508036 -269.22603)
			)
		)
		(stroke
			(width 0)
			(type solid)
		)
		(fill yes)
		(layer "In12.Cu")
		(net "P5E_CPU0_P2_TX_DN<0>")
	)
	(gr_poly
		(pts
			(arc
				(start 364.91799 -273.27606)
				(mid 364.51159 -273.27606)
				(end 364.91799 -273.27606)
			)
		)
		(stroke
			(width 0)
			(type solid)
		)
		(fill yes)
		(layer "In12.Cu")
		(net "P5E_CPU0_P2_TX_DP<5>")
	)
	(gr_poly
		(pts
			(arc
				(start 364.91799 -271.656048)
				(mid 364.51159 -271.656048)
				(end 364.91799 -271.656048)
			)
		)
		(stroke
			(width 0)
			(type solid)
		)
		(fill yes)
		(layer "In12.Cu")
		(net "P5E_CPU0_P2_TX_DP<6>")
	)
	(gr_poly
		(pts
			(arc
				(start 364.91799 -270.036036)
				(mid 364.51159 -270.036036)
				(end 364.91799 -270.036036)
			)
		)
		(stroke
			(width 0)
			(type solid)
		)
		(fill yes)
		(layer "In12.Cu")
		(net "P5E_CPU0_P2_TX_DP<4>")
	)
	(gr_poly
		(pts
			(arc
				(start 365.858044 -273.27606)
				(mid 365.451644 -273.27606)
				(end 365.858044 -273.27606)
			)
		)
		(stroke
			(width 0)
			(type solid)
		)
		(fill yes)
		(layer "In12.Cu")
		(net "P5E_CPU0_P2_TX_DN<5>")
	)
	(gr_poly
		(pts
			(arc
				(start 365.858044 -271.656048)
				(mid 365.451644 -271.656048)
				(end 365.858044 -271.656048)
			)
		)
		(stroke
			(width 0)
			(type solid)
		)
		(fill yes)
		(layer "In12.Cu")
		(net "P5E_CPU0_P2_TX_DN<6>")
	)
	(gr_poly
		(pts
			(arc
				(start 365.858044 -270.036036)
				(mid 365.451644 -270.036036)
				(end 365.858044 -270.036036)
			)
		)
		(stroke
			(width 0)
			(type solid)
		)
		(fill yes)
		(layer "In12.Cu")
		(net "P5E_CPU0_P2_TX_DN<4>")
	)
	(gr_poly
		(pts
			(arc
				(start 367.737898 -273.27606)
				(mid 367.331498 -273.27606)
				(end 367.737898 -273.27606)
			)
		)
		(stroke
			(width 0)
			(type solid)
		)
		(fill yes)
		(layer "In12.Cu")
		(net "P5E_CPU0_P2_TX_DP<8>")
	)
	(gr_poly
		(pts
			(arc
				(start 367.737898 -271.656048)
				(mid 367.331498 -271.656048)
				(end 367.737898 -271.656048)
			)
		)
		(stroke
			(width 0)
			(type solid)
		)
		(fill yes)
		(layer "In12.Cu")
		(net "P5E_CPU0_P2_TX_DP<9>")
	)
	(gr_poly
		(pts
			(arc
				(start 367.737898 -270.036036)
				(mid 367.331498 -270.036036)
				(end 367.737898 -270.036036)
			)
		)
		(stroke
			(width 0)
			(type solid)
		)
		(fill yes)
		(layer "In12.Cu")
		(net "P5E_CPU0_P2_TX_DP<7>")
	)
	(gr_poly
		(pts
			(arc
				(start 368.677952 -273.27606)
				(mid 368.271552 -273.27606)
				(end 368.677952 -273.27606)
			)
		)
		(stroke
			(width 0)
			(type solid)
		)
		(fill yes)
		(layer "In12.Cu")
		(net "P5E_CPU0_P2_TX_DN<8>")
	)
	(gr_poly
		(pts
			(arc
				(start 368.677952 -271.656048)
				(mid 368.271552 -271.656048)
				(end 368.677952 -271.656048)
			)
		)
		(stroke
			(width 0)
			(type solid)
		)
		(fill yes)
		(layer "In12.Cu")
		(net "P5E_CPU0_P2_TX_DN<9>")
	)
	(gr_poly
		(pts
			(arc
				(start 368.677952 -270.036036)
				(mid 368.271552 -270.036036)
				(end 368.677952 -270.036036)
			)
		)
		(stroke
			(width 0)
			(type solid)
		)
		(fill yes)
		(layer "In12.Cu")
		(net "P5E_CPU0_P2_TX_DN<7>")
	)
	(gr_poly
		(pts
			(arc
				(start 370.55806 -273.27606)
				(mid 370.15166 -273.27606)
				(end 370.55806 -273.27606)
			)
		)
		(stroke
			(width 0)
			(type solid)
		)
		(fill yes)
		(layer "In12.Cu")
		(net "P5E_CPU0_P2_TX_DP<11>")
	)
	(gr_poly
		(pts
			(arc
				(start 370.55806 -271.656048)
				(mid 370.15166 -271.656048)
				(end 370.55806 -271.656048)
			)
		)
		(stroke
			(width 0)
			(type solid)
		)
		(fill yes)
		(layer "In12.Cu")
		(net "P5E_CPU0_P2_TX_DP<12>")
	)
	(gr_poly
		(pts
			(arc
				(start 370.55806 -270.036036)
				(mid 370.15166 -270.036036)
				(end 370.55806 -270.036036)
			)
		)
		(stroke
			(width 0)
			(type solid)
		)
		(fill yes)
		(layer "In12.Cu")
		(net "P5E_CPU0_P2_TX_DP<10>")
	)
	(gr_poly
		(pts
			(arc
				(start 371.498114 -273.27606)
				(mid 371.091714 -273.27606)
				(end 371.498114 -273.27606)
			)
		)
		(stroke
			(width 0)
			(type solid)
		)
		(fill yes)
		(layer "In12.Cu")
		(net "P5E_CPU0_P2_TX_DN<11>")
	)
	(gr_poly
		(pts
			(arc
				(start 371.498114 -271.656048)
				(mid 371.091714 -271.656048)
				(end 371.498114 -271.656048)
			)
		)
		(stroke
			(width 0)
			(type solid)
		)
		(fill yes)
		(layer "In12.Cu")
		(net "P5E_CPU0_P2_TX_DN<12>")
	)
	(gr_poly
		(pts
			(arc
				(start 371.498114 -270.036036)
				(mid 371.091714 -270.036036)
				(end 371.498114 -270.036036)
			)
		)
		(stroke
			(width 0)
			(type solid)
		)
		(fill yes)
		(layer "In12.Cu")
		(net "P5E_CPU0_P2_TX_DN<10>")
	)
	(gr_poly
		(pts
			(arc
				(start 373.377968 -273.27606)
				(mid 372.971568 -273.27606)
				(end 373.377968 -273.27606)
			)
		)
		(stroke
			(width 0)
			(type solid)
		)
		(fill yes)
		(layer "In12.Cu")
		(net "P5E_CPU0_P2_TX_DP<14>")
	)
	(gr_poly
		(pts
			(arc
				(start 373.377968 -271.656048)
				(mid 372.971568 -271.656048)
				(end 373.377968 -271.656048)
			)
		)
		(stroke
			(width 0)
			(type solid)
		)
		(fill yes)
		(layer "In12.Cu")
		(net "P5E_CPU0_P2_TX_DP<15>")
	)
	(gr_poly
		(pts
			(arc
				(start 373.377968 -270.036036)
				(mid 372.971568 -270.036036)
				(end 373.377968 -270.036036)
			)
		)
		(stroke
			(width 0)
			(type solid)
		)
		(fill yes)
		(layer "In12.Cu")
		(net "P5E_CPU0_P2_TX_DP<13>")
	)
	(gr_poly
		(pts
			(arc
				(start 374.318022 -273.27606)
				(mid 373.911622 -273.27606)
				(end 374.318022 -273.27606)
			)
		)
		(stroke
			(width 0)
			(type solid)
		)
		(fill yes)
		(layer "In12.Cu")
		(net "P5E_CPU0_P2_TX_DN<14>")
	)
	(gr_poly
		(pts
			(arc
				(start 374.318022 -271.656048)
				(mid 373.911622 -271.656048)
				(end 374.318022 -271.656048)
			)
		)
		(stroke
			(width 0)
			(type solid)
		)
		(fill yes)
		(layer "In12.Cu")
		(net "P5E_CPU0_P2_TX_DN<15>")
	)
	(gr_poly
		(pts
			(arc
				(start 374.318022 -270.036036)
				(mid 373.911622 -270.036036)
				(end 374.318022 -270.036036)
			)
		)
		(stroke
			(width 0)
			(type solid)
		)
		(fill yes)
		(layer "In12.Cu")
		(net "P5E_CPU0_P2_TX_DN<13>")
	)
	(gr_poly
		(pts
			(arc
				(start 273.15541 -393.27836)
				(mid 273.174933 -393.274459)
				(end 273.191478 -393.263374)
			)
			(xy 273.191732 -393.26312) (xy 273.669252 -392.7856)
			(arc
				(start 273.669506 -392.785346)
				(mid 273.680617 -392.768812)
				(end 273.684492 -392.749278)
			)
			(arc
				(start 273.684492 -384.155442)
				(mid 273.680591 -384.135919)
				(end 273.669506 -384.119374)
			)
			(xy 273.669252 -384.11912) (xy 273.447764 -383.897632) (xy 273.447256 -383.897124)
			(arc
				(start 273.445478 -383.895346)
				(mid 273.428944 -383.884235)
				(end 273.40941 -383.88036)
			)
			(arc
				(start 239.542574 -383.88036)
				(mid 239.523051 -383.884261)
				(end 239.506506 -383.895346)
			)
			(xy 239.506252 -383.8956) (xy 239.03051 -384.371342) (xy 239.030256 -384.371596)
			(arc
				(start 239.028478 -384.373374)
				(mid 239.017367 -384.389908)
				(end 239.013492 -384.409442)
			)
			(arc
				(start 239.013492 -393.003278)
				(mid 239.017393 -393.022801)
				(end 239.028478 -393.039346)
			)
			(xy 239.028732 -393.0396) (xy 239.252252 -393.26312)
			(arc
				(start 239.252506 -393.263374)
				(mid 239.26904 -393.274485)
				(end 239.288574 -393.27836)
			)
		)
		(stroke
			(width 0)
			(type solid)
		)
		(fill yes)
		(layer "In12.Cu")
		(net "P12V_MAIN_R")
	)
	(gr_poly
		(pts
			(arc
				(start 228.921818 -436.47868)
				(mid 228.941341 -436.474779)
				(end 228.957886 -436.463694)
			)
			(arc
				(start 229.664514 -435.757066)
				(mid 229.675625 -435.740532)
				(end 229.6795 -435.720998)
			)
			(arc
				(start 229.6795 -422.180766)
				(mid 229.703653 -422.05925)
				(end 229.772464 -421.95623)
			)
			(arc
				(start 234.67314 -417.055554)
				(mid 234.776172 -416.986773)
				(end 234.897676 -416.96259)
			)
			(arc
				(start 272.037556 -416.96259)
				(mid 272.057079 -416.958689)
				(end 272.073624 -416.947604)
			)
			(arc
				(start 280.035254 -408.985974)
				(mid 280.046365 -408.96944)
				(end 280.05024 -408.949906)
			)
			(arc
				(start 280.05024 -394.963396)
				(mid 280.046339 -394.943873)
				(end 280.035254 -394.927328)
			)
			(xy 280.035 -394.927074) (xy 279.65146 -394.543534)
			(arc
				(start 279.651206 -394.54328)
				(mid 279.634672 -394.532169)
				(end 279.615138 -394.528294)
			)
			(arc
				(start 278.051514 -394.528294)
				(mid 278.036928 -394.530433)
				(end 278.023574 -394.536676)
			)
			(arc
				(start 278.023574 -394.536676)
				(mid 277.823537 -394.629726)
				(end 277.605236 -394.661644)
			)
			(arc
				(start 277.605236 -394.661644)
				(mid 277.421236 -394.639047)
				(end 277.248112 -394.572744)
			)
			(arc
				(start 277.248112 -394.572744)
				(mid 277.224236 -394.566797)
				(end 277.20036 -394.572744)
			)
			(arc
				(start 277.20036 -394.572744)
				(mid 277.027244 -394.639078)
				(end 276.843236 -394.661644)
			)
			(arc
				(start 276.843236 -394.661644)
				(mid 276.624932 -394.629737)
				(end 276.424898 -394.536676)
			)
			(arc
				(start 276.424898 -394.536676)
				(mid 276.411542 -394.53044)
				(end 276.396958 -394.528294)
			)
			(arc
				(start 269.04569 -394.528294)
				(mid 269.030398 -394.53065)
				(end 269.01648 -394.537438)
			)
			(arc
				(start 269.01648 -394.537438)
				(mid 268.808203 -394.640414)
				(end 268.578584 -394.675868)
			)
			(arc
				(start 268.578584 -394.675868)
				(mid 268.394584 -394.653271)
				(end 268.22146 -394.586968)
			)
			(arc
				(start 268.22146 -394.586968)
				(mid 268.197584 -394.581021)
				(end 268.173708 -394.586968)
			)
			(arc
				(start 268.173708 -394.586968)
				(mid 268.000592 -394.653302)
				(end 267.816584 -394.675868)
			)
			(arc
				(start 267.816584 -394.675868)
				(mid 267.586971 -394.640395)
				(end 267.378688 -394.537438)
			)
			(arc
				(start 267.378688 -394.537438)
				(mid 267.364793 -394.530577)
				(end 267.349478 -394.528294)
			)
			(arc
				(start 261.01929 -394.528294)
				(mid 261.003998 -394.53065)
				(end 260.99008 -394.537438)
			)
			(arc
				(start 260.99008 -394.537438)
				(mid 260.781803 -394.640414)
				(end 260.552184 -394.675868)
			)
			(arc
				(start 260.552184 -394.675868)
				(mid 260.368184 -394.653271)
				(end 260.19506 -394.586968)
			)
			(arc
				(start 260.19506 -394.586968)
				(mid 260.171184 -394.581021)
				(end 260.147308 -394.586968)
			)
			(arc
				(start 260.147308 -394.586968)
				(mid 259.974192 -394.653302)
				(end 259.790184 -394.675868)
			)
			(arc
				(start 259.790184 -394.675868)
				(mid 259.560571 -394.640395)
				(end 259.352288 -394.537438)
			)
			(arc
				(start 259.352288 -394.537438)
				(mid 259.338393 -394.530577)
				(end 259.323078 -394.528294)
			)
			(arc
				(start 252.99289 -394.528294)
				(mid 252.977598 -394.53065)
				(end 252.96368 -394.537438)
			)
			(arc
				(start 252.96368 -394.537438)
				(mid 252.755403 -394.640414)
				(end 252.525784 -394.675868)
			)
			(arc
				(start 252.525784 -394.675868)
				(mid 252.341784 -394.653271)
				(end 252.16866 -394.586968)
			)
			(arc
				(start 252.16866 -394.586968)
				(mid 252.144784 -394.581021)
				(end 252.120908 -394.586968)
			)
			(arc
				(start 252.120908 -394.586968)
				(mid 251.947792 -394.653302)
				(end 251.763784 -394.675868)
			)
			(arc
				(start 251.763784 -394.675868)
				(mid 251.534171 -394.640395)
				(end 251.325888 -394.537438)
			)
			(arc
				(start 251.325888 -394.537438)
				(mid 251.311993 -394.530577)
				(end 251.296678 -394.528294)
			)
			(arc
				(start 244.9576 -394.528294)
				(mid 244.942576 -394.530567)
				(end 244.928898 -394.537184)
			)
			(arc
				(start 244.928898 -394.537184)
				(mid 244.722849 -394.637373)
				(end 244.496336 -394.671804)
			)
			(arc
				(start 244.496336 -394.671804)
				(mid 244.312336 -394.649207)
				(end 244.139212 -394.582904)
			)
			(arc
				(start 244.139212 -394.582904)
				(mid 244.115336 -394.576957)
				(end 244.09146 -394.582904)
			)
			(arc
				(start 244.09146 -394.582904)
				(mid 243.918344 -394.649238)
				(end 243.734336 -394.671804)
			)
			(arc
				(start 243.734336 -394.671804)
				(mid 243.507823 -394.637371)
				(end 243.301774 -394.537184)
			)
			(arc
				(start 243.301774 -394.537184)
				(mid 243.288095 -394.53057)
				(end 243.273072 -394.528294)
			)
			(arc
				(start 239.250982 -394.528294)
				(mid 239.215061 -394.543173)
				(end 239.200182 -394.579094)
			)
			(arc
				(start 239.200182 -406.147778)
				(mid 239.176029 -406.269294)
				(end 239.107218 -406.372314)
			)
			(arc
				(start 234.94238 -410.537152)
				(mid 234.839348 -410.605933)
				(end 234.717844 -410.630116)
			)
			(arc
				(start 229.698042 -410.630116)
				(mid 229.678519 -410.634017)
				(end 229.661974 -410.645102)
			)
			(arc
				(start 227.151946 -413.15513)
				(mid 227.048914 -413.223911)
				(end 226.92741 -413.248094)
			)
			(arc
				(start 195.944998 -413.248094)
				(mid 195.925475 -413.251995)
				(end 195.90893 -413.26308)
			)
			(arc
				(start 195.239386 -413.932624)
				(mid 195.228275 -413.949158)
				(end 195.2244 -413.968692)
			)
			(arc
				(start 195.2244 -420.7002)
				(mid 195.228301 -420.719723)
				(end 195.239386 -420.736268)
			)
			(xy 195.23964 -420.736522)
			(arc
				(start 205.961996 -431.458878)
				(mid 206.030777 -431.56191)
				(end 206.05496 -431.683414)
			)
			(arc
				(start 206.05496 -435.078378)
				(mid 206.058861 -435.097901)
				(end 206.069946 -435.114446)
			)
			(arc
				(start 207.419194 -436.463694)
				(mid 207.435728 -436.474805)
				(end 207.455262 -436.47868)
			)
		)
		(stroke
			(width 0)
			(type solid)
		)
		(fill yes)
		(layer "In12.Cu")
		(net "P12V_PSU")
	)
	(gr_poly
		(pts
			(xy 531.7998 -462.519268) (xy 531.855569 -462.518759) (xy 531.966796 -462.510424) (xy 532.077089 -462.4938)
			(xy 532.185831 -462.46898) (xy 532.292414 -462.436103) (xy 532.396243 -462.395354) (xy 532.496736 -462.346959)
			(xy 532.593331 -462.291189) (xy 532.685488 -462.228357) (xy 532.772692 -462.158813) (xy 532.854456 -462.082947)
			(xy 532.930321 -462.001183) (xy 532.999864 -461.913979) (xy 533.062695 -461.821821) (xy 533.118464 -461.725225)
			(xy 533.166858 -461.624732) (xy 533.207607 -461.520903) (xy 533.240483 -461.41432) (xy 533.265302 -461.305577)
			(xy 533.281925 -461.195284) (xy 533.29026 -461.084057) (xy 533.29078 -461.028288) (xy 533.29078 -455.0283)
			(xy 533.290259 -454.972531) (xy 533.281923 -454.861305) (xy 533.265299 -454.751013) (xy 533.24048 -454.642271)
			(xy 533.207603 -454.535688) (xy 533.166854 -454.43186) (xy 533.118459 -454.331368) (xy 533.06269 -454.234773)
			(xy 532.999859 -454.142616) (xy 532.930316 -454.055412) (xy 532.854451 -453.973649) (xy 532.772688 -453.897784)
			(xy 532.685484 -453.828241) (xy 532.593327 -453.76541) (xy 532.496732 -453.709641) (xy 532.39624 -453.661246)
			(xy 532.292412 -453.620497) (xy 532.185829 -453.58762) (xy 532.077087 -453.562801) (xy 531.966795 -453.546177)
			(xy 531.855569 -453.537841) (xy 531.7998 -453.53732) (xy 516.019796 -453.53732) (xy 515.949414 -453.536826)
			(xy 515.808871 -453.528933) (xy 515.668991 -453.513172) (xy 515.530216 -453.489593) (xy 515.392981 -453.45827)
			(xy 515.257718 -453.419302) (xy 515.124852 -453.37281) (xy 514.994803 -453.318942) (xy 514.867978 -453.257866)
			(xy 514.744778 -453.189776) (xy 514.625589 -453.114884) (xy 514.510787 -453.033428) (xy 514.400733 -452.945663)
			(xy 514.295773 -452.851865) (xy 514.196238 -452.75233) (xy 514.10244 -452.64737) (xy 514.014674 -452.537316)
			(xy 513.933218 -452.422514) (xy 513.858326 -452.303325) (xy 513.790236 -452.180125) (xy 513.72916 -452.053301)
			(xy 513.675292 -451.923251) (xy 513.6288 -451.790386) (xy 513.589831 -451.655123) (xy 513.558507 -451.517888)
			(xy 513.534928 -451.379113) (xy 513.519167 -451.239233) (xy 513.511274 -451.09869) (xy 513.510784 -451.028308)
			(xy 513.510784 -312.408316) (xy 513.511268 -312.337933) (xy 513.51916 -312.197389) (xy 513.53492 -312.057508)
			(xy 513.558498 -311.918731) (xy 513.589821 -311.781495) (xy 513.628789 -311.646231) (xy 513.67528 -311.513364)
			(xy 513.729148 -311.383313) (xy 513.790224 -311.256488) (xy 513.858314 -311.133286) (xy 513.933205 -311.014096)
			(xy 514.014662 -310.899292) (xy 514.102427 -310.789237) (xy 514.196225 -310.684276) (xy 514.295761 -310.584739)
			(xy 514.400722 -310.49094) (xy 514.510776 -310.403174) (xy 514.625579 -310.321716) (xy 514.744769 -310.246824)
			(xy 514.86797 -310.178733) (xy 514.994795 -310.117656) (xy 515.124845 -310.063787) (xy 515.257712 -310.017295)
			(xy 515.392976 -309.978326) (xy 515.530212 -309.947002) (xy 515.668989 -309.923423) (xy 515.808869 -309.907662)
			(xy 515.949413 -309.899769) (xy 516.019796 -309.899304) (xy 531.7998 -309.899304) (xy 531.855569 -309.898783)
			(xy 531.966796 -309.890447) (xy 532.077089 -309.873823) (xy 532.185831 -309.849004) (xy 532.292415 -309.816128)
			(xy 532.396243 -309.775378) (xy 532.496737 -309.726984) (xy 532.593332 -309.671215) (xy 532.68549 -309.608384)
			(xy 532.772695 -309.538841) (xy 532.854459 -309.462976) (xy 532.930326 -309.381213) (xy 532.99987 -309.294009)
			(xy 533.062703 -309.201852) (xy 533.118473 -309.105258) (xy 533.166869 -309.004765) (xy 533.20762 -308.900937)
			(xy 533.240498 -308.794355) (xy 533.265319 -308.685613) (xy 533.281945 -308.57532) (xy 533.290282 -308.464093)
			(xy 533.29078 -308.408324) (xy 533.29078 10.40003) (xy 533.290257 10.455798) (xy 533.28192 10.567023)
			(xy 533.265294 10.677313) (xy 533.240473 10.786053) (xy 533.207596 10.892634) (xy 533.166845 10.99646)
			(xy 533.11845 11.09695) (xy 533.06268 11.193543) (xy 532.999848 11.285698) (xy 532.930305 11.3729)
			(xy 532.85444 11.454661) (xy 532.772677 11.530525) (xy 532.685474 11.600066) (xy 532.593318 11.662896)
			(xy 532.496724 11.718664) (xy 532.396232 11.767057) (xy 532.292406 11.807806) (xy 532.185824 11.840681)
			(xy 532.077084 11.8655) (xy 531.966793 11.882123) (xy 531.855568 11.890459) (xy 531.7998 11.89101)
			(xy 475.799912 11.89101) (xy 475.744142 11.890489) (xy 475.632915 11.882155) (xy 475.522621 11.865531)
			(xy 475.413878 11.840713) (xy 475.307293 11.807837) (xy 475.203464 11.767088) (xy 475.10297 11.718694)
			(xy 475.006373 11.662926) (xy 474.914214 11.600094) (xy 474.827008 11.530552) (xy 474.745243 11.454687)
			(xy 474.669376 11.372924) (xy 474.599831 11.28572) (xy 474.536997 11.193563) (xy 474.481225 11.096967)
			(xy 474.432829 10.996475) (xy 474.392077 10.892646) (xy 474.359198 10.786063) (xy 474.334376 10.67732)
			(xy 474.31775 10.567027) (xy 474.309413 10.4558) (xy 474.308932 10.40003) (xy 474.308932 7.335466)
			(xy 526.704041 7.335466) (xy 526.704041 7.464606) (xy 526.711991 7.593501) (xy 526.727861 7.721661)
			(xy 526.75159 7.848602) (xy 526.783089 7.973841) (xy 526.822238 8.096904) (xy 526.868889 8.217323)
			(xy 526.922864 8.334642) (xy 526.983959 8.448416) (xy 527.051942 8.558213) (xy 527.126556 8.663616)
			(xy 527.207517 8.764226) (xy 527.294517 8.859661) (xy 527.387228 8.94956) (xy 527.485298 9.033581)
			(xy 527.588353 9.111405) (xy 527.696004 9.182737) (xy 527.807843 9.247307) (xy 527.923444 9.304869)
			(xy 528.042369 9.355206) (xy 528.164168 9.398126) (xy 528.288378 9.433467) (xy 528.414527 9.461094)
			(xy 528.542139 9.480903) (xy 528.670728 9.492819) (xy 528.799806 9.496796) (xy 528.928884 9.492819)
			(xy 529.057473 9.480903) (xy 529.185085 9.461094) (xy 529.311234 9.433467) (xy 529.435444 9.398126)
			(xy 529.557243 9.355206) (xy 529.676168 9.304869) (xy 529.791769 9.247307) (xy 529.903608 9.182737)
			(xy 530.011259 9.111405) (xy 530.114314 9.033581) (xy 530.212384 8.94956) (xy 530.305095 8.859661)
			(xy 530.392095 8.764226) (xy 530.473056 8.663616) (xy 530.54767 8.558213) (xy 530.615653 8.448416)
			(xy 530.676748 8.334642) (xy 530.730723 8.217323) (xy 530.777374 8.096904) (xy 530.816523 7.973841)
			(xy 530.848022 7.848602) (xy 530.871751 7.721661) (xy 530.887621 7.593501) (xy 530.895571 7.464606)
			(xy 530.896068 7.400036) (xy 530.895571 7.335466) (xy 530.887621 7.206571) (xy 530.871751 7.078411)
			(xy 530.848022 6.95147) (xy 530.816523 6.826231) (xy 530.777374 6.703168) (xy 530.730723 6.582749)
			(xy 530.676748 6.46543) (xy 530.615653 6.351656) (xy 530.54767 6.241859) (xy 530.473056 6.136456)
			(xy 530.392095 6.035846) (xy 530.305095 5.940411) (xy 530.212384 5.850512) (xy 530.114314 5.766491)
			(xy 530.011259 5.688667) (xy 529.903608 5.617335) (xy 529.791769 5.552765) (xy 529.676168 5.495203)
			(xy 529.557243 5.444866) (xy 529.435444 5.401946) (xy 529.311234 5.366605) (xy 529.185085 5.338978)
			(xy 529.057473 5.319169) (xy 528.928884 5.307253) (xy 528.799806 5.303277) (xy 528.670728 5.307253)
			(xy 528.542139 5.319169) (xy 528.414527 5.338978) (xy 528.288378 5.366605) (xy 528.164168 5.401946)
			(xy 528.042369 5.444866) (xy 527.923444 5.495203) (xy 527.807843 5.552765) (xy 527.696004 5.617335)
			(xy 527.588353 5.688667) (xy 527.485298 5.766491) (xy 527.387228 5.850512) (xy 527.294517 5.940411)
			(xy 527.207517 6.035846) (xy 527.126556 6.136456) (xy 527.051942 6.241859) (xy 526.983959 6.351656)
			(xy 526.922864 6.46543) (xy 526.868889 6.582749) (xy 526.822238 6.703168) (xy 526.783089 6.826231)
			(xy 526.75159 6.95147) (xy 526.727861 7.078411) (xy 526.711991 7.206571) (xy 526.704041 7.335466)
			(xy 474.308932 7.335466) (xy 474.308932 -12.515904) (xy 476.704141 -12.515904) (xy 476.704141 -12.386764)
			(xy 476.712091 -12.257869) (xy 476.727961 -12.129709) (xy 476.75169 -12.002768) (xy 476.783189 -11.877529)
			(xy 476.822338 -11.754466) (xy 476.868989 -11.634047) (xy 476.922964 -11.516728) (xy 476.984059 -11.402954)
			(xy 477.052042 -11.293157) (xy 477.126656 -11.187754) (xy 477.207617 -11.087144) (xy 477.294617 -10.991709)
			(xy 477.387328 -10.90181) (xy 477.485398 -10.817789) (xy 477.588453 -10.739965) (xy 477.696104 -10.668633)
			(xy 477.807943 -10.604063) (xy 477.923544 -10.546501) (xy 478.042469 -10.496164) (xy 478.164268 -10.453244)
			(xy 478.288478 -10.417903) (xy 478.414627 -10.390276) (xy 478.542239 -10.370467) (xy 478.670828 -10.358551)
			(xy 478.799906 -10.354575) (xy 478.928984 -10.358551) (xy 479.057573 -10.370467) (xy 479.185185 -10.390276)
			(xy 479.311334 -10.417903) (xy 479.435544 -10.453244) (xy 479.557343 -10.496164) (xy 479.676268 -10.546501)
			(xy 479.791869 -10.604063) (xy 479.903708 -10.668633) (xy 480.011359 -10.739965) (xy 480.114414 -10.817789)
			(xy 480.212484 -10.90181) (xy 480.305195 -10.991709) (xy 480.392195 -11.087144) (xy 480.473156 -11.187754)
			(xy 480.54777 -11.293157) (xy 480.615753 -11.402954) (xy 480.676848 -11.516728) (xy 480.730823 -11.634047)
			(xy 480.777474 -11.754466) (xy 480.816623 -11.877529) (xy 480.848122 -12.002768) (xy 480.871851 -12.129709)
			(xy 480.887721 -12.257869) (xy 480.895671 -12.386764) (xy 480.896168 -12.451334) (xy 480.895671 -12.515904)
			(xy 480.887721 -12.644799) (xy 480.871851 -12.772959) (xy 480.848122 -12.8999) (xy 480.816623 -13.025139)
			(xy 480.777474 -13.148202) (xy 480.730823 -13.268621) (xy 480.676848 -13.38594) (xy 480.615753 -13.499714)
			(xy 480.54777 -13.609511) (xy 480.473156 -13.714914) (xy 480.392195 -13.815524) (xy 480.305195 -13.910959)
			(xy 480.212484 -14.000858) (xy 480.114414 -14.084879) (xy 480.011359 -14.162703) (xy 479.903708 -14.234035)
			(xy 479.791869 -14.298605) (xy 479.676268 -14.356167) (xy 479.557343 -14.406504) (xy 479.435544 -14.449424)
			(xy 479.311334 -14.484765) (xy 479.185185 -14.512392) (xy 479.057573 -14.532201) (xy 478.928984 -14.544117)
			(xy 478.799906 -14.548094) (xy 478.670828 -14.544117) (xy 478.542239 -14.532201) (xy 478.414627 -14.512392)
			(xy 478.288478 -14.484765) (xy 478.164268 -14.449424) (xy 478.042469 -14.406504) (xy 477.923544 -14.356167)
			(xy 477.807943 -14.298605) (xy 477.696104 -14.234035) (xy 477.588453 -14.162703) (xy 477.485398 -14.084879)
			(xy 477.387328 -14.000858) (xy 477.294617 -13.910959) (xy 477.207617 -13.815524) (xy 477.126656 -13.714914)
			(xy 477.052042 -13.609511) (xy 476.984059 -13.499714) (xy 476.922964 -13.38594) (xy 476.868989 -13.268621)
			(xy 476.822338 -13.148202) (xy 476.783189 -13.025139) (xy 476.75169 -12.8999) (xy 476.727961 -12.772959)
			(xy 476.712091 -12.644799) (xy 476.704141 -12.515904) (xy 474.308932 -12.515904) (xy 474.308932 -77.67193)
			(xy 474.308458 -77.765117) (xy 474.300759 -77.951331) (xy 474.28537 -78.137067) (xy 474.262318 -78.32201)
			(xy 474.231642 -78.505841) (xy 474.193396 -78.688247) (xy 474.147643 -78.868917) (xy 474.094463 -79.047542)
			(xy 474.033945 -79.223817) (xy 473.966195 -79.397439) (xy 473.891327 -79.568113) (xy 473.809469 -79.735548)
			(xy 473.720761 -79.899456) (xy 473.625355 -80.059558) (xy 473.523414 -80.21558) (xy 473.415112 -80.367256)
			(xy 473.300633 -80.514327) (xy 473.180175 -80.65654) (xy 473.053942 -80.793654) (xy 472.988386 -80.859884)
			(xy 471.245946 -82.602324) (xy 471.208633 -82.640304) (xy 471.138899 -82.72077) (xy 471.07508 -82.806006)
			(xy 471.017504 -82.895576) (xy 470.966464 -82.989025) (xy 470.922218 -83.085876) (xy 470.884993 -83.185636)
			(xy 470.854978 -83.287798) (xy 470.832326 -83.391839) (xy 470.817153 -83.497232) (xy 470.809535 -83.603438)
			(xy 470.809066 -83.656678) (xy 470.809066 -328.137828) (xy 473.204275 -328.137828) (xy 473.204275 -328.008688)
			(xy 473.212225 -327.879793) (xy 473.228095 -327.751633) (xy 473.251824 -327.624692) (xy 473.283323 -327.499453)
			(xy 473.322472 -327.37639) (xy 473.369123 -327.255971) (xy 473.423098 -327.138652) (xy 473.484193 -327.024878)
			(xy 473.552176 -326.915081) (xy 473.62679 -326.809678) (xy 473.707751 -326.709068) (xy 473.794751 -326.613633)
			(xy 473.887462 -326.523734) (xy 473.985532 -326.439713) (xy 474.088587 -326.361889) (xy 474.196238 -326.290557)
			(xy 474.308077 -326.225987) (xy 474.423678 -326.168425) (xy 474.542603 -326.118088) (xy 474.664402 -326.075168)
			(xy 474.788612 -326.039827) (xy 474.914761 -326.0122) (xy 475.042373 -325.992391) (xy 475.170962 -325.980475)
			(xy 475.30004 -325.976499) (xy 475.429118 -325.980475) (xy 475.557707 -325.992391) (xy 475.685319 -326.0122)
			(xy 475.811468 -326.039827) (xy 475.935678 -326.075168) (xy 476.057477 -326.118088) (xy 476.176402 -326.168425)
			(xy 476.292003 -326.225987) (xy 476.403842 -326.290557) (xy 476.511493 -326.361889) (xy 476.614548 -326.439713)
			(xy 476.712618 -326.523734) (xy 476.805329 -326.613633) (xy 476.892329 -326.709068) (xy 476.97329 -326.809678)
			(xy 477.047904 -326.915081) (xy 477.115887 -327.024878) (xy 477.176982 -327.138652) (xy 477.230957 -327.255971)
			(xy 477.277608 -327.37639) (xy 477.316757 -327.499453) (xy 477.348256 -327.624692) (xy 477.371985 -327.751633)
			(xy 477.387855 -327.879793) (xy 477.395805 -328.008688) (xy 477.396302 -328.073258) (xy 477.395805 -328.137828)
			(xy 477.387855 -328.266723) (xy 477.371985 -328.394883) (xy 477.348256 -328.521824) (xy 477.316757 -328.647063)
			(xy 477.277608 -328.770126) (xy 477.230957 -328.890545) (xy 477.176982 -329.007864) (xy 477.115887 -329.121638)
			(xy 477.047904 -329.231435) (xy 476.97329 -329.336838) (xy 476.892329 -329.437448) (xy 476.805329 -329.532883)
			(xy 476.712618 -329.622782) (xy 476.614548 -329.706803) (xy 476.511493 -329.784627) (xy 476.403842 -329.855959)
			(xy 476.292003 -329.920529) (xy 476.176402 -329.978091) (xy 476.057477 -330.028428) (xy 475.935678 -330.071348)
			(xy 475.811468 -330.106689) (xy 475.685319 -330.134316) (xy 475.557707 -330.154125) (xy 475.429118 -330.166041)
			(xy 475.30004 -330.170018) (xy 475.170962 -330.166041) (xy 475.042373 -330.154125) (xy 474.914761 -330.134316)
			(xy 474.788612 -330.106689) (xy 474.664402 -330.071348) (xy 474.542603 -330.028428) (xy 474.423678 -329.978091)
			(xy 474.308077 -329.920529) (xy 474.196238 -329.855959) (xy 474.088587 -329.784627) (xy 473.985532 -329.706803)
			(xy 473.887462 -329.622782) (xy 473.794751 -329.532883) (xy 473.707751 -329.437448) (xy 473.62679 -329.336838)
			(xy 473.552176 -329.231435) (xy 473.484193 -329.121638) (xy 473.423098 -329.007864) (xy 473.369123 -328.890545)
			(xy 473.322472 -328.770126) (xy 473.283323 -328.647063) (xy 473.251824 -328.521824) (xy 473.228095 -328.394883)
			(xy 473.212225 -328.266723) (xy 473.204275 -328.137828) (xy 470.809066 -328.137828) (xy 470.809066 -404.871936)
			(xy 470.808592 -404.965123) (xy 470.800892 -405.151337) (xy 470.785503 -405.337074) (xy 470.762451 -405.522016)
			(xy 470.731776 -405.705847) (xy 470.693529 -405.888254) (xy 470.647776 -406.068924) (xy 470.594596 -406.247549)
			(xy 470.534079 -406.423823) (xy 470.466329 -406.597446) (xy 470.391461 -406.76812) (xy 470.309603 -406.935555)
			(xy 470.220896 -407.099463) (xy 470.12549 -407.259566) (xy 470.02355 -407.415588) (xy 469.915248 -407.567265)
			(xy 469.80077 -407.714335) (xy 469.680312 -407.856549) (xy 469.554079 -407.993664) (xy 469.48852 -408.05989)
			(xy 468.245698 -409.302712) (xy 468.208406 -409.340689) (xy 468.138712 -409.421147) (xy 468.074932 -409.506369)
			(xy 468.017391 -409.595922) (xy 467.966382 -409.68935) (xy 467.922165 -409.786178) (xy 467.884964 -409.885911)
			(xy 467.85497 -409.988044) (xy 467.832334 -410.092055) (xy 467.817172 -410.197416) (xy 467.809562 -410.303589)
			(xy 467.809072 -410.356812) (xy 467.809072 -439.989976) (xy 467.809593 -440.045746) (xy 467.817926 -440.156975)
			(xy 467.834548 -440.26727) (xy 467.859367 -440.376014) (xy 467.892242 -440.4826) (xy 467.93299 -440.586431)
			(xy 467.981383 -440.686926) (xy 468.037152 -440.783525) (xy 468.099983 -440.875685) (xy 468.169525 -440.962893)
			(xy 468.24539 -441.044659) (xy 468.327153 -441.120528) (xy 468.414357 -441.190075) (xy 468.506514 -441.25291)
			(xy 468.60311 -441.308683) (xy 468.703603 -441.357081) (xy 468.807432 -441.397835) (xy 468.914016 -441.430715)
			(xy 469.022759 -441.455538) (xy 469.133053 -441.472166) (xy 469.244282 -441.480505) (xy 469.300052 -441.480956)
			(xy 471.79992 -441.480956) (xy 471.870302 -441.48145) (xy 472.010845 -441.489344) (xy 472.150724 -441.505105)
			(xy 472.2895 -441.528685) (xy 472.426735 -441.560009) (xy 472.561998 -441.598978) (xy 472.694863 -441.64547)
			(xy 472.824912 -441.699339) (xy 472.951736 -441.760414) (xy 473.074936 -441.828505) (xy 473.194125 -441.903396)
			(xy 473.308927 -441.984852) (xy 473.418981 -442.072617) (xy 473.523941 -442.166415) (xy 473.623477 -442.26595)
			(xy 473.717275 -442.37091) (xy 473.80504 -442.480964) (xy 473.886497 -442.595765) (xy 473.961389 -442.714953)
			(xy 474.02948 -442.838153) (xy 474.090556 -442.964977) (xy 474.144426 -443.095026) (xy 474.190918 -443.227891)
			(xy 474.229888 -443.363154) (xy 474.261212 -443.500389) (xy 474.284793 -443.639164) (xy 474.300555 -443.779043)
			(xy 474.308449 -443.919586) (xy 474.308932 -443.989968) (xy 474.308932 -458.092864) (xy 526.704041 -458.092864)
			(xy 526.704041 -457.963724) (xy 526.711991 -457.834829) (xy 526.727861 -457.706669) (xy 526.75159 -457.579728)
			(xy 526.783089 -457.454489) (xy 526.822238 -457.331426) (xy 526.868889 -457.211007) (xy 526.922864 -457.093688)
			(xy 526.983959 -456.979914) (xy 527.051942 -456.870117) (xy 527.126556 -456.764714) (xy 527.207517 -456.664104)
			(xy 527.294517 -456.568669) (xy 527.387228 -456.47877) (xy 527.485298 -456.394749) (xy 527.588353 -456.316925)
			(xy 527.696004 -456.245593) (xy 527.807843 -456.181023) (xy 527.923444 -456.123461) (xy 528.042369 -456.073124)
			(xy 528.164168 -456.030204) (xy 528.288378 -455.994863) (xy 528.414527 -455.967236) (xy 528.542139 -455.947427)
			(xy 528.670728 -455.935511) (xy 528.799806 -455.931535) (xy 528.928884 -455.935511) (xy 529.057473 -455.947427)
			(xy 529.185085 -455.967236) (xy 529.311234 -455.994863) (xy 529.435444 -456.030204) (xy 529.557243 -456.073124)
			(xy 529.676168 -456.123461) (xy 529.791769 -456.181023) (xy 529.903608 -456.245593) (xy 530.011259 -456.316925)
			(xy 530.114314 -456.394749) (xy 530.212384 -456.47877) (xy 530.305095 -456.568669) (xy 530.392095 -456.664104)
			(xy 530.473056 -456.764714) (xy 530.54767 -456.870117) (xy 530.615653 -456.979914) (xy 530.676748 -457.093688)
			(xy 530.730723 -457.211007) (xy 530.777374 -457.331426) (xy 530.816523 -457.454489) (xy 530.848022 -457.579728)
			(xy 530.871751 -457.706669) (xy 530.887621 -457.834829) (xy 530.895571 -457.963724) (xy 530.896068 -458.028294)
			(xy 530.895571 -458.092864) (xy 530.887621 -458.221759) (xy 530.871751 -458.349919) (xy 530.848022 -458.47686)
			(xy 530.816523 -458.602099) (xy 530.777374 -458.725162) (xy 530.730723 -458.845581) (xy 530.676748 -458.9629)
			(xy 530.615653 -459.076674) (xy 530.54767 -459.186471) (xy 530.473056 -459.291874) (xy 530.392095 -459.392484)
			(xy 530.305095 -459.487919) (xy 530.212384 -459.577818) (xy 530.114314 -459.661839) (xy 530.011259 -459.739663)
			(xy 529.903608 -459.810995) (xy 529.791769 -459.875565) (xy 529.676168 -459.933127) (xy 529.557243 -459.983464)
			(xy 529.435444 -460.026384) (xy 529.311234 -460.061725) (xy 529.185085 -460.089352) (xy 529.057473 -460.109161)
			(xy 528.928884 -460.121077) (xy 528.799806 -460.125054) (xy 528.670728 -460.121077) (xy 528.542139 -460.109161)
			(xy 528.414527 -460.089352) (xy 528.288378 -460.061725) (xy 528.164168 -460.026384) (xy 528.042369 -459.983464)
			(xy 527.923444 -459.933127) (xy 527.807843 -459.875565) (xy 527.696004 -459.810995) (xy 527.588353 -459.739663)
			(xy 527.485298 -459.661839) (xy 527.387228 -459.577818) (xy 527.294517 -459.487919) (xy 527.207517 -459.392484)
			(xy 527.126556 -459.291874) (xy 527.051942 -459.186471) (xy 526.983959 -459.076674) (xy 526.922864 -458.9629)
			(xy 526.868889 -458.845581) (xy 526.822238 -458.725162) (xy 526.783089 -458.602099) (xy 526.75159 -458.47686)
			(xy 526.727861 -458.349919) (xy 526.711991 -458.221759) (xy 526.704041 -458.092864) (xy 474.308932 -458.092864)
			(xy 474.308932 -461.028288) (xy 474.30944 -461.084058) (xy 474.317775 -461.195285) (xy 474.334398 -461.305579)
			(xy 474.359217 -461.414322) (xy 474.392093 -461.520906) (xy 474.432843 -461.624735) (xy 474.481238 -461.725228)
			(xy 474.537007 -461.821824) (xy 474.599839 -461.913982) (xy 474.669383 -462.001187) (xy 474.745248 -462.082952)
			(xy 474.827013 -462.158817) (xy 474.914218 -462.228361) (xy 475.006376 -462.291193) (xy 475.102972 -462.346962)
			(xy 475.203465 -462.395357) (xy 475.307294 -462.436107) (xy 475.413878 -462.468983) (xy 475.522621 -462.493802)
			(xy 475.632915 -462.510425) (xy 475.744142 -462.51876) (xy 475.799912 -462.519268)
		)
		(stroke
			(width 0)
			(type solid)
		)
		(fill yes)
		(layer "In12.Cu")
		(net "T1_GND")
	)
	(gr_poly
		(pts
			(xy 255.800098 -33.611058) (xy 255.832245 -33.610555) (xy 255.89599 -33.602163) (xy 255.958093 -33.585522)
			(xy 256.017493 -33.560917) (xy 256.073173 -33.528769) (xy 256.124181 -33.489628) (xy 256.169643 -33.444164)
			(xy 256.208781 -33.393155) (xy 256.240927 -33.337473) (xy 256.265529 -33.278072) (xy 256.282167 -33.215968)
			(xy 256.290557 -33.152223) (xy 256.29108 -33.120076) (xy 256.29108 -11.780012) (xy 256.291564 -11.709629)
			(xy 256.299456 -11.569085) (xy 256.315217 -11.429205) (xy 256.338795 -11.290428) (xy 256.370118 -11.153191)
			(xy 256.409086 -11.017927) (xy 256.455577 -10.885061) (xy 256.509445 -10.75501) (xy 256.570521 -10.628184)
			(xy 256.638611 -10.504983) (xy 256.713502 -10.385793) (xy 256.794959 -10.27099) (xy 256.882724 -10.160934)
			(xy 256.976523 -10.055973) (xy 257.076059 -9.956436) (xy 257.181019 -9.862637) (xy 257.291074 -9.774871)
			(xy 257.405876 -9.693414) (xy 257.525065 -9.618521) (xy 257.648266 -9.55043) (xy 257.775092 -9.489354)
			(xy 257.905142 -9.435484) (xy 258.038008 -9.388992) (xy 258.173272 -9.350023) (xy 258.310508 -9.318699)
			(xy 258.449285 -9.295119) (xy 258.589165 -9.279358) (xy 258.729709 -9.271465) (xy 258.800092 -9.271)
			(xy 383.601976 -9.271) (xy 383.657746 -9.270492) (xy 383.768975 -9.262159) (xy 383.87927 -9.245536)
			(xy 383.988015 -9.220718) (xy 384.094601 -9.187842) (xy 384.198432 -9.147093) (xy 384.298927 -9.098699)
			(xy 384.395525 -9.04293) (xy 384.487685 -8.980099) (xy 384.574892 -8.910555) (xy 384.656659 -8.83469)
			(xy 384.732527 -8.752926) (xy 384.802073 -8.665721) (xy 384.864907 -8.573562) (xy 384.920679 -8.476966)
			(xy 384.969076 -8.376472) (xy 385.009828 -8.272642) (xy 385.042706 -8.166058) (xy 385.067528 -8.057314)
			(xy 385.084154 -7.947019) (xy 385.092491 -7.83579) (xy 385.092956 -7.78002) (xy 385.092956 0.40005)
			(xy 385.093451 0.470432) (xy 385.101346 0.610973) (xy 385.117109 0.750851) (xy 385.14069 0.889625)
			(xy 385.172015 1.026859) (xy 385.210985 1.16212) (xy 385.257478 1.294984) (xy 385.311348 1.425032)
			(xy 385.372424 1.551855) (xy 385.440515 1.675053) (xy 385.515407 1.79424) (xy 385.596863 1.909041)
			(xy 385.684628 2.019094) (xy 385.778426 2.124052) (xy 385.877961 2.223587) (xy 385.98292 2.317383)
			(xy 386.092974 2.405148) (xy 386.207775 2.486603) (xy 386.326962 2.561494) (xy 386.450161 2.629584)
			(xy 386.576985 2.69066) (xy 386.707033 2.744528) (xy 386.839897 2.79102) (xy 386.975158 2.829989)
			(xy 387.112392 2.861313) (xy 387.251166 2.884893) (xy 387.391045 2.900655) (xy 387.531586 2.908549)
			(xy 387.601968 2.909062) (xy 456.202034 2.909062) (xy 456.272416 2.908567) (xy 456.412959 2.900673)
			(xy 456.552838 2.884911) (xy 456.691613 2.861331) (xy 456.828848 2.830006) (xy 456.96411 2.791037)
			(xy 457.096975 2.744544) (xy 457.227024 2.690676) (xy 457.353848 2.6296) (xy 457.477048 2.561509)
			(xy 457.596236 2.486618) (xy 457.711038 2.405161) (xy 457.821092 2.317396) (xy 457.926052 2.223599)
			(xy 458.025588 2.124064) (xy 458.119386 2.019104) (xy 458.207152 1.909051) (xy 458.288609 1.79425)
			(xy 458.363501 1.675062) (xy 458.431592 1.551862) (xy 458.492669 1.425039) (xy 458.546539 1.29499)
			(xy 458.593032 1.162126) (xy 458.632002 1.026863) (xy 458.663327 0.889629) (xy 458.686909 0.750854)
			(xy 458.702672 0.610975) (xy 458.710567 0.470432) (xy 458.711046 0.40005) (xy 458.711046 -4.844596)
			(xy 464.704165 -4.844596) (xy 464.704165 -4.715456) (xy 464.712115 -4.586561) (xy 464.727985 -4.458401)
			(xy 464.751714 -4.33146) (xy 464.783213 -4.206221) (xy 464.822362 -4.083158) (xy 464.869013 -3.962739)
			(xy 464.922988 -3.84542) (xy 464.984083 -3.731646) (xy 465.052066 -3.621849) (xy 465.12668 -3.516446)
			(xy 465.207641 -3.415836) (xy 465.294641 -3.320401) (xy 465.387352 -3.230502) (xy 465.485422 -3.146481)
			(xy 465.588477 -3.068657) (xy 465.696128 -2.997325) (xy 465.807967 -2.932755) (xy 465.923568 -2.875193)
			(xy 466.042493 -2.824856) (xy 466.164292 -2.781936) (xy 466.288502 -2.746595) (xy 466.414651 -2.718968)
			(xy 466.542263 -2.699159) (xy 466.670852 -2.687243) (xy 466.79993 -2.683267) (xy 466.929008 -2.687243)
			(xy 467.057597 -2.699159) (xy 467.185209 -2.718968) (xy 467.311358 -2.746595) (xy 467.435568 -2.781936)
			(xy 467.557367 -2.824856) (xy 467.676292 -2.875193) (xy 467.791893 -2.932755) (xy 467.903732 -2.997325)
			(xy 468.011383 -3.068657) (xy 468.114438 -3.146481) (xy 468.212508 -3.230502) (xy 468.305219 -3.320401)
			(xy 468.392219 -3.415836) (xy 468.47318 -3.516446) (xy 468.547794 -3.621849) (xy 468.615777 -3.731646)
			(xy 468.676872 -3.84542) (xy 468.730847 -3.962739) (xy 468.777498 -4.083158) (xy 468.816647 -4.206221)
			(xy 468.848146 -4.33146) (xy 468.871875 -4.458401) (xy 468.887745 -4.586561) (xy 468.895695 -4.715456)
			(xy 468.896192 -4.780026) (xy 468.895695 -4.844596) (xy 468.887745 -4.973491) (xy 468.871875 -5.101651)
			(xy 468.848146 -5.228592) (xy 468.816647 -5.353831) (xy 468.777498 -5.476894) (xy 468.730847 -5.597313)
			(xy 468.676872 -5.714632) (xy 468.615777 -5.828406) (xy 468.547794 -5.938203) (xy 468.47318 -6.043606)
			(xy 468.392219 -6.144216) (xy 468.305219 -6.239651) (xy 468.212508 -6.32955) (xy 468.114438 -6.413571)
			(xy 468.011383 -6.491395) (xy 467.903732 -6.562727) (xy 467.791893 -6.627297) (xy 467.676292 -6.684859)
			(xy 467.557367 -6.735196) (xy 467.435568 -6.778116) (xy 467.311358 -6.813457) (xy 467.185209 -6.841084)
			(xy 467.057597 -6.860893) (xy 466.929008 -6.872809) (xy 466.79993 -6.876786) (xy 466.670852 -6.872809)
			(xy 466.542263 -6.860893) (xy 466.414651 -6.841084) (xy 466.288502 -6.813457) (xy 466.164292 -6.778116)
			(xy 466.042493 -6.735196) (xy 465.923568 -6.684859) (xy 465.807967 -6.627297) (xy 465.696128 -6.562727)
			(xy 465.588477 -6.491395) (xy 465.485422 -6.413571) (xy 465.387352 -6.32955) (xy 465.294641 -6.239651)
			(xy 465.207641 -6.144216) (xy 465.12668 -6.043606) (xy 465.052066 -5.938203) (xy 464.984083 -5.828406)
			(xy 464.922988 -5.714632) (xy 464.869013 -5.597313) (xy 464.822362 -5.476894) (xy 464.783213 -5.353831)
			(xy 464.751714 -5.228592) (xy 464.727985 -5.101651) (xy 464.712115 -4.973491) (xy 464.704165 -4.844596)
			(xy 458.711046 -4.844596) (xy 458.711046 -7.78002) (xy 458.711555 -7.835789) (xy 458.719892 -7.947014)
			(xy 458.736517 -8.057305) (xy 458.761338 -8.166046) (xy 458.794216 -8.272628) (xy 458.834967 -8.376454)
			(xy 458.883362 -8.476945) (xy 458.939132 -8.573538) (xy 459.001965 -8.665694) (xy 459.071509 -8.752896)
			(xy 459.147375 -8.834658) (xy 459.229138 -8.910521) (xy 459.316343 -8.980062) (xy 459.4085 -9.042892)
			(xy 459.505096 -9.098659) (xy 459.605588 -9.147052) (xy 459.709416 -9.187799) (xy 459.815999 -9.220674)
			(xy 459.92474 -9.245491) (xy 460.035032 -9.262113) (xy 460.146257 -9.270446) (xy 460.202026 -9.271)
			(xy 469.799924 -9.271) (xy 469.855693 -9.270478) (xy 469.966918 -9.262141) (xy 470.07721 -9.245516)
			(xy 470.18595 -9.220695) (xy 470.292532 -9.187817) (xy 470.396359 -9.147067) (xy 470.49685 -9.098672)
			(xy 470.593444 -9.042903) (xy 470.685601 -8.980071) (xy 470.772804 -8.910528) (xy 470.854566 -8.834664)
			(xy 470.930431 -8.752901) (xy 470.999974 -8.665697) (xy 471.062805 -8.573541) (xy 471.118574 -8.476947)
			(xy 471.166969 -8.376455) (xy 471.207719 -8.272628) (xy 471.240596 -8.166046) (xy 471.265416 -8.057306)
			(xy 471.282041 -7.947014) (xy 471.290378 -7.835789) (xy 471.290904 -7.78002) (xy 471.290904 10.40003)
			(xy 471.290381 10.455799) (xy 471.282044 10.567024) (xy 471.265419 10.677315) (xy 471.240598 10.786055)
			(xy 471.20772 10.892637) (xy 471.16697 10.996464) (xy 471.118574 11.096955) (xy 471.062805 11.193548)
			(xy 470.999973 11.285705) (xy 470.930431 11.372908) (xy 470.854566 11.45467) (xy 470.772803 11.530534)
			(xy 470.6856 11.600077) (xy 470.593443 11.662908) (xy 470.49685 11.718677) (xy 470.396358 11.767072)
			(xy 470.292531 11.807822) (xy 470.18595 11.840699) (xy 470.077209 11.86552) (xy 469.966918 11.882145)
			(xy 469.855693 11.890482) (xy 469.799924 11.89101) (xy 1.999996 11.89101) (xy 1.944227 11.890488)
			(xy 1.833001 11.882153) (xy 1.722709 11.865529) (xy 1.613968 11.840709) (xy 1.507385 11.807832) (xy 1.403558 11.767083)
			(xy 1.303066 11.718688) (xy 1.206471 11.662919) (xy 1.114314 11.600087) (xy 1.027111 11.530545) (xy 0.945348 11.454679)
			(xy 0.869483 11.372916) (xy 0.79994 11.285712) (xy 0.737109 11.193555) (xy 0.68134 11.096961) (xy 0.632946 10.996469)
			(xy 0.592196 10.892641) (xy 0.55932 10.786058) (xy 0.534501 10.677317) (xy 0.517877 10.567025) (xy 0.509541 10.455799)
			(xy 0.509016 10.40003) (xy 0.509016 9.916973) (xy 385.651997 9.916973) (xy 385.651997 10.002723)
			(xy 385.659909 10.088106) (xy 385.675665 10.172396) (xy 385.699132 10.254872) (xy 385.730108 10.334831)
			(xy 385.76833 10.411591) (xy 385.813471 10.484497) (xy 385.865147 10.552926) (xy 385.922916 10.616296)
			(xy 385.986286 10.674065) (xy 386.054715 10.725741) (xy 386.127621 10.770882) (xy 386.204381 10.809104)
			(xy 386.28434 10.84008) (xy 386.366816 10.863547) (xy 386.451106 10.879303) (xy 386.536489 10.887215)
			(xy 386.622239 10.887215) (xy 386.707622 10.879303) (xy 386.791912 10.863547) (xy 386.874388 10.84008)
			(xy 386.954347 10.809104) (xy 387.031107 10.770882) (xy 387.104013 10.725741) (xy 387.172442 10.674065)
			(xy 387.235812 10.616296) (xy 387.293581 10.552926) (xy 387.345257 10.484497) (xy 387.390398 10.411591)
			(xy 387.42862 10.334831) (xy 387.459596 10.254872) (xy 387.483063 10.172396) (xy 387.498819 10.088106)
			(xy 387.506731 10.002723) (xy 387.507226 9.959848) (xy 387.506731 9.916973) (xy 392.001997 9.916973)
			(xy 392.001997 10.002723) (xy 392.009909 10.088106) (xy 392.025665 10.172396) (xy 392.049132 10.254872)
			(xy 392.080108 10.334831) (xy 392.11833 10.411591) (xy 392.163471 10.484497) (xy 392.215147 10.552926)
			(xy 392.272916 10.616296) (xy 392.336286 10.674065) (xy 392.404715 10.725741) (xy 392.477621 10.770882)
			(xy 392.554381 10.809104) (xy 392.63434 10.84008) (xy 392.716816 10.863547) (xy 392.801106 10.879303)
			(xy 392.886489 10.887215) (xy 392.972239 10.887215) (xy 393.057622 10.879303) (xy 393.141912 10.863547)
			(xy 393.224388 10.84008) (xy 393.304347 10.809104) (xy 393.381107 10.770882) (xy 393.454013 10.725741)
			(xy 393.522442 10.674065) (xy 393.585812 10.616296) (xy 393.643581 10.552926) (xy 393.695257 10.484497)
			(xy 393.740398 10.411591) (xy 393.77862 10.334831) (xy 393.809596 10.254872) (xy 393.833063 10.172396)
			(xy 393.848819 10.088106) (xy 393.856731 10.002723) (xy 393.857226 9.959848) (xy 393.856731 9.916973)
			(xy 436.390783 9.916973) (xy 436.390783 10.002723) (xy 436.398695 10.088106) (xy 436.414451 10.172396)
			(xy 436.437918 10.254872) (xy 436.468894 10.334831) (xy 436.507116 10.411591) (xy 436.552257 10.484497)
			(xy 436.603933 10.552926) (xy 436.661702 10.616296) (xy 436.725072 10.674065) (xy 436.793501 10.725741)
			(xy 436.866407 10.770882) (xy 436.943167 10.809104) (xy 437.023126 10.84008) (xy 437.105602 10.863547)
			(xy 437.189892 10.879303) (xy 437.275275 10.887215) (xy 437.361025 10.887215) (xy 437.446408 10.879303)
			(xy 437.530698 10.863547) (xy 437.613174 10.84008) (xy 437.693133 10.809104) (xy 437.769893 10.770882)
			(xy 437.842799 10.725741) (xy 437.911228 10.674065) (xy 437.974598 10.616296) (xy 438.032367 10.552926)
			(xy 438.084043 10.484497) (xy 438.129184 10.411591) (xy 438.167406 10.334831) (xy 438.198382 10.254872)
			(xy 438.221849 10.172396) (xy 438.237605 10.088106) (xy 438.245517 10.002723) (xy 438.246012 9.959848)
			(xy 438.245517 9.916973) (xy 442.740783 9.916973) (xy 442.740783 10.002723) (xy 442.748695 10.088106)
			(xy 442.764451 10.172396) (xy 442.787918 10.254872) (xy 442.818894 10.334831) (xy 442.857116 10.411591)
			(xy 442.902257 10.484497) (xy 442.953933 10.552926) (xy 443.011702 10.616296) (xy 443.075072 10.674065)
			(xy 443.143501 10.725741) (xy 443.216407 10.770882) (xy 443.293167 10.809104) (xy 443.373126 10.84008)
			(xy 443.455602 10.863547) (xy 443.539892 10.879303) (xy 443.625275 10.887215) (xy 443.711025 10.887215)
			(xy 443.796408 10.879303) (xy 443.880698 10.863547) (xy 443.963174 10.84008) (xy 444.043133 10.809104)
			(xy 444.119893 10.770882) (xy 444.192799 10.725741) (xy 444.261228 10.674065) (xy 444.324598 10.616296)
			(xy 444.382367 10.552926) (xy 444.434043 10.484497) (xy 444.479184 10.411591) (xy 444.517406 10.334831)
			(xy 444.548382 10.254872) (xy 444.571849 10.172396) (xy 444.587605 10.088106) (xy 444.595517 10.002723)
			(xy 444.596012 9.959848) (xy 444.595517 9.916973) (xy 444.587605 9.83159) (xy 444.571849 9.7473)
			(xy 444.548382 9.664824) (xy 444.517406 9.584865) (xy 444.479184 9.508105) (xy 444.434043 9.435199)
			(xy 444.382367 9.36677) (xy 444.324598 9.3034) (xy 444.261228 9.245631) (xy 444.192799 9.193955)
			(xy 444.119893 9.148814) (xy 444.043133 9.110592) (xy 443.963174 9.079616) (xy 443.880698 9.056149)
			(xy 443.796408 9.040393) (xy 443.711025 9.032481) (xy 443.625275 9.032481) (xy 443.539892 9.040393)
			(xy 443.455602 9.056149) (xy 443.373126 9.079616) (xy 443.293167 9.110592) (xy 443.216407 9.148814)
			(xy 443.143501 9.193955) (xy 443.075072 9.245631) (xy 443.011702 9.3034) (xy 442.953933 9.36677)
			(xy 442.902257 9.435199) (xy 442.857116 9.508105) (xy 442.818894 9.584865) (xy 442.787918 9.664824)
			(xy 442.764451 9.7473) (xy 442.748695 9.83159) (xy 442.740783 9.916973) (xy 438.245517 9.916973)
			(xy 438.237605 9.83159) (xy 438.221849 9.7473) (xy 438.198382 9.664824) (xy 438.167406 9.584865)
			(xy 438.129184 9.508105) (xy 438.084043 9.435199) (xy 438.032367 9.36677) (xy 437.974598 9.3034)
			(xy 437.911228 9.245631) (xy 437.842799 9.193955) (xy 437.769893 9.148814) (xy 437.693133 9.110592)
			(xy 437.613174 9.079616) (xy 437.530698 9.056149) (xy 437.446408 9.040393) (xy 437.361025 9.032481)
			(xy 437.275275 9.032481) (xy 437.189892 9.040393) (xy 437.105602 9.056149) (xy 437.023126 9.079616)
			(xy 436.943167 9.110592) (xy 436.866407 9.148814) (xy 436.793501 9.193955) (xy 436.725072 9.245631)
			(xy 436.661702 9.3034) (xy 436.603933 9.36677) (xy 436.552257 9.435199) (xy 436.507116 9.508105)
			(xy 436.468894 9.584865) (xy 436.437918 9.664824) (xy 436.414451 9.7473) (xy 436.398695 9.83159)
			(xy 436.390783 9.916973) (xy 393.856731 9.916973) (xy 393.848819 9.83159) (xy 393.833063 9.7473)
			(xy 393.809596 9.664824) (xy 393.77862 9.584865) (xy 393.740398 9.508105) (xy 393.695257 9.435199)
			(xy 393.643581 9.36677) (xy 393.585812 9.3034) (xy 393.522442 9.245631) (xy 393.454013 9.193955)
			(xy 393.381107 9.148814) (xy 393.304347 9.110592) (xy 393.224388 9.079616) (xy 393.141912 9.056149)
			(xy 393.057622 9.040393) (xy 392.972239 9.032481) (xy 392.886489 9.032481) (xy 392.801106 9.040393)
			(xy 392.716816 9.056149) (xy 392.63434 9.079616) (xy 392.554381 9.110592) (xy 392.477621 9.148814)
			(xy 392.404715 9.193955) (xy 392.336286 9.245631) (xy 392.272916 9.3034) (xy 392.215147 9.36677)
			(xy 392.163471 9.435199) (xy 392.11833 9.508105) (xy 392.080108 9.584865) (xy 392.049132 9.664824)
			(xy 392.025665 9.7473) (xy 392.009909 9.83159) (xy 392.001997 9.916973) (xy 387.506731 9.916973)
			(xy 387.498819 9.83159) (xy 387.483063 9.7473) (xy 387.459596 9.664824) (xy 387.42862 9.584865) (xy 387.390398 9.508105)
			(xy 387.345257 9.435199) (xy 387.293581 9.36677) (xy 387.235812 9.3034) (xy 387.172442 9.245631)
			(xy 387.104013 9.193955) (xy 387.031107 9.148814) (xy 386.954347 9.110592) (xy 386.874388 9.079616)
			(xy 386.791912 9.056149) (xy 386.707622 9.040393) (xy 386.622239 9.032481) (xy 386.536489 9.032481)
			(xy 386.451106 9.040393) (xy 386.366816 9.056149) (xy 386.28434 9.079616) (xy 386.204381 9.110592)
			(xy 386.127621 9.148814) (xy 386.054715 9.193955) (xy 385.986286 9.245631) (xy 385.922916 9.3034)
			(xy 385.865147 9.36677) (xy 385.813471 9.435199) (xy 385.76833 9.508105) (xy 385.730108 9.584865)
			(xy 385.699132 9.664824) (xy 385.675665 9.7473) (xy 385.659909 9.83159) (xy 385.651997 9.916973)
			(xy 0.509016 9.916973) (xy 0.509016 7.335466) (xy 2.904225 7.335466) (xy 2.904225 7.464606) (xy 2.912175 7.593501)
			(xy 2.928045 7.721661) (xy 2.951774 7.848602) (xy 2.983273 7.973841) (xy 3.022422 8.096904) (xy 3.069073 8.217323)
			(xy 3.123048 8.334642) (xy 3.184143 8.448416) (xy 3.252126 8.558213) (xy 3.32674 8.663616) (xy 3.407701 8.764226)
			(xy 3.494701 8.859661) (xy 3.587412 8.94956) (xy 3.685482 9.033581) (xy 3.788537 9.111405) (xy 3.896188 9.182737)
			(xy 4.008027 9.247307) (xy 4.123628 9.304869) (xy 4.242553 9.355206) (xy 4.364352 9.398126) (xy 4.488562 9.433467)
			(xy 4.614711 9.461094) (xy 4.742323 9.480903) (xy 4.870912 9.492819) (xy 4.99999 9.496796) (xy 5.129068 9.492819)
			(xy 5.257657 9.480903) (xy 5.385269 9.461094) (xy 5.511418 9.433467) (xy 5.635628 9.398126) (xy 5.757427 9.355206)
			(xy 5.876352 9.304869) (xy 5.991953 9.247307) (xy 6.103792 9.182737) (xy 6.211443 9.111405) (xy 6.314498 9.033581)
			(xy 6.412568 8.94956) (xy 6.505279 8.859661) (xy 6.51416 8.849919) (xy 208.661241 8.849919) (xy 208.661241 8.935669)
			(xy 208.669153 9.021052) (xy 208.684909 9.105342) (xy 208.708376 9.187818) (xy 208.739352 9.267777)
			(xy 208.777574 9.344537) (xy 208.822715 9.417443) (xy 208.874391 9.485872) (xy 208.93216 9.549242)
			(xy 208.99553 9.607011) (xy 209.063959 9.658687) (xy 209.136865 9.703828) (xy 209.213625 9.74205)
			(xy 209.293584 9.773026) (xy 209.37606 9.796493) (xy 209.46035 9.812249) (xy 209.545733 9.820161)
			(xy 209.631483 9.820161) (xy 209.716866 9.812249) (xy 209.801156 9.796493) (xy 209.883632 9.773026)
			(xy 209.963591 9.74205) (xy 210.040351 9.703828) (xy 210.113257 9.658687) (xy 210.181686 9.607011)
			(xy 210.245056 9.549242) (xy 210.302825 9.485872) (xy 210.354501 9.417443) (xy 210.399642 9.344537)
			(xy 210.437864 9.267777) (xy 210.46884 9.187818) (xy 210.492307 9.105342) (xy 210.508063 9.021052)
			(xy 210.515975 8.935669) (xy 210.51647 8.892794) (xy 210.515975 8.849919) (xy 215.011241 8.849919)
			(xy 215.011241 8.935669) (xy 215.019153 9.021052) (xy 215.034909 9.105342) (xy 215.058376 9.187818)
			(xy 215.089352 9.267777) (xy 215.127574 9.344537) (xy 215.172715 9.417443) (xy 215.224391 9.485872)
			(xy 215.28216 9.549242) (xy 215.34553 9.607011) (xy 215.413959 9.658687) (xy 215.486865 9.703828)
			(xy 215.563625 9.74205) (xy 215.643584 9.773026) (xy 215.72606 9.796493) (xy 215.81035 9.812249)
			(xy 215.895733 9.820161) (xy 215.981483 9.820161) (xy 216.066866 9.812249) (xy 216.151156 9.796493)
			(xy 216.233632 9.773026) (xy 216.313591 9.74205) (xy 216.390351 9.703828) (xy 216.463257 9.658687)
			(xy 216.531686 9.607011) (xy 216.595056 9.549242) (xy 216.652825 9.485872) (xy 216.704501 9.417443)
			(xy 216.749642 9.344537) (xy 216.787864 9.267777) (xy 216.81884 9.187818) (xy 216.842307 9.105342)
			(xy 216.858063 9.021052) (xy 216.865975 8.935669) (xy 216.86647 8.892794) (xy 216.865975 8.849919)
			(xy 296.143921 8.849919) (xy 296.143921 8.935669) (xy 296.151833 9.021052) (xy 296.167589 9.105342)
			(xy 296.191056 9.187818) (xy 296.222032 9.267777) (xy 296.260254 9.344537) (xy 296.305395 9.417443)
			(xy 296.357071 9.485872) (xy 296.41484 9.549242) (xy 296.47821 9.607011) (xy 296.546639 9.658687)
			(xy 296.619545 9.703828) (xy 296.696305 9.74205) (xy 296.776264 9.773026) (xy 296.85874 9.796493)
			(xy 296.94303 9.812249) (xy 297.028413 9.820161) (xy 297.114163 9.820161) (xy 297.199546 9.812249)
			(xy 297.283836 9.796493) (xy 297.366312 9.773026) (xy 297.446271 9.74205) (xy 297.523031 9.703828)
			(xy 297.595937 9.658687) (xy 297.664366 9.607011) (xy 297.727736 9.549242) (xy 297.785505 9.485872)
			(xy 297.837181 9.417443) (xy 297.882322 9.344537) (xy 297.920544 9.267777) (xy 297.95152 9.187818)
			(xy 297.974987 9.105342) (xy 297.990743 9.021052) (xy 297.998655 8.935669) (xy 297.99915 8.892794)
			(xy 297.998655 8.849919) (xy 302.493921 8.849919) (xy 302.493921 8.935669) (xy 302.501833 9.021052)
			(xy 302.517589 9.105342) (xy 302.541056 9.187818) (xy 302.572032 9.267777) (xy 302.610254 9.344537)
			(xy 302.655395 9.417443) (xy 302.707071 9.485872) (xy 302.76484 9.549242) (xy 302.82821 9.607011)
			(xy 302.896639 9.658687) (xy 302.969545 9.703828) (xy 303.046305 9.74205) (xy 303.126264 9.773026)
			(xy 303.20874 9.796493) (xy 303.29303 9.812249) (xy 303.378413 9.820161) (xy 303.464163 9.820161)
			(xy 303.549546 9.812249) (xy 303.633836 9.796493) (xy 303.716312 9.773026) (xy 303.796271 9.74205)
			(xy 303.873031 9.703828) (xy 303.945937 9.658687) (xy 304.014366 9.607011) (xy 304.077736 9.549242)
			(xy 304.135505 9.485872) (xy 304.187181 9.417443) (xy 304.232322 9.344537) (xy 304.270544 9.267777)
			(xy 304.30152 9.187818) (xy 304.324987 9.105342) (xy 304.340743 9.021052) (xy 304.348655 8.935669)
			(xy 304.34915 8.892794) (xy 304.348655 8.849919) (xy 311.155321 8.849919) (xy 311.155321 8.935669)
			(xy 311.163233 9.021052) (xy 311.178989 9.105342) (xy 311.202456 9.187818) (xy 311.233432 9.267777)
			(xy 311.271654 9.344537) (xy 311.316795 9.417443) (xy 311.368471 9.485872) (xy 311.42624 9.549242)
			(xy 311.48961 9.607011) (xy 311.558039 9.658687) (xy 311.630945 9.703828) (xy 311.707705 9.74205)
			(xy 311.787664 9.773026) (xy 311.87014 9.796493) (xy 311.95443 9.812249) (xy 312.039813 9.820161)
			(xy 312.125563 9.820161) (xy 312.210946 9.812249) (xy 312.295236 9.796493) (xy 312.377712 9.773026)
			(xy 312.457671 9.74205) (xy 312.534431 9.703828) (xy 312.607337 9.658687) (xy 312.675766 9.607011)
			(xy 312.739136 9.549242) (xy 312.796905 9.485872) (xy 312.848581 9.417443) (xy 312.893722 9.344537)
			(xy 312.931944 9.267777) (xy 312.96292 9.187818) (xy 312.986387 9.105342) (xy 313.002143 9.021052)
			(xy 313.010055 8.935669) (xy 313.01055 8.892794) (xy 313.010055 8.849919) (xy 317.505321 8.849919)
			(xy 317.505321 8.935669) (xy 317.513233 9.021052) (xy 317.528989 9.105342) (xy 317.552456 9.187818)
			(xy 317.583432 9.267777) (xy 317.621654 9.344537) (xy 317.666795 9.417443) (xy 317.718471 9.485872)
			(xy 317.77624 9.549242) (xy 317.83961 9.607011) (xy 317.908039 9.658687) (xy 317.980945 9.703828)
			(xy 318.057705 9.74205) (xy 318.137664 9.773026) (xy 318.22014 9.796493) (xy 318.30443 9.812249)
			(xy 318.389813 9.820161) (xy 318.475563 9.820161) (xy 318.560946 9.812249) (xy 318.645236 9.796493)
			(xy 318.727712 9.773026) (xy 318.807671 9.74205) (xy 318.884431 9.703828) (xy 318.957337 9.658687)
			(xy 319.025766 9.607011) (xy 319.089136 9.549242) (xy 319.146905 9.485872) (xy 319.198581 9.417443)
			(xy 319.243722 9.344537) (xy 319.281944 9.267777) (xy 319.31292 9.187818) (xy 319.336387 9.105342)
			(xy 319.352143 9.021052) (xy 319.360055 8.935669) (xy 319.36055 8.892794) (xy 319.360055 8.849919)
			(xy 361.894107 8.849919) (xy 361.894107 8.935669) (xy 361.902019 9.021052) (xy 361.917775 9.105342)
			(xy 361.941242 9.187818) (xy 361.972218 9.267777) (xy 362.01044 9.344537) (xy 362.055581 9.417443)
			(xy 362.107257 9.485872) (xy 362.165026 9.549242) (xy 362.228396 9.607011) (xy 362.296825 9.658687)
			(xy 362.369731 9.703828) (xy 362.446491 9.74205) (xy 362.52645 9.773026) (xy 362.608926 9.796493)
			(xy 362.693216 9.812249) (xy 362.778599 9.820161) (xy 362.864349 9.820161) (xy 362.949732 9.812249)
			(xy 363.034022 9.796493) (xy 363.116498 9.773026) (xy 363.196457 9.74205) (xy 363.273217 9.703828)
			(xy 363.346123 9.658687) (xy 363.414552 9.607011) (xy 363.477922 9.549242) (xy 363.535691 9.485872)
			(xy 363.587367 9.417443) (xy 363.632508 9.344537) (xy 363.67073 9.267777) (xy 363.701706 9.187818)
			(xy 363.725173 9.105342) (xy 363.740929 9.021052) (xy 363.748841 8.935669) (xy 363.749336 8.892794)
			(xy 363.748841 8.849919) (xy 368.244107 8.849919) (xy 368.244107 8.935669) (xy 368.252019 9.021052)
			(xy 368.267775 9.105342) (xy 368.291242 9.187818) (xy 368.322218 9.267777) (xy 368.36044 9.344537)
			(xy 368.405581 9.417443) (xy 368.457257 9.485872) (xy 368.515026 9.549242) (xy 368.578396 9.607011)
			(xy 368.646825 9.658687) (xy 368.719731 9.703828) (xy 368.796491 9.74205) (xy 368.87645 9.773026)
			(xy 368.958926 9.796493) (xy 369.043216 9.812249) (xy 369.128599 9.820161) (xy 369.214349 9.820161)
			(xy 369.299732 9.812249) (xy 369.384022 9.796493) (xy 369.466498 9.773026) (xy 369.546457 9.74205)
			(xy 369.623217 9.703828) (xy 369.696123 9.658687) (xy 369.764552 9.607011) (xy 369.827922 9.549242)
			(xy 369.885691 9.485872) (xy 369.937367 9.417443) (xy 369.982508 9.344537) (xy 370.02073 9.267777)
			(xy 370.051706 9.187818) (xy 370.075173 9.105342) (xy 370.090929 9.021052) (xy 370.098841 8.935669)
			(xy 370.099336 8.892794) (xy 370.098841 8.849919) (xy 370.090929 8.764536) (xy 370.075173 8.680246)
			(xy 370.051706 8.59777) (xy 370.02073 8.517811) (xy 369.982508 8.441051) (xy 369.937367 8.368145)
			(xy 369.885691 8.299716) (xy 369.827922 8.236346) (xy 369.764552 8.178577) (xy 369.696123 8.126901)
			(xy 369.623217 8.08176) (xy 369.546457 8.043538) (xy 369.466498 8.012562) (xy 369.384022 7.989095)
			(xy 369.299732 7.973339) (xy 369.214349 7.965427) (xy 369.128599 7.965427) (xy 369.043216 7.973339)
			(xy 368.958926 7.989095) (xy 368.87645 8.012562) (xy 368.796491 8.043538) (xy 368.719731 8.08176)
			(xy 368.646825 8.126901) (xy 368.578396 8.178577) (xy 368.515026 8.236346) (xy 368.457257 8.299716)
			(xy 368.405581 8.368145) (xy 368.36044 8.441051) (xy 368.322218 8.517811) (xy 368.291242 8.59777)
			(xy 368.267775 8.680246) (xy 368.252019 8.764536) (xy 368.244107 8.849919) (xy 363.748841 8.849919)
			(xy 363.740929 8.764536) (xy 363.725173 8.680246) (xy 363.701706 8.59777) (xy 363.67073 8.517811)
			(xy 363.632508 8.441051) (xy 363.587367 8.368145) (xy 363.535691 8.299716) (xy 363.477922 8.236346)
			(xy 363.414552 8.178577) (xy 363.346123 8.126901) (xy 363.273217 8.08176) (xy 363.196457 8.043538)
			(xy 363.116498 8.012562) (xy 363.034022 7.989095) (xy 362.949732 7.973339) (xy 362.864349 7.965427)
			(xy 362.778599 7.965427) (xy 362.693216 7.973339) (xy 362.608926 7.989095) (xy 362.52645 8.012562)
			(xy 362.446491 8.043538) (xy 362.369731 8.08176) (xy 362.296825 8.126901) (xy 362.228396 8.178577)
			(xy 362.165026 8.236346) (xy 362.107257 8.299716) (xy 362.055581 8.368145) (xy 362.01044 8.441051)
			(xy 361.972218 8.517811) (xy 361.941242 8.59777) (xy 361.917775 8.680246) (xy 361.902019 8.764536)
			(xy 361.894107 8.849919) (xy 319.360055 8.849919) (xy 319.352143 8.764536) (xy 319.336387 8.680246)
			(xy 319.31292 8.59777) (xy 319.281944 8.517811) (xy 319.243722 8.441051) (xy 319.198581 8.368145)
			(xy 319.146905 8.299716) (xy 319.089136 8.236346) (xy 319.025766 8.178577) (xy 318.957337 8.126901)
			(xy 318.884431 8.08176) (xy 318.807671 8.043538) (xy 318.727712 8.012562) (xy 318.645236 7.989095)
			(xy 318.560946 7.973339) (xy 318.475563 7.965427) (xy 318.389813 7.965427) (xy 318.30443 7.973339)
			(xy 318.22014 7.989095) (xy 318.137664 8.012562) (xy 318.057705 8.043538) (xy 317.980945 8.08176)
			(xy 317.908039 8.126901) (xy 317.83961 8.178577) (xy 317.77624 8.236346) (xy 317.718471 8.299716)
			(xy 317.666795 8.368145) (xy 317.621654 8.441051) (xy 317.583432 8.517811) (xy 317.552456 8.59777)
			(xy 317.528989 8.680246) (xy 317.513233 8.764536) (xy 317.505321 8.849919) (xy 313.010055 8.849919)
			(xy 313.002143 8.764536) (xy 312.986387 8.680246) (xy 312.96292 8.59777) (xy 312.931944 8.517811)
			(xy 312.893722 8.441051) (xy 312.848581 8.368145) (xy 312.796905 8.299716) (xy 312.739136 8.236346)
			(xy 312.675766 8.178577) (xy 312.607337 8.126901) (xy 312.534431 8.08176) (xy 312.457671 8.043538)
			(xy 312.377712 8.012562) (xy 312.295236 7.989095) (xy 312.210946 7.973339) (xy 312.125563 7.965427)
			(xy 312.039813 7.965427) (xy 311.95443 7.973339) (xy 311.87014 7.989095) (xy 311.787664 8.012562)
			(xy 311.707705 8.043538) (xy 311.630945 8.08176) (xy 311.558039 8.126901) (xy 311.48961 8.178577)
			(xy 311.42624 8.236346) (xy 311.368471 8.299716) (xy 311.316795 8.368145) (xy 311.271654 8.441051)
			(xy 311.233432 8.517811) (xy 311.202456 8.59777) (xy 311.178989 8.680246) (xy 311.163233 8.764536)
			(xy 311.155321 8.849919) (xy 304.348655 8.849919) (xy 304.340743 8.764536) (xy 304.324987 8.680246)
			(xy 304.30152 8.59777) (xy 304.270544 8.517811) (xy 304.232322 8.441051) (xy 304.187181 8.368145)
			(xy 304.135505 8.299716) (xy 304.077736 8.236346) (xy 304.014366 8.178577) (xy 303.945937 8.126901)
			(xy 303.873031 8.08176) (xy 303.796271 8.043538) (xy 303.716312 8.012562) (xy 303.633836 7.989095)
			(xy 303.549546 7.973339) (xy 303.464163 7.965427) (xy 303.378413 7.965427) (xy 303.29303 7.973339)
			(xy 303.20874 7.989095) (xy 303.126264 8.012562) (xy 303.046305 8.043538) (xy 302.969545 8.08176)
			(xy 302.896639 8.126901) (xy 302.82821 8.178577) (xy 302.76484 8.236346) (xy 302.707071 8.299716)
			(xy 302.655395 8.368145) (xy 302.610254 8.441051) (xy 302.572032 8.517811) (xy 302.541056 8.59777)
			(xy 302.517589 8.680246) (xy 302.501833 8.764536) (xy 302.493921 8.849919) (xy 297.998655 8.849919)
			(xy 297.990743 8.764536) (xy 297.974987 8.680246) (xy 297.95152 8.59777) (xy 297.920544 8.517811)
			(xy 297.882322 8.441051) (xy 297.837181 8.368145) (xy 297.785505 8.299716) (xy 297.727736 8.236346)
			(xy 297.664366 8.178577) (xy 297.595937 8.126901) (xy 297.523031 8.08176) (xy 297.446271 8.043538)
			(xy 297.366312 8.012562) (xy 297.283836 7.989095) (xy 297.199546 7.973339) (xy 297.114163 7.965427)
			(xy 297.028413 7.965427) (xy 296.94303 7.973339) (xy 296.85874 7.989095) (xy 296.776264 8.012562)
			(xy 296.696305 8.043538) (xy 296.619545 8.08176) (xy 296.546639 8.126901) (xy 296.47821 8.178577)
			(xy 296.41484 8.236346) (xy 296.357071 8.299716) (xy 296.305395 8.368145) (xy 296.260254 8.441051)
			(xy 296.222032 8.517811) (xy 296.191056 8.59777) (xy 296.167589 8.680246) (xy 296.151833 8.764536)
			(xy 296.143921 8.849919) (xy 216.865975 8.849919) (xy 216.858063 8.764536) (xy 216.842307 8.680246)
			(xy 216.81884 8.59777) (xy 216.787864 8.517811) (xy 216.749642 8.441051) (xy 216.704501 8.368145)
			(xy 216.652825 8.299716) (xy 216.595056 8.236346) (xy 216.531686 8.178577) (xy 216.463257 8.126901)
			(xy 216.390351 8.08176) (xy 216.313591 8.043538) (xy 216.233632 8.012562) (xy 216.151156 7.989095)
			(xy 216.066866 7.973339) (xy 215.981483 7.965427) (xy 215.895733 7.965427) (xy 215.81035 7.973339)
			(xy 215.72606 7.989095) (xy 215.643584 8.012562) (xy 215.563625 8.043538) (xy 215.486865 8.08176)
			(xy 215.413959 8.126901) (xy 215.34553 8.178577) (xy 215.28216 8.236346) (xy 215.224391 8.299716)
			(xy 215.172715 8.368145) (xy 215.127574 8.441051) (xy 215.089352 8.517811) (xy 215.058376 8.59777)
			(xy 215.034909 8.680246) (xy 215.019153 8.764536) (xy 215.011241 8.849919) (xy 210.515975 8.849919)
			(xy 210.508063 8.764536) (xy 210.492307 8.680246) (xy 210.46884 8.59777) (xy 210.437864 8.517811)
			(xy 210.399642 8.441051) (xy 210.354501 8.368145) (xy 210.302825 8.299716) (xy 210.245056 8.236346)
			(xy 210.181686 8.178577) (xy 210.113257 8.126901) (xy 210.040351 8.08176) (xy 209.963591 8.043538)
			(xy 209.883632 8.012562) (xy 209.801156 7.989095) (xy 209.716866 7.973339) (xy 209.631483 7.965427)
			(xy 209.545733 7.965427) (xy 209.46035 7.973339) (xy 209.37606 7.989095) (xy 209.293584 8.012562)
			(xy 209.213625 8.043538) (xy 209.136865 8.08176) (xy 209.063959 8.126901) (xy 208.99553 8.178577)
			(xy 208.93216 8.236346) (xy 208.874391 8.299716) (xy 208.822715 8.368145) (xy 208.777574 8.441051)
			(xy 208.739352 8.517811) (xy 208.708376 8.59777) (xy 208.684909 8.680246) (xy 208.669153 8.764536)
			(xy 208.661241 8.849919) (xy 6.51416 8.849919) (xy 6.592279 8.764226) (xy 6.67324 8.663616) (xy 6.747854 8.558213)
			(xy 6.815837 8.448416) (xy 6.876932 8.334642) (xy 6.930907 8.217323) (xy 6.977558 8.096904) (xy 7.016707 7.973841)
			(xy 7.048206 7.848602) (xy 7.071935 7.721661) (xy 7.087805 7.593501) (xy 7.095755 7.464606) (xy 7.096252 7.400036)
			(xy 7.095755 7.335466) (xy 7.092973 7.290359) (xy 93.985575 7.290359) (xy 93.985575 7.376109) (xy 93.993487 7.461492)
			(xy 94.009243 7.545782) (xy 94.03271 7.628258) (xy 94.063686 7.708217) (xy 94.101908 7.784977) (xy 94.147049 7.857883)
			(xy 94.198725 7.926312) (xy 94.256494 7.989682) (xy 94.319864 8.047451) (xy 94.388293 8.099127) (xy 94.461199 8.144268)
			(xy 94.537959 8.18249) (xy 94.617918 8.213466) (xy 94.700394 8.236933) (xy 94.784684 8.252689) (xy 94.870067 8.260601)
			(xy 94.955817 8.260601) (xy 95.0412 8.252689) (xy 95.12549 8.236933) (xy 95.207966 8.213466) (xy 95.287925 8.18249)
			(xy 95.364685 8.144268) (xy 95.437591 8.099127) (xy 95.50602 8.047451) (xy 95.56939 7.989682) (xy 95.627159 7.926312)
			(xy 95.678835 7.857883) (xy 95.723976 7.784977) (xy 95.762198 7.708217) (xy 95.793174 7.628258) (xy 95.816641 7.545782)
			(xy 95.832397 7.461492) (xy 95.840309 7.376109) (xy 95.840804 7.333234) (xy 95.840309 7.290359) (xy 100.335575 7.290359)
			(xy 100.335575 7.376109) (xy 100.343487 7.461492) (xy 100.359243 7.545782) (xy 100.38271 7.628258)
			(xy 100.413686 7.708217) (xy 100.451908 7.784977) (xy 100.497049 7.857883) (xy 100.548725 7.926312)
			(xy 100.606494 7.989682) (xy 100.669864 8.047451) (xy 100.738293 8.099127) (xy 100.811199 8.144268)
			(xy 100.887959 8.18249) (xy 100.967918 8.213466) (xy 101.050394 8.236933) (xy 101.134684 8.252689)
			(xy 101.220067 8.260601) (xy 101.305817 8.260601) (xy 101.3912 8.252689) (xy 101.47549 8.236933)
			(xy 101.557966 8.213466) (xy 101.637925 8.18249) (xy 101.714685 8.144268) (xy 101.787591 8.099127)
			(xy 101.85602 8.047451) (xy 101.91939 7.989682) (xy 101.977159 7.926312) (xy 102.028835 7.857883)
			(xy 102.073976 7.784977) (xy 102.112198 7.708217) (xy 102.143174 7.628258) (xy 102.166641 7.545782)
			(xy 102.182397 7.461492) (xy 102.190309 7.376109) (xy 102.190804 7.333234) (xy 102.190309 7.290359)
			(xy 181.468255 7.290359) (xy 181.468255 7.376109) (xy 181.476167 7.461492) (xy 181.491923 7.545782)
			(xy 181.51539 7.628258) (xy 181.546366 7.708217) (xy 181.584588 7.784977) (xy 181.629729 7.857883)
			(xy 181.681405 7.926312) (xy 181.739174 7.989682) (xy 181.802544 8.047451) (xy 181.870973 8.099127)
			(xy 181.943879 8.144268) (xy 182.020639 8.18249) (xy 182.100598 8.213466) (xy 182.183074 8.236933)
			(xy 182.267364 8.252689) (xy 182.352747 8.260601) (xy 182.438497 8.260601) (xy 182.52388 8.252689)
			(xy 182.60817 8.236933) (xy 182.690646 8.213466) (xy 182.770605 8.18249) (xy 182.847365 8.144268)
			(xy 182.920271 8.099127) (xy 182.9887 8.047451) (xy 183.05207 7.989682) (xy 183.109839 7.926312)
			(xy 183.161515 7.857883) (xy 183.206656 7.784977) (xy 183.244878 7.708217) (xy 183.275854 7.628258)
			(xy 183.299321 7.545782) (xy 183.315077 7.461492) (xy 183.322989 7.376109) (xy 183.323484 7.333234)
			(xy 183.322989 7.290359) (xy 187.818255 7.290359) (xy 187.818255 7.376109) (xy 187.826167 7.461492)
			(xy 187.841923 7.545782) (xy 187.86539 7.628258) (xy 187.896366 7.708217) (xy 187.934588 7.784977)
			(xy 187.979729 7.857883) (xy 188.031405 7.926312) (xy 188.089174 7.989682) (xy 188.152544 8.047451)
			(xy 188.220973 8.099127) (xy 188.293879 8.144268) (xy 188.370639 8.18249) (xy 188.450598 8.213466)
			(xy 188.533074 8.236933) (xy 188.617364 8.252689) (xy 188.702747 8.260601) (xy 188.788497 8.260601)
			(xy 188.87388 8.252689) (xy 188.95817 8.236933) (xy 189.040646 8.213466) (xy 189.120605 8.18249)
			(xy 189.197365 8.144268) (xy 189.270271 8.099127) (xy 189.3387 8.047451) (xy 189.40207 7.989682)
			(xy 189.459839 7.926312) (xy 189.511515 7.857883) (xy 189.556656 7.784977) (xy 189.594878 7.708217)
			(xy 189.625854 7.628258) (xy 189.649321 7.545782) (xy 189.665077 7.461492) (xy 189.672989 7.376109)
			(xy 189.673484 7.333234) (xy 189.672989 7.290359) (xy 189.665077 7.204976) (xy 189.649321 7.120686)
			(xy 189.625854 7.03821) (xy 189.594878 6.958251) (xy 189.556656 6.881491) (xy 189.511515 6.808585)
			(xy 189.459839 6.740156) (xy 189.40207 6.676786) (xy 189.3387 6.619017) (xy 189.270271 6.567341)
			(xy 189.197365 6.5222) (xy 189.120605 6.483978) (xy 189.040646 6.453002) (xy 188.95817 6.429535)
			(xy 188.87388 6.413779) (xy 188.788497 6.405867) (xy 188.702747 6.405867) (xy 188.617364 6.413779)
			(xy 188.533074 6.429535) (xy 188.450598 6.453002) (xy 188.370639 6.483978) (xy 188.293879 6.5222)
			(xy 188.220973 6.567341) (xy 188.152544 6.619017) (xy 188.089174 6.676786) (xy 188.031405 6.740156)
			(xy 187.979729 6.808585) (xy 187.934588 6.881491) (xy 187.896366 6.958251) (xy 187.86539 7.03821)
			(xy 187.841923 7.120686) (xy 187.826167 7.204976) (xy 187.818255 7.290359) (xy 183.322989 7.290359)
			(xy 183.315077 7.204976) (xy 183.299321 7.120686) (xy 183.275854 7.03821) (xy 183.244878 6.958251)
			(xy 183.206656 6.881491) (xy 183.161515 6.808585) (xy 183.109839 6.740156) (xy 183.05207 6.676786)
			(xy 182.9887 6.619017) (xy 182.920271 6.567341) (xy 182.847365 6.5222) (xy 182.770605 6.483978) (xy 182.690646 6.453002)
			(xy 182.60817 6.429535) (xy 182.52388 6.413779) (xy 182.438497 6.405867) (xy 182.352747 6.405867)
			(xy 182.267364 6.413779) (xy 182.183074 6.429535) (xy 182.100598 6.453002) (xy 182.020639 6.483978)
			(xy 181.943879 6.5222) (xy 181.870973 6.567341) (xy 181.802544 6.619017) (xy 181.739174 6.676786)
			(xy 181.681405 6.740156) (xy 181.629729 6.808585) (xy 181.584588 6.881491) (xy 181.546366 6.958251)
			(xy 181.51539 7.03821) (xy 181.491923 7.120686) (xy 181.476167 7.204976) (xy 181.468255 7.290359)
			(xy 102.190309 7.290359) (xy 102.182397 7.204976) (xy 102.166641 7.120686) (xy 102.143174 7.03821)
			(xy 102.112198 6.958251) (xy 102.073976 6.881491) (xy 102.028835 6.808585) (xy 101.977159 6.740156)
			(xy 101.91939 6.676786) (xy 101.85602 6.619017) (xy 101.787591 6.567341) (xy 101.714685 6.5222) (xy 101.637925 6.483978)
			(xy 101.557966 6.453002) (xy 101.47549 6.429535) (xy 101.3912 6.413779) (xy 101.305817 6.405867)
			(xy 101.220067 6.405867) (xy 101.134684 6.413779) (xy 101.050394 6.429535) (xy 100.967918 6.453002)
			(xy 100.887959 6.483978) (xy 100.811199 6.5222) (xy 100.738293 6.567341) (xy 100.669864 6.619017)
			(xy 100.606494 6.676786) (xy 100.548725 6.740156) (xy 100.497049 6.808585) (xy 100.451908 6.881491)
			(xy 100.413686 6.958251) (xy 100.38271 7.03821) (xy 100.359243 7.120686) (xy 100.343487 7.204976)
			(xy 100.335575 7.290359) (xy 95.840309 7.290359) (xy 95.832397 7.204976) (xy 95.816641 7.120686)
			(xy 95.793174 7.03821) (xy 95.762198 6.958251) (xy 95.723976 6.881491) (xy 95.678835 6.808585) (xy 95.627159 6.740156)
			(xy 95.56939 6.676786) (xy 95.50602 6.619017) (xy 95.437591 6.567341) (xy 95.364685 6.5222) (xy 95.287925 6.483978)
			(xy 95.207966 6.453002) (xy 95.12549 6.429535) (xy 95.0412 6.413779) (xy 94.955817 6.405867) (xy 94.870067 6.405867)
			(xy 94.784684 6.413779) (xy 94.700394 6.429535) (xy 94.617918 6.453002) (xy 94.537959 6.483978) (xy 94.461199 6.5222)
			(xy 94.388293 6.567341) (xy 94.319864 6.619017) (xy 94.256494 6.676786) (xy 94.198725 6.740156) (xy 94.147049 6.808585)
			(xy 94.101908 6.881491) (xy 94.063686 6.958251) (xy 94.03271 7.03821) (xy 94.009243 7.120686) (xy 93.993487 7.204976)
			(xy 93.985575 7.290359) (xy 7.092973 7.290359) (xy 7.087805 7.206571) (xy 7.071935 7.078411) (xy 7.048206 6.95147)
			(xy 7.016707 6.826231) (xy 6.977558 6.703168) (xy 6.930907 6.582749) (xy 6.876932 6.46543) (xy 6.815837 6.351656)
			(xy 6.747854 6.241859) (xy 6.67324 6.136456) (xy 6.592279 6.035846) (xy 6.505279 5.940411) (xy 6.412568 5.850512)
			(xy 6.314498 5.766491) (xy 6.211443 5.688667) (xy 6.103792 5.617335) (xy 5.991953 5.552765) (xy 5.876352 5.495203)
			(xy 5.757427 5.444866) (xy 5.635628 5.401946) (xy 5.511418 5.366605) (xy 5.385269 5.338978) (xy 5.257657 5.319169)
			(xy 5.129068 5.307253) (xy 4.99999 5.303277) (xy 4.870912 5.307253) (xy 4.742323 5.319169) (xy 4.614711 5.338978)
			(xy 4.488562 5.366605) (xy 4.364352 5.401946) (xy 4.242553 5.444866) (xy 4.123628 5.495203) (xy 4.008027 5.552765)
			(xy 3.896188 5.617335) (xy 3.788537 5.688667) (xy 3.685482 5.766491) (xy 3.587412 5.850512) (xy 3.494701 5.940411)
			(xy 3.407701 6.035846) (xy 3.32674 6.136456) (xy 3.252126 6.241859) (xy 3.184143 6.351656) (xy 3.123048 6.46543)
			(xy 3.069073 6.582749) (xy 3.022422 6.703168) (xy 2.983273 6.826231) (xy 2.951774 6.95147) (xy 2.928045 7.078411)
			(xy 2.912175 7.206571) (xy 2.904225 7.335466) (xy 0.509016 7.335466) (xy 0.509016 4.750359) (xy 93.985575 4.750359)
			(xy 93.985575 4.836109) (xy 93.993487 4.921492) (xy 94.009243 5.005782) (xy 94.03271 5.088258) (xy 94.063686 5.168217)
			(xy 94.101908 5.244977) (xy 94.147049 5.317883) (xy 94.198725 5.386312) (xy 94.256494 5.449682) (xy 94.319864 5.507451)
			(xy 94.388293 5.559127) (xy 94.461199 5.604268) (xy 94.537959 5.64249) (xy 94.617918 5.673466) (xy 94.700394 5.696933)
			(xy 94.784684 5.712689) (xy 94.870067 5.720601) (xy 94.955817 5.720601) (xy 95.0412 5.712689) (xy 95.12549 5.696933)
			(xy 95.207966 5.673466) (xy 95.287925 5.64249) (xy 95.308598 5.632196) (xy 98.842576 5.632196) (xy 98.842576 6.495796)
			(xy 98.84308 6.525332) (xy 98.851124 6.583854) (xy 98.867061 6.640736) (xy 98.890596 6.694918) (xy 98.921289 6.745391)
			(xy 98.958569 6.791214) (xy 99.001741 6.831534) (xy 99.050001 6.8656) (xy 99.102451 6.892777) (xy 99.158112 6.912559)
			(xy 99.215949 6.924578) (xy 99.274884 6.928609) (xy 99.333819 6.924578) (xy 99.391656 6.912559) (xy 99.447317 6.892777)
			(xy 99.499767 6.8656) (xy 99.548027 6.831534) (xy 99.591199 6.791214) (xy 99.628479 6.745391) (xy 99.659172 6.694918)
			(xy 99.682707 6.640736) (xy 99.698644 6.583854) (xy 99.706688 6.525332) (xy 99.707192 6.495796) (xy 99.707192 5.632196)
			(xy 99.706688 5.60266) (xy 99.698644 5.544138) (xy 99.682707 5.487256) (xy 99.659172 5.433074) (xy 99.628479 5.382601)
			(xy 99.591199 5.336778) (xy 99.548027 5.296458) (xy 99.499767 5.262392) (xy 99.447317 5.235215) (xy 99.391656 5.215433)
			(xy 99.333819 5.203414) (xy 99.274884 5.199383) (xy 99.215949 5.203414) (xy 99.158112 5.215433) (xy 99.102451 5.235215)
			(xy 99.050001 5.262392) (xy 99.001741 5.296458) (xy 98.958569 5.336778) (xy 98.921289 5.382601) (xy 98.890596 5.433074)
			(xy 98.867061 5.487256) (xy 98.851124 5.544138) (xy 98.84308 5.60266) (xy 98.842576 5.632196) (xy 95.308598 5.632196)
			(xy 95.364685 5.604268) (xy 95.437591 5.559127) (xy 95.50602 5.507451) (xy 95.56939 5.449682) (xy 95.627159 5.386312)
			(xy 95.678835 5.317883) (xy 95.723976 5.244977) (xy 95.762198 5.168217) (xy 95.793174 5.088258) (xy 95.816641 5.005782)
			(xy 95.832397 4.921492) (xy 95.840309 4.836109) (xy 95.840804 4.793234) (xy 95.840309 4.750359) (xy 100.335575 4.750359)
			(xy 100.335575 4.836109) (xy 100.343487 4.921492) (xy 100.359243 5.005782) (xy 100.38271 5.088258)
			(xy 100.413686 5.168217) (xy 100.451908 5.244977) (xy 100.497049 5.317883) (xy 100.548725 5.386312)
			(xy 100.606494 5.449682) (xy 100.669864 5.507451) (xy 100.738293 5.559127) (xy 100.811199 5.604268)
			(xy 100.887959 5.64249) (xy 100.967918 5.673466) (xy 101.050394 5.696933) (xy 101.134684 5.712689)
			(xy 101.220067 5.720601) (xy 101.305817 5.720601) (xy 101.3912 5.712689) (xy 101.47549 5.696933)
			(xy 101.557966 5.673466) (xy 101.637925 5.64249) (xy 101.714685 5.604268) (xy 101.787591 5.559127)
			(xy 101.85602 5.507451) (xy 101.91939 5.449682) (xy 101.977159 5.386312) (xy 102.028835 5.317883)
			(xy 102.073976 5.244977) (xy 102.112198 5.168217) (xy 102.143174 5.088258) (xy 102.166641 5.005782)
			(xy 102.182397 4.921492) (xy 102.190309 4.836109) (xy 102.190804 4.793234) (xy 102.190309 4.750359)
			(xy 181.468255 4.750359) (xy 181.468255 4.836109) (xy 181.476167 4.921492) (xy 181.491923 5.005782)
			(xy 181.51539 5.088258) (xy 181.546366 5.168217) (xy 181.584588 5.244977) (xy 181.629729 5.317883)
			(xy 181.681405 5.386312) (xy 181.739174 5.449682) (xy 181.802544 5.507451) (xy 181.870973 5.559127)
			(xy 181.943879 5.604268) (xy 182.020639 5.64249) (xy 182.100598 5.673466) (xy 182.183074 5.696933)
			(xy 182.267364 5.712689) (xy 182.352747 5.720601) (xy 182.438497 5.720601) (xy 182.52388 5.712689)
			(xy 182.60817 5.696933) (xy 182.690646 5.673466) (xy 182.770605 5.64249) (xy 182.791278 5.632196)
			(xy 183.953912 5.632196) (xy 183.953912 6.495796) (xy 183.954416 6.525332) (xy 183.96246 6.583854)
			(xy 183.978397 6.640736) (xy 184.001932 6.694918) (xy 184.032625 6.745391) (xy 184.069905 6.791214)
			(xy 184.113077 6.831534) (xy 184.161337 6.8656) (xy 184.213787 6.892777) (xy 184.269448 6.912559)
			(xy 184.327285 6.924578) (xy 184.38622 6.928609) (xy 184.445155 6.924578) (xy 184.502992 6.912559)
			(xy 184.558653 6.892777) (xy 184.611103 6.8656) (xy 184.659363 6.831534) (xy 184.702535 6.791214)
			(xy 184.739815 6.745391) (xy 184.770508 6.694918) (xy 184.794043 6.640736) (xy 184.80998 6.583854)
			(xy 184.818024 6.525332) (xy 184.818528 6.495796) (xy 184.818528 6.309919) (xy 208.661241 6.309919)
			(xy 208.661241 6.395669) (xy 208.669153 6.481052) (xy 208.684909 6.565342) (xy 208.708376 6.647818)
			(xy 208.739352 6.727777) (xy 208.777574 6.804537) (xy 208.822715 6.877443) (xy 208.874391 6.945872)
			(xy 208.93216 7.009242) (xy 208.99553 7.067011) (xy 209.063959 7.118687) (xy 209.136865 7.163828)
			(xy 209.213625 7.20205) (xy 209.293584 7.233026) (xy 209.37606 7.256493) (xy 209.46035 7.272249)
			(xy 209.545733 7.280161) (xy 209.631483 7.280161) (xy 209.716866 7.272249) (xy 209.801156 7.256493)
			(xy 209.883632 7.233026) (xy 209.963591 7.20205) (xy 210.040351 7.163828) (xy 210.113257 7.118687)
			(xy 210.181686 7.067011) (xy 210.245056 7.009242) (xy 210.302825 6.945872) (xy 210.354501 6.877443)
			(xy 210.399642 6.804537) (xy 210.437864 6.727777) (xy 210.46884 6.647818) (xy 210.492307 6.565342)
			(xy 210.508063 6.481052) (xy 210.515975 6.395669) (xy 210.51647 6.352794) (xy 210.515975 6.309919)
			(xy 215.011241 6.309919) (xy 215.011241 6.395669) (xy 215.019153 6.481052) (xy 215.034909 6.565342)
			(xy 215.058376 6.647818) (xy 215.089352 6.727777) (xy 215.127574 6.804537) (xy 215.172715 6.877443)
			(xy 215.224391 6.945872) (xy 215.28216 7.009242) (xy 215.34553 7.067011) (xy 215.413959 7.118687)
			(xy 215.486865 7.163828) (xy 215.563625 7.20205) (xy 215.643584 7.233026) (xy 215.72606 7.256493)
			(xy 215.81035 7.272249) (xy 215.895733 7.280161) (xy 215.981483 7.280161) (xy 216.066866 7.272249)
			(xy 216.151156 7.256493) (xy 216.233632 7.233026) (xy 216.313591 7.20205) (xy 216.390351 7.163828)
			(xy 216.463257 7.118687) (xy 216.531686 7.067011) (xy 216.595056 7.009242) (xy 216.652825 6.945872)
			(xy 216.704501 6.877443) (xy 216.749642 6.804537) (xy 216.787864 6.727777) (xy 216.81884 6.647818)
			(xy 216.842307 6.565342) (xy 216.858063 6.481052) (xy 216.865975 6.395669) (xy 216.86647 6.352794)
			(xy 216.865975 6.309919) (xy 296.143921 6.309919) (xy 296.143921 6.395669) (xy 296.151833 6.481052)
			(xy 296.167589 6.565342) (xy 296.191056 6.647818) (xy 296.222032 6.727777) (xy 296.260254 6.804537)
			(xy 296.305395 6.877443) (xy 296.357071 6.945872) (xy 296.41484 7.009242) (xy 296.47821 7.067011)
			(xy 296.546639 7.118687) (xy 296.619545 7.163828) (xy 296.696305 7.20205) (xy 296.776264 7.233026)
			(xy 296.85874 7.256493) (xy 296.94303 7.272249) (xy 297.028413 7.280161) (xy 297.114163 7.280161)
			(xy 297.199546 7.272249) (xy 297.283836 7.256493) (xy 297.366312 7.233026) (xy 297.446271 7.20205)
			(xy 297.523031 7.163828) (xy 297.595937 7.118687) (xy 297.664366 7.067011) (xy 297.727736 7.009242)
			(xy 297.785505 6.945872) (xy 297.837181 6.877443) (xy 297.882322 6.804537) (xy 297.920544 6.727777)
			(xy 297.95152 6.647818) (xy 297.974987 6.565342) (xy 297.990743 6.481052) (xy 297.998655 6.395669)
			(xy 297.99915 6.352794) (xy 297.998655 6.309919) (xy 302.493921 6.309919) (xy 302.493921 6.395669)
			(xy 302.501833 6.481052) (xy 302.517589 6.565342) (xy 302.541056 6.647818) (xy 302.572032 6.727777)
			(xy 302.610254 6.804537) (xy 302.655395 6.877443) (xy 302.707071 6.945872) (xy 302.76484 7.009242)
			(xy 302.82821 7.067011) (xy 302.896639 7.118687) (xy 302.969545 7.163828) (xy 303.046305 7.20205)
			(xy 303.126264 7.233026) (xy 303.20874 7.256493) (xy 303.29303 7.272249) (xy 303.378413 7.280161)
			(xy 303.464163 7.280161) (xy 303.549546 7.272249) (xy 303.633836 7.256493) (xy 303.716312 7.233026)
			(xy 303.796271 7.20205) (xy 303.873031 7.163828) (xy 303.945937 7.118687) (xy 304.014366 7.067011)
			(xy 304.077736 7.009242) (xy 304.135505 6.945872) (xy 304.187181 6.877443) (xy 304.232322 6.804537)
			(xy 304.270544 6.727777) (xy 304.30152 6.647818) (xy 304.324987 6.565342) (xy 304.340743 6.481052)
			(xy 304.348655 6.395669) (xy 304.34915 6.352794) (xy 304.348655 6.309919) (xy 311.155321 6.309919)
			(xy 311.155321 6.395669) (xy 311.163233 6.481052) (xy 311.178989 6.565342) (xy 311.202456 6.647818)
			(xy 311.233432 6.727777) (xy 311.271654 6.804537) (xy 311.316795 6.877443) (xy 311.368471 6.945872)
			(xy 311.42624 7.009242) (xy 311.48961 7.067011) (xy 311.558039 7.118687) (xy 311.630945 7.163828)
			(xy 311.707705 7.20205) (xy 311.787664 7.233026) (xy 311.87014 7.256493) (xy 311.95443 7.272249)
			(xy 312.039813 7.280161) (xy 312.125563 7.280161) (xy 312.210946 7.272249) (xy 312.295236 7.256493)
			(xy 312.377712 7.233026) (xy 312.457671 7.20205) (xy 312.478344 7.191756) (xy 316.012068 7.191756)
			(xy 316.012068 8.055356) (xy 316.012572 8.08491) (xy 316.020621 8.143466) (xy 316.036567 8.200381)
			(xy 316.060116 8.254595) (xy 316.090827 8.305098) (xy 316.128129 8.350948) (xy 316.171326 8.391291)
			(xy 316.219615 8.425377) (xy 316.272095 8.45257) (xy 316.32779 8.472364) (xy 316.385661 8.48439)
			(xy 316.44463 8.488424) (xy 316.503599 8.48439) (xy 316.56147 8.472364) (xy 316.617165 8.45257) (xy 316.669645 8.425377)
			(xy 316.717934 8.391291) (xy 316.761131 8.350948) (xy 316.798433 8.305098) (xy 316.829144 8.254595)
			(xy 316.852693 8.200381) (xy 316.868639 8.143466) (xy 316.876688 8.08491) (xy 316.877192 8.055356)
			(xy 316.877192 7.191756) (xy 316.876688 7.162202) (xy 316.868639 7.103646) (xy 316.852693 7.046731)
			(xy 316.829144 6.992517) (xy 316.798433 6.942014) (xy 316.761131 6.896164) (xy 316.717934 6.855821)
			(xy 316.669645 6.821735) (xy 316.617165 6.794542) (xy 316.56147 6.774748) (xy 316.503599 6.762722)
			(xy 316.44463 6.758689) (xy 316.385661 6.762722) (xy 316.32779 6.774748) (xy 316.272095 6.794542)
			(xy 316.219615 6.821735) (xy 316.171326 6.855821) (xy 316.128129 6.896164) (xy 316.090827 6.942014)
			(xy 316.060116 6.992517) (xy 316.036567 7.046731) (xy 316.020621 7.103646) (xy 316.012572 7.162202)
			(xy 316.012068 7.191756) (xy 312.478344 7.191756) (xy 312.534431 7.163828) (xy 312.607337 7.118687)
			(xy 312.675766 7.067011) (xy 312.739136 7.009242) (xy 312.796905 6.945872) (xy 312.848581 6.877443)
			(xy 312.893722 6.804537) (xy 312.931944 6.727777) (xy 312.96292 6.647818) (xy 312.986387 6.565342)
			(xy 313.002143 6.481052) (xy 313.010055 6.395669) (xy 313.01055 6.352794) (xy 313.010055 6.309919)
			(xy 317.505321 6.309919) (xy 317.505321 6.395669) (xy 317.513233 6.481052) (xy 317.528989 6.565342)
			(xy 317.552456 6.647818) (xy 317.583432 6.727777) (xy 317.621654 6.804537) (xy 317.666795 6.877443)
			(xy 317.718471 6.945872) (xy 317.77624 7.009242) (xy 317.83961 7.067011) (xy 317.908039 7.118687)
			(xy 317.980945 7.163828) (xy 318.057705 7.20205) (xy 318.137664 7.233026) (xy 318.22014 7.256493)
			(xy 318.30443 7.272249) (xy 318.389813 7.280161) (xy 318.475563 7.280161) (xy 318.560946 7.272249)
			(xy 318.645236 7.256493) (xy 318.727712 7.233026) (xy 318.807671 7.20205) (xy 318.884431 7.163828)
			(xy 318.957337 7.118687) (xy 319.025766 7.067011) (xy 319.089136 7.009242) (xy 319.146905 6.945872)
			(xy 319.198581 6.877443) (xy 319.243722 6.804537) (xy 319.281944 6.727777) (xy 319.31292 6.647818)
			(xy 319.336387 6.565342) (xy 319.352143 6.481052) (xy 319.360055 6.395669) (xy 319.36055 6.352794)
			(xy 319.360055 6.309919) (xy 361.894107 6.309919) (xy 361.894107 6.395669) (xy 361.902019 6.481052)
			(xy 361.917775 6.565342) (xy 361.941242 6.647818) (xy 361.972218 6.727777) (xy 362.01044 6.804537)
			(xy 362.055581 6.877443) (xy 362.107257 6.945872) (xy 362.165026 7.009242) (xy 362.228396 7.067011)
			(xy 362.296825 7.118687) (xy 362.369731 7.163828) (xy 362.446491 7.20205) (xy 362.52645 7.233026)
			(xy 362.608926 7.256493) (xy 362.693216 7.272249) (xy 362.778599 7.280161) (xy 362.864349 7.280161)
			(xy 362.949732 7.272249) (xy 363.034022 7.256493) (xy 363.116498 7.233026) (xy 363.196457 7.20205)
			(xy 363.21713 7.191756) (xy 364.379764 7.191756) (xy 364.379764 8.055356) (xy 364.380268 8.084892)
			(xy 364.388312 8.143414) (xy 364.404249 8.200296) (xy 364.427784 8.254478) (xy 364.458477 8.304951)
			(xy 364.495757 8.350774) (xy 364.538929 8.391094) (xy 364.587189 8.42516) (xy 364.639639 8.452337)
			(xy 364.6953 8.472119) (xy 364.753137 8.484138) (xy 364.812072 8.488169) (xy 364.871007 8.484138)
			(xy 364.928844 8.472119) (xy 364.984505 8.452337) (xy 365.036955 8.42516) (xy 365.085215 8.391094)
			(xy 365.128387 8.350774) (xy 365.165667 8.304951) (xy 365.19636 8.254478) (xy 365.219895 8.200296)
			(xy 365.235832 8.143414) (xy 365.243876 8.084892) (xy 365.24438 8.055356) (xy 365.24438 7.376973)
			(xy 385.651997 7.376973) (xy 385.651997 7.462723) (xy 385.659909 7.548106) (xy 385.675665 7.632396)
			(xy 385.699132 7.714872) (xy 385.730108 7.794831) (xy 385.76833 7.871591) (xy 385.813471 7.944497)
			(xy 385.865147 8.012926) (xy 385.922916 8.076296) (xy 385.986286 8.134065) (xy 386.054715 8.185741)
			(xy 386.127621 8.230882) (xy 386.204381 8.269104) (xy 386.28434 8.30008) (xy 386.366816 8.323547)
			(xy 386.451106 8.339303) (xy 386.536489 8.347215) (xy 386.622239 8.347215) (xy 386.707622 8.339303)
			(xy 386.791912 8.323547) (xy 386.874388 8.30008) (xy 386.954347 8.269104) (xy 386.97502 8.25881)
			(xy 390.508744 8.25881) (xy 390.508744 9.12241) (xy 390.509248 9.151964) (xy 390.517297 9.21052)
			(xy 390.533243 9.267435) (xy 390.556792 9.321649) (xy 390.587503 9.372152) (xy 390.624805 9.418002)
			(xy 390.668002 9.458345) (xy 390.716291 9.492431) (xy 390.768771 9.519624) (xy 390.824466 9.539418)
			(xy 390.882337 9.551444) (xy 390.941306 9.555478) (xy 391.000275 9.551444) (xy 391.058146 9.539418)
			(xy 391.113841 9.519624) (xy 391.166321 9.492431) (xy 391.21461 9.458345) (xy 391.257807 9.418002)
			(xy 391.295109 9.372152) (xy 391.32582 9.321649) (xy 391.349369 9.267435) (xy 391.365315 9.21052)
			(xy 391.373364 9.151964) (xy 391.373868 9.12241) (xy 391.373868 8.25881) (xy 391.373364 8.229256)
			(xy 391.365315 8.1707) (xy 391.349369 8.113785) (xy 391.32582 8.059571) (xy 391.295109 8.009068)
			(xy 391.257807 7.963218) (xy 391.21461 7.922875) (xy 391.166321 7.888789) (xy 391.113841 7.861596)
			(xy 391.058146 7.841802) (xy 391.000275 7.829776) (xy 390.941306 7.825743) (xy 390.882337 7.829776)
			(xy 390.824466 7.841802) (xy 390.768771 7.861596) (xy 390.716291 7.888789) (xy 390.668002 7.922875)
			(xy 390.624805 7.963218) (xy 390.587503 8.009068) (xy 390.556792 8.059571) (xy 390.533243 8.113785)
			(xy 390.517297 8.1707) (xy 390.509248 8.229256) (xy 390.508744 8.25881) (xy 386.97502 8.25881) (xy 387.031107 8.230882)
			(xy 387.104013 8.185741) (xy 387.172442 8.134065) (xy 387.235812 8.076296) (xy 387.293581 8.012926)
			(xy 387.345257 7.944497) (xy 387.390398 7.871591) (xy 387.42862 7.794831) (xy 387.459596 7.714872)
			(xy 387.483063 7.632396) (xy 387.498819 7.548106) (xy 387.506731 7.462723) (xy 387.507226 7.419848)
			(xy 387.506731 7.376973) (xy 392.001997 7.376973) (xy 392.001997 7.462723) (xy 392.009909 7.548106)
			(xy 392.025665 7.632396) (xy 392.049132 7.714872) (xy 392.080108 7.794831) (xy 392.11833 7.871591)
			(xy 392.163471 7.944497) (xy 392.215147 8.012926) (xy 392.272916 8.076296) (xy 392.336286 8.134065)
			(xy 392.404715 8.185741) (xy 392.477621 8.230882) (xy 392.554381 8.269104) (xy 392.63434 8.30008)
			(xy 392.716816 8.323547) (xy 392.801106 8.339303) (xy 392.886489 8.347215) (xy 392.972239 8.347215)
			(xy 393.057622 8.339303) (xy 393.141912 8.323547) (xy 393.224388 8.30008) (xy 393.304347 8.269104)
			(xy 393.381107 8.230882) (xy 393.454013 8.185741) (xy 393.522442 8.134065) (xy 393.585812 8.076296)
			(xy 393.643581 8.012926) (xy 393.695257 7.944497) (xy 393.740398 7.871591) (xy 393.77862 7.794831)
			(xy 393.809596 7.714872) (xy 393.833063 7.632396) (xy 393.848819 7.548106) (xy 393.856731 7.462723)
			(xy 393.857226 7.419848) (xy 393.856731 7.376973) (xy 436.390783 7.376973) (xy 436.390783 7.462723)
			(xy 436.398695 7.548106) (xy 436.414451 7.632396) (xy 436.437918 7.714872) (xy 436.468894 7.794831)
			(xy 436.507116 7.871591) (xy 436.552257 7.944497) (xy 436.603933 8.012926) (xy 436.661702 8.076296)
			(xy 436.725072 8.134065) (xy 436.793501 8.185741) (xy 436.866407 8.230882) (xy 436.943167 8.269104)
			(xy 437.023126 8.30008) (xy 437.105602 8.323547) (xy 437.189892 8.339303) (xy 437.275275 8.347215)
			(xy 437.361025 8.347215) (xy 437.446408 8.339303) (xy 437.530698 8.323547) (xy 437.613174 8.30008)
			(xy 437.693133 8.269104) (xy 437.713806 8.25881) (xy 438.87644 8.25881) (xy 438.87644 9.12241) (xy 438.876944 9.151946)
			(xy 438.884988 9.210468) (xy 438.900925 9.26735) (xy 438.92446 9.321532) (xy 438.955153 9.372005)
			(xy 438.992433 9.417828) (xy 439.035605 9.458148) (xy 439.083865 9.492214) (xy 439.136315 9.519391)
			(xy 439.191976 9.539173) (xy 439.249813 9.551192) (xy 439.308748 9.555223) (xy 439.367683 9.551192)
			(xy 439.42552 9.539173) (xy 439.481181 9.519391) (xy 439.533631 9.492214) (xy 439.581891 9.458148)
			(xy 439.625063 9.417828) (xy 439.662343 9.372005) (xy 439.693036 9.321532) (xy 439.716571 9.26735)
			(xy 439.732508 9.210468) (xy 439.740552 9.151946) (xy 439.741056 9.12241) (xy 439.741056 8.25881)
			(xy 439.740552 8.229274) (xy 439.732508 8.170752) (xy 439.716571 8.11387) (xy 439.693036 8.059688)
			(xy 439.662343 8.009215) (xy 439.625063 7.963392) (xy 439.581891 7.923072) (xy 439.533631 7.889006)
			(xy 439.481181 7.861829) (xy 439.42552 7.842047) (xy 439.367683 7.830028) (xy 439.308748 7.825997)
			(xy 439.249813 7.830028) (xy 439.191976 7.842047) (xy 439.136315 7.861829) (xy 439.083865 7.889006)
			(xy 439.035605 7.923072) (xy 438.992433 7.963392) (xy 438.955153 8.009215) (xy 438.92446 8.059688)
			(xy 438.900925 8.11387) (xy 438.884988 8.170752) (xy 438.876944 8.229274) (xy 438.87644 8.25881)
			(xy 437.713806 8.25881) (xy 437.769893 8.230882) (xy 437.842799 8.185741) (xy 437.911228 8.134065)
			(xy 437.974598 8.076296) (xy 438.032367 8.012926) (xy 438.084043 7.944497) (xy 438.129184 7.871591)
			(xy 438.167406 7.794831) (xy 438.198382 7.714872) (xy 438.221849 7.632396) (xy 438.237605 7.548106)
			(xy 438.245517 7.462723) (xy 438.246012 7.419848) (xy 438.245517 7.376973) (xy 442.740783 7.376973)
			(xy 442.740783 7.462723) (xy 442.748695 7.548106) (xy 442.764451 7.632396) (xy 442.787918 7.714872)
			(xy 442.818894 7.794831) (xy 442.857116 7.871591) (xy 442.902257 7.944497) (xy 442.953933 8.012926)
			(xy 443.011702 8.076296) (xy 443.075072 8.134065) (xy 443.143501 8.185741) (xy 443.216407 8.230882)
			(xy 443.293167 8.269104) (xy 443.373126 8.30008) (xy 443.455602 8.323547) (xy 443.539892 8.339303)
			(xy 443.625275 8.347215) (xy 443.711025 8.347215) (xy 443.796408 8.339303) (xy 443.880698 8.323547)
			(xy 443.963174 8.30008) (xy 444.043133 8.269104) (xy 444.119893 8.230882) (xy 444.192799 8.185741)
			(xy 444.261228 8.134065) (xy 444.324598 8.076296) (xy 444.382367 8.012926) (xy 444.434043 7.944497)
			(xy 444.479184 7.871591) (xy 444.517406 7.794831) (xy 444.548382 7.714872) (xy 444.571849 7.632396)
			(xy 444.587605 7.548106) (xy 444.595517 7.462723) (xy 444.596012 7.419848) (xy 444.595517 7.376973)
			(xy 444.587605 7.29159) (xy 444.571849 7.2073) (xy 444.548382 7.124824) (xy 444.517406 7.044865)
			(xy 444.479184 6.968105) (xy 444.434043 6.895199) (xy 444.382367 6.82677) (xy 444.324598 6.7634)
			(xy 444.261228 6.705631) (xy 444.192799 6.653955) (xy 444.119893 6.608814) (xy 444.043133 6.570592)
			(xy 443.963174 6.539616) (xy 443.880698 6.516149) (xy 443.796408 6.500393) (xy 443.711025 6.492481)
			(xy 443.625275 6.492481) (xy 443.539892 6.500393) (xy 443.455602 6.516149) (xy 443.373126 6.539616)
			(xy 443.293167 6.570592) (xy 443.216407 6.608814) (xy 443.143501 6.653955) (xy 443.075072 6.705631)
			(xy 443.011702 6.7634) (xy 442.953933 6.82677) (xy 442.902257 6.895199) (xy 442.857116 6.968105)
			(xy 442.818894 7.044865) (xy 442.787918 7.124824) (xy 442.764451 7.2073) (xy 442.748695 7.29159)
			(xy 442.740783 7.376973) (xy 438.245517 7.376973) (xy 438.237605 7.29159) (xy 438.221849 7.2073)
			(xy 438.198382 7.124824) (xy 438.167406 7.044865) (xy 438.129184 6.968105) (xy 438.084043 6.895199)
			(xy 438.032367 6.82677) (xy 437.974598 6.7634) (xy 437.911228 6.705631) (xy 437.842799 6.653955)
			(xy 437.769893 6.608814) (xy 437.693133 6.570592) (xy 437.613174 6.539616) (xy 437.530698 6.516149)
			(xy 437.446408 6.500393) (xy 437.361025 6.492481) (xy 437.275275 6.492481) (xy 437.189892 6.500393)
			(xy 437.105602 6.516149) (xy 437.023126 6.539616) (xy 436.943167 6.570592) (xy 436.866407 6.608814)
			(xy 436.793501 6.653955) (xy 436.725072 6.705631) (xy 436.661702 6.7634) (xy 436.603933 6.82677)
			(xy 436.552257 6.895199) (xy 436.507116 6.968105) (xy 436.468894 7.044865) (xy 436.437918 7.124824)
			(xy 436.414451 7.2073) (xy 436.398695 7.29159) (xy 436.390783 7.376973) (xy 393.856731 7.376973)
			(xy 393.848819 7.29159) (xy 393.833063 7.2073) (xy 393.809596 7.124824) (xy 393.77862 7.044865) (xy 393.740398 6.968105)
			(xy 393.695257 6.895199) (xy 393.643581 6.82677) (xy 393.585812 6.7634) (xy 393.522442 6.705631)
			(xy 393.454013 6.653955) (xy 393.381107 6.608814) (xy 393.304347 6.570592) (xy 393.224388 6.539616)
			(xy 393.141912 6.516149) (xy 393.057622 6.500393) (xy 392.972239 6.492481) (xy 392.886489 6.492481)
			(xy 392.801106 6.500393) (xy 392.716816 6.516149) (xy 392.63434 6.539616) (xy 392.554381 6.570592)
			(xy 392.477621 6.608814) (xy 392.404715 6.653955) (xy 392.336286 6.705631) (xy 392.272916 6.7634)
			(xy 392.215147 6.82677) (xy 392.163471 6.895199) (xy 392.11833 6.968105) (xy 392.080108 7.044865)
			(xy 392.049132 7.124824) (xy 392.025665 7.2073) (xy 392.009909 7.29159) (xy 392.001997 7.376973)
			(xy 387.506731 7.376973) (xy 387.498819 7.29159) (xy 387.483063 7.2073) (xy 387.459596 7.124824)
			(xy 387.42862 7.044865) (xy 387.390398 6.968105) (xy 387.345257 6.895199) (xy 387.293581 6.82677)
			(xy 387.235812 6.7634) (xy 387.172442 6.705631) (xy 387.104013 6.653955) (xy 387.031107 6.608814)
			(xy 386.954347 6.570592) (xy 386.874388 6.539616) (xy 386.791912 6.516149) (xy 386.707622 6.500393)
			(xy 386.622239 6.492481) (xy 386.536489 6.492481) (xy 386.451106 6.500393) (xy 386.366816 6.516149)
			(xy 386.28434 6.539616) (xy 386.204381 6.570592) (xy 386.127621 6.608814) (xy 386.054715 6.653955)
			(xy 385.986286 6.705631) (xy 385.922916 6.7634) (xy 385.865147 6.82677) (xy 385.813471 6.895199)
			(xy 385.76833 6.968105) (xy 385.730108 7.044865) (xy 385.699132 7.124824) (xy 385.675665 7.2073)
			(xy 385.659909 7.29159) (xy 385.651997 7.376973) (xy 365.24438 7.376973) (xy 365.24438 7.191756)
			(xy 365.243876 7.16222) (xy 365.235832 7.103698) (xy 365.219895 7.046816) (xy 365.19636 6.992634)
			(xy 365.165667 6.942161) (xy 365.128387 6.896338) (xy 365.085215 6.856018) (xy 365.036955 6.821952)
			(xy 364.984505 6.794775) (xy 364.928844 6.774993) (xy 364.871007 6.762974) (xy 364.812072 6.758943)
			(xy 364.753137 6.762974) (xy 364.6953 6.774993) (xy 364.639639 6.794775) (xy 364.587189 6.821952)
			(xy 364.538929 6.856018) (xy 364.495757 6.896338) (xy 364.458477 6.942161) (xy 364.427784 6.992634)
			(xy 364.404249 7.046816) (xy 364.388312 7.103698) (xy 364.380268 7.16222) (xy 364.379764 7.191756)
			(xy 363.21713 7.191756) (xy 363.273217 7.163828) (xy 363.346123 7.118687) (xy 363.414552 7.067011)
			(xy 363.477922 7.009242) (xy 363.535691 6.945872) (xy 363.587367 6.877443) (xy 363.632508 6.804537)
			(xy 363.67073 6.727777) (xy 363.701706 6.647818) (xy 363.725173 6.565342) (xy 363.740929 6.481052)
			(xy 363.748841 6.395669) (xy 363.749336 6.352794) (xy 363.748841 6.309919) (xy 368.244107 6.309919)
			(xy 368.244107 6.395669) (xy 368.252019 6.481052) (xy 368.267775 6.565342) (xy 368.291242 6.647818)
			(xy 368.322218 6.727777) (xy 368.36044 6.804537) (xy 368.405581 6.877443) (xy 368.457257 6.945872)
			(xy 368.515026 7.009242) (xy 368.578396 7.067011) (xy 368.646825 7.118687) (xy 368.719731 7.163828)
			(xy 368.796491 7.20205) (xy 368.87645 7.233026) (xy 368.958926 7.256493) (xy 369.043216 7.272249)
			(xy 369.128599 7.280161) (xy 369.214349 7.280161) (xy 369.299732 7.272249) (xy 369.384022 7.256493)
			(xy 369.466498 7.233026) (xy 369.546457 7.20205) (xy 369.623217 7.163828) (xy 369.696123 7.118687)
			(xy 369.764552 7.067011) (xy 369.827922 7.009242) (xy 369.885691 6.945872) (xy 369.937367 6.877443)
			(xy 369.982508 6.804537) (xy 370.02073 6.727777) (xy 370.051706 6.647818) (xy 370.075173 6.565342)
			(xy 370.090929 6.481052) (xy 370.098841 6.395669) (xy 370.099336 6.352794) (xy 370.098841 6.309919)
			(xy 370.090929 6.224536) (xy 370.075173 6.140246) (xy 370.051706 6.05777) (xy 370.02073 5.977811)
			(xy 369.982508 5.901051) (xy 369.937367 5.828145) (xy 369.885691 5.759716) (xy 369.827922 5.696346)
			(xy 369.764552 5.638577) (xy 369.696123 5.586901) (xy 369.623217 5.54176) (xy 369.546457 5.503538)
			(xy 369.466498 5.472562) (xy 369.384022 5.449095) (xy 369.299732 5.433339) (xy 369.214349 5.425427)
			(xy 369.128599 5.425427) (xy 369.043216 5.433339) (xy 368.958926 5.449095) (xy 368.87645 5.472562)
			(xy 368.796491 5.503538) (xy 368.719731 5.54176) (xy 368.646825 5.586901) (xy 368.578396 5.638577)
			(xy 368.515026 5.696346) (xy 368.457257 5.759716) (xy 368.405581 5.828145) (xy 368.36044 5.901051)
			(xy 368.322218 5.977811) (xy 368.291242 6.05777) (xy 368.267775 6.140246) (xy 368.252019 6.224536)
			(xy 368.244107 6.309919) (xy 363.748841 6.309919) (xy 363.740929 6.224536) (xy 363.725173 6.140246)
			(xy 363.701706 6.05777) (xy 363.67073 5.977811) (xy 363.632508 5.901051) (xy 363.587367 5.828145)
			(xy 363.535691 5.759716) (xy 363.477922 5.696346) (xy 363.414552 5.638577) (xy 363.346123 5.586901)
			(xy 363.273217 5.54176) (xy 363.196457 5.503538) (xy 363.116498 5.472562) (xy 363.034022 5.449095)
			(xy 362.949732 5.433339) (xy 362.864349 5.425427) (xy 362.778599 5.425427) (xy 362.693216 5.433339)
			(xy 362.608926 5.449095) (xy 362.52645 5.472562) (xy 362.446491 5.503538) (xy 362.369731 5.54176)
			(xy 362.296825 5.586901) (xy 362.228396 5.638577) (xy 362.165026 5.696346) (xy 362.107257 5.759716)
			(xy 362.055581 5.828145) (xy 362.01044 5.901051) (xy 361.972218 5.977811) (xy 361.941242 6.05777)
			(xy 361.917775 6.140246) (xy 361.902019 6.224536) (xy 361.894107 6.309919) (xy 319.360055 6.309919)
			(xy 319.352143 6.224536) (xy 319.336387 6.140246) (xy 319.31292 6.05777) (xy 319.281944 5.977811)
			(xy 319.243722 5.901051) (xy 319.198581 5.828145) (xy 319.146905 5.759716) (xy 319.089136 5.696346)
			(xy 319.025766 5.638577) (xy 318.957337 5.586901) (xy 318.884431 5.54176) (xy 318.807671 5.503538)
			(xy 318.727712 5.472562) (xy 318.645236 5.449095) (xy 318.560946 5.433339) (xy 318.475563 5.425427)
			(xy 318.389813 5.425427) (xy 318.30443 5.433339) (xy 318.22014 5.449095) (xy 318.137664 5.472562)
			(xy 318.057705 5.503538) (xy 317.980945 5.54176) (xy 317.908039 5.586901) (xy 317.83961 5.638577)
			(xy 317.77624 5.696346) (xy 317.718471 5.759716) (xy 317.666795 5.828145) (xy 317.621654 5.901051)
			(xy 317.583432 5.977811) (xy 317.552456 6.05777) (xy 317.528989 6.140246) (xy 317.513233 6.224536)
			(xy 317.505321 6.309919) (xy 313.010055 6.309919) (xy 313.002143 6.224536) (xy 312.986387 6.140246)
			(xy 312.96292 6.05777) (xy 312.931944 5.977811) (xy 312.893722 5.901051) (xy 312.848581 5.828145)
			(xy 312.796905 5.759716) (xy 312.739136 5.696346) (xy 312.675766 5.638577) (xy 312.607337 5.586901)
			(xy 312.534431 5.54176) (xy 312.457671 5.503538) (xy 312.377712 5.472562) (xy 312.295236 5.449095)
			(xy 312.210946 5.433339) (xy 312.125563 5.425427) (xy 312.039813 5.425427) (xy 311.95443 5.433339)
			(xy 311.87014 5.449095) (xy 311.787664 5.472562) (xy 311.707705 5.503538) (xy 311.630945 5.54176)
			(xy 311.558039 5.586901) (xy 311.48961 5.638577) (xy 311.42624 5.696346) (xy 311.368471 5.759716)
			(xy 311.316795 5.828145) (xy 311.271654 5.901051) (xy 311.233432 5.977811) (xy 311.202456 6.05777)
			(xy 311.178989 6.140246) (xy 311.163233 6.224536) (xy 311.155321 6.309919) (xy 304.348655 6.309919)
			(xy 304.340743 6.224536) (xy 304.324987 6.140246) (xy 304.30152 6.05777) (xy 304.270544 5.977811)
			(xy 304.232322 5.901051) (xy 304.187181 5.828145) (xy 304.135505 5.759716) (xy 304.077736 5.696346)
			(xy 304.014366 5.638577) (xy 303.945937 5.586901) (xy 303.873031 5.54176) (xy 303.796271 5.503538)
			(xy 303.716312 5.472562) (xy 303.633836 5.449095) (xy 303.549546 5.433339) (xy 303.464163 5.425427)
			(xy 303.378413 5.425427) (xy 303.29303 5.433339) (xy 303.20874 5.449095) (xy 303.126264 5.472562)
			(xy 303.046305 5.503538) (xy 302.969545 5.54176) (xy 302.896639 5.586901) (xy 302.82821 5.638577)
			(xy 302.76484 5.696346) (xy 302.707071 5.759716) (xy 302.655395 5.828145) (xy 302.610254 5.901051)
			(xy 302.572032 5.977811) (xy 302.541056 6.05777) (xy 302.517589 6.140246) (xy 302.501833 6.224536)
			(xy 302.493921 6.309919) (xy 297.998655 6.309919) (xy 297.990743 6.224536) (xy 297.974987 6.140246)
			(xy 297.95152 6.05777) (xy 297.920544 5.977811) (xy 297.882322 5.901051) (xy 297.837181 5.828145)
			(xy 297.785505 5.759716) (xy 297.727736 5.696346) (xy 297.664366 5.638577) (xy 297.595937 5.586901)
			(xy 297.523031 5.54176) (xy 297.446271 5.503538) (xy 297.366312 5.472562) (xy 297.283836 5.449095)
			(xy 297.199546 5.433339) (xy 297.114163 5.425427) (xy 297.028413 5.425427) (xy 296.94303 5.433339)
			(xy 296.85874 5.449095) (xy 296.776264 5.472562) (xy 296.696305 5.503538) (xy 296.619545 5.54176)
			(xy 296.546639 5.586901) (xy 296.47821 5.638577) (xy 296.41484 5.696346) (xy 296.357071 5.759716)
			(xy 296.305395 5.828145) (xy 296.260254 5.901051) (xy 296.222032 5.977811) (xy 296.191056 6.05777)
			(xy 296.167589 6.140246) (xy 296.151833 6.224536) (xy 296.143921 6.309919) (xy 216.865975 6.309919)
			(xy 216.858063 6.224536) (xy 216.842307 6.140246) (xy 216.81884 6.05777) (xy 216.787864 5.977811)
			(xy 216.749642 5.901051) (xy 216.704501 5.828145) (xy 216.652825 5.759716) (xy 216.595056 5.696346)
			(xy 216.531686 5.638577) (xy 216.463257 5.586901) (xy 216.390351 5.54176) (xy 216.313591 5.503538)
			(xy 216.233632 5.472562) (xy 216.151156 5.449095) (xy 216.066866 5.433339) (xy 215.981483 5.425427)
			(xy 215.895733 5.425427) (xy 215.81035 5.433339) (xy 215.72606 5.449095) (xy 215.643584 5.472562)
			(xy 215.563625 5.503538) (xy 215.486865 5.54176) (xy 215.413959 5.586901) (xy 215.34553 5.638577)
			(xy 215.28216 5.696346) (xy 215.224391 5.759716) (xy 215.172715 5.828145) (xy 215.127574 5.901051)
			(xy 215.089352 5.977811) (xy 215.058376 6.05777) (xy 215.034909 6.140246) (xy 215.019153 6.224536)
			(xy 215.011241 6.309919) (xy 210.515975 6.309919) (xy 210.508063 6.224536) (xy 210.492307 6.140246)
			(xy 210.46884 6.05777) (xy 210.437864 5.977811) (xy 210.399642 5.901051) (xy 210.354501 5.828145)
			(xy 210.302825 5.759716) (xy 210.245056 5.696346) (xy 210.181686 5.638577) (xy 210.113257 5.586901)
			(xy 210.040351 5.54176) (xy 209.963591 5.503538) (xy 209.883632 5.472562) (xy 209.801156 5.449095)
			(xy 209.716866 5.433339) (xy 209.631483 5.425427) (xy 209.545733 5.425427) (xy 209.46035 5.433339)
			(xy 209.37606 5.449095) (xy 209.293584 5.472562) (xy 209.213625 5.503538) (xy 209.136865 5.54176)
			(xy 209.063959 5.586901) (xy 208.99553 5.638577) (xy 208.93216 5.696346) (xy 208.874391 5.759716)
			(xy 208.822715 5.828145) (xy 208.777574 5.901051) (xy 208.739352 5.977811) (xy 208.708376 6.05777)
			(xy 208.684909 6.140246) (xy 208.669153 6.224536) (xy 208.661241 6.309919) (xy 184.818528 6.309919)
			(xy 184.818528 5.632196) (xy 184.818024 5.60266) (xy 184.80998 5.544138) (xy 184.794043 5.487256)
			(xy 184.770508 5.433074) (xy 184.739815 5.382601) (xy 184.702535 5.336778) (xy 184.659363 5.296458)
			(xy 184.611103 5.262392) (xy 184.558653 5.235215) (xy 184.502992 5.215433) (xy 184.445155 5.203414)
			(xy 184.38622 5.199383) (xy 184.327285 5.203414) (xy 184.269448 5.215433) (xy 184.213787 5.235215)
			(xy 184.161337 5.262392) (xy 184.113077 5.296458) (xy 184.069905 5.336778) (xy 184.032625 5.382601)
			(xy 184.001932 5.433074) (xy 183.978397 5.487256) (xy 183.96246 5.544138) (xy 183.954416 5.60266)
			(xy 183.953912 5.632196) (xy 182.791278 5.632196) (xy 182.847365 5.604268) (xy 182.920271 5.559127)
			(xy 182.9887 5.507451) (xy 183.05207 5.449682) (xy 183.109839 5.386312) (xy 183.161515 5.317883)
			(xy 183.206656 5.244977) (xy 183.244878 5.168217) (xy 183.275854 5.088258) (xy 183.299321 5.005782)
			(xy 183.315077 4.921492) (xy 183.322989 4.836109) (xy 183.323484 4.793234) (xy 183.322989 4.750359)
			(xy 187.818255 4.750359) (xy 187.818255 4.836109) (xy 187.826167 4.921492) (xy 187.841923 5.005782)
			(xy 187.86539 5.088258) (xy 187.896366 5.168217) (xy 187.934588 5.244977) (xy 187.979729 5.317883)
			(xy 188.031405 5.386312) (xy 188.089174 5.449682) (xy 188.152544 5.507451) (xy 188.220973 5.559127)
			(xy 188.293879 5.604268) (xy 188.370639 5.64249) (xy 188.450598 5.673466) (xy 188.533074 5.696933)
			(xy 188.617364 5.712689) (xy 188.702747 5.720601) (xy 188.788497 5.720601) (xy 188.87388 5.712689)
			(xy 188.95817 5.696933) (xy 189.040646 5.673466) (xy 189.120605 5.64249) (xy 189.197365 5.604268)
			(xy 189.270271 5.559127) (xy 189.3387 5.507451) (xy 189.40207 5.449682) (xy 189.459839 5.386312)
			(xy 189.511515 5.317883) (xy 189.556656 5.244977) (xy 189.594878 5.168217) (xy 189.625854 5.088258)
			(xy 189.649321 5.005782) (xy 189.665077 4.921492) (xy 189.672989 4.836109) (xy 189.673484 4.793234)
			(xy 189.672989 4.750359) (xy 189.665077 4.664976) (xy 189.649321 4.580686) (xy 189.625854 4.49821)
			(xy 189.594878 4.418251) (xy 189.556656 4.341491) (xy 189.511515 4.268585) (xy 189.459839 4.200156)
			(xy 189.40207 4.136786) (xy 189.3387 4.079017) (xy 189.270271 4.027341) (xy 189.197365 3.9822) (xy 189.120605 3.943978)
			(xy 189.040646 3.913002) (xy 188.95817 3.889535) (xy 188.87388 3.873779) (xy 188.788497 3.865867)
			(xy 188.702747 3.865867) (xy 188.617364 3.873779) (xy 188.533074 3.889535) (xy 188.450598 3.913002)
			(xy 188.370639 3.943978) (xy 188.293879 3.9822) (xy 188.220973 4.027341) (xy 188.152544 4.079017)
			(xy 188.089174 4.136786) (xy 188.031405 4.200156) (xy 187.979729 4.268585) (xy 187.934588 4.341491)
			(xy 187.896366 4.418251) (xy 187.86539 4.49821) (xy 187.841923 4.580686) (xy 187.826167 4.664976)
			(xy 187.818255 4.750359) (xy 183.322989 4.750359) (xy 183.315077 4.664976) (xy 183.299321 4.580686)
			(xy 183.275854 4.49821) (xy 183.244878 4.418251) (xy 183.206656 4.341491) (xy 183.161515 4.268585)
			(xy 183.109839 4.200156) (xy 183.05207 4.136786) (xy 182.9887 4.079017) (xy 182.920271 4.027341)
			(xy 182.847365 3.9822) (xy 182.770605 3.943978) (xy 182.690646 3.913002) (xy 182.60817 3.889535)
			(xy 182.52388 3.873779) (xy 182.438497 3.865867) (xy 182.352747 3.865867) (xy 182.267364 3.873779)
			(xy 182.183074 3.889535) (xy 182.100598 3.913002) (xy 182.020639 3.943978) (xy 181.943879 3.9822)
			(xy 181.870973 4.027341) (xy 181.802544 4.079017) (xy 181.739174 4.136786) (xy 181.681405 4.200156)
			(xy 181.629729 4.268585) (xy 181.584588 4.341491) (xy 181.546366 4.418251) (xy 181.51539 4.49821)
			(xy 181.491923 4.580686) (xy 181.476167 4.664976) (xy 181.468255 4.750359) (xy 102.190309 4.750359)
			(xy 102.182397 4.664976) (xy 102.166641 4.580686) (xy 102.143174 4.49821) (xy 102.112198 4.418251)
			(xy 102.073976 4.341491) (xy 102.028835 4.268585) (xy 101.977159 4.200156) (xy 101.91939 4.136786)
			(xy 101.85602 4.079017) (xy 101.787591 4.027341) (xy 101.714685 3.9822) (xy 101.637925 3.943978)
			(xy 101.557966 3.913002) (xy 101.47549 3.889535) (xy 101.3912 3.873779) (xy 101.305817 3.865867)
			(xy 101.220067 3.865867) (xy 101.134684 3.873779) (xy 101.050394 3.889535) (xy 100.967918 3.913002)
			(xy 100.887959 3.943978) (xy 100.811199 3.9822) (xy 100.738293 4.027341) (xy 100.669864 4.079017)
			(xy 100.606494 4.136786) (xy 100.548725 4.200156) (xy 100.497049 4.268585) (xy 100.451908 4.341491)
			(xy 100.413686 4.418251) (xy 100.38271 4.49821) (xy 100.359243 4.580686) (xy 100.343487 4.664976)
			(xy 100.335575 4.750359) (xy 95.840309 4.750359) (xy 95.832397 4.664976) (xy 95.816641 4.580686)
			(xy 95.793174 4.49821) (xy 95.762198 4.418251) (xy 95.723976 4.341491) (xy 95.678835 4.268585) (xy 95.627159 4.200156)
			(xy 95.56939 4.136786) (xy 95.50602 4.079017) (xy 95.437591 4.027341) (xy 95.364685 3.9822) (xy 95.287925 3.943978)
			(xy 95.207966 3.913002) (xy 95.12549 3.889535) (xy 95.0412 3.873779) (xy 94.955817 3.865867) (xy 94.870067 3.865867)
			(xy 94.784684 3.873779) (xy 94.700394 3.889535) (xy 94.617918 3.913002) (xy 94.537959 3.943978) (xy 94.461199 3.9822)
			(xy 94.388293 4.027341) (xy 94.319864 4.079017) (xy 94.256494 4.136786) (xy 94.198725 4.200156) (xy 94.147049 4.268585)
			(xy 94.101908 4.341491) (xy 94.063686 4.418251) (xy 94.03271 4.49821) (xy 94.009243 4.580686) (xy 93.993487 4.664976)
			(xy 93.985575 4.750359) (xy 0.509016 4.750359) (xy 0.509016 -7.78002) (xy 0.509537 -7.835789) (xy 0.517873 -7.947015)
			(xy 0.534497 -8.057308) (xy 0.559316 -8.166049) (xy 0.592193 -8.272632) (xy 0.632942 -8.37646) (xy 0.681336 -8.476953)
			(xy 0.737105 -8.573548) (xy 0.799937 -8.665705) (xy 0.86948 -8.752909) (xy 0.945345 -8.834672) (xy 1.027108 -8.910538)
			(xy 1.114312 -8.980081) (xy 1.206469 -9.042912) (xy 1.303064 -9.098682) (xy 1.403556 -9.147076) (xy 1.507384 -9.187826)
			(xy 1.613967 -9.220703) (xy 1.722708 -9.245523) (xy 1.833001 -9.262147) (xy 1.944227 -9.270482) (xy 1.999996 -9.271)
			(xy 9.10209 -9.271) (xy 9.15786 -9.270479) (xy 9.269087 -9.262144) (xy 9.37938 -9.245521) (xy 9.488123 -9.220702)
			(xy 9.594707 -9.187826) (xy 9.698536 -9.147077) (xy 9.79903 -9.098683) (xy 9.895626 -9.042915) (xy 9.987784 -8.980083)
			(xy 10.07499 -8.910541) (xy 10.156754 -8.834676) (xy 10.232621 -8.752912) (xy 10.302165 -8.665708)
			(xy 10.364999 -8.573551) (xy 10.420769 -8.476956) (xy 10.469165 -8.376463) (xy 10.509916 -8.272635)
			(xy 10.542794 -8.166052) (xy 10.567616 -8.05731) (xy 10.584241 -7.947017) (xy 10.592578 -7.83579)
			(xy 10.59307 -7.78002) (xy 10.59307 0.40005) (xy 10.593555 0.470432) (xy 10.601447 0.610976) (xy 10.617208 0.750856)
			(xy 10.640787 0.889632) (xy 10.67211 1.026868) (xy 10.711079 1.162131) (xy 10.757571 1.294997) (xy 10.811439 1.425046)
			(xy 10.872515 1.551871) (xy 10.940606 1.675072) (xy 11.015497 1.794261) (xy 11.096954 1.909063) (xy 11.184719 2.019118)
			(xy 11.278518 2.124078) (xy 11.378053 2.223614) (xy 11.483014 2.317412) (xy 11.593068 2.405178) (xy 11.707871 2.486634)
			(xy 11.82706 2.561525) (xy 11.950261 2.629616) (xy 12.077085 2.690692) (xy 12.207135 2.74456) (xy 12.340001 2.791052)
			(xy 12.475264 2.83002) (xy 12.6125 2.861343) (xy 12.751276 2.884922) (xy 12.891156 2.900683) (xy 13.0317 2.908575)
			(xy 13.102082 2.909062) (xy 81.701894 2.909062) (xy 81.772277 2.908568) (xy 81.912821 2.900676) (xy 82.052702 2.884916)
			(xy 82.191479 2.861337) (xy 82.328715 2.830015) (xy 82.46398 2.791046) (xy 82.596846 2.744555) (xy 82.726897 2.690688)
			(xy 82.853723 2.629613) (xy 82.976925 2.561522) (xy 83.096116 2.486632) (xy 83.210919 2.405176) (xy 83.320975 2.317411)
			(xy 83.425937 2.223613) (xy 83.439191 2.210359) (xy 93.985575 2.210359) (xy 93.985575 2.296109) (xy 93.993487 2.381492)
			(xy 94.009243 2.465782) (xy 94.03271 2.548258) (xy 94.063686 2.628217) (xy 94.101908 2.704977) (xy 94.147049 2.777883)
			(xy 94.198725 2.846312) (xy 94.256494 2.909682) (xy 94.319864 2.967451) (xy 94.388293 3.019127) (xy 94.461199 3.064268)
			(xy 94.537959 3.10249) (xy 94.617918 3.133466) (xy 94.700394 3.156933) (xy 94.784684 3.172689) (xy 94.870067 3.180601)
			(xy 94.955817 3.180601) (xy 95.0412 3.172689) (xy 95.12549 3.156933) (xy 95.207966 3.133466) (xy 95.287925 3.10249)
			(xy 95.308598 3.092196) (xy 98.842576 3.092196) (xy 98.842576 3.955796) (xy 98.84308 3.985332) (xy 98.851124 4.043854)
			(xy 98.867061 4.100736) (xy 98.890596 4.154918) (xy 98.921289 4.205391) (xy 98.958569 4.251214) (xy 99.001741 4.291534)
			(xy 99.050001 4.3256) (xy 99.102451 4.352777) (xy 99.158112 4.372559) (xy 99.215949 4.384578) (xy 99.274884 4.388609)
			(xy 99.333819 4.384578) (xy 99.391656 4.372559) (xy 99.447317 4.352777) (xy 99.499767 4.3256) (xy 99.548027 4.291534)
			(xy 99.591199 4.251214) (xy 99.628479 4.205391) (xy 99.659172 4.154918) (xy 99.682707 4.100736) (xy 99.698644 4.043854)
			(xy 99.706688 3.985332) (xy 99.707192 3.955796) (xy 99.707192 3.092196) (xy 99.706688 3.06266) (xy 99.698644 3.004138)
			(xy 99.682707 2.947256) (xy 99.659172 2.893074) (xy 99.628479 2.842601) (xy 99.591199 2.796778) (xy 99.548027 2.756458)
			(xy 99.499767 2.722392) (xy 99.447317 2.695215) (xy 99.391656 2.675433) (xy 99.333819 2.663414) (xy 99.274884 2.659383)
			(xy 99.215949 2.663414) (xy 99.158112 2.675433) (xy 99.102451 2.695215) (xy 99.050001 2.722392) (xy 99.001741 2.756458)
			(xy 98.958569 2.796778) (xy 98.921289 2.842601) (xy 98.890596 2.893074) (xy 98.867061 2.947256) (xy 98.851124 3.004138)
			(xy 98.84308 3.06266) (xy 98.842576 3.092196) (xy 95.308598 3.092196) (xy 95.364685 3.064268) (xy 95.437591 3.019127)
			(xy 95.50602 2.967451) (xy 95.56939 2.909682) (xy 95.627159 2.846312) (xy 95.678835 2.777883) (xy 95.723976 2.704977)
			(xy 95.762198 2.628217) (xy 95.793174 2.548258) (xy 95.816641 2.465782) (xy 95.832397 2.381492) (xy 95.840309 2.296109)
			(xy 95.840804 2.253234) (xy 95.840309 2.210359) (xy 100.335575 2.210359) (xy 100.335575 2.296109)
			(xy 100.343487 2.381492) (xy 100.359243 2.465782) (xy 100.38271 2.548258) (xy 100.413686 2.628217)
			(xy 100.451908 2.704977) (xy 100.497049 2.777883) (xy 100.548725 2.846312) (xy 100.606494 2.909682)
			(xy 100.669864 2.967451) (xy 100.738293 3.019127) (xy 100.811199 3.064268) (xy 100.887959 3.10249)
			(xy 100.967918 3.133466) (xy 101.050394 3.156933) (xy 101.134684 3.172689) (xy 101.220067 3.180601)
			(xy 101.305817 3.180601) (xy 101.3912 3.172689) (xy 101.47549 3.156933) (xy 101.557966 3.133466)
			(xy 101.637925 3.10249) (xy 101.714685 3.064268) (xy 101.787591 3.019127) (xy 101.85602 2.967451)
			(xy 101.91939 2.909682) (xy 101.977159 2.846312) (xy 102.028835 2.777883) (xy 102.073976 2.704977)
			(xy 102.112198 2.628217) (xy 102.143174 2.548258) (xy 102.166641 2.465782) (xy 102.182397 2.381492)
			(xy 102.190309 2.296109) (xy 102.190804 2.253234) (xy 102.190309 2.210359) (xy 181.468255 2.210359)
			(xy 181.468255 2.296109) (xy 181.476167 2.381492) (xy 181.491923 2.465782) (xy 181.51539 2.548258)
			(xy 181.546366 2.628217) (xy 181.584588 2.704977) (xy 181.629729 2.777883) (xy 181.681405 2.846312)
			(xy 181.739174 2.909682) (xy 181.802544 2.967451) (xy 181.870973 3.019127) (xy 181.943879 3.064268)
			(xy 182.020639 3.10249) (xy 182.100598 3.133466) (xy 182.183074 3.156933) (xy 182.267364 3.172689)
			(xy 182.352747 3.180601) (xy 182.438497 3.180601) (xy 182.52388 3.172689) (xy 182.60817 3.156933)
			(xy 182.690646 3.133466) (xy 182.770605 3.10249) (xy 182.791278 3.092196) (xy 183.953912 3.092196)
			(xy 183.953912 3.955796) (xy 183.954416 3.985332) (xy 183.96246 4.043854) (xy 183.978397 4.100736)
			(xy 184.001932 4.154918) (xy 184.032625 4.205391) (xy 184.069905 4.251214) (xy 184.113077 4.291534)
			(xy 184.161337 4.3256) (xy 184.213787 4.352777) (xy 184.269448 4.372559) (xy 184.327285 4.384578)
			(xy 184.38622 4.388609) (xy 184.445155 4.384578) (xy 184.502992 4.372559) (xy 184.558653 4.352777)
			(xy 184.611103 4.3256) (xy 184.659363 4.291534) (xy 184.702535 4.251214) (xy 184.739815 4.205391)
			(xy 184.770508 4.154918) (xy 184.794043 4.100736) (xy 184.80998 4.043854) (xy 184.818024 3.985332)
			(xy 184.818528 3.955796) (xy 184.818528 3.769919) (xy 208.661241 3.769919) (xy 208.661241 3.855669)
			(xy 208.669153 3.941052) (xy 208.684909 4.025342) (xy 208.708376 4.107818) (xy 208.739352 4.187777)
			(xy 208.777574 4.264537) (xy 208.822715 4.337443) (xy 208.874391 4.405872) (xy 208.93216 4.469242)
			(xy 208.99553 4.527011) (xy 209.063959 4.578687) (xy 209.136865 4.623828) (xy 209.213625 4.66205)
			(xy 209.293584 4.693026) (xy 209.37606 4.716493) (xy 209.46035 4.732249) (xy 209.545733 4.740161)
			(xy 209.631483 4.740161) (xy 209.716866 4.732249) (xy 209.801156 4.716493) (xy 209.883632 4.693026)
			(xy 209.963591 4.66205) (xy 209.984264 4.651756) (xy 213.517988 4.651756) (xy 213.517988 5.515356)
			(xy 213.518492 5.54491) (xy 213.526541 5.603466) (xy 213.542487 5.660381) (xy 213.566036 5.714595)
			(xy 213.596747 5.765098) (xy 213.634049 5.810948) (xy 213.677246 5.851291) (xy 213.725535 5.885377)
			(xy 213.778015 5.91257) (xy 213.83371 5.932364) (xy 213.891581 5.94439) (xy 213.95055 5.948424) (xy 214.009519 5.94439)
			(xy 214.06739 5.932364) (xy 214.123085 5.91257) (xy 214.175565 5.885377) (xy 214.223854 5.851291)
			(xy 214.267051 5.810948) (xy 214.304353 5.765098) (xy 214.335064 5.714595) (xy 214.358613 5.660381)
			(xy 214.374559 5.603466) (xy 214.382608 5.54491) (xy 214.383112 5.515356) (xy 214.383112 4.651756)
			(xy 214.382608 4.622202) (xy 214.374559 4.563646) (xy 214.358613 4.506731) (xy 214.335064 4.452517)
			(xy 214.304353 4.402014) (xy 214.267051 4.356164) (xy 214.223854 4.315821) (xy 214.175565 4.281735)
			(xy 214.123085 4.254542) (xy 214.06739 4.234748) (xy 214.009519 4.222722) (xy 213.95055 4.218689)
			(xy 213.891581 4.222722) (xy 213.83371 4.234748) (xy 213.778015 4.254542) (xy 213.725535 4.281735)
			(xy 213.677246 4.315821) (xy 213.634049 4.356164) (xy 213.596747 4.402014) (xy 213.566036 4.452517)
			(xy 213.542487 4.506731) (xy 213.526541 4.563646) (xy 213.518492 4.622202) (xy 213.517988 4.651756)
			(xy 209.984264 4.651756) (xy 210.040351 4.623828) (xy 210.113257 4.578687) (xy 210.181686 4.527011)
			(xy 210.245056 4.469242) (xy 210.302825 4.405872) (xy 210.354501 4.337443) (xy 210.399642 4.264537)
			(xy 210.437864 4.187777) (xy 210.46884 4.107818) (xy 210.492307 4.025342) (xy 210.508063 3.941052)
			(xy 210.515975 3.855669) (xy 210.51647 3.812794) (xy 210.515975 3.769919) (xy 215.011241 3.769919)
			(xy 215.011241 3.855669) (xy 215.019153 3.941052) (xy 215.034909 4.025342) (xy 215.058376 4.107818)
			(xy 215.089352 4.187777) (xy 215.127574 4.264537) (xy 215.172715 4.337443) (xy 215.224391 4.405872)
			(xy 215.28216 4.469242) (xy 215.34553 4.527011) (xy 215.413959 4.578687) (xy 215.486865 4.623828)
			(xy 215.563625 4.66205) (xy 215.643584 4.693026) (xy 215.72606 4.716493) (xy 215.81035 4.732249)
			(xy 215.895733 4.740161) (xy 215.981483 4.740161) (xy 216.066866 4.732249) (xy 216.151156 4.716493)
			(xy 216.233632 4.693026) (xy 216.313591 4.66205) (xy 216.390351 4.623828) (xy 216.463257 4.578687)
			(xy 216.531686 4.527011) (xy 216.595056 4.469242) (xy 216.652825 4.405872) (xy 216.704501 4.337443)
			(xy 216.749642 4.264537) (xy 216.787864 4.187777) (xy 216.81884 4.107818) (xy 216.842307 4.025342)
			(xy 216.858063 3.941052) (xy 216.865975 3.855669) (xy 216.86647 3.812794) (xy 216.865975 3.769919)
			(xy 296.143921 3.769919) (xy 296.143921 3.855669) (xy 296.151833 3.941052) (xy 296.167589 4.025342)
			(xy 296.191056 4.107818) (xy 296.222032 4.187777) (xy 296.260254 4.264537) (xy 296.305395 4.337443)
			(xy 296.357071 4.405872) (xy 296.41484 4.469242) (xy 296.47821 4.527011) (xy 296.546639 4.578687)
			(xy 296.619545 4.623828) (xy 296.696305 4.66205) (xy 296.776264 4.693026) (xy 296.85874 4.716493)
			(xy 296.94303 4.732249) (xy 297.028413 4.740161) (xy 297.114163 4.740161) (xy 297.199546 4.732249)
			(xy 297.283836 4.716493) (xy 297.366312 4.693026) (xy 297.446271 4.66205) (xy 297.466944 4.651756)
			(xy 298.629324 4.651756) (xy 298.629324 5.515356) (xy 298.629828 5.54491) (xy 298.637877 5.603466)
			(xy 298.653823 5.660381) (xy 298.677372 5.714595) (xy 298.708083 5.765098) (xy 298.745385 5.810948)
			(xy 298.788582 5.851291) (xy 298.836871 5.885377) (xy 298.889351 5.91257) (xy 298.945046 5.932364)
			(xy 299.002917 5.94439) (xy 299.061886 5.948424) (xy 299.120855 5.94439) (xy 299.178726 5.932364)
			(xy 299.234421 5.91257) (xy 299.286901 5.885377) (xy 299.33519 5.851291) (xy 299.378387 5.810948)
			(xy 299.415689 5.765098) (xy 299.4464 5.714595) (xy 299.469949 5.660381) (xy 299.485895 5.603466)
			(xy 299.493944 5.54491) (xy 299.494448 5.515356) (xy 299.494448 4.651756) (xy 299.493944 4.622202)
			(xy 299.485895 4.563646) (xy 299.469949 4.506731) (xy 299.4464 4.452517) (xy 299.415689 4.402014)
			(xy 299.378387 4.356164) (xy 299.33519 4.315821) (xy 299.286901 4.281735) (xy 299.234421 4.254542)
			(xy 299.178726 4.234748) (xy 299.120855 4.222722) (xy 299.061886 4.218689) (xy 299.002917 4.222722)
			(xy 298.945046 4.234748) (xy 298.889351 4.254542) (xy 298.836871 4.281735) (xy 298.788582 4.315821)
			(xy 298.745385 4.356164) (xy 298.708083 4.402014) (xy 298.677372 4.452517) (xy 298.653823 4.506731)
			(xy 298.637877 4.563646) (xy 298.629828 4.622202) (xy 298.629324 4.651756) (xy 297.466944 4.651756)
			(xy 297.523031 4.623828) (xy 297.595937 4.578687) (xy 297.664366 4.527011) (xy 297.727736 4.469242)
			(xy 297.785505 4.405872) (xy 297.837181 4.337443) (xy 297.882322 4.264537) (xy 297.920544 4.187777)
			(xy 297.95152 4.107818) (xy 297.974987 4.025342) (xy 297.990743 3.941052) (xy 297.998655 3.855669)
			(xy 297.99915 3.812794) (xy 297.998655 3.769919) (xy 302.493921 3.769919) (xy 302.493921 3.855669)
			(xy 302.501833 3.941052) (xy 302.517589 4.025342) (xy 302.541056 4.107818) (xy 302.572032 4.187777)
			(xy 302.610254 4.264537) (xy 302.655395 4.337443) (xy 302.707071 4.405872) (xy 302.76484 4.469242)
			(xy 302.82821 4.527011) (xy 302.896639 4.578687) (xy 302.969545 4.623828) (xy 303.046305 4.66205)
			(xy 303.126264 4.693026) (xy 303.20874 4.716493) (xy 303.29303 4.732249) (xy 303.378413 4.740161)
			(xy 303.464163 4.740161) (xy 303.549546 4.732249) (xy 303.633836 4.716493) (xy 303.716312 4.693026)
			(xy 303.796271 4.66205) (xy 303.873031 4.623828) (xy 303.945937 4.578687) (xy 304.014366 4.527011)
			(xy 304.077736 4.469242) (xy 304.135505 4.405872) (xy 304.187181 4.337443) (xy 304.232322 4.264537)
			(xy 304.270544 4.187777) (xy 304.30152 4.107818) (xy 304.324987 4.025342) (xy 304.340743 3.941052)
			(xy 304.348655 3.855669) (xy 304.34915 3.812794) (xy 304.348655 3.769919) (xy 311.155321 3.769919)
			(xy 311.155321 3.855669) (xy 311.163233 3.941052) (xy 311.178989 4.025342) (xy 311.202456 4.107818)
			(xy 311.233432 4.187777) (xy 311.271654 4.264537) (xy 311.316795 4.337443) (xy 311.368471 4.405872)
			(xy 311.42624 4.469242) (xy 311.48961 4.527011) (xy 311.558039 4.578687) (xy 311.630945 4.623828)
			(xy 311.707705 4.66205) (xy 311.787664 4.693026) (xy 311.87014 4.716493) (xy 311.95443 4.732249)
			(xy 312.039813 4.740161) (xy 312.125563 4.740161) (xy 312.210946 4.732249) (xy 312.295236 4.716493)
			(xy 312.377712 4.693026) (xy 312.457671 4.66205) (xy 312.478344 4.651756) (xy 316.012068 4.651756)
			(xy 316.012068 5.515356) (xy 316.012572 5.54491) (xy 316.020621 5.603466) (xy 316.036567 5.660381)
			(xy 316.060116 5.714595) (xy 316.090827 5.765098) (xy 316.128129 5.810948) (xy 316.171326 5.851291)
			(xy 316.219615 5.885377) (xy 316.272095 5.91257) (xy 316.32779 5.932364) (xy 316.385661 5.94439)
			(xy 316.44463 5.948424) (xy 316.503599 5.94439) (xy 316.56147 5.932364) (xy 316.617165 5.91257) (xy 316.669645 5.885377)
			(xy 316.717934 5.851291) (xy 316.761131 5.810948) (xy 316.798433 5.765098) (xy 316.829144 5.714595)
			(xy 316.852693 5.660381) (xy 316.868639 5.603466) (xy 316.876688 5.54491) (xy 316.877192 5.515356)
			(xy 316.877192 4.651756) (xy 316.876688 4.622202) (xy 316.868639 4.563646) (xy 316.852693 4.506731)
			(xy 316.829144 4.452517) (xy 316.798433 4.402014) (xy 316.761131 4.356164) (xy 316.717934 4.315821)
			(xy 316.669645 4.281735) (xy 316.617165 4.254542) (xy 316.56147 4.234748) (xy 316.503599 4.222722)
			(xy 316.44463 4.218689) (xy 316.385661 4.222722) (xy 316.32779 4.234748) (xy 316.272095 4.254542)
			(xy 316.219615 4.281735) (xy 316.171326 4.315821) (xy 316.128129 4.356164) (xy 316.090827 4.402014)
			(xy 316.060116 4.452517) (xy 316.036567 4.506731) (xy 316.020621 4.563646) (xy 316.012572 4.622202)
			(xy 316.012068 4.651756) (xy 312.478344 4.651756) (xy 312.534431 4.623828) (xy 312.607337 4.578687)
			(xy 312.675766 4.527011) (xy 312.739136 4.469242) (xy 312.796905 4.405872) (xy 312.848581 4.337443)
			(xy 312.893722 4.264537) (xy 312.931944 4.187777) (xy 312.96292 4.107818) (xy 312.986387 4.025342)
			(xy 313.002143 3.941052) (xy 313.010055 3.855669) (xy 313.01055 3.812794) (xy 313.010055 3.769919)
			(xy 317.505321 3.769919) (xy 317.505321 3.855669) (xy 317.513233 3.941052) (xy 317.528989 4.025342)
			(xy 317.552456 4.107818) (xy 317.583432 4.187777) (xy 317.621654 4.264537) (xy 317.666795 4.337443)
			(xy 317.718471 4.405872) (xy 317.77624 4.469242) (xy 317.83961 4.527011) (xy 317.908039 4.578687)
			(xy 317.980945 4.623828) (xy 318.057705 4.66205) (xy 318.137664 4.693026) (xy 318.22014 4.716493)
			(xy 318.30443 4.732249) (xy 318.389813 4.740161) (xy 318.475563 4.740161) (xy 318.560946 4.732249)
			(xy 318.645236 4.716493) (xy 318.727712 4.693026) (xy 318.807671 4.66205) (xy 318.884431 4.623828)
			(xy 318.957337 4.578687) (xy 319.025766 4.527011) (xy 319.089136 4.469242) (xy 319.146905 4.405872)
			(xy 319.198581 4.337443) (xy 319.243722 4.264537) (xy 319.281944 4.187777) (xy 319.31292 4.107818)
			(xy 319.336387 4.025342) (xy 319.352143 3.941052) (xy 319.360055 3.855669) (xy 319.36055 3.812794)
			(xy 319.360055 3.769919) (xy 361.894107 3.769919) (xy 361.894107 3.855669) (xy 361.902019 3.941052)
			(xy 361.917775 4.025342) (xy 361.941242 4.107818) (xy 361.972218 4.187777) (xy 362.01044 4.264537)
			(xy 362.055581 4.337443) (xy 362.107257 4.405872) (xy 362.165026 4.469242) (xy 362.228396 4.527011)
			(xy 362.296825 4.578687) (xy 362.369731 4.623828) (xy 362.446491 4.66205) (xy 362.52645 4.693026)
			(xy 362.608926 4.716493) (xy 362.693216 4.732249) (xy 362.778599 4.740161) (xy 362.864349 4.740161)
			(xy 362.949732 4.732249) (xy 363.034022 4.716493) (xy 363.116498 4.693026) (xy 363.196457 4.66205)
			(xy 363.21713 4.651756) (xy 364.379764 4.651756) (xy 364.379764 5.515356) (xy 364.380268 5.544892)
			(xy 364.388312 5.603414) (xy 364.404249 5.660296) (xy 364.427784 5.714478) (xy 364.458477 5.764951)
			(xy 364.495757 5.810774) (xy 364.538929 5.851094) (xy 364.587189 5.88516) (xy 364.639639 5.912337)
			(xy 364.6953 5.932119) (xy 364.753137 5.944138) (xy 364.812072 5.948169) (xy 364.871007 5.944138)
			(xy 364.928844 5.932119) (xy 364.984505 5.912337) (xy 365.036955 5.88516) (xy 365.085215 5.851094)
			(xy 365.128387 5.810774) (xy 365.165667 5.764951) (xy 365.19636 5.714478) (xy 365.219895 5.660296)
			(xy 365.235832 5.603414) (xy 365.243876 5.544892) (xy 365.24438 5.515356) (xy 365.24438 4.836973)
			(xy 385.651997 4.836973) (xy 385.651997 4.922723) (xy 385.659909 5.008106) (xy 385.675665 5.092396)
			(xy 385.699132 5.174872) (xy 385.730108 5.254831) (xy 385.76833 5.331591) (xy 385.813471 5.404497)
			(xy 385.865147 5.472926) (xy 385.922916 5.536296) (xy 385.986286 5.594065) (xy 386.054715 5.645741)
			(xy 386.127621 5.690882) (xy 386.204381 5.729104) (xy 386.28434 5.76008) (xy 386.366816 5.783547)
			(xy 386.451106 5.799303) (xy 386.536489 5.807215) (xy 386.622239 5.807215) (xy 386.707622 5.799303)
			(xy 386.791912 5.783547) (xy 386.874388 5.76008) (xy 386.954347 5.729104) (xy 386.97502 5.71881)
			(xy 390.508744 5.71881) (xy 390.508744 6.58241) (xy 390.509248 6.611964) (xy 390.517297 6.67052)
			(xy 390.533243 6.727435) (xy 390.556792 6.781649) (xy 390.587503 6.832152) (xy 390.624805 6.878002)
			(xy 390.668002 6.918345) (xy 390.716291 6.952431) (xy 390.768771 6.979624) (xy 390.824466 6.999418)
			(xy 390.882337 7.011444) (xy 390.941306 7.015478) (xy 391.000275 7.011444) (xy 391.058146 6.999418)
			(xy 391.113841 6.979624) (xy 391.166321 6.952431) (xy 391.21461 6.918345) (xy 391.257807 6.878002)
			(xy 391.295109 6.832152) (xy 391.32582 6.781649) (xy 391.349369 6.727435) (xy 391.365315 6.67052)
			(xy 391.373364 6.611964) (xy 391.373868 6.58241) (xy 391.373868 5.71881) (xy 391.373364 5.689256)
			(xy 391.365315 5.6307) (xy 391.349369 5.573785) (xy 391.32582 5.519571) (xy 391.295109 5.469068)
			(xy 391.257807 5.423218) (xy 391.21461 5.382875) (xy 391.166321 5.348789) (xy 391.113841 5.321596)
			(xy 391.058146 5.301802) (xy 391.000275 5.289776) (xy 390.941306 5.285743) (xy 390.882337 5.289776)
			(xy 390.824466 5.301802) (xy 390.768771 5.321596) (xy 390.716291 5.348789) (xy 390.668002 5.382875)
			(xy 390.624805 5.423218) (xy 390.587503 5.469068) (xy 390.556792 5.519571) (xy 390.533243 5.573785)
			(xy 390.517297 5.6307) (xy 390.509248 5.689256) (xy 390.508744 5.71881) (xy 386.97502 5.71881) (xy 387.031107 5.690882)
			(xy 387.104013 5.645741) (xy 387.172442 5.594065) (xy 387.235812 5.536296) (xy 387.293581 5.472926)
			(xy 387.345257 5.404497) (xy 387.390398 5.331591) (xy 387.42862 5.254831) (xy 387.459596 5.174872)
			(xy 387.483063 5.092396) (xy 387.498819 5.008106) (xy 387.506731 4.922723) (xy 387.507226 4.879848)
			(xy 387.506731 4.836973) (xy 392.001997 4.836973) (xy 392.001997 4.922723) (xy 392.009909 5.008106)
			(xy 392.025665 5.092396) (xy 392.049132 5.174872) (xy 392.080108 5.254831) (xy 392.11833 5.331591)
			(xy 392.163471 5.404497) (xy 392.215147 5.472926) (xy 392.272916 5.536296) (xy 392.336286 5.594065)
			(xy 392.404715 5.645741) (xy 392.477621 5.690882) (xy 392.554381 5.729104) (xy 392.63434 5.76008)
			(xy 392.716816 5.783547) (xy 392.801106 5.799303) (xy 392.886489 5.807215) (xy 392.972239 5.807215)
			(xy 393.057622 5.799303) (xy 393.141912 5.783547) (xy 393.224388 5.76008) (xy 393.304347 5.729104)
			(xy 393.381107 5.690882) (xy 393.454013 5.645741) (xy 393.522442 5.594065) (xy 393.585812 5.536296)
			(xy 393.643581 5.472926) (xy 393.695257 5.404497) (xy 393.740398 5.331591) (xy 393.77862 5.254831)
			(xy 393.809596 5.174872) (xy 393.833063 5.092396) (xy 393.848819 5.008106) (xy 393.856731 4.922723)
			(xy 393.857226 4.879848) (xy 393.856731 4.836973) (xy 436.390783 4.836973) (xy 436.390783 4.922723)
			(xy 436.398695 5.008106) (xy 436.414451 5.092396) (xy 436.437918 5.174872) (xy 436.468894 5.254831)
			(xy 436.507116 5.331591) (xy 436.552257 5.404497) (xy 436.603933 5.472926) (xy 436.661702 5.536296)
			(xy 436.725072 5.594065) (xy 436.793501 5.645741) (xy 436.866407 5.690882) (xy 436.943167 5.729104)
			(xy 437.023126 5.76008) (xy 437.105602 5.783547) (xy 437.189892 5.799303) (xy 437.275275 5.807215)
			(xy 437.361025 5.807215) (xy 437.446408 5.799303) (xy 437.530698 5.783547) (xy 437.613174 5.76008)
			(xy 437.693133 5.729104) (xy 437.713806 5.71881) (xy 438.87644 5.71881) (xy 438.87644 6.58241) (xy 438.876944 6.611946)
			(xy 438.884988 6.670468) (xy 438.900925 6.72735) (xy 438.92446 6.781532) (xy 438.955153 6.832005)
			(xy 438.992433 6.877828) (xy 439.035605 6.918148) (xy 439.083865 6.952214) (xy 439.136315 6.979391)
			(xy 439.191976 6.999173) (xy 439.249813 7.011192) (xy 439.308748 7.015223) (xy 439.367683 7.011192)
			(xy 439.42552 6.999173) (xy 439.481181 6.979391) (xy 439.533631 6.952214) (xy 439.581891 6.918148)
			(xy 439.625063 6.877828) (xy 439.662343 6.832005) (xy 439.693036 6.781532) (xy 439.716571 6.72735)
			(xy 439.732508 6.670468) (xy 439.740552 6.611946) (xy 439.741056 6.58241) (xy 439.741056 5.71881)
			(xy 439.740552 5.689274) (xy 439.732508 5.630752) (xy 439.716571 5.57387) (xy 439.693036 5.519688)
			(xy 439.662343 5.469215) (xy 439.625063 5.423392) (xy 439.581891 5.383072) (xy 439.533631 5.349006)
			(xy 439.481181 5.321829) (xy 439.42552 5.302047) (xy 439.367683 5.290028) (xy 439.308748 5.285997)
			(xy 439.249813 5.290028) (xy 439.191976 5.302047) (xy 439.136315 5.321829) (xy 439.083865 5.349006)
			(xy 439.035605 5.383072) (xy 438.992433 5.423392) (xy 438.955153 5.469215) (xy 438.92446 5.519688)
			(xy 438.900925 5.57387) (xy 438.884988 5.630752) (xy 438.876944 5.689274) (xy 438.87644 5.71881)
			(xy 437.713806 5.71881) (xy 437.769893 5.690882) (xy 437.842799 5.645741) (xy 437.911228 5.594065)
			(xy 437.974598 5.536296) (xy 438.032367 5.472926) (xy 438.084043 5.404497) (xy 438.129184 5.331591)
			(xy 438.167406 5.254831) (xy 438.198382 5.174872) (xy 438.221849 5.092396) (xy 438.237605 5.008106)
			(xy 438.245517 4.922723) (xy 438.246012 4.879848) (xy 438.245517 4.836973) (xy 442.740783 4.836973)
			(xy 442.740783 4.922723) (xy 442.748695 5.008106) (xy 442.764451 5.092396) (xy 442.787918 5.174872)
			(xy 442.818894 5.254831) (xy 442.857116 5.331591) (xy 442.902257 5.404497) (xy 442.953933 5.472926)
			(xy 443.011702 5.536296) (xy 443.075072 5.594065) (xy 443.143501 5.645741) (xy 443.216407 5.690882)
			(xy 443.293167 5.729104) (xy 443.373126 5.76008) (xy 443.455602 5.783547) (xy 443.539892 5.799303)
			(xy 443.625275 5.807215) (xy 443.711025 5.807215) (xy 443.796408 5.799303) (xy 443.880698 5.783547)
			(xy 443.963174 5.76008) (xy 444.043133 5.729104) (xy 444.119893 5.690882) (xy 444.192799 5.645741)
			(xy 444.261228 5.594065) (xy 444.324598 5.536296) (xy 444.382367 5.472926) (xy 444.434043 5.404497)
			(xy 444.479184 5.331591) (xy 444.517406 5.254831) (xy 444.548382 5.174872) (xy 444.571849 5.092396)
			(xy 444.587605 5.008106) (xy 444.595517 4.922723) (xy 444.596012 4.879848) (xy 444.595517 4.836973)
			(xy 444.587605 4.75159) (xy 444.571849 4.6673) (xy 444.548382 4.584824) (xy 444.517406 4.504865)
			(xy 444.479184 4.428105) (xy 444.434043 4.355199) (xy 444.382367 4.28677) (xy 444.324598 4.2234)
			(xy 444.261228 4.165631) (xy 444.192799 4.113955) (xy 444.119893 4.068814) (xy 444.043133 4.030592)
			(xy 443.963174 3.999616) (xy 443.880698 3.976149) (xy 443.796408 3.960393) (xy 443.711025 3.952481)
			(xy 443.625275 3.952481) (xy 443.539892 3.960393) (xy 443.455602 3.976149) (xy 443.373126 3.999616)
			(xy 443.293167 4.030592) (xy 443.216407 4.068814) (xy 443.143501 4.113955) (xy 443.075072 4.165631)
			(xy 443.011702 4.2234) (xy 442.953933 4.28677) (xy 442.902257 4.355199) (xy 442.857116 4.428105)
			(xy 442.818894 4.504865) (xy 442.787918 4.584824) (xy 442.764451 4.6673) (xy 442.748695 4.75159)
			(xy 442.740783 4.836973) (xy 438.245517 4.836973) (xy 438.237605 4.75159) (xy 438.221849 4.6673)
			(xy 438.198382 4.584824) (xy 438.167406 4.504865) (xy 438.129184 4.428105) (xy 438.084043 4.355199)
			(xy 438.032367 4.28677) (xy 437.974598 4.2234) (xy 437.911228 4.165631) (xy 437.842799 4.113955)
			(xy 437.769893 4.068814) (xy 437.693133 4.030592) (xy 437.613174 3.999616) (xy 437.530698 3.976149)
			(xy 437.446408 3.960393) (xy 437.361025 3.952481) (xy 437.275275 3.952481) (xy 437.189892 3.960393)
			(xy 437.105602 3.976149) (xy 437.023126 3.999616) (xy 436.943167 4.030592) (xy 436.866407 4.068814)
			(xy 436.793501 4.113955) (xy 436.725072 4.165631) (xy 436.661702 4.2234) (xy 436.603933 4.28677)
			(xy 436.552257 4.355199) (xy 436.507116 4.428105) (xy 436.468894 4.504865) (xy 436.437918 4.584824)
			(xy 436.414451 4.6673) (xy 436.398695 4.75159) (xy 436.390783 4.836973) (xy 393.856731 4.836973)
			(xy 393.848819 4.75159) (xy 393.833063 4.6673) (xy 393.809596 4.584824) (xy 393.77862 4.504865) (xy 393.740398 4.428105)
			(xy 393.695257 4.355199) (xy 393.643581 4.28677) (xy 393.585812 4.2234) (xy 393.522442 4.165631)
			(xy 393.454013 4.113955) (xy 393.381107 4.068814) (xy 393.304347 4.030592) (xy 393.224388 3.999616)
			(xy 393.141912 3.976149) (xy 393.057622 3.960393) (xy 392.972239 3.952481) (xy 392.886489 3.952481)
			(xy 392.801106 3.960393) (xy 392.716816 3.976149) (xy 392.63434 3.999616) (xy 392.554381 4.030592)
			(xy 392.477621 4.068814) (xy 392.404715 4.113955) (xy 392.336286 4.165631) (xy 392.272916 4.2234)
			(xy 392.215147 4.28677) (xy 392.163471 4.355199) (xy 392.11833 4.428105) (xy 392.080108 4.504865)
			(xy 392.049132 4.584824) (xy 392.025665 4.6673) (xy 392.009909 4.75159) (xy 392.001997 4.836973)
			(xy 387.506731 4.836973) (xy 387.498819 4.75159) (xy 387.483063 4.6673) (xy 387.459596 4.584824)
			(xy 387.42862 4.504865) (xy 387.390398 4.428105) (xy 387.345257 4.355199) (xy 387.293581 4.28677)
			(xy 387.235812 4.2234) (xy 387.172442 4.165631) (xy 387.104013 4.113955) (xy 387.031107 4.068814)
			(xy 386.954347 4.030592) (xy 386.874388 3.999616) (xy 386.791912 3.976149) (xy 386.707622 3.960393)
			(xy 386.622239 3.952481) (xy 386.536489 3.952481) (xy 386.451106 3.960393) (xy 386.366816 3.976149)
			(xy 386.28434 3.999616) (xy 386.204381 4.030592) (xy 386.127621 4.068814) (xy 386.054715 4.113955)
			(xy 385.986286 4.165631) (xy 385.922916 4.2234) (xy 385.865147 4.28677) (xy 385.813471 4.355199)
			(xy 385.76833 4.428105) (xy 385.730108 4.504865) (xy 385.699132 4.584824) (xy 385.675665 4.6673)
			(xy 385.659909 4.75159) (xy 385.651997 4.836973) (xy 365.24438 4.836973) (xy 365.24438 4.651756)
			(xy 365.243876 4.62222) (xy 365.235832 4.563698) (xy 365.219895 4.506816) (xy 365.19636 4.452634)
			(xy 365.165667 4.402161) (xy 365.128387 4.356338) (xy 365.085215 4.316018) (xy 365.036955 4.281952)
			(xy 364.984505 4.254775) (xy 364.928844 4.234993) (xy 364.871007 4.222974) (xy 364.812072 4.218943)
			(xy 364.753137 4.222974) (xy 364.6953 4.234993) (xy 364.639639 4.254775) (xy 364.587189 4.281952)
			(xy 364.538929 4.316018) (xy 364.495757 4.356338) (xy 364.458477 4.402161) (xy 364.427784 4.452634)
			(xy 364.404249 4.506816) (xy 364.388312 4.563698) (xy 364.380268 4.62222) (xy 364.379764 4.651756)
			(xy 363.21713 4.651756) (xy 363.273217 4.623828) (xy 363.346123 4.578687) (xy 363.414552 4.527011)
			(xy 363.477922 4.469242) (xy 363.535691 4.405872) (xy 363.587367 4.337443) (xy 363.632508 4.264537)
			(xy 363.67073 4.187777) (xy 363.701706 4.107818) (xy 363.725173 4.025342) (xy 363.740929 3.941052)
			(xy 363.748841 3.855669) (xy 363.749336 3.812794) (xy 363.748841 3.769919) (xy 368.244107 3.769919)
			(xy 368.244107 3.855669) (xy 368.252019 3.941052) (xy 368.267775 4.025342) (xy 368.291242 4.107818)
			(xy 368.322218 4.187777) (xy 368.36044 4.264537) (xy 368.405581 4.337443) (xy 368.457257 4.405872)
			(xy 368.515026 4.469242) (xy 368.578396 4.527011) (xy 368.646825 4.578687) (xy 368.719731 4.623828)
			(xy 368.796491 4.66205) (xy 368.87645 4.693026) (xy 368.958926 4.716493) (xy 369.043216 4.732249)
			(xy 369.128599 4.740161) (xy 369.214349 4.740161) (xy 369.299732 4.732249) (xy 369.384022 4.716493)
			(xy 369.466498 4.693026) (xy 369.546457 4.66205) (xy 369.623217 4.623828) (xy 369.696123 4.578687)
			(xy 369.764552 4.527011) (xy 369.827922 4.469242) (xy 369.885691 4.405872) (xy 369.937367 4.337443)
			(xy 369.982508 4.264537) (xy 370.02073 4.187777) (xy 370.051706 4.107818) (xy 370.075173 4.025342)
			(xy 370.090929 3.941052) (xy 370.098841 3.855669) (xy 370.099336 3.812794) (xy 370.098841 3.769919)
			(xy 370.090929 3.684536) (xy 370.075173 3.600246) (xy 370.051706 3.51777) (xy 370.02073 3.437811)
			(xy 369.982508 3.361051) (xy 369.937367 3.288145) (xy 369.885691 3.219716) (xy 369.827922 3.156346)
			(xy 369.764552 3.098577) (xy 369.696123 3.046901) (xy 369.623217 3.00176) (xy 369.546457 2.963538)
			(xy 369.466498 2.932562) (xy 369.384022 2.909095) (xy 369.299732 2.893339) (xy 369.214349 2.885427)
			(xy 369.128599 2.885427) (xy 369.043216 2.893339) (xy 368.958926 2.909095) (xy 368.87645 2.932562)
			(xy 368.796491 2.963538) (xy 368.719731 3.00176) (xy 368.646825 3.046901) (xy 368.578396 3.098577)
			(xy 368.515026 3.156346) (xy 368.457257 3.219716) (xy 368.405581 3.288145) (xy 368.36044 3.361051)
			(xy 368.322218 3.437811) (xy 368.291242 3.51777) (xy 368.267775 3.600246) (xy 368.252019 3.684536)
			(xy 368.244107 3.769919) (xy 363.748841 3.769919) (xy 363.740929 3.684536) (xy 363.725173 3.600246)
			(xy 363.701706 3.51777) (xy 363.67073 3.437811) (xy 363.632508 3.361051) (xy 363.587367 3.288145)
			(xy 363.535691 3.219716) (xy 363.477922 3.156346) (xy 363.414552 3.098577) (xy 363.346123 3.046901)
			(xy 363.273217 3.00176) (xy 363.196457 2.963538) (xy 363.116498 2.932562) (xy 363.034022 2.909095)
			(xy 362.949732 2.893339) (xy 362.864349 2.885427) (xy 362.778599 2.885427) (xy 362.693216 2.893339)
			(xy 362.608926 2.909095) (xy 362.52645 2.932562) (xy 362.446491 2.963538) (xy 362.369731 3.00176)
			(xy 362.296825 3.046901) (xy 362.228396 3.098577) (xy 362.165026 3.156346) (xy 362.107257 3.219716)
			(xy 362.055581 3.288145) (xy 362.01044 3.361051) (xy 361.972218 3.437811) (xy 361.941242 3.51777)
			(xy 361.917775 3.600246) (xy 361.902019 3.684536) (xy 361.894107 3.769919) (xy 319.360055 3.769919)
			(xy 319.352143 3.684536) (xy 319.336387 3.600246) (xy 319.31292 3.51777) (xy 319.281944 3.437811)
			(xy 319.243722 3.361051) (xy 319.198581 3.288145) (xy 319.146905 3.219716) (xy 319.089136 3.156346)
			(xy 319.025766 3.098577) (xy 318.957337 3.046901) (xy 318.884431 3.00176) (xy 318.807671 2.963538)
			(xy 318.727712 2.932562) (xy 318.645236 2.909095) (xy 318.560946 2.893339) (xy 318.475563 2.885427)
			(xy 318.389813 2.885427) (xy 318.30443 2.893339) (xy 318.22014 2.909095) (xy 318.137664 2.932562)
			(xy 318.057705 2.963538) (xy 317.980945 3.00176) (xy 317.908039 3.046901) (xy 317.83961 3.098577)
			(xy 317.77624 3.156346) (xy 317.718471 3.219716) (xy 317.666795 3.288145) (xy 317.621654 3.361051)
			(xy 317.583432 3.437811) (xy 317.552456 3.51777) (xy 317.528989 3.600246) (xy 317.513233 3.684536)
			(xy 317.505321 3.769919) (xy 313.010055 3.769919) (xy 313.002143 3.684536) (xy 312.986387 3.600246)
			(xy 312.96292 3.51777) (xy 312.931944 3.437811) (xy 312.893722 3.361051) (xy 312.848581 3.288145)
			(xy 312.796905 3.219716) (xy 312.739136 3.156346) (xy 312.675766 3.098577) (xy 312.607337 3.046901)
			(xy 312.534431 3.00176) (xy 312.457671 2.963538) (xy 312.377712 2.932562) (xy 312.295236 2.909095)
			(xy 312.210946 2.893339) (xy 312.125563 2.885427) (xy 312.039813 2.885427) (xy 311.95443 2.893339)
			(xy 311.87014 2.909095) (xy 311.787664 2.932562) (xy 311.707705 2.963538) (xy 311.630945 3.00176)
			(xy 311.558039 3.046901) (xy 311.48961 3.098577) (xy 311.42624 3.156346) (xy 311.368471 3.219716)
			(xy 311.316795 3.288145) (xy 311.271654 3.361051) (xy 311.233432 3.437811) (xy 311.202456 3.51777)
			(xy 311.178989 3.600246) (xy 311.163233 3.684536) (xy 311.155321 3.769919) (xy 304.348655 3.769919)
			(xy 304.340743 3.684536) (xy 304.324987 3.600246) (xy 304.30152 3.51777) (xy 304.270544 3.437811)
			(xy 304.232322 3.361051) (xy 304.187181 3.288145) (xy 304.135505 3.219716) (xy 304.077736 3.156346)
			(xy 304.014366 3.098577) (xy 303.945937 3.046901) (xy 303.873031 3.00176) (xy 303.796271 2.963538)
			(xy 303.716312 2.932562) (xy 303.633836 2.909095) (xy 303.549546 2.893339) (xy 303.464163 2.885427)
			(xy 303.378413 2.885427) (xy 303.29303 2.893339) (xy 303.20874 2.909095) (xy 303.126264 2.932562)
			(xy 303.046305 2.963538) (xy 302.969545 3.00176) (xy 302.896639 3.046901) (xy 302.82821 3.098577)
			(xy 302.76484 3.156346) (xy 302.707071 3.219716) (xy 302.655395 3.288145) (xy 302.610254 3.361051)
			(xy 302.572032 3.437811) (xy 302.541056 3.51777) (xy 302.517589 3.600246) (xy 302.501833 3.684536)
			(xy 302.493921 3.769919) (xy 297.998655 3.769919) (xy 297.990743 3.684536) (xy 297.974987 3.600246)
			(xy 297.95152 3.51777) (xy 297.920544 3.437811) (xy 297.882322 3.361051) (xy 297.837181 3.288145)
			(xy 297.785505 3.219716) (xy 297.727736 3.156346) (xy 297.664366 3.098577) (xy 297.595937 3.046901)
			(xy 297.523031 3.00176) (xy 297.446271 2.963538) (xy 297.366312 2.932562) (xy 297.283836 2.909095)
			(xy 297.199546 2.893339) (xy 297.114163 2.885427) (xy 297.028413 2.885427) (xy 296.94303 2.893339)
			(xy 296.85874 2.909095) (xy 296.776264 2.932562) (xy 296.696305 2.963538) (xy 296.619545 3.00176)
			(xy 296.546639 3.046901) (xy 296.47821 3.098577) (xy 296.41484 3.156346) (xy 296.357071 3.219716)
			(xy 296.305395 3.288145) (xy 296.260254 3.361051) (xy 296.222032 3.437811) (xy 296.191056 3.51777)
			(xy 296.167589 3.600246) (xy 296.151833 3.684536) (xy 296.143921 3.769919) (xy 216.865975 3.769919)
			(xy 216.858063 3.684536) (xy 216.842307 3.600246) (xy 216.81884 3.51777) (xy 216.787864 3.437811)
			(xy 216.749642 3.361051) (xy 216.704501 3.288145) (xy 216.652825 3.219716) (xy 216.595056 3.156346)
			(xy 216.531686 3.098577) (xy 216.463257 3.046901) (xy 216.390351 3.00176) (xy 216.313591 2.963538)
			(xy 216.233632 2.932562) (xy 216.151156 2.909095) (xy 216.066866 2.893339) (xy 215.981483 2.885427)
			(xy 215.895733 2.885427) (xy 215.81035 2.893339) (xy 215.72606 2.909095) (xy 215.643584 2.932562)
			(xy 215.563625 2.963538) (xy 215.486865 3.00176) (xy 215.413959 3.046901) (xy 215.34553 3.098577)
			(xy 215.28216 3.156346) (xy 215.224391 3.219716) (xy 215.172715 3.288145) (xy 215.127574 3.361051)
			(xy 215.089352 3.437811) (xy 215.058376 3.51777) (xy 215.034909 3.600246) (xy 215.019153 3.684536)
			(xy 215.011241 3.769919) (xy 210.515975 3.769919) (xy 210.508063 3.684536) (xy 210.492307 3.600246)
			(xy 210.46884 3.51777) (xy 210.437864 3.437811) (xy 210.399642 3.361051) (xy 210.354501 3.288145)
			(xy 210.302825 3.219716) (xy 210.245056 3.156346) (xy 210.181686 3.098577) (xy 210.113257 3.046901)
			(xy 210.040351 3.00176) (xy 209.963591 2.963538) (xy 209.883632 2.932562) (xy 209.801156 2.909095)
			(xy 209.716866 2.893339) (xy 209.631483 2.885427) (xy 209.545733 2.885427) (xy 209.46035 2.893339)
			(xy 209.37606 2.909095) (xy 209.293584 2.932562) (xy 209.213625 2.963538) (xy 209.136865 3.00176)
			(xy 209.063959 3.046901) (xy 208.99553 3.098577) (xy 208.93216 3.156346) (xy 208.874391 3.219716)
			(xy 208.822715 3.288145) (xy 208.777574 3.361051) (xy 208.739352 3.437811) (xy 208.708376 3.51777)
			(xy 208.684909 3.600246) (xy 208.669153 3.684536) (xy 208.661241 3.769919) (xy 184.818528 3.769919)
			(xy 184.818528 3.092196) (xy 184.818024 3.06266) (xy 184.80998 3.004138) (xy 184.794043 2.947256)
			(xy 184.770508 2.893074) (xy 184.739815 2.842601) (xy 184.702535 2.796778) (xy 184.659363 2.756458)
			(xy 184.611103 2.722392) (xy 184.558653 2.695215) (xy 184.502992 2.675433) (xy 184.445155 2.663414)
			(xy 184.38622 2.659383) (xy 184.327285 2.663414) (xy 184.269448 2.675433) (xy 184.213787 2.695215)
			(xy 184.161337 2.722392) (xy 184.113077 2.756458) (xy 184.069905 2.796778) (xy 184.032625 2.842601)
			(xy 184.001932 2.893074) (xy 183.978397 2.947256) (xy 183.96246 3.004138) (xy 183.954416 3.06266)
			(xy 183.953912 3.092196) (xy 182.791278 3.092196) (xy 182.847365 3.064268) (xy 182.920271 3.019127)
			(xy 182.9887 2.967451) (xy 183.05207 2.909682) (xy 183.109839 2.846312) (xy 183.161515 2.777883)
			(xy 183.206656 2.704977) (xy 183.244878 2.628217) (xy 183.275854 2.548258) (xy 183.299321 2.465782)
			(xy 183.315077 2.381492) (xy 183.322989 2.296109) (xy 183.323484 2.253234) (xy 183.322989 2.210359)
			(xy 187.818255 2.210359) (xy 187.818255 2.296109) (xy 187.826167 2.381492) (xy 187.841923 2.465782)
			(xy 187.86539 2.548258) (xy 187.896366 2.628217) (xy 187.934588 2.704977) (xy 187.979729 2.777883)
			(xy 188.031405 2.846312) (xy 188.089174 2.909682) (xy 188.152544 2.967451) (xy 188.220973 3.019127)
			(xy 188.293879 3.064268) (xy 188.370639 3.10249) (xy 188.450598 3.133466) (xy 188.533074 3.156933)
			(xy 188.617364 3.172689) (xy 188.702747 3.180601) (xy 188.788497 3.180601) (xy 188.87388 3.172689)
			(xy 188.95817 3.156933) (xy 189.040646 3.133466) (xy 189.120605 3.10249) (xy 189.197365 3.064268)
			(xy 189.270271 3.019127) (xy 189.3387 2.967451) (xy 189.40207 2.909682) (xy 189.459839 2.846312)
			(xy 189.511515 2.777883) (xy 189.556656 2.704977) (xy 189.594878 2.628217) (xy 189.625854 2.548258)
			(xy 189.649321 2.465782) (xy 189.665077 2.381492) (xy 189.672989 2.296109) (xy 189.673484 2.253234)
			(xy 189.672989 2.210359) (xy 189.665077 2.124976) (xy 189.649321 2.040686) (xy 189.625854 1.95821)
			(xy 189.594878 1.878251) (xy 189.556656 1.801491) (xy 189.511515 1.728585) (xy 189.459839 1.660156)
			(xy 189.40207 1.596786) (xy 189.3387 1.539017) (xy 189.270271 1.487341) (xy 189.197365 1.4422) (xy 189.120605 1.403978)
			(xy 189.040646 1.373002) (xy 188.95817 1.349535) (xy 188.87388 1.333779) (xy 188.788497 1.325867)
			(xy 188.702747 1.325867) (xy 188.617364 1.333779) (xy 188.533074 1.349535) (xy 188.450598 1.373002)
			(xy 188.370639 1.403978) (xy 188.293879 1.4422) (xy 188.220973 1.487341) (xy 188.152544 1.539017)
			(xy 188.089174 1.596786) (xy 188.031405 1.660156) (xy 187.979729 1.728585) (xy 187.934588 1.801491)
			(xy 187.896366 1.878251) (xy 187.86539 1.95821) (xy 187.841923 2.040686) (xy 187.826167 2.124976)
			(xy 187.818255 2.210359) (xy 183.322989 2.210359) (xy 183.315077 2.124976) (xy 183.299321 2.040686)
			(xy 183.275854 1.95821) (xy 183.244878 1.878251) (xy 183.206656 1.801491) (xy 183.161515 1.728585)
			(xy 183.109839 1.660156) (xy 183.05207 1.596786) (xy 182.9887 1.539017) (xy 182.920271 1.487341)
			(xy 182.847365 1.4422) (xy 182.770605 1.403978) (xy 182.690646 1.373002) (xy 182.60817 1.349535)
			(xy 182.52388 1.333779) (xy 182.438497 1.325867) (xy 182.352747 1.325867) (xy 182.267364 1.333779)
			(xy 182.183074 1.349535) (xy 182.100598 1.373002) (xy 182.020639 1.403978) (xy 181.943879 1.4422)
			(xy 181.870973 1.487341) (xy 181.802544 1.539017) (xy 181.739174 1.596786) (xy 181.681405 1.660156)
			(xy 181.629729 1.728585) (xy 181.584588 1.801491) (xy 181.546366 1.878251) (xy 181.51539 1.95821)
			(xy 181.491923 2.040686) (xy 181.476167 2.124976) (xy 181.468255 2.210359) (xy 102.190309 2.210359)
			(xy 102.182397 2.124976) (xy 102.166641 2.040686) (xy 102.143174 1.95821) (xy 102.112198 1.878251)
			(xy 102.073976 1.801491) (xy 102.028835 1.728585) (xy 101.977159 1.660156) (xy 101.91939 1.596786)
			(xy 101.85602 1.539017) (xy 101.787591 1.487341) (xy 101.714685 1.4422) (xy 101.637925 1.403978)
			(xy 101.557966 1.373002) (xy 101.47549 1.349535) (xy 101.3912 1.333779) (xy 101.305817 1.325867)
			(xy 101.220067 1.325867) (xy 101.134684 1.333779) (xy 101.050394 1.349535) (xy 100.967918 1.373002)
			(xy 100.887959 1.403978) (xy 100.811199 1.4422) (xy 100.738293 1.487341) (xy 100.669864 1.539017)
			(xy 100.606494 1.596786) (xy 100.548725 1.660156) (xy 100.497049 1.728585) (xy 100.451908 1.801491)
			(xy 100.413686 1.878251) (xy 100.38271 1.95821) (xy 100.359243 2.040686) (xy 100.343487 2.124976)
			(xy 100.335575 2.210359) (xy 95.840309 2.210359) (xy 95.832397 2.124976) (xy 95.816641 2.040686)
			(xy 95.793174 1.95821) (xy 95.762198 1.878251) (xy 95.723976 1.801491) (xy 95.678835 1.728585) (xy 95.627159 1.660156)
			(xy 95.56939 1.596786) (xy 95.50602 1.539017) (xy 95.437591 1.487341) (xy 95.364685 1.4422) (xy 95.287925 1.403978)
			(xy 95.207966 1.373002) (xy 95.12549 1.349535) (xy 95.0412 1.333779) (xy 94.955817 1.325867) (xy 94.870067 1.325867)
			(xy 94.784684 1.333779) (xy 94.700394 1.349535) (xy 94.617918 1.373002) (xy 94.537959 1.403978) (xy 94.461199 1.4422)
			(xy 94.388293 1.487341) (xy 94.319864 1.539017) (xy 94.256494 1.596786) (xy 94.198725 1.660156) (xy 94.147049 1.728585)
			(xy 94.101908 1.801491) (xy 94.063686 1.878251) (xy 94.03271 1.95821) (xy 94.009243 2.040686) (xy 93.993487 2.124976)
			(xy 93.985575 2.210359) (xy 83.439191 2.210359) (xy 83.525475 2.124078) (xy 83.619275 2.019118) (xy 83.707042 1.909064)
			(xy 83.788501 1.794262) (xy 83.863394 1.675073) (xy 83.931487 1.551873) (xy 83.992565 1.425048) (xy 84.046435 1.294999)
			(xy 84.069209 1.229919) (xy 208.661241 1.229919) (xy 208.661241 1.315669) (xy 208.669153 1.401052)
			(xy 208.684909 1.485342) (xy 208.708376 1.567818) (xy 208.739352 1.647777) (xy 208.777574 1.724537)
			(xy 208.822715 1.797443) (xy 208.874391 1.865872) (xy 208.93216 1.929242) (xy 208.99553 1.987011)
			(xy 209.063959 2.038687) (xy 209.136865 2.083828) (xy 209.213625 2.12205) (xy 209.293584 2.153026)
			(xy 209.37606 2.176493) (xy 209.46035 2.192249) (xy 209.545733 2.200161) (xy 209.631483 2.200161)
			(xy 209.716866 2.192249) (xy 209.801156 2.176493) (xy 209.883632 2.153026) (xy 209.963591 2.12205)
			(xy 209.984264 2.111756) (xy 213.517988 2.111756) (xy 213.517988 2.975356) (xy 213.518492 3.00491)
			(xy 213.526541 3.063466) (xy 213.542487 3.120381) (xy 213.566036 3.174595) (xy 213.596747 3.225098)
			(xy 213.634049 3.270948) (xy 213.677246 3.311291) (xy 213.725535 3.345377) (xy 213.778015 3.37257)
			(xy 213.83371 3.392364) (xy 213.891581 3.40439) (xy 213.95055 3.408424) (xy 214.009519 3.40439) (xy 214.06739 3.392364)
			(xy 214.123085 3.37257) (xy 214.175565 3.345377) (xy 214.223854 3.311291) (xy 214.267051 3.270948)
			(xy 214.304353 3.225098) (xy 214.335064 3.174595) (xy 214.358613 3.120381) (xy 214.374559 3.063466)
			(xy 214.382608 3.00491) (xy 214.383112 2.975356) (xy 214.383112 2.111756) (xy 214.382608 2.082202)
			(xy 214.374559 2.023646) (xy 214.358613 1.966731) (xy 214.335064 1.912517) (xy 214.304353 1.862014)
			(xy 214.267051 1.816164) (xy 214.223854 1.775821) (xy 214.175565 1.741735) (xy 214.123085 1.714542)
			(xy 214.06739 1.694748) (xy 214.009519 1.682722) (xy 213.95055 1.678689) (xy 213.891581 1.682722)
			(xy 213.83371 1.694748) (xy 213.778015 1.714542) (xy 213.725535 1.741735) (xy 213.677246 1.775821)
			(xy 213.634049 1.816164) (xy 213.596747 1.862014) (xy 213.566036 1.912517) (xy 213.542487 1.966731)
			(xy 213.526541 2.023646) (xy 213.518492 2.082202) (xy 213.517988 2.111756) (xy 209.984264 2.111756)
			(xy 210.040351 2.083828) (xy 210.113257 2.038687) (xy 210.181686 1.987011) (xy 210.245056 1.929242)
			(xy 210.302825 1.865872) (xy 210.354501 1.797443) (xy 210.399642 1.724537) (xy 210.437864 1.647777)
			(xy 210.46884 1.567818) (xy 210.492307 1.485342) (xy 210.508063 1.401052) (xy 210.515975 1.315669)
			(xy 210.51647 1.272794) (xy 210.515975 1.229919) (xy 215.011241 1.229919) (xy 215.011241 1.315669)
			(xy 215.019153 1.401052) (xy 215.034909 1.485342) (xy 215.058376 1.567818) (xy 215.089352 1.647777)
			(xy 215.127574 1.724537) (xy 215.172715 1.797443) (xy 215.224391 1.865872) (xy 215.28216 1.929242)
			(xy 215.34553 1.987011) (xy 215.413959 2.038687) (xy 215.486865 2.083828) (xy 215.563625 2.12205)
			(xy 215.643584 2.153026) (xy 215.72606 2.176493) (xy 215.81035 2.192249) (xy 215.895733 2.200161)
			(xy 215.981483 2.200161) (xy 216.066866 2.192249) (xy 216.151156 2.176493) (xy 216.233632 2.153026)
			(xy 216.313591 2.12205) (xy 216.390351 2.083828) (xy 216.463257 2.038687) (xy 216.531686 1.987011)
			(xy 216.595056 1.929242) (xy 216.652825 1.865872) (xy 216.704501 1.797443) (xy 216.749642 1.724537)
			(xy 216.787864 1.647777) (xy 216.81884 1.567818) (xy 216.842307 1.485342) (xy 216.858063 1.401052)
			(xy 216.865975 1.315669) (xy 216.86647 1.272794) (xy 216.865975 1.229919) (xy 296.143921 1.229919)
			(xy 296.143921 1.315669) (xy 296.151833 1.401052) (xy 296.167589 1.485342) (xy 296.191056 1.567818)
			(xy 296.222032 1.647777) (xy 296.260254 1.724537) (xy 296.305395 1.797443) (xy 296.357071 1.865872)
			(xy 296.41484 1.929242) (xy 296.47821 1.987011) (xy 296.546639 2.038687) (xy 296.619545 2.083828)
			(xy 296.696305 2.12205) (xy 296.776264 2.153026) (xy 296.85874 2.176493) (xy 296.94303 2.192249)
			(xy 297.028413 2.200161) (xy 297.114163 2.200161) (xy 297.199546 2.192249) (xy 297.283836 2.176493)
			(xy 297.366312 2.153026) (xy 297.446271 2.12205) (xy 297.466944 2.111756) (xy 298.629324 2.111756)
			(xy 298.629324 2.975356) (xy 298.629828 3.00491) (xy 298.637877 3.063466) (xy 298.653823 3.120381)
			(xy 298.677372 3.174595) (xy 298.708083 3.225098) (xy 298.745385 3.270948) (xy 298.788582 3.311291)
			(xy 298.836871 3.345377) (xy 298.889351 3.37257) (xy 298.945046 3.392364) (xy 299.002917 3.40439)
			(xy 299.061886 3.408424) (xy 299.120855 3.40439) (xy 299.178726 3.392364) (xy 299.234421 3.37257)
			(xy 299.286901 3.345377) (xy 299.33519 3.311291) (xy 299.378387 3.270948) (xy 299.415689 3.225098)
			(xy 299.4464 3.174595) (xy 299.469949 3.120381) (xy 299.485895 3.063466) (xy 299.493944 3.00491)
			(xy 299.494448 2.975356) (xy 299.494448 2.111756) (xy 299.493944 2.082202) (xy 299.485895 2.023646)
			(xy 299.469949 1.966731) (xy 299.4464 1.912517) (xy 299.415689 1.862014) (xy 299.378387 1.816164)
			(xy 299.33519 1.775821) (xy 299.286901 1.741735) (xy 299.234421 1.714542) (xy 299.178726 1.694748)
			(xy 299.120855 1.682722) (xy 299.061886 1.678689) (xy 299.002917 1.682722) (xy 298.945046 1.694748)
			(xy 298.889351 1.714542) (xy 298.836871 1.741735) (xy 298.788582 1.775821) (xy 298.745385 1.816164)
			(xy 298.708083 1.862014) (xy 298.677372 1.912517) (xy 298.653823 1.966731) (xy 298.637877 2.023646)
			(xy 298.629828 2.082202) (xy 298.629324 2.111756) (xy 297.466944 2.111756) (xy 297.523031 2.083828)
			(xy 297.595937 2.038687) (xy 297.664366 1.987011) (xy 297.727736 1.929242) (xy 297.785505 1.865872)
			(xy 297.837181 1.797443) (xy 297.882322 1.724537) (xy 297.920544 1.647777) (xy 297.95152 1.567818)
			(xy 297.974987 1.485342) (xy 297.990743 1.401052) (xy 297.998655 1.315669) (xy 297.99915 1.272794)
			(xy 297.998655 1.229919) (xy 302.493921 1.229919) (xy 302.493921 1.315669) (xy 302.501833 1.401052)
			(xy 302.517589 1.485342) (xy 302.541056 1.567818) (xy 302.572032 1.647777) (xy 302.610254 1.724537)
			(xy 302.655395 1.797443) (xy 302.707071 1.865872) (xy 302.76484 1.929242) (xy 302.82821 1.987011)
			(xy 302.896639 2.038687) (xy 302.969545 2.083828) (xy 303.046305 2.12205) (xy 303.126264 2.153026)
			(xy 303.20874 2.176493) (xy 303.29303 2.192249) (xy 303.378413 2.200161) (xy 303.464163 2.200161)
			(xy 303.549546 2.192249) (xy 303.633836 2.176493) (xy 303.716312 2.153026) (xy 303.796271 2.12205)
			(xy 303.873031 2.083828) (xy 303.945937 2.038687) (xy 304.014366 1.987011) (xy 304.077736 1.929242)
			(xy 304.135505 1.865872) (xy 304.187181 1.797443) (xy 304.232322 1.724537) (xy 304.270544 1.647777)
			(xy 304.30152 1.567818) (xy 304.324987 1.485342) (xy 304.340743 1.401052) (xy 304.348655 1.315669)
			(xy 304.34915 1.272794) (xy 304.348655 1.229919) (xy 311.155321 1.229919) (xy 311.155321 1.315669)
			(xy 311.163233 1.401052) (xy 311.178989 1.485342) (xy 311.202456 1.567818) (xy 311.233432 1.647777)
			(xy 311.271654 1.724537) (xy 311.316795 1.797443) (xy 311.368471 1.865872) (xy 311.42624 1.929242)
			(xy 311.48961 1.987011) (xy 311.558039 2.038687) (xy 311.630945 2.083828) (xy 311.707705 2.12205)
			(xy 311.787664 2.153026) (xy 311.87014 2.176493) (xy 311.95443 2.192249) (xy 312.039813 2.200161)
			(xy 312.125563 2.200161) (xy 312.210946 2.192249) (xy 312.295236 2.176493) (xy 312.377712 2.153026)
			(xy 312.457671 2.12205) (xy 312.534431 2.083828) (xy 312.607337 2.038687) (xy 312.675766 1.987011)
			(xy 312.739136 1.929242) (xy 312.796905 1.865872) (xy 312.848581 1.797443) (xy 312.893722 1.724537)
			(xy 312.931944 1.647777) (xy 312.96292 1.567818) (xy 312.986387 1.485342) (xy 313.002143 1.401052)
			(xy 313.010055 1.315669) (xy 313.01055 1.272794) (xy 313.010055 1.229919) (xy 317.505321 1.229919)
			(xy 317.505321 1.315669) (xy 317.513233 1.401052) (xy 317.528989 1.485342) (xy 317.552456 1.567818)
			(xy 317.583432 1.647777) (xy 317.621654 1.724537) (xy 317.666795 1.797443) (xy 317.718471 1.865872)
			(xy 317.77624 1.929242) (xy 317.83961 1.987011) (xy 317.908039 2.038687) (xy 317.980945 2.083828)
			(xy 318.057705 2.12205) (xy 318.137664 2.153026) (xy 318.22014 2.176493) (xy 318.30443 2.192249)
			(xy 318.389813 2.200161) (xy 318.475563 2.200161) (xy 318.560946 2.192249) (xy 318.645236 2.176493)
			(xy 318.727712 2.153026) (xy 318.807671 2.12205) (xy 318.884431 2.083828) (xy 318.957337 2.038687)
			(xy 319.025766 1.987011) (xy 319.089136 1.929242) (xy 319.146905 1.865872) (xy 319.198581 1.797443)
			(xy 319.243722 1.724537) (xy 319.281944 1.647777) (xy 319.31292 1.567818) (xy 319.336387 1.485342)
			(xy 319.352143 1.401052) (xy 319.360055 1.315669) (xy 319.36055 1.272794) (xy 319.360055 1.229919)
			(xy 361.894107 1.229919) (xy 361.894107 1.315669) (xy 361.902019 1.401052) (xy 361.917775 1.485342)
			(xy 361.941242 1.567818) (xy 361.972218 1.647777) (xy 362.01044 1.724537) (xy 362.055581 1.797443)
			(xy 362.107257 1.865872) (xy 362.165026 1.929242) (xy 362.228396 1.987011) (xy 362.296825 2.038687)
			(xy 362.369731 2.083828) (xy 362.446491 2.12205) (xy 362.52645 2.153026) (xy 362.608926 2.176493)
			(xy 362.693216 2.192249) (xy 362.778599 2.200161) (xy 362.864349 2.200161) (xy 362.949732 2.192249)
			(xy 363.034022 2.176493) (xy 363.116498 2.153026) (xy 363.196457 2.12205) (xy 363.273217 2.083828)
			(xy 363.346123 2.038687) (xy 363.414552 1.987011) (xy 363.477922 1.929242) (xy 363.535691 1.865872)
			(xy 363.587367 1.797443) (xy 363.632508 1.724537) (xy 363.67073 1.647777) (xy 363.701706 1.567818)
			(xy 363.725173 1.485342) (xy 363.740929 1.401052) (xy 363.748841 1.315669) (xy 363.749336 1.272794)
			(xy 363.748841 1.229919) (xy 368.244107 1.229919) (xy 368.244107 1.315669) (xy 368.252019 1.401052)
			(xy 368.267775 1.485342) (xy 368.291242 1.567818) (xy 368.322218 1.647777) (xy 368.36044 1.724537)
			(xy 368.405581 1.797443) (xy 368.457257 1.865872) (xy 368.515026 1.929242) (xy 368.578396 1.987011)
			(xy 368.646825 2.038687) (xy 368.719731 2.083828) (xy 368.796491 2.12205) (xy 368.87645 2.153026)
			(xy 368.958926 2.176493) (xy 369.043216 2.192249) (xy 369.128599 2.200161) (xy 369.214349 2.200161)
			(xy 369.299732 2.192249) (xy 369.384022 2.176493) (xy 369.466498 2.153026) (xy 369.546457 2.12205)
			(xy 369.623217 2.083828) (xy 369.696123 2.038687) (xy 369.764552 1.987011) (xy 369.827922 1.929242)
			(xy 369.885691 1.865872) (xy 369.937367 1.797443) (xy 369.982508 1.724537) (xy 370.02073 1.647777)
			(xy 370.051706 1.567818) (xy 370.075173 1.485342) (xy 370.090929 1.401052) (xy 370.098841 1.315669)
			(xy 370.099336 1.272794) (xy 370.098841 1.229919) (xy 370.090929 1.144536) (xy 370.075173 1.060246)
			(xy 370.051706 0.97777) (xy 370.02073 0.897811) (xy 369.982508 0.821051) (xy 369.937367 0.748145)
			(xy 369.885691 0.679716) (xy 369.827922 0.616346) (xy 369.764552 0.558577) (xy 369.696123 0.506901)
			(xy 369.623217 0.46176) (xy 369.546457 0.423538) (xy 369.466498 0.392562) (xy 369.384022 0.369095)
			(xy 369.299732 0.353339) (xy 369.214349 0.345427) (xy 369.128599 0.345427) (xy 369.043216 0.353339)
			(xy 368.958926 0.369095) (xy 368.87645 0.392562) (xy 368.796491 0.423538) (xy 368.719731 0.46176)
			(xy 368.646825 0.506901) (xy 368.578396 0.558577) (xy 368.515026 0.616346) (xy 368.457257 0.679716)
			(xy 368.405581 0.748145) (xy 368.36044 0.821051) (xy 368.322218 0.897811) (xy 368.291242 0.97777)
			(xy 368.267775 1.060246) (xy 368.252019 1.144536) (xy 368.244107 1.229919) (xy 363.748841 1.229919)
			(xy 363.740929 1.144536) (xy 363.725173 1.060246) (xy 363.701706 0.97777) (xy 363.67073 0.897811)
			(xy 363.632508 0.821051) (xy 363.587367 0.748145) (xy 363.535691 0.679716) (xy 363.477922 0.616346)
			(xy 363.414552 0.558577) (xy 363.346123 0.506901) (xy 363.273217 0.46176) (xy 363.196457 0.423538)
			(xy 363.116498 0.392562) (xy 363.034022 0.369095) (xy 362.949732 0.353339) (xy 362.864349 0.345427)
			(xy 362.778599 0.345427) (xy 362.693216 0.353339) (xy 362.608926 0.369095) (xy 362.52645 0.392562)
			(xy 362.446491 0.423538) (xy 362.369731 0.46176) (xy 362.296825 0.506901) (xy 362.228396 0.558577)
			(xy 362.165026 0.616346) (xy 362.107257 0.679716) (xy 362.055581 0.748145) (xy 362.01044 0.821051)
			(xy 361.972218 0.897811) (xy 361.941242 0.97777) (xy 361.917775 1.060246) (xy 361.902019 1.144536)
			(xy 361.894107 1.229919) (xy 319.360055 1.229919) (xy 319.352143 1.144536) (xy 319.336387 1.060246)
			(xy 319.31292 0.97777) (xy 319.281944 0.897811) (xy 319.243722 0.821051) (xy 319.198581 0.748145)
			(xy 319.146905 0.679716) (xy 319.089136 0.616346) (xy 319.025766 0.558577) (xy 318.957337 0.506901)
			(xy 318.884431 0.46176) (xy 318.807671 0.423538) (xy 318.727712 0.392562) (xy 318.645236 0.369095)
			(xy 318.560946 0.353339) (xy 318.475563 0.345427) (xy 318.389813 0.345427) (xy 318.30443 0.353339)
			(xy 318.22014 0.369095) (xy 318.137664 0.392562) (xy 318.057705 0.423538) (xy 317.980945 0.46176)
			(xy 317.908039 0.506901) (xy 317.83961 0.558577) (xy 317.77624 0.616346) (xy 317.718471 0.679716)
			(xy 317.666795 0.748145) (xy 317.621654 0.821051) (xy 317.583432 0.897811) (xy 317.552456 0.97777)
			(xy 317.528989 1.060246) (xy 317.513233 1.144536) (xy 317.505321 1.229919) (xy 313.010055 1.229919)
			(xy 313.002143 1.144536) (xy 312.986387 1.060246) (xy 312.96292 0.97777) (xy 312.931944 0.897811)
			(xy 312.893722 0.821051) (xy 312.848581 0.748145) (xy 312.796905 0.679716) (xy 312.739136 0.616346)
			(xy 312.675766 0.558577) (xy 312.607337 0.506901) (xy 312.534431 0.46176) (xy 312.457671 0.423538)
			(xy 312.377712 0.392562) (xy 312.295236 0.369095) (xy 312.210946 0.353339) (xy 312.125563 0.345427)
			(xy 312.039813 0.345427) (xy 311.95443 0.353339) (xy 311.87014 0.369095) (xy 311.787664 0.392562)
			(xy 311.707705 0.423538) (xy 311.630945 0.46176) (xy 311.558039 0.506901) (xy 311.48961 0.558577)
			(xy 311.42624 0.616346) (xy 311.368471 0.679716) (xy 311.316795 0.748145) (xy 311.271654 0.821051)
			(xy 311.233432 0.897811) (xy 311.202456 0.97777) (xy 311.178989 1.060246) (xy 311.163233 1.144536)
			(xy 311.155321 1.229919) (xy 304.348655 1.229919) (xy 304.340743 1.144536) (xy 304.324987 1.060246)
			(xy 304.30152 0.97777) (xy 304.270544 0.897811) (xy 304.232322 0.821051) (xy 304.187181 0.748145)
			(xy 304.135505 0.679716) (xy 304.077736 0.616346) (xy 304.014366 0.558577) (xy 303.945937 0.506901)
			(xy 303.873031 0.46176) (xy 303.796271 0.423538) (xy 303.716312 0.392562) (xy 303.633836 0.369095)
			(xy 303.549546 0.353339) (xy 303.464163 0.345427) (xy 303.378413 0.345427) (xy 303.29303 0.353339)
			(xy 303.20874 0.369095) (xy 303.126264 0.392562) (xy 303.046305 0.423538) (xy 302.969545 0.46176)
			(xy 302.896639 0.506901) (xy 302.82821 0.558577) (xy 302.76484 0.616346) (xy 302.707071 0.679716)
			(xy 302.655395 0.748145) (xy 302.610254 0.821051) (xy 302.572032 0.897811) (xy 302.541056 0.97777)
			(xy 302.517589 1.060246) (xy 302.501833 1.144536) (xy 302.493921 1.229919) (xy 297.998655 1.229919)
			(xy 297.990743 1.144536) (xy 297.974987 1.060246) (xy 297.95152 0.97777) (xy 297.920544 0.897811)
			(xy 297.882322 0.821051) (xy 297.837181 0.748145) (xy 297.785505 0.679716) (xy 297.727736 0.616346)
			(xy 297.664366 0.558577) (xy 297.595937 0.506901) (xy 297.523031 0.46176) (xy 297.446271 0.423538)
			(xy 297.366312 0.392562) (xy 297.283836 0.369095) (xy 297.199546 0.353339) (xy 297.114163 0.345427)
			(xy 297.028413 0.345427) (xy 296.94303 0.353339) (xy 296.85874 0.369095) (xy 296.776264 0.392562)
			(xy 296.696305 0.423538) (xy 296.619545 0.46176) (xy 296.546639 0.506901) (xy 296.47821 0.558577)
			(xy 296.41484 0.616346) (xy 296.357071 0.679716) (xy 296.305395 0.748145) (xy 296.260254 0.821051)
			(xy 296.222032 0.897811) (xy 296.191056 0.97777) (xy 296.167589 1.060246) (xy 296.151833 1.144536)
			(xy 296.143921 1.229919) (xy 216.865975 1.229919) (xy 216.858063 1.144536) (xy 216.842307 1.060246)
			(xy 216.81884 0.97777) (xy 216.787864 0.897811) (xy 216.749642 0.821051) (xy 216.704501 0.748145)
			(xy 216.652825 0.679716) (xy 216.595056 0.616346) (xy 216.531686 0.558577) (xy 216.463257 0.506901)
			(xy 216.390351 0.46176) (xy 216.313591 0.423538) (xy 216.233632 0.392562) (xy 216.151156 0.369095)
			(xy 216.066866 0.353339) (xy 215.981483 0.345427) (xy 215.895733 0.345427) (xy 215.81035 0.353339)
			(xy 215.72606 0.369095) (xy 215.643584 0.392562) (xy 215.563625 0.423538) (xy 215.486865 0.46176)
			(xy 215.413959 0.506901) (xy 215.34553 0.558577) (xy 215.28216 0.616346) (xy 215.224391 0.679716)
			(xy 215.172715 0.748145) (xy 215.127574 0.821051) (xy 215.089352 0.897811) (xy 215.058376 0.97777)
			(xy 215.034909 1.060246) (xy 215.019153 1.144536) (xy 215.011241 1.229919) (xy 210.515975 1.229919)
			(xy 210.508063 1.144536) (xy 210.492307 1.060246) (xy 210.46884 0.97777) (xy 210.437864 0.897811)
			(xy 210.399642 0.821051) (xy 210.354501 0.748145) (xy 210.302825 0.679716) (xy 210.245056 0.616346)
			(xy 210.181686 0.558577) (xy 210.113257 0.506901) (xy 210.040351 0.46176) (xy 209.963591 0.423538)
			(xy 209.883632 0.392562) (xy 209.801156 0.369095) (xy 209.716866 0.353339) (xy 209.631483 0.345427)
			(xy 209.545733 0.345427) (xy 209.46035 0.353339) (xy 209.37606 0.369095) (xy 209.293584 0.392562)
			(xy 209.213625 0.423538) (xy 209.136865 0.46176) (xy 209.063959 0.506901) (xy 208.99553 0.558577)
			(xy 208.93216 0.616346) (xy 208.874391 0.679716) (xy 208.822715 0.748145) (xy 208.777574 0.821051)
			(xy 208.739352 0.897811) (xy 208.708376 0.97777) (xy 208.684909 1.060246) (xy 208.669153 1.144536)
			(xy 208.661241 1.229919) (xy 84.069209 1.229919) (xy 84.092929 1.162133) (xy 84.131901 1.02687) (xy 84.163226 0.889634)
			(xy 84.186808 0.750857) (xy 84.202571 0.610977) (xy 84.210467 0.470433) (xy 84.210906 0.40005) (xy 84.210906 -1.310081)
			(xy 208.661241 -1.310081) (xy 208.661241 -1.224331) (xy 208.669153 -1.138948) (xy 208.684909 -1.054658)
			(xy 208.708376 -0.972182) (xy 208.739352 -0.892223) (xy 208.777574 -0.815463) (xy 208.822715 -0.742557)
			(xy 208.874391 -0.674128) (xy 208.93216 -0.610758) (xy 208.99553 -0.552989) (xy 209.063959 -0.501313)
			(xy 209.136865 -0.456172) (xy 209.213625 -0.41795) (xy 209.293584 -0.386974) (xy 209.37606 -0.363507)
			(xy 209.46035 -0.347751) (xy 209.545733 -0.339839) (xy 209.631483 -0.339839) (xy 209.716866 -0.347751)
			(xy 209.801156 -0.363507) (xy 209.883632 -0.386974) (xy 209.963591 -0.41795) (xy 210.040351 -0.456172)
			(xy 210.113257 -0.501313) (xy 210.181686 -0.552989) (xy 210.245056 -0.610758) (xy 210.302825 -0.674128)
			(xy 210.354501 -0.742557) (xy 210.399642 -0.815463) (xy 210.437864 -0.892223) (xy 210.46884 -0.972182)
			(xy 210.492307 -1.054658) (xy 210.508063 -1.138948) (xy 210.515975 -1.224331) (xy 210.51647 -1.267206)
			(xy 210.515975 -1.310081) (xy 215.011241 -1.310081) (xy 215.011241 -1.224331) (xy 215.019153 -1.138948)
			(xy 215.034909 -1.054658) (xy 215.058376 -0.972182) (xy 215.089352 -0.892223) (xy 215.127574 -0.815463)
			(xy 215.172715 -0.742557) (xy 215.224391 -0.674128) (xy 215.28216 -0.610758) (xy 215.34553 -0.552989)
			(xy 215.413959 -0.501313) (xy 215.486865 -0.456172) (xy 215.563625 -0.41795) (xy 215.643584 -0.386974)
			(xy 215.72606 -0.363507) (xy 215.81035 -0.347751) (xy 215.895733 -0.339839) (xy 215.981483 -0.339839)
			(xy 216.066866 -0.347751) (xy 216.151156 -0.363507) (xy 216.233632 -0.386974) (xy 216.313591 -0.41795)
			(xy 216.390351 -0.456172) (xy 216.463257 -0.501313) (xy 216.531686 -0.552989) (xy 216.595056 -0.610758)
			(xy 216.652825 -0.674128) (xy 216.704501 -0.742557) (xy 216.749642 -0.815463) (xy 216.787864 -0.892223)
			(xy 216.81884 -0.972182) (xy 216.842307 -1.054658) (xy 216.858063 -1.138948) (xy 216.865975 -1.224331)
			(xy 216.86647 -1.267206) (xy 216.865975 -1.310081) (xy 296.143921 -1.310081) (xy 296.143921 -1.224331)
			(xy 296.151833 -1.138948) (xy 296.167589 -1.054658) (xy 296.191056 -0.972182) (xy 296.222032 -0.892223)
			(xy 296.260254 -0.815463) (xy 296.305395 -0.742557) (xy 296.357071 -0.674128) (xy 296.41484 -0.610758)
			(xy 296.47821 -0.552989) (xy 296.546639 -0.501313) (xy 296.619545 -0.456172) (xy 296.696305 -0.41795)
			(xy 296.776264 -0.386974) (xy 296.85874 -0.363507) (xy 296.94303 -0.347751) (xy 297.028413 -0.339839)
			(xy 297.114163 -0.339839) (xy 297.199546 -0.347751) (xy 297.283836 -0.363507) (xy 297.366312 -0.386974)
			(xy 297.446271 -0.41795) (xy 297.523031 -0.456172) (xy 297.595937 -0.501313) (xy 297.664366 -0.552989)
			(xy 297.727736 -0.610758) (xy 297.785505 -0.674128) (xy 297.837181 -0.742557) (xy 297.882322 -0.815463)
			(xy 297.920544 -0.892223) (xy 297.95152 -0.972182) (xy 297.974987 -1.054658) (xy 297.990743 -1.138948)
			(xy 297.998655 -1.224331) (xy 297.99915 -1.267206) (xy 297.998655 -1.310081) (xy 302.493921 -1.310081)
			(xy 302.493921 -1.224331) (xy 302.501833 -1.138948) (xy 302.517589 -1.054658) (xy 302.541056 -0.972182)
			(xy 302.572032 -0.892223) (xy 302.610254 -0.815463) (xy 302.655395 -0.742557) (xy 302.707071 -0.674128)
			(xy 302.76484 -0.610758) (xy 302.82821 -0.552989) (xy 302.896639 -0.501313) (xy 302.969545 -0.456172)
			(xy 303.046305 -0.41795) (xy 303.126264 -0.386974) (xy 303.20874 -0.363507) (xy 303.29303 -0.347751)
			(xy 303.378413 -0.339839) (xy 303.464163 -0.339839) (xy 303.549546 -0.347751) (xy 303.633836 -0.363507)
			(xy 303.716312 -0.386974) (xy 303.796271 -0.41795) (xy 303.873031 -0.456172) (xy 303.945937 -0.501313)
			(xy 304.014366 -0.552989) (xy 304.077736 -0.610758) (xy 304.135505 -0.674128) (xy 304.187181 -0.742557)
			(xy 304.232322 -0.815463) (xy 304.270544 -0.892223) (xy 304.30152 -0.972182) (xy 304.324987 -1.054658)
			(xy 304.340743 -1.138948) (xy 304.348655 -1.224331) (xy 304.34915 -1.267206) (xy 304.348655 -1.310081)
			(xy 311.155321 -1.310081) (xy 311.155321 -1.224331) (xy 311.163233 -1.138948) (xy 311.178989 -1.054658)
			(xy 311.202456 -0.972182) (xy 311.233432 -0.892223) (xy 311.271654 -0.815463) (xy 311.316795 -0.742557)
			(xy 311.368471 -0.674128) (xy 311.42624 -0.610758) (xy 311.48961 -0.552989) (xy 311.558039 -0.501313)
			(xy 311.630945 -0.456172) (xy 311.707705 -0.41795) (xy 311.787664 -0.386974) (xy 311.87014 -0.363507)
			(xy 311.95443 -0.347751) (xy 312.039813 -0.339839) (xy 312.125563 -0.339839) (xy 312.210946 -0.347751)
			(xy 312.295236 -0.363507) (xy 312.377712 -0.386974) (xy 312.457671 -0.41795) (xy 312.478344 -0.428244)
			(xy 316.012068 -0.428244) (xy 316.012068 0.435356) (xy 316.012572 0.46491) (xy 316.020621 0.523466)
			(xy 316.036567 0.580381) (xy 316.060116 0.634595) (xy 316.090827 0.685098) (xy 316.128129 0.730948)
			(xy 316.171326 0.771291) (xy 316.219615 0.805377) (xy 316.272095 0.83257) (xy 316.32779 0.852364)
			(xy 316.385661 0.86439) (xy 316.44463 0.868424) (xy 316.503599 0.86439) (xy 316.56147 0.852364) (xy 316.617165 0.83257)
			(xy 316.669645 0.805377) (xy 316.717934 0.771291) (xy 316.761131 0.730948) (xy 316.798433 0.685098)
			(xy 316.829144 0.634595) (xy 316.852693 0.580381) (xy 316.868639 0.523466) (xy 316.876688 0.46491)
			(xy 316.877192 0.435356) (xy 316.877192 -0.428244) (xy 316.876688 -0.457798) (xy 316.868639 -0.516354)
			(xy 316.852693 -0.573269) (xy 316.829144 -0.627483) (xy 316.798433 -0.677986) (xy 316.761131 -0.723836)
			(xy 316.717934 -0.764179) (xy 316.669645 -0.798265) (xy 316.617165 -0.825458) (xy 316.56147 -0.845252)
			(xy 316.503599 -0.857278) (xy 316.44463 -0.861312) (xy 316.385661 -0.857278) (xy 316.32779 -0.845252)
			(xy 316.272095 -0.825458) (xy 316.219615 -0.798265) (xy 316.171326 -0.764179) (xy 316.128129 -0.723836)
			(xy 316.090827 -0.677986) (xy 316.060116 -0.627483) (xy 316.036567 -0.573269) (xy 316.020621 -0.516354)
			(xy 316.012572 -0.457798) (xy 316.012068 -0.428244) (xy 312.478344 -0.428244) (xy 312.534431 -0.456172)
			(xy 312.607337 -0.501313) (xy 312.675766 -0.552989) (xy 312.739136 -0.610758) (xy 312.796905 -0.674128)
			(xy 312.848581 -0.742557) (xy 312.893722 -0.815463) (xy 312.931944 -0.892223) (xy 312.96292 -0.972182)
			(xy 312.986387 -1.054658) (xy 313.002143 -1.138948) (xy 313.010055 -1.224331) (xy 313.01055 -1.267206)
			(xy 313.010055 -1.310081) (xy 317.505321 -1.310081) (xy 317.505321 -1.224331) (xy 317.513233 -1.138948)
			(xy 317.528989 -1.054658) (xy 317.552456 -0.972182) (xy 317.583432 -0.892223) (xy 317.621654 -0.815463)
			(xy 317.666795 -0.742557) (xy 317.718471 -0.674128) (xy 317.77624 -0.610758) (xy 317.83961 -0.552989)
			(xy 317.908039 -0.501313) (xy 317.980945 -0.456172) (xy 318.057705 -0.41795) (xy 318.137664 -0.386974)
			(xy 318.22014 -0.363507) (xy 318.30443 -0.347751) (xy 318.389813 -0.339839) (xy 318.475563 -0.339839)
			(xy 318.560946 -0.347751) (xy 318.645236 -0.363507) (xy 318.727712 -0.386974) (xy 318.807671 -0.41795)
			(xy 318.884431 -0.456172) (xy 318.957337 -0.501313) (xy 319.025766 -0.552989) (xy 319.089136 -0.610758)
			(xy 319.146905 -0.674128) (xy 319.198581 -0.742557) (xy 319.243722 -0.815463) (xy 319.281944 -0.892223)
			(xy 319.31292 -0.972182) (xy 319.336387 -1.054658) (xy 319.352143 -1.138948) (xy 319.360055 -1.224331)
			(xy 319.36055 -1.267206) (xy 319.360055 -1.310081) (xy 361.894107 -1.310081) (xy 361.894107 -1.224331)
			(xy 361.902019 -1.138948) (xy 361.917775 -1.054658) (xy 361.941242 -0.972182) (xy 361.972218 -0.892223)
			(xy 362.01044 -0.815463) (xy 362.055581 -0.742557) (xy 362.107257 -0.674128) (xy 362.165026 -0.610758)
			(xy 362.228396 -0.552989) (xy 362.296825 -0.501313) (xy 362.369731 -0.456172) (xy 362.446491 -0.41795)
			(xy 362.52645 -0.386974) (xy 362.608926 -0.363507) (xy 362.693216 -0.347751) (xy 362.778599 -0.339839)
			(xy 362.864349 -0.339839) (xy 362.949732 -0.347751) (xy 363.034022 -0.363507) (xy 363.116498 -0.386974)
			(xy 363.196457 -0.41795) (xy 363.21713 -0.428244) (xy 364.379764 -0.428244) (xy 364.379764 0.435356)
			(xy 364.380268 0.464892) (xy 364.388312 0.523414) (xy 364.404249 0.580296) (xy 364.427784 0.634478)
			(xy 364.458477 0.684951) (xy 364.495757 0.730774) (xy 364.538929 0.771094) (xy 364.587189 0.80516)
			(xy 364.639639 0.832337) (xy 364.6953 0.852119) (xy 364.753137 0.864138) (xy 364.812072 0.868169)
			(xy 364.871007 0.864138) (xy 364.928844 0.852119) (xy 364.984505 0.832337) (xy 365.036955 0.80516)
			(xy 365.085215 0.771094) (xy 365.128387 0.730774) (xy 365.165667 0.684951) (xy 365.19636 0.634478)
			(xy 365.219895 0.580296) (xy 365.235832 0.523414) (xy 365.243876 0.464892) (xy 365.24438 0.435356)
			(xy 365.24438 -0.428244) (xy 365.243876 -0.45778) (xy 365.235832 -0.516302) (xy 365.219895 -0.573184)
			(xy 365.19636 -0.627366) (xy 365.165667 -0.677839) (xy 365.128387 -0.723662) (xy 365.085215 -0.763982)
			(xy 365.036955 -0.798048) (xy 364.984505 -0.825225) (xy 364.928844 -0.845007) (xy 364.871007 -0.857026)
			(xy 364.812072 -0.861057) (xy 364.753137 -0.857026) (xy 364.6953 -0.845007) (xy 364.639639 -0.825225)
			(xy 364.587189 -0.798048) (xy 364.538929 -0.763982) (xy 364.495757 -0.723662) (xy 364.458477 -0.677839)
			(xy 364.427784 -0.627366) (xy 364.404249 -0.573184) (xy 364.388312 -0.516302) (xy 364.380268 -0.45778)
			(xy 364.379764 -0.428244) (xy 363.21713 -0.428244) (xy 363.273217 -0.456172) (xy 363.346123 -0.501313)
			(xy 363.414552 -0.552989) (xy 363.477922 -0.610758) (xy 363.535691 -0.674128) (xy 363.587367 -0.742557)
			(xy 363.632508 -0.815463) (xy 363.67073 -0.892223) (xy 363.701706 -0.972182) (xy 363.725173 -1.054658)
			(xy 363.740929 -1.138948) (xy 363.748841 -1.224331) (xy 363.749336 -1.267206) (xy 363.748841 -1.310081)
			(xy 368.244107 -1.310081) (xy 368.244107 -1.224331) (xy 368.252019 -1.138948) (xy 368.267775 -1.054658)
			(xy 368.291242 -0.972182) (xy 368.322218 -0.892223) (xy 368.36044 -0.815463) (xy 368.405581 -0.742557)
			(xy 368.457257 -0.674128) (xy 368.515026 -0.610758) (xy 368.578396 -0.552989) (xy 368.646825 -0.501313)
			(xy 368.719731 -0.456172) (xy 368.796491 -0.41795) (xy 368.87645 -0.386974) (xy 368.958926 -0.363507)
			(xy 369.043216 -0.347751) (xy 369.128599 -0.339839) (xy 369.214349 -0.339839) (xy 369.299732 -0.347751)
			(xy 369.384022 -0.363507) (xy 369.466498 -0.386974) (xy 369.546457 -0.41795) (xy 369.623217 -0.456172)
			(xy 369.696123 -0.501313) (xy 369.764552 -0.552989) (xy 369.827922 -0.610758) (xy 369.885691 -0.674128)
			(xy 369.937367 -0.742557) (xy 369.982508 -0.815463) (xy 370.02073 -0.892223) (xy 370.051706 -0.972182)
			(xy 370.075173 -1.054658) (xy 370.090929 -1.138948) (xy 370.098841 -1.224331) (xy 370.099336 -1.267206)
			(xy 370.098841 -1.310081) (xy 370.090929 -1.395464) (xy 370.075173 -1.479754) (xy 370.051706 -1.56223)
			(xy 370.02073 -1.642189) (xy 369.982508 -1.718949) (xy 369.937367 -1.791855) (xy 369.885691 -1.860284)
			(xy 369.827922 -1.923654) (xy 369.764552 -1.981423) (xy 369.696123 -2.033099) (xy 369.623217 -2.07824)
			(xy 369.546457 -2.116462) (xy 369.466498 -2.147438) (xy 369.384022 -2.170905) (xy 369.299732 -2.186661)
			(xy 369.214349 -2.194573) (xy 369.128599 -2.194573) (xy 369.043216 -2.186661) (xy 368.958926 -2.170905)
			(xy 368.87645 -2.147438) (xy 368.796491 -2.116462) (xy 368.719731 -2.07824) (xy 368.646825 -2.033099)
			(xy 368.578396 -1.981423) (xy 368.515026 -1.923654) (xy 368.457257 -1.860284) (xy 368.405581 -1.791855)
			(xy 368.36044 -1.718949) (xy 368.322218 -1.642189) (xy 368.291242 -1.56223) (xy 368.267775 -1.479754)
			(xy 368.252019 -1.395464) (xy 368.244107 -1.310081) (xy 363.748841 -1.310081) (xy 363.740929 -1.395464)
			(xy 363.725173 -1.479754) (xy 363.701706 -1.56223) (xy 363.67073 -1.642189) (xy 363.632508 -1.718949)
			(xy 363.587367 -1.791855) (xy 363.535691 -1.860284) (xy 363.477922 -1.923654) (xy 363.414552 -1.981423)
			(xy 363.346123 -2.033099) (xy 363.273217 -2.07824) (xy 363.196457 -2.116462) (xy 363.116498 -2.147438)
			(xy 363.034022 -2.170905) (xy 362.949732 -2.186661) (xy 362.864349 -2.194573) (xy 362.778599 -2.194573)
			(xy 362.693216 -2.186661) (xy 362.608926 -2.170905) (xy 362.52645 -2.147438) (xy 362.446491 -2.116462)
			(xy 362.369731 -2.07824) (xy 362.296825 -2.033099) (xy 362.228396 -1.981423) (xy 362.165026 -1.923654)
			(xy 362.107257 -1.860284) (xy 362.055581 -1.791855) (xy 362.01044 -1.718949) (xy 361.972218 -1.642189)
			(xy 361.941242 -1.56223) (xy 361.917775 -1.479754) (xy 361.902019 -1.395464) (xy 361.894107 -1.310081)
			(xy 319.360055 -1.310081) (xy 319.352143 -1.395464) (xy 319.336387 -1.479754) (xy 319.31292 -1.56223)
			(xy 319.281944 -1.642189) (xy 319.243722 -1.718949) (xy 319.198581 -1.791855) (xy 319.146905 -1.860284)
			(xy 319.089136 -1.923654) (xy 319.025766 -1.981423) (xy 318.957337 -2.033099) (xy 318.884431 -2.07824)
			(xy 318.807671 -2.116462) (xy 318.727712 -2.147438) (xy 318.645236 -2.170905) (xy 318.560946 -2.186661)
			(xy 318.475563 -2.194573) (xy 318.389813 -2.194573) (xy 318.30443 -2.186661) (xy 318.22014 -2.170905)
			(xy 318.137664 -2.147438) (xy 318.057705 -2.116462) (xy 317.980945 -2.07824) (xy 317.908039 -2.033099)
			(xy 317.83961 -1.981423) (xy 317.77624 -1.923654) (xy 317.718471 -1.860284) (xy 317.666795 -1.791855)
			(xy 317.621654 -1.718949) (xy 317.583432 -1.642189) (xy 317.552456 -1.56223) (xy 317.528989 -1.479754)
			(xy 317.513233 -1.395464) (xy 317.505321 -1.310081) (xy 313.010055 -1.310081) (xy 313.002143 -1.395464)
			(xy 312.986387 -1.479754) (xy 312.96292 -1.56223) (xy 312.931944 -1.642189) (xy 312.893722 -1.718949)
			(xy 312.848581 -1.791855) (xy 312.796905 -1.860284) (xy 312.739136 -1.923654) (xy 312.675766 -1.981423)
			(xy 312.607337 -2.033099) (xy 312.534431 -2.07824) (xy 312.457671 -2.116462) (xy 312.377712 -2.147438)
			(xy 312.295236 -2.170905) (xy 312.210946 -2.186661) (xy 312.125563 -2.194573) (xy 312.039813 -2.194573)
			(xy 311.95443 -2.186661) (xy 311.87014 -2.170905) (xy 311.787664 -2.147438) (xy 311.707705 -2.116462)
			(xy 311.630945 -2.07824) (xy 311.558039 -2.033099) (xy 311.48961 -1.981423) (xy 311.42624 -1.923654)
			(xy 311.368471 -1.860284) (xy 311.316795 -1.791855) (xy 311.271654 -1.718949) (xy 311.233432 -1.642189)
			(xy 311.202456 -1.56223) (xy 311.178989 -1.479754) (xy 311.163233 -1.395464) (xy 311.155321 -1.310081)
			(xy 304.348655 -1.310081) (xy 304.340743 -1.395464) (xy 304.324987 -1.479754) (xy 304.30152 -1.56223)
			(xy 304.270544 -1.642189) (xy 304.232322 -1.718949) (xy 304.187181 -1.791855) (xy 304.135505 -1.860284)
			(xy 304.077736 -1.923654) (xy 304.014366 -1.981423) (xy 303.945937 -2.033099) (xy 303.873031 -2.07824)
			(xy 303.796271 -2.116462) (xy 303.716312 -2.147438) (xy 303.633836 -2.170905) (xy 303.549546 -2.186661)
			(xy 303.464163 -2.194573) (xy 303.378413 -2.194573) (xy 303.29303 -2.186661) (xy 303.20874 -2.170905)
			(xy 303.126264 -2.147438) (xy 303.046305 -2.116462) (xy 302.969545 -2.07824) (xy 302.896639 -2.033099)
			(xy 302.82821 -1.981423) (xy 302.76484 -1.923654) (xy 302.707071 -1.860284) (xy 302.655395 -1.791855)
			(xy 302.610254 -1.718949) (xy 302.572032 -1.642189) (xy 302.541056 -1.56223) (xy 302.517589 -1.479754)
			(xy 302.501833 -1.395464) (xy 302.493921 -1.310081) (xy 297.998655 -1.310081) (xy 297.990743 -1.395464)
			(xy 297.974987 -1.479754) (xy 297.95152 -1.56223) (xy 297.920544 -1.642189) (xy 297.882322 -1.718949)
			(xy 297.837181 -1.791855) (xy 297.785505 -1.860284) (xy 297.727736 -1.923654) (xy 297.664366 -1.981423)
			(xy 297.595937 -2.033099) (xy 297.523031 -2.07824) (xy 297.446271 -2.116462) (xy 297.366312 -2.147438)
			(xy 297.283836 -2.170905) (xy 297.199546 -2.186661) (xy 297.114163 -2.194573) (xy 297.028413 -2.194573)
			(xy 296.94303 -2.186661) (xy 296.85874 -2.170905) (xy 296.776264 -2.147438) (xy 296.696305 -2.116462)
			(xy 296.619545 -2.07824) (xy 296.546639 -2.033099) (xy 296.47821 -1.981423) (xy 296.41484 -1.923654)
			(xy 296.357071 -1.860284) (xy 296.305395 -1.791855) (xy 296.260254 -1.718949) (xy 296.222032 -1.642189)
			(xy 296.191056 -1.56223) (xy 296.167589 -1.479754) (xy 296.151833 -1.395464) (xy 296.143921 -1.310081)
			(xy 216.865975 -1.310081) (xy 216.858063 -1.395464) (xy 216.842307 -1.479754) (xy 216.81884 -1.56223)
			(xy 216.787864 -1.642189) (xy 216.749642 -1.718949) (xy 216.704501 -1.791855) (xy 216.652825 -1.860284)
			(xy 216.595056 -1.923654) (xy 216.531686 -1.981423) (xy 216.463257 -2.033099) (xy 216.390351 -2.07824)
			(xy 216.313591 -2.116462) (xy 216.233632 -2.147438) (xy 216.151156 -2.170905) (xy 216.066866 -2.186661)
			(xy 215.981483 -2.194573) (xy 215.895733 -2.194573) (xy 215.81035 -2.186661) (xy 215.72606 -2.170905)
			(xy 215.643584 -2.147438) (xy 215.563625 -2.116462) (xy 215.486865 -2.07824) (xy 215.413959 -2.033099)
			(xy 215.34553 -1.981423) (xy 215.28216 -1.923654) (xy 215.224391 -1.860284) (xy 215.172715 -1.791855)
			(xy 215.127574 -1.718949) (xy 215.089352 -1.642189) (xy 215.058376 -1.56223) (xy 215.034909 -1.479754)
			(xy 215.019153 -1.395464) (xy 215.011241 -1.310081) (xy 210.515975 -1.310081) (xy 210.508063 -1.395464)
			(xy 210.492307 -1.479754) (xy 210.46884 -1.56223) (xy 210.437864 -1.642189) (xy 210.399642 -1.718949)
			(xy 210.354501 -1.791855) (xy 210.302825 -1.860284) (xy 210.245056 -1.923654) (xy 210.181686 -1.981423)
			(xy 210.113257 -2.033099) (xy 210.040351 -2.07824) (xy 209.963591 -2.116462) (xy 209.883632 -2.147438)
			(xy 209.801156 -2.170905) (xy 209.716866 -2.186661) (xy 209.631483 -2.194573) (xy 209.545733 -2.194573)
			(xy 209.46035 -2.186661) (xy 209.37606 -2.170905) (xy 209.293584 -2.147438) (xy 209.213625 -2.116462)
			(xy 209.136865 -2.07824) (xy 209.063959 -2.033099) (xy 208.99553 -1.981423) (xy 208.93216 -1.923654)
			(xy 208.874391 -1.860284) (xy 208.822715 -1.791855) (xy 208.777574 -1.718949) (xy 208.739352 -1.642189)
			(xy 208.708376 -1.56223) (xy 208.684909 -1.479754) (xy 208.669153 -1.395464) (xy 208.661241 -1.310081)
			(xy 84.210906 -1.310081) (xy 84.210906 -7.78002) (xy 84.211428 -7.835789) (xy 84.219765 -7.947014)
			(xy 84.23639 -8.057306) (xy 84.26121 -8.166046) (xy 84.294088 -8.272628) (xy 84.334838 -8.376455)
			(xy 84.383233 -8.476947) (xy 84.439002 -8.573541) (xy 84.501834 -8.665697) (xy 84.571376 -8.7529)
			(xy 84.647241 -8.834663) (xy 84.729004 -8.910527) (xy 84.816208 -8.98007) (xy 84.908364 -9.042901)
			(xy 85.004959 -9.09867) (xy 85.10545 -9.147065) (xy 85.209277 -9.187814) (xy 85.315859 -9.220691)
			(xy 85.4246 -9.245511) (xy 85.534892 -9.262136) (xy 85.646117 -9.270472) (xy 85.701886 -9.271) (xy 122.102118 -9.271)
			(xy 122.157887 -9.270478) (xy 122.269113 -9.262141) (xy 122.379404 -9.245517) (xy 122.488145 -9.220696)
			(xy 122.594728 -9.187819) (xy 122.698555 -9.147069) (xy 122.799047 -9.098674) (xy 122.895641 -9.042905)
			(xy 122.987798 -8.980073) (xy 123.075001 -8.910531) (xy 123.156764 -8.834666) (xy 123.232629 -8.752903)
			(xy 123.302172 -8.665699) (xy 123.365004 -8.573543) (xy 123.420773 -8.476948) (xy 123.469168 -8.376457)
			(xy 123.509918 -8.27263) (xy 123.542796 -8.166047) (xy 123.567616 -8.057306) (xy 123.584241 -7.947015)
			(xy 123.592578 -7.835789) (xy 123.593098 -7.78002) (xy 123.593098 -4.879848) (xy 123.593581 -4.809465)
			(xy 123.601472 -4.66892) (xy 123.61723 -4.529038) (xy 123.640807 -4.39026) (xy 123.672128 -4.253022)
			(xy 123.711095 -4.117757) (xy 123.757586 -3.984889) (xy 123.811453 -3.854837) (xy 123.872528 -3.72801)
			(xy 123.940618 -3.604807) (xy 124.015509 -3.485616) (xy 124.096965 -3.370811) (xy 124.184731 -3.260755)
			(xy 124.278529 -3.155793) (xy 124.378065 -3.056255) (xy 124.483026 -2.962455) (xy 124.593081 -2.874688)
			(xy 124.707884 -2.79323) (xy 124.827074 -2.718337) (xy 124.950276 -2.650245) (xy 125.077102 -2.589169)
			(xy 125.207153 -2.535299) (xy 125.340021 -2.488807) (xy 125.475285 -2.449838) (xy 125.612523 -2.418514)
			(xy 125.7513 -2.394935) (xy 125.891182 -2.379175) (xy 126.031727 -2.371282) (xy 126.10211 -2.370836)
			(xy 194.701922 -2.370836) (xy 194.772304 -2.371321) (xy 194.912845 -2.379215) (xy 195.052723 -2.394977)
			(xy 195.191497 -2.418557) (xy 195.328731 -2.449881) (xy 195.463992 -2.488851) (xy 195.596856 -2.535344)
			(xy 195.726904 -2.589213) (xy 195.853726 -2.650289) (xy 195.976925 -2.71838) (xy 196.096111 -2.793273)
			(xy 196.210911 -2.87473) (xy 196.320963 -2.962495) (xy 196.425921 -3.056294) (xy 196.525454 -3.15583)
			(xy 196.61925 -3.26079) (xy 196.707012 -3.370845) (xy 196.788466 -3.485647) (xy 196.863355 -3.604836)
			(xy 196.931443 -3.728036) (xy 196.990215 -3.850081) (xy 208.661241 -3.850081) (xy 208.661241 -3.764331)
			(xy 208.669153 -3.678948) (xy 208.684909 -3.594658) (xy 208.708376 -3.512182) (xy 208.739352 -3.432223)
			(xy 208.777574 -3.355463) (xy 208.822715 -3.282557) (xy 208.874391 -3.214128) (xy 208.93216 -3.150758)
			(xy 208.99553 -3.092989) (xy 209.063959 -3.041313) (xy 209.136865 -2.996172) (xy 209.213625 -2.95795)
			(xy 209.293584 -2.926974) (xy 209.37606 -2.903507) (xy 209.46035 -2.887751) (xy 209.545733 -2.879839)
			(xy 209.631483 -2.879839) (xy 209.716866 -2.887751) (xy 209.801156 -2.903507) (xy 209.883632 -2.926974)
			(xy 209.963591 -2.95795) (xy 209.984264 -2.968244) (xy 213.517988 -2.968244) (xy 213.517988 -2.104644)
			(xy 213.518492 -2.07509) (xy 213.526541 -2.016534) (xy 213.542487 -1.959619) (xy 213.566036 -1.905405)
			(xy 213.596747 -1.854902) (xy 213.634049 -1.809052) (xy 213.677246 -1.768709) (xy 213.725535 -1.734623)
			(xy 213.778015 -1.70743) (xy 213.83371 -1.687636) (xy 213.891581 -1.67561) (xy 213.95055 -1.671577)
			(xy 214.009519 -1.67561) (xy 214.06739 -1.687636) (xy 214.123085 -1.70743) (xy 214.175565 -1.734623)
			(xy 214.223854 -1.768709) (xy 214.267051 -1.809052) (xy 214.304353 -1.854902) (xy 214.335064 -1.905405)
			(xy 214.358613 -1.959619) (xy 214.374559 -2.016534) (xy 214.382608 -2.07509) (xy 214.383112 -2.104644)
			(xy 214.383112 -2.968244) (xy 214.382608 -2.997798) (xy 214.374559 -3.056354) (xy 214.358613 -3.113269)
			(xy 214.335064 -3.167483) (xy 214.304353 -3.217986) (xy 214.267051 -3.263836) (xy 214.223854 -3.304179)
			(xy 214.175565 -3.338265) (xy 214.123085 -3.365458) (xy 214.06739 -3.385252) (xy 214.009519 -3.397278)
			(xy 213.95055 -3.401312) (xy 213.891581 -3.397278) (xy 213.83371 -3.385252) (xy 213.778015 -3.365458)
			(xy 213.725535 -3.338265) (xy 213.677246 -3.304179) (xy 213.634049 -3.263836) (xy 213.596747 -3.217986)
			(xy 213.566036 -3.167483) (xy 213.542487 -3.113269) (xy 213.526541 -3.056354) (xy 213.518492 -2.997798)
			(xy 213.517988 -2.968244) (xy 209.984264 -2.968244) (xy 210.040351 -2.996172) (xy 210.113257 -3.041313)
			(xy 210.181686 -3.092989) (xy 210.245056 -3.150758) (xy 210.302825 -3.214128) (xy 210.354501 -3.282557)
			(xy 210.399642 -3.355463) (xy 210.437864 -3.432223) (xy 210.46884 -3.512182) (xy 210.492307 -3.594658)
			(xy 210.508063 -3.678948) (xy 210.515975 -3.764331) (xy 210.51647 -3.807206) (xy 210.515975 -3.850081)
			(xy 215.011241 -3.850081) (xy 215.011241 -3.764331) (xy 215.019153 -3.678948) (xy 215.034909 -3.594658)
			(xy 215.058376 -3.512182) (xy 215.089352 -3.432223) (xy 215.127574 -3.355463) (xy 215.172715 -3.282557)
			(xy 215.224391 -3.214128) (xy 215.28216 -3.150758) (xy 215.34553 -3.092989) (xy 215.413959 -3.041313)
			(xy 215.486865 -2.996172) (xy 215.563625 -2.95795) (xy 215.643584 -2.926974) (xy 215.72606 -2.903507)
			(xy 215.81035 -2.887751) (xy 215.895733 -2.879839) (xy 215.981483 -2.879839) (xy 216.066866 -2.887751)
			(xy 216.151156 -2.903507) (xy 216.233632 -2.926974) (xy 216.313591 -2.95795) (xy 216.390351 -2.996172)
			(xy 216.463257 -3.041313) (xy 216.531686 -3.092989) (xy 216.595056 -3.150758) (xy 216.652825 -3.214128)
			(xy 216.704501 -3.282557) (xy 216.749642 -3.355463) (xy 216.787864 -3.432223) (xy 216.81884 -3.512182)
			(xy 216.842307 -3.594658) (xy 216.858063 -3.678948) (xy 216.865975 -3.764331) (xy 216.86647 -3.807206)
			(xy 216.865975 -3.850081) (xy 296.143921 -3.850081) (xy 296.143921 -3.764331) (xy 296.151833 -3.678948)
			(xy 296.167589 -3.594658) (xy 296.191056 -3.512182) (xy 296.222032 -3.432223) (xy 296.260254 -3.355463)
			(xy 296.305395 -3.282557) (xy 296.357071 -3.214128) (xy 296.41484 -3.150758) (xy 296.47821 -3.092989)
			(xy 296.546639 -3.041313) (xy 296.619545 -2.996172) (xy 296.696305 -2.95795) (xy 296.776264 -2.926974)
			(xy 296.85874 -2.903507) (xy 296.94303 -2.887751) (xy 297.028413 -2.879839) (xy 297.114163 -2.879839)
			(xy 297.199546 -2.887751) (xy 297.283836 -2.903507) (xy 297.366312 -2.926974) (xy 297.446271 -2.95795)
			(xy 297.466944 -2.968244) (xy 298.629324 -2.968244) (xy 298.629324 -2.104644) (xy 298.629828 -2.07509)
			(xy 298.637877 -2.016534) (xy 298.653823 -1.959619) (xy 298.677372 -1.905405) (xy 298.708083 -1.854902)
			(xy 298.745385 -1.809052) (xy 298.788582 -1.768709) (xy 298.836871 -1.734623) (xy 298.889351 -1.70743)
			(xy 298.945046 -1.687636) (xy 299.002917 -1.67561) (xy 299.061886 -1.671577) (xy 299.120855 -1.67561)
			(xy 299.178726 -1.687636) (xy 299.234421 -1.70743) (xy 299.286901 -1.734623) (xy 299.33519 -1.768709)
			(xy 299.378387 -1.809052) (xy 299.415689 -1.854902) (xy 299.4464 -1.905405) (xy 299.469949 -1.959619)
			(xy 299.485895 -2.016534) (xy 299.493944 -2.07509) (xy 299.494448 -2.104644) (xy 299.494448 -2.968244)
			(xy 299.493944 -2.997798) (xy 299.485895 -3.056354) (xy 299.469949 -3.113269) (xy 299.4464 -3.167483)
			(xy 299.415689 -3.217986) (xy 299.378387 -3.263836) (xy 299.33519 -3.304179) (xy 299.286901 -3.338265)
			(xy 299.234421 -3.365458) (xy 299.178726 -3.385252) (xy 299.120855 -3.397278) (xy 299.061886 -3.401312)
			(xy 299.002917 -3.397278) (xy 298.945046 -3.385252) (xy 298.889351 -3.365458) (xy 298.836871 -3.338265)
			(xy 298.788582 -3.304179) (xy 298.745385 -3.263836) (xy 298.708083 -3.217986) (xy 298.677372 -3.167483)
			(xy 298.653823 -3.113269) (xy 298.637877 -3.056354) (xy 298.629828 -2.997798) (xy 298.629324 -2.968244)
			(xy 297.466944 -2.968244) (xy 297.523031 -2.996172) (xy 297.595937 -3.041313) (xy 297.664366 -3.092989)
			(xy 297.727736 -3.150758) (xy 297.785505 -3.214128) (xy 297.837181 -3.282557) (xy 297.882322 -3.355463)
			(xy 297.920544 -3.432223) (xy 297.95152 -3.512182) (xy 297.974987 -3.594658) (xy 297.990743 -3.678948)
			(xy 297.998655 -3.764331) (xy 297.99915 -3.807206) (xy 297.998655 -3.850081) (xy 302.493921 -3.850081)
			(xy 302.493921 -3.764331) (xy 302.501833 -3.678948) (xy 302.517589 -3.594658) (xy 302.541056 -3.512182)
			(xy 302.572032 -3.432223) (xy 302.610254 -3.355463) (xy 302.655395 -3.282557) (xy 302.707071 -3.214128)
			(xy 302.76484 -3.150758) (xy 302.82821 -3.092989) (xy 302.896639 -3.041313) (xy 302.969545 -2.996172)
			(xy 303.046305 -2.95795) (xy 303.126264 -2.926974) (xy 303.20874 -2.903507) (xy 303.29303 -2.887751)
			(xy 303.378413 -2.879839) (xy 303.464163 -2.879839) (xy 303.549546 -2.887751) (xy 303.633836 -2.903507)
			(xy 303.716312 -2.926974) (xy 303.796271 -2.95795) (xy 303.873031 -2.996172) (xy 303.945937 -3.041313)
			(xy 304.014366 -3.092989) (xy 304.077736 -3.150758) (xy 304.135505 -3.214128) (xy 304.187181 -3.282557)
			(xy 304.232322 -3.355463) (xy 304.270544 -3.432223) (xy 304.30152 -3.512182) (xy 304.324987 -3.594658)
			(xy 304.340743 -3.678948) (xy 304.348655 -3.764331) (xy 304.34915 -3.807206) (xy 304.348655 -3.850081)
			(xy 311.155321 -3.850081) (xy 311.155321 -3.764331) (xy 311.163233 -3.678948) (xy 311.178989 -3.594658)
			(xy 311.202456 -3.512182) (xy 311.233432 -3.432223) (xy 311.271654 -3.355463) (xy 311.316795 -3.282557)
			(xy 311.368471 -3.214128) (xy 311.42624 -3.150758) (xy 311.48961 -3.092989) (xy 311.558039 -3.041313)
			(xy 311.630945 -2.996172) (xy 311.707705 -2.95795) (xy 311.787664 -2.926974) (xy 311.87014 -2.903507)
			(xy 311.95443 -2.887751) (xy 312.039813 -2.879839) (xy 312.125563 -2.879839) (xy 312.210946 -2.887751)
			(xy 312.295236 -2.903507) (xy 312.377712 -2.926974) (xy 312.457671 -2.95795) (xy 312.478344 -2.968244)
			(xy 316.012068 -2.968244) (xy 316.012068 -2.104644) (xy 316.012572 -2.07509) (xy 316.020621 -2.016534)
			(xy 316.036567 -1.959619) (xy 316.060116 -1.905405) (xy 316.090827 -1.854902) (xy 316.128129 -1.809052)
			(xy 316.171326 -1.768709) (xy 316.219615 -1.734623) (xy 316.272095 -1.70743) (xy 316.32779 -1.687636)
			(xy 316.385661 -1.67561) (xy 316.44463 -1.671577) (xy 316.503599 -1.67561) (xy 316.56147 -1.687636)
			(xy 316.617165 -1.70743) (xy 316.669645 -1.734623) (xy 316.717934 -1.768709) (xy 316.761131 -1.809052)
			(xy 316.798433 -1.854902) (xy 316.829144 -1.905405) (xy 316.852693 -1.959619) (xy 316.868639 -2.016534)
			(xy 316.876688 -2.07509) (xy 316.877192 -2.104644) (xy 316.877192 -2.968244) (xy 316.876688 -2.997798)
			(xy 316.868639 -3.056354) (xy 316.852693 -3.113269) (xy 316.829144 -3.167483) (xy 316.798433 -3.217986)
			(xy 316.761131 -3.263836) (xy 316.717934 -3.304179) (xy 316.669645 -3.338265) (xy 316.617165 -3.365458)
			(xy 316.56147 -3.385252) (xy 316.503599 -3.397278) (xy 316.44463 -3.401312) (xy 316.385661 -3.397278)
			(xy 316.32779 -3.385252) (xy 316.272095 -3.365458) (xy 316.219615 -3.338265) (xy 316.171326 -3.304179)
			(xy 316.128129 -3.263836) (xy 316.090827 -3.217986) (xy 316.060116 -3.167483) (xy 316.036567 -3.113269)
			(xy 316.020621 -3.056354) (xy 316.012572 -2.997798) (xy 316.012068 -2.968244) (xy 312.478344 -2.968244)
			(xy 312.534431 -2.996172) (xy 312.607337 -3.041313) (xy 312.675766 -3.092989) (xy 312.739136 -3.150758)
			(xy 312.796905 -3.214128) (xy 312.848581 -3.282557) (xy 312.893722 -3.355463) (xy 312.931944 -3.432223)
			(xy 312.96292 -3.512182) (xy 312.986387 -3.594658) (xy 313.002143 -3.678948) (xy 313.010055 -3.764331)
			(xy 313.01055 -3.807206) (xy 313.010055 -3.850081) (xy 317.505321 -3.850081) (xy 317.505321 -3.764331)
			(xy 317.513233 -3.678948) (xy 317.528989 -3.594658) (xy 317.552456 -3.512182) (xy 317.583432 -3.432223)
			(xy 317.621654 -3.355463) (xy 317.666795 -3.282557) (xy 317.718471 -3.214128) (xy 317.77624 -3.150758)
			(xy 317.83961 -3.092989) (xy 317.908039 -3.041313) (xy 317.980945 -2.996172) (xy 318.057705 -2.95795)
			(xy 318.137664 -2.926974) (xy 318.22014 -2.903507) (xy 318.30443 -2.887751) (xy 318.389813 -2.879839)
			(xy 318.475563 -2.879839) (xy 318.560946 -2.887751) (xy 318.645236 -2.903507) (xy 318.727712 -2.926974)
			(xy 318.807671 -2.95795) (xy 318.884431 -2.996172) (xy 318.957337 -3.041313) (xy 319.025766 -3.092989)
			(xy 319.089136 -3.150758) (xy 319.146905 -3.214128) (xy 319.198581 -3.282557) (xy 319.243722 -3.355463)
			(xy 319.281944 -3.432223) (xy 319.31292 -3.512182) (xy 319.336387 -3.594658) (xy 319.352143 -3.678948)
			(xy 319.360055 -3.764331) (xy 319.36055 -3.807206) (xy 319.360055 -3.850081) (xy 361.894107 -3.850081)
			(xy 361.894107 -3.764331) (xy 361.902019 -3.678948) (xy 361.917775 -3.594658) (xy 361.941242 -3.512182)
			(xy 361.972218 -3.432223) (xy 362.01044 -3.355463) (xy 362.055581 -3.282557) (xy 362.107257 -3.214128)
			(xy 362.165026 -3.150758) (xy 362.228396 -3.092989) (xy 362.296825 -3.041313) (xy 362.369731 -2.996172)
			(xy 362.446491 -2.95795) (xy 362.52645 -2.926974) (xy 362.608926 -2.903507) (xy 362.693216 -2.887751)
			(xy 362.778599 -2.879839) (xy 362.864349 -2.879839) (xy 362.949732 -2.887751) (xy 363.034022 -2.903507)
			(xy 363.116498 -2.926974) (xy 363.196457 -2.95795) (xy 363.21713 -2.968244) (xy 364.379764 -2.968244)
			(xy 364.379764 -2.104644) (xy 364.380268 -2.075108) (xy 364.388312 -2.016586) (xy 364.404249 -1.959704)
			(xy 364.427784 -1.905522) (xy 364.458477 -1.855049) (xy 364.495757 -1.809226) (xy 364.538929 -1.768906)
			(xy 364.587189 -1.73484) (xy 364.639639 -1.707663) (xy 364.6953 -1.687881) (xy 364.753137 -1.675862)
			(xy 364.812072 -1.671831) (xy 364.871007 -1.675862) (xy 364.928844 -1.687881) (xy 364.984505 -1.707663)
			(xy 365.036955 -1.73484) (xy 365.085215 -1.768906) (xy 365.128387 -1.809226) (xy 365.165667 -1.855049)
			(xy 365.19636 -1.905522) (xy 365.219895 -1.959704) (xy 365.235832 -2.016586) (xy 365.243876 -2.075108)
			(xy 365.24438 -2.104644) (xy 365.24438 -2.968244) (xy 365.243876 -2.99778) (xy 365.235832 -3.056302)
			(xy 365.219895 -3.113184) (xy 365.19636 -3.167366) (xy 365.165667 -3.217839) (xy 365.128387 -3.263662)
			(xy 365.085215 -3.303982) (xy 365.036955 -3.338048) (xy 364.984505 -3.365225) (xy 364.928844 -3.385007)
			(xy 364.871007 -3.397026) (xy 364.812072 -3.401057) (xy 364.753137 -3.397026) (xy 364.6953 -3.385007)
			(xy 364.639639 -3.365225) (xy 364.587189 -3.338048) (xy 364.538929 -3.303982) (xy 364.495757 -3.263662)
			(xy 364.458477 -3.217839) (xy 364.427784 -3.167366) (xy 364.404249 -3.113184) (xy 364.388312 -3.056302)
			(xy 364.380268 -2.99778) (xy 364.379764 -2.968244) (xy 363.21713 -2.968244) (xy 363.273217 -2.996172)
			(xy 363.346123 -3.041313) (xy 363.414552 -3.092989) (xy 363.477922 -3.150758) (xy 363.535691 -3.214128)
			(xy 363.587367 -3.282557) (xy 363.632508 -3.355463) (xy 363.67073 -3.432223) (xy 363.701706 -3.512182)
			(xy 363.725173 -3.594658) (xy 363.740929 -3.678948) (xy 363.748841 -3.764331) (xy 363.749336 -3.807206)
			(xy 363.748841 -3.850081) (xy 368.244107 -3.850081) (xy 368.244107 -3.764331) (xy 368.252019 -3.678948)
			(xy 368.267775 -3.594658) (xy 368.291242 -3.512182) (xy 368.322218 -3.432223) (xy 368.36044 -3.355463)
			(xy 368.405581 -3.282557) (xy 368.457257 -3.214128) (xy 368.515026 -3.150758) (xy 368.578396 -3.092989)
			(xy 368.646825 -3.041313) (xy 368.719731 -2.996172) (xy 368.796491 -2.95795) (xy 368.87645 -2.926974)
			(xy 368.958926 -2.903507) (xy 369.043216 -2.887751) (xy 369.128599 -2.879839) (xy 369.214349 -2.879839)
			(xy 369.299732 -2.887751) (xy 369.384022 -2.903507) (xy 369.466498 -2.926974) (xy 369.546457 -2.95795)
			(xy 369.623217 -2.996172) (xy 369.696123 -3.041313) (xy 369.764552 -3.092989) (xy 369.827922 -3.150758)
			(xy 369.885691 -3.214128) (xy 369.937367 -3.282557) (xy 369.982508 -3.355463) (xy 370.02073 -3.432223)
			(xy 370.051706 -3.512182) (xy 370.075173 -3.594658) (xy 370.090929 -3.678948) (xy 370.098841 -3.764331)
			(xy 370.099336 -3.807206) (xy 370.098841 -3.850081) (xy 370.090929 -3.935464) (xy 370.075173 -4.019754)
			(xy 370.051706 -4.10223) (xy 370.02073 -4.182189) (xy 369.982508 -4.258949) (xy 369.937367 -4.331855)
			(xy 369.885691 -4.400284) (xy 369.827922 -4.463654) (xy 369.764552 -4.521423) (xy 369.696123 -4.573099)
			(xy 369.623217 -4.61824) (xy 369.546457 -4.656462) (xy 369.466498 -4.687438) (xy 369.384022 -4.710905)
			(xy 369.299732 -4.726661) (xy 369.214349 -4.734573) (xy 369.128599 -4.734573) (xy 369.043216 -4.726661)
			(xy 368.958926 -4.710905) (xy 368.87645 -4.687438) (xy 368.796491 -4.656462) (xy 368.719731 -4.61824)
			(xy 368.646825 -4.573099) (xy 368.578396 -4.521423) (xy 368.515026 -4.463654) (xy 368.457257 -4.400284)
			(xy 368.405581 -4.331855) (xy 368.36044 -4.258949) (xy 368.322218 -4.182189) (xy 368.291242 -4.10223)
			(xy 368.267775 -4.019754) (xy 368.252019 -3.935464) (xy 368.244107 -3.850081) (xy 363.748841 -3.850081)
			(xy 363.740929 -3.935464) (xy 363.725173 -4.019754) (xy 363.701706 -4.10223) (xy 363.67073 -4.182189)
			(xy 363.632508 -4.258949) (xy 363.587367 -4.331855) (xy 363.535691 -4.400284) (xy 363.477922 -4.463654)
			(xy 363.414552 -4.521423) (xy 363.346123 -4.573099) (xy 363.273217 -4.61824) (xy 363.196457 -4.656462)
			(xy 363.116498 -4.687438) (xy 363.034022 -4.710905) (xy 362.949732 -4.726661) (xy 362.864349 -4.734573)
			(xy 362.778599 -4.734573) (xy 362.693216 -4.726661) (xy 362.608926 -4.710905) (xy 362.52645 -4.687438)
			(xy 362.446491 -4.656462) (xy 362.369731 -4.61824) (xy 362.296825 -4.573099) (xy 362.228396 -4.521423)
			(xy 362.165026 -4.463654) (xy 362.107257 -4.400284) (xy 362.055581 -4.331855) (xy 362.01044 -4.258949)
			(xy 361.972218 -4.182189) (xy 361.941242 -4.10223) (xy 361.917775 -4.019754) (xy 361.902019 -3.935464)
			(xy 361.894107 -3.850081) (xy 319.360055 -3.850081) (xy 319.352143 -3.935464) (xy 319.336387 -4.019754)
			(xy 319.31292 -4.10223) (xy 319.281944 -4.182189) (xy 319.243722 -4.258949) (xy 319.198581 -4.331855)
			(xy 319.146905 -4.400284) (xy 319.089136 -4.463654) (xy 319.025766 -4.521423) (xy 318.957337 -4.573099)
			(xy 318.884431 -4.61824) (xy 318.807671 -4.656462) (xy 318.727712 -4.687438) (xy 318.645236 -4.710905)
			(xy 318.560946 -4.726661) (xy 318.475563 -4.734573) (xy 318.389813 -4.734573) (xy 318.30443 -4.726661)
			(xy 318.22014 -4.710905) (xy 318.137664 -4.687438) (xy 318.057705 -4.656462) (xy 317.980945 -4.61824)
			(xy 317.908039 -4.573099) (xy 317.83961 -4.521423) (xy 317.77624 -4.463654) (xy 317.718471 -4.400284)
			(xy 317.666795 -4.331855) (xy 317.621654 -4.258949) (xy 317.583432 -4.182189) (xy 317.552456 -4.10223)
			(xy 317.528989 -4.019754) (xy 317.513233 -3.935464) (xy 317.505321 -3.850081) (xy 313.010055 -3.850081)
			(xy 313.002143 -3.935464) (xy 312.986387 -4.019754) (xy 312.96292 -4.10223) (xy 312.931944 -4.182189)
			(xy 312.893722 -4.258949) (xy 312.848581 -4.331855) (xy 312.796905 -4.400284) (xy 312.739136 -4.463654)
			(xy 312.675766 -4.521423) (xy 312.607337 -4.573099) (xy 312.534431 -4.61824) (xy 312.457671 -4.656462)
			(xy 312.377712 -4.687438) (xy 312.295236 -4.710905) (xy 312.210946 -4.726661) (xy 312.125563 -4.734573)
			(xy 312.039813 -4.734573) (xy 311.95443 -4.726661) (xy 311.87014 -4.710905) (xy 311.787664 -4.687438)
			(xy 311.707705 -4.656462) (xy 311.630945 -4.61824) (xy 311.558039 -4.573099) (xy 311.48961 -4.521423)
			(xy 311.42624 -4.463654) (xy 311.368471 -4.400284) (xy 311.316795 -4.331855) (xy 311.271654 -4.258949)
			(xy 311.233432 -4.182189) (xy 311.202456 -4.10223) (xy 311.178989 -4.019754) (xy 311.163233 -3.935464)
			(xy 311.155321 -3.850081) (xy 304.348655 -3.850081) (xy 304.340743 -3.935464) (xy 304.324987 -4.019754)
			(xy 304.30152 -4.10223) (xy 304.270544 -4.182189) (xy 304.232322 -4.258949) (xy 304.187181 -4.331855)
			(xy 304.135505 -4.400284) (xy 304.077736 -4.463654) (xy 304.014366 -4.521423) (xy 303.945937 -4.573099)
			(xy 303.873031 -4.61824) (xy 303.796271 -4.656462) (xy 303.716312 -4.687438) (xy 303.633836 -4.710905)
			(xy 303.549546 -4.726661) (xy 303.464163 -4.734573) (xy 303.378413 -4.734573) (xy 303.29303 -4.726661)
			(xy 303.20874 -4.710905) (xy 303.126264 -4.687438) (xy 303.046305 -4.656462) (xy 302.969545 -4.61824)
			(xy 302.896639 -4.573099) (xy 302.82821 -4.521423) (xy 302.76484 -4.463654) (xy 302.707071 -4.400284)
			(xy 302.655395 -4.331855) (xy 302.610254 -4.258949) (xy 302.572032 -4.182189) (xy 302.541056 -4.10223)
			(xy 302.517589 -4.019754) (xy 302.501833 -3.935464) (xy 302.493921 -3.850081) (xy 297.998655 -3.850081)
			(xy 297.990743 -3.935464) (xy 297.974987 -4.019754) (xy 297.95152 -4.10223) (xy 297.920544 -4.182189)
			(xy 297.882322 -4.258949) (xy 297.837181 -4.331855) (xy 297.785505 -4.400284) (xy 297.727736 -4.463654)
			(xy 297.664366 -4.521423) (xy 297.595937 -4.573099) (xy 297.523031 -4.61824) (xy 297.446271 -4.656462)
			(xy 297.366312 -4.687438) (xy 297.283836 -4.710905) (xy 297.199546 -4.726661) (xy 297.114163 -4.734573)
			(xy 297.028413 -4.734573) (xy 296.94303 -4.726661) (xy 296.85874 -4.710905) (xy 296.776264 -4.687438)
			(xy 296.696305 -4.656462) (xy 296.619545 -4.61824) (xy 296.546639 -4.573099) (xy 296.47821 -4.521423)
			(xy 296.41484 -4.463654) (xy 296.357071 -4.400284) (xy 296.305395 -4.331855) (xy 296.260254 -4.258949)
			(xy 296.222032 -4.182189) (xy 296.191056 -4.10223) (xy 296.167589 -4.019754) (xy 296.151833 -3.935464)
			(xy 296.143921 -3.850081) (xy 216.865975 -3.850081) (xy 216.858063 -3.935464) (xy 216.842307 -4.019754)
			(xy 216.81884 -4.10223) (xy 216.787864 -4.182189) (xy 216.749642 -4.258949) (xy 216.704501 -4.331855)
			(xy 216.652825 -4.400284) (xy 216.595056 -4.463654) (xy 216.531686 -4.521423) (xy 216.463257 -4.573099)
			(xy 216.390351 -4.61824) (xy 216.313591 -4.656462) (xy 216.233632 -4.687438) (xy 216.151156 -4.710905)
			(xy 216.066866 -4.726661) (xy 215.981483 -4.734573) (xy 215.895733 -4.734573) (xy 215.81035 -4.726661)
			(xy 215.72606 -4.710905) (xy 215.643584 -4.687438) (xy 215.563625 -4.656462) (xy 215.486865 -4.61824)
			(xy 215.413959 -4.573099) (xy 215.34553 -4.521423) (xy 215.28216 -4.463654) (xy 215.224391 -4.400284)
			(xy 215.172715 -4.331855) (xy 215.127574 -4.258949) (xy 215.089352 -4.182189) (xy 215.058376 -4.10223)
			(xy 215.034909 -4.019754) (xy 215.019153 -3.935464) (xy 215.011241 -3.850081) (xy 210.515975 -3.850081)
			(xy 210.508063 -3.935464) (xy 210.492307 -4.019754) (xy 210.46884 -4.10223) (xy 210.437864 -4.182189)
			(xy 210.399642 -4.258949) (xy 210.354501 -4.331855) (xy 210.302825 -4.400284) (xy 210.245056 -4.463654)
			(xy 210.181686 -4.521423) (xy 210.113257 -4.573099) (xy 210.040351 -4.61824) (xy 209.963591 -4.656462)
			(xy 209.883632 -4.687438) (xy 209.801156 -4.710905) (xy 209.716866 -4.726661) (xy 209.631483 -4.734573)
			(xy 209.545733 -4.734573) (xy 209.46035 -4.726661) (xy 209.37606 -4.710905) (xy 209.293584 -4.687438)
			(xy 209.213625 -4.656462) (xy 209.136865 -4.61824) (xy 209.063959 -4.573099) (xy 208.99553 -4.521423)
			(xy 208.93216 -4.463654) (xy 208.874391 -4.400284) (xy 208.822715 -4.331855) (xy 208.777574 -4.258949)
			(xy 208.739352 -4.182189) (xy 208.708376 -4.10223) (xy 208.684909 -4.019754) (xy 208.669153 -3.935464)
			(xy 208.661241 -3.850081) (xy 196.990215 -3.850081) (xy 196.992516 -3.85486) (xy 197.046381 -3.984909)
			(xy 197.09287 -4.117774) (xy 197.131836 -4.253037) (xy 197.163157 -4.390271) (xy 197.186733 -4.529046)
			(xy 197.202491 -4.668924) (xy 197.210381 -4.809466) (xy 197.210934 -4.879848) (xy 197.210934 -6.390081)
			(xy 208.661241 -6.390081) (xy 208.661241 -6.304331) (xy 208.669153 -6.218948) (xy 208.684909 -6.134658)
			(xy 208.708376 -6.052182) (xy 208.739352 -5.972223) (xy 208.777574 -5.895463) (xy 208.822715 -5.822557)
			(xy 208.874391 -5.754128) (xy 208.93216 -5.690758) (xy 208.99553 -5.632989) (xy 209.063959 -5.581313)
			(xy 209.136865 -5.536172) (xy 209.213625 -5.49795) (xy 209.293584 -5.466974) (xy 209.37606 -5.443507)
			(xy 209.46035 -5.427751) (xy 209.545733 -5.419839) (xy 209.631483 -5.419839) (xy 209.716866 -5.427751)
			(xy 209.801156 -5.443507) (xy 209.883632 -5.466974) (xy 209.963591 -5.49795) (xy 209.984264 -5.508244)
			(xy 213.517988 -5.508244) (xy 213.517988 -4.644644) (xy 213.518492 -4.61509) (xy 213.526541 -4.556534)
			(xy 213.542487 -4.499619) (xy 213.566036 -4.445405) (xy 213.596747 -4.394902) (xy 213.634049 -4.349052)
			(xy 213.677246 -4.308709) (xy 213.725535 -4.274623) (xy 213.778015 -4.24743) (xy 213.83371 -4.227636)
			(xy 213.891581 -4.21561) (xy 213.95055 -4.211577) (xy 214.009519 -4.21561) (xy 214.06739 -4.227636)
			(xy 214.123085 -4.24743) (xy 214.175565 -4.274623) (xy 214.223854 -4.308709) (xy 214.267051 -4.349052)
			(xy 214.304353 -4.394902) (xy 214.335064 -4.445405) (xy 214.358613 -4.499619) (xy 214.374559 -4.556534)
			(xy 214.382608 -4.61509) (xy 214.383112 -4.644644) (xy 214.383112 -5.508244) (xy 214.382608 -5.537798)
			(xy 214.374559 -5.596354) (xy 214.358613 -5.653269) (xy 214.335064 -5.707483) (xy 214.304353 -5.757986)
			(xy 214.267051 -5.803836) (xy 214.223854 -5.844179) (xy 214.175565 -5.878265) (xy 214.123085 -5.905458)
			(xy 214.06739 -5.925252) (xy 214.009519 -5.937278) (xy 213.95055 -5.941312) (xy 213.891581 -5.937278)
			(xy 213.83371 -5.925252) (xy 213.778015 -5.905458) (xy 213.725535 -5.878265) (xy 213.677246 -5.844179)
			(xy 213.634049 -5.803836) (xy 213.596747 -5.757986) (xy 213.566036 -5.707483) (xy 213.542487 -5.653269)
			(xy 213.526541 -5.596354) (xy 213.518492 -5.537798) (xy 213.517988 -5.508244) (xy 209.984264 -5.508244)
			(xy 210.040351 -5.536172) (xy 210.113257 -5.581313) (xy 210.181686 -5.632989) (xy 210.245056 -5.690758)
			(xy 210.302825 -5.754128) (xy 210.354501 -5.822557) (xy 210.399642 -5.895463) (xy 210.437864 -5.972223)
			(xy 210.46884 -6.052182) (xy 210.492307 -6.134658) (xy 210.508063 -6.218948) (xy 210.515975 -6.304331)
			(xy 210.51647 -6.347206) (xy 210.515975 -6.390081) (xy 215.011241 -6.390081) (xy 215.011241 -6.304331)
			(xy 215.019153 -6.218948) (xy 215.034909 -6.134658) (xy 215.058376 -6.052182) (xy 215.089352 -5.972223)
			(xy 215.127574 -5.895463) (xy 215.172715 -5.822557) (xy 215.224391 -5.754128) (xy 215.28216 -5.690758)
			(xy 215.34553 -5.632989) (xy 215.413959 -5.581313) (xy 215.486865 -5.536172) (xy 215.563625 -5.49795)
			(xy 215.643584 -5.466974) (xy 215.72606 -5.443507) (xy 215.81035 -5.427751) (xy 215.895733 -5.419839)
			(xy 215.981483 -5.419839) (xy 216.066866 -5.427751) (xy 216.151156 -5.443507) (xy 216.233632 -5.466974)
			(xy 216.313591 -5.49795) (xy 216.390351 -5.536172) (xy 216.463257 -5.581313) (xy 216.531686 -5.632989)
			(xy 216.595056 -5.690758) (xy 216.652825 -5.754128) (xy 216.704501 -5.822557) (xy 216.749642 -5.895463)
			(xy 216.787864 -5.972223) (xy 216.81884 -6.052182) (xy 216.842307 -6.134658) (xy 216.858063 -6.218948)
			(xy 216.865975 -6.304331) (xy 216.86647 -6.347206) (xy 216.865975 -6.390081) (xy 296.143921 -6.390081)
			(xy 296.143921 -6.304331) (xy 296.151833 -6.218948) (xy 296.167589 -6.134658) (xy 296.191056 -6.052182)
			(xy 296.222032 -5.972223) (xy 296.260254 -5.895463) (xy 296.305395 -5.822557) (xy 296.357071 -5.754128)
			(xy 296.41484 -5.690758) (xy 296.47821 -5.632989) (xy 296.546639 -5.581313) (xy 296.619545 -5.536172)
			(xy 296.696305 -5.49795) (xy 296.776264 -5.466974) (xy 296.85874 -5.443507) (xy 296.94303 -5.427751)
			(xy 297.028413 -5.419839) (xy 297.114163 -5.419839) (xy 297.199546 -5.427751) (xy 297.283836 -5.443507)
			(xy 297.366312 -5.466974) (xy 297.446271 -5.49795) (xy 297.466944 -5.508244) (xy 298.629324 -5.508244)
			(xy 298.629324 -4.644644) (xy 298.629828 -4.61509) (xy 298.637877 -4.556534) (xy 298.653823 -4.499619)
			(xy 298.677372 -4.445405) (xy 298.708083 -4.394902) (xy 298.745385 -4.349052) (xy 298.788582 -4.308709)
			(xy 298.836871 -4.274623) (xy 298.889351 -4.24743) (xy 298.945046 -4.227636) (xy 299.002917 -4.21561)
			(xy 299.061886 -4.211577) (xy 299.120855 -4.21561) (xy 299.178726 -4.227636) (xy 299.234421 -4.24743)
			(xy 299.286901 -4.274623) (xy 299.33519 -4.308709) (xy 299.378387 -4.349052) (xy 299.415689 -4.394902)
			(xy 299.4464 -4.445405) (xy 299.469949 -4.499619) (xy 299.485895 -4.556534) (xy 299.493944 -4.61509)
			(xy 299.494448 -4.644644) (xy 299.494448 -5.508244) (xy 299.493944 -5.537798) (xy 299.485895 -5.596354)
			(xy 299.469949 -5.653269) (xy 299.4464 -5.707483) (xy 299.415689 -5.757986) (xy 299.378387 -5.803836)
			(xy 299.33519 -5.844179) (xy 299.286901 -5.878265) (xy 299.234421 -5.905458) (xy 299.178726 -5.925252)
			(xy 299.120855 -5.937278) (xy 299.061886 -5.941312) (xy 299.002917 -5.937278) (xy 298.945046 -5.925252)
			(xy 298.889351 -5.905458) (xy 298.836871 -5.878265) (xy 298.788582 -5.844179) (xy 298.745385 -5.803836)
			(xy 298.708083 -5.757986) (xy 298.677372 -5.707483) (xy 298.653823 -5.653269) (xy 298.637877 -5.596354)
			(xy 298.629828 -5.537798) (xy 298.629324 -5.508244) (xy 297.466944 -5.508244) (xy 297.523031 -5.536172)
			(xy 297.595937 -5.581313) (xy 297.664366 -5.632989) (xy 297.727736 -5.690758) (xy 297.785505 -5.754128)
			(xy 297.837181 -5.822557) (xy 297.882322 -5.895463) (xy 297.920544 -5.972223) (xy 297.95152 -6.052182)
			(xy 297.974987 -6.134658) (xy 297.990743 -6.218948) (xy 297.998655 -6.304331) (xy 297.99915 -6.347206)
			(xy 297.998655 -6.390081) (xy 302.493921 -6.390081) (xy 302.493921 -6.304331) (xy 302.501833 -6.218948)
			(xy 302.517589 -6.134658) (xy 302.541056 -6.052182) (xy 302.572032 -5.972223) (xy 302.610254 -5.895463)
			(xy 302.655395 -5.822557) (xy 302.707071 -5.754128) (xy 302.76484 -5.690758) (xy 302.82821 -5.632989)
			(xy 302.896639 -5.581313) (xy 302.969545 -5.536172) (xy 303.046305 -5.49795) (xy 303.126264 -5.466974)
			(xy 303.20874 -5.443507) (xy 303.29303 -5.427751) (xy 303.378413 -5.419839) (xy 303.464163 -5.419839)
			(xy 303.549546 -5.427751) (xy 303.633836 -5.443507) (xy 303.716312 -5.466974) (xy 303.796271 -5.49795)
			(xy 303.873031 -5.536172) (xy 303.945937 -5.581313) (xy 304.014366 -5.632989) (xy 304.077736 -5.690758)
			(xy 304.135505 -5.754128) (xy 304.187181 -5.822557) (xy 304.232322 -5.895463) (xy 304.270544 -5.972223)
			(xy 304.30152 -6.052182) (xy 304.324987 -6.134658) (xy 304.340743 -6.218948) (xy 304.348655 -6.304331)
			(xy 304.34915 -6.347206) (xy 304.348655 -6.390081) (xy 311.155321 -6.390081) (xy 311.155321 -6.304331)
			(xy 311.163233 -6.218948) (xy 311.178989 -6.134658) (xy 311.202456 -6.052182) (xy 311.233432 -5.972223)
			(xy 311.271654 -5.895463) (xy 311.316795 -5.822557) (xy 311.368471 -5.754128) (xy 311.42624 -5.690758)
			(xy 311.48961 -5.632989) (xy 311.558039 -5.581313) (xy 311.630945 -5.536172) (xy 311.707705 -5.49795)
			(xy 311.787664 -5.466974) (xy 311.87014 -5.443507) (xy 311.95443 -5.427751) (xy 312.039813 -5.419839)
			(xy 312.125563 -5.419839) (xy 312.210946 -5.427751) (xy 312.295236 -5.443507) (xy 312.377712 -5.466974)
			(xy 312.457671 -5.49795) (xy 312.534431 -5.536172) (xy 312.607337 -5.581313) (xy 312.675766 -5.632989)
			(xy 312.739136 -5.690758) (xy 312.796905 -5.754128) (xy 312.848581 -5.822557) (xy 312.893722 -5.895463)
			(xy 312.931944 -5.972223) (xy 312.96292 -6.052182) (xy 312.986387 -6.134658) (xy 313.002143 -6.218948)
			(xy 313.010055 -6.304331) (xy 313.01055 -6.347206) (xy 313.010055 -6.390081) (xy 317.505321 -6.390081)
			(xy 317.505321 -6.304331) (xy 317.513233 -6.218948) (xy 317.528989 -6.134658) (xy 317.552456 -6.052182)
			(xy 317.583432 -5.972223) (xy 317.621654 -5.895463) (xy 317.666795 -5.822557) (xy 317.718471 -5.754128)
			(xy 317.77624 -5.690758) (xy 317.83961 -5.632989) (xy 317.908039 -5.581313) (xy 317.980945 -5.536172)
			(xy 318.057705 -5.49795) (xy 318.137664 -5.466974) (xy 318.22014 -5.443507) (xy 318.30443 -5.427751)
			(xy 318.389813 -5.419839) (xy 318.475563 -5.419839) (xy 318.560946 -5.427751) (xy 318.645236 -5.443507)
			(xy 318.727712 -5.466974) (xy 318.807671 -5.49795) (xy 318.884431 -5.536172) (xy 318.957337 -5.581313)
			(xy 319.025766 -5.632989) (xy 319.089136 -5.690758) (xy 319.146905 -5.754128) (xy 319.198581 -5.822557)
			(xy 319.243722 -5.895463) (xy 319.281944 -5.972223) (xy 319.31292 -6.052182) (xy 319.336387 -6.134658)
			(xy 319.352143 -6.218948) (xy 319.360055 -6.304331) (xy 319.36055 -6.347206) (xy 319.360055 -6.390081)
			(xy 361.894107 -6.390081) (xy 361.894107 -6.304331) (xy 361.902019 -6.218948) (xy 361.917775 -6.134658)
			(xy 361.941242 -6.052182) (xy 361.972218 -5.972223) (xy 362.01044 -5.895463) (xy 362.055581 -5.822557)
			(xy 362.107257 -5.754128) (xy 362.165026 -5.690758) (xy 362.228396 -5.632989) (xy 362.296825 -5.581313)
			(xy 362.369731 -5.536172) (xy 362.446491 -5.49795) (xy 362.52645 -5.466974) (xy 362.608926 -5.443507)
			(xy 362.693216 -5.427751) (xy 362.778599 -5.419839) (xy 362.864349 -5.419839) (xy 362.949732 -5.427751)
			(xy 363.034022 -5.443507) (xy 363.116498 -5.466974) (xy 363.196457 -5.49795) (xy 363.273217 -5.536172)
			(xy 363.346123 -5.581313) (xy 363.414552 -5.632989) (xy 363.477922 -5.690758) (xy 363.535691 -5.754128)
			(xy 363.587367 -5.822557) (xy 363.632508 -5.895463) (xy 363.67073 -5.972223) (xy 363.701706 -6.052182)
			(xy 363.725173 -6.134658) (xy 363.740929 -6.218948) (xy 363.748841 -6.304331) (xy 363.749336 -6.347206)
			(xy 363.748841 -6.390081) (xy 368.244107 -6.390081) (xy 368.244107 -6.304331) (xy 368.252019 -6.218948)
			(xy 368.267775 -6.134658) (xy 368.291242 -6.052182) (xy 368.322218 -5.972223) (xy 368.36044 -5.895463)
			(xy 368.405581 -5.822557) (xy 368.457257 -5.754128) (xy 368.515026 -5.690758) (xy 368.578396 -5.632989)
			(xy 368.646825 -5.581313) (xy 368.719731 -5.536172) (xy 368.796491 -5.49795) (xy 368.87645 -5.466974)
			(xy 368.958926 -5.443507) (xy 369.043216 -5.427751) (xy 369.128599 -5.419839) (xy 369.214349 -5.419839)
			(xy 369.299732 -5.427751) (xy 369.384022 -5.443507) (xy 369.466498 -5.466974) (xy 369.546457 -5.49795)
			(xy 369.623217 -5.536172) (xy 369.696123 -5.581313) (xy 369.764552 -5.632989) (xy 369.827922 -5.690758)
			(xy 369.885691 -5.754128) (xy 369.937367 -5.822557) (xy 369.982508 -5.895463) (xy 370.02073 -5.972223)
			(xy 370.051706 -6.052182) (xy 370.075173 -6.134658) (xy 370.090929 -6.218948) (xy 370.098841 -6.304331)
			(xy 370.099336 -6.347206) (xy 370.098841 -6.390081) (xy 370.090929 -6.475464) (xy 370.075173 -6.559754)
			(xy 370.051706 -6.64223) (xy 370.02073 -6.722189) (xy 369.982508 -6.798949) (xy 369.937367 -6.871855)
			(xy 369.885691 -6.940284) (xy 369.827922 -7.003654) (xy 369.764552 -7.061423) (xy 369.696123 -7.113099)
			(xy 369.623217 -7.15824) (xy 369.546457 -7.196462) (xy 369.466498 -7.227438) (xy 369.384022 -7.250905)
			(xy 369.299732 -7.266661) (xy 369.214349 -7.274573) (xy 369.128599 -7.274573) (xy 369.043216 -7.266661)
			(xy 368.958926 -7.250905) (xy 368.87645 -7.227438) (xy 368.796491 -7.196462) (xy 368.719731 -7.15824)
			(xy 368.646825 -7.113099) (xy 368.578396 -7.061423) (xy 368.515026 -7.003654) (xy 368.457257 -6.940284)
			(xy 368.405581 -6.871855) (xy 368.36044 -6.798949) (xy 368.322218 -6.722189) (xy 368.291242 -6.64223)
			(xy 368.267775 -6.559754) (xy 368.252019 -6.475464) (xy 368.244107 -6.390081) (xy 363.748841 -6.390081)
			(xy 363.740929 -6.475464) (xy 363.725173 -6.559754) (xy 363.701706 -6.64223) (xy 363.67073 -6.722189)
			(xy 363.632508 -6.798949) (xy 363.587367 -6.871855) (xy 363.535691 -6.940284) (xy 363.477922 -7.003654)
			(xy 363.414552 -7.061423) (xy 363.346123 -7.113099) (xy 363.273217 -7.15824) (xy 363.196457 -7.196462)
			(xy 363.116498 -7.227438) (xy 363.034022 -7.250905) (xy 362.949732 -7.266661) (xy 362.864349 -7.274573)
			(xy 362.778599 -7.274573) (xy 362.693216 -7.266661) (xy 362.608926 -7.250905) (xy 362.52645 -7.227438)
			(xy 362.446491 -7.196462) (xy 362.369731 -7.15824) (xy 362.296825 -7.113099) (xy 362.228396 -7.061423)
			(xy 362.165026 -7.003654) (xy 362.107257 -6.940284) (xy 362.055581 -6.871855) (xy 362.01044 -6.798949)
			(xy 361.972218 -6.722189) (xy 361.941242 -6.64223) (xy 361.917775 -6.559754) (xy 361.902019 -6.475464)
			(xy 361.894107 -6.390081) (xy 319.360055 -6.390081) (xy 319.352143 -6.475464) (xy 319.336387 -6.559754)
			(xy 319.31292 -6.64223) (xy 319.281944 -6.722189) (xy 319.243722 -6.798949) (xy 319.198581 -6.871855)
			(xy 319.146905 -6.940284) (xy 319.089136 -7.003654) (xy 319.025766 -7.061423) (xy 318.957337 -7.113099)
			(xy 318.884431 -7.15824) (xy 318.807671 -7.196462) (xy 318.727712 -7.227438) (xy 318.645236 -7.250905)
			(xy 318.560946 -7.266661) (xy 318.475563 -7.274573) (xy 318.389813 -7.274573) (xy 318.30443 -7.266661)
			(xy 318.22014 -7.250905) (xy 318.137664 -7.227438) (xy 318.057705 -7.196462) (xy 317.980945 -7.15824)
			(xy 317.908039 -7.113099) (xy 317.83961 -7.061423) (xy 317.77624 -7.003654) (xy 317.718471 -6.940284)
			(xy 317.666795 -6.871855) (xy 317.621654 -6.798949) (xy 317.583432 -6.722189) (xy 317.552456 -6.64223)
			(xy 317.528989 -6.559754) (xy 317.513233 -6.475464) (xy 317.505321 -6.390081) (xy 313.010055 -6.390081)
			(xy 313.002143 -6.475464) (xy 312.986387 -6.559754) (xy 312.96292 -6.64223) (xy 312.931944 -6.722189)
			(xy 312.893722 -6.798949) (xy 312.848581 -6.871855) (xy 312.796905 -6.940284) (xy 312.739136 -7.003654)
			(xy 312.675766 -7.061423) (xy 312.607337 -7.113099) (xy 312.534431 -7.15824) (xy 312.457671 -7.196462)
			(xy 312.377712 -7.227438) (xy 312.295236 -7.250905) (xy 312.210946 -7.266661) (xy 312.125563 -7.274573)
			(xy 312.039813 -7.274573) (xy 311.95443 -7.266661) (xy 311.87014 -7.250905) (xy 311.787664 -7.227438)
			(xy 311.707705 -7.196462) (xy 311.630945 -7.15824) (xy 311.558039 -7.113099) (xy 311.48961 -7.061423)
			(xy 311.42624 -7.003654) (xy 311.368471 -6.940284) (xy 311.316795 -6.871855) (xy 311.271654 -6.798949)
			(xy 311.233432 -6.722189) (xy 311.202456 -6.64223) (xy 311.178989 -6.559754) (xy 311.163233 -6.475464)
			(xy 311.155321 -6.390081) (xy 304.348655 -6.390081) (xy 304.340743 -6.475464) (xy 304.324987 -6.559754)
			(xy 304.30152 -6.64223) (xy 304.270544 -6.722189) (xy 304.232322 -6.798949) (xy 304.187181 -6.871855)
			(xy 304.135505 -6.940284) (xy 304.077736 -7.003654) (xy 304.014366 -7.061423) (xy 303.945937 -7.113099)
			(xy 303.873031 -7.15824) (xy 303.796271 -7.196462) (xy 303.716312 -7.227438) (xy 303.633836 -7.250905)
			(xy 303.549546 -7.266661) (xy 303.464163 -7.274573) (xy 303.378413 -7.274573) (xy 303.29303 -7.266661)
			(xy 303.20874 -7.250905) (xy 303.126264 -7.227438) (xy 303.046305 -7.196462) (xy 302.969545 -7.15824)
			(xy 302.896639 -7.113099) (xy 302.82821 -7.061423) (xy 302.76484 -7.003654) (xy 302.707071 -6.940284)
			(xy 302.655395 -6.871855) (xy 302.610254 -6.798949) (xy 302.572032 -6.722189) (xy 302.541056 -6.64223)
			(xy 302.517589 -6.559754) (xy 302.501833 -6.475464) (xy 302.493921 -6.390081) (xy 297.998655 -6.390081)
			(xy 297.990743 -6.475464) (xy 297.974987 -6.559754) (xy 297.95152 -6.64223) (xy 297.920544 -6.722189)
			(xy 297.882322 -6.798949) (xy 297.837181 -6.871855) (xy 297.785505 -6.940284) (xy 297.727736 -7.003654)
			(xy 297.664366 -7.061423) (xy 297.595937 -7.113099) (xy 297.523031 -7.15824) (xy 297.446271 -7.196462)
			(xy 297.366312 -7.227438) (xy 297.283836 -7.250905) (xy 297.199546 -7.266661) (xy 297.114163 -7.274573)
			(xy 297.028413 -7.274573) (xy 296.94303 -7.266661) (xy 296.85874 -7.250905) (xy 296.776264 -7.227438)
			(xy 296.696305 -7.196462) (xy 296.619545 -7.15824) (xy 296.546639 -7.113099) (xy 296.47821 -7.061423)
			(xy 296.41484 -7.003654) (xy 296.357071 -6.940284) (xy 296.305395 -6.871855) (xy 296.260254 -6.798949)
			(xy 296.222032 -6.722189) (xy 296.191056 -6.64223) (xy 296.167589 -6.559754) (xy 296.151833 -6.475464)
			(xy 296.143921 -6.390081) (xy 216.865975 -6.390081) (xy 216.858063 -6.475464) (xy 216.842307 -6.559754)
			(xy 216.81884 -6.64223) (xy 216.787864 -6.722189) (xy 216.749642 -6.798949) (xy 216.704501 -6.871855)
			(xy 216.652825 -6.940284) (xy 216.595056 -7.003654) (xy 216.531686 -7.061423) (xy 216.463257 -7.113099)
			(xy 216.390351 -7.15824) (xy 216.313591 -7.196462) (xy 216.233632 -7.227438) (xy 216.151156 -7.250905)
			(xy 216.066866 -7.266661) (xy 215.981483 -7.274573) (xy 215.895733 -7.274573) (xy 215.81035 -7.266661)
			(xy 215.72606 -7.250905) (xy 215.643584 -7.227438) (xy 215.563625 -7.196462) (xy 215.486865 -7.15824)
			(xy 215.413959 -7.113099) (xy 215.34553 -7.061423) (xy 215.28216 -7.003654) (xy 215.224391 -6.940284)
			(xy 215.172715 -6.871855) (xy 215.127574 -6.798949) (xy 215.089352 -6.722189) (xy 215.058376 -6.64223)
			(xy 215.034909 -6.559754) (xy 215.019153 -6.475464) (xy 215.011241 -6.390081) (xy 210.515975 -6.390081)
			(xy 210.508063 -6.475464) (xy 210.492307 -6.559754) (xy 210.46884 -6.64223) (xy 210.437864 -6.722189)
			(xy 210.399642 -6.798949) (xy 210.354501 -6.871855) (xy 210.302825 -6.940284) (xy 210.245056 -7.003654)
			(xy 210.181686 -7.061423) (xy 210.113257 -7.113099) (xy 210.040351 -7.15824) (xy 209.963591 -7.196462)
			(xy 209.883632 -7.227438) (xy 209.801156 -7.250905) (xy 209.716866 -7.266661) (xy 209.631483 -7.274573)
			(xy 209.545733 -7.274573) (xy 209.46035 -7.266661) (xy 209.37606 -7.250905) (xy 209.293584 -7.227438)
			(xy 209.213625 -7.196462) (xy 209.136865 -7.15824) (xy 209.063959 -7.113099) (xy 208.99553 -7.061423)
			(xy 208.93216 -7.003654) (xy 208.874391 -6.940284) (xy 208.822715 -6.871855) (xy 208.777574 -6.798949)
			(xy 208.739352 -6.722189) (xy 208.708376 -6.64223) (xy 208.684909 -6.559754) (xy 208.669153 -6.475464)
			(xy 208.661241 -6.390081) (xy 197.210934 -6.390081) (xy 197.210934 -7.78002) (xy 197.211456 -7.835788)
			(xy 197.219793 -7.947013) (xy 197.236418 -8.057304) (xy 197.261239 -8.166044) (xy 197.294116 -8.272625)
			(xy 197.334866 -8.376451) (xy 197.383261 -8.476941) (xy 197.439031 -8.573534) (xy 197.501863 -8.66569)
			(xy 197.571406 -8.752892) (xy 197.647271 -8.834653) (xy 197.729034 -8.910516) (xy 197.816238 -8.980057)
			(xy 197.908394 -9.042887) (xy 198.004989 -9.098654) (xy 198.10548 -9.147047) (xy 198.209307 -9.187795)
			(xy 198.315889 -9.22067) (xy 198.42463 -9.245488) (xy 198.534921 -9.262111) (xy 198.646146 -9.270445)
			(xy 198.701914 -9.271) (xy 223.300036 -9.271) (xy 223.370417 -9.271495) (xy 223.510959 -9.279389)
			(xy 223.650836 -9.295152) (xy 223.78961 -9.318732) (xy 223.926844 -9.350057) (xy 224.062105 -9.389027)
			(xy 224.194968 -9.435519) (xy 224.325015 -9.489388) (xy 224.451838 -9.550465) (xy 224.575036 -9.618556)
			(xy 224.694222 -9.693447) (xy 224.809022 -9.774904) (xy 224.919074 -9.862669) (xy 225.024032 -9.956467)
			(xy 225.123566 -10.056003) (xy 225.217361 -10.160962) (xy 225.305125 -10.271016) (xy 225.386579 -10.385818)
			(xy 225.461469 -10.505006) (xy 225.529557 -10.628205) (xy 225.590631 -10.755029) (xy 225.644498 -10.885077)
			(xy 225.690988 -11.017941) (xy 225.729955 -11.153203) (xy 225.761277 -11.290437) (xy 225.784855 -11.429211)
			(xy 225.800615 -11.569089) (xy 225.808507 -11.709631) (xy 225.809048 -11.780012) (xy 225.809048 -33.120076)
			(xy 225.809549 -33.152224) (xy 225.817939 -33.21597) (xy 225.834578 -33.278076) (xy 225.859182 -33.337478)
			(xy 225.891329 -33.39316) (xy 225.93047 -33.44417) (xy 225.975934 -33.489634) (xy 226.026945 -33.528774)
			(xy 226.082627 -33.560921) (xy 226.14203 -33.585524) (xy 226.204136 -33.602162) (xy 226.267882 -33.610551)
			(xy 226.30003 -33.611058)
		)
		(stroke
			(width 0)
			(type solid)
		)
		(fill yes)
		(layer "In12.Cu")
		(net "DELTA_L_GND_1")
	)
	(gr_poly
		(pts
			(xy 194.445128 -441.480956) (xy 194.455142 -441.480531) (xy 194.473642 -441.472854) (xy 194.487795 -441.458682)
			(xy 194.495445 -441.440171) (xy 194.495928 -441.430156) (xy 194.495928 -441.17006) (xy 194.49641 -441.126022)
			(xy 194.50409 -441.03828) (xy 194.519387 -440.951542) (xy 194.542185 -440.866466) (xy 194.572311 -440.783702)
			(xy 194.609536 -440.703878) (xy 194.653576 -440.627602) (xy 194.704095 -440.555454) (xy 194.760711 -440.487984)
			(xy 194.822991 -440.425704) (xy 194.890462 -440.369089) (xy 194.96261 -440.31857) (xy 195.038887 -440.274531)
			(xy 195.118711 -440.237308) (xy 195.201476 -440.207182) (xy 195.286551 -440.184385) (xy 195.37329 -440.169088)
			(xy 195.461032 -440.16141) (xy 195.50507 -440.160918) (xy 276.314916 -440.160918) (xy 276.358955 -440.161399)
			(xy 276.446699 -440.169077) (xy 276.533439 -440.184372) (xy 276.618516 -440.207169) (xy 276.701283 -440.237294)
			(xy 276.781109 -440.274518) (xy 276.857388 -440.318557) (xy 276.929538 -440.369076) (xy 276.99701 -440.425692)
			(xy 277.059292 -440.487972) (xy 277.115909 -440.555443) (xy 277.16643 -440.627592) (xy 277.210471 -440.703869)
			(xy 277.247697 -440.783695) (xy 277.277823 -440.866461) (xy 277.300622 -440.951538) (xy 277.31592 -441.038278)
			(xy 277.3236 -441.126021) (xy 277.324058 -441.17006) (xy 277.324058 -441.430156) (xy 277.324469 -441.440186)
			(xy 277.33213 -441.458725) (xy 277.346302 -441.472922) (xy 277.364828 -441.480614) (xy 277.374858 -441.480956)
			(xy 463.300064 -441.480956) (xy 463.355834 -441.480449) (xy 463.467062 -441.472116) (xy 463.577357 -441.455494)
			(xy 463.686101 -441.430676) (xy 463.792686 -441.397801) (xy 463.896517 -441.357052) (xy 463.997011 -441.308658)
			(xy 464.093608 -441.252889) (xy 464.185768 -441.190057) (xy 464.272974 -441.120513) (xy 464.354739 -441.044647)
			(xy 464.430606 -440.962883) (xy 464.50015 -440.875677) (xy 464.562982 -440.783519) (xy 464.618752 -440.686922)
			(xy 464.667147 -440.586428) (xy 464.707897 -440.482598) (xy 464.740773 -440.376013) (xy 464.765592 -440.267269)
			(xy 464.782215 -440.156974) (xy 464.790548 -440.045746) (xy 464.791044 -439.989976) (xy 464.791044 -409.528264)
			(xy 464.791546 -409.457891) (xy 464.799454 -409.317366) (xy 464.815227 -409.177505) (xy 464.838815 -409.038749)
			(xy 464.870143 -408.901532) (xy 464.909113 -408.766288) (xy 464.955604 -408.633441) (xy 465.009467 -408.503408)
			(xy 465.070535 -408.376599) (xy 465.138615 -408.253413) (xy 465.213493 -408.134236) (xy 465.294933 -408.019444)
			(xy 465.38268 -407.909398) (xy 465.476458 -407.804443) (xy 465.525866 -407.754328) (xy 467.354412 -405.925782)
			(xy 467.391703 -405.887819) (xy 467.461396 -405.807388) (xy 467.525176 -405.722192) (xy 467.582717 -405.632663)
			(xy 467.633725 -405.539259) (xy 467.677942 -405.442454) (xy 467.715142 -405.342742) (xy 467.745135 -405.240631)
			(xy 467.767768 -405.136641) (xy 467.782928 -405.031301) (xy 467.790535 -404.925148) (xy 467.791038 -404.871936)
			(xy 467.791038 -82.82813) (xy 467.791541 -82.757757) (xy 467.799451 -82.617233) (xy 467.815226 -82.477373)
			(xy 467.838815 -82.338618) (xy 467.870145 -82.201402) (xy 467.909116 -82.066159) (xy 467.955608 -81.933313)
			(xy 468.009473 -81.803282) (xy 468.070541 -81.676474) (xy 468.138622 -81.553289) (xy 468.213501 -81.434114)
			(xy 468.294942 -81.319323) (xy 468.382689 -81.209278) (xy 468.476467 -81.104324) (xy 468.52586 -81.054194)
			(xy 470.854278 -78.725776) (xy 470.891569 -78.687813) (xy 470.961264 -78.607383) (xy 471.025045 -78.522187)
			(xy 471.082586 -78.432659) (xy 471.133596 -78.339255) (xy 471.177813 -78.24245) (xy 471.215013 -78.142738)
			(xy 471.245007 -78.040626) (xy 471.267641 -77.936636) (xy 471.2828 -77.831296) (xy 471.290407 -77.725143)
			(xy 471.290904 -77.67193) (xy 471.290904 -13.780008) (xy 471.290383 -13.724238) (xy 471.282048 -13.613011)
			(xy 471.265425 -13.502718) (xy 471.240606 -13.393975) (xy 471.20773 -13.287391) (xy 471.166981 -13.183562)
			(xy 471.118587 -13.083068) (xy 471.062818 -12.986472) (xy 470.999987 -12.894314) (xy 470.930444 -12.807108)
			(xy 470.854579 -12.725344) (xy 470.772816 -12.649477) (xy 470.685612 -12.579932) (xy 470.593455 -12.517099)
			(xy 470.49686 -12.461328) (xy 470.396367 -12.412932) (xy 470.292539 -12.372181) (xy 470.185956 -12.339303)
			(xy 470.077214 -12.314481) (xy 469.966921 -12.297855) (xy 469.855694 -12.289518) (xy 469.799924 -12.289028)
			(xy 458.20203 -12.289028) (xy 458.131647 -12.288544) (xy 457.991102 -12.280653) (xy 457.85122 -12.264894)
			(xy 457.712443 -12.241316) (xy 457.575205 -12.209994) (xy 457.43994 -12.171027) (xy 457.307072 -12.124536)
			(xy 457.177021 -12.070668) (xy 457.050194 -12.009593) (xy 456.926991 -11.941503) (xy 456.8078 -11.866612)
			(xy 456.692996 -11.785156) (xy 456.582939 -11.69739) (xy 456.477977 -11.603592) (xy 456.378439 -11.504056)
			(xy 456.284639 -11.399096) (xy 456.196872 -11.289041) (xy 456.115413 -11.174238) (xy 456.04052 -11.055048)
			(xy 455.972428 -10.931847) (xy 455.911351 -10.805021) (xy 455.857481 -10.674971) (xy 455.810987 -10.542104)
			(xy 455.772017 -10.406839) (xy 455.740693 -10.269603) (xy 455.717113 -10.130825) (xy 455.701351 -9.990944)
			(xy 455.693457 -9.850399) (xy 455.693018 -9.780016) (xy 455.693018 -0.559816) (xy 455.692533 -0.549805)
			(xy 455.684877 -0.531304) (xy 455.670724 -0.517142) (xy 455.652229 -0.509474) (xy 455.642218 -0.509016)
			(xy 388.161784 -0.509016) (xy 388.15178 -0.509507) (xy 388.133296 -0.51717) (xy 388.119152 -0.531323)
			(xy 388.111501 -0.549811) (xy 388.110984 -0.559816) (xy 388.110984 -5.169916) (xy 388.848098 -5.169916)
			(xy 388.852112 -5.081823) (xy 388.864119 -4.99446) (xy 388.884022 -4.90855) (xy 388.911654 -4.824807)
			(xy 388.946787 -4.743923) (xy 388.989129 -4.666569) (xy 389.03833 -4.593386) (xy 389.093983 -4.52498)
			(xy 389.155625 -4.461919) (xy 389.222746 -4.404724) (xy 389.29479 -4.353869) (xy 389.37116 -4.309777)
			(xy 389.451223 -4.272812) (xy 389.534316 -4.243281) (xy 389.61975 -4.221428) (xy 389.706817 -4.207435)
			(xy 389.794796 -4.201417) (xy 389.882958 -4.203424) (xy 389.970572 -4.21344) (xy 390.056912 -4.231382)
			(xy 390.141263 -4.257101) (xy 390.222925 -4.290383) (xy 390.301223 -4.330954) (xy 390.375507 -4.378476)
			(xy 390.445162 -4.432557) (xy 390.50961 -4.492748) (xy 390.568318 -4.55855) (xy 390.620799 -4.629417)
			(xy 390.666619 -4.704764) (xy 390.705396 -4.783965) (xy 390.736811 -4.866364) (xy 390.760603 -4.951278)
			(xy 390.767857 -4.990667) (xy 394.939038 -4.990667) (xy 394.939038 -4.936133) (xy 394.946799 -4.882155)
			(xy 394.962162 -4.82983) (xy 394.984815 -4.780224) (xy 395.014296 -4.734346) (xy 395.050007 -4.693131)
			(xy 395.091219 -4.657417) (xy 395.137094 -4.627931) (xy 395.186698 -4.605274) (xy 395.239021 -4.589906)
			(xy 395.292999 -4.582141) (xy 395.320266 -4.581652) (xy 396.183866 -4.581652) (xy 396.21114 -4.582085)
			(xy 396.265132 -4.589844) (xy 396.317471 -4.605208) (xy 396.36709 -4.627864) (xy 396.41298 -4.657352)
			(xy 396.454205 -4.693071) (xy 396.489928 -4.734293) (xy 396.51942 -4.78018) (xy 396.542081 -4.829797)
			(xy 396.557449 -4.882135) (xy 396.565212 -4.936126) (xy 396.565212 -4.99067) (xy 398.538915 -4.99067)
			(xy 398.538915 -4.93613) (xy 398.546678 -4.882144) (xy 398.562044 -4.829813) (xy 398.584701 -4.780201)
			(xy 398.614188 -4.734318) (xy 398.649905 -4.6931) (xy 398.691125 -4.657383) (xy 398.737008 -4.627897)
			(xy 398.78662 -4.605241) (xy 398.838952 -4.589876) (xy 398.892938 -4.582115) (xy 398.920208 -4.581652)
			(xy 399.783808 -4.581652) (xy 399.811078 -4.582111) (xy 399.865063 -4.589874) (xy 399.917393 -4.60524)
			(xy 399.967004 -4.627898) (xy 400.012886 -4.657385) (xy 400.054104 -4.693102) (xy 400.08982 -4.734321)
			(xy 400.119306 -4.780203) (xy 400.141962 -4.829814) (xy 400.157328 -4.882145) (xy 400.16509 -4.93613)
			(xy 400.16509 -4.990666) (xy 402.138938 -4.990666) (xy 402.138938 -4.936134) (xy 402.146698 -4.882157)
			(xy 402.162061 -4.829833) (xy 402.184712 -4.780228) (xy 402.214192 -4.734351) (xy 402.249901 -4.693136)
			(xy 402.291111 -4.657422) (xy 402.336984 -4.627936) (xy 402.386586 -4.605278) (xy 402.438908 -4.589909)
			(xy 402.492884 -4.582142) (xy 402.52015 -4.581652) (xy 403.38375 -4.581652) (xy 403.411024 -4.582084)
			(xy 403.465019 -4.589841) (xy 403.517359 -4.605203) (xy 403.56698 -4.627859) (xy 403.612872 -4.657346)
			(xy 403.6541 -4.693065) (xy 403.689824 -4.734288) (xy 403.719317 -4.780176) (xy 403.741979 -4.829794)
			(xy 403.757349 -4.882132) (xy 403.765112 -4.936126) (xy 403.765112 -4.990672) (xy 405.739016 -4.990672)
			(xy 405.739016 -4.936128) (xy 405.746779 -4.882139) (xy 405.762147 -4.829805) (xy 405.784807 -4.78019)
			(xy 405.814298 -4.734306) (xy 405.850019 -4.693086) (xy 405.891243 -4.65737) (xy 405.937131 -4.627885)
			(xy 405.986748 -4.605231) (xy 406.039084 -4.589869) (xy 406.093074 -4.582112) (xy 406.120346 -4.581652)
			(xy 406.983946 -4.581652) (xy 407.011214 -4.582114) (xy 407.065195 -4.589881) (xy 407.117521 -4.605251)
			(xy 407.167127 -4.62791) (xy 407.213004 -4.657399) (xy 407.254217 -4.693115) (xy 407.289929 -4.734333)
			(xy 407.319412 -4.780213) (xy 407.342065 -4.829822) (xy 407.357429 -4.88215) (xy 407.36519 -4.936132)
			(xy 407.36519 -4.990668) (xy 407.36519 -4.99067) (xy 414.849015 -4.99067) (xy 414.849015 -4.93613)
			(xy 414.856778 -4.882144) (xy 414.872144 -4.829812) (xy 414.894801 -4.7802) (xy 414.924289 -4.734318)
			(xy 414.960006 -4.693099) (xy 415.001226 -4.657383) (xy 415.047109 -4.627896) (xy 415.096722 -4.60524)
			(xy 415.149054 -4.589875) (xy 415.20304 -4.582115) (xy 415.23031 -4.581652) (xy 416.09391 -4.581652)
			(xy 416.12118 -4.582111) (xy 416.175164 -4.589874) (xy 416.227495 -4.605241) (xy 416.277105 -4.627899)
			(xy 416.322987 -4.657386) (xy 416.364205 -4.693102) (xy 416.39992 -4.734321) (xy 416.429406 -4.780203)
			(xy 416.452062 -4.829815) (xy 416.467428 -4.882145) (xy 416.47519 -4.93613) (xy 416.47519 -4.990666)
			(xy 418.449038 -4.990666) (xy 418.449038 -4.936134) (xy 418.456798 -4.882156) (xy 418.472161 -4.829833)
			(xy 418.494813 -4.780227) (xy 418.524293 -4.734351) (xy 418.560002 -4.693136) (xy 418.601212 -4.657422)
			(xy 418.647085 -4.627936) (xy 418.696688 -4.605278) (xy 418.749009 -4.589909) (xy 418.802986 -4.582142)
			(xy 418.830252 -4.581652) (xy 419.693852 -4.581652) (xy 419.721126 -4.582084) (xy 419.77512 -4.589841)
			(xy 419.827461 -4.605204) (xy 419.877082 -4.627859) (xy 419.922973 -4.657347) (xy 419.9642 -4.693066)
			(xy 419.999924 -4.734288) (xy 420.029418 -4.780176) (xy 420.052079 -4.829794) (xy 420.067449 -4.882133)
			(xy 420.075212 -4.936126) (xy 420.075212 -4.990672) (xy 426.059016 -4.990672) (xy 426.059016 -4.936128)
			(xy 426.066779 -4.882139) (xy 426.082147 -4.829805) (xy 426.104807 -4.78019) (xy 426.134298 -4.734306)
			(xy 426.170019 -4.693086) (xy 426.211243 -4.65737) (xy 426.257131 -4.627885) (xy 426.306748 -4.605231)
			(xy 426.359084 -4.589869) (xy 426.413074 -4.582112) (xy 426.440346 -4.581652) (xy 427.303946 -4.581652)
			(xy 427.331214 -4.582114) (xy 427.385195 -4.589881) (xy 427.437521 -4.605251) (xy 427.487127 -4.62791)
			(xy 427.533004 -4.657399) (xy 427.574217 -4.693115) (xy 427.609929 -4.734333) (xy 427.639412 -4.780213)
			(xy 427.662065 -4.829822) (xy 427.677429 -4.88215) (xy 427.68519 -4.936132) (xy 427.68519 -4.990668)
			(xy 429.659038 -4.990668) (xy 429.659038 -4.936132) (xy 429.666799 -4.882152) (xy 429.682164 -4.829825)
			(xy 429.704818 -4.780217) (xy 429.734302 -4.734339) (xy 429.770014 -4.693123) (xy 429.811229 -4.657409)
			(xy 429.857107 -4.627924) (xy 429.906714 -4.605268) (xy 429.95904 -4.589902) (xy 430.01302 -4.582139)
			(xy 430.040288 -4.581652) (xy 430.903888 -4.581652) (xy 430.931161 -4.582087) (xy 430.985151 -4.589848)
			(xy 431.037487 -4.605214) (xy 431.087103 -4.627871) (xy 431.13299 -4.65736) (xy 431.174213 -4.693078)
			(xy 431.209933 -4.7343) (xy 431.239423 -4.780186) (xy 431.262082 -4.829802) (xy 431.27745 -4.882138)
			(xy 431.285212 -4.936127) (xy 431.285212 -4.990673) (xy 431.27745 -5.044662) (xy 431.262082 -5.096998)
			(xy 431.239423 -5.146614) (xy 431.209933 -5.1925) (xy 431.174213 -5.233722) (xy 431.13299 -5.26944)
			(xy 431.087103 -5.298929) (xy 431.037487 -5.321586) (xy 430.985151 -5.336952) (xy 430.931161 -5.344713)
			(xy 430.903888 -5.345176) (xy 430.040288 -5.345176) (xy 430.01302 -5.344661) (xy 429.95904 -5.336898)
			(xy 429.906714 -5.321532) (xy 429.857107 -5.298876) (xy 429.811229 -5.269391) (xy 429.770014 -5.233677)
			(xy 429.734302 -5.192461) (xy 429.704818 -5.146583) (xy 429.682164 -5.096975) (xy 429.666799 -5.044648)
			(xy 429.659038 -4.990668) (xy 427.68519 -4.990668) (xy 427.677429 -5.04465) (xy 427.662065 -5.096978)
			(xy 427.639412 -5.146587) (xy 427.609929 -5.192467) (xy 427.574217 -5.233685) (xy 427.533004 -5.269401)
			(xy 427.487127 -5.29889) (xy 427.437521 -5.321549) (xy 427.385195 -5.336919) (xy 427.331214 -5.344686)
			(xy 427.303946 -5.345176) (xy 426.440346 -5.345176) (xy 426.413074 -5.344688) (xy 426.359084 -5.336931)
			(xy 426.306748 -5.321569) (xy 426.257131 -5.298915) (xy 426.211243 -5.26943) (xy 426.170019 -5.233714)
			(xy 426.134298 -5.192494) (xy 426.104807 -5.14661) (xy 426.082147 -5.096995) (xy 426.066779 -5.044661)
			(xy 426.059016 -4.990672) (xy 420.075212 -4.990672) (xy 420.075212 -4.990674) (xy 420.067449 -5.044667)
			(xy 420.052079 -5.097006) (xy 420.029418 -5.146624) (xy 419.999924 -5.192512) (xy 419.9642 -5.233734)
			(xy 419.922973 -5.269453) (xy 419.877082 -5.298941) (xy 419.827461 -5.321596) (xy 419.77512 -5.336959)
			(xy 419.721126 -5.344716) (xy 419.693852 -5.345176) (xy 418.830252 -5.345176) (xy 418.802986 -5.344658)
			(xy 418.749009 -5.336891) (xy 418.696688 -5.321522) (xy 418.647085 -5.298864) (xy 418.601212 -5.269378)
			(xy 418.560002 -5.233664) (xy 418.524293 -5.192449) (xy 418.494813 -5.146573) (xy 418.472161 -5.096967)
			(xy 418.456798 -5.044644) (xy 418.449038 -4.990666) (xy 416.47519 -4.990666) (xy 416.47519 -4.99067)
			(xy 416.467428 -5.044655) (xy 416.452062 -5.096985) (xy 416.429406 -5.146597) (xy 416.39992 -5.192479)
			(xy 416.364205 -5.233698) (xy 416.322987 -5.269414) (xy 416.277105 -5.298901) (xy 416.227495 -5.321559)
			(xy 416.175164 -5.336926) (xy 416.12118 -5.344689) (xy 416.09391 -5.345176) (xy 415.23031 -5.345176)
			(xy 415.20304 -5.344685) (xy 415.149054 -5.336925) (xy 415.096722 -5.32156) (xy 415.047109 -5.298904)
			(xy 415.001226 -5.269417) (xy 414.960006 -5.233701) (xy 414.924289 -5.192482) (xy 414.894801 -5.1466)
			(xy 414.872144 -5.096988) (xy 414.856778 -5.044656) (xy 414.849015 -4.99067) (xy 407.36519 -4.99067)
			(xy 407.357429 -5.04465) (xy 407.342065 -5.096978) (xy 407.319412 -5.146587) (xy 407.289929 -5.192467)
			(xy 407.254217 -5.233685) (xy 407.213004 -5.269401) (xy 407.167127 -5.29889) (xy 407.117521 -5.321549)
			(xy 407.065195 -5.336919) (xy 407.011214 -5.344686) (xy 406.983946 -5.345176) (xy 406.120346 -5.345176)
			(xy 406.093074 -5.344688) (xy 406.039084 -5.336931) (xy 405.986748 -5.321569) (xy 405.937131 -5.298915)
			(xy 405.891243 -5.26943) (xy 405.850019 -5.233714) (xy 405.814298 -5.192494) (xy 405.784807 -5.14661)
			(xy 405.762147 -5.096995) (xy 405.746779 -5.044661) (xy 405.739016 -4.990672) (xy 403.765112 -4.990672)
			(xy 403.765112 -4.990674) (xy 403.757349 -5.044668) (xy 403.741979 -5.097006) (xy 403.719317 -5.146624)
			(xy 403.689824 -5.192512) (xy 403.6541 -5.233735) (xy 403.612872 -5.269454) (xy 403.56698 -5.298941)
			(xy 403.517359 -5.321597) (xy 403.465019 -5.336959) (xy 403.411024 -5.344716) (xy 403.38375 -5.345176)
			(xy 402.52015 -5.345176) (xy 402.492884 -5.344658) (xy 402.438908 -5.336891) (xy 402.386586 -5.321522)
			(xy 402.336984 -5.298864) (xy 402.291111 -5.269378) (xy 402.249901 -5.233664) (xy 402.214192 -5.192449)
			(xy 402.184712 -5.146572) (xy 402.162061 -5.096967) (xy 402.146698 -5.044643) (xy 402.138938 -4.990666)
			(xy 400.16509 -4.990666) (xy 400.16509 -4.99067) (xy 400.157328 -5.044655) (xy 400.141962 -5.096986)
			(xy 400.119306 -5.146597) (xy 400.08982 -5.192479) (xy 400.054104 -5.233698) (xy 400.012886 -5.269415)
			(xy 399.967004 -5.298902) (xy 399.917393 -5.32156) (xy 399.865063 -5.336926) (xy 399.811078 -5.344689)
			(xy 399.783808 -5.345176) (xy 398.920208 -5.345176) (xy 398.892938 -5.344685) (xy 398.838952 -5.336924)
			(xy 398.78662 -5.321559) (xy 398.737008 -5.298903) (xy 398.691125 -5.269417) (xy 398.649905 -5.2337)
			(xy 398.614188 -5.192482) (xy 398.584701 -5.146599) (xy 398.562044 -5.096987) (xy 398.546678 -5.044656)
			(xy 398.538915 -4.99067) (xy 396.565212 -4.99067) (xy 396.565212 -4.990674) (xy 396.557449 -5.044665)
			(xy 396.542081 -5.097003) (xy 396.51942 -5.14662) (xy 396.489928 -5.192507) (xy 396.454205 -5.233729)
			(xy 396.41298 -5.269448) (xy 396.36709 -5.298936) (xy 396.317471 -5.321592) (xy 396.265132 -5.336956)
			(xy 396.21114 -5.344715) (xy 396.183866 -5.345176) (xy 395.320266 -5.345176) (xy 395.292999 -5.344659)
			(xy 395.239021 -5.336894) (xy 395.186698 -5.321526) (xy 395.137094 -5.298869) (xy 395.091219 -5.269383)
			(xy 395.050007 -5.233669) (xy 395.014296 -5.192454) (xy 394.984815 -5.146576) (xy 394.962162 -5.09697)
			(xy 394.946799 -5.044645) (xy 394.939038 -4.990667) (xy 390.767857 -4.990667) (xy 390.776575 -5.038005)
			(xy 390.784594 -5.125824) (xy 390.785096 -5.169916) (xy 390.784594 -5.214008) (xy 390.776575 -5.301827)
			(xy 390.760603 -5.388554) (xy 390.736811 -5.473468) (xy 390.705396 -5.555867) (xy 390.666619 -5.635068)
			(xy 390.620799 -5.710415) (xy 390.568318 -5.781282) (xy 390.50961 -5.847084) (xy 390.445162 -5.907275)
			(xy 390.375507 -5.961356) (xy 390.301223 -6.008878) (xy 390.222925 -6.049449) (xy 390.141263 -6.082731)
			(xy 390.056912 -6.10845) (xy 389.970572 -6.126392) (xy 389.882958 -6.136408) (xy 389.794796 -6.138415)
			(xy 389.706817 -6.132397) (xy 389.61975 -6.118404) (xy 389.534316 -6.096551) (xy 389.451223 -6.06702)
			(xy 389.37116 -6.030055) (xy 389.29479 -5.985963) (xy 389.222746 -5.935108) (xy 389.155625 -5.877913)
			(xy 389.093983 -5.814852) (xy 389.03833 -5.746446) (xy 388.989129 -5.673263) (xy 388.946787 -5.595909)
			(xy 388.911654 -5.515025) (xy 388.884022 -5.431282) (xy 388.864119 -5.345372) (xy 388.852112 -5.258009)
			(xy 388.848098 -5.169916) (xy 388.110984 -5.169916) (xy 388.110984 -6.169914) (xy 453.015103 -6.169914)
			(xy 453.019108 -6.082006) (xy 453.031091 -5.994826) (xy 453.050951 -5.909097) (xy 453.078526 -5.825529)
			(xy 453.113585 -5.744815) (xy 453.155838 -5.667623) (xy 453.204936 -5.594594) (xy 453.260472 -5.526332)
			(xy 453.321984 -5.463402) (xy 453.388965 -5.406328) (xy 453.460858 -5.35558) (xy 453.537067 -5.31158)
			(xy 453.616962 -5.274693) (xy 453.699881 -5.245224) (xy 453.785136 -5.223417) (xy 453.87202 -5.209453)
			(xy 453.959814 -5.203447) (xy 454.047791 -5.205451) (xy 454.135221 -5.215446) (xy 454.22138 -5.23335)
			(xy 454.305554 -5.259014) (xy 454.387045 -5.292227) (xy 454.465179 -5.332713) (xy 454.539307 -5.380135)
			(xy 454.608815 -5.434102) (xy 454.673129 -5.494167) (xy 454.731713 -5.559831) (xy 454.784084 -5.63055)
			(xy 454.829807 -5.705738) (xy 454.868504 -5.784773) (xy 454.899853 -5.866999) (xy 454.923595 -5.951735)
			(xy 454.939533 -6.038279) (xy 454.947535 -6.125914) (xy 454.948036 -6.169914) (xy 454.947535 -6.213914)
			(xy 454.939533 -6.301549) (xy 454.923595 -6.388093) (xy 454.899853 -6.472829) (xy 454.868504 -6.555055)
			(xy 454.829807 -6.63409) (xy 454.784084 -6.709278) (xy 454.731713 -6.779997) (xy 454.673129 -6.845661)
			(xy 454.608815 -6.905726) (xy 454.539307 -6.959693) (xy 454.465179 -7.007115) (xy 454.387045 -7.047601)
			(xy 454.305554 -7.080814) (xy 454.22138 -7.106478) (xy 454.135221 -7.124382) (xy 454.047791 -7.134377)
			(xy 453.959814 -7.136381) (xy 453.87202 -7.130375) (xy 453.785136 -7.116411) (xy 453.699881 -7.094604)
			(xy 453.616962 -7.065135) (xy 453.537067 -7.028248) (xy 453.460858 -6.984248) (xy 453.388965 -6.9335)
			(xy 453.321984 -6.876426) (xy 453.260472 -6.813496) (xy 453.204936 -6.745234) (xy 453.155838 -6.672205)
			(xy 453.113585 -6.595013) (xy 453.078526 -6.514299) (xy 453.050951 -6.430731) (xy 453.031091 -6.345002)
			(xy 453.019108 -6.257822) (xy 453.015103 -6.169914) (xy 388.110984 -6.169914) (xy 388.110984 -6.752472)
			(xy 393.134283 -6.752472) (xy 393.134283 -6.697928) (xy 393.142045 -6.643939) (xy 393.157412 -6.591604)
			(xy 393.18007 -6.541988) (xy 393.209559 -6.496103) (xy 393.245278 -6.454881) (xy 393.286499 -6.419161)
			(xy 393.332385 -6.389672) (xy 393.382 -6.367013) (xy 393.434335 -6.351646) (xy 393.488324 -6.343883)
			(xy 393.515596 -6.343396) (xy 394.379196 -6.343396) (xy 394.406464 -6.343943) (xy 394.460446 -6.351704)
			(xy 394.512773 -6.367068) (xy 394.562381 -6.389723) (xy 394.60826 -6.419207) (xy 394.649476 -6.454921)
			(xy 394.68519 -6.496136) (xy 394.714675 -6.542015) (xy 394.73733 -6.591623) (xy 394.752695 -6.643951)
			(xy 394.760457 -6.697932) (xy 394.760457 -6.752468) (xy 394.760456 -6.752476) (xy 396.73416 -6.752476)
			(xy 396.73416 -6.697924) (xy 396.741924 -6.643928) (xy 396.757294 -6.591587) (xy 396.779956 -6.541966)
			(xy 396.809451 -6.496075) (xy 396.845176 -6.454849) (xy 396.886405 -6.419128) (xy 396.932299 -6.389638)
			(xy 396.981922 -6.36698) (xy 397.034265 -6.351616) (xy 397.088262 -6.343857) (xy 397.115538 -6.343396)
			(xy 397.979138 -6.343396) (xy 398.006403 -6.343969) (xy 398.060376 -6.351734) (xy 398.112695 -6.367101)
			(xy 398.162295 -6.389757) (xy 398.208166 -6.419241) (xy 398.249375 -6.454952) (xy 398.285082 -6.496164)
			(xy 398.314561 -6.542038) (xy 398.337212 -6.59164) (xy 398.352574 -6.643961) (xy 398.360334 -6.697935)
			(xy 398.360334 -6.752465) (xy 398.360333 -6.752471) (xy 400.334182 -6.752471) (xy 400.334182 -6.697929)
			(xy 400.341944 -6.643941) (xy 400.35731 -6.591607) (xy 400.379968 -6.541993) (xy 400.409455 -6.496108)
			(xy 400.445172 -6.454886) (xy 400.486392 -6.419167) (xy 400.532275 -6.389677) (xy 400.581888 -6.367017)
			(xy 400.634221 -6.351649) (xy 400.688209 -6.343884) (xy 400.71548 -6.343396) (xy 401.57908 -6.343396)
			(xy 401.606349 -6.343942) (xy 401.660332 -6.351701) (xy 401.712661 -6.367064) (xy 401.762272 -6.389718)
			(xy 401.808153 -6.419202) (xy 401.849371 -6.454915) (xy 401.885086 -6.496131) (xy 401.914573 -6.542011)
			(xy 401.937229 -6.59162) (xy 401.952595 -6.643948) (xy 401.960357 -6.697931) (xy 401.960357 -6.752469)
			(xy 401.960357 -6.752471) (xy 403.934382 -6.752471) (xy 403.934382 -6.697929) (xy 403.942144 -6.643941)
			(xy 403.95751 -6.591608) (xy 403.980167 -6.541994) (xy 404.009654 -6.496109) (xy 404.045371 -6.454888)
			(xy 404.08659 -6.419168) (xy 404.132473 -6.389679) (xy 404.182085 -6.367019) (xy 404.234418 -6.351649)
			(xy 404.288405 -6.343884) (xy 404.315676 -6.343396) (xy 405.179276 -6.343396) (xy 405.206545 -6.343942)
			(xy 405.260529 -6.3517) (xy 405.312858 -6.367063) (xy 405.362469 -6.389716) (xy 405.408351 -6.4192)
			(xy 405.449569 -6.454914) (xy 405.485285 -6.49613) (xy 405.514772 -6.54201) (xy 405.537429 -6.591619)
			(xy 405.552795 -6.643948) (xy 405.560557 -6.697931) (xy 405.560557 -6.752469) (xy 405.560556 -6.752476)
			(xy 413.04426 -6.752476) (xy 413.04426 -6.697924) (xy 413.052024 -6.643928) (xy 413.067394 -6.591586)
			(xy 413.090057 -6.541965) (xy 413.119551 -6.496074) (xy 413.155277 -6.454849) (xy 413.196506 -6.419127)
			(xy 413.2424 -6.389638) (xy 413.292024 -6.36698) (xy 413.344367 -6.351615) (xy 413.398364 -6.343857)
			(xy 413.42564 -6.343396) (xy 414.28924 -6.343396) (xy 414.316504 -6.343969) (xy 414.370478 -6.351734)
			(xy 414.422797 -6.367102) (xy 414.472397 -6.389758) (xy 414.518267 -6.419241) (xy 414.559476 -6.454953)
			(xy 414.595183 -6.496165) (xy 414.624662 -6.542039) (xy 414.647312 -6.591641) (xy 414.662674 -6.643961)
			(xy 414.670434 -6.697935) (xy 414.670434 -6.752465) (xy 414.670433 -6.752472) (xy 416.644282 -6.752472)
			(xy 416.644282 -6.697928) (xy 416.652045 -6.64394) (xy 416.667411 -6.591607) (xy 416.690068 -6.541992)
			(xy 416.719555 -6.496107) (xy 416.755273 -6.454885) (xy 416.796493 -6.419166) (xy 416.842376 -6.389677)
			(xy 416.89199 -6.367017) (xy 416.944323 -6.351648) (xy 416.99831 -6.343884) (xy 417.025582 -6.343396)
			(xy 417.889182 -6.343396) (xy 417.916451 -6.343942) (xy 417.970434 -6.351701) (xy 418.022763 -6.367064)
			(xy 418.072373 -6.389718) (xy 418.118254 -6.419202) (xy 418.159471 -6.454916) (xy 418.195187 -6.496132)
			(xy 418.224673 -6.542011) (xy 418.247329 -6.59162) (xy 418.262695 -6.643949) (xy 418.270457 -6.697931)
			(xy 418.270457 -6.752469) (xy 418.270457 -6.752471) (xy 424.254382 -6.752471) (xy 424.254382 -6.697929)
			(xy 424.262144 -6.643941) (xy 424.27751 -6.591608) (xy 424.300167 -6.541994) (xy 424.329654 -6.496109)
			(xy 424.365371 -6.454888) (xy 424.40659 -6.419168) (xy 424.452473 -6.389679) (xy 424.502085 -6.367019)
			(xy 424.554418 -6.351649) (xy 424.608405 -6.343884) (xy 424.635676 -6.343396) (xy 425.499276 -6.343396)
			(xy 425.526545 -6.343942) (xy 425.580529 -6.3517) (xy 425.632858 -6.367063) (xy 425.682469 -6.389716)
			(xy 425.728351 -6.4192) (xy 425.769569 -6.454914) (xy 425.805285 -6.49613) (xy 425.834772 -6.54201)
			(xy 425.857429 -6.591619) (xy 425.872795 -6.643948) (xy 425.880557 -6.697931) (xy 425.880557 -6.752469)
			(xy 425.880556 -6.752475) (xy 427.85426 -6.752475) (xy 427.85426 -6.697925) (xy 427.862023 -6.643931)
			(xy 427.877392 -6.591591) (xy 427.900053 -6.541971) (xy 427.929546 -6.496082) (xy 427.965269 -6.454856)
			(xy 428.006496 -6.419135) (xy 428.052387 -6.389645) (xy 428.102008 -6.366986) (xy 428.154348 -6.351619)
			(xy 428.208343 -6.343858) (xy 428.235618 -6.343396) (xy 429.099218 -6.343396) (xy 429.126484 -6.343968)
			(xy 429.180459 -6.35173) (xy 429.232781 -6.367096) (xy 429.282383 -6.38975) (xy 429.328257 -6.419234)
			(xy 429.369468 -6.454945) (xy 429.405177 -6.496157) (xy 429.434658 -6.542032) (xy 429.457311 -6.591636)
			(xy 429.472673 -6.643958) (xy 429.480434 -6.697934) (xy 429.480434 -6.752466) (xy 429.479412 -6.759571)
			(xy 431.465194 -6.759571) (xy 431.465194 -6.705029) (xy 431.472956 -6.651043) (xy 431.488322 -6.598711)
			(xy 431.510979 -6.549098) (xy 431.540465 -6.503214) (xy 431.576181 -6.461994) (xy 431.6174 -6.426276)
			(xy 431.663282 -6.396787) (xy 431.712894 -6.374128) (xy 431.765225 -6.35876) (xy 431.819211 -6.350996)
			(xy 431.846482 -6.350508) (xy 432.710082 -6.350508) (xy 432.737352 -6.35103) (xy 432.791336 -6.35879)
			(xy 432.843667 -6.374153) (xy 432.893279 -6.396808) (xy 432.939161 -6.426293) (xy 432.98038 -6.462007)
			(xy 433.016096 -6.503225) (xy 433.045583 -6.549106) (xy 433.068241 -6.598716) (xy 433.083607 -6.651046)
			(xy 433.091369 -6.70503) (xy 433.091369 -6.75247) (xy 445.449182 -6.75247) (xy 445.449182 -6.69793)
			(xy 445.456944 -6.643944) (xy 445.472308 -6.591613) (xy 445.494963 -6.542001) (xy 445.524448 -6.496117)
			(xy 445.560162 -6.454896) (xy 445.601379 -6.419177) (xy 445.647258 -6.389686) (xy 445.696868 -6.367025)
			(xy 445.749198 -6.351654) (xy 445.803182 -6.343886) (xy 445.830452 -6.343396) (xy 446.694052 -6.343396)
			(xy 446.721322 -6.34394) (xy 446.775308 -6.351696) (xy 446.827641 -6.367056) (xy 446.877255 -6.389709)
			(xy 446.923139 -6.419192) (xy 446.964361 -6.454905) (xy 447.00008 -6.496122) (xy 447.029568 -6.542003)
			(xy 447.052227 -6.591614) (xy 447.067594 -6.643945) (xy 447.075356 -6.69793) (xy 447.075356 -6.75247)
			(xy 447.067594 -6.806455) (xy 447.052227 -6.858786) (xy 447.029568 -6.908397) (xy 447.000079 -6.954278)
			(xy 446.964361 -6.995495) (xy 446.923139 -7.031208) (xy 446.877255 -7.060691) (xy 446.827641 -7.083344)
			(xy 446.775308 -7.098704) (xy 446.721322 -7.10646) (xy 446.694052 -7.10692) (xy 445.830452 -7.10692)
			(xy 445.803182 -7.106514) (xy 445.749198 -7.098746) (xy 445.696868 -7.083375) (xy 445.647258 -7.060714)
			(xy 445.601378 -7.031223) (xy 445.560162 -6.995504) (xy 445.524448 -6.954283) (xy 445.494963 -6.908399)
			(xy 445.472308 -6.858787) (xy 445.456944 -6.806455) (xy 445.449182 -6.75247) (xy 433.091369 -6.75247)
			(xy 433.091369 -6.75957) (xy 433.083607 -6.813554) (xy 433.068241 -6.865884) (xy 433.045583 -6.915494)
			(xy 433.016096 -6.961375) (xy 432.98038 -7.002593) (xy 432.939161 -7.038307) (xy 432.893279 -7.067792)
			(xy 432.843667 -7.090447) (xy 432.791336 -7.10581) (xy 432.737352 -7.11357) (xy 432.710082 -7.114032)
			(xy 431.846482 -7.114032) (xy 431.819211 -7.113604) (xy 431.765225 -7.10584) (xy 431.712894 -7.090472)
			(xy 431.663282 -7.067813) (xy 431.6174 -7.038324) (xy 431.576181 -7.002606) (xy 431.540465 -6.961386)
			(xy 431.510979 -6.915502) (xy 431.488322 -6.865889) (xy 431.472956 -6.813557) (xy 431.465194 -6.759571)
			(xy 429.479412 -6.759571) (xy 429.472673 -6.806442) (xy 429.457311 -6.858764) (xy 429.434658 -6.908368)
			(xy 429.405177 -6.954243) (xy 429.369468 -6.995455) (xy 429.328257 -7.031166) (xy 429.282383 -7.06065)
			(xy 429.232781 -7.083304) (xy 429.180459 -7.09867) (xy 429.126484 -7.106432) (xy 429.099218 -7.10692)
			(xy 428.235618 -7.10692) (xy 428.208343 -7.106542) (xy 428.154348 -7.098781) (xy 428.102008 -7.083414)
			(xy 428.052387 -7.060755) (xy 428.006496 -7.031265) (xy 427.965269 -6.995544) (xy 427.929546 -6.954318)
			(xy 427.900053 -6.908429) (xy 427.877392 -6.858809) (xy 427.862023 -6.806469) (xy 427.85426 -6.752475)
			(xy 425.880556 -6.752475) (xy 425.872795 -6.806452) (xy 425.857429 -6.858781) (xy 425.834772 -6.90839)
			(xy 425.805285 -6.95427) (xy 425.769569 -6.995486) (xy 425.728351 -7.0312) (xy 425.682469 -7.060684)
			(xy 425.632858 -7.083337) (xy 425.580529 -7.0987) (xy 425.526545 -7.106458) (xy 425.499276 -7.10692)
			(xy 424.635676 -7.10692) (xy 424.608405 -7.106516) (xy 424.554418 -7.098751) (xy 424.502085 -7.083381)
			(xy 424.452473 -7.060721) (xy 424.40659 -7.031232) (xy 424.365371 -6.995512) (xy 424.329654 -6.954291)
			(xy 424.300167 -6.908406) (xy 424.27751 -6.858792) (xy 424.262144 -6.806459) (xy 424.254382 -6.752471)
			(xy 418.270457 -6.752471) (xy 418.262695 -6.806451) (xy 418.247329 -6.85878) (xy 418.224673 -6.908389)
			(xy 418.195187 -6.954268) (xy 418.159471 -6.995484) (xy 418.118254 -7.031198) (xy 418.072373 -7.060682)
			(xy 418.022763 -7.083336) (xy 417.970434 -7.098699) (xy 417.916451 -7.106458) (xy 417.889182 -7.10692)
			(xy 417.025582 -7.10692) (xy 416.99831 -7.106516) (xy 416.944323 -7.098752) (xy 416.89199 -7.083383)
			(xy 416.842376 -7.060723) (xy 416.796493 -7.031234) (xy 416.755273 -6.995515) (xy 416.719555 -6.954293)
			(xy 416.690068 -6.908408) (xy 416.667411 -6.858793) (xy 416.652045 -6.806459) (xy 416.644282 -6.752472)
			(xy 414.670433 -6.752472) (xy 414.662674 -6.806439) (xy 414.647312 -6.858759) (xy 414.624662 -6.908361)
			(xy 414.595183 -6.954235) (xy 414.559476 -6.995447) (xy 414.518267 -7.031159) (xy 414.472397 -7.060642)
			(xy 414.422797 -7.083298) (xy 414.370478 -7.098666) (xy 414.316505 -7.106431) (xy 414.28924 -7.10692)
			(xy 413.42564 -7.10692) (xy 413.398364 -7.106543) (xy 413.344367 -7.098785) (xy 413.292024 -7.08342)
			(xy 413.2424 -7.060762) (xy 413.196506 -7.031273) (xy 413.155277 -6.995551) (xy 413.119551 -6.954326)
			(xy 413.090057 -6.908435) (xy 413.067394 -6.858814) (xy 413.052024 -6.806472) (xy 413.04426 -6.752476)
			(xy 405.560556 -6.752476) (xy 405.552795 -6.806452) (xy 405.537429 -6.858781) (xy 405.514772 -6.90839)
			(xy 405.485285 -6.95427) (xy 405.449569 -6.995486) (xy 405.408351 -7.0312) (xy 405.362469 -7.060684)
			(xy 405.312858 -7.083337) (xy 405.260529 -7.0987) (xy 405.206545 -7.106458) (xy 405.179276 -7.10692)
			(xy 404.315676 -7.10692) (xy 404.288405 -7.106516) (xy 404.234418 -7.098751) (xy 404.182085 -7.083381)
			(xy 404.132473 -7.060721) (xy 404.08659 -7.031232) (xy 404.045371 -6.995512) (xy 404.009654 -6.954291)
			(xy 403.980167 -6.908406) (xy 403.95751 -6.858792) (xy 403.942144 -6.806459) (xy 403.934382 -6.752471)
			(xy 401.960357 -6.752471) (xy 401.952595 -6.806452) (xy 401.937229 -6.85878) (xy 401.914573 -6.908389)
			(xy 401.885086 -6.954269) (xy 401.849371 -6.995485) (xy 401.808153 -7.031198) (xy 401.762272 -7.060682)
			(xy 401.712661 -7.083336) (xy 401.660332 -7.098699) (xy 401.606349 -7.106458) (xy 401.57908 -7.10692)
			(xy 400.71548 -7.10692) (xy 400.688209 -7.106516) (xy 400.634221 -7.098751) (xy 400.581888 -7.083383)
			(xy 400.532275 -7.060723) (xy 400.486392 -7.031233) (xy 400.445172 -6.995514) (xy 400.409455 -6.954292)
			(xy 400.379968 -6.908407) (xy 400.35731 -6.858793) (xy 400.341944 -6.806459) (xy 400.334182 -6.752471)
			(xy 398.360333 -6.752471) (xy 398.352574 -6.806439) (xy 398.337212 -6.85876) (xy 398.314561 -6.908362)
			(xy 398.285082 -6.954236) (xy 398.249375 -6.995448) (xy 398.208166 -7.031159) (xy 398.162295 -7.060643)
			(xy 398.112695 -7.083299) (xy 398.060376 -7.098666) (xy 398.006403 -7.106431) (xy 397.979138 -7.10692)
			(xy 397.115538 -7.10692) (xy 397.088262 -7.106543) (xy 397.034265 -7.098784) (xy 396.981922 -7.08342)
			(xy 396.932299 -7.060762) (xy 396.886405 -7.031272) (xy 396.845176 -6.995551) (xy 396.809451 -6.954325)
			(xy 396.779956 -6.908434) (xy 396.757294 -6.858813) (xy 396.741924 -6.806472) (xy 396.73416 -6.752476)
			(xy 394.760456 -6.752476) (xy 394.752695 -6.806449) (xy 394.73733 -6.858777) (xy 394.714675 -6.908385)
			(xy 394.68519 -6.954264) (xy 394.649476 -6.995479) (xy 394.60826 -7.031193) (xy 394.562381 -7.060677)
			(xy 394.512773 -7.083332) (xy 394.460446 -7.098696) (xy 394.406464 -7.106457) (xy 394.379196 -7.10692)
			(xy 393.515596 -7.10692) (xy 393.488324 -7.106517) (xy 393.434335 -7.098754) (xy 393.382 -7.083387)
			(xy 393.332385 -7.060728) (xy 393.286499 -7.031239) (xy 393.245278 -6.995519) (xy 393.209559 -6.954297)
			(xy 393.18007 -6.908412) (xy 393.157412 -6.858796) (xy 393.142045 -6.806461) (xy 393.134283 -6.752472)
			(xy 388.110984 -6.752472) (xy 388.110984 -9.780016) (xy 388.110499 -9.850398) (xy 388.102605 -9.99094)
			(xy 388.086844 -10.130819) (xy 388.063264 -10.269594) (xy 388.03194 -10.406828) (xy 387.992971 -10.54209)
			(xy 387.946478 -10.674954) (xy 387.892609 -10.805003) (xy 387.831533 -10.931826) (xy 387.763442 -11.055026)
			(xy 387.68855 -11.174213) (xy 387.607093 -11.289014) (xy 387.519328 -11.399067) (xy 387.425529 -11.504025)
			(xy 387.325993 -11.60356) (xy 387.221033 -11.697356) (xy 387.110979 -11.78512) (xy 386.996176 -11.866575)
			(xy 386.876988 -11.941465) (xy 386.753787 -12.009554) (xy 386.626963 -12.070627) (xy 386.496913 -12.124494)
			(xy 386.364048 -12.170984) (xy 386.228785 -12.209951) (xy 386.091551 -12.241273) (xy 385.952775 -12.26485)
			(xy 385.812896 -12.280609) (xy 385.672354 -12.2885) (xy 385.601972 -12.289028) (xy 260.800088 -12.289028)
			(xy 260.744319 -12.28955) (xy 260.633094 -12.297886) (xy 260.522803 -12.314511) (xy 260.414062 -12.339331)
			(xy 260.30748 -12.372208) (xy 260.234662 -12.400788) (xy 436.813452 -12.400788) (xy 436.813941 -12.359678)
			(xy 436.821529 -12.27781) (xy 436.83664 -12.196991) (xy 436.859145 -12.117912) (xy 436.888851 -12.041247)
			(xy 436.925505 -11.96765) (xy 436.968795 -11.89775) (xy 437.01835 -11.832142) (xy 437.073748 -11.771388)
			(xy 437.134516 -11.716006) (xy 437.200136 -11.666467) (xy 437.270047 -11.623195) (xy 437.343653 -11.58656)
			(xy 437.420326 -11.556873) (xy 437.499411 -11.534389) (xy 437.580234 -11.519298) (xy 437.662104 -11.511731)
			(xy 437.703214 -11.51128) (xy 437.747029 -11.511772) (xy 437.83424 -11.520318) (xy 437.920187 -11.537406)
			(xy 438.004035 -11.562868) (xy 438.084971 -11.596458) (xy 438.123838 -11.61669) (xy 438.135191 -11.622017)
			(xy 438.160237 -11.622017) (xy 438.17159 -11.61669) (xy 438.210465 -11.596477) (xy 438.291405 -11.562905)
			(xy 438.375252 -11.537448) (xy 438.461195 -11.520353) (xy 438.548401 -11.511784) (xy 438.592214 -11.51128)
			(xy 438.636029 -11.511772) (xy 438.72324 -11.520318) (xy 438.809187 -11.537406) (xy 438.893035 -11.562868)
			(xy 438.973971 -11.596458) (xy 439.012838 -11.61669) (xy 439.024191 -11.622017) (xy 439.049237 -11.622017)
			(xy 439.06059 -11.61669) (xy 439.099465 -11.596477) (xy 439.180405 -11.562905) (xy 439.264252 -11.537448)
			(xy 439.350195 -11.520353) (xy 439.437401 -11.511784) (xy 439.481214 -11.51128) (xy 439.521951 -11.511719)
			(xy 439.603086 -11.519152) (xy 439.683202 -11.533973) (xy 439.761626 -11.556057) (xy 439.837703 -11.585219)
			(xy 439.910794 -11.621216) (xy 439.94578 -11.64209) (xy 439.954798 -11.647053) (xy 439.975154 -11.650004)
			(xy 439.995036 -11.644737) (xy 440.003438 -11.638788) (xy 440.091322 -11.570462) (xy 440.10072 -11.54049)
			(xy 440.095894 -11.52525) (xy 440.083229 -11.482506) (xy 440.065483 -11.395136) (xy 440.056563 -11.306429)
			(xy 440.056016 -11.261852) (xy 440.056016 -11.26109) (xy 440.056438 -11.22287) (xy 440.062998 -11.146712)
			(xy 440.076079 -11.071399) (xy 440.095582 -10.997489) (xy 440.108086 -10.96137) (xy 440.110695 -10.953059)
			(xy 440.110679 -10.935651) (xy 440.108086 -10.927334) (xy 440.095582 -10.891215) (xy 440.076095 -10.817302)
			(xy 440.063015 -10.74199) (xy 440.056437 -10.665834) (xy 440.056016 -10.627614) (xy 440.056016 -10.626852)
			(xy 440.05652 -10.584504) (xy 440.064571 -10.50019) (xy 440.0806 -10.417024) (xy 440.104461 -10.335757)
			(xy 440.13594 -10.257127) (xy 440.174751 -10.181846) (xy 440.220541 -10.110594) (xy 440.272897 -10.044018)
			(xy 440.331345 -9.98272) (xy 440.395355 -9.927255) (xy 440.464347 -9.878126) (xy 440.537697 -9.835777)
			(xy 440.61474 -9.800593) (xy 440.694779 -9.772891) (xy 440.777088 -9.752923) (xy 440.860923 -9.74087)
			(xy 440.945524 -9.73684) (xy 441.030125 -9.74087) (xy 441.11396 -9.752923) (xy 441.196269 -9.772891)
			(xy 441.276308 -9.800593) (xy 441.353351 -9.835777) (xy 441.426701 -9.878126) (xy 441.495693 -9.927255)
			(xy 441.559703 -9.98272) (xy 441.618151 -10.044018) (xy 441.670507 -10.110594) (xy 441.716297 -10.181846)
			(xy 441.755108 -10.257127) (xy 441.786587 -10.335757) (xy 441.810448 -10.417024) (xy 441.826477 -10.50019)
			(xy 441.834528 -10.584504) (xy 441.835032 -10.626852) (xy 441.835032 -10.627614) (xy 441.834614 -10.665834)
			(xy 441.828053 -10.741992) (xy 441.814972 -10.817305) (xy 441.795467 -10.891215) (xy 441.782962 -10.927334)
			(xy 441.780399 -10.935656) (xy 441.780383 -10.953054) (xy 441.782962 -10.96137) (xy 441.795465 -10.997489)
			(xy 441.814952 -11.071403) (xy 441.828033 -11.146715) (xy 441.834611 -11.22287) (xy 441.835032 -11.26109)
			(xy 441.835032 -11.261852) (xy 441.834502 -11.302954) (xy 441.826922 -11.384807) (xy 441.811821 -11.465611)
			(xy 441.789329 -11.544677) (xy 441.759637 -11.621331) (xy 441.722999 -11.694918) (xy 441.679728 -11.764811)
			(xy 441.630192 -11.830413) (xy 441.574815 -11.891164) (xy 441.514068 -11.946546) (xy 441.44847 -11.996087)
			(xy 441.378581 -12.039364) (xy 441.304997 -12.076008) (xy 441.228346 -12.105706) (xy 441.149281 -12.128204)
			(xy 441.068478 -12.143312) (xy 440.986626 -12.150899) (xy 440.945524 -12.15136) (xy 440.945016 -12.15136)
			(xy 440.904322 -12.150875) (xy 440.823276 -12.143416) (xy 440.74325 -12.128584) (xy 440.664913 -12.106505)
			(xy 440.58892 -12.077363) (xy 440.515907 -12.041401) (xy 440.480958 -12.02055) (xy 440.471926 -12.015614)
			(xy 440.451579 -12.012649) (xy 440.431701 -12.017907) (xy 440.4233 -12.023852) (xy 440.335416 -12.092178)
			(xy 440.326018 -12.12215) (xy 440.330844 -12.13739) (xy 440.343568 -12.180123) (xy 440.361398 -12.267491)
			(xy 440.370394 -12.356204) (xy 440.370976 -12.400788) (xy 440.370415 -12.444238) (xy 440.361895 -12.530719)
			(xy 440.344992 -12.615959) (xy 440.319868 -12.699148) (xy 440.286761 -12.779495) (xy 440.266836 -12.81811)
			(xy 440.262961 -12.82623) (xy 440.260628 -12.84406) (xy 440.262264 -12.852908) (xy 440.272023 -12.900055)
			(xy 440.282457 -12.995773) (xy 440.283092 -13.043916) (xy 440.282667 -13.085188) (xy 440.275027 -13.167377)
			(xy 440.259804 -13.248505) (xy 440.23713 -13.327874) (xy 440.2072 -13.4048) (xy 440.170271 -13.478622)
			(xy 440.126661 -13.548705) (xy 440.076745 -13.614446) (xy 440.020952 -13.675279) (xy 439.959763 -13.730681)
			(xy 439.893704 -13.780175) (xy 439.823344 -13.823336) (xy 439.786522 -13.841984) (xy 439.778885 -13.846179)
			(xy 439.766763 -13.858679) (xy 439.759479 -13.874495) (xy 439.758328 -13.883132) (xy 439.755251 -13.911241)
			(xy 439.741951 -13.966197) (xy 439.720685 -14.018587) (xy 439.69192 -14.067266) (xy 439.656285 -14.111165)
			(xy 439.643167 -14.123162) (xy 440.58586 -14.123162) (xy 440.586283 -14.084873) (xy 440.592885 -14.008579)
			(xy 440.60603 -13.933136) (xy 440.625619 -13.859105) (xy 440.638184 -13.822934) (xy 440.640853 -13.814502)
			(xy 440.64084 -13.796827) (xy 440.638184 -13.78839) (xy 440.625655 -13.752208) (xy 440.606078 -13.678176)
			(xy 440.592927 -13.602738) (xy 440.586298 -13.52645) (xy 440.58586 -13.488162) (xy 440.586364 -13.445801)
			(xy 440.594417 -13.361464) (xy 440.610451 -13.278274) (xy 440.634319 -13.196984) (xy 440.665807 -13.118332)
			(xy 440.704629 -13.043029) (xy 440.750432 -12.971757) (xy 440.802803 -12.905161) (xy 440.861268 -12.843846)
			(xy 440.925296 -12.788365) (xy 440.994308 -12.739222) (xy 441.067678 -12.696862) (xy 441.144743 -12.661667)
			(xy 441.224805 -12.633958) (xy 441.307138 -12.613984) (xy 441.390997 -12.601927) (xy 441.475622 -12.597896)
			(xy 441.560247 -12.601927) (xy 441.644106 -12.613984) (xy 441.726439 -12.633958) (xy 441.806501 -12.661667)
			(xy 441.883566 -12.696862) (xy 441.956936 -12.739222) (xy 442.025948 -12.788365) (xy 442.089976 -12.843846)
			(xy 442.135955 -12.892066) (xy 445.44847 -12.892066) (xy 445.44847 -12.837534) (xy 445.456231 -12.783558)
			(xy 445.471594 -12.731236) (xy 445.494246 -12.681632) (xy 445.523728 -12.635757) (xy 445.559438 -12.594545)
			(xy 445.600649 -12.558834) (xy 445.646523 -12.529351) (xy 445.696126 -12.506697) (xy 445.748448 -12.491333)
			(xy 445.802424 -12.483571) (xy 445.82969 -12.483084) (xy 446.69329 -12.483084) (xy 446.720565 -12.483455)
			(xy 446.774559 -12.491217) (xy 446.826899 -12.506584) (xy 446.87652 -12.529244) (xy 446.92241 -12.558735)
			(xy 446.963636 -12.594456) (xy 446.999359 -12.635682) (xy 447.028851 -12.681571) (xy 447.051512 -12.731191)
			(xy 447.066881 -12.783531) (xy 447.074644 -12.837525) (xy 447.074644 -12.892075) (xy 447.066881 -12.946069)
			(xy 447.051512 -12.998409) (xy 447.028851 -13.048029) (xy 446.999359 -13.093918) (xy 446.963636 -13.135144)
			(xy 446.92241 -13.170865) (xy 446.87652 -13.200356) (xy 446.826899 -13.223016) (xy 446.774559 -13.238383)
			(xy 446.720565 -13.246145) (xy 446.69329 -13.246608) (xy 445.82969 -13.246608) (xy 445.802424 -13.246029)
			(xy 445.748448 -13.238267) (xy 445.696126 -13.222903) (xy 445.646523 -13.200249) (xy 445.600649 -13.170766)
			(xy 445.559438 -13.135055) (xy 445.523728 -13.093843) (xy 445.494246 -13.047968) (xy 445.471594 -12.998364)
			(xy 445.456231 -12.946042) (xy 445.44847 -12.892066) (xy 442.135955 -12.892066) (xy 442.148441 -12.905161)
			(xy 442.200812 -12.971757) (xy 442.246615 -13.043029) (xy 442.285437 -13.118332) (xy 442.316925 -13.196984)
			(xy 442.340793 -13.278274) (xy 442.356827 -13.361464) (xy 442.36488 -13.445801) (xy 442.365384 -13.488162)
			(xy 442.364966 -13.526452) (xy 442.358362 -13.602745) (xy 442.345216 -13.678188) (xy 442.325626 -13.752219)
			(xy 442.31306 -13.78839) (xy 442.310428 -13.796831) (xy 442.310415 -13.814498) (xy 442.31306 -13.822934)
			(xy 442.325598 -13.859113) (xy 442.345172 -13.933146) (xy 442.358321 -14.008585) (xy 442.364947 -14.084874)
			(xy 442.365384 -14.123162) (xy 442.36488 -14.165523) (xy 442.356827 -14.24986) (xy 442.340793 -14.33305)
			(xy 442.316925 -14.41434) (xy 442.285437 -14.492992) (xy 442.268155 -14.526514) (xy 449.780152 -14.526514)
			(xy 449.780656 -14.484153) (xy 449.788709 -14.399816) (xy 449.804743 -14.316626) (xy 449.828611 -14.235336)
			(xy 449.860099 -14.156684) (xy 449.898921 -14.081381) (xy 449.944724 -14.010109) (xy 449.997095 -13.943513)
			(xy 450.05556 -13.882198) (xy 450.119588 -13.826717) (xy 450.1886 -13.777574) (xy 450.26197 -13.735214)
			(xy 450.339035 -13.700019) (xy 450.419097 -13.67231) (xy 450.50143 -13.652336) (xy 450.585289 -13.640279)
			(xy 450.669914 -13.636248) (xy 450.754539 -13.640279) (xy 450.838398 -13.652336) (xy 450.920731 -13.67231)
			(xy 451.000793 -13.700019) (xy 451.077858 -13.735214) (xy 451.151228 -13.777574) (xy 451.22024 -13.826717)
			(xy 451.284268 -13.882198) (xy 451.342733 -13.943513) (xy 451.395104 -14.010109) (xy 451.440907 -14.081381)
			(xy 451.479729 -14.156684) (xy 451.511217 -14.235336) (xy 451.535085 -14.316626) (xy 451.551119 -14.399816)
			(xy 451.559172 -14.484153) (xy 451.559676 -14.526514) (xy 451.559114 -14.571839) (xy 451.549887 -14.662018)
			(xy 451.531531 -14.750791) (xy 451.504235 -14.837234) (xy 451.486778 -14.879066) (xy 451.483143 -14.888844)
			(xy 451.483128 -14.909681) (xy 451.486778 -14.919452) (xy 451.504318 -14.961366) (xy 451.53178 -15.047983)
			(xy 451.550267 -15.136947) (xy 451.559587 -15.227334) (xy 451.560184 -15.272766) (xy 451.560184 -15.273782)
			(xy 451.559623 -15.318552) (xy 451.550621 -15.407639) (xy 451.532717 -15.495371) (xy 451.506092 -15.580861)
			(xy 451.489064 -15.62227) (xy 451.485509 -15.631864) (xy 451.485503 -15.652304) (xy 451.489064 -15.661894)
			(xy 451.50607 -15.703278) (xy 451.532693 -15.788702) (xy 451.550602 -15.876368) (xy 451.559616 -15.96539)
			(xy 451.560184 -16.010128) (xy 451.560184 -16.010382) (xy 451.55968 -16.05273) (xy 451.551629 -16.137044)
			(xy 451.5356 -16.22021) (xy 451.511739 -16.301477) (xy 451.48026 -16.380107) (xy 451.441449 -16.455388)
			(xy 451.395659 -16.52664) (xy 451.343303 -16.593216) (xy 451.284855 -16.654514) (xy 451.220845 -16.709979)
			(xy 451.151853 -16.759108) (xy 451.078503 -16.801457) (xy 451.00146 -16.836641) (xy 450.921421 -16.864343)
			(xy 450.839112 -16.884311) (xy 450.755277 -16.896364) (xy 450.670676 -16.900395) (xy 450.586075 -16.896364)
			(xy 450.50224 -16.884311) (xy 450.419931 -16.864343) (xy 450.339892 -16.836641) (xy 450.262849 -16.801457)
			(xy 450.189499 -16.759108) (xy 450.120507 -16.709979) (xy 450.056497 -16.654514) (xy 449.998049 -16.593216)
			(xy 449.945693 -16.52664) (xy 449.899903 -16.455388) (xy 449.861092 -16.380107) (xy 449.829613 -16.301477)
			(xy 449.805752 -16.22021) (xy 449.789723 -16.137044) (xy 449.781672 -16.05273) (xy 449.781168 -16.010382)
			(xy 449.781168 -16.010128) (xy 449.781731 -15.96539) (xy 449.790749 -15.876368) (xy 449.808655 -15.788701)
			(xy 449.83527 -15.703273) (xy 449.852288 -15.661894) (xy 449.855865 -15.652307) (xy 449.855859 -15.63186)
			(xy 449.852288 -15.62227) (xy 449.835263 -15.580859) (xy 449.808628 -15.495372) (xy 449.790721 -15.40764)
			(xy 449.781723 -15.318552) (xy 449.781168 -15.273782) (xy 449.781749 -15.228458) (xy 449.79099 -15.138283)
			(xy 449.809345 -15.049513) (xy 449.836623 -14.963067) (xy 449.854066 -14.92123) (xy 449.857691 -14.911438)
			(xy 449.857571 -14.890584) (xy 449.853812 -14.880844) (xy 449.836183 -14.838823) (xy 449.808624 -14.751958)
			(xy 449.790079 -14.662732) (xy 449.780742 -14.57208) (xy 449.780152 -14.526514) (xy 442.268155 -14.526514)
			(xy 442.246615 -14.568295) (xy 442.200812 -14.639567) (xy 442.148441 -14.706163) (xy 442.089976 -14.767478)
			(xy 442.025948 -14.822959) (xy 441.956936 -14.872102) (xy 441.883566 -14.914462) (xy 441.806501 -14.949657)
			(xy 441.726439 -14.977366) (xy 441.644106 -14.99734) (xy 441.560247 -15.009397) (xy 441.475622 -15.013429)
			(xy 441.390997 -15.009397) (xy 441.307138 -14.99734) (xy 441.224805 -14.977366) (xy 441.144743 -14.949657)
			(xy 441.067678 -14.914462) (xy 440.994308 -14.872102) (xy 440.925296 -14.822959) (xy 440.861268 -14.767478)
			(xy 440.802803 -14.706163) (xy 440.750432 -14.639567) (xy 440.704629 -14.568295) (xy 440.665807 -14.492992)
			(xy 440.634319 -14.41434) (xy 440.610451 -14.33305) (xy 440.594417 -14.24986) (xy 440.586364 -14.165523)
			(xy 440.58586 -14.123162) (xy 439.643167 -14.123162) (xy 439.614561 -14.149324) (xy 439.567661 -14.180907)
			(xy 439.516614 -14.205222) (xy 439.462537 -14.221736) (xy 439.406615 -14.230088) (xy 439.378344 -14.230604)
			(xy 439.350975 -14.230111) (xy 439.296797 -14.2223) (xy 439.244294 -14.206817) (xy 439.194547 -14.183981)
			(xy 439.148579 -14.154262) (xy 439.127646 -14.136624) (xy 439.127392 -14.13637) (xy 439.120314 -14.130771)
			(xy 439.103391 -14.124533) (xy 439.094372 -14.124178) (xy 439.027316 -14.124178) (xy 439.018301 -14.124547)
			(xy 439.001384 -14.130787) (xy 438.994296 -14.13637) (xy 438.994296 -14.136624) (xy 438.994042 -14.136624)
			(xy 438.973108 -14.154261) (xy 438.927135 -14.183972) (xy 438.877388 -14.206808) (xy 438.824888 -14.2223)
			(xy 438.770713 -14.230129) (xy 438.743344 -14.230604) (xy 438.713998 -14.230028) (xy 438.656001 -14.221024)
			(xy 438.600065 -14.203253) (xy 438.547506 -14.177132) (xy 438.499563 -14.143277) (xy 438.457364 -14.102486)
			(xy 438.421903 -14.055718) (xy 438.394015 -14.004075) (xy 438.38368 -13.976604) (xy 438.380221 -13.968026)
			(xy 438.368225 -13.953963) (xy 438.360312 -13.949172) (xy 438.333388 -13.93444) (xy 438.324705 -13.93016)
			(xy 438.305508 -13.927807) (xy 438.29605 -13.929868) (xy 438.259095 -13.939128) (xy 438.184005 -13.952036)
			(xy 438.108086 -13.958466) (xy 438.06999 -13.958824) (xy 438.028658 -13.958363) (xy 437.94635 -13.95071)
			(xy 437.865107 -13.935453) (xy 437.78563 -13.912724) (xy 437.708605 -13.882718) (xy 437.634696 -13.845694)
			(xy 437.564542 -13.801972) (xy 437.498747 -13.751929) (xy 437.43788 -13.695998) (xy 437.382465 -13.634659)
			(xy 437.332981 -13.568444) (xy 437.289854 -13.497922) (xy 437.253456 -13.423703) (xy 437.224103 -13.346427)
			(xy 437.202046 -13.266761) (xy 437.187477 -13.185391) (xy 437.18353 -13.144246) (xy 437.182106 -13.133691)
			(xy 437.171856 -13.11505) (xy 437.163718 -13.108178) (xy 437.131484 -13.082996) (xy 437.071245 -13.027653)
			(xy 437.016344 -12.967011) (xy 436.967245 -12.901582) (xy 436.924364 -12.831919) (xy 436.888063 -12.758612)
			(xy 436.858649 -12.682281) (xy 436.83637 -12.603571) (xy 436.821416 -12.523147) (xy 436.813913 -12.441689)
			(xy 436.813452 -12.400788) (xy 260.234662 -12.400788) (xy 260.203654 -12.412958) (xy 260.103162 -12.461353)
			(xy 260.006569 -12.517122) (xy 259.914413 -12.579954) (xy 259.82721 -12.649497) (xy 259.745448 -12.725362)
			(xy 259.669584 -12.807125) (xy 259.601843 -12.89207) (xy 431.453248 -12.89207) (xy 431.453248 -12.83753)
			(xy 431.46101 -12.783546) (xy 431.476376 -12.731216) (xy 431.499035 -12.681606) (xy 431.528523 -12.635726)
			(xy 431.564241 -12.594509) (xy 431.605461 -12.558796) (xy 431.651345 -12.529313) (xy 431.700957 -12.506661)
			(xy 431.753289 -12.4913) (xy 431.807274 -12.483544) (xy 431.834544 -12.483084) (xy 432.698144 -12.483084)
			(xy 432.725415 -12.483482) (xy 432.7794 -12.491249) (xy 432.83173 -12.50662) (xy 432.881341 -12.529282)
			(xy 432.927222 -12.558772) (xy 432.968439 -12.594492) (xy 433.004154 -12.635713) (xy 433.033639 -12.681598)
			(xy 433.056295 -12.731211) (xy 433.07166 -12.783543) (xy 433.079422 -12.837529) (xy 433.079422 -12.892071)
			(xy 433.07166 -12.946057) (xy 433.056295 -12.998389) (xy 433.033639 -13.048002) (xy 433.004154 -13.093887)
			(xy 432.968439 -13.135108) (xy 432.927222 -13.170828) (xy 432.881341 -13.200318) (xy 432.83173 -13.22298)
			(xy 432.7794 -13.238351) (xy 432.725415 -13.246118) (xy 432.698144 -13.246608) (xy 431.834544 -13.246608)
			(xy 431.807274 -13.246056) (xy 431.753289 -13.2383) (xy 431.700957 -13.222939) (xy 431.651345 -13.200287)
			(xy 431.605461 -13.170804) (xy 431.564241 -13.135091) (xy 431.528523 -13.093874) (xy 431.499035 -13.047994)
			(xy 431.476376 -12.998384) (xy 431.46101 -12.946054) (xy 431.453248 -12.89207) (xy 259.601843 -12.89207)
			(xy 259.600042 -12.894329) (xy 259.537211 -12.986486) (xy 259.481443 -13.08308) (xy 259.43305 -13.183572)
			(xy 259.392301 -13.287399) (xy 259.359426 -13.393981) (xy 259.334607 -13.502722) (xy 259.317984 -13.613014)
			(xy 259.309649 -13.724239) (xy 259.309108 -13.780008) (xy 259.309108 -17.126458) (xy 310.265572 -17.126458)
			(xy 310.265992 -17.082972) (xy 310.273576 -16.996331) (xy 310.288682 -16.910681) (xy 310.311195 -16.826674)
			(xy 310.340944 -16.744948) (xy 310.377702 -16.666126) (xy 310.421191 -16.590808) (xy 310.471078 -16.519566)
			(xy 310.526985 -16.452943) (xy 310.588485 -16.391447) (xy 310.65511 -16.335544) (xy 310.726355 -16.285661)
			(xy 310.801676 -16.242177) (xy 310.8805 -16.205422) (xy 310.962227 -16.175678) (xy 311.046236 -16.15317)
			(xy 311.131887 -16.138068) (xy 311.218528 -16.13049) (xy 311.262014 -16.130016) (xy 311.287414 -16.130016)
			(xy 311.33271 -16.130609) (xy 311.422936 -16.13873) (xy 311.512071 -16.154907) (xy 311.599397 -16.179009)
			(xy 311.684211 -16.210841) (xy 311.76583 -16.250148) (xy 311.843598 -16.296613) (xy 311.916887 -16.349861)
			(xy 311.985108 -16.409465) (xy 312.047712 -16.474944) (xy 312.104194 -16.545772) (xy 312.1541 -16.621377)
			(xy 312.197028 -16.701151) (xy 312.232632 -16.784452) (xy 312.260626 -16.870609) (xy 312.280784 -16.958929)
			(xy 312.292944 -17.0487) (xy 312.297009 -17.1392) (xy 312.292944 -17.2297) (xy 312.280784 -17.319471)
			(xy 312.260626 -17.407791) (xy 312.232632 -17.493948) (xy 312.197028 -17.577249) (xy 312.163448 -17.639652)
			(xy 389.652738 -17.639652) (xy 389.652738 -17.585148) (xy 389.660494 -17.531197) (xy 389.675849 -17.4789)
			(xy 389.69849 -17.42932) (xy 389.727956 -17.383466) (xy 389.763647 -17.342273) (xy 389.804838 -17.306578)
			(xy 389.850688 -17.277107) (xy 389.900266 -17.254462) (xy 389.952562 -17.239102) (xy 390.006512 -17.23134)
			(xy 390.033764 -17.230852) (xy 390.897364 -17.230852) (xy 390.924616 -17.231393) (xy 390.978565 -17.239145)
			(xy 391.030862 -17.254496) (xy 391.080441 -17.277134) (xy 391.126294 -17.306598) (xy 391.167486 -17.342288)
			(xy 391.20318 -17.383477) (xy 391.232649 -17.429327) (xy 391.255291 -17.478905) (xy 391.270648 -17.5312)
			(xy 391.278405 -17.585148) (xy 391.278405 -17.639652) (xy 395.240738 -17.639652) (xy 395.240738 -17.585148)
			(xy 395.248494 -17.531197) (xy 395.263849 -17.4789) (xy 395.28649 -17.42932) (xy 395.315956 -17.383466)
			(xy 395.351647 -17.342273) (xy 395.392838 -17.306578) (xy 395.438688 -17.277107) (xy 395.488266 -17.254462)
			(xy 395.540562 -17.239102) (xy 395.594512 -17.23134) (xy 395.621764 -17.230852) (xy 396.485364 -17.230852)
			(xy 396.512616 -17.231393) (xy 396.566565 -17.239145) (xy 396.618862 -17.254496) (xy 396.668441 -17.277134)
			(xy 396.714294 -17.306598) (xy 396.755486 -17.342288) (xy 396.79118 -17.383477) (xy 396.820649 -17.429327)
			(xy 396.843291 -17.478905) (xy 396.858648 -17.5312) (xy 396.866405 -17.585148) (xy 396.866405 -17.639652)
			(xy 400.828738 -17.639652) (xy 400.828738 -17.585148) (xy 400.836494 -17.531197) (xy 400.851849 -17.4789)
			(xy 400.87449 -17.42932) (xy 400.903956 -17.383466) (xy 400.939647 -17.342273) (xy 400.980838 -17.306578)
			(xy 401.026688 -17.277107) (xy 401.076266 -17.254462) (xy 401.128562 -17.239102) (xy 401.182512 -17.23134)
			(xy 401.209764 -17.230852) (xy 402.073364 -17.230852) (xy 402.100616 -17.231393) (xy 402.154565 -17.239145)
			(xy 402.206862 -17.254496) (xy 402.256441 -17.277134) (xy 402.302294 -17.306598) (xy 402.343486 -17.342288)
			(xy 402.37918 -17.383477) (xy 402.408649 -17.429327) (xy 402.431291 -17.478905) (xy 402.446648 -17.5312)
			(xy 402.454405 -17.585148) (xy 402.454405 -17.639652) (xy 402.454301 -17.640372) (xy 406.415424 -17.640372)
			(xy 406.415424 -17.585828) (xy 406.423187 -17.53184) (xy 406.438554 -17.479507) (xy 406.461214 -17.429893)
			(xy 406.490704 -17.38401) (xy 406.526425 -17.342791) (xy 406.567649 -17.307076) (xy 406.613536 -17.277591)
			(xy 406.663152 -17.254938) (xy 406.715487 -17.239576) (xy 406.769476 -17.23182) (xy 406.796748 -17.23136)
			(xy 407.660348 -17.23136) (xy 407.687617 -17.231806) (xy 407.741598 -17.239573) (xy 407.793925 -17.254944)
			(xy 407.843532 -17.277604) (xy 407.88941 -17.307093) (xy 407.930624 -17.34281) (xy 407.966336 -17.384029)
			(xy 407.995819 -17.42991) (xy 408.018473 -17.47952) (xy 408.033837 -17.531849) (xy 408.041598 -17.585831)
			(xy 408.041598 -17.640369) (xy 408.041598 -17.640372) (xy 412.003424 -17.640372) (xy 412.003424 -17.585828)
			(xy 412.011187 -17.53184) (xy 412.026554 -17.479507) (xy 412.049214 -17.429893) (xy 412.078704 -17.38401)
			(xy 412.114425 -17.342791) (xy 412.155649 -17.307076) (xy 412.201536 -17.277591) (xy 412.251152 -17.254938)
			(xy 412.303487 -17.239576) (xy 412.357476 -17.23182) (xy 412.384748 -17.23136) (xy 413.248348 -17.23136)
			(xy 413.275617 -17.231806) (xy 413.329598 -17.239573) (xy 413.381925 -17.254944) (xy 413.431532 -17.277604)
			(xy 413.47741 -17.307093) (xy 413.518624 -17.34281) (xy 413.554336 -17.384029) (xy 413.583819 -17.42991)
			(xy 413.606473 -17.47952) (xy 413.621837 -17.531849) (xy 413.629598 -17.585831) (xy 413.629598 -17.639653)
			(xy 417.898538 -17.639653) (xy 417.898538 -17.585147) (xy 417.906295 -17.531195) (xy 417.92165 -17.478897)
			(xy 417.944292 -17.429315) (xy 417.97376 -17.383461) (xy 418.009453 -17.342267) (xy 418.050645 -17.306572)
			(xy 418.096498 -17.277102) (xy 418.146078 -17.254457) (xy 418.198376 -17.239099) (xy 418.252327 -17.231339)
			(xy 418.27958 -17.230852) (xy 419.14318 -17.230852) (xy 419.170431 -17.231394) (xy 419.224378 -17.239148)
			(xy 419.276673 -17.2545) (xy 419.326251 -17.277139) (xy 419.372101 -17.306604) (xy 419.413292 -17.342294)
			(xy 419.448984 -17.383483) (xy 419.478451 -17.429332) (xy 419.501093 -17.478908) (xy 419.516448 -17.531202)
			(xy 419.524205 -17.585149) (xy 419.524205 -17.639651) (xy 419.524205 -17.639653) (xy 423.486538 -17.639653)
			(xy 423.486538 -17.585147) (xy 423.494295 -17.531195) (xy 423.50965 -17.478897) (xy 423.532292 -17.429315)
			(xy 423.56176 -17.383461) (xy 423.597453 -17.342267) (xy 423.638645 -17.306572) (xy 423.684498 -17.277102)
			(xy 423.734078 -17.254457) (xy 423.786376 -17.239099) (xy 423.840327 -17.231339) (xy 423.86758 -17.230852)
			(xy 424.73118 -17.230852) (xy 424.758431 -17.231394) (xy 424.812378 -17.239148) (xy 424.864673 -17.2545)
			(xy 424.914251 -17.277139) (xy 424.960101 -17.306604) (xy 425.001292 -17.342294) (xy 425.036984 -17.383483)
			(xy 425.066451 -17.429332) (xy 425.089093 -17.478908) (xy 425.104448 -17.531202) (xy 425.112205 -17.585149)
			(xy 425.112205 -17.639651) (xy 425.112102 -17.640368) (xy 429.107346 -17.640368) (xy 429.107346 -17.585832)
			(xy 429.115108 -17.531852) (xy 429.130472 -17.479525) (xy 429.153127 -17.429918) (xy 429.182611 -17.38404)
			(xy 429.218324 -17.342824) (xy 429.25954 -17.307111) (xy 429.305418 -17.277627) (xy 429.355025 -17.254972)
			(xy 429.407352 -17.239608) (xy 429.461332 -17.231846) (xy 429.4886 -17.23136) (xy 430.3522 -17.23136)
			(xy 430.379471 -17.231802) (xy 430.433458 -17.239565) (xy 430.48579 -17.254931) (xy 430.535403 -17.277588)
			(xy 430.581287 -17.307076) (xy 430.622507 -17.342793) (xy 430.658224 -17.384013) (xy 430.687712 -17.429897)
			(xy 430.710369 -17.47951) (xy 430.725735 -17.531842) (xy 430.733498 -17.585829) (xy 430.733498 -17.640371)
			(xy 430.725735 -17.694358) (xy 430.710369 -17.74669) (xy 430.687712 -17.796303) (xy 430.658224 -17.842187)
			(xy 430.622507 -17.883407) (xy 430.581287 -17.919124) (xy 430.535403 -17.948612) (xy 430.48579 -17.971269)
			(xy 430.433458 -17.986635) (xy 430.379471 -17.994398) (xy 430.3522 -17.994884) (xy 429.4886 -17.994884)
			(xy 429.461332 -17.994354) (xy 429.407352 -17.986592) (xy 429.355025 -17.971228) (xy 429.305418 -17.948573)
			(xy 429.25954 -17.919089) (xy 429.218324 -17.883376) (xy 429.182611 -17.84216) (xy 429.153127 -17.796282)
			(xy 429.130472 -17.746675) (xy 429.115108 -17.694348) (xy 429.107346 -17.640368) (xy 425.112102 -17.640368)
			(xy 425.104448 -17.693598) (xy 425.089093 -17.745892) (xy 425.066451 -17.795468) (xy 425.036984 -17.841317)
			(xy 425.001292 -17.882506) (xy 424.960101 -17.918196) (xy 424.914251 -17.947661) (xy 424.864673 -17.9703)
			(xy 424.812378 -17.985652) (xy 424.758431 -17.993406) (xy 424.73118 -17.993868) (xy 423.86758 -17.993868)
			(xy 423.840327 -17.993461) (xy 423.786376 -17.985701) (xy 423.734078 -17.970343) (xy 423.684498 -17.947698)
			(xy 423.638645 -17.918228) (xy 423.597453 -17.882533) (xy 423.56176 -17.841339) (xy 423.532292 -17.795485)
			(xy 423.50965 -17.745903) (xy 423.494295 -17.693605) (xy 423.486538 -17.639653) (xy 419.524205 -17.639653)
			(xy 419.516448 -17.693598) (xy 419.501093 -17.745892) (xy 419.478451 -17.795468) (xy 419.448984 -17.841317)
			(xy 419.413292 -17.882506) (xy 419.372101 -17.918196) (xy 419.326251 -17.947661) (xy 419.276673 -17.9703)
			(xy 419.224378 -17.985652) (xy 419.170431 -17.993406) (xy 419.14318 -17.993868) (xy 418.27958 -17.993868)
			(xy 418.252327 -17.993461) (xy 418.198376 -17.985701) (xy 418.146078 -17.970343) (xy 418.096498 -17.947698)
			(xy 418.050645 -17.918228) (xy 418.009453 -17.882533) (xy 417.97376 -17.841339) (xy 417.944292 -17.795485)
			(xy 417.92165 -17.745903) (xy 417.906295 -17.693605) (xy 417.898538 -17.639653) (xy 413.629598 -17.639653)
			(xy 413.629598 -17.640369) (xy 413.621837 -17.694351) (xy 413.606473 -17.74668) (xy 413.583819 -17.79629)
			(xy 413.554336 -17.842171) (xy 413.518624 -17.88339) (xy 413.47741 -17.919107) (xy 413.431532 -17.948596)
			(xy 413.381925 -17.971256) (xy 413.329598 -17.986627) (xy 413.275617 -17.994394) (xy 413.248348 -17.994884)
			(xy 412.384748 -17.994884) (xy 412.357476 -17.99438) (xy 412.303487 -17.986624) (xy 412.251152 -17.971262)
			(xy 412.201536 -17.948609) (xy 412.155649 -17.919124) (xy 412.114425 -17.883409) (xy 412.078704 -17.84219)
			(xy 412.049214 -17.796307) (xy 412.026554 -17.746693) (xy 412.011187 -17.69436) (xy 412.003424 -17.640372)
			(xy 408.041598 -17.640372) (xy 408.033837 -17.694351) (xy 408.018473 -17.74668) (xy 407.995819 -17.79629)
			(xy 407.966336 -17.842171) (xy 407.930624 -17.88339) (xy 407.88941 -17.919107) (xy 407.843532 -17.948596)
			(xy 407.793925 -17.971256) (xy 407.741598 -17.986627) (xy 407.687617 -17.994394) (xy 407.660348 -17.994884)
			(xy 406.796748 -17.994884) (xy 406.769476 -17.99438) (xy 406.715487 -17.986624) (xy 406.663152 -17.971262)
			(xy 406.613536 -17.948609) (xy 406.567649 -17.919124) (xy 406.526425 -17.883409) (xy 406.490704 -17.84219)
			(xy 406.461214 -17.796307) (xy 406.438554 -17.746693) (xy 406.423187 -17.69436) (xy 406.415424 -17.640372)
			(xy 402.454301 -17.640372) (xy 402.446648 -17.6936) (xy 402.431291 -17.745895) (xy 402.408649 -17.795473)
			(xy 402.37918 -17.841323) (xy 402.343486 -17.882512) (xy 402.302294 -17.918202) (xy 402.256441 -17.947666)
			(xy 402.206862 -17.970304) (xy 402.154565 -17.985655) (xy 402.100616 -17.993407) (xy 402.073364 -17.993868)
			(xy 401.209764 -17.993868) (xy 401.182512 -17.99346) (xy 401.128562 -17.985698) (xy 401.076266 -17.970338)
			(xy 401.026688 -17.947693) (xy 400.980838 -17.918222) (xy 400.939647 -17.882527) (xy 400.903956 -17.841334)
			(xy 400.87449 -17.79548) (xy 400.851849 -17.7459) (xy 400.836494 -17.693603) (xy 400.828738 -17.639652)
			(xy 396.866405 -17.639652) (xy 396.858648 -17.6936) (xy 396.843291 -17.745895) (xy 396.820649 -17.795473)
			(xy 396.79118 -17.841323) (xy 396.755486 -17.882512) (xy 396.714294 -17.918202) (xy 396.668441 -17.947666)
			(xy 396.618862 -17.970304) (xy 396.566565 -17.985655) (xy 396.512616 -17.993407) (xy 396.485364 -17.993868)
			(xy 395.621764 -17.993868) (xy 395.594512 -17.99346) (xy 395.540562 -17.985698) (xy 395.488266 -17.970338)
			(xy 395.438688 -17.947693) (xy 395.392838 -17.918222) (xy 395.351647 -17.882527) (xy 395.315956 -17.841334)
			(xy 395.28649 -17.79548) (xy 395.263849 -17.7459) (xy 395.248494 -17.693603) (xy 395.240738 -17.639652)
			(xy 391.278405 -17.639652) (xy 391.270648 -17.6936) (xy 391.255291 -17.745895) (xy 391.232649 -17.795473)
			(xy 391.20318 -17.841323) (xy 391.167486 -17.882512) (xy 391.126294 -17.918202) (xy 391.080441 -17.947666)
			(xy 391.030862 -17.970304) (xy 390.978565 -17.985655) (xy 390.924616 -17.993407) (xy 390.897364 -17.993868)
			(xy 390.033764 -17.993868) (xy 390.006512 -17.99346) (xy 389.952562 -17.985698) (xy 389.900266 -17.970338)
			(xy 389.850688 -17.947693) (xy 389.804838 -17.918222) (xy 389.763647 -17.882527) (xy 389.727956 -17.841334)
			(xy 389.69849 -17.79548) (xy 389.675849 -17.7459) (xy 389.660494 -17.693603) (xy 389.652738 -17.639652)
			(xy 312.163448 -17.639652) (xy 312.1541 -17.657023) (xy 312.104194 -17.732628) (xy 312.047712 -17.803456)
			(xy 311.985108 -17.868935) (xy 311.916887 -17.928539) (xy 311.843598 -17.981787) (xy 311.76583 -18.028252)
			(xy 311.684211 -18.067559) (xy 311.599397 -18.099391) (xy 311.512071 -18.123493) (xy 311.422936 -18.13967)
			(xy 311.33271 -18.147791) (xy 311.287414 -18.1483) (xy 311.28716 -18.1483) (xy 311.242573 -18.147831)
			(xy 311.153739 -18.140039) (xy 311.065923 -18.124536) (xy 310.979792 -18.101438) (xy 310.896001 -18.070922)
			(xy 310.815188 -18.033221) (xy 310.737969 -17.988621) (xy 310.664929 -17.937461) (xy 310.596626 -17.88013)
			(xy 310.533579 -17.817066) (xy 310.476268 -17.748747) (xy 310.425128 -17.675693) (xy 310.380549 -17.598461)
			(xy 310.34287 -17.517638) (xy 310.312377 -17.433839) (xy 310.289303 -17.347701) (xy 310.273824 -17.259881)
			(xy 310.266056 -17.171045) (xy 310.265572 -17.126458) (xy 259.309108 -17.126458) (xy 259.309108 -19.164372)
			(xy 392.445424 -19.164372) (xy 392.445424 -19.109828) (xy 392.453187 -19.05584) (xy 392.468554 -19.003507)
			(xy 392.491214 -18.953893) (xy 392.520704 -18.90801) (xy 392.556425 -18.866791) (xy 392.597649 -18.831076)
			(xy 392.643536 -18.801591) (xy 392.693152 -18.778938) (xy 392.745487 -18.763576) (xy 392.799476 -18.75582)
			(xy 392.826748 -18.75536) (xy 393.690348 -18.75536) (xy 393.717617 -18.755806) (xy 393.771598 -18.763573)
			(xy 393.823925 -18.778944) (xy 393.873532 -18.801604) (xy 393.91941 -18.831093) (xy 393.960624 -18.86681)
			(xy 393.996336 -18.908029) (xy 394.025819 -18.95391) (xy 394.048473 -19.00352) (xy 394.063837 -19.055849)
			(xy 394.071598 -19.109831) (xy 394.071598 -19.163652) (xy 398.034738 -19.163652) (xy 398.034738 -19.109148)
			(xy 398.042494 -19.055197) (xy 398.057849 -19.0029) (xy 398.08049 -18.95332) (xy 398.109956 -18.907466)
			(xy 398.145647 -18.866273) (xy 398.186838 -18.830578) (xy 398.232688 -18.801107) (xy 398.282266 -18.778462)
			(xy 398.334562 -18.763102) (xy 398.388512 -18.75534) (xy 398.415764 -18.754852) (xy 399.279364 -18.754852)
			(xy 399.306616 -18.755393) (xy 399.360565 -18.763145) (xy 399.412862 -18.778496) (xy 399.462441 -18.801134)
			(xy 399.508294 -18.830598) (xy 399.549486 -18.866288) (xy 399.58518 -18.907477) (xy 399.614649 -18.953327)
			(xy 399.637291 -19.002905) (xy 399.652648 -19.0552) (xy 399.660405 -19.109148) (xy 399.660405 -19.163652)
			(xy 403.622738 -19.163652) (xy 403.622738 -19.109148) (xy 403.630494 -19.055197) (xy 403.645849 -19.0029)
			(xy 403.66849 -18.95332) (xy 403.697956 -18.907466) (xy 403.733647 -18.866273) (xy 403.774838 -18.830578)
			(xy 403.820688 -18.801107) (xy 403.870266 -18.778462) (xy 403.922562 -18.763102) (xy 403.976512 -18.75534)
			(xy 404.003764 -18.754852) (xy 404.867364 -18.754852) (xy 404.894616 -18.755393) (xy 404.948565 -18.763145)
			(xy 405.000862 -18.778496) (xy 405.050441 -18.801134) (xy 405.096294 -18.830598) (xy 405.137486 -18.866288)
			(xy 405.17318 -18.907477) (xy 405.202649 -18.953327) (xy 405.225291 -19.002905) (xy 405.240648 -19.0552)
			(xy 405.248405 -19.109148) (xy 405.248405 -19.163652) (xy 409.210738 -19.163652) (xy 409.210738 -19.109148)
			(xy 409.218494 -19.055197) (xy 409.233849 -19.0029) (xy 409.25649 -18.95332) (xy 409.285956 -18.907466)
			(xy 409.321647 -18.866273) (xy 409.362838 -18.830578) (xy 409.408688 -18.801107) (xy 409.458266 -18.778462)
			(xy 409.510562 -18.763102) (xy 409.564512 -18.75534) (xy 409.591764 -18.754852) (xy 410.455364 -18.754852)
			(xy 410.482616 -18.755393) (xy 410.536565 -18.763145) (xy 410.588862 -18.778496) (xy 410.638441 -18.801134)
			(xy 410.684294 -18.830598) (xy 410.725486 -18.866288) (xy 410.76118 -18.907477) (xy 410.790649 -18.953327)
			(xy 410.813291 -19.002905) (xy 410.828648 -19.0552) (xy 410.836405 -19.109148) (xy 410.836405 -19.163652)
			(xy 410.836405 -19.163653) (xy 415.104538 -19.163653) (xy 415.104538 -19.109147) (xy 415.112295 -19.055195)
			(xy 415.12765 -19.002897) (xy 415.150292 -18.953315) (xy 415.17976 -18.907461) (xy 415.215453 -18.866267)
			(xy 415.256645 -18.830572) (xy 415.302498 -18.801102) (xy 415.352078 -18.778457) (xy 415.404376 -18.763099)
			(xy 415.458327 -18.755339) (xy 415.48558 -18.754852) (xy 416.34918 -18.754852) (xy 416.376431 -18.755394)
			(xy 416.430378 -18.763148) (xy 416.482673 -18.7785) (xy 416.532251 -18.801139) (xy 416.578101 -18.830604)
			(xy 416.619292 -18.866294) (xy 416.654984 -18.907483) (xy 416.684451 -18.953332) (xy 416.707093 -19.002908)
			(xy 416.722448 -19.055202) (xy 416.730205 -19.109149) (xy 416.730205 -19.163651) (xy 416.730102 -19.164366)
			(xy 420.691346 -19.164366) (xy 420.691346 -19.109834) (xy 420.699107 -19.055857) (xy 420.714469 -19.003533)
			(xy 420.737121 -18.953928) (xy 420.766602 -18.908051) (xy 420.802312 -18.866837) (xy 420.843523 -18.831124)
			(xy 420.889396 -18.801639) (xy 420.938999 -18.778982) (xy 420.991321 -18.763614) (xy 421.045298 -18.755849)
			(xy 421.072564 -18.75536) (xy 421.936164 -18.75536) (xy 421.963438 -18.755777) (xy 422.017432 -18.763536)
			(xy 422.069772 -18.7789) (xy 422.119393 -18.801556) (xy 422.165284 -18.831045) (xy 422.20651 -18.866764)
			(xy 422.242234 -18.907988) (xy 422.271726 -18.953876) (xy 422.294388 -19.003494) (xy 422.309757 -19.055833)
			(xy 422.31752 -19.109826) (xy 422.31752 -19.163656) (xy 426.314515 -19.163656) (xy 426.314515 -19.109144)
			(xy 426.322273 -19.055185) (xy 426.337632 -19.002881) (xy 426.360278 -18.953294) (xy 426.38975 -18.907436)
			(xy 426.42545 -18.866238) (xy 426.466648 -18.830541) (xy 426.512508 -18.80107) (xy 426.562096 -18.778426)
			(xy 426.614401 -18.76307) (xy 426.66836 -18.755314) (xy 426.695616 -18.754852) (xy 427.559216 -18.754852)
			(xy 427.586464 -18.755419) (xy 427.640404 -18.763177) (xy 427.692691 -18.778532) (xy 427.742261 -18.801171)
			(xy 427.788105 -18.830635) (xy 427.829289 -18.866323) (xy 427.864975 -18.907508) (xy 427.894436 -18.953353)
			(xy 427.917074 -19.002924) (xy 427.932427 -19.055212) (xy 427.940182 -19.109152) (xy 427.940182 -19.163648)
			(xy 427.940181 -19.163656) (xy 431.902515 -19.163656) (xy 431.902515 -19.109144) (xy 431.910273 -19.055185)
			(xy 431.925632 -19.002881) (xy 431.948278 -18.953294) (xy 431.97775 -18.907436) (xy 432.01345 -18.866238)
			(xy 432.054648 -18.830541) (xy 432.100508 -18.80107) (xy 432.150096 -18.778426) (xy 432.202401 -18.76307)
			(xy 432.25636 -18.755314) (xy 432.283616 -18.754852) (xy 433.147216 -18.754852) (xy 433.174464 -18.755419)
			(xy 433.228404 -18.763177) (xy 433.280691 -18.778532) (xy 433.330261 -18.801171) (xy 433.376105 -18.830635)
			(xy 433.417289 -18.866323) (xy 433.452975 -18.907508) (xy 433.482436 -18.953353) (xy 433.505074 -19.002924)
			(xy 433.520427 -19.055212) (xy 433.528182 -19.109152) (xy 433.528182 -19.163648) (xy 433.520427 -19.217588)
			(xy 433.505074 -19.269876) (xy 433.482436 -19.319447) (xy 433.452975 -19.365292) (xy 433.417289 -19.406477)
			(xy 433.376105 -19.442165) (xy 433.330261 -19.471629) (xy 433.280691 -19.494268) (xy 433.228404 -19.509623)
			(xy 433.174464 -19.517381) (xy 433.147216 -19.517868) (xy 432.283616 -19.517868) (xy 432.25636 -19.517486)
			(xy 432.202401 -19.50973) (xy 432.150096 -19.494374) (xy 432.100508 -19.47173) (xy 432.054648 -19.442259)
			(xy 432.01345 -19.406562) (xy 431.97775 -19.365364) (xy 431.948278 -19.319506) (xy 431.925632 -19.269919)
			(xy 431.910273 -19.217615) (xy 431.902515 -19.163656) (xy 427.940181 -19.163656) (xy 427.932427 -19.217588)
			(xy 427.917074 -19.269876) (xy 427.894436 -19.319447) (xy 427.864975 -19.365292) (xy 427.829289 -19.406477)
			(xy 427.788105 -19.442165) (xy 427.742261 -19.471629) (xy 427.692691 -19.494268) (xy 427.640404 -19.509623)
			(xy 427.586464 -19.517381) (xy 427.559216 -19.517868) (xy 426.695616 -19.517868) (xy 426.66836 -19.517486)
			(xy 426.614401 -19.50973) (xy 426.562096 -19.494374) (xy 426.512508 -19.47173) (xy 426.466648 -19.442259)
			(xy 426.42545 -19.406562) (xy 426.38975 -19.365364) (xy 426.360278 -19.319506) (xy 426.337632 -19.269919)
			(xy 426.322273 -19.217615) (xy 426.314515 -19.163656) (xy 422.31752 -19.163656) (xy 422.31752 -19.164374)
			(xy 422.309757 -19.218367) (xy 422.294388 -19.270706) (xy 422.271726 -19.320324) (xy 422.242234 -19.366212)
			(xy 422.20651 -19.407436) (xy 422.165284 -19.443155) (xy 422.119393 -19.472644) (xy 422.069772 -19.4953)
			(xy 422.017432 -19.510664) (xy 421.963438 -19.518423) (xy 421.936164 -19.518884) (xy 421.072564 -19.518884)
			(xy 421.045298 -19.518351) (xy 420.991321 -19.510586) (xy 420.938999 -19.495218) (xy 420.889396 -19.472561)
			(xy 420.843523 -19.443076) (xy 420.802312 -19.407363) (xy 420.766602 -19.366149) (xy 420.737121 -19.320272)
			(xy 420.714469 -19.270667) (xy 420.699107 -19.218343) (xy 420.691346 -19.164366) (xy 416.730102 -19.164366)
			(xy 416.722448 -19.217598) (xy 416.707093 -19.269892) (xy 416.684451 -19.319468) (xy 416.654984 -19.365317)
			(xy 416.619292 -19.406506) (xy 416.578101 -19.442196) (xy 416.532251 -19.471661) (xy 416.482673 -19.4943)
			(xy 416.430378 -19.509652) (xy 416.376431 -19.517406) (xy 416.34918 -19.517868) (xy 415.48558 -19.517868)
			(xy 415.458327 -19.517461) (xy 415.404376 -19.509701) (xy 415.352078 -19.494343) (xy 415.302498 -19.471698)
			(xy 415.256645 -19.442228) (xy 415.215453 -19.406533) (xy 415.17976 -19.365339) (xy 415.150292 -19.319485)
			(xy 415.12765 -19.269903) (xy 415.112295 -19.217605) (xy 415.104538 -19.163653) (xy 410.836405 -19.163653)
			(xy 410.828648 -19.2176) (xy 410.813291 -19.269895) (xy 410.790649 -19.319473) (xy 410.76118 -19.365323)
			(xy 410.725486 -19.406512) (xy 410.684294 -19.442202) (xy 410.638441 -19.471666) (xy 410.588862 -19.494304)
			(xy 410.536565 -19.509655) (xy 410.482616 -19.517407) (xy 410.455364 -19.517868) (xy 409.591764 -19.517868)
			(xy 409.564512 -19.51746) (xy 409.510562 -19.509698) (xy 409.458266 -19.494338) (xy 409.408688 -19.471693)
			(xy 409.362838 -19.442222) (xy 409.321647 -19.406527) (xy 409.285956 -19.365334) (xy 409.25649 -19.31948)
			(xy 409.233849 -19.2699) (xy 409.218494 -19.217603) (xy 409.210738 -19.163652) (xy 405.248405 -19.163652)
			(xy 405.240648 -19.2176) (xy 405.225291 -19.269895) (xy 405.202649 -19.319473) (xy 405.17318 -19.365323)
			(xy 405.137486 -19.406512) (xy 405.096294 -19.442202) (xy 405.050441 -19.471666) (xy 405.000862 -19.494304)
			(xy 404.948565 -19.509655) (xy 404.894616 -19.517407) (xy 404.867364 -19.517868) (xy 404.003764 -19.517868)
			(xy 403.976512 -19.51746) (xy 403.922562 -19.509698) (xy 403.870266 -19.494338) (xy 403.820688 -19.471693)
			(xy 403.774838 -19.442222) (xy 403.733647 -19.406527) (xy 403.697956 -19.365334) (xy 403.66849 -19.31948)
			(xy 403.645849 -19.2699) (xy 403.630494 -19.217603) (xy 403.622738 -19.163652) (xy 399.660405 -19.163652)
			(xy 399.652648 -19.2176) (xy 399.637291 -19.269895) (xy 399.614649 -19.319473) (xy 399.58518 -19.365323)
			(xy 399.549486 -19.406512) (xy 399.508294 -19.442202) (xy 399.462441 -19.471666) (xy 399.412862 -19.494304)
			(xy 399.360565 -19.509655) (xy 399.306616 -19.517407) (xy 399.279364 -19.517868) (xy 398.415764 -19.517868)
			(xy 398.388512 -19.51746) (xy 398.334562 -19.509698) (xy 398.282266 -19.494338) (xy 398.232688 -19.471693)
			(xy 398.186838 -19.442222) (xy 398.145647 -19.406527) (xy 398.109956 -19.365334) (xy 398.08049 -19.31948)
			(xy 398.057849 -19.2699) (xy 398.042494 -19.217603) (xy 398.034738 -19.163652) (xy 394.071598 -19.163652)
			(xy 394.071598 -19.164369) (xy 394.063837 -19.218351) (xy 394.048473 -19.27068) (xy 394.025819 -19.32029)
			(xy 393.996336 -19.366171) (xy 393.960624 -19.40739) (xy 393.91941 -19.443107) (xy 393.873532 -19.472596)
			(xy 393.823925 -19.495256) (xy 393.771598 -19.510627) (xy 393.717617 -19.518394) (xy 393.690348 -19.518884)
			(xy 392.826748 -19.518884) (xy 392.799476 -19.51838) (xy 392.745487 -19.510624) (xy 392.693152 -19.495262)
			(xy 392.643536 -19.472609) (xy 392.597649 -19.443124) (xy 392.556425 -19.407409) (xy 392.520704 -19.36619)
			(xy 392.491214 -19.320307) (xy 392.468554 -19.270693) (xy 392.453187 -19.21836) (xy 392.445424 -19.164372)
			(xy 259.309108 -19.164372) (xy 259.309108 -20.4061) (xy 368.50594 -20.4061) (xy 368.510005 -20.315592)
			(xy 368.522167 -20.225813) (xy 368.542328 -20.137486) (xy 368.570325 -20.051322) (xy 368.605934 -19.968014)
			(xy 368.648867 -19.888233) (xy 368.698779 -19.812623) (xy 368.755267 -19.741791) (xy 368.817878 -19.676308)
			(xy 368.886107 -19.616701) (xy 368.959405 -19.56345) (xy 369.037181 -19.516984) (xy 369.118809 -19.477677)
			(xy 369.203632 -19.445846) (xy 369.290966 -19.421746) (xy 369.38011 -19.405573) (xy 369.470345 -19.397455)
			(xy 369.515644 -19.396964) (xy 369.560233 -19.397442) (xy 369.649072 -19.405219) (xy 369.736895 -19.420711)
			(xy 369.823033 -19.443798) (xy 369.906831 -19.474305) (xy 369.987651 -19.512001) (xy 370.064878 -19.556597)
			(xy 370.137923 -19.607756) (xy 370.206232 -19.665086) (xy 370.269283 -19.728153) (xy 370.326597 -19.796475)
			(xy 370.377737 -19.869533) (xy 370.422315 -19.946771) (xy 370.459991 -20.0276) (xy 370.490478 -20.111405)
			(xy 370.513544 -20.197549) (xy 370.529013 -20.285376) (xy 370.536768 -20.374217) (xy 370.537232 -20.418806)
			(xy 370.536774 -20.462284) (xy 370.529196 -20.54891) (xy 370.514098 -20.634545) (xy 370.491595 -20.71854)
			(xy 370.485037 -20.73656) (xy 440.464956 -20.73656) (xy 440.465378 -20.698271) (xy 440.471981 -20.621977)
			(xy 440.485126 -20.546534) (xy 440.504715 -20.472503) (xy 440.51728 -20.436332) (xy 440.51995 -20.4279)
			(xy 440.519937 -20.410225) (xy 440.51728 -20.401788) (xy 440.50475 -20.365606) (xy 440.485173 -20.291575)
			(xy 440.472022 -20.216136) (xy 440.465394 -20.139848) (xy 440.464956 -20.10156) (xy 440.46549 -20.057765)
			(xy 440.474106 -19.9706) (xy 440.49125 -19.884704) (xy 440.516756 -19.80091) (xy 440.550377 -19.72003)
			(xy 440.57062 -19.68119) (xy 440.576064 -19.669733) (xy 440.576046 -19.644397) (xy 440.57062 -19.63293)
			(xy 440.550398 -19.594081) (xy 440.51679 -19.513198) (xy 440.491286 -19.429406) (xy 440.474133 -19.343514)
			(xy 440.465497 -19.256354) (xy 440.464956 -19.21256) (xy 440.465378 -19.174271) (xy 440.471981 -19.097977)
			(xy 440.485126 -19.022534) (xy 440.504715 -18.948503) (xy 440.51728 -18.912332) (xy 440.51995 -18.9039)
			(xy 440.519937 -18.886225) (xy 440.51728 -18.877788) (xy 440.50475 -18.841606) (xy 440.485173 -18.767575)
			(xy 440.472022 -18.692136) (xy 440.465394 -18.615848) (xy 440.464956 -18.57756) (xy 440.465414 -18.53645)
			(xy 440.473005 -18.45458) (xy 440.488119 -18.373761) (xy 440.510626 -18.294681) (xy 440.540334 -18.218015)
			(xy 440.576991 -18.144418) (xy 440.620282 -18.074518) (xy 440.66984 -18.008911) (xy 440.72524 -17.948157)
			(xy 440.78601 -17.892775) (xy 440.851631 -17.843237) (xy 440.921544 -17.799965) (xy 440.995152 -17.76333)
			(xy 441.071826 -17.733644) (xy 441.150912 -17.71116) (xy 441.231736 -17.69607) (xy 441.313608 -17.688502)
			(xy 441.354718 -17.688052) (xy 441.395668 -17.688478) (xy 441.477223 -17.695989) (xy 441.557742 -17.710965)
			(xy 441.636544 -17.733279) (xy 441.712961 -17.762742) (xy 441.786347 -17.799105) (xy 441.856079 -17.842059)
			(xy 441.921567 -17.891241) (xy 441.982258 -17.946234) (xy 442.010292 -17.976088) (xy 442.017449 -17.983101)
			(xy 442.035585 -17.991562) (xy 442.055576 -17.99248) (xy 442.065156 -17.98955) (xy 442.102033 -17.976445)
			(xy 442.177582 -17.955997) (xy 442.254637 -17.94227) (xy 442.3326 -17.935373) (xy 442.371734 -17.93494)
			(xy 442.412849 -17.93538) (xy 442.494727 -17.942971) (xy 442.575557 -17.958083) (xy 442.654646 -17.980589)
			(xy 442.731323 -18.010296) (xy 442.804931 -18.046951) (xy 442.874843 -18.090241) (xy 442.940462 -18.139797)
			(xy 443.001229 -18.195196) (xy 443.056626 -18.255966) (xy 443.106179 -18.321587) (xy 443.149467 -18.391501)
			(xy 443.186119 -18.46511) (xy 443.213248 -18.535142) (xy 451.165468 -18.535142) (xy 451.165468 -18.534888)
			(xy 451.166052 -18.49015) (xy 451.175063 -18.401129) (xy 451.192964 -18.313462) (xy 451.219572 -18.228034)
			(xy 451.236588 -18.186654) (xy 451.240131 -18.177057) (xy 451.240147 -18.15662) (xy 451.236588 -18.14703)
			(xy 451.219555 -18.105656) (xy 451.192939 -18.020228) (xy 451.175038 -17.932559) (xy 451.166032 -17.843535)
			(xy 451.165468 -17.798796) (xy 451.165468 -17.798542) (xy 451.165972 -17.756194) (xy 451.174023 -17.67188)
			(xy 451.190052 -17.588714) (xy 451.213913 -17.507447) (xy 451.245392 -17.428817) (xy 451.284203 -17.353536)
			(xy 451.329993 -17.282284) (xy 451.382349 -17.215708) (xy 451.440797 -17.15441) (xy 451.504807 -17.098945)
			(xy 451.573799 -17.049816) (xy 451.647149 -17.007467) (xy 451.724192 -16.972283) (xy 451.804231 -16.944581)
			(xy 451.88654 -16.924613) (xy 451.970375 -16.91256) (xy 452.054976 -16.90853) (xy 452.139577 -16.91256)
			(xy 452.223412 -16.924613) (xy 452.305721 -16.944581) (xy 452.38576 -16.972283) (xy 452.462803 -17.007467)
			(xy 452.536153 -17.049816) (xy 452.605145 -17.098945) (xy 452.669155 -17.15441) (xy 452.727603 -17.215708)
			(xy 452.779959 -17.282284) (xy 452.825749 -17.353536) (xy 452.86456 -17.428817) (xy 452.896039 -17.507447)
			(xy 452.9199 -17.588714) (xy 452.935929 -17.67188) (xy 452.94398 -17.756194) (xy 452.944484 -17.798542)
			(xy 452.944484 -17.798796) (xy 452.943898 -17.843534) (xy 452.934888 -17.932555) (xy 452.916988 -18.020222)
			(xy 452.890379 -18.10565) (xy 452.873364 -18.14703) (xy 452.869775 -18.156614) (xy 452.869791 -18.177063)
			(xy 452.873364 -18.186654) (xy 452.890389 -18.228031) (xy 452.917007 -18.313458) (xy 452.934911 -18.401126)
			(xy 452.943919 -18.490149) (xy 452.944484 -18.534888) (xy 452.944484 -18.535142) (xy 452.94398 -18.57749)
			(xy 452.935929 -18.661804) (xy 452.9199 -18.74497) (xy 452.896039 -18.826237) (xy 452.86456 -18.904867)
			(xy 452.825749 -18.980148) (xy 452.779959 -19.0514) (xy 452.727603 -19.117976) (xy 452.669155 -19.179274)
			(xy 452.605145 -19.234739) (xy 452.536153 -19.283868) (xy 452.462803 -19.326217) (xy 452.38576 -19.361401)
			(xy 452.305721 -19.389103) (xy 452.223412 -19.409071) (xy 452.139577 -19.421124) (xy 452.054976 -19.425155)
			(xy 451.970375 -19.421124) (xy 451.88654 -19.409071) (xy 451.804231 -19.389103) (xy 451.724192 -19.361401)
			(xy 451.647149 -19.326217) (xy 451.573799 -19.283868) (xy 451.504807 -19.234739) (xy 451.440797 -19.179274)
			(xy 451.382349 -19.117976) (xy 451.329993 -19.0514) (xy 451.284203 -18.980148) (xy 451.245392 -18.904867)
			(xy 451.213913 -18.826237) (xy 451.190052 -18.74497) (xy 451.174023 -18.661804) (xy 451.165972 -18.57749)
			(xy 451.165468 -18.535142) (xy 443.213248 -18.535142) (xy 443.215823 -18.541788) (xy 443.238325 -18.620878)
			(xy 443.253434 -18.701708) (xy 443.261021 -18.783587) (xy 443.261496 -18.824702) (xy 443.261095 -18.862992)
			(xy 443.254486 -18.939286) (xy 443.241336 -19.014729) (xy 443.221741 -19.088759) (xy 443.209172 -19.12493)
			(xy 443.206519 -19.133366) (xy 443.20652 -19.151037) (xy 443.209172 -19.159474) (xy 443.221718 -19.195651)
			(xy 443.24129 -19.269684) (xy 443.254437 -19.345124) (xy 443.261061 -19.421414) (xy 443.261496 -19.459702)
			(xy 443.260982 -19.503497) (xy 443.252361 -19.590663) (xy 443.235212 -19.676559) (xy 443.209701 -19.760353)
			(xy 443.176076 -19.841233) (xy 443.155832 -19.880072) (xy 443.15041 -19.891537) (xy 443.150411 -19.916866)
			(xy 443.155832 -19.928332) (xy 443.176073 -19.967172) (xy 443.209679 -20.048057) (xy 443.235179 -20.131851)
			(xy 443.252328 -20.217745) (xy 443.260958 -20.304908) (xy 443.261496 -20.348702) (xy 443.261095 -20.386992)
			(xy 443.254486 -20.463286) (xy 443.241336 -20.538729) (xy 443.221741 -20.612759) (xy 443.209172 -20.64893)
			(xy 443.206519 -20.657366) (xy 443.20652 -20.675037) (xy 443.209172 -20.683474) (xy 443.221718 -20.719651)
			(xy 443.24129 -20.793684) (xy 443.254437 -20.869124) (xy 443.261061 -20.945414) (xy 443.261496 -20.983702)
			(xy 443.260989 -21.024815) (xy 443.253402 -21.106691) (xy 443.238293 -21.187518) (xy 443.215791 -21.266605)
			(xy 443.186088 -21.343279) (xy 443.149437 -21.416886) (xy 443.106152 -21.486797) (xy 443.0566 -21.552416)
			(xy 443.001205 -21.613183) (xy 442.94044 -21.66858) (xy 442.874823 -21.718133) (xy 442.804914 -21.761422)
			(xy 442.731309 -21.798075) (xy 442.654636 -21.827781) (xy 442.575549 -21.850286) (xy 442.494723 -21.865398)
			(xy 442.412847 -21.872988) (xy 442.371734 -21.873464) (xy 442.330778 -21.872996) (xy 442.249213 -21.865468)
			(xy 442.168686 -21.850472) (xy 442.089879 -21.828136) (xy 442.013459 -21.798648) (xy 441.940074 -21.762259)
			(xy 441.870346 -21.719277) (xy 441.804865 -21.670066) (xy 441.744186 -21.615042) (xy 441.71616 -21.585174)
			(xy 441.709037 -21.578124) (xy 441.690882 -21.569676) (xy 441.670879 -21.568774) (xy 441.661296 -21.571712)
			(xy 441.624502 -21.584749) (xy 441.549137 -21.605106) (xy 441.472276 -21.618771) (xy 441.394513 -21.625637)
			(xy 441.35548 -21.626068) (xy 441.354718 -21.626068) (xy 441.313612 -21.62557) (xy 441.23175 -21.617988)
			(xy 441.150936 -21.602885) (xy 441.07186 -21.580392) (xy 440.995197 -21.5507) (xy 440.9216 -21.514062)
			(xy 440.851696 -21.470791) (xy 440.786082 -21.421255) (xy 440.725318 -21.365878) (xy 440.669922 -21.305132)
			(xy 440.620366 -21.239533) (xy 440.577073 -21.169643) (xy 440.540412 -21.096058) (xy 440.510696 -21.019403)
			(xy 440.488178 -20.940335) (xy 440.473051 -20.859526) (xy 440.465443 -20.777666) (xy 440.464956 -20.73656)
			(xy 370.485037 -20.73656) (xy 370.461858 -20.800254) (xy 370.425114 -20.879065) (xy 370.381641 -20.954375)
			(xy 370.331772 -21.02561) (xy 370.275884 -21.092228) (xy 370.214404 -21.153723) (xy 370.147799 -21.209627)
			(xy 370.076576 -21.259513) (xy 370.001276 -21.303004) (xy 369.922473 -21.339767) (xy 369.840767 -21.369523)
			(xy 369.756778 -21.392046) (xy 369.671146 -21.407165) (xy 369.584522 -21.414763) (xy 369.541044 -21.415248)
			(xy 369.515644 -21.415248) (xy 369.470345 -21.414745) (xy 369.38011 -21.406627) (xy 369.290966 -21.390454)
			(xy 369.203632 -21.366354) (xy 369.118809 -21.334523) (xy 369.037181 -21.295216) (xy 368.959405 -21.24875)
			(xy 368.886107 -21.195499) (xy 368.817878 -21.135892) (xy 368.755267 -21.070409) (xy 368.698779 -20.999577)
			(xy 368.648867 -20.923967) (xy 368.605934 -20.844186) (xy 368.570325 -20.760878) (xy 368.542328 -20.674714)
			(xy 368.522167 -20.586387) (xy 368.510005 -20.496608) (xy 368.50594 -20.4061) (xy 259.309108 -20.4061)
			(xy 259.309108 -25.982422) (xy 440.239912 -25.982422) (xy 440.240419 -25.939461) (xy 440.248702 -25.85394)
			(xy 440.265193 -25.769616) (xy 440.289738 -25.687275) (xy 440.322109 -25.607684) (xy 440.362003 -25.531586)
			(xy 440.40905 -25.459689) (xy 440.46281 -25.392664) (xy 440.522782 -25.331135) (xy 440.588408 -25.275676)
			(xy 440.659076 -25.226803) (xy 440.69635 -25.205436) (xy 440.704332 -25.200469) (xy 440.716316 -25.186006)
			(xy 440.719718 -25.177242) (xy 440.733823 -25.137039) (xy 440.768699 -25.059297) (xy 440.810847 -24.985247)
			(xy 440.859883 -24.915565) (xy 440.915357 -24.850891) (xy 440.97676 -24.791817) (xy 441.043529 -24.738885)
			(xy 441.115054 -24.692579) (xy 441.190679 -24.653323) (xy 441.26971 -24.621478) (xy 441.351424 -24.597336)
			(xy 441.435072 -24.581116) (xy 441.519887 -24.572969) (xy 441.56249 -24.572468) (xy 441.562998 -24.572468)
			(xy 441.606762 -24.572982) (xy 441.693869 -24.581557) (xy 441.77971 -24.598653) (xy 441.863455 -24.624106)
			(xy 441.944293 -24.657667) (xy 441.983114 -24.677878) (xy 441.994467 -24.683205) (xy 442.019513 -24.683205)
			(xy 442.030866 -24.677878) (xy 442.069745 -24.657673) (xy 442.150684 -24.6241) (xy 442.23453 -24.598641)
			(xy 442.320472 -24.581544) (xy 442.407677 -24.572973) (xy 442.45149 -24.572468) (xy 442.495305 -24.572971)
			(xy 442.582516 -24.581515) (xy 442.668462 -24.5986) (xy 442.752311 -24.62406) (xy 442.833246 -24.657648)
			(xy 442.872114 -24.677878) (xy 442.883467 -24.683205) (xy 442.908513 -24.683205) (xy 442.919866 -24.677878)
			(xy 442.959061 -24.657499) (xy 443.040701 -24.623735) (xy 443.125286 -24.598229) (xy 443.211982 -24.581233)
			(xy 443.255908 -24.576532) (xy 443.266358 -24.575008) (xy 443.284755 -24.564681) (xy 443.297434 -24.547819)
			(xy 443.300358 -24.53767) (xy 443.310609 -24.496358) (xy 443.337964 -24.415751) (xy 443.372893 -24.338124)
			(xy 443.415077 -24.264189) (xy 443.464129 -24.19462) (xy 443.519603 -24.130055) (xy 443.580989 -24.071084)
			(xy 443.647727 -24.018245) (xy 443.719207 -23.972023) (xy 443.794775 -23.932839) (xy 443.87374 -23.901052)
			(xy 443.955381 -23.876952) (xy 444.038949 -23.86076) (xy 444.123683 -23.852625) (xy 444.166244 -23.852124)
			(xy 444.207348 -23.852525) (xy 444.289205 -23.860114) (xy 444.370013 -23.875224) (xy 444.449082 -23.897725)
			(xy 444.525738 -23.927425) (xy 444.599326 -23.964072) (xy 444.669219 -24.007352) (xy 444.734821 -24.056897)
			(xy 444.795571 -24.112283) (xy 444.850952 -24.173038) (xy 444.900491 -24.238644) (xy 444.943765 -24.30854)
			(xy 444.980405 -24.382132) (xy 445.0101 -24.45879) (xy 445.032594 -24.537861) (xy 445.047697 -24.61867)
			(xy 445.055279 -24.700528) (xy 445.055752 -24.741632) (xy 445.055238 -24.782654) (xy 445.04768 -24.864348)
			(xy 445.032631 -24.944999) (xy 445.01022 -25.023921) (xy 444.980635 -25.100445) (xy 444.94413 -25.173919)
			(xy 444.901014 -25.243719) (xy 444.851653 -25.309252) (xy 444.796467 -25.369961) (xy 444.735925 -25.425331)
			(xy 444.670542 -25.47489) (xy 444.600873 -25.518217) (xy 444.52751 -25.554945) (xy 444.451076 -25.584761)
			(xy 444.372222 -25.607412) (xy 444.291617 -25.622705) (xy 444.250826 -25.627076) (xy 444.240379 -25.628618)
			(xy 444.221981 -25.638935) (xy 444.2093 -25.655791) (xy 444.206376 -25.665938) (xy 444.196473 -25.705794)
			(xy 444.170375 -25.783666) (xy 444.137208 -25.8588) (xy 444.097254 -25.930555) (xy 444.050854 -25.998321)
			(xy 443.998403 -26.061519) (xy 443.940348 -26.119612) (xy 443.877184 -26.172104) (xy 443.809448 -26.218548)
			(xy 443.773814 -26.238962) (xy 443.765845 -26.243946) (xy 443.753852 -26.258396) (xy 443.750446 -26.267156)
			(xy 443.736369 -26.307378) (xy 443.701515 -26.385148) (xy 443.659384 -26.459228) (xy 443.61036 -26.528939)
			(xy 443.554893 -26.593641) (xy 443.493492 -26.652741) (xy 443.42672 -26.705698) (xy 443.355189 -26.752025)
			(xy 443.279554 -26.791298) (xy 443.200511 -26.823158) (xy 443.118782 -26.847311) (xy 443.035118 -26.863536)
			(xy 442.950285 -26.871685) (xy 442.907674 -26.872184) (xy 442.863879 -26.871639) (xy 442.776715 -26.863025)
			(xy 442.690819 -26.845883) (xy 442.607025 -26.82038) (xy 442.526144 -26.786761) (xy 442.487304 -26.76652)
			(xy 442.475838 -26.761102) (xy 442.45051 -26.761102) (xy 442.439044 -26.76652) (xy 442.400209 -26.786769)
			(xy 442.319322 -26.820374) (xy 442.235526 -26.845873) (xy 442.149632 -26.863019) (xy 442.062468 -26.871647)
			(xy 442.018674 -26.872184) (xy 441.974879 -26.871639) (xy 441.887715 -26.863025) (xy 441.801819 -26.845883)
			(xy 441.718025 -26.82038) (xy 441.637144 -26.786761) (xy 441.598304 -26.76652) (xy 441.586838 -26.761102)
			(xy 441.56151 -26.761102) (xy 441.550044 -26.76652) (xy 441.511209 -26.786769) (xy 441.430322 -26.820374)
			(xy 441.346526 -26.845873) (xy 441.260632 -26.863019) (xy 441.173468 -26.871647) (xy 441.129674 -26.872184)
			(xy 441.08856 -26.871712) (xy 441.006683 -26.864123) (xy 440.925855 -26.849012) (xy 440.846767 -26.826507)
			(xy 440.770092 -26.796802) (xy 440.696485 -26.760149) (xy 440.626574 -26.71686) (xy 440.560955 -26.667306)
			(xy 440.500188 -26.61191) (xy 440.444791 -26.551142) (xy 440.395237 -26.485523) (xy 440.351949 -26.415612)
			(xy 440.315297 -26.342004) (xy 440.285592 -26.265329) (xy 440.263088 -26.186241) (xy 440.247977 -26.105413)
			(xy 440.240388 -26.023536) (xy 440.239912 -25.982422) (xy 259.309108 -25.982422) (xy 259.309108 -32.117846)
			(xy 455.218281 -32.117846) (xy 455.218281 -31.988706) (xy 455.226231 -31.859811) (xy 455.242101 -31.731651)
			(xy 455.26583 -31.60471) (xy 455.297329 -31.479471) (xy 455.336478 -31.356408) (xy 455.383129 -31.235989)
			(xy 455.437104 -31.11867) (xy 455.498199 -31.004896) (xy 455.566182 -30.895099) (xy 455.640796 -30.789696)
			(xy 455.721757 -30.689086) (xy 455.808757 -30.593651) (xy 455.901468 -30.503752) (xy 455.999538 -30.419731)
			(xy 456.102593 -30.341907) (xy 456.210244 -30.270575) (xy 456.322083 -30.206005) (xy 456.437684 -30.148443)
			(xy 456.556609 -30.098106) (xy 456.678408 -30.055186) (xy 456.802618 -30.019845) (xy 456.928767 -29.992218)
			(xy 457.056379 -29.972409) (xy 457.184968 -29.960493) (xy 457.314046 -29.956517) (xy 457.443124 -29.960493)
			(xy 457.571713 -29.972409) (xy 457.699325 -29.992218) (xy 457.825474 -30.019845) (xy 457.949684 -30.055186)
			(xy 458.071483 -30.098106) (xy 458.190408 -30.148443) (xy 458.306009 -30.206005) (xy 458.417848 -30.270575)
			(xy 458.525499 -30.341907) (xy 458.628554 -30.419731) (xy 458.726624 -30.503752) (xy 458.819335 -30.593651)
			(xy 458.906335 -30.689086) (xy 458.987296 -30.789696) (xy 459.06191 -30.895099) (xy 459.129893 -31.004896)
			(xy 459.190988 -31.11867) (xy 459.244963 -31.235989) (xy 459.291614 -31.356408) (xy 459.330763 -31.479471)
			(xy 459.362262 -31.60471) (xy 459.385991 -31.731651) (xy 459.401861 -31.859811) (xy 459.409811 -31.988706)
			(xy 459.410308 -32.053276) (xy 459.409811 -32.117846) (xy 459.401861 -32.246741) (xy 459.385991 -32.374901)
			(xy 459.362262 -32.501842) (xy 459.330763 -32.627081) (xy 459.291614 -32.750144) (xy 459.244963 -32.870563)
			(xy 459.190988 -32.987882) (xy 459.129893 -33.101656) (xy 459.06191 -33.211453) (xy 458.987296 -33.316856)
			(xy 458.906335 -33.417466) (xy 458.819335 -33.512901) (xy 458.726624 -33.6028) (xy 458.628554 -33.686821)
			(xy 458.525499 -33.764645) (xy 458.417848 -33.835977) (xy 458.307206 -33.899856) (xy 461.798924 -33.899856)
			(xy 461.798924 -32.299656) (xy 461.799422 -32.222373) (xy 461.807378 -32.068013) (xy 461.823271 -31.914267)
			(xy 461.847057 -31.761543) (xy 461.878674 -31.610247) (xy 461.918037 -31.460778) (xy 461.965042 -31.313534)
			(xy 462.019566 -31.168904) (xy 462.081462 -31.027274) (xy 462.150567 -30.889017) (xy 462.226698 -30.754502)
			(xy 462.309652 -30.624083) (xy 462.399211 -30.498108) (xy 462.495135 -30.376911) (xy 462.597172 -30.260812)
			(xy 462.705049 -30.15012) (xy 462.818482 -30.045128) (xy 462.93717 -29.946115) (xy 463.060797 -29.853342)
			(xy 463.189036 -29.767057) (xy 463.321547 -29.687488) (xy 463.457979 -29.614846) (xy 463.597969 -29.549324)
			(xy 463.741146 -29.491095) (xy 463.887131 -29.440314) (xy 464.035537 -29.397115) (xy 464.185969 -29.361613)
			(xy 464.33803 -29.333903) (xy 464.491316 -29.314057) (xy 464.64542 -29.302128) (xy 464.799934 -29.298149)
			(xy 464.954448 -29.302128) (xy 465.108552 -29.314057) (xy 465.261838 -29.333903) (xy 465.413899 -29.361613)
			(xy 465.564331 -29.397115) (xy 465.712737 -29.440314) (xy 465.858722 -29.491095) (xy 466.001899 -29.549324)
			(xy 466.141889 -29.614846) (xy 466.278321 -29.687488) (xy 466.410832 -29.767057) (xy 466.539071 -29.853342)
			(xy 466.662698 -29.946115) (xy 466.781386 -30.045128) (xy 466.894819 -30.15012) (xy 467.002696 -30.260812)
			(xy 467.104733 -30.376911) (xy 467.200657 -30.498108) (xy 467.290216 -30.624083) (xy 467.37317 -30.754502)
			(xy 467.449301 -30.889017) (xy 467.518406 -31.027274) (xy 467.580302 -31.168904) (xy 467.634826 -31.313534)
			(xy 467.681831 -31.460778) (xy 467.721194 -31.610247) (xy 467.752811 -31.761543) (xy 467.776597 -31.914267)
			(xy 467.79249 -32.068013) (xy 467.800446 -32.222373) (xy 467.800944 -32.299656) (xy 467.800944 -33.899856)
			(xy 467.800446 -33.977139) (xy 467.79249 -34.131499) (xy 467.776597 -34.285245) (xy 467.752811 -34.437969)
			(xy 467.721194 -34.589265) (xy 467.681831 -34.738734) (xy 467.634826 -34.885978) (xy 467.580302 -35.030608)
			(xy 467.518406 -35.172238) (xy 467.449301 -35.310495) (xy 467.37317 -35.44501) (xy 467.290216 -35.575429)
			(xy 467.200657 -35.701404) (xy 467.104733 -35.822601) (xy 467.002696 -35.9387) (xy 466.894819 -36.049392)
			(xy 466.781386 -36.154384) (xy 466.662698 -36.253397) (xy 466.539071 -36.34617) (xy 466.410832 -36.432455)
			(xy 466.278321 -36.512024) (xy 466.141889 -36.584666) (xy 466.001899 -36.650188) (xy 465.858722 -36.708417)
			(xy 465.712737 -36.759198) (xy 465.564331 -36.802397) (xy 465.413899 -36.837899) (xy 465.261838 -36.865609)
			(xy 465.108552 -36.885455) (xy 464.954448 -36.897384) (xy 464.799934 -36.901364) (xy 464.64542 -36.897384)
			(xy 464.491316 -36.885455) (xy 464.33803 -36.865609) (xy 464.185969 -36.837899) (xy 464.035537 -36.802397)
			(xy 463.887131 -36.759198) (xy 463.741146 -36.708417) (xy 463.597969 -36.650188) (xy 463.457979 -36.584666)
			(xy 463.321547 -36.512024) (xy 463.189036 -36.432455) (xy 463.060797 -36.34617) (xy 462.93717 -36.253397)
			(xy 462.818482 -36.154384) (xy 462.705049 -36.049392) (xy 462.597172 -35.9387) (xy 462.495135 -35.822601)
			(xy 462.399211 -35.701404) (xy 462.309652 -35.575429) (xy 462.226698 -35.44501) (xy 462.150567 -35.310495)
			(xy 462.081462 -35.172238) (xy 462.019566 -35.030608) (xy 461.965042 -34.885978) (xy 461.918037 -34.738734)
			(xy 461.878674 -34.589265) (xy 461.847057 -34.437969) (xy 461.823271 -34.285245) (xy 461.807378 -34.131499)
			(xy 461.799422 -33.977139) (xy 461.798924 -33.899856) (xy 458.307206 -33.899856) (xy 458.306009 -33.900547)
			(xy 458.190408 -33.958109) (xy 458.071483 -34.008446) (xy 457.949684 -34.051366) (xy 457.825474 -34.086707)
			(xy 457.699325 -34.114334) (xy 457.571713 -34.134143) (xy 457.443124 -34.146059) (xy 457.314046 -34.150036)
			(xy 457.184968 -34.146059) (xy 457.056379 -34.134143) (xy 456.928767 -34.114334) (xy 456.802618 -34.086707)
			(xy 456.678408 -34.051366) (xy 456.556609 -34.008446) (xy 456.437684 -33.958109) (xy 456.322083 -33.900547)
			(xy 456.210244 -33.835977) (xy 456.102593 -33.764645) (xy 455.999538 -33.686821) (xy 455.901468 -33.6028)
			(xy 455.808757 -33.512901) (xy 455.721757 -33.417466) (xy 455.640796 -33.316856) (xy 455.566182 -33.211453)
			(xy 455.498199 -33.101656) (xy 455.437104 -32.987882) (xy 455.383129 -32.870563) (xy 455.336478 -32.750144)
			(xy 455.297329 -32.627081) (xy 455.26583 -32.501842) (xy 455.242101 -32.374901) (xy 455.226231 -32.246741)
			(xy 455.218281 -32.117846) (xy 259.309108 -32.117846) (xy 259.309108 -34.120074) (xy 259.308624 -34.190457)
			(xy 259.300733 -34.331001) (xy 259.284973 -34.470882) (xy 259.261395 -34.609659) (xy 259.230073 -34.746896)
			(xy 259.191105 -34.882161) (xy 259.144614 -35.015028) (xy 259.090747 -35.145079) (xy 259.029671 -35.271905)
			(xy 258.961581 -35.395107) (xy 258.88669 -35.514297) (xy 258.805233 -35.629101) (xy 258.717468 -35.739156)
			(xy 258.62367 -35.844118) (xy 258.524134 -35.943655) (xy 258.419173 -36.037454) (xy 258.309118 -36.12522)
			(xy 258.194315 -36.206678) (xy 258.075126 -36.28157) (xy 257.951924 -36.349661) (xy 257.825099 -36.410738)
			(xy 257.695048 -36.464606) (xy 257.562182 -36.511099) (xy 257.426917 -36.550068) (xy 257.289681 -36.581391)
			(xy 257.150904 -36.60497) (xy 257.011023 -36.620731) (xy 256.870479 -36.628623) (xy 256.800096 -36.629086)
			(xy 225.300032 -36.629086) (xy 225.229649 -36.628602) (xy 225.089105 -36.620711) (xy 224.949224 -36.604952)
			(xy 224.810447 -36.581374) (xy 224.673211 -36.550052) (xy 224.537946 -36.511084) (xy 224.40508 -36.464594)
			(xy 224.275029 -36.410726) (xy 224.148203 -36.349651) (xy 224.025001 -36.28156) (xy 223.905811 -36.206669)
			(xy 223.791008 -36.125213) (xy 223.680953 -36.037447) (xy 223.575992 -35.943648) (xy 223.476456 -35.844112)
			(xy 223.382657 -35.739152) (xy 223.294891 -35.629097) (xy 223.213434 -35.514294) (xy 223.138543 -35.395104)
			(xy 223.070452 -35.271902) (xy 223.009377 -35.145077) (xy 222.955509 -35.015026) (xy 222.909017 -34.882159)
			(xy 222.870049 -34.746895) (xy 222.838727 -34.609659) (xy 222.815149 -34.470882) (xy 222.799389 -34.331001)
			(xy 222.791498 -34.190457) (xy 222.79102 -34.120074) (xy 222.79102 -13.780008) (xy 222.790499 -13.724238)
			(xy 222.782164 -13.613011) (xy 222.765541 -13.502717) (xy 222.740722 -13.393974) (xy 222.707846 -13.287389)
			(xy 222.667097 -13.183559) (xy 222.618703 -13.083065) (xy 222.562935 -12.986469) (xy 222.500103 -12.894309)
			(xy 222.430561 -12.807103) (xy 222.354696 -12.725338) (xy 222.272933 -12.64947) (xy 222.185729 -12.579925)
			(xy 222.093572 -12.517091) (xy 221.996977 -12.461319) (xy 221.896485 -12.412922) (xy 221.792656 -12.37217)
			(xy 221.686073 -12.339291) (xy 221.57733 -12.314468) (xy 221.467037 -12.297841) (xy 221.35581 -12.289503)
			(xy 221.30004 -12.289028) (xy 196.701918 -12.289028) (xy 196.631535 -12.288544) (xy 196.49099 -12.280652)
			(xy 196.35111 -12.264892) (xy 196.212332 -12.241314) (xy 196.075095 -12.209992) (xy 195.939831 -12.171024)
			(xy 195.806964 -12.124532) (xy 195.676913 -12.070665) (xy 195.550086 -12.009589) (xy 195.426884 -11.941499)
			(xy 195.307694 -11.866608) (xy 195.19289 -11.785152) (xy 195.082834 -11.697386) (xy 194.977873 -11.603588)
			(xy 194.878335 -11.504052) (xy 194.784536 -11.399092) (xy 194.696769 -11.289037) (xy 194.615311 -11.174234)
			(xy 194.540418 -11.055045) (xy 194.472326 -10.931844) (xy 194.411249 -10.805018) (xy 194.35738 -10.674968)
			(xy 194.310887 -10.542102) (xy 194.271917 -10.406837) (xy 194.240593 -10.269601) (xy 194.217013 -10.130824)
			(xy 194.201251 -9.990943) (xy 194.193357 -9.850399) (xy 194.192906 -9.780016) (xy 194.192906 -5.839714)
			(xy 194.192489 -5.82969) (xy 194.184822 -5.811168) (xy 194.170649 -5.79699) (xy 194.152129 -5.789315)
			(xy 194.142106 -5.788914) (xy 126.661926 -5.788914) (xy 126.651902 -5.789329) (xy 126.633379 -5.796995)
			(xy 126.619202 -5.811169) (xy 126.611531 -5.82969) (xy 126.611126 -5.839714) (xy 126.611126 -9.780016)
			(xy 126.610632 -9.850398) (xy 126.602738 -9.990941) (xy 126.586977 -10.13082) (xy 126.563397 -10.269595)
			(xy 126.532074 -10.40683) (xy 126.51969 -10.449814) (xy 127.34824 -10.449814) (xy 127.352254 -10.361721)
			(xy 127.364261 -10.274358) (xy 127.384164 -10.188448) (xy 127.411796 -10.104705) (xy 127.446929 -10.023821)
			(xy 127.489271 -9.946467) (xy 127.538472 -9.873284) (xy 127.594125 -9.804878) (xy 127.655767 -9.741817)
			(xy 127.722888 -9.684622) (xy 127.794932 -9.633767) (xy 127.871302 -9.589675) (xy 127.951365 -9.55271)
			(xy 128.034458 -9.523179) (xy 128.119892 -9.501326) (xy 128.206959 -9.487333) (xy 128.294938 -9.481315)
			(xy 128.3831 -9.483322) (xy 128.470714 -9.493338) (xy 128.557054 -9.51128) (xy 128.641405 -9.536999)
			(xy 128.723067 -9.570281) (xy 128.801365 -9.610852) (xy 128.875649 -9.658374) (xy 128.945304 -9.712455)
			(xy 129.009752 -9.772646) (xy 129.06846 -9.838448) (xy 129.120941 -9.909315) (xy 129.166761 -9.984662)
			(xy 129.205538 -10.063863) (xy 129.236953 -10.146262) (xy 129.260745 -10.231176) (xy 129.267997 -10.270552)
			(xy 131.639267 -10.270552) (xy 131.639267 -10.216048) (xy 131.647024 -10.162097) (xy 131.66238 -10.1098)
			(xy 131.685023 -10.060221) (xy 131.714491 -10.014369) (xy 131.750185 -9.973177) (xy 131.791377 -9.937485)
			(xy 131.83723 -9.908018) (xy 131.88681 -9.885377) (xy 131.939107 -9.870022) (xy 131.993058 -9.862267)
			(xy 132.02031 -9.861804) (xy 132.88391 -9.861804) (xy 132.911162 -9.862266) (xy 132.96511 -9.870024)
			(xy 133.017405 -9.885381) (xy 133.066983 -9.908023) (xy 133.112833 -9.937491) (xy 133.154024 -9.973183)
			(xy 133.189715 -10.014375) (xy 133.219181 -10.060226) (xy 133.241823 -10.109804) (xy 133.257178 -10.1621)
			(xy 133.264934 -10.216048) (xy 133.264934 -10.270552) (xy 133.257178 -10.3245) (xy 133.241823 -10.376796)
			(xy 133.219181 -10.426374) (xy 133.189715 -10.472225) (xy 133.154024 -10.513417) (xy 133.112833 -10.549109)
			(xy 133.066983 -10.578577) (xy 133.017405 -10.601219) (xy 132.96511 -10.616576) (xy 132.911162 -10.624334)
			(xy 132.88391 -10.62482) (xy 132.02031 -10.62482) (xy 131.993058 -10.624333) (xy 131.939107 -10.616578)
			(xy 131.88681 -10.601223) (xy 131.83723 -10.578582) (xy 131.791377 -10.549115) (xy 131.750185 -10.513423)
			(xy 131.714491 -10.472231) (xy 131.685023 -10.426379) (xy 131.66238 -10.3768) (xy 131.647024 -10.324503)
			(xy 131.639267 -10.270552) (xy 129.267997 -10.270552) (xy 129.276717 -10.317903) (xy 129.284736 -10.405722)
			(xy 129.285238 -10.449814) (xy 129.284736 -10.493906) (xy 129.276717 -10.581725) (xy 129.260745 -10.668452)
			(xy 129.236953 -10.753366) (xy 129.214158 -10.813156) (xy 169.954611 -10.813156) (xy 169.954611 -10.758644)
			(xy 169.962369 -10.704687) (xy 169.977727 -10.652382) (xy 170.000372 -10.602796) (xy 170.029844 -10.556938)
			(xy 170.065542 -10.51574) (xy 170.106739 -10.480043) (xy 170.152598 -10.450571) (xy 170.202184 -10.427926)
			(xy 170.254488 -10.412568) (xy 170.308446 -10.404811) (xy 170.335702 -10.404348) (xy 171.199302 -10.404348)
			(xy 171.22655 -10.404922) (xy 171.280491 -10.412678) (xy 171.33278 -10.428032) (xy 171.382351 -10.45067)
			(xy 171.428196 -10.480133) (xy 171.469381 -10.515821) (xy 171.505068 -10.557006) (xy 171.534531 -10.602851)
			(xy 171.557169 -10.652422) (xy 171.572522 -10.704711) (xy 171.580278 -10.758652) (xy 171.580278 -10.813148)
			(xy 171.572522 -10.867089) (xy 171.557169 -10.919378) (xy 171.534531 -10.968949) (xy 171.505068 -11.014794)
			(xy 171.469381 -11.055979) (xy 171.428196 -11.091667) (xy 171.382351 -11.12113) (xy 171.33278 -11.143768)
			(xy 171.280491 -11.159122) (xy 171.22655 -11.166878) (xy 171.199302 -11.167364) (xy 170.335702 -11.167364)
			(xy 170.308446 -11.166989) (xy 170.254488 -11.159232) (xy 170.202184 -11.143874) (xy 170.152598 -11.121229)
			(xy 170.106739 -11.091757) (xy 170.065542 -11.05606) (xy 170.029844 -11.014862) (xy 170.000372 -10.969004)
			(xy 169.977727 -10.919418) (xy 169.962369 -10.867113) (xy 169.954611 -10.813156) (xy 129.214158 -10.813156)
			(xy 129.205538 -10.835765) (xy 129.166761 -10.914966) (xy 129.120941 -10.990313) (xy 129.06846 -11.06118)
			(xy 129.009752 -11.126982) (xy 128.945304 -11.187173) (xy 128.875649 -11.241254) (xy 128.801365 -11.288776)
			(xy 128.723067 -11.329347) (xy 128.641405 -11.362629) (xy 128.557054 -11.388348) (xy 128.470714 -11.40629)
			(xy 128.3831 -11.416306) (xy 128.294938 -11.418313) (xy 128.206959 -11.412295) (xy 128.119892 -11.398302)
			(xy 128.034458 -11.376449) (xy 127.951365 -11.346918) (xy 127.871302 -11.309953) (xy 127.794932 -11.265861)
			(xy 127.722888 -11.215006) (xy 127.655767 -11.157811) (xy 127.594125 -11.09475) (xy 127.538472 -11.026344)
			(xy 127.489271 -10.953161) (xy 127.446929 -10.875807) (xy 127.411796 -10.794923) (xy 127.384164 -10.71118)
			(xy 127.364261 -10.62527) (xy 127.352254 -10.537907) (xy 127.34824 -10.449814) (xy 126.51969 -10.449814)
			(xy 126.493105 -10.542092) (xy 126.446613 -10.674957) (xy 126.392744 -10.805006) (xy 126.331668 -10.93183)
			(xy 126.263578 -11.05503) (xy 126.188687 -11.174218) (xy 126.10723 -11.28902) (xy 126.019465 -11.399074)
			(xy 125.925667 -11.504033) (xy 125.826132 -11.603569) (xy 125.721172 -11.697366) (xy 125.611118 -11.785131)
			(xy 125.496317 -11.866588) (xy 125.495706 -11.866972) (xy 129.833804 -11.866972) (xy 129.833804 -11.812428)
			(xy 129.841567 -11.758438) (xy 129.856934 -11.706103) (xy 129.879594 -11.656488) (xy 129.909085 -11.610603)
			(xy 129.944805 -11.569383) (xy 129.986029 -11.533665) (xy 130.031916 -11.504179) (xy 130.081533 -11.481523)
			(xy 130.13387 -11.46616) (xy 130.18786 -11.458401) (xy 130.215132 -11.45794) (xy 131.078732 -11.45794)
			(xy 131.106 -11.458425) (xy 131.15998 -11.46619) (xy 131.212306 -11.481558) (xy 131.261913 -11.504216)
			(xy 131.30779 -11.533703) (xy 131.349004 -11.569419) (xy 131.384716 -11.610636) (xy 131.414199 -11.656515)
			(xy 131.436853 -11.706124) (xy 131.452217 -11.758451) (xy 131.459978 -11.812432) (xy 131.459978 -11.866968)
			(xy 131.452217 -11.920949) (xy 131.436853 -11.973276) (xy 131.432747 -11.982267) (xy 135.233942 -11.982267)
			(xy 135.233942 -11.927733) (xy 135.241703 -11.873755) (xy 135.257066 -11.82143) (xy 135.279719 -11.771824)
			(xy 135.309201 -11.725946) (xy 135.344912 -11.684731) (xy 135.386124 -11.649018) (xy 135.431999 -11.619533)
			(xy 135.481603 -11.596876) (xy 135.533927 -11.581509) (xy 135.587905 -11.573744) (xy 135.615172 -11.573256)
			(xy 136.478772 -11.573256) (xy 136.506046 -11.573682) (xy 136.560038 -11.581441) (xy 136.612377 -11.596805)
			(xy 136.661996 -11.619462) (xy 136.707885 -11.648951) (xy 136.74911 -11.68467) (xy 136.784832 -11.725893)
			(xy 136.814324 -11.77178) (xy 136.836985 -11.821397) (xy 136.852353 -11.873735) (xy 136.860116 -11.927726)
			(xy 136.860116 -11.982274) (xy 136.852353 -12.036265) (xy 136.836985 -12.088603) (xy 136.814324 -12.13822)
			(xy 136.784832 -12.184107) (xy 136.74911 -12.22533) (xy 136.707885 -12.261049) (xy 136.661996 -12.290538)
			(xy 136.612377 -12.313195) (xy 136.560038 -12.328559) (xy 136.506046 -12.336318) (xy 136.478772 -12.33678)
			(xy 135.615172 -12.33678) (xy 135.587905 -12.336256) (xy 135.533927 -12.328491) (xy 135.481603 -12.313124)
			(xy 135.431999 -12.290467) (xy 135.386124 -12.260982) (xy 135.344912 -12.225269) (xy 135.309201 -12.184054)
			(xy 135.279719 -12.138176) (xy 135.257066 -12.08857) (xy 135.241703 -12.036245) (xy 135.233942 -11.982267)
			(xy 131.432747 -11.982267) (xy 131.414199 -12.022885) (xy 131.384716 -12.068764) (xy 131.349004 -12.109981)
			(xy 131.30779 -12.145697) (xy 131.261913 -12.175184) (xy 131.212306 -12.197842) (xy 131.15998 -12.21321)
			(xy 131.106 -12.220975) (xy 131.078732 -12.221464) (xy 130.215132 -12.221464) (xy 130.18786 -12.220999)
			(xy 130.13387 -12.21324) (xy 130.081533 -12.197877) (xy 130.031916 -12.175221) (xy 129.986029 -12.145735)
			(xy 129.944805 -12.110017) (xy 129.909085 -12.068797) (xy 129.879594 -12.022912) (xy 129.856934 -11.973297)
			(xy 129.841567 -11.920962) (xy 129.833804 -11.866972) (xy 125.495706 -11.866972) (xy 125.377128 -11.941479)
			(xy 125.253928 -12.009569) (xy 125.127104 -12.070645) (xy 124.997055 -12.124513) (xy 124.86419 -12.171005)
			(xy 124.728928 -12.209974) (xy 124.591693 -12.241298) (xy 124.452918 -12.264877) (xy 124.313039 -12.280639)
			(xy 124.172496 -12.288532) (xy 124.102114 -12.289028) (xy 83.70189 -12.289028) (xy 83.631508 -12.288534)
			(xy 83.490965 -12.280641) (xy 83.351086 -12.26488) (xy 83.21231 -12.2413) (xy 83.075075 -12.209977)
			(xy 82.939812 -12.171008) (xy 82.806947 -12.124516) (xy 82.676898 -12.070648) (xy 82.550073 -12.009572)
			(xy 82.426873 -11.941482) (xy 82.307684 -11.866591) (xy 82.192882 -11.785134) (xy 82.082828 -11.697369)
			(xy 81.977868 -11.603571) (xy 81.878333 -11.504036) (xy 81.784535 -11.399076) (xy 81.696769 -11.289022)
			(xy 81.615313 -11.174221) (xy 81.540421 -11.055032) (xy 81.47233 -10.931832) (xy 81.411254 -10.805008)
			(xy 81.357386 -10.674959) (xy 81.310894 -10.542094) (xy 81.271924 -10.406831) (xy 81.240601 -10.269596)
			(xy 81.217021 -10.13082) (xy 81.20126 -9.990941) (xy 81.193366 -9.850398) (xy 81.192878 -9.780016)
			(xy 81.192878 -0.559816) (xy 81.192461 -0.549794) (xy 81.184793 -0.531276) (xy 81.170619 -0.517104)
			(xy 81.1521 -0.509438) (xy 81.142078 -0.509016) (xy 13.661898 -0.509016) (xy 13.651878 -0.509436)
			(xy 13.633365 -0.517107) (xy 13.619197 -0.53128) (xy 13.611532 -0.549796) (xy 13.611098 -0.559816)
			(xy 13.611098 -5.169916) (xy 14.348212 -5.169916) (xy 14.352226 -5.081823) (xy 14.364233 -4.99446)
			(xy 14.384136 -4.90855) (xy 14.411768 -4.824807) (xy 14.446901 -4.743923) (xy 14.489243 -4.666569)
			(xy 14.538444 -4.593386) (xy 14.594097 -4.52498) (xy 14.655739 -4.461919) (xy 14.72286 -4.404724)
			(xy 14.794904 -4.353869) (xy 14.871274 -4.309777) (xy 14.951337 -4.272812) (xy 15.03443 -4.243281)
			(xy 15.119864 -4.221428) (xy 15.206931 -4.207435) (xy 15.29491 -4.201417) (xy 15.383072 -4.203424)
			(xy 15.470686 -4.21344) (xy 15.557026 -4.231382) (xy 15.641377 -4.257101) (xy 15.723039 -4.290383)
			(xy 15.801337 -4.330954) (xy 15.875621 -4.378476) (xy 15.945276 -4.432557) (xy 16.009724 -4.492748)
			(xy 16.068432 -4.55855) (xy 16.120913 -4.629417) (xy 16.166733 -4.704764) (xy 16.20551 -4.783965)
			(xy 16.236925 -4.866364) (xy 16.260717 -4.951278) (xy 16.267971 -4.990667) (xy 20.439138 -4.990667)
			(xy 20.439138 -4.936133) (xy 20.446899 -4.882153) (xy 20.462263 -4.829827) (xy 20.484917 -4.78022)
			(xy 20.5144 -4.734341) (xy 20.550112 -4.693126) (xy 20.591325 -4.657412) (xy 20.637202 -4.627926)
			(xy 20.686808 -4.60527) (xy 20.739133 -4.589903) (xy 20.793113 -4.58214) (xy 20.82038 -4.581652)
			(xy 21.68398 -4.581652) (xy 21.711253 -4.582086) (xy 21.765244 -4.589846) (xy 21.817581 -4.605211)
			(xy 21.867198 -4.627869) (xy 21.913086 -4.657357) (xy 21.95431 -4.693076) (xy 21.990031 -4.734298)
			(xy 22.019522 -4.780184) (xy 22.042182 -4.8298) (xy 22.057549 -4.882136) (xy 22.065312 -4.936127)
			(xy 22.065312 -4.990671) (xy 24.039016 -4.990671) (xy 24.039016 -4.936129) (xy 24.046778 -4.882142)
			(xy 24.062145 -4.82981) (xy 24.084803 -4.780197) (xy 24.114292 -4.734314) (xy 24.15001 -4.693095)
			(xy 24.191231 -4.657379) (xy 24.237116 -4.627893) (xy 24.28673 -4.605237) (xy 24.339064 -4.589873)
			(xy 24.393051 -4.582114) (xy 24.420322 -4.581652) (xy 25.283922 -4.581652) (xy 25.311191 -4.582112)
			(xy 25.365175 -4.589876) (xy 25.417503 -4.605244) (xy 25.467113 -4.627903) (xy 25.512992 -4.65739)
			(xy 25.554209 -4.693107) (xy 25.589923 -4.734325) (xy 25.619408 -4.780207) (xy 25.642063 -4.829817)
			(xy 25.657428 -4.882147) (xy 25.66519 -4.936131) (xy 25.66519 -4.990667) (xy 27.639038 -4.990667)
			(xy 27.639038 -4.936133) (xy 27.646799 -4.882155) (xy 27.662162 -4.82983) (xy 27.684814 -4.780224)
			(xy 27.714296 -4.734347) (xy 27.750006 -4.693131) (xy 27.791218 -4.657417) (xy 27.837092 -4.627932)
			(xy 27.886696 -4.605274) (xy 27.93902 -4.589906) (xy 27.992997 -4.582141) (xy 28.020264 -4.581652)
			(xy 28.883864 -4.581652) (xy 28.911138 -4.582085) (xy 28.96513 -4.589843) (xy 29.017469 -4.605207)
			(xy 29.067089 -4.627863) (xy 29.112979 -4.657351) (xy 29.154205 -4.69307) (xy 29.189927 -4.734292)
			(xy 29.219419 -4.78018) (xy 29.24208 -4.829797) (xy 29.257449 -4.882134) (xy 29.265212 -4.936126)
			(xy 29.265212 -4.990667) (xy 31.239238 -4.990667) (xy 31.239238 -4.936133) (xy 31.246999 -4.882155)
			(xy 31.262361 -4.829831) (xy 31.285014 -4.780225) (xy 31.314495 -4.734348) (xy 31.350205 -4.693133)
			(xy 31.391416 -4.657419) (xy 31.43729 -4.627933) (xy 31.486893 -4.605275) (xy 31.539216 -4.589907)
			(xy 31.593193 -4.582141) (xy 31.62046 -4.581652) (xy 32.48406 -4.581652) (xy 32.511334 -4.582085)
			(xy 32.565327 -4.589843) (xy 32.617666 -4.605206) (xy 32.667286 -4.627862) (xy 32.713177 -4.65735)
			(xy 32.754403 -4.693068) (xy 32.790126 -4.734291) (xy 32.819619 -4.780178) (xy 32.84228 -4.829796)
			(xy 32.857649 -4.882134) (xy 32.865412 -4.936126) (xy 32.865412 -4.990671) (xy 40.349116 -4.990671)
			(xy 40.349116 -4.936129) (xy 40.356878 -4.882142) (xy 40.372245 -4.829809) (xy 40.394903 -4.780196)
			(xy 40.424392 -4.734313) (xy 40.460111 -4.693094) (xy 40.501332 -4.657378) (xy 40.547217 -4.627892)
			(xy 40.596832 -4.605237) (xy 40.649165 -4.589873) (xy 40.703153 -4.582114) (xy 40.730424 -4.581652)
			(xy 41.594024 -4.581652) (xy 41.621293 -4.582112) (xy 41.675276 -4.589877) (xy 41.727605 -4.605245)
			(xy 41.777214 -4.627903) (xy 41.823093 -4.657391) (xy 41.86431 -4.693107) (xy 41.900024 -4.734326)
			(xy 41.929508 -4.780207) (xy 41.952164 -4.829818) (xy 41.967528 -4.882147) (xy 41.97529 -4.936131)
			(xy 41.97529 -4.990667) (xy 43.949138 -4.990667) (xy 43.949138 -4.936133) (xy 43.956899 -4.882155)
			(xy 43.972262 -4.82983) (xy 43.994915 -4.780224) (xy 44.024396 -4.734346) (xy 44.060107 -4.693131)
			(xy 44.101319 -4.657417) (xy 44.147194 -4.627931) (xy 44.196798 -4.605274) (xy 44.249121 -4.589906)
			(xy 44.303099 -4.582141) (xy 44.330366 -4.581652) (xy 45.193966 -4.581652) (xy 45.22124 -4.582085)
			(xy 45.275232 -4.589844) (xy 45.327571 -4.605208) (xy 45.37719 -4.627864) (xy 45.42308 -4.657352)
			(xy 45.464305 -4.693071) (xy 45.500028 -4.734293) (xy 45.52952 -4.78018) (xy 45.552181 -4.829797)
			(xy 45.567549 -4.882135) (xy 45.575312 -4.936126) (xy 45.575312 -4.990667) (xy 51.559238 -4.990667)
			(xy 51.559238 -4.936133) (xy 51.566999 -4.882155) (xy 51.582361 -4.829831) (xy 51.605014 -4.780225)
			(xy 51.634495 -4.734348) (xy 51.670205 -4.693133) (xy 51.711416 -4.657419) (xy 51.75729 -4.627933)
			(xy 51.806893 -4.605275) (xy 51.859216 -4.589907) (xy 51.913193 -4.582141) (xy 51.94046 -4.581652)
			(xy 52.80406 -4.581652) (xy 52.831334 -4.582085) (xy 52.885327 -4.589843) (xy 52.937666 -4.605206)
			(xy 52.987286 -4.627862) (xy 53.033177 -4.65735) (xy 53.074403 -4.693068) (xy 53.110126 -4.734291)
			(xy 53.139619 -4.780178) (xy 53.16228 -4.829796) (xy 53.177649 -4.882134) (xy 53.185412 -4.936126)
			(xy 53.185412 -4.99067) (xy 55.159115 -4.99067) (xy 55.159115 -4.93613) (xy 55.166877 -4.882145)
			(xy 55.182243 -4.829814) (xy 55.2049 -4.780202) (xy 55.234387 -4.73432) (xy 55.270103 -4.693102)
			(xy 55.311322 -4.657386) (xy 55.357204 -4.627899) (xy 55.406816 -4.605242) (xy 55.459147 -4.589877)
			(xy 55.513132 -4.582115) (xy 55.540402 -4.581652) (xy 56.404002 -4.581652) (xy 56.431272 -4.582111)
			(xy 56.485258 -4.589873) (xy 56.537589 -4.605239) (xy 56.587201 -4.627896) (xy 56.633083 -4.657383)
			(xy 56.674302 -4.6931) (xy 56.710018 -4.734319) (xy 56.739505 -4.780201) (xy 56.762162 -4.829813)
			(xy 56.777528 -4.882144) (xy 56.78529 -4.93613) (xy 56.78529 -4.99067) (xy 56.777528 -5.044656) (xy 56.762162 -5.096987)
			(xy 56.739505 -5.146599) (xy 56.710018 -5.192481) (xy 56.674302 -5.2337) (xy 56.633083 -5.269417)
			(xy 56.587201 -5.298904) (xy 56.537589 -5.321561) (xy 56.485258 -5.336927) (xy 56.431272 -5.344689)
			(xy 56.404002 -5.345176) (xy 55.540402 -5.345176) (xy 55.513132 -5.344685) (xy 55.459147 -5.336923)
			(xy 55.406816 -5.321558) (xy 55.357204 -5.298901) (xy 55.311322 -5.269414) (xy 55.270103 -5.233698)
			(xy 55.234387 -5.19248) (xy 55.2049 -5.146598) (xy 55.182243 -5.096986) (xy 55.166877 -5.044655)
			(xy 55.159115 -4.99067) (xy 53.185412 -4.99067) (xy 53.185412 -4.990674) (xy 53.177649 -5.044666)
			(xy 53.16228 -5.097004) (xy 53.139619 -5.146622) (xy 53.110126 -5.192509) (xy 53.074403 -5.233732)
			(xy 53.033177 -5.26945) (xy 52.987286 -5.298938) (xy 52.937666 -5.321594) (xy 52.885327 -5.336957)
			(xy 52.831334 -5.344715) (xy 52.80406 -5.345176) (xy 51.94046 -5.345176) (xy 51.913194 -5.344659)
			(xy 51.859216 -5.336893) (xy 51.806893 -5.321525) (xy 51.75729 -5.298867) (xy 51.711416 -5.269381)
			(xy 51.670205 -5.233667) (xy 51.634495 -5.192452) (xy 51.605014 -5.146575) (xy 51.582361 -5.096969)
			(xy 51.566999 -5.044645) (xy 51.559238 -4.990667) (xy 45.575312 -4.990667) (xy 45.575312 -4.990674)
			(xy 45.567549 -5.044665) (xy 45.552181 -5.097003) (xy 45.52952 -5.14662) (xy 45.500028 -5.192507)
			(xy 45.464305 -5.233729) (xy 45.42308 -5.269448) (xy 45.37719 -5.298936) (xy 45.327571 -5.321592)
			(xy 45.275232 -5.336956) (xy 45.22124 -5.344715) (xy 45.193966 -5.345176) (xy 44.330366 -5.345176)
			(xy 44.303099 -5.344659) (xy 44.249121 -5.336894) (xy 44.196798 -5.321526) (xy 44.147194 -5.298869)
			(xy 44.101319 -5.269383) (xy 44.060107 -5.233669) (xy 44.024396 -5.192454) (xy 43.994915 -5.146576)
			(xy 43.972262 -5.09697) (xy 43.956899 -5.044645) (xy 43.949138 -4.990667) (xy 41.97529 -4.990667)
			(xy 41.97529 -4.990669) (xy 41.967528 -5.044653) (xy 41.952164 -5.096982) (xy 41.929508 -5.146593)
			(xy 41.900024 -5.192474) (xy 41.86431 -5.233693) (xy 41.823093 -5.269409) (xy 41.777214 -5.298897)
			(xy 41.727605 -5.321555) (xy 41.675276 -5.336923) (xy 41.621293 -5.344688) (xy 41.594024 -5.345176)
			(xy 40.730424 -5.345176) (xy 40.703153 -5.344686) (xy 40.649165 -5.336927) (xy 40.596832 -5.321563)
			(xy 40.547217 -5.298908) (xy 40.501332 -5.269422) (xy 40.460111 -5.233706) (xy 40.424392 -5.192487)
			(xy 40.394903 -5.146604) (xy 40.372245 -5.096991) (xy 40.356878 -5.044658) (xy 40.349116 -4.990671)
			(xy 32.865412 -4.990671) (xy 32.865412 -4.990674) (xy 32.857649 -5.044666) (xy 32.84228 -5.097004)
			(xy 32.819619 -5.146622) (xy 32.790126 -5.192509) (xy 32.754403 -5.233732) (xy 32.713177 -5.26945)
			(xy 32.667286 -5.298938) (xy 32.617666 -5.321594) (xy 32.565327 -5.336957) (xy 32.511334 -5.344715)
			(xy 32.48406 -5.345176) (xy 31.62046 -5.345176) (xy 31.593194 -5.344659) (xy 31.539216 -5.336893)
			(xy 31.486893 -5.321525) (xy 31.43729 -5.298867) (xy 31.391416 -5.269381) (xy 31.350205 -5.233667)
			(xy 31.314495 -5.192452) (xy 31.285014 -5.146575) (xy 31.262361 -5.096969) (xy 31.246999 -5.044645)
			(xy 31.239238 -4.990667) (xy 29.265212 -4.990667) (xy 29.265212 -4.990674) (xy 29.257449 -5.044666)
			(xy 29.24208 -5.097003) (xy 29.219419 -5.14662) (xy 29.189927 -5.192508) (xy 29.154205 -5.23373)
			(xy 29.112979 -5.269449) (xy 29.067089 -5.298937) (xy 29.017469 -5.321593) (xy 28.96513 -5.336957)
			(xy 28.911138 -5.344715) (xy 28.883864 -5.345176) (xy 28.020264 -5.345176) (xy 27.992997 -5.344659)
			(xy 27.93902 -5.336894) (xy 27.886696 -5.321526) (xy 27.837092 -5.298868) (xy 27.791218 -5.269383)
			(xy 27.750006 -5.233669) (xy 27.714296 -5.192453) (xy 27.684814 -5.146576) (xy 27.662162 -5.09697)
			(xy 27.646799 -5.044645) (xy 27.639038 -4.990667) (xy 25.66519 -4.990667) (xy 25.66519 -4.990669)
			(xy 25.657428 -5.044653) (xy 25.642063 -5.096983) (xy 25.619408 -5.146593) (xy 25.589923 -5.192475)
			(xy 25.554209 -5.233693) (xy 25.512992 -5.26941) (xy 25.467113 -5.298897) (xy 25.417503 -5.321556)
			(xy 25.365175 -5.336924) (xy 25.311191 -5.344688) (xy 25.283922 -5.345176) (xy 24.420322 -5.345176)
			(xy 24.393051 -5.344686) (xy 24.339064 -5.336927) (xy 24.28673 -5.321563) (xy 24.237116 -5.298907)
			(xy 24.191231 -5.269421) (xy 24.15001 -5.233705) (xy 24.114292 -5.192486) (xy 24.084803 -5.146603)
			(xy 24.062145 -5.09699) (xy 24.046778 -5.044658) (xy 24.039016 -4.990671) (xy 22.065312 -4.990671)
			(xy 22.065312 -4.990673) (xy 22.057549 -5.044664) (xy 22.042182 -5.097) (xy 22.019522 -5.146616)
			(xy 21.990031 -5.192502) (xy 21.95431 -5.233724) (xy 21.913086 -5.269443) (xy 21.867198 -5.298931)
			(xy 21.817581 -5.321589) (xy 21.765244 -5.336954) (xy 21.711253 -5.344714) (xy 21.68398 -5.345176)
			(xy 20.82038 -5.345176) (xy 20.793113 -5.34466) (xy 20.739133 -5.336897) (xy 20.686808 -5.32153)
			(xy 20.637202 -5.298874) (xy 20.591325 -5.269388) (xy 20.550112 -5.233674) (xy 20.5144 -5.192459)
			(xy 20.484917 -5.14658) (xy 20.462263 -5.096973) (xy 20.446899 -5.044647) (xy 20.439138 -4.990667)
			(xy 16.267971 -4.990667) (xy 16.276689 -5.038005) (xy 16.284708 -5.125824) (xy 16.28521 -5.169916)
			(xy 16.284708 -5.214008) (xy 16.276689 -5.301827) (xy 16.260717 -5.388554) (xy 16.236925 -5.473468)
			(xy 16.20551 -5.555867) (xy 16.166733 -5.635068) (xy 16.120913 -5.710415) (xy 16.068432 -5.781282)
			(xy 16.009724 -5.847084) (xy 15.945276 -5.907275) (xy 15.875621 -5.961356) (xy 15.801337 -6.008878)
			(xy 15.723039 -6.049449) (xy 15.641377 -6.082731) (xy 15.557026 -6.10845) (xy 15.470686 -6.126392)
			(xy 15.383072 -6.136408) (xy 15.29491 -6.138415) (xy 15.206931 -6.132397) (xy 15.119864 -6.118404)
			(xy 15.03443 -6.096551) (xy 14.951337 -6.06702) (xy 14.871274 -6.030055) (xy 14.794904 -5.985963)
			(xy 14.72286 -5.935108) (xy 14.655739 -5.877913) (xy 14.594097 -5.814852) (xy 14.538444 -5.746446)
			(xy 14.489243 -5.673263) (xy 14.446901 -5.595909) (xy 14.411768 -5.515025) (xy 14.384136 -5.431282)
			(xy 14.364233 -5.345372) (xy 14.352226 -5.258009) (xy 14.348212 -5.169916) (xy 13.611098 -5.169916)
			(xy 13.611098 -6.169914) (xy 78.515217 -6.169914) (xy 78.519222 -6.082006) (xy 78.531205 -5.994826)
			(xy 78.551065 -5.909097) (xy 78.57864 -5.825529) (xy 78.613699 -5.744815) (xy 78.655952 -5.667623)
			(xy 78.70505 -5.594594) (xy 78.760586 -5.526332) (xy 78.822098 -5.463402) (xy 78.889079 -5.406328)
			(xy 78.960972 -5.35558) (xy 79.037181 -5.31158) (xy 79.117076 -5.274693) (xy 79.199995 -5.245224)
			(xy 79.28525 -5.223417) (xy 79.372134 -5.209453) (xy 79.459928 -5.203447) (xy 79.547905 -5.205451)
			(xy 79.635335 -5.215446) (xy 79.721494 -5.23335) (xy 79.805668 -5.259014) (xy 79.887159 -5.292227)
			(xy 79.965293 -5.332713) (xy 80.039421 -5.380135) (xy 80.108929 -5.434102) (xy 80.173243 -5.494167)
			(xy 80.231827 -5.559831) (xy 80.284198 -5.63055) (xy 80.329921 -5.705738) (xy 80.368618 -5.784773)
			(xy 80.399967 -5.866999) (xy 80.423709 -5.951735) (xy 80.439647 -6.038279) (xy 80.447649 -6.125914)
			(xy 80.44815 -6.169914) (xy 80.447649 -6.213914) (xy 80.439647 -6.301549) (xy 80.423709 -6.388093)
			(xy 80.399967 -6.472829) (xy 80.368618 -6.555055) (xy 80.329921 -6.63409) (xy 80.284198 -6.709278)
			(xy 80.231827 -6.779997) (xy 80.173243 -6.845661) (xy 80.108929 -6.905726) (xy 80.039421 -6.959693)
			(xy 79.965293 -7.007115) (xy 79.887159 -7.047601) (xy 79.805668 -7.080814) (xy 79.721494 -7.106478)
			(xy 79.635335 -7.124382) (xy 79.547905 -7.134377) (xy 79.459928 -7.136381) (xy 79.372134 -7.130375)
			(xy 79.28525 -7.116411) (xy 79.199995 -7.094604) (xy 79.117076 -7.065135) (xy 79.037181 -7.028248)
			(xy 78.960972 -6.984248) (xy 78.889079 -6.9335) (xy 78.822098 -6.876426) (xy 78.760586 -6.813496)
			(xy 78.70505 -6.745234) (xy 78.655952 -6.672205) (xy 78.613699 -6.595013) (xy 78.57864 -6.514299)
			(xy 78.551065 -6.430731) (xy 78.531205 -6.345002) (xy 78.519222 -6.257822) (xy 78.515217 -6.169914)
			(xy 13.611098 -6.169914) (xy 13.611098 -6.75243) (xy 18.634432 -6.75243) (xy 18.634432 -6.69789)
			(xy 18.642194 -6.643907) (xy 18.65756 -6.591577) (xy 18.680216 -6.541966) (xy 18.709702 -6.496085)
			(xy 18.745417 -6.454867) (xy 18.786635 -6.419152) (xy 18.832516 -6.389666) (xy 18.882127 -6.36701)
			(xy 18.934457 -6.351644) (xy 18.98844 -6.343882) (xy 19.01571 -6.343396) (xy 19.87931 -6.343396)
			(xy 19.906579 -6.343886) (xy 19.960563 -6.351648) (xy 20.012892 -6.367013) (xy 20.062502 -6.389669)
			(xy 20.108382 -6.419155) (xy 20.1496 -6.45487) (xy 20.185315 -6.496088) (xy 20.214801 -6.541968)
			(xy 20.237457 -6.591578) (xy 20.252822 -6.643907) (xy 20.260584 -6.697891) (xy 20.260584 -6.752429)
			(xy 20.260584 -6.752431) (xy 22.234349 -6.752431) (xy 22.234349 -6.697889) (xy 22.242112 -6.643901)
			(xy 22.257478 -6.591568) (xy 22.280136 -6.541955) (xy 22.309624 -6.496071) (xy 22.345342 -6.45485)
			(xy 22.386562 -6.419133) (xy 22.432447 -6.389645) (xy 22.48206 -6.366987) (xy 22.534393 -6.351621)
			(xy 22.588381 -6.343859) (xy 22.615652 -6.343396) (xy 23.479252 -6.343396) (xy 23.506521 -6.343887)
			(xy 23.560504 -6.351648) (xy 23.612833 -6.367014) (xy 23.662443 -6.38967) (xy 23.708323 -6.419156)
			(xy 23.749541 -6.454871) (xy 23.785255 -6.496088) (xy 23.814741 -6.541969) (xy 23.837397 -6.591579)
			(xy 23.852762 -6.643908) (xy 23.860524 -6.697891) (xy 23.860524 -6.752429) (xy 23.860518 -6.752472)
			(xy 25.834283 -6.752472) (xy 25.834283 -6.697928) (xy 25.842045 -6.643939) (xy 25.857412 -6.591604)
			(xy 25.88007 -6.541989) (xy 25.909558 -6.496103) (xy 25.945277 -6.454881) (xy 25.986498 -6.419162)
			(xy 26.032384 -6.389673) (xy 26.081998 -6.367014) (xy 26.134333 -6.351646) (xy 26.188322 -6.343883)
			(xy 26.215594 -6.343396) (xy 27.079194 -6.343396) (xy 27.106462 -6.343943) (xy 27.160444 -6.351704)
			(xy 27.212772 -6.367068) (xy 27.26238 -6.389722) (xy 27.308259 -6.419207) (xy 27.349476 -6.45492)
			(xy 27.38519 -6.496136) (xy 27.414675 -6.542015) (xy 27.43733 -6.591623) (xy 27.452695 -6.64395)
			(xy 27.460457 -6.697932) (xy 27.460457 -6.752468) (xy 27.460456 -6.752472) (xy 29.434483 -6.752472)
			(xy 29.434483 -6.697928) (xy 29.442245 -6.643939) (xy 29.457611 -6.591605) (xy 29.480269 -6.54199)
			(xy 29.509757 -6.496105) (xy 29.545476 -6.454883) (xy 29.586697 -6.419163) (xy 29.632581 -6.389674)
			(xy 29.682196 -6.367015) (xy 29.73453 -6.351647) (xy 29.788518 -6.343883) (xy 29.81579 -6.343396)
			(xy 30.67939 -6.343396) (xy 30.706658 -6.343943) (xy 30.76064 -6.351703) (xy 30.812969 -6.367067)
			(xy 30.862578 -6.389721) (xy 30.908457 -6.419205) (xy 30.949674 -6.454919) (xy 30.985389 -6.496135)
			(xy 31.014874 -6.542014) (xy 31.03753 -6.591622) (xy 31.052895 -6.64395) (xy 31.060657 -6.697932)
			(xy 31.060657 -6.752468) (xy 31.060657 -6.75247) (xy 38.544482 -6.75247) (xy 38.544482 -6.69793)
			(xy 38.552244 -6.643944) (xy 38.567608 -6.591613) (xy 38.590264 -6.542) (xy 38.619749 -6.496116)
			(xy 38.655463 -6.454895) (xy 38.696679 -6.419176) (xy 38.74256 -6.389686) (xy 38.792169 -6.367025)
			(xy 38.844499 -6.351654) (xy 38.898484 -6.343886) (xy 38.925754 -6.343396) (xy 39.789354 -6.343396)
			(xy 39.816624 -6.34394) (xy 39.87061 -6.351696) (xy 39.922943 -6.367057) (xy 39.972556 -6.389709)
			(xy 40.01844 -6.419192) (xy 40.059662 -6.454906) (xy 40.09538 -6.496123) (xy 40.124869 -6.542004)
			(xy 40.147527 -6.591614) (xy 40.162894 -6.643945) (xy 40.170656 -6.69793) (xy 40.170656 -6.75247)
			(xy 40.170656 -6.752472) (xy 42.144383 -6.752472) (xy 42.144383 -6.697928) (xy 42.152145 -6.643939)
			(xy 42.167512 -6.591604) (xy 42.19017 -6.541988) (xy 42.219659 -6.496103) (xy 42.255378 -6.454881)
			(xy 42.296599 -6.419161) (xy 42.342485 -6.389672) (xy 42.3921 -6.367013) (xy 42.444435 -6.351646)
			(xy 42.498424 -6.343883) (xy 42.525696 -6.343396) (xy 43.389296 -6.343396) (xy 43.416564 -6.343943)
			(xy 43.470546 -6.351704) (xy 43.522873 -6.367068) (xy 43.572481 -6.389723) (xy 43.61836 -6.419207)
			(xy 43.659576 -6.454921) (xy 43.69529 -6.496136) (xy 43.724775 -6.542015) (xy 43.74743 -6.591623)
			(xy 43.762795 -6.643951) (xy 43.770557 -6.697932) (xy 43.770557 -6.752468) (xy 43.770556 -6.752472)
			(xy 49.754483 -6.752472) (xy 49.754483 -6.697928) (xy 49.762245 -6.643939) (xy 49.777611 -6.591605)
			(xy 49.800269 -6.54199) (xy 49.829757 -6.496105) (xy 49.865476 -6.454883) (xy 49.906697 -6.419163)
			(xy 49.952581 -6.389674) (xy 50.002196 -6.367015) (xy 50.05453 -6.351647) (xy 50.108518 -6.343883)
			(xy 50.13579 -6.343396) (xy 50.99939 -6.343396) (xy 51.026658 -6.343943) (xy 51.08064 -6.351703)
			(xy 51.132969 -6.367067) (xy 51.182578 -6.389721) (xy 51.228457 -6.419205) (xy 51.269674 -6.454919)
			(xy 51.305389 -6.496135) (xy 51.334874 -6.542014) (xy 51.35753 -6.591622) (xy 51.372895 -6.64395)
			(xy 51.380657 -6.697932) (xy 51.380657 -6.752468) (xy 51.380656 -6.752475) (xy 53.35436 -6.752475)
			(xy 53.35436 -6.697925) (xy 53.362124 -6.643929) (xy 53.377493 -6.591588) (xy 53.400155 -6.541967)
			(xy 53.429649 -6.496077) (xy 53.465374 -6.454851) (xy 53.506603 -6.41913) (xy 53.552495 -6.38964)
			(xy 53.602118 -6.366982) (xy 53.65446 -6.351617) (xy 53.708457 -6.343857) (xy 53.735732 -6.343396)
			(xy 54.599332 -6.343396) (xy 54.626597 -6.343969) (xy 54.680571 -6.351733) (xy 54.732891 -6.367099)
			(xy 54.782492 -6.389755) (xy 54.828364 -6.419238) (xy 54.869573 -6.45495) (xy 54.905281 -6.496162)
			(xy 54.93476 -6.542036) (xy 54.957412 -6.591639) (xy 54.972774 -6.64396) (xy 54.980534 -6.697935)
			(xy 54.980534 -6.752465) (xy 54.980533 -6.752471) (xy 56.954382 -6.752471) (xy 56.954382 -6.697929)
			(xy 56.962144 -6.643942) (xy 56.97751 -6.591608) (xy 57.000167 -6.541994) (xy 57.029654 -6.49611)
			(xy 57.06537 -6.454888) (xy 57.106589 -6.419169) (xy 57.152472 -6.389679) (xy 57.202084 -6.367019)
			(xy 57.254416 -6.35165) (xy 57.308403 -6.343884) (xy 57.335674 -6.343396) (xy 58.199274 -6.343396)
			(xy 58.226543 -6.343942) (xy 58.280527 -6.3517) (xy 58.332857 -6.367062) (xy 58.382468 -6.389716)
			(xy 58.42835 -6.4192) (xy 58.469569 -6.454913) (xy 58.505285 -6.496129) (xy 58.534772 -6.542009)
			(xy 58.557429 -6.591619) (xy 58.564228 -6.614772) (xy 70.948992 -6.614772) (xy 70.948992 -6.560228)
			(xy 70.956754 -6.506238) (xy 70.972121 -6.453903) (xy 70.994781 -6.404288) (xy 71.02427 -6.358403)
			(xy 71.05999 -6.317181) (xy 71.101212 -6.281463) (xy 71.147099 -6.251975) (xy 71.196715 -6.229317)
			(xy 71.24905 -6.213952) (xy 71.30304 -6.206191) (xy 71.330312 -6.205728) (xy 72.193912 -6.205728)
			(xy 72.22118 -6.206235) (xy 72.275161 -6.213998) (xy 72.327488 -6.229364) (xy 72.377095 -6.25202)
			(xy 72.422973 -6.281506) (xy 72.464188 -6.31722) (xy 72.499901 -6.358436) (xy 72.529385 -6.404315)
			(xy 72.55204 -6.453924) (xy 72.567404 -6.506251) (xy 72.575166 -6.560232) (xy 72.575166 -6.614768)
			(xy 72.567404 -6.668749) (xy 72.55204 -6.721076) (xy 72.529385 -6.770685) (xy 72.499901 -6.816564)
			(xy 72.464188 -6.85778) (xy 72.422973 -6.893494) (xy 72.377095 -6.92298) (xy 72.327488 -6.945636)
			(xy 72.275161 -6.961002) (xy 72.22118 -6.968765) (xy 72.193912 -6.969252) (xy 71.330312 -6.969252)
			(xy 71.30304 -6.968809) (xy 71.24905 -6.961048) (xy 71.196715 -6.945683) (xy 71.147099 -6.923025)
			(xy 71.101212 -6.893537) (xy 71.05999 -6.857819) (xy 71.02427 -6.816597) (xy 70.994781 -6.770712)
			(xy 70.972121 -6.721097) (xy 70.956754 -6.668762) (xy 70.948992 -6.614772) (xy 58.564228 -6.614772)
			(xy 58.572795 -6.643948) (xy 58.580557 -6.697931) (xy 58.580557 -6.752469) (xy 58.572795 -6.806452)
			(xy 58.557429 -6.858781) (xy 58.534772 -6.908391) (xy 58.505285 -6.954271) (xy 58.469569 -6.995487)
			(xy 58.42835 -7.0312) (xy 58.382468 -7.060684) (xy 58.332857 -7.083338) (xy 58.280527 -7.0987) (xy 58.226543 -7.106458)
			(xy 58.199274 -7.10692) (xy 57.335674 -7.10692) (xy 57.308403 -7.106516) (xy 57.254416 -7.09875)
			(xy 57.202084 -7.083381) (xy 57.152472 -7.060721) (xy 57.106589 -7.031231) (xy 57.06537 -6.995512)
			(xy 57.029654 -6.95429) (xy 57.000167 -6.908406) (xy 56.97751 -6.858792) (xy 56.962144 -6.806458)
			(xy 56.954382 -6.752471) (xy 54.980533 -6.752471) (xy 54.972774 -6.80644) (xy 54.957412 -6.858761)
			(xy 54.93476 -6.908364) (xy 54.905281 -6.954238) (xy 54.869573 -6.99545) (xy 54.828364 -7.031162)
			(xy 54.782492 -7.060645) (xy 54.732891 -7.083301) (xy 54.680571 -7.098667) (xy 54.626597 -7.106431)
			(xy 54.599332 -7.10692) (xy 53.735732 -7.10692) (xy 53.708457 -7.106543) (xy 53.65446 -7.098783)
			(xy 53.602118 -7.083418) (xy 53.552495 -7.06076) (xy 53.506603 -7.03127) (xy 53.465374 -6.995549)
			(xy 53.429649 -6.954323) (xy 53.400155 -6.908433) (xy 53.377493 -6.858812) (xy 53.362124 -6.806471)
			(xy 53.35436 -6.752475) (xy 51.380656 -6.752475) (xy 51.372895 -6.80645) (xy 51.35753 -6.858778)
			(xy 51.334874 -6.908386) (xy 51.305389 -6.954265) (xy 51.269674 -6.995481) (xy 51.228457 -7.031195)
			(xy 51.182578 -7.060679) (xy 51.132969 -7.083333) (xy 51.08064 -7.098697) (xy 51.026658 -7.106457)
			(xy 50.99939 -7.10692) (xy 50.13579 -7.10692) (xy 50.108518 -7.106517) (xy 50.05453 -7.098753) (xy 50.002196 -7.083385)
			(xy 49.952581 -7.060726) (xy 49.906697 -7.031237) (xy 49.865476 -6.995517) (xy 49.829757 -6.954295)
			(xy 49.800269 -6.90841) (xy 49.777611 -6.858795) (xy 49.762245 -6.806461) (xy 49.754483 -6.752472)
			(xy 43.770556 -6.752472) (xy 43.762795 -6.806449) (xy 43.74743 -6.858777) (xy 43.724775 -6.908385)
			(xy 43.69529 -6.954264) (xy 43.659576 -6.995479) (xy 43.61836 -7.031193) (xy 43.572481 -7.060677)
			(xy 43.522873 -7.083332) (xy 43.470546 -7.098696) (xy 43.416564 -7.106457) (xy 43.389296 -7.10692)
			(xy 42.525696 -7.10692) (xy 42.498424 -7.106517) (xy 42.444435 -7.098754) (xy 42.3921 -7.083387)
			(xy 42.342485 -7.060728) (xy 42.296599 -7.031239) (xy 42.255378 -6.995519) (xy 42.219659 -6.954297)
			(xy 42.19017 -6.908412) (xy 42.167512 -6.858796) (xy 42.152145 -6.806461) (xy 42.144383 -6.752472)
			(xy 40.170656 -6.752472) (xy 40.162894 -6.806455) (xy 40.147527 -6.858786) (xy 40.124869 -6.908396)
			(xy 40.09538 -6.954277) (xy 40.059661 -6.995494) (xy 40.01844 -7.031208) (xy 39.972556 -7.060691)
			(xy 39.922943 -7.083343) (xy 39.87061 -7.098704) (xy 39.816624 -7.10646) (xy 39.789354 -7.10692)
			(xy 38.925754 -7.10692) (xy 38.898484 -7.106514) (xy 38.844499 -7.098746) (xy 38.792169 -7.083375)
			(xy 38.74256 -7.060714) (xy 38.696679 -7.031224) (xy 38.655463 -6.995505) (xy 38.619749 -6.954284)
			(xy 38.590264 -6.9084) (xy 38.567608 -6.858787) (xy 38.552244 -6.806456) (xy 38.544482 -6.75247)
			(xy 31.060657 -6.75247) (xy 31.052895 -6.80645) (xy 31.03753 -6.858778) (xy 31.014874 -6.908386)
			(xy 30.985389 -6.954265) (xy 30.949674 -6.995481) (xy 30.908457 -7.031195) (xy 30.862578 -7.060679)
			(xy 30.812969 -7.083333) (xy 30.76064 -7.098697) (xy 30.706658 -7.106457) (xy 30.67939 -7.10692)
			(xy 29.81579 -7.10692) (xy 29.788518 -7.106517) (xy 29.73453 -7.098753) (xy 29.682196 -7.083385)
			(xy 29.632581 -7.060726) (xy 29.586697 -7.031237) (xy 29.545476 -6.995517) (xy 29.509757 -6.954295)
			(xy 29.480269 -6.90841) (xy 29.457611 -6.858795) (xy 29.442245 -6.806461) (xy 29.434483 -6.752472)
			(xy 27.460456 -6.752472) (xy 27.452695 -6.80645) (xy 27.43733 -6.858777) (xy 27.414675 -6.908385)
			(xy 27.38519 -6.954264) (xy 27.349476 -6.99548) (xy 27.308259 -7.031193) (xy 27.26238 -7.060678)
			(xy 27.212772 -7.083332) (xy 27.160444 -7.098696) (xy 27.106462 -7.106457) (xy 27.079194 -7.10692)
			(xy 26.215594 -7.10692) (xy 26.188322 -7.106517) (xy 26.134333 -7.098754) (xy 26.081998 -7.083386)
			(xy 26.032384 -7.060727) (xy 25.986498 -7.031238) (xy 25.945277 -6.995519) (xy 25.909558 -6.954297)
			(xy 25.88007 -6.908411) (xy 25.857412 -6.858796) (xy 25.842045 -6.806461) (xy 25.834283 -6.752472)
			(xy 23.860518 -6.752472) (xy 23.852762 -6.806412) (xy 23.837397 -6.858741) (xy 23.814741 -6.908351)
			(xy 23.785255 -6.954232) (xy 23.749541 -6.995449) (xy 23.708323 -7.031164) (xy 23.662443 -7.06065)
			(xy 23.612833 -7.083306) (xy 23.560504 -7.098672) (xy 23.506521 -7.106433) (xy 23.479252 -7.10692)
			(xy 22.615652 -7.10692) (xy 22.588381 -7.106461) (xy 22.534393 -7.098699) (xy 22.48206 -7.083333)
			(xy 22.432447 -7.060675) (xy 22.386562 -7.031187) (xy 22.345342 -6.99547) (xy 22.309624 -6.954249)
			(xy 22.280136 -6.908365) (xy 22.257478 -6.858752) (xy 22.242112 -6.806419) (xy 22.234349 -6.752431)
			(xy 20.260584 -6.752431) (xy 20.252822 -6.806413) (xy 20.237457 -6.858742) (xy 20.214801 -6.908352)
			(xy 20.185315 -6.954232) (xy 20.1496 -6.99545) (xy 20.108382 -7.031165) (xy 20.062502 -7.060651)
			(xy 20.012892 -7.083307) (xy 19.960563 -7.098672) (xy 19.906579 -7.106434) (xy 19.87931 -7.10692)
			(xy 19.01571 -7.10692) (xy 18.98844 -7.106438) (xy 18.934457 -7.098676) (xy 18.882127 -7.08331) (xy 18.832516 -7.060654)
			(xy 18.786635 -7.031168) (xy 18.745417 -6.995453) (xy 18.709702 -6.954235) (xy 18.680216 -6.908354)
			(xy 18.65756 -6.858743) (xy 18.642194 -6.806413) (xy 18.634432 -6.75243) (xy 13.611098 -6.75243)
			(xy 13.611098 -9.780016) (xy 13.610604 -9.850398) (xy 13.602711 -9.990941) (xy 13.58695 -10.13082)
			(xy 13.563371 -10.269596) (xy 13.532048 -10.406831) (xy 13.493079 -10.542094) (xy 13.446587 -10.674959)
			(xy 13.392719 -10.805008) (xy 13.331643 -10.931832) (xy 13.263553 -11.055033) (xy 13.188662 -11.174221)
			(xy 13.107205 -11.289023) (xy 13.01944 -11.399077) (xy 12.925642 -11.504037) (xy 12.826107 -11.603572)
			(xy 12.721147 -11.69737) (xy 12.611093 -11.785135) (xy 12.496291 -11.866592) (xy 12.377103 -11.941483)
			(xy 12.253902 -12.009573) (xy 12.127078 -12.070649) (xy 11.997029 -12.124517) (xy 11.864164 -12.171009)
			(xy 11.728901 -12.209978) (xy 11.591666 -12.241301) (xy 11.45289 -12.26488) (xy 11.313011 -12.280641)
			(xy 11.172468 -12.288534) (xy 11.102086 -12.289028) (xy 1.999996 -12.289028) (xy 1.944227 -12.289537)
			(xy 1.833 -12.297872) (xy 1.722707 -12.314497) (xy 1.613965 -12.339317) (xy 1.507382 -12.372193)
			(xy 1.403554 -12.412943) (xy 1.353372 -12.43711) (xy 62.309756 -12.43711) (xy 62.310222 -12.396003)
			(xy 62.317806 -12.314139) (xy 62.332909 -12.233324) (xy 62.355404 -12.154247) (xy 62.385098 -12.077583)
			(xy 62.421737 -12.003984) (xy 62.46501 -11.93408) (xy 62.514548 -11.868466) (xy 62.569927 -11.807701)
			(xy 62.630676 -11.752305) (xy 62.696277 -11.70275) (xy 62.766169 -11.659457) (xy 62.839757 -11.622797)
			(xy 62.916414 -11.593082) (xy 62.995485 -11.570566) (xy 63.076295 -11.55544) (xy 63.158157 -11.547833)
			(xy 63.199264 -11.547348) (xy 63.243059 -11.547873) (xy 63.330225 -11.556491) (xy 63.416121 -11.573637)
			(xy 63.499915 -11.599145) (xy 63.580795 -11.632768) (xy 63.619634 -11.653012) (xy 63.6311 -11.65843)
			(xy 63.656428 -11.65843) (xy 63.667894 -11.653012) (xy 63.706738 -11.632781) (xy 63.787623 -11.599174)
			(xy 63.871416 -11.573672) (xy 63.957309 -11.556521) (xy 64.04447 -11.547888) (xy 64.088264 -11.547348)
			(xy 64.132059 -11.547873) (xy 64.219225 -11.556491) (xy 64.305121 -11.573637) (xy 64.388915 -11.599145)
			(xy 64.469795 -11.632768) (xy 64.508634 -11.653012) (xy 64.5201 -11.65843) (xy 64.545428 -11.65843)
			(xy 64.556894 -11.653012) (xy 64.595738 -11.632781) (xy 64.676623 -11.599174) (xy 64.760416 -11.573672)
			(xy 64.846309 -11.556521) (xy 64.93347 -11.547888) (xy 64.977264 -11.547348) (xy 65.021059 -11.547873)
			(xy 65.108225 -11.556491) (xy 65.194121 -11.573637) (xy 65.277915 -11.599145) (xy 65.358795 -11.632768)
			(xy 65.397634 -11.653012) (xy 65.4091 -11.65843) (xy 65.434428 -11.65843) (xy 65.445894 -11.653012)
			(xy 65.484738 -11.632781) (xy 65.565623 -11.599174) (xy 65.649416 -11.573672) (xy 65.735309 -11.556521)
			(xy 65.82247 -11.547888) (xy 65.866264 -11.547348) (xy 65.904554 -11.547763) (xy 65.980848 -11.554368)
			(xy 66.05629 -11.567515) (xy 66.130321 -11.587105) (xy 66.166492 -11.599672) (xy 66.174929 -11.602323)
			(xy 66.192599 -11.602323) (xy 66.201036 -11.599672) (xy 66.237216 -11.587135) (xy 66.311248 -11.56756)
			(xy 66.386687 -11.554411) (xy 66.462976 -11.547785) (xy 66.501264 -11.547348) (xy 66.54268 -11.547848)
			(xy 66.625149 -11.555593) (xy 66.706543 -11.570964) (xy 66.786158 -11.593827) (xy 66.863305 -11.623986)
			(xy 66.937318 -11.661178) (xy 66.972688 -11.68273) (xy 66.980074 -11.686987) (xy 66.996689 -11.690769)
			(xy 67.013625 -11.688896) (xy 67.021456 -11.685524) (xy 67.057233 -11.668994) (xy 67.131154 -11.641645)
			(xy 67.207206 -11.620946) (xy 67.284791 -11.607058) (xy 67.363301 -11.600092) (xy 67.40271 -11.599672)
			(xy 67.443826 -11.600089) (xy 67.525707 -11.607677) (xy 67.606539 -11.622789) (xy 67.685632 -11.645294)
			(xy 67.76231 -11.675001) (xy 67.835921 -11.711656) (xy 67.905835 -11.754947) (xy 67.971457 -11.804505)
			(xy 68.032226 -11.859906) (xy 68.087623 -11.920677) (xy 68.137178 -11.986301) (xy 68.180465 -12.056218)
			(xy 68.217117 -12.12983) (xy 68.24682 -12.20651) (xy 68.269321 -12.285604) (xy 68.284429 -12.366436)
			(xy 68.292013 -12.448318) (xy 68.292472 -12.489434) (xy 68.291907 -12.533047) (xy 68.283357 -12.619854)
			(xy 68.266352 -12.705408) (xy 68.241056 -12.788886) (xy 68.207711 -12.869488) (xy 68.195659 -12.892068)
			(xy 70.948547 -12.892068) (xy 70.948547 -12.837532) (xy 70.956309 -12.783551) (xy 70.971673 -12.731225)
			(xy 70.994328 -12.681617) (xy 71.023813 -12.635739) (xy 71.059526 -12.594524) (xy 71.100742 -12.558811)
			(xy 71.146621 -12.529327) (xy 71.196228 -12.506672) (xy 71.248555 -12.491308) (xy 71.302536 -12.483547)
			(xy 71.329804 -12.483084) (xy 72.193404 -12.483084) (xy 72.220676 -12.483479) (xy 72.274666 -12.491242)
			(xy 72.327001 -12.506609) (xy 72.376617 -12.529269) (xy 72.422503 -12.558758) (xy 72.463725 -12.594478)
			(xy 72.499444 -12.6357) (xy 72.528933 -12.681586) (xy 72.551592 -12.731202) (xy 72.566959 -12.783538)
			(xy 72.574721 -12.837528) (xy 72.574721 -12.892072) (xy 72.566959 -12.946062) (xy 72.551592 -12.998398)
			(xy 72.528933 -13.048014) (xy 72.499444 -13.0939) (xy 72.488173 -13.106908) (xy 191.037972 -13.106908)
			(xy 191.03849 -13.065179) (xy 191.046314 -12.98209) (xy 191.061883 -12.900098) (xy 191.085062 -12.819924)
			(xy 191.115646 -12.742273) (xy 191.153367 -12.667827) (xy 191.197893 -12.59724) (xy 191.248833 -12.531132)
			(xy 191.305739 -12.470085) (xy 191.368112 -12.414635) (xy 191.435403 -12.365269) (xy 191.507021 -12.32242)
			(xy 191.582336 -12.286466) (xy 191.660687 -12.257723) (xy 191.700912 -12.24661) (xy 191.713612 -12.243308)
			(xy 191.732408 -12.225274) (xy 191.765936 -12.117578) (xy 191.760348 -12.091924) (xy 191.751712 -12.082018)
			(xy 191.723476 -12.048682) (xy 191.672486 -11.977736) (xy 191.628113 -11.902474) (xy 191.590718 -11.823512)
			(xy 191.560607 -11.741496) (xy 191.538028 -11.657095) (xy 191.523163 -11.571) (xy 191.516135 -11.483915)
			(xy 191.517001 -11.39655) (xy 191.525753 -11.309621) (xy 191.542322 -11.223837) (xy 191.56657 -11.139901)
			(xy 191.5983 -11.058497) (xy 191.637253 -10.980292) (xy 191.683109 -10.905925) (xy 191.735495 -10.836003)
			(xy 191.793982 -10.771099) (xy 191.858092 -10.711742) (xy 191.927301 -10.658417) (xy 192.001043 -10.611562)
			(xy 192.078715 -10.571558) (xy 192.159684 -10.538733) (xy 192.243285 -10.513355) (xy 192.328838 -10.495631)
			(xy 192.415641 -10.485707) (xy 192.502986 -10.483662) (xy 192.590159 -10.489515) (xy 192.676446 -10.503218)
			(xy 192.761144 -10.524657) (xy 192.843559 -10.553659) (xy 192.923018 -10.589985) (xy 192.998871 -10.63334)
			(xy 193.070499 -10.683368) (xy 193.137315 -10.739661) (xy 193.198774 -10.801758) (xy 193.254374 -10.869153)
			(xy 193.303659 -10.941294) (xy 193.346227 -11.017591) (xy 193.381731 -11.097421) (xy 193.409879 -11.180131)
			(xy 193.430442 -11.265046) (xy 193.443252 -11.35147) (xy 193.448204 -11.438699) (xy 193.445257 -11.526018)
			(xy 193.434436 -11.612714) (xy 193.415829 -11.698079) (xy 193.389589 -11.781414) (xy 193.355929 -11.862038)
			(xy 193.315124 -11.939293) (xy 193.267509 -12.012547) (xy 193.213473 -12.081201) (xy 193.153457 -12.144694)
			(xy 193.121026 -12.173966) (xy 193.112347 -12.182457) (xy 193.103466 -12.205016) (xy 193.104008 -12.217146)
			(xy 193.112136 -12.298934) (xy 193.113935 -12.310868) (xy 193.126948 -12.331156) (xy 193.137028 -12.337796)
			(xy 193.137282 -12.33805) (xy 193.173525 -12.359702) (xy 193.242152 -12.408882) (xy 193.305811 -12.464344)
			(xy 193.363928 -12.525589) (xy 193.415979 -12.592065) (xy 193.461498 -12.663174) (xy 193.500073 -12.738277)
			(xy 193.531358 -12.816697) (xy 193.555071 -12.897729) (xy 193.570999 -12.980643) (xy 193.578999 -13.064693)
			(xy 193.579496 -13.106908) (xy 193.579055 -13.148019) (xy 193.571467 -13.22989) (xy 193.556355 -13.310712)
			(xy 193.533849 -13.389794) (xy 193.504141 -13.466462) (xy 193.467484 -13.540061) (xy 193.424192 -13.609963)
			(xy 193.374634 -13.675571) (xy 193.319232 -13.736326) (xy 193.25846 -13.791709) (xy 193.192836 -13.841247)
			(xy 193.122921 -13.884518) (xy 193.049311 -13.921151) (xy 192.972634 -13.950836) (xy 192.893545 -13.973317)
			(xy 192.812719 -13.988404) (xy 192.730845 -13.995968) (xy 192.689734 -13.996416) (xy 192.643339 -13.99582)
			(xy 192.551051 -13.986179) (xy 192.460267 -13.966987) (xy 192.371973 -13.938452) (xy 192.329308 -13.920216)
			(xy 192.319366 -13.91641) (xy 192.298102 -13.91641) (xy 192.28816 -13.920216) (xy 192.245553 -13.938427)
			(xy 192.157387 -13.966948) (xy 192.066733 -13.986143) (xy 191.974574 -13.995806) (xy 191.928242 -13.996416)
			(xy 191.927734 -13.996416) (xy 191.886626 -13.995955) (xy 191.804762 -13.988373) (xy 191.723946 -13.973271)
			(xy 191.644867 -13.950778) (xy 191.568202 -13.921085) (xy 191.494602 -13.884445) (xy 191.424697 -13.841172)
			(xy 191.359082 -13.791634) (xy 191.298317 -13.736254) (xy 191.24292 -13.675504) (xy 191.193365 -13.609903)
			(xy 191.150073 -13.540009) (xy 191.113413 -13.46642) (xy 191.083699 -13.389762) (xy 191.061184 -13.31069)
			(xy 191.04606 -13.229878) (xy 191.038456 -13.148015) (xy 191.037972 -13.106908) (xy 72.488173 -13.106908)
			(xy 72.463725 -13.135122) (xy 72.422503 -13.170842) (xy 72.376617 -13.200331) (xy 72.327001 -13.222991)
			(xy 72.274666 -13.238358) (xy 72.220676 -13.246121) (xy 72.193404 -13.246608) (xy 71.329804 -13.246608)
			(xy 71.302536 -13.246053) (xy 71.248555 -13.238292) (xy 71.196228 -13.222928) (xy 71.146621 -13.200273)
			(xy 71.100742 -13.170789) (xy 71.059526 -13.135076) (xy 71.023813 -13.093861) (xy 70.994328 -13.047983)
			(xy 70.971673 -12.998375) (xy 70.956309 -12.946049) (xy 70.948547 -12.892068) (xy 68.195659 -12.892068)
			(xy 68.166638 -12.946439) (xy 68.118231 -13.019001) (xy 68.062955 -13.086478) (xy 68.00134 -13.14822)
			(xy 67.933978 -13.203636) (xy 67.861516 -13.252193) (xy 67.823334 -13.273278) (xy 67.814055 -13.278811)
			(xy 67.800889 -13.295908) (xy 67.797934 -13.306298) (xy 67.787525 -13.3474) (xy 67.759881 -13.427561)
			(xy 67.724737 -13.504728) (xy 67.682409 -13.578201) (xy 67.633283 -13.647314) (xy 67.577804 -13.711439)
			(xy 67.516475 -13.769995) (xy 67.449854 -13.82245) (xy 67.378544 -13.868328) (xy 67.303192 -13.907213)
			(xy 67.224482 -13.938753) (xy 67.143129 -13.96266) (xy 67.05987 -13.978719) (xy 66.975461 -13.986784)
			(xy 66.933064 -13.987272) (xy 66.894775 -13.986847) (xy 66.818481 -13.980245) (xy 66.743038 -13.967101)
			(xy 66.669007 -13.947513) (xy 66.632836 -13.934948) (xy 66.624399 -13.932297) (xy 66.606729 -13.932297)
			(xy 66.598292 -13.934948) (xy 66.56211 -13.947478) (xy 66.488079 -13.967055) (xy 66.41264 -13.980205)
			(xy 66.336352 -13.986834) (xy 66.298064 -13.987272) (xy 66.254269 -13.986733) (xy 66.167104 -13.978118)
			(xy 66.081208 -13.960975) (xy 65.997414 -13.93547) (xy 65.916534 -13.90185) (xy 65.877694 -13.881608)
			(xy 65.866228 -13.87619) (xy 65.8409 -13.87619) (xy 65.829434 -13.881608) (xy 65.790581 -13.901822)
			(xy 65.709699 -13.935433) (xy 65.625908 -13.96094) (xy 65.540018 -13.978094) (xy 65.452857 -13.986731)
			(xy 65.409064 -13.987272) (xy 65.365269 -13.986733) (xy 65.278104 -13.978118) (xy 65.192208 -13.960975)
			(xy 65.108414 -13.93547) (xy 65.027534 -13.90185) (xy 64.988694 -13.881608) (xy 64.977228 -13.87619)
			(xy 64.9519 -13.87619) (xy 64.940434 -13.881608) (xy 64.901581 -13.901822) (xy 64.820699 -13.935433)
			(xy 64.736908 -13.96094) (xy 64.651018 -13.978094) (xy 64.563857 -13.986731) (xy 64.520064 -13.987272)
			(xy 64.476269 -13.986733) (xy 64.389104 -13.978118) (xy 64.303208 -13.960975) (xy 64.219414 -13.93547)
			(xy 64.138534 -13.90185) (xy 64.099694 -13.881608) (xy 64.088228 -13.87619) (xy 64.0629 -13.87619)
			(xy 64.051434 -13.881608) (xy 64.012581 -13.901822) (xy 63.931699 -13.935433) (xy 63.847908 -13.96094)
			(xy 63.762018 -13.978094) (xy 63.674857 -13.986731) (xy 63.631064 -13.987272) (xy 63.588804 -13.98679)
			(xy 63.504665 -13.978779) (xy 63.421665 -13.962822) (xy 63.340553 -13.939064) (xy 63.26206 -13.907718)
			(xy 63.186895 -13.869068) (xy 63.115735 -13.823463) (xy 63.049222 -13.771312) (xy 62.987956 -13.713088)
			(xy 62.93249 -13.649314) (xy 62.883323 -13.580566) (xy 62.840899 -13.507464) (xy 62.805601 -13.430668)
			(xy 62.777747 -13.35087) (xy 62.757589 -13.268789) (xy 62.750954 -13.22705) (xy 62.748768 -13.216225)
			(xy 62.736658 -13.197787) (xy 62.727586 -13.19149) (xy 62.693115 -13.169417) (xy 62.628004 -13.119803)
			(xy 62.567725 -13.064419) (xy 62.512788 -13.003732) (xy 62.463657 -12.938255) (xy 62.420747 -12.868543)
			(xy 62.384422 -12.795185) (xy 62.354987 -12.7188) (xy 62.332693 -12.640034) (xy 62.317728 -12.559554)
			(xy 62.310218 -12.47804) (xy 62.309756 -12.43711) (xy 1.353372 -12.43711) (xy 1.303061 -12.461339)
			(xy 1.206466 -12.517108) (xy 1.114309 -12.579941) (xy 1.027105 -12.649484) (xy 0.945341 -12.72535)
			(xy 0.869476 -12.807114) (xy 0.801731 -12.892064) (xy 56.95347 -12.892064) (xy 56.95347 -12.837536)
			(xy 56.96123 -12.783562) (xy 56.976591 -12.731243) (xy 56.999242 -12.681641) (xy 57.02872 -12.635768)
			(xy 57.064426 -12.594556) (xy 57.105634 -12.558845) (xy 57.151504 -12.529362) (xy 57.201103 -12.506706)
			(xy 57.253421 -12.491339) (xy 57.307394 -12.483573) (xy 57.334658 -12.483084) (xy 58.198258 -12.483084)
			(xy 58.225534 -12.483453) (xy 58.279532 -12.491211) (xy 58.331876 -12.506575) (xy 58.381501 -12.529233)
			(xy 58.427395 -12.558723) (xy 58.468625 -12.594445) (xy 58.504351 -12.635671) (xy 58.533847 -12.681562)
			(xy 58.55651 -12.731184) (xy 58.57188 -12.783527) (xy 58.579644 -12.837524) (xy 58.579644 -12.892076)
			(xy 58.57188 -12.946073) (xy 58.55651 -12.998416) (xy 58.533847 -13.048037) (xy 58.504351 -13.093929)
			(xy 58.468625 -13.135155) (xy 58.427395 -13.170877) (xy 58.381501 -13.200367) (xy 58.331876 -13.223025)
			(xy 58.279532 -13.238389) (xy 58.225534 -13.246147) (xy 58.198258 -13.246608) (xy 57.334658 -13.246608)
			(xy 57.307394 -13.246027) (xy 57.253421 -13.238261) (xy 57.201103 -13.222894) (xy 57.151504 -13.200238)
			(xy 57.105634 -13.170755) (xy 57.064426 -13.135044) (xy 57.02872 -13.093832) (xy 56.999242 -13.047959)
			(xy 56.976591 -12.998357) (xy 56.96123 -12.946038) (xy 56.95347 -12.892064) (xy 0.801731 -12.892064)
			(xy 0.799933 -12.894318) (xy 0.737102 -12.986476) (xy 0.681333 -13.083072) (xy 0.632939 -13.183565)
			(xy 0.59219 -13.287393) (xy 0.559313 -13.393977) (xy 0.534494 -13.502719) (xy 0.517871 -13.613012)
			(xy 0.509536 -13.724239) (xy 0.509016 -13.780008) (xy 0.509016 -16.5207) (xy 76.28834 -16.5207) (xy 76.29237 -16.436094)
			(xy 76.304425 -16.352254) (xy 76.324394 -16.26994) (xy 76.352098 -16.189896) (xy 76.387284 -16.112849)
			(xy 76.429635 -16.039495) (xy 76.478768 -15.970499) (xy 76.534236 -15.906485) (xy 76.595538 -15.848035)
			(xy 76.662118 -15.795676) (xy 76.733375 -15.749883) (xy 76.808661 -15.711071) (xy 76.887296 -15.679591)
			(xy 76.968567 -15.655728) (xy 77.051738 -15.639698) (xy 77.136057 -15.631648) (xy 77.178408 -15.63116)
			(xy 77.178916 -15.63116) (xy 77.224101 -15.631724) (xy 77.314005 -15.640873) (xy 77.402518 -15.659097)
			(xy 77.488725 -15.686205) (xy 77.530452 -15.70355) (xy 77.539034 -15.706862) (xy 77.557395 -15.707764)
			(xy 77.566266 -15.705328) (xy 77.610936 -15.69133) (xy 77.702468 -15.671687) (xy 77.795557 -15.661772)
			(xy 77.842364 -15.661132) (xy 77.84338 -15.661132) (xy 77.885732 -15.661539) (xy 77.970052 -15.669589)
			(xy 78.053225 -15.685618) (xy 78.134498 -15.70948) (xy 78.213134 -15.74096) (xy 78.288422 -15.779772)
			(xy 78.35968 -15.825565) (xy 78.426262 -15.877924) (xy 78.487566 -15.936376) (xy 78.543035 -16.00039)
			(xy 78.592169 -16.069387) (xy 78.634521 -16.142742) (xy 78.669709 -16.219791) (xy 78.697413 -16.299835)
			(xy 78.717383 -16.382151) (xy 78.722326 -16.416528) (xy 191.571372 -16.416528) (xy 191.571784 -16.378238)
			(xy 191.57839 -16.301944) (xy 191.591537 -16.226502) (xy 191.611129 -16.152471) (xy 191.623696 -16.1163)
			(xy 191.626331 -16.10786) (xy 191.62634 -16.090193) (xy 191.623696 -16.081756) (xy 191.611158 -16.045577)
			(xy 191.591583 -15.971544) (xy 191.578434 -15.896105) (xy 191.571809 -15.819816) (xy 191.571372 -15.781528)
			(xy 191.571879 -15.740418) (xy 191.579464 -15.65855) (xy 191.594572 -15.577731) (xy 191.617074 -15.498651)
			(xy 191.646778 -15.421985) (xy 191.68343 -15.348387) (xy 191.726718 -15.278486) (xy 191.776272 -15.212878)
			(xy 191.831669 -15.152124) (xy 191.892437 -15.096741) (xy 191.958056 -15.047202) (xy 192.027967 -15.00393)
			(xy 192.101573 -14.967295) (xy 192.178246 -14.937609) (xy 192.257331 -14.915125) (xy 192.338154 -14.900036)
			(xy 192.420024 -14.89247) (xy 192.461134 -14.89202) (xy 192.499451 -14.892376) (xy 192.575804 -14.898912)
			(xy 192.651311 -14.912) (xy 192.72541 -14.931543) (xy 192.761616 -14.94409) (xy 192.769932 -14.946676)
			(xy 192.787336 -14.946676) (xy 192.795652 -14.94409) (xy 192.831863 -14.931562) (xy 192.905965 -14.912041)
			(xy 192.981469 -14.898959) (xy 193.057819 -14.892413) (xy 193.096134 -14.89202) (xy 193.134451 -14.892376)
			(xy 193.210804 -14.898912) (xy 193.286311 -14.912) (xy 193.36041 -14.931543) (xy 193.396616 -14.94409)
			(xy 193.404932 -14.946676) (xy 193.422336 -14.946676) (xy 193.430652 -14.94409) (xy 193.466772 -14.93159)
			(xy 193.540685 -14.912102) (xy 193.615997 -14.899021) (xy 193.692153 -14.892442) (xy 193.730372 -14.89202)
			(xy 193.731134 -14.89202) (xy 193.772241 -14.89248) (xy 193.854104 -14.900067) (xy 193.934917 -14.915174)
			(xy 194.013993 -14.937671) (xy 194.090656 -14.967367) (xy 194.164253 -15.004008) (xy 194.234156 -15.047282)
			(xy 194.299769 -15.09682) (xy 194.360532 -15.152199) (xy 194.415928 -15.212948) (xy 194.465484 -15.278547)
			(xy 194.508776 -15.348439) (xy 194.545437 -15.422026) (xy 194.575153 -15.498681) (xy 194.597672 -15.577751)
			(xy 194.6128 -15.658561) (xy 194.620409 -15.740421) (xy 194.620896 -15.781528) (xy 194.620451 -15.819809)
			(xy 194.613795 -15.896082) (xy 194.600605 -15.971499) (xy 194.591178 -16.008604) (xy 194.588893 -16.019174)
			(xy 194.592456 -16.040487) (xy 194.598036 -16.049752) (xy 194.621836 -16.08633) (xy 194.662956 -16.163308)
			(xy 194.696348 -16.24394) (xy 194.721691 -16.327453) (xy 194.738741 -16.413043) (xy 194.747336 -16.499892)
			(xy 194.747896 -16.543528) (xy 194.747474 -16.584639) (xy 194.739884 -16.666511) (xy 194.72477 -16.747333)
			(xy 194.702263 -16.826416) (xy 194.672553 -16.903083) (xy 194.635895 -16.976682) (xy 194.592602 -17.046584)
			(xy 194.543042 -17.112192) (xy 194.487639 -17.172947) (xy 194.426866 -17.22833) (xy 194.361241 -17.277868)
			(xy 194.291325 -17.321138) (xy 194.217714 -17.357772) (xy 194.141037 -17.387456) (xy 194.061947 -17.409938)
			(xy 193.98112 -17.425024) (xy 193.899246 -17.432588) (xy 193.858134 -17.433036) (xy 193.814503 -17.432505)
			(xy 193.727659 -17.42397) (xy 193.642069 -17.40697) (xy 193.558556 -17.381667) (xy 193.477923 -17.348306)
			(xy 193.400945 -17.307207) (xy 193.364358 -17.28343) (xy 193.355108 -17.277824) (xy 193.333785 -17.274289)
			(xy 193.32321 -17.276572) (xy 193.286097 -17.285942) (xy 193.210677 -17.299046) (xy 193.134409 -17.305624)
			(xy 193.096134 -17.306036) (xy 193.057818 -17.305656) (xy 192.981465 -17.299127) (xy 192.905958 -17.286046)
			(xy 192.831859 -17.26651) (xy 192.795652 -17.253966) (xy 192.787336 -17.25138) (xy 192.769932 -17.25138)
			(xy 192.761616 -17.253966) (xy 192.725489 -17.266445) (xy 192.651578 -17.285939) (xy 192.576269 -17.299026)
			(xy 192.500115 -17.305611) (xy 192.461896 -17.306036) (xy 192.461134 -17.306036) (xy 192.420027 -17.305555)
			(xy 192.338163 -17.297973) (xy 192.257348 -17.282872) (xy 192.178271 -17.260379) (xy 192.101606 -17.230687)
			(xy 192.028008 -17.194048) (xy 191.958103 -17.150776) (xy 191.892489 -17.10124) (xy 191.831724 -17.045861)
			(xy 191.776328 -16.985113) (xy 191.726772 -16.919513) (xy 191.683479 -16.849621) (xy 191.646819 -16.776033)
			(xy 191.617104 -16.699377) (xy 191.594588 -16.620307) (xy 191.579463 -16.539496) (xy 191.571857 -16.457635)
			(xy 191.571372 -16.416528) (xy 78.722326 -16.416528) (xy 78.729438 -16.465992) (xy 78.733468 -16.5506)
			(xy 78.729438 -16.635208) (xy 78.717383 -16.719049) (xy 78.697413 -16.801365) (xy 78.669709 -16.881409)
			(xy 78.634521 -16.958458) (xy 78.592169 -17.031813) (xy 78.543035 -17.10081) (xy 78.487566 -17.164824)
			(xy 78.426262 -17.223276) (xy 78.35968 -17.275635) (xy 78.288422 -17.321428) (xy 78.213134 -17.36024)
			(xy 78.134498 -17.39172) (xy 78.053225 -17.415582) (xy 77.970052 -17.431611) (xy 77.885732 -17.439661)
			(xy 77.84338 -17.440148) (xy 77.842872 -17.440148) (xy 77.797687 -17.439588) (xy 77.707782 -17.430437)
			(xy 77.61927 -17.412213) (xy 77.533063 -17.385103) (xy 77.491336 -17.367758) (xy 77.482756 -17.36444)
			(xy 77.464393 -17.363542) (xy 77.455522 -17.36598) (xy 77.410853 -17.379982) (xy 77.319321 -17.399623)
			(xy 77.226231 -17.409537) (xy 77.179424 -17.410176) (xy 77.178408 -17.410176) (xy 77.136057 -17.409752)
			(xy 77.051738 -17.401702) (xy 76.968567 -17.385672) (xy 76.887296 -17.361809) (xy 76.808661 -17.330329)
			(xy 76.733375 -17.291517) (xy 76.662118 -17.245724) (xy 76.595538 -17.193365) (xy 76.534236 -17.134915)
			(xy 76.478768 -17.070901) (xy 76.429635 -17.001905) (xy 76.387284 -16.928551) (xy 76.352098 -16.851504)
			(xy 76.324394 -16.77146) (xy 76.304425 -16.689146) (xy 76.29237 -16.605306) (xy 76.28834 -16.5207)
			(xy 0.509016 -16.5207) (xy 0.509016 -17.639611) (xy 15.152858 -17.639611) (xy 15.152858 -17.585109)
			(xy 15.160614 -17.531161) (xy 15.175969 -17.478867) (xy 15.19861 -17.42929) (xy 15.228076 -17.383439)
			(xy 15.263768 -17.342249) (xy 15.304958 -17.306558) (xy 15.350808 -17.277091) (xy 15.400385 -17.25445)
			(xy 15.452679 -17.239095) (xy 15.506627 -17.231338) (xy 15.533878 -17.230852) (xy 16.397478 -17.230852)
			(xy 16.424731 -17.231315) (xy 16.478682 -17.239072) (xy 16.53098 -17.254428) (xy 16.580561 -17.27707)
			(xy 16.626414 -17.306538) (xy 16.667607 -17.342232) (xy 16.703301 -17.383424) (xy 16.732769 -17.429278)
			(xy 16.755412 -17.478858) (xy 16.770768 -17.531156) (xy 16.778525 -17.585107) (xy 16.778525 -17.639611)
			(xy 20.740858 -17.639611) (xy 20.740858 -17.585109) (xy 20.748614 -17.531161) (xy 20.763969 -17.478867)
			(xy 20.78661 -17.42929) (xy 20.816076 -17.383439) (xy 20.851768 -17.342249) (xy 20.892958 -17.306558)
			(xy 20.938808 -17.277091) (xy 20.988385 -17.25445) (xy 21.040679 -17.239095) (xy 21.094627 -17.231338)
			(xy 21.121878 -17.230852) (xy 21.985478 -17.230852) (xy 22.012729 -17.231394) (xy 22.066677 -17.239147)
			(xy 22.118972 -17.2545) (xy 22.168549 -17.277139) (xy 22.2144 -17.306603) (xy 22.255591 -17.342293)
			(xy 22.291284 -17.383482) (xy 22.320751 -17.429331) (xy 22.343392 -17.478908) (xy 22.358748 -17.531202)
			(xy 22.366505 -17.585149) (xy 22.366505 -17.639651) (xy 22.366505 -17.639653) (xy 26.328838 -17.639653)
			(xy 26.328838 -17.585147) (xy 26.336595 -17.531195) (xy 26.35195 -17.478897) (xy 26.374592 -17.429316)
			(xy 26.404059 -17.383462) (xy 26.439752 -17.342268) (xy 26.480944 -17.306573) (xy 26.526797 -17.277103)
			(xy 26.576376 -17.254458) (xy 26.628674 -17.239099) (xy 26.682625 -17.231339) (xy 26.709878 -17.230852)
			(xy 27.573478 -17.230852) (xy 27.600729 -17.231394) (xy 27.654677 -17.239147) (xy 27.706972 -17.2545)
			(xy 27.756549 -17.277139) (xy 27.8024 -17.306603) (xy 27.843591 -17.342293) (xy 27.879284 -17.383482)
			(xy 27.908751 -17.429331) (xy 27.931392 -17.478908) (xy 27.946748 -17.531202) (xy 27.954505 -17.585149)
			(xy 27.954505 -17.639651) (xy 27.954402 -17.640366) (xy 31.915646 -17.640366) (xy 31.915646 -17.585834)
			(xy 31.923406 -17.531857) (xy 31.938769 -17.479533) (xy 31.961421 -17.429928) (xy 31.990902 -17.384052)
			(xy 32.026611 -17.342838) (xy 32.067822 -17.307125) (xy 32.113695 -17.277639) (xy 32.163298 -17.254982)
			(xy 32.21562 -17.239615) (xy 32.269596 -17.231849) (xy 32.296862 -17.23136) (xy 33.160462 -17.23136)
			(xy 33.187736 -17.231777) (xy 33.24173 -17.239535) (xy 33.294071 -17.254899) (xy 33.343691 -17.277556)
			(xy 33.389583 -17.307044) (xy 33.43081 -17.342764) (xy 33.466533 -17.383987) (xy 33.496026 -17.429875)
			(xy 33.518688 -17.479494) (xy 33.534057 -17.531832) (xy 33.54182 -17.585826) (xy 33.54182 -17.640366)
			(xy 37.503646 -17.640366) (xy 37.503646 -17.585834) (xy 37.511406 -17.531857) (xy 37.526769 -17.479533)
			(xy 37.549421 -17.429928) (xy 37.578902 -17.384052) (xy 37.614611 -17.342838) (xy 37.655822 -17.307125)
			(xy 37.701695 -17.277639) (xy 37.751298 -17.254982) (xy 37.80362 -17.239615) (xy 37.857596 -17.231849)
			(xy 37.884862 -17.23136) (xy 38.748462 -17.23136) (xy 38.775736 -17.231777) (xy 38.82973 -17.239535)
			(xy 38.882071 -17.254899) (xy 38.931691 -17.277556) (xy 38.977583 -17.307044) (xy 39.01881 -17.342764)
			(xy 39.054533 -17.383987) (xy 39.084026 -17.429875) (xy 39.106688 -17.479494) (xy 39.122057 -17.531832)
			(xy 39.12982 -17.585826) (xy 39.12982 -17.639654) (xy 43.398638 -17.639654) (xy 43.398638 -17.585146)
			(xy 43.406395 -17.531193) (xy 43.421751 -17.478894) (xy 43.444395 -17.429312) (xy 43.473863 -17.383457)
			(xy 43.509558 -17.342262) (xy 43.550752 -17.306567) (xy 43.596606 -17.277097) (xy 43.646188 -17.254454)
			(xy 43.698487 -17.239096) (xy 43.75244 -17.231338) (xy 43.779694 -17.230852) (xy 44.643294 -17.230852)
			(xy 44.670544 -17.231395) (xy 44.72449 -17.23915) (xy 44.776783 -17.254504) (xy 44.826359 -17.277144)
			(xy 44.872208 -17.306609) (xy 44.913397 -17.342299) (xy 44.949088 -17.383487) (xy 44.978553 -17.429336)
			(xy 45.001194 -17.478911) (xy 45.016548 -17.531204) (xy 45.024305 -17.58515) (xy 45.024305 -17.63965)
			(xy 45.024304 -17.639654) (xy 48.986638 -17.639654) (xy 48.986638 -17.585146) (xy 48.994395 -17.531193)
			(xy 49.009751 -17.478894) (xy 49.032395 -17.429312) (xy 49.061863 -17.383457) (xy 49.097558 -17.342262)
			(xy 49.138752 -17.306567) (xy 49.184606 -17.277097) (xy 49.234188 -17.254454) (xy 49.286487 -17.239096)
			(xy 49.34044 -17.231338) (xy 49.367694 -17.230852) (xy 50.231294 -17.230852) (xy 50.258544 -17.231395)
			(xy 50.31249 -17.23915) (xy 50.364783 -17.254504) (xy 50.414359 -17.277144) (xy 50.460208 -17.306609)
			(xy 50.501397 -17.342299) (xy 50.537088 -17.383487) (xy 50.566553 -17.429336) (xy 50.589194 -17.478911)
			(xy 50.604548 -17.531204) (xy 50.612305 -17.58515) (xy 50.612305 -17.63965) (xy 50.612201 -17.64037)
			(xy 54.607423 -17.64037) (xy 54.607423 -17.58583) (xy 54.615186 -17.531845) (xy 54.630552 -17.479514)
			(xy 54.653209 -17.429903) (xy 54.682696 -17.384021) (xy 54.718413 -17.342803) (xy 54.759632 -17.307088)
			(xy 54.805515 -17.277602) (xy 54.855127 -17.254947) (xy 54.907459 -17.239583) (xy 54.961444 -17.231822)
			(xy 54.988714 -17.23136) (xy 55.852314 -17.23136) (xy 55.879584 -17.231803) (xy 55.933569 -17.239567)
			(xy 55.9859 -17.254935) (xy 56.035512 -17.277593) (xy 56.081393 -17.307081) (xy 56.122612 -17.342798)
			(xy 56.158328 -17.384018) (xy 56.187814 -17.429901) (xy 56.21047 -17.479513) (xy 56.225836 -17.531844)
			(xy 56.233598 -17.58583) (xy 56.233598 -17.64037) (xy 56.225836 -17.694356) (xy 56.21047 -17.746687)
			(xy 56.187814 -17.796299) (xy 56.158328 -17.842182) (xy 56.122612 -17.883402) (xy 56.081393 -17.919119)
			(xy 56.035512 -17.948607) (xy 55.9859 -17.971265) (xy 55.933569 -17.986633) (xy 55.879584 -17.994397)
			(xy 55.852314 -17.994884) (xy 54.988714 -17.994884) (xy 54.961444 -17.994378) (xy 54.907459 -17.986617)
			(xy 54.855127 -17.971253) (xy 54.805515 -17.948598) (xy 54.759632 -17.919112) (xy 54.718413 -17.883397)
			(xy 54.682696 -17.842179) (xy 54.653209 -17.796297) (xy 54.630552 -17.746686) (xy 54.615186 -17.694355)
			(xy 54.607423 -17.64037) (xy 50.612201 -17.64037) (xy 50.604548 -17.693596) (xy 50.589194 -17.745889)
			(xy 50.566553 -17.795464) (xy 50.537088 -17.841313) (xy 50.501397 -17.882501) (xy 50.460208 -17.918191)
			(xy 50.414359 -17.947656) (xy 50.364783 -17.970296) (xy 50.31249 -17.98565) (xy 50.258544 -17.993405)
			(xy 50.231294 -17.993868) (xy 49.367694 -17.993868) (xy 49.34044 -17.993462) (xy 49.286487 -17.985704)
			(xy 49.234188 -17.970346) (xy 49.184606 -17.947703) (xy 49.138752 -17.918233) (xy 49.097558 -17.882538)
			(xy 49.061863 -17.841343) (xy 49.032395 -17.795488) (xy 49.009751 -17.745906) (xy 48.994395 -17.693607)
			(xy 48.986638 -17.639654) (xy 45.024304 -17.639654) (xy 45.016548 -17.693596) (xy 45.001194 -17.745889)
			(xy 44.978553 -17.795464) (xy 44.949088 -17.841313) (xy 44.913397 -17.882501) (xy 44.872208 -17.918191)
			(xy 44.826359 -17.947656) (xy 44.776783 -17.970296) (xy 44.72449 -17.98565) (xy 44.670544 -17.993405)
			(xy 44.643294 -17.993868) (xy 43.779694 -17.993868) (xy 43.75244 -17.993462) (xy 43.698487 -17.985704)
			(xy 43.646188 -17.970346) (xy 43.596606 -17.947703) (xy 43.550752 -17.918233) (xy 43.509558 -17.882538)
			(xy 43.473863 -17.841343) (xy 43.444395 -17.795488) (xy 43.421751 -17.745906) (xy 43.406395 -17.693607)
			(xy 43.398638 -17.639654) (xy 39.12982 -17.639654) (xy 39.12982 -17.640374) (xy 39.122057 -17.694368)
			(xy 39.106688 -17.746706) (xy 39.084026 -17.796325) (xy 39.054533 -17.842213) (xy 39.01881 -17.883436)
			(xy 38.977583 -17.919156) (xy 38.931691 -17.948644) (xy 38.882071 -17.971301) (xy 38.82973 -17.986665)
			(xy 38.775736 -17.994423) (xy 38.748462 -17.994884) (xy 37.884862 -17.994884) (xy 37.857596 -17.994351)
			(xy 37.80362 -17.986585) (xy 37.751298 -17.971218) (xy 37.701695 -17.948561) (xy 37.655822 -17.919075)
			(xy 37.614611 -17.883362) (xy 37.578902 -17.842148) (xy 37.549421 -17.796272) (xy 37.526769 -17.746667)
			(xy 37.511406 -17.694343) (xy 37.503646 -17.640366) (xy 33.54182 -17.640366) (xy 33.54182 -17.640374)
			(xy 33.534057 -17.694368) (xy 33.518688 -17.746706) (xy 33.496026 -17.796325) (xy 33.466533 -17.842213)
			(xy 33.43081 -17.883436) (xy 33.389583 -17.919156) (xy 33.343691 -17.948644) (xy 33.294071 -17.971301)
			(xy 33.24173 -17.986665) (xy 33.187736 -17.994423) (xy 33.160462 -17.994884) (xy 32.296862 -17.994884)
			(xy 32.269596 -17.994351) (xy 32.21562 -17.986585) (xy 32.163298 -17.971218) (xy 32.113695 -17.948561)
			(xy 32.067822 -17.919075) (xy 32.026611 -17.883362) (xy 31.990902 -17.842148) (xy 31.961421 -17.796272)
			(xy 31.938769 -17.746667) (xy 31.923406 -17.694343) (xy 31.915646 -17.640366) (xy 27.954402 -17.640366)
			(xy 27.946748 -17.693598) (xy 27.931392 -17.745892) (xy 27.908751 -17.795469) (xy 27.879284 -17.841318)
			(xy 27.843591 -17.882507) (xy 27.8024 -17.918197) (xy 27.756549 -17.947661) (xy 27.706972 -17.9703)
			(xy 27.654677 -17.985653) (xy 27.600729 -17.993406) (xy 27.573478 -17.993868) (xy 26.709878 -17.993868)
			(xy 26.682625 -17.993461) (xy 26.628674 -17.985701) (xy 26.576376 -17.970342) (xy 26.526797 -17.947697)
			(xy 26.480944 -17.918227) (xy 26.439752 -17.882532) (xy 26.404059 -17.841338) (xy 26.374592 -17.795484)
			(xy 26.35195 -17.745903) (xy 26.336595 -17.693605) (xy 26.328838 -17.639653) (xy 22.366505 -17.639653)
			(xy 22.358748 -17.693598) (xy 22.343392 -17.745892) (xy 22.320751 -17.795469) (xy 22.291284 -17.841318)
			(xy 22.255591 -17.882507) (xy 22.2144 -17.918197) (xy 22.168549 -17.947661) (xy 22.118972 -17.9703)
			(xy 22.066677 -17.985653) (xy 22.012729 -17.993406) (xy 21.985478 -17.993868) (xy 21.121878 -17.993868)
			(xy 21.094627 -17.993382) (xy 21.040679 -17.985625) (xy 20.988385 -17.97027) (xy 20.938808 -17.947629)
			(xy 20.892958 -17.918162) (xy 20.851768 -17.882471) (xy 20.816076 -17.841281) (xy 20.78661 -17.79543)
			(xy 20.763969 -17.745853) (xy 20.748614 -17.693559) (xy 20.740858 -17.639611) (xy 16.778525 -17.639611)
			(xy 16.778525 -17.639613) (xy 16.770768 -17.693564) (xy 16.755412 -17.745862) (xy 16.732769 -17.795442)
			(xy 16.703301 -17.841296) (xy 16.667607 -17.882488) (xy 16.626414 -17.918182) (xy 16.580561 -17.94765)
			(xy 16.53098 -17.970292) (xy 16.478682 -17.985648) (xy 16.424731 -17.993405) (xy 16.397478 -17.993868)
			(xy 15.533878 -17.993868) (xy 15.506627 -17.993382) (xy 15.452679 -17.985625) (xy 15.400385 -17.97027)
			(xy 15.350808 -17.947629) (xy 15.304958 -17.918162) (xy 15.263768 -17.882471) (xy 15.228076 -17.841281)
			(xy 15.19861 -17.79543) (xy 15.175969 -17.745853) (xy 15.160614 -17.693559) (xy 15.152858 -17.639611)
			(xy 0.509016 -17.639611) (xy 0.509016 -19.164391) (xy 17.945563 -19.164391) (xy 17.945563 -19.109849)
			(xy 17.953326 -19.055862) (xy 17.968692 -19.00353) (xy 17.99135 -18.953917) (xy 18.020837 -18.908033)
			(xy 18.056555 -18.866813) (xy 18.097775 -18.831096) (xy 18.143658 -18.801609) (xy 18.193272 -18.778951)
			(xy 18.245604 -18.763585) (xy 18.299591 -18.755823) (xy 18.326862 -18.75536) (xy 19.190462 -18.75536)
			(xy 19.217731 -18.755843) (xy 19.271715 -18.763605) (xy 19.324045 -18.77897) (xy 19.373655 -18.801627)
			(xy 19.419536 -18.831113) (xy 19.460753 -18.866828) (xy 19.496469 -18.908046) (xy 19.525954 -18.953927)
			(xy 19.548611 -19.003537) (xy 19.563976 -19.055867) (xy 19.571738 -19.109851) (xy 19.571738 -19.163653)
			(xy 23.534838 -19.163653) (xy 23.534838 -19.109147) (xy 23.542595 -19.055195) (xy 23.55795 -19.002897)
			(xy 23.580592 -18.953316) (xy 23.610059 -18.907462) (xy 23.645752 -18.866268) (xy 23.686944 -18.830573)
			(xy 23.732797 -18.801103) (xy 23.782376 -18.778458) (xy 23.834674 -18.763099) (xy 23.888625 -18.755339)
			(xy 23.915878 -18.754852) (xy 24.779478 -18.754852) (xy 24.806729 -18.755394) (xy 24.860677 -18.763147)
			(xy 24.912972 -18.7785) (xy 24.962549 -18.801139) (xy 25.0084 -18.830603) (xy 25.049591 -18.866293)
			(xy 25.085284 -18.907482) (xy 25.114751 -18.953331) (xy 25.137392 -19.002908) (xy 25.152748 -19.055202)
			(xy 25.160505 -19.109149) (xy 25.160505 -19.163651) (xy 25.160505 -19.163653) (xy 29.122838 -19.163653)
			(xy 29.122838 -19.109147) (xy 29.130595 -19.055195) (xy 29.14595 -19.002897) (xy 29.168592 -18.953316)
			(xy 29.198059 -18.907462) (xy 29.233752 -18.866268) (xy 29.274944 -18.830573) (xy 29.320797 -18.801103)
			(xy 29.370376 -18.778458) (xy 29.422674 -18.763099) (xy 29.476625 -18.755339) (xy 29.503878 -18.754852)
			(xy 30.367478 -18.754852) (xy 30.394729 -18.755394) (xy 30.448677 -18.763147) (xy 30.500972 -18.7785)
			(xy 30.550549 -18.801139) (xy 30.5964 -18.830603) (xy 30.637591 -18.866293) (xy 30.673284 -18.907482)
			(xy 30.702751 -18.953331) (xy 30.725392 -19.002908) (xy 30.740748 -19.055202) (xy 30.748505 -19.109149)
			(xy 30.748505 -19.163651) (xy 30.748505 -19.163653) (xy 34.710838 -19.163653) (xy 34.710838 -19.109147)
			(xy 34.718595 -19.055195) (xy 34.73395 -19.002897) (xy 34.756592 -18.953316) (xy 34.786059 -18.907462)
			(xy 34.821752 -18.866268) (xy 34.862944 -18.830573) (xy 34.908797 -18.801103) (xy 34.958376 -18.778458)
			(xy 35.010674 -18.763099) (xy 35.064625 -18.755339) (xy 35.091878 -18.754852) (xy 35.955478 -18.754852)
			(xy 35.982729 -18.755394) (xy 36.036677 -18.763147) (xy 36.088972 -18.7785) (xy 36.138549 -18.801139)
			(xy 36.1844 -18.830603) (xy 36.225591 -18.866293) (xy 36.261284 -18.907482) (xy 36.290751 -18.953331)
			(xy 36.313392 -19.002908) (xy 36.328748 -19.055202) (xy 36.336505 -19.109149) (xy 36.336505 -19.163651)
			(xy 36.336505 -19.163654) (xy 40.604638 -19.163654) (xy 40.604638 -19.109146) (xy 40.612395 -19.055193)
			(xy 40.627751 -19.002894) (xy 40.650395 -18.953312) (xy 40.679863 -18.907457) (xy 40.715558 -18.866262)
			(xy 40.756752 -18.830567) (xy 40.802606 -18.801097) (xy 40.852188 -18.778454) (xy 40.904487 -18.763096)
			(xy 40.95844 -18.755338) (xy 40.985694 -18.754852) (xy 41.849294 -18.754852) (xy 41.876544 -18.755395)
			(xy 41.93049 -18.76315) (xy 41.982783 -18.778504) (xy 42.032359 -18.801144) (xy 42.078208 -18.830609)
			(xy 42.119397 -18.866299) (xy 42.155088 -18.907487) (xy 42.184553 -18.953336) (xy 42.207194 -19.002911)
			(xy 42.222548 -19.055204) (xy 42.230305 -19.10915) (xy 42.230305 -19.16365) (xy 42.230202 -19.164367)
			(xy 46.191446 -19.164367) (xy 46.191446 -19.109833) (xy 46.199207 -19.055855) (xy 46.21457 -19.00353)
			(xy 46.237224 -18.953924) (xy 46.266706 -18.908047) (xy 46.302417 -18.866832) (xy 46.343629 -18.831119)
			(xy 46.389505 -18.801634) (xy 46.439109 -18.778978) (xy 46.491433 -18.763612) (xy 46.545411 -18.755848)
			(xy 46.572678 -18.75536) (xy 47.436278 -18.75536) (xy 47.463552 -18.755778) (xy 47.517544 -18.763538)
			(xy 47.569882 -18.778903) (xy 47.619501 -18.801561) (xy 47.66539 -18.83105) (xy 47.706615 -18.866769)
			(xy 47.742337 -18.907992) (xy 47.771828 -18.95388) (xy 47.794489 -19.003497) (xy 47.809857 -19.055835)
			(xy 47.81762 -19.109826) (xy 47.81762 -19.163657) (xy 51.814615 -19.163657) (xy 51.814615 -19.109143)
			(xy 51.822374 -19.055184) (xy 51.837733 -19.002878) (xy 51.86038 -18.95329) (xy 51.889854 -18.907431)
			(xy 51.925554 -18.866233) (xy 51.966755 -18.830536) (xy 52.012617 -18.801065) (xy 52.062206 -18.778422)
			(xy 52.114513 -18.763067) (xy 52.168473 -18.755313) (xy 52.19573 -18.754852) (xy 53.05933 -18.754852)
			(xy 53.086577 -18.75542) (xy 53.140516 -18.763179) (xy 53.192801 -18.778535) (xy 53.24237 -18.801176)
			(xy 53.288211 -18.83064) (xy 53.329394 -18.866328) (xy 53.365078 -18.907513) (xy 53.394538 -18.953357)
			(xy 53.417175 -19.002927) (xy 53.432527 -19.055214) (xy 53.440282 -19.109153) (xy 53.440282 -19.163647)
			(xy 53.440281 -19.163657) (xy 57.402615 -19.163657) (xy 57.402615 -19.109143) (xy 57.410374 -19.055184)
			(xy 57.425733 -19.002878) (xy 57.44838 -18.95329) (xy 57.477854 -18.907431) (xy 57.513554 -18.866233)
			(xy 57.554755 -18.830536) (xy 57.600617 -18.801065) (xy 57.650206 -18.778422) (xy 57.702513 -18.763067)
			(xy 57.756473 -18.755313) (xy 57.78373 -18.754852) (xy 58.64733 -18.754852) (xy 58.674577 -18.75542)
			(xy 58.728516 -18.763179) (xy 58.780801 -18.778535) (xy 58.83037 -18.801176) (xy 58.876211 -18.83064)
			(xy 58.917394 -18.866328) (xy 58.953078 -18.907513) (xy 58.982538 -18.953357) (xy 59.005175 -19.002927)
			(xy 59.020527 -19.055214) (xy 59.028282 -19.109153) (xy 59.028282 -19.163647) (xy 59.020527 -19.217586)
			(xy 59.005175 -19.269873) (xy 58.982538 -19.319443) (xy 58.953078 -19.365287) (xy 58.917394 -19.406472)
			(xy 58.876211 -19.44216) (xy 58.83037 -19.471624) (xy 58.780801 -19.494265) (xy 58.728516 -19.509621)
			(xy 58.674577 -19.51738) (xy 58.64733 -19.517868) (xy 57.78373 -19.517868) (xy 57.756473 -19.517487)
			(xy 57.702513 -19.509733) (xy 57.650206 -19.494378) (xy 57.600617 -19.471735) (xy 57.554755 -19.442264)
			(xy 57.513554 -19.406567) (xy 57.477854 -19.365369) (xy 57.44838 -19.31951) (xy 57.425733 -19.269922)
			(xy 57.410374 -19.217616) (xy 57.402615 -19.163657) (xy 53.440281 -19.163657) (xy 53.432527 -19.217586)
			(xy 53.417175 -19.269873) (xy 53.394538 -19.319443) (xy 53.365078 -19.365287) (xy 53.329394 -19.406472)
			(xy 53.288211 -19.44216) (xy 53.24237 -19.471624) (xy 53.192801 -19.494265) (xy 53.140516 -19.509621)
			(xy 53.086577 -19.51738) (xy 53.05933 -19.517868) (xy 52.19573 -19.517868) (xy 52.168473 -19.517487)
			(xy 52.114513 -19.509733) (xy 52.062206 -19.494378) (xy 52.012617 -19.471735) (xy 51.966755 -19.442264)
			(xy 51.925554 -19.406567) (xy 51.889854 -19.365369) (xy 51.86038 -19.31951) (xy 51.837733 -19.269922)
			(xy 51.822374 -19.217616) (xy 51.814615 -19.163657) (xy 47.81762 -19.163657) (xy 47.81762 -19.164374)
			(xy 47.809857 -19.218365) (xy 47.794489 -19.270703) (xy 47.771828 -19.32032) (xy 47.742337 -19.366208)
			(xy 47.706615 -19.407431) (xy 47.66539 -19.44315) (xy 47.619501 -19.472639) (xy 47.569882 -19.495297)
			(xy 47.517544 -19.510662) (xy 47.463552 -19.518422) (xy 47.436278 -19.518884) (xy 46.572678 -19.518884)
			(xy 46.545411 -19.518352) (xy 46.491433 -19.510588) (xy 46.439109 -19.495222) (xy 46.389505 -19.472566)
			(xy 46.343629 -19.443081) (xy 46.302417 -19.407368) (xy 46.266706 -19.366153) (xy 46.237224 -19.320276)
			(xy 46.21457 -19.27067) (xy 46.199207 -19.218345) (xy 46.191446 -19.164367) (xy 42.230202 -19.164367)
			(xy 42.222548 -19.217596) (xy 42.207194 -19.269889) (xy 42.184553 -19.319464) (xy 42.155088 -19.365313)
			(xy 42.119397 -19.406501) (xy 42.078208 -19.442191) (xy 42.032359 -19.471656) (xy 41.982783 -19.494296)
			(xy 41.93049 -19.50965) (xy 41.876544 -19.517405) (xy 41.849294 -19.517868) (xy 40.985694 -19.517868)
			(xy 40.95844 -19.517462) (xy 40.904487 -19.509704) (xy 40.852188 -19.494346) (xy 40.802606 -19.471703)
			(xy 40.756752 -19.442233) (xy 40.715558 -19.406538) (xy 40.679863 -19.365343) (xy 40.650395 -19.319488)
			(xy 40.627751 -19.269906) (xy 40.612395 -19.217607) (xy 40.604638 -19.163654) (xy 36.336505 -19.163654)
			(xy 36.328748 -19.217598) (xy 36.313392 -19.269892) (xy 36.290751 -19.319469) (xy 36.261284 -19.365318)
			(xy 36.225591 -19.406507) (xy 36.1844 -19.442197) (xy 36.138549 -19.471661) (xy 36.088972 -19.4943)
			(xy 36.036677 -19.509653) (xy 35.982729 -19.517406) (xy 35.955478 -19.517868) (xy 35.091878 -19.517868)
			(xy 35.064625 -19.517461) (xy 35.010674 -19.509701) (xy 34.958376 -19.494342) (xy 34.908797 -19.471697)
			(xy 34.862944 -19.442227) (xy 34.821752 -19.406532) (xy 34.786059 -19.365338) (xy 34.756592 -19.319484)
			(xy 34.73395 -19.269903) (xy 34.718595 -19.217605) (xy 34.710838 -19.163653) (xy 30.748505 -19.163653)
			(xy 30.740748 -19.217598) (xy 30.725392 -19.269892) (xy 30.702751 -19.319469) (xy 30.673284 -19.365318)
			(xy 30.637591 -19.406507) (xy 30.5964 -19.442197) (xy 30.550549 -19.471661) (xy 30.500972 -19.4943)
			(xy 30.448677 -19.509653) (xy 30.394729 -19.517406) (xy 30.367478 -19.517868) (xy 29.503878 -19.517868)
			(xy 29.476625 -19.517461) (xy 29.422674 -19.509701) (xy 29.370376 -19.494342) (xy 29.320797 -19.471697)
			(xy 29.274944 -19.442227) (xy 29.233752 -19.406532) (xy 29.198059 -19.365338) (xy 29.168592 -19.319484)
			(xy 29.14595 -19.269903) (xy 29.130595 -19.217605) (xy 29.122838 -19.163653) (xy 25.160505 -19.163653)
			(xy 25.152748 -19.217598) (xy 25.137392 -19.269892) (xy 25.114751 -19.319469) (xy 25.085284 -19.365318)
			(xy 25.049591 -19.406507) (xy 25.0084 -19.442197) (xy 24.962549 -19.471661) (xy 24.912972 -19.4943)
			(xy 24.860677 -19.509653) (xy 24.806729 -19.517406) (xy 24.779478 -19.517868) (xy 23.915878 -19.517868)
			(xy 23.888625 -19.517461) (xy 23.834674 -19.509701) (xy 23.782376 -19.494342) (xy 23.732797 -19.471697)
			(xy 23.686944 -19.442227) (xy 23.645752 -19.406532) (xy 23.610059 -19.365338) (xy 23.580592 -19.319484)
			(xy 23.55795 -19.269903) (xy 23.542595 -19.217605) (xy 23.534838 -19.163653) (xy 19.571738 -19.163653)
			(xy 19.571738 -19.164389) (xy 19.563976 -19.218373) (xy 19.548611 -19.270703) (xy 19.525954 -19.320313)
			(xy 19.496469 -19.366194) (xy 19.460753 -19.407412) (xy 19.419536 -19.443127) (xy 19.373655 -19.472613)
			(xy 19.324045 -19.49527) (xy 19.271715 -19.510635) (xy 19.217731 -19.518397) (xy 19.190462 -19.518884)
			(xy 18.326862 -19.518884) (xy 18.299591 -19.518417) (xy 18.245604 -19.510655) (xy 18.193272 -19.495289)
			(xy 18.143658 -19.472631) (xy 18.097775 -19.443144) (xy 18.056555 -19.407427) (xy 18.020837 -19.366207)
			(xy 17.99135 -19.320323) (xy 17.968692 -19.27071) (xy 17.953326 -19.218378) (xy 17.945563 -19.164391)
			(xy 0.509016 -19.164391) (xy 0.509016 -20.327366) (xy 65.88506 -20.327366) (xy 65.885484 -20.289077)
			(xy 65.892086 -20.212783) (xy 65.90523 -20.13734) (xy 65.924819 -20.063309) (xy 65.937384 -20.027138)
			(xy 65.940051 -20.018705) (xy 65.94004 -20.001031) (xy 65.937384 -19.992594) (xy 65.924856 -19.956411)
			(xy 65.905279 -19.88238) (xy 65.892127 -19.806942) (xy 65.885498 -19.730654) (xy 65.88506 -19.692366)
			(xy 65.885582 -19.650174) (xy 65.893576 -19.56617) (xy 65.909488 -19.483301) (xy 65.933176 -19.402311)
			(xy 65.964427 -19.323927) (xy 66.00296 -19.248856) (xy 66.048429 -19.17777) (xy 66.074036 -19.144234)
			(xy 66.079883 -19.13601) (xy 66.085128 -19.116537) (xy 66.082515 -19.096539) (xy 66.077846 -19.087592)
			(xy 66.058798 -19.053767) (xy 66.026006 -18.983399) (xy 65.999468 -18.910441) (xy 65.979384 -18.83545)
			(xy 65.965909 -18.758994) (xy 65.959144 -18.681655) (xy 65.95872 -18.642838) (xy 65.95872 -18.642584)
			(xy 65.959137 -18.60148) (xy 65.966724 -18.519622) (xy 65.981831 -18.438814) (xy 66.00433 -18.359744)
			(xy 66.034029 -18.283087) (xy 66.070674 -18.209498) (xy 66.113953 -18.139604) (xy 66.163496 -18.074001)
			(xy 66.218881 -18.01325) (xy 66.279635 -17.957868) (xy 66.34524 -17.908328) (xy 66.415137 -17.865053)
			(xy 66.488728 -17.828411) (xy 66.565386 -17.798716) (xy 66.644456 -17.776221) (xy 66.725266 -17.761118)
			(xy 66.807124 -17.753535) (xy 66.848228 -17.753076) (xy 66.889911 -17.753577) (xy 66.972911 -17.761363)
			(xy 67.054819 -17.776882) (xy 67.134915 -17.799999) (xy 67.212496 -17.830511) (xy 67.286881 -17.868149)
			(xy 67.357417 -17.912584) (xy 67.423485 -17.963425) (xy 67.484504 -18.020226) (xy 67.53994 -18.082488)
			(xy 67.565016 -18.115788) (xy 67.56527 -18.116042) (xy 67.570757 -18.122776) (xy 67.585223 -18.132372)
			(xy 67.602063 -18.136587) (xy 67.610736 -18.136108) (xy 67.697858 -18.127726) (xy 67.706567 -18.126584)
			(xy 67.722478 -18.119178) (xy 67.734922 -18.1068) (xy 67.739006 -18.099024) (xy 67.739006 -18.098516)
			(xy 67.757258 -18.060702) (xy 67.799884 -17.988356) (xy 67.849141 -17.920351) (xy 67.90459 -17.857291)
			(xy 67.965736 -17.79974) (xy 68.032035 -17.748209) (xy 68.102897 -17.703158) (xy 68.17769 -17.664987)
			(xy 68.255748 -17.634037) (xy 68.336377 -17.610583) (xy 68.418857 -17.594835) (xy 68.502455 -17.586933)
			(xy 68.54444 -17.586452) (xy 68.5868 -17.58693) (xy 68.671136 -17.594986) (xy 68.754325 -17.611023)
			(xy 68.835612 -17.634895) (xy 68.914262 -17.666384) (xy 68.989563 -17.705208) (xy 69.060833 -17.751013)
			(xy 69.127426 -17.803385) (xy 69.18874 -17.86185) (xy 69.244218 -17.925878) (xy 69.293359 -17.99489)
			(xy 69.335718 -18.068261) (xy 69.370911 -18.145325) (xy 69.39862 -18.225386) (xy 69.401856 -18.238724)
			(xy 79.0321 -18.238724) (xy 79.032651 -18.193954) (xy 79.041664 -18.104869) (xy 79.059573 -18.017137)
			(xy 79.086195 -17.931647) (xy 79.10322 -17.890236) (xy 79.106772 -17.880641) (xy 79.106781 -17.860202)
			(xy 79.10322 -17.850612) (xy 79.086184 -17.809205) (xy 79.059551 -17.723717) (xy 79.041646 -17.635983)
			(xy 79.032653 -17.546895) (xy 79.0321 -17.502124) (xy 79.032604 -17.459763) (xy 79.040657 -17.375426)
			(xy 79.056691 -17.292236) (xy 79.080559 -17.210946) (xy 79.112047 -17.132294) (xy 79.150869 -17.056991)
			(xy 79.196672 -16.985719) (xy 79.249043 -16.919123) (xy 79.307508 -16.857808) (xy 79.371536 -16.802327)
			(xy 79.440548 -16.753184) (xy 79.513918 -16.710824) (xy 79.590983 -16.675629) (xy 79.671045 -16.64792)
			(xy 79.753378 -16.627946) (xy 79.837237 -16.615889) (xy 79.921862 -16.611858) (xy 80.006487 -16.615889)
			(xy 80.090346 -16.627946) (xy 80.172679 -16.64792) (xy 80.252741 -16.675629) (xy 80.329806 -16.710824)
			(xy 80.403176 -16.753184) (xy 80.472188 -16.802327) (xy 80.536216 -16.857808) (xy 80.594681 -16.919123)
			(xy 80.647052 -16.985719) (xy 80.692855 -17.056991) (xy 80.731677 -17.132294) (xy 80.763165 -17.210946)
			(xy 80.787033 -17.292236) (xy 80.803067 -17.375426) (xy 80.81112 -17.459763) (xy 80.811624 -17.502124)
			(xy 80.811054 -17.546893) (xy 80.802046 -17.635978) (xy 80.784143 -17.723709) (xy 80.757526 -17.809201)
			(xy 80.740504 -17.850612) (xy 80.736924 -17.860198) (xy 80.736933 -17.880645) (xy 80.740504 -17.890236)
			(xy 80.757551 -17.931638) (xy 80.784182 -18.017129) (xy 80.802084 -18.104863) (xy 80.808854 -18.171951)
			(xy 131.633699 -18.171951) (xy 131.633699 -18.117449) (xy 131.641456 -18.063503) (xy 131.656811 -18.011209)
			(xy 131.679453 -17.961633) (xy 131.708919 -17.915784) (xy 131.744611 -17.874596) (xy 131.785802 -17.838906)
			(xy 131.831653 -17.809442) (xy 131.88123 -17.786804) (xy 131.933524 -17.771451) (xy 131.987471 -17.763698)
			(xy 132.014722 -17.763236) (xy 132.878322 -17.763236) (xy 132.905575 -17.763635) (xy 132.959527 -17.771395)
			(xy 133.011825 -17.786754) (xy 133.061405 -17.809399) (xy 133.107258 -17.838869) (xy 133.148451 -17.874565)
			(xy 133.184144 -17.915759) (xy 133.213611 -17.961614) (xy 133.236254 -18.011196) (xy 133.251609 -18.063495)
			(xy 133.259366 -18.117447) (xy 133.259366 -18.171946) (xy 137.033822 -18.171946) (xy 137.033822 -18.117454)
			(xy 137.041577 -18.063516) (xy 137.056928 -18.01123) (xy 137.079564 -17.961661) (xy 137.109023 -17.915818)
			(xy 137.144706 -17.874633) (xy 137.185887 -17.838946) (xy 137.231728 -17.809482) (xy 137.281294 -17.786841)
			(xy 137.333578 -17.771485) (xy 137.387516 -17.763725) (xy 137.414762 -17.763236) (xy 138.278362 -17.763236)
			(xy 138.30562 -17.763608) (xy 138.359581 -17.771362) (xy 138.41189 -17.786716) (xy 138.46148 -17.809359)
			(xy 138.507344 -17.83883) (xy 138.548546 -17.874528) (xy 138.584247 -17.915726) (xy 138.613722 -17.961586)
			(xy 138.63637 -18.011175) (xy 138.65173 -18.063482) (xy 138.659489 -18.117442) (xy 138.659489 -18.17195)
			(xy 140.633699 -18.17195) (xy 140.633699 -18.11745) (xy 140.641455 -18.063505) (xy 140.65681 -18.011213)
			(xy 140.67945 -17.961638) (xy 140.708915 -17.91579) (xy 140.744605 -17.874602) (xy 140.785793 -17.838913)
			(xy 140.831642 -17.809448) (xy 140.881217 -17.786808) (xy 140.933509 -17.771455) (xy 140.987454 -17.763699)
			(xy 141.014704 -17.763236) (xy 141.878304 -17.763236) (xy 141.905558 -17.763634) (xy 141.959512 -17.771392)
			(xy 142.011812 -17.786749) (xy 142.061394 -17.809393) (xy 142.10725 -17.838863) (xy 142.148444 -17.874559)
			(xy 142.184139 -17.915754) (xy 142.213609 -17.961609) (xy 142.236252 -18.011192) (xy 142.251609 -18.063492)
			(xy 142.259366 -18.117446) (xy 142.259366 -18.171954) (xy 142.251609 -18.225908) (xy 142.236252 -18.278208)
			(xy 142.213609 -18.327791) (xy 142.184139 -18.373646) (xy 142.148444 -18.414841) (xy 142.10725 -18.450537)
			(xy 142.061394 -18.480007) (xy 142.011812 -18.502651) (xy 141.959512 -18.518008) (xy 141.905558 -18.525766)
			(xy 141.878304 -18.526252) (xy 141.014704 -18.526252) (xy 140.987454 -18.525701) (xy 140.933509 -18.517945)
			(xy 140.881217 -18.502592) (xy 140.831642 -18.479952) (xy 140.785793 -18.450487) (xy 140.744605 -18.414798)
			(xy 140.708915 -18.37361) (xy 140.67945 -18.327762) (xy 140.65681 -18.278187) (xy 140.641455 -18.225895)
			(xy 140.633699 -18.17195) (xy 138.659489 -18.17195) (xy 138.659489 -18.171958) (xy 138.65173 -18.225918)
			(xy 138.63637 -18.278225) (xy 138.613722 -18.327814) (xy 138.584247 -18.373674) (xy 138.548546 -18.414872)
			(xy 138.507344 -18.45057) (xy 138.46148 -18.480041) (xy 138.41189 -18.502684) (xy 138.359581 -18.518038)
			(xy 138.30562 -18.525792) (xy 138.278362 -18.526252) (xy 137.414762 -18.526252) (xy 137.387516 -18.525675)
			(xy 137.333578 -18.517915) (xy 137.281294 -18.502559) (xy 137.231728 -18.479918) (xy 137.185887 -18.450454)
			(xy 137.144706 -18.414767) (xy 137.109023 -18.373582) (xy 137.079564 -18.327739) (xy 137.056928 -18.27817)
			(xy 137.041577 -18.225884) (xy 137.033822 -18.171946) (xy 133.259366 -18.171946) (xy 133.259366 -18.171953)
			(xy 133.251609 -18.225905) (xy 133.236254 -18.278204) (xy 133.213611 -18.327786) (xy 133.184144 -18.373641)
			(xy 133.148451 -18.414835) (xy 133.107258 -18.450531) (xy 133.061405 -18.480001) (xy 133.011825 -18.502646)
			(xy 132.959527 -18.518005) (xy 132.905575 -18.525765) (xy 132.878322 -18.526252) (xy 132.014722 -18.526252)
			(xy 131.987471 -18.525702) (xy 131.933524 -18.517949) (xy 131.88123 -18.502596) (xy 131.831653 -18.479958)
			(xy 131.785802 -18.450494) (xy 131.744611 -18.414804) (xy 131.708919 -18.373616) (xy 131.679453 -18.327767)
			(xy 131.656811 -18.278191) (xy 131.641456 -18.225897) (xy 131.633699 -18.171951) (xy 80.808854 -18.171951)
			(xy 80.811074 -18.193953) (xy 80.811624 -18.238724) (xy 80.81112 -18.281085) (xy 80.803067 -18.365422)
			(xy 80.787033 -18.448612) (xy 80.763165 -18.529902) (xy 80.731677 -18.608554) (xy 80.692855 -18.683857)
			(xy 80.647052 -18.755129) (xy 80.594681 -18.821725) (xy 80.536216 -18.88304) (xy 80.472188 -18.938521)
			(xy 80.403176 -18.987664) (xy 80.329806 -19.030024) (xy 80.252741 -19.065219) (xy 80.172679 -19.092928)
			(xy 80.090346 -19.112902) (xy 80.006487 -19.124959) (xy 79.921862 -19.128991) (xy 79.837237 -19.124959)
			(xy 79.753378 -19.112902) (xy 79.671045 -19.092928) (xy 79.590983 -19.065219) (xy 79.513918 -19.030024)
			(xy 79.440548 -18.987664) (xy 79.371536 -18.938521) (xy 79.307508 -18.88304) (xy 79.249043 -18.821725)
			(xy 79.196672 -18.755129) (xy 79.150869 -18.683857) (xy 79.112047 -18.608554) (xy 79.080559 -18.529902)
			(xy 79.056691 -18.448612) (xy 79.040657 -18.365422) (xy 79.032604 -18.281085) (xy 79.0321 -18.238724)
			(xy 69.401856 -18.238724) (xy 69.418593 -18.307718) (xy 69.430649 -18.391576) (xy 69.434681 -18.4762)
			(xy 69.430649 -18.560824) (xy 69.418593 -18.644682) (xy 69.39862 -18.727014) (xy 69.370911 -18.807075)
			(xy 69.335718 -18.884139) (xy 69.293359 -18.95751) (xy 69.244218 -19.026522) (xy 69.18874 -19.09055)
			(xy 69.127426 -19.149015) (xy 69.060833 -19.201387) (xy 68.989563 -19.247192) (xy 68.914262 -19.286016)
			(xy 68.835612 -19.317505) (xy 68.754325 -19.341377) (xy 68.671136 -19.357414) (xy 68.5868 -19.36547)
			(xy 68.54444 -19.365976) (xy 68.502753 -19.365468) (xy 68.419745 -19.357644) (xy 68.337834 -19.342089)
			(xy 68.257737 -19.31894) (xy 68.180157 -19.288398) (xy 68.105774 -19.250734) (xy 68.035242 -19.206275)
			(xy 67.969177 -19.155414) (xy 67.90816 -19.098595) (xy 67.852727 -19.036317) (xy 67.827652 -19.00301)
			(xy 67.827398 -19.002756) (xy 67.821873 -18.996058) (xy 67.807425 -18.986454) (xy 67.790601 -18.982223)
			(xy 67.781932 -18.98269) (xy 67.69481 -18.991072) (xy 67.686098 -18.992195) (xy 67.670187 -18.999611)
			(xy 67.657745 -19.011995) (xy 67.653662 -19.019774) (xy 67.653662 -19.020282) (xy 67.63179 -19.065383)
			(xy 67.579339 -19.150805) (xy 67.549014 -19.190716) (xy 67.543272 -19.198996) (xy 67.538026 -19.218428)
			(xy 67.540615 -19.238388) (xy 67.545204 -19.247358) (xy 67.564269 -19.281203) (xy 67.597117 -19.351604)
			(xy 67.623706 -19.424598) (xy 67.643834 -19.499632) (xy 67.657349 -19.576134) (xy 67.664146 -19.653523)
			(xy 67.664584 -19.692366) (xy 67.664167 -19.730656) (xy 67.657563 -19.806949) (xy 67.644416 -19.882392)
			(xy 67.624826 -19.956423) (xy 67.61226 -19.992594) (xy 67.609626 -20.001035) (xy 67.609615 -20.018702)
			(xy 67.61226 -20.027138) (xy 67.624799 -20.063317) (xy 67.644373 -20.13735) (xy 67.653158 -20.187755)
			(xy 138.765443 -20.187755) (xy 138.765443 -20.133245) (xy 138.773201 -20.079289) (xy 138.788559 -20.026987)
			(xy 138.811205 -19.977403) (xy 138.840677 -19.931547) (xy 138.876376 -19.890352) (xy 138.917574 -19.854657)
			(xy 138.963433 -19.825189) (xy 139.013019 -19.802547) (xy 139.065322 -19.787194) (xy 139.119279 -19.779441)
			(xy 139.146534 -19.77898) (xy 140.137134 -19.77898) (xy 140.164383 -19.779493) (xy 140.218325 -19.787253)
			(xy 140.270614 -19.80261) (xy 140.320185 -19.825253) (xy 140.36603 -19.854719) (xy 140.407215 -19.890409)
			(xy 140.442901 -19.931597) (xy 140.449617 -19.942048) (xy 175.988472 -19.942048) (xy 175.988976 -19.899687)
			(xy 175.997029 -19.81535) (xy 176.013063 -19.73216) (xy 176.036931 -19.65087) (xy 176.068419 -19.572218)
			(xy 176.107241 -19.496915) (xy 176.153044 -19.425643) (xy 176.205415 -19.359047) (xy 176.26388 -19.297732)
			(xy 176.327908 -19.242251) (xy 176.39692 -19.193108) (xy 176.47029 -19.150748) (xy 176.547355 -19.115553)
			(xy 176.627417 -19.087844) (xy 176.70975 -19.06787) (xy 176.793609 -19.055813) (xy 176.878234 -19.051782)
			(xy 176.962859 -19.055813) (xy 177.046718 -19.06787) (xy 177.129051 -19.087844) (xy 177.209113 -19.115553)
			(xy 177.286178 -19.150748) (xy 177.359548 -19.193108) (xy 177.42856 -19.242251) (xy 177.492588 -19.297732)
			(xy 177.551053 -19.359047) (xy 177.603424 -19.425643) (xy 177.649227 -19.496915) (xy 177.688049 -19.572218)
			(xy 177.719537 -19.65087) (xy 177.743405 -19.73216) (xy 177.759439 -19.81535) (xy 177.767492 -19.899687)
			(xy 177.767996 -19.942048) (xy 177.767398 -19.98792) (xy 177.757891 -20.079169) (xy 177.739034 -20.168954)
			(xy 177.725578 -20.212812) (xy 177.722752 -20.223379) (xy 177.72523 -20.245087) (xy 177.730404 -20.254722)
			(xy 177.750836 -20.289402) (xy 177.786035 -20.361795) (xy 177.814552 -20.437071) (xy 177.836153 -20.514616)
			(xy 177.850661 -20.593794) (xy 177.857958 -20.67396) (xy 177.85842 -20.714208) (xy 177.85842 -20.715224)
			(xy 177.857839 -20.760561) (xy 177.84856 -20.850758) (xy 177.830152 -20.939544) (xy 177.817018 -20.98294)
			(xy 177.81462 -20.991841) (xy 177.815621 -21.010233) (xy 177.823067 -21.02708) (xy 177.835994 -21.040201)
			(xy 177.844196 -21.044408) (xy 177.8824 -21.062505) (xy 177.955518 -21.104946) (xy 178.024281 -21.15413)
			(xy 178.088069 -21.209614) (xy 178.146306 -21.270898) (xy 178.198469 -21.337429) (xy 178.244087 -21.408608)
			(xy 178.282748 -21.483792) (xy 178.314103 -21.562305) (xy 178.337871 -21.643437) (xy 178.353837 -21.726458)
			(xy 178.361856 -21.810619) (xy 178.362356 -21.85289) (xy 178.361892 -21.894005) (xy 178.354306 -21.975884)
			(xy 178.339197 -22.056714) (xy 178.316694 -22.135805) (xy 178.28699 -22.212482) (xy 178.250337 -22.286091)
			(xy 178.207049 -22.356005) (xy 178.157495 -22.421626) (xy 178.102097 -22.482394) (xy 178.041329 -22.537792)
			(xy 177.975708 -22.587347) (xy 177.905795 -22.630635) (xy 177.832186 -22.667288) (xy 177.755509 -22.696993)
			(xy 177.676418 -22.719496) (xy 177.595588 -22.734605) (xy 177.513709 -22.742192) (xy 177.472594 -22.742652)
			(xy 177.429071 -22.742084) (xy 177.34244 -22.73358) (xy 177.257055 -22.716655) (xy 177.173731 -22.69147)
			(xy 177.093266 -22.658267) (xy 177.016429 -22.617362) (xy 176.943956 -22.569146) (xy 176.876538 -22.514083)
			(xy 176.814822 -22.452697) (xy 176.759398 -22.385575) (xy 176.710795 -22.313361) (xy 176.669479 -22.236745)
			(xy 176.652174 -22.196806) (xy 176.647921 -22.187866) (xy 176.633936 -22.17388) (xy 176.624996 -22.169628)
			(xy 176.585068 -22.152314) (xy 176.508472 -22.110985) (xy 176.436278 -22.062372) (xy 176.369178 -22.006941)
			(xy 176.307813 -21.945221) (xy 176.252769 -21.877802) (xy 176.204574 -21.80533) (xy 176.163687 -21.728496)
			(xy 176.1305 -21.648037) (xy 176.105331 -21.564721) (xy 176.088419 -21.479345) (xy 176.079928 -21.392725)
			(xy 176.079404 -21.349208) (xy 176.079404 -21.348446) (xy 176.079814 -21.310226) (xy 176.086378 -21.234067)
			(xy 176.099462 -21.158755) (xy 176.118968 -21.084845) (xy 176.131474 -21.048726) (xy 176.134055 -21.040409)
			(xy 176.134058 -21.023006) (xy 176.131474 -21.01469) (xy 176.118957 -20.978475) (xy 176.099434 -20.904375)
			(xy 176.086349 -20.828871) (xy 176.079799 -20.752523) (xy 176.079404 -20.714208) (xy 176.07999 -20.668344)
			(xy 176.089425 -20.577104) (xy 176.108186 -20.487316) (xy 176.121568 -20.443444) (xy 176.124428 -20.432883)
			(xy 176.121929 -20.411168) (xy 176.116742 -20.401534) (xy 176.096312 -20.366847) (xy 176.06107 -20.294464)
			(xy 176.032509 -20.219194) (xy 176.010862 -20.141652) (xy 175.996306 -20.062472) (xy 175.988959 -19.982301)
			(xy 175.988472 -19.942048) (xy 140.449617 -19.942048) (xy 140.472364 -19.977445) (xy 140.495002 -20.027018)
			(xy 140.510354 -20.079308) (xy 140.51811 -20.133251) (xy 140.51811 -20.187749) (xy 140.510354 -20.241692)
			(xy 140.495002 -20.293982) (xy 140.472364 -20.343555) (xy 140.442901 -20.389403) (xy 140.407215 -20.430591)
			(xy 140.36603 -20.466281) (xy 140.320185 -20.495747) (xy 140.270614 -20.51839) (xy 140.218325 -20.533747)
			(xy 140.164383 -20.541507) (xy 140.137134 -20.541996) (xy 139.146534 -20.541996) (xy 139.119279 -20.541559)
			(xy 139.065322 -20.533806) (xy 139.013019 -20.518453) (xy 138.963433 -20.495811) (xy 138.917574 -20.466343)
			(xy 138.876376 -20.430648) (xy 138.840677 -20.389453) (xy 138.811205 -20.343597) (xy 138.788559 -20.294013)
			(xy 138.773201 -20.241711) (xy 138.765443 -20.187755) (xy 67.653158 -20.187755) (xy 67.657521 -20.212789)
			(xy 67.664147 -20.289078) (xy 67.664584 -20.327366) (xy 67.66408 -20.369727) (xy 67.656027 -20.454064)
			(xy 67.639993 -20.537254) (xy 67.616125 -20.618544) (xy 67.584637 -20.697196) (xy 67.545815 -20.772499)
			(xy 67.500012 -20.843771) (xy 67.447641 -20.910367) (xy 67.389176 -20.971682) (xy 67.325148 -21.027163)
			(xy 67.256136 -21.076306) (xy 67.182766 -21.118666) (xy 67.105701 -21.153861) (xy 67.025639 -21.18157)
			(xy 66.943306 -21.201544) (xy 66.859447 -21.213601) (xy 66.774822 -21.217633) (xy 66.690197 -21.213601)
			(xy 66.606338 -21.201544) (xy 66.524005 -21.18157) (xy 66.443943 -21.153861) (xy 66.366878 -21.118666)
			(xy 66.293508 -21.076306) (xy 66.224496 -21.027163) (xy 66.160468 -20.971682) (xy 66.102003 -20.910367)
			(xy 66.049632 -20.843771) (xy 66.003829 -20.772499) (xy 65.965007 -20.697196) (xy 65.933519 -20.618544)
			(xy 65.909651 -20.537254) (xy 65.893617 -20.454064) (xy 65.885564 -20.369727) (xy 65.88506 -20.327366)
			(xy 0.509016 -20.327366) (xy 0.509016 -20.981162) (xy 21.562822 -20.981162) (xy 21.563459 -20.968608)
			(xy 21.575328 -20.946483) (xy 21.585428 -20.938998) (xy 22.19198 -20.532852) (xy 22.198351 -20.528901)
			(xy 22.212683 -20.524518) (xy 22.220174 -20.524216) (xy 22.232729 -20.524854) (xy 22.254857 -20.536719)
			(xy 22.262338 -20.546822) (xy 22.487116 -20.88261) (xy 35.377882 -20.88261) (xy 35.37832 -20.872995)
			(xy 35.385399 -20.855115) (xy 35.398566 -20.841099) (xy 35.407092 -20.836636) (xy 36.068254 -20.527264)
			(xy 36.073363 -20.525009) (xy 36.084261 -20.52258) (xy 36.089844 -20.522438) (xy 36.09946 -20.522861)
			(xy 36.117337 -20.529952) (xy 36.131353 -20.543122) (xy 36.135818 -20.551648) (xy 36.461914 -21.24837)
			(xy 44.103798 -21.24837) (xy 44.103798 -21.248116) (xy 44.104258 -21.237325) (xy 44.113077 -21.21763)
			(xy 44.129208 -21.203295) (xy 44.139358 -21.199602) (xy 44.835572 -20.980146) (xy 44.839227 -20.979079)
			(xy 44.846752 -20.977928) (xy 44.850558 -20.97786) (xy 44.850812 -20.97786) (xy 44.861601 -20.978324)
			(xy 44.881293 -20.987146) (xy 44.895629 -21.003273) (xy 44.899326 -21.01342) (xy 44.980651 -21.27123)
			(xy 49.60112 -21.27123) (xy 49.601635 -21.259587) (xy 49.611841 -21.238661) (xy 49.630224 -21.224372)
			(xy 49.641506 -21.221446) (xy 50.3555 -21.070062) (xy 50.365914 -21.069046) (xy 50.377552 -21.069584)
			(xy 50.398469 -21.079789) (xy 50.412762 -21.098157) (xy 50.415698 -21.109432) (xy 50.816437 -22.9997)
			(xy 55.005224 -22.9997) (xy 55.005224 -20.8407) (xy 55.00562 -20.830676) (xy 55.013295 -20.812154)
			(xy 55.027474 -20.797981) (xy 55.046 -20.790315) (xy 55.056024 -20.7899) (xy 55.785004 -20.7899)
			(xy 55.795012 -20.790385) (xy 55.813504 -20.798046) (xy 55.827656 -20.8122) (xy 55.835316 -20.830692)
			(xy 55.835804 -20.8407) (xy 55.835804 -22.9997) (xy 55.835316 -23.009708) (xy 55.827656 -23.028199)
			(xy 55.813503 -23.042352) (xy 55.795012 -23.050012) (xy 55.774996 -23.050012) (xy 55.756505 -23.042352)
			(xy 55.742352 -23.028199) (xy 55.734692 -23.009708) (xy 55.734204 -22.9997) (xy 55.734204 -20.9423)
			(xy 55.733712 -20.932293) (xy 55.726053 -20.913802) (xy 55.711901 -20.899649) (xy 55.693411 -20.891989)
			(xy 55.683404 -20.8915) (xy 55.157624 -20.8915) (xy 55.147604 -20.891939) (xy 55.129088 -20.899601)
			(xy 55.114915 -20.913768) (xy 55.107244 -20.932281) (xy 55.106824 -20.9423) (xy 55.106824 -22.9997)
			(xy 55.106336 -23.009708) (xy 55.098676 -23.028199) (xy 55.084523 -23.042352) (xy 55.066032 -23.050012)
			(xy 55.046016 -23.050012) (xy 55.027525 -23.042352) (xy 55.013372 -23.028199) (xy 55.005712 -23.009708)
			(xy 55.005224 -22.9997) (xy 50.816437 -22.9997) (xy 50.8635 -23.221696) (xy 50.864516 -23.23211)
			(xy 50.86402 -23.242116) (xy 50.85636 -23.260605) (xy 50.84221 -23.274757) (xy 50.823722 -23.282419)
			(xy 50.813716 -23.28291) (xy 50.802076 -23.282382) (xy 50.781153 -23.272178) (xy 50.766862 -23.253803)
			(xy 50.763932 -23.242524) (xy 50.337212 -21.230082) (xy 50.334654 -21.220384) (xy 50.323364 -21.203837)
			(xy 50.306602 -21.192867) (xy 50.286919 -21.189145) (xy 50.277014 -21.190712) (xy 49.761902 -21.300186)
			(xy 49.752208 -21.302757) (xy 49.735659 -21.314042) (xy 49.724688 -21.3308) (xy 49.720964 -21.35048)
			(xy 49.722532 -21.360384) (xy 50.149506 -23.37308) (xy 50.150522 -23.383494) (xy 50.150008 -23.393499)
			(xy 50.142354 -23.411986) (xy 50.128209 -23.426138) (xy 50.109726 -23.433802) (xy 50.099722 -23.434294)
			(xy 50.08808 -23.433774) (xy 50.067155 -23.423569) (xy 50.052866 -23.405189) (xy 50.049938 -23.393908)
			(xy 49.602136 -21.281644) (xy 49.60112 -21.27123) (xy 44.980651 -21.27123) (xy 45.548804 -23.072344)
			(xy 45.549866 -23.076) (xy 45.55102 -23.083524) (xy 45.55109 -23.08733) (xy 45.55109 -23.087584)
			(xy 45.550667 -23.097606) (xy 45.543001 -23.116124) (xy 45.528829 -23.130297) (xy 45.510311 -23.137966)
			(xy 45.50029 -23.138384) (xy 45.489495 -23.137956) (xy 45.469797 -23.129124) (xy 45.455465 -23.11298)
			(xy 45.451776 -23.102824) (xy 44.832778 -21.140928) (xy 44.829363 -21.131494) (xy 44.816482 -21.116133)
			(xy 44.798703 -21.106868) (xy 44.778732 -21.105111) (xy 44.769024 -21.107654) (xy 44.518072 -21.186902)
			(xy 44.266866 -21.26615) (xy 44.257473 -21.26966) (xy 44.242115 -21.282509) (xy 44.232841 -21.300258)
			(xy 44.231063 -21.320204) (xy 44.233592 -21.329904) (xy 44.85259 -23.2918) (xy 44.853664 -23.295453)
			(xy 44.85481 -23.302979) (xy 44.854876 -23.306786) (xy 44.854876 -23.30704) (xy 44.854444 -23.317053)
			(xy 44.846767 -23.33555) (xy 44.832597 -23.349703) (xy 44.81409 -23.357357) (xy 44.804076 -23.35784)
			(xy 44.793286 -23.357385) (xy 44.773594 -23.348558) (xy 44.759259 -23.332429) (xy 44.755562 -23.32228)
			(xy 44.106084 -21.263356) (xy 44.105022 -21.2597) (xy 44.103868 -21.252176) (xy 44.103798 -21.24837)
			(xy 36.461914 -21.24837) (xy 37.05098 -22.50694) (xy 37.053228 -22.512052) (xy 37.055661 -22.522948)
			(xy 37.055806 -22.52853) (xy 37.055337 -22.538539) (xy 37.047668 -22.55703) (xy 37.03351 -22.571182)
			(xy 37.015015 -22.578841) (xy 37.005006 -22.57933) (xy 36.995391 -22.578888) (xy 36.977513 -22.57181)
			(xy 36.963496 -22.558645) (xy 36.959032 -22.55012) (xy 36.08705 -20.686776) (xy 36.08239 -20.677906)
			(xy 36.067585 -20.66443) (xy 36.048751 -20.657643) (xy 36.028753 -20.658577) (xy 36.019486 -20.662392)
			(xy 35.78098 -20.773898) (xy 35.729926 -20.797774) (xy 35.654996 -20.832826) (xy 35.54222 -20.885404)
			(xy 35.533345 -20.890069) (xy 35.519846 -20.90487) (xy 35.513039 -20.923711) (xy 35.513961 -20.943722)
			(xy 35.517836 -20.952968) (xy 36.389818 -22.816312) (xy 36.392059 -22.821426) (xy 36.394497 -22.83232)
			(xy 36.394644 -22.837902) (xy 36.394115 -22.847904) (xy 36.386463 -22.866388) (xy 36.372323 -22.880539)
			(xy 36.353846 -22.888206) (xy 36.343844 -22.888702) (xy 36.334223 -22.88832) (xy 36.31634 -22.881216)
			(xy 36.302329 -22.868028) (xy 36.29787 -22.859492) (xy 35.382708 -20.9042) (xy 35.380472 -20.899084)
			(xy 35.378031 -20.888191) (xy 35.377882 -20.88261) (xy 22.487116 -20.88261) (xy 22.864579 -21.44649)
			(xy 27.379422 -21.44649) (xy 27.379422 -21.446236) (xy 27.379783 -21.437384) (xy 27.385822 -21.420738)
			(xy 27.397131 -21.407113) (xy 27.404568 -21.402294) (xy 28.034488 -21.033486) (xy 28.040347 -21.030297)
			(xy 28.05322 -21.026823) (xy 28.059888 -21.026628) (xy 28.060142 -21.026628) (xy 28.068993 -21.027002)
			(xy 28.085639 -21.033034) (xy 28.099265 -21.044339) (xy 28.104084 -21.051774) (xy 29.195268 -22.91461)
			(xy 29.198461 -22.920467) (xy 29.201933 -22.933342) (xy 29.202126 -22.94001) (xy 29.202126 -22.940264)
			(xy 29.201652 -22.95028) (xy 29.193998 -22.968791) (xy 29.179843 -22.982963) (xy 29.161341 -22.990639)
			(xy 29.151326 -22.991064) (xy 29.142478 -22.990647) (xy 29.125834 -22.984635) (xy 29.112206 -22.973346)
			(xy 29.107384 -22.965918) (xy 28.067508 -21.190966) (xy 28.062115 -21.182486) (xy 28.046119 -21.170339)
			(xy 28.026692 -21.165242) (xy 28.006793 -21.167972) (xy 27.997912 -21.172678) (xy 27.54376 -21.43887)
			(xy 27.535296 -21.444284) (xy 27.52315 -21.460272) (xy 27.518049 -21.479692) (xy 27.520771 -21.499586)
			(xy 27.525472 -21.508466) (xy 28.548235 -23.254208) (xy 31.107126 -23.254208) (xy 31.107499 -23.245068)
			(xy 31.113915 -23.227952) (xy 31.125933 -23.214178) (xy 31.133796 -23.209504) (xy 31.775654 -22.861778)
			(xy 31.781285 -22.858958) (xy 31.79349 -22.855872) (xy 31.799784 -22.855682) (xy 31.808921 -22.856083)
			(xy 31.826033 -22.86249) (xy 31.839809 -22.874495) (xy 31.844488 -22.882352) (xy 32.254563 -23.63978)
			(xy 57.80024 -23.63978) (xy 57.80024 -21.48078) (xy 57.800604 -21.470752) (xy 57.808288 -21.452227)
			(xy 57.822478 -21.438055) (xy 57.841012 -21.430392) (xy 57.85104 -21.42998) (xy 58.58002 -21.42998)
			(xy 58.590027 -21.430471) (xy 58.608515 -21.438133) (xy 58.622667 -21.452285) (xy 58.630329 -21.470773)
			(xy 58.63082 -21.48078) (xy 58.63082 -22.309271) (xy 65.993006 -22.309271) (xy 65.993006 -22.224549)
			(xy 66.001059 -22.140212) (xy 66.017093 -22.057022) (xy 66.040961 -21.975732) (xy 66.072449 -21.89708)
			(xy 66.111271 -21.821777) (xy 66.157074 -21.750505) (xy 66.209445 -21.683909) (xy 66.26791 -21.622594)
			(xy 66.331938 -21.567113) (xy 66.40095 -21.51797) (xy 66.47432 -21.47561) (xy 66.551385 -21.440415)
			(xy 66.631447 -21.412706) (xy 66.71378 -21.392732) (xy 66.797639 -21.380675) (xy 66.882264 -21.376644)
			(xy 66.966889 -21.380675) (xy 67.050748 -21.392732) (xy 67.133081 -21.412706) (xy 67.213143 -21.440415)
			(xy 67.290208 -21.47561) (xy 67.363578 -21.51797) (xy 67.43259 -21.567113) (xy 67.496618 -21.622594)
			(xy 67.555083 -21.683909) (xy 67.607454 -21.750505) (xy 67.653257 -21.821777) (xy 67.692079 -21.89708)
			(xy 67.723567 -21.975732) (xy 67.747435 -22.057022) (xy 67.763469 -22.140212) (xy 67.771522 -22.224549)
			(xy 67.772026 -22.26691) (xy 67.771522 -22.309271) (xy 67.763469 -22.393608) (xy 67.747435 -22.476798)
			(xy 67.723567 -22.558088) (xy 67.722853 -22.559872) (xy 114.452596 -22.559872) (xy 114.452596 -22.505328)
			(xy 114.460358 -22.45134) (xy 114.475725 -22.399006) (xy 114.498383 -22.349391) (xy 114.527872 -22.303506)
			(xy 114.563591 -22.262285) (xy 114.604813 -22.226567) (xy 114.650698 -22.19708) (xy 114.700313 -22.174422)
			(xy 114.752648 -22.159056) (xy 114.806636 -22.151295) (xy 114.833908 -22.150832) (xy 115.697508 -22.150832)
			(xy 115.724777 -22.151331) (xy 115.778758 -22.159093) (xy 115.831086 -22.174459) (xy 115.880695 -22.197116)
			(xy 115.926574 -22.226601) (xy 115.96779 -22.262316) (xy 116.003504 -22.303533) (xy 116.032988 -22.349412)
			(xy 116.055644 -22.399021) (xy 116.071008 -22.451349) (xy 116.07877 -22.505331) (xy 116.07877 -22.559869)
			(xy 116.071008 -22.613851) (xy 116.055644 -22.666179) (xy 116.032988 -22.715788) (xy 116.003504 -22.761667)
			(xy 115.96779 -22.802884) (xy 115.926574 -22.838599) (xy 115.880695 -22.868084) (xy 115.831086 -22.890741)
			(xy 115.778758 -22.906107) (xy 115.724777 -22.913869) (xy 115.697508 -22.914356) (xy 114.833908 -22.914356)
			(xy 114.806636 -22.913905) (xy 114.752648 -22.906144) (xy 114.700313 -22.890778) (xy 114.650698 -22.86812)
			(xy 114.604813 -22.838633) (xy 114.563591 -22.802915) (xy 114.527872 -22.761694) (xy 114.498383 -22.715809)
			(xy 114.475725 -22.666194) (xy 114.460358 -22.61386) (xy 114.452596 -22.559872) (xy 67.722853 -22.559872)
			(xy 67.692079 -22.63674) (xy 67.653257 -22.712043) (xy 67.607454 -22.783315) (xy 67.555083 -22.849911)
			(xy 67.496618 -22.911226) (xy 67.43259 -22.966707) (xy 67.363578 -23.01585) (xy 67.361784 -23.016886)
			(xy 136.323137 -23.016886) (xy 136.327046 -22.962479) (xy 136.338661 -22.909183) (xy 136.357746 -22.858084)
			(xy 136.383911 -22.810221) (xy 136.416623 -22.766572) (xy 136.435592 -22.74697) (xy 137.046208 -22.1361)
			(xy 137.06783 -22.115331) (xy 137.116345 -22.080114) (xy 137.169764 -22.052902) (xy 137.226775 -22.034363)
			(xy 137.285982 -22.024951) (xy 137.315956 -22.02434) (xy 137.31621 -22.02434) (xy 137.34348 -22.024815)
			(xy 137.397464 -22.032578) (xy 137.449794 -22.047945) (xy 137.499404 -22.070602) (xy 137.545285 -22.10009)
			(xy 137.586503 -22.135806) (xy 137.622218 -22.177025) (xy 137.651703 -22.222907) (xy 137.674359 -22.272518)
			(xy 137.689724 -22.324848) (xy 137.697486 -22.378832) (xy 137.697972 -22.406102) (xy 137.697972 -22.406356)
			(xy 137.6974 -22.436336) (xy 137.688023 -22.495559) (xy 137.669494 -22.552585) (xy 137.64227 -22.606009)
			(xy 137.60702 -22.654514) (xy 137.586212 -22.676104) (xy 136.975342 -23.28672) (xy 136.955728 -23.305677)
			(xy 136.912079 -23.338389) (xy 136.864216 -23.364554) (xy 136.813117 -23.383639) (xy 136.759821 -23.395254)
			(xy 136.705414 -23.399163) (xy 136.651005 -23.395286) (xy 136.597702 -23.383703) (xy 136.546591 -23.364649)
			(xy 136.498713 -23.338513) (xy 136.455044 -23.305826) (xy 136.416474 -23.267256) (xy 136.383787 -23.223587)
			(xy 136.357651 -23.175709) (xy 136.338597 -23.124598) (xy 136.327014 -23.071295) (xy 136.323137 -23.016886)
			(xy 67.361784 -23.016886) (xy 67.290208 -23.05821) (xy 67.213143 -23.093405) (xy 67.133081 -23.121114)
			(xy 67.050748 -23.141088) (xy 66.966889 -23.153145) (xy 66.882264 -23.157177) (xy 66.797639 -23.153145)
			(xy 66.71378 -23.141088) (xy 66.631447 -23.121114) (xy 66.551385 -23.093405) (xy 66.47432 -23.05821)
			(xy 66.40095 -23.01585) (xy 66.331938 -22.966707) (xy 66.26791 -22.911226) (xy 66.209445 -22.849911)
			(xy 66.157074 -22.783315) (xy 66.111271 -22.712043) (xy 66.072449 -22.63674) (xy 66.040961 -22.558088)
			(xy 66.017093 -22.476798) (xy 66.001059 -22.393608) (xy 65.993006 -22.309271) (xy 58.63082 -22.309271)
			(xy 58.63082 -23.593552) (xy 189.619128 -23.593552) (xy 189.619128 -23.593298) (xy 189.619711 -23.54856)
			(xy 189.628722 -23.459539) (xy 189.646623 -23.371871) (xy 189.673232 -23.286444) (xy 189.690248 -23.245064)
			(xy 189.69384 -23.235481) (xy 189.693822 -23.215031) (xy 189.690248 -23.20544) (xy 189.673222 -23.164064)
			(xy 189.646604 -23.078637) (xy 189.6287 -22.990968) (xy 189.619692 -22.901945) (xy 189.619128 -22.857206)
			(xy 189.619128 -22.856952) (xy 189.619632 -22.814604) (xy 189.627683 -22.73029) (xy 189.643712 -22.647124)
			(xy 189.667573 -22.565857) (xy 189.699052 -22.487227) (xy 189.737863 -22.411946) (xy 189.783653 -22.340694)
			(xy 189.836009 -22.274118) (xy 189.894457 -22.21282) (xy 189.958467 -22.157355) (xy 190.027459 -22.108226)
			(xy 190.100809 -22.065877) (xy 190.177852 -22.030693) (xy 190.257891 -22.002991) (xy 190.3402 -21.983023)
			(xy 190.424035 -21.97097) (xy 190.508636 -21.96694) (xy 190.593237 -21.97097) (xy 190.677072 -21.983023)
			(xy 190.759381 -22.002991) (xy 190.83942 -22.030693) (xy 190.916463 -22.065877) (xy 190.989813 -22.108226)
			(xy 191.058805 -22.157355) (xy 191.122815 -22.21282) (xy 191.181263 -22.274118) (xy 191.233619 -22.340694)
			(xy 191.279409 -22.411946) (xy 191.31822 -22.487227) (xy 191.349699 -22.565857) (xy 191.37356 -22.647124)
			(xy 191.389589 -22.73029) (xy 191.39764 -22.814604) (xy 191.398144 -22.856952) (xy 191.398144 -22.857206)
			(xy 191.397557 -22.901944) (xy 191.388547 -22.990965) (xy 191.370647 -23.078632) (xy 191.344039 -23.16406)
			(xy 191.327024 -23.20544) (xy 191.323489 -23.215039) (xy 191.323471 -23.235473) (xy 191.327024 -23.245064)
			(xy 191.344055 -23.286438) (xy 191.370671 -23.371866) (xy 191.388573 -23.459535) (xy 191.39758 -23.548559)
			(xy 191.398144 -23.593298) (xy 191.398144 -23.593552) (xy 191.39764 -23.6359) (xy 191.389589 -23.720214)
			(xy 191.37356 -23.80338) (xy 191.349699 -23.884647) (xy 191.31822 -23.963277) (xy 191.279409 -24.038558)
			(xy 191.233619 -24.10981) (xy 191.181263 -24.176386) (xy 191.122815 -24.237684) (xy 191.058805 -24.293149)
			(xy 190.989813 -24.342278) (xy 190.916463 -24.384627) (xy 190.83942 -24.419811) (xy 190.759381 -24.447513)
			(xy 190.677072 -24.467481) (xy 190.593237 -24.479534) (xy 190.508636 -24.483565) (xy 190.424035 -24.479534)
			(xy 190.3402 -24.467481) (xy 190.257891 -24.447513) (xy 190.177852 -24.419811) (xy 190.100809 -24.384627)
			(xy 190.027459 -24.342278) (xy 189.958467 -24.293149) (xy 189.894457 -24.237684) (xy 189.836009 -24.176386)
			(xy 189.783653 -24.10981) (xy 189.737863 -24.038558) (xy 189.699052 -23.963277) (xy 189.667573 -23.884647)
			(xy 189.643712 -23.80338) (xy 189.627683 -23.720214) (xy 189.619632 -23.6359) (xy 189.619128 -23.593552)
			(xy 58.63082 -23.593552) (xy 58.63082 -23.63978) (xy 58.630332 -23.649788) (xy 58.622672 -23.668279)
			(xy 58.608519 -23.682432) (xy 58.590028 -23.690092) (xy 58.570012 -23.690092) (xy 58.551521 -23.682432)
			(xy 58.537368 -23.668279) (xy 58.529708 -23.649788) (xy 58.52922 -23.63978) (xy 58.52922 -21.58238)
			(xy 58.528729 -21.572373) (xy 58.521067 -21.553885) (xy 58.506915 -21.539733) (xy 58.488427 -21.532071)
			(xy 58.47842 -21.53158) (xy 57.95264 -21.53158) (xy 57.942624 -21.532052) (xy 57.924112 -21.539705)
			(xy 57.909939 -21.553861) (xy 57.902264 -21.572364) (xy 57.90184 -21.58238) (xy 57.90184 -23.63978)
			(xy 57.901352 -23.649788) (xy 57.893692 -23.668279) (xy 57.879539 -23.682432) (xy 57.861048 -23.690092)
			(xy 57.841032 -23.690092) (xy 57.822541 -23.682432) (xy 57.808388 -23.668279) (xy 57.800728 -23.649788)
			(xy 57.80024 -23.63978) (xy 32.254563 -23.63978) (xy 32.501131 -24.095202) (xy 52.59705 -24.095202)
			(xy 52.59705 -24.094694) (xy 52.597426 -24.085691) (xy 52.603676 -24.068805) (xy 52.615397 -24.055137)
			(xy 52.631134 -24.046386) (xy 52.639976 -24.044656) (xy 53.361082 -23.930356) (xy 53.368702 -23.929848)
			(xy 53.36921 -23.929848) (xy 53.378213 -23.930222) (xy 53.395099 -23.936473) (xy 53.408766 -23.948195)
			(xy 53.417518 -23.963932) (xy 53.419248 -23.972774) (xy 53.67228 -25.56891) (xy 65.510156 -25.56891)
			(xy 65.510621 -25.527206) (xy 65.518403 -25.444163) (xy 65.533928 -25.362214) (xy 65.557059 -25.282079)
			(xy 65.587593 -25.204462) (xy 65.625262 -25.130046) (xy 65.669734 -25.059485) (xy 65.720619 -24.993398)
			(xy 65.777469 -24.932368) (xy 65.839786 -24.876929) (xy 65.873122 -24.851868) (xy 65.88167 -24.844931)
			(xy 65.892346 -24.825708) (xy 65.893696 -24.814784) (xy 65.897332 -24.773398) (xy 65.911399 -24.69151)
			(xy 65.933041 -24.611291) (xy 65.962067 -24.53344) (xy 65.998226 -24.458634) (xy 66.041203 -24.387525)
			(xy 66.090622 -24.320733) (xy 66.146054 -24.25884) (xy 66.207015 -24.202385) (xy 66.272974 -24.15186)
			(xy 66.343357 -24.107705) (xy 66.41755 -24.070304) (xy 66.494907 -24.039985) (xy 66.574755 -24.01701)
			(xy 66.656396 -24.00158) (xy 66.739121 -23.99383) (xy 66.780664 -23.993348) (xy 66.824459 -23.993873)
			(xy 66.911625 -24.002491) (xy 66.997521 -24.019637) (xy 67.081315 -24.045145) (xy 67.162195 -24.078768)
			(xy 67.201034 -24.099012) (xy 67.2125 -24.10443) (xy 67.237828 -24.10443) (xy 67.249294 -24.099012)
			(xy 67.288138 -24.078781) (xy 67.369023 -24.045174) (xy 67.452816 -24.019672) (xy 67.538709 -24.002521)
			(xy 67.62587 -23.993888) (xy 67.669664 -23.993348) (xy 67.713459 -23.993873) (xy 67.800625 -24.002491)
			(xy 67.886521 -24.019637) (xy 67.970315 -24.045145) (xy 68.051195 -24.078768) (xy 68.090034 -24.099012)
			(xy 68.1015 -24.10443) (xy 68.126828 -24.10443) (xy 68.138294 -24.099012) (xy 68.177138 -24.078781)
			(xy 68.258023 -24.045174) (xy 68.341816 -24.019672) (xy 68.427709 -24.002521) (xy 68.51487 -23.993888)
			(xy 68.558664 -23.993348) (xy 68.607651 -23.994055) (xy 68.705028 -24.00487) (xy 68.752974 -24.014938)
			(xy 68.762324 -24.016604) (xy 68.781086 -24.013776) (xy 68.797533 -24.004314) (xy 68.803774 -23.997158)
			(xy 68.831851 -23.962886) (xy 68.893786 -23.899527) (xy 68.961714 -23.842641) (xy 69.034963 -23.792791)
			(xy 69.112805 -23.750472) (xy 69.19447 -23.716104) (xy 69.279148 -23.690027) (xy 69.365999 -23.672499)
			(xy 69.454163 -23.663695) (xy 69.498464 -23.663148) (xy 69.540827 -23.663615) (xy 69.625169 -23.671665)
			(xy 69.708365 -23.687697) (xy 69.789659 -23.711564) (xy 69.868317 -23.743051) (xy 69.943625 -23.781873)
			(xy 70.014902 -23.827677) (xy 70.081502 -23.880049) (xy 70.142823 -23.938516) (xy 70.198307 -24.002546)
			(xy 70.247454 -24.071561) (xy 70.250564 -24.076947) (xy 112.652614 -24.076947) (xy 112.652614 -24.022453)
			(xy 112.660369 -23.968515) (xy 112.67572 -23.916228) (xy 112.698356 -23.866659) (xy 112.727815 -23.820815)
			(xy 112.763499 -23.77963) (xy 112.80468 -23.743942) (xy 112.85052 -23.714477) (xy 112.900087 -23.691836)
			(xy 112.952372 -23.676478) (xy 113.006309 -23.668717) (xy 113.033556 -23.668228) (xy 113.897156 -23.668228)
			(xy 113.924413 -23.668616) (xy 113.978374 -23.676369) (xy 114.030682 -23.691722) (xy 114.080273 -23.714364)
			(xy 114.126136 -23.743834) (xy 114.167338 -23.779531) (xy 114.20304 -23.820729) (xy 114.232514 -23.866588)
			(xy 114.255162 -23.916176) (xy 114.270522 -23.968483) (xy 114.278281 -24.022443) (xy 114.278281 -24.076957)
			(xy 114.270522 -24.130917) (xy 114.255235 -24.182975) (xy 116.218856 -24.182975) (xy 116.218856 -24.128425)
			(xy 116.226619 -24.074429) (xy 116.241989 -24.022088) (xy 116.264651 -23.972468) (xy 116.294144 -23.926577)
			(xy 116.329868 -23.885352) (xy 116.371096 -23.84963) (xy 116.416989 -23.820139) (xy 116.466611 -23.79748)
			(xy 116.518953 -23.782114) (xy 116.572949 -23.774354) (xy 116.600224 -23.773892) (xy 117.463824 -23.773892)
			(xy 117.491089 -23.774472) (xy 117.545063 -23.782235) (xy 117.597384 -23.797601) (xy 117.646985 -23.820256)
			(xy 117.692857 -23.849739) (xy 117.734067 -23.88545) (xy 117.769776 -23.926662) (xy 117.799256 -23.972536)
			(xy 117.821907 -24.022139) (xy 117.83727 -24.07446) (xy 117.84503 -24.128435) (xy 117.84503 -24.182965)
			(xy 117.83727 -24.23694) (xy 117.821907 -24.289261) (xy 117.799256 -24.338864) (xy 117.769776 -24.384738)
			(xy 117.734067 -24.42595) (xy 117.692857 -24.461661) (xy 117.646985 -24.491144) (xy 117.597384 -24.513799)
			(xy 117.545063 -24.529165) (xy 117.491089 -24.536928) (xy 117.463824 -24.537416) (xy 116.600224 -24.537416)
			(xy 116.572949 -24.537046) (xy 116.518953 -24.529286) (xy 116.466611 -24.51392) (xy 116.416989 -24.491261)
			(xy 116.371096 -24.46177) (xy 116.329868 -24.426049) (xy 116.294144 -24.384823) (xy 116.264651 -24.338932)
			(xy 116.241989 -24.289312) (xy 116.226619 -24.236971) (xy 116.218856 -24.182975) (xy 114.255235 -24.182975)
			(xy 114.255162 -24.183224) (xy 114.232514 -24.232812) (xy 114.20304 -24.278671) (xy 114.167338 -24.319869)
			(xy 114.126136 -24.355566) (xy 114.080273 -24.385036) (xy 114.030682 -24.407678) (xy 113.978374 -24.423031)
			(xy 113.924414 -24.430784) (xy 113.897156 -24.431244) (xy 113.033556 -24.431244) (xy 113.006309 -24.430683)
			(xy 112.952372 -24.422922) (xy 112.900087 -24.407564) (xy 112.85052 -24.384923) (xy 112.80468 -24.355458)
			(xy 112.763499 -24.31977) (xy 112.727815 -24.278585) (xy 112.698356 -24.232741) (xy 112.67572 -24.183172)
			(xy 112.660369 -24.130885) (xy 112.652614 -24.076947) (xy 70.250564 -24.076947) (xy 70.289818 -24.144935)
			(xy 70.325015 -24.222004) (xy 70.352727 -24.302069) (xy 70.372702 -24.384407) (xy 70.38476 -24.46827)
			(xy 70.388792 -24.5529) (xy 70.38476 -24.63753) (xy 70.37544 -24.702351) (xy 130.235962 -24.702351)
			(xy 130.235962 -24.647849) (xy 130.243717 -24.593903) (xy 130.259071 -24.541609) (xy 130.28171 -24.492033)
			(xy 130.311174 -24.446182) (xy 130.346863 -24.404991) (xy 130.38805 -24.369298) (xy 130.433897 -24.33983)
			(xy 130.483472 -24.317185) (xy 130.535764 -24.301826) (xy 130.589709 -24.294065) (xy 130.61696 -24.293576)
			(xy 131.48056 -24.293576) (xy 131.507814 -24.294069) (xy 131.561767 -24.301821) (xy 131.614067 -24.317173)
			(xy 131.66365 -24.339812) (xy 131.709506 -24.369277) (xy 131.750702 -24.40497) (xy 131.786399 -24.446162)
			(xy 131.815869 -24.492015) (xy 131.838513 -24.541595) (xy 131.853871 -24.593894) (xy 131.861629 -24.647846)
			(xy 131.861629 -24.702354) (xy 131.853871 -24.756306) (xy 131.838513 -24.808605) (xy 131.815869 -24.858185)
			(xy 131.786399 -24.904038) (xy 131.750702 -24.94523) (xy 131.709506 -24.980923) (xy 131.66365 -25.010388)
			(xy 131.614067 -25.033027) (xy 131.561767 -25.048379) (xy 131.507814 -25.056131) (xy 131.48056 -25.056592)
			(xy 130.61696 -25.056592) (xy 130.589709 -25.056135) (xy 130.535764 -25.048374) (xy 130.483472 -25.033015)
			(xy 130.433897 -25.01037) (xy 130.38805 -24.980902) (xy 130.346863 -24.945209) (xy 130.311174 -24.904018)
			(xy 130.28171 -24.858167) (xy 130.259071 -24.808591) (xy 130.243717 -24.756297) (xy 130.235962 -24.702351)
			(xy 70.37544 -24.702351) (xy 70.372702 -24.721393) (xy 70.352727 -24.803731) (xy 70.325015 -24.883796)
			(xy 70.289818 -24.960865) (xy 70.247454 -25.034239) (xy 70.198307 -25.103254) (xy 70.142823 -25.167284)
			(xy 70.081502 -25.225751) (xy 70.014902 -25.278123) (xy 69.943625 -25.323927) (xy 69.868317 -25.362749)
			(xy 69.789659 -25.394236) (xy 69.708365 -25.418103) (xy 69.625169 -25.434135) (xy 69.540827 -25.442185)
			(xy 69.498464 -25.442672) (xy 69.449476 -25.441976) (xy 69.3521 -25.431154) (xy 69.304154 -25.421082)
			(xy 69.294812 -25.41935) (xy 69.276039 -25.422204) (xy 69.259591 -25.431693) (xy 69.253354 -25.438862)
			(xy 69.228687 -25.46901) (xy 69.174875 -25.52534) (xy 69.116354 -25.57676) (xy 69.085206 -25.600152)
			(xy 69.076637 -25.607067) (xy 69.065975 -25.626306) (xy 69.065849 -25.62733) (xy 133.339332 -25.62733)
			(xy 133.339332 -24.76373) (xy 133.339818 -24.736479) (xy 133.347574 -24.682531) (xy 133.362929 -24.630236)
			(xy 133.385571 -24.580659) (xy 133.415037 -24.534809) (xy 133.450728 -24.493618) (xy 133.491919 -24.457927)
			(xy 133.537769 -24.428461) (xy 133.587346 -24.405819) (xy 133.639641 -24.390464) (xy 133.693589 -24.382708)
			(xy 133.748091 -24.382708) (xy 133.802039 -24.390464) (xy 133.854334 -24.405819) (xy 133.903911 -24.428461)
			(xy 133.949761 -24.457927) (xy 133.990952 -24.493618) (xy 134.026643 -24.534809) (xy 134.056109 -24.580659)
			(xy 134.078751 -24.630236) (xy 134.094106 -24.682531) (xy 134.101862 -24.736479) (xy 134.102348 -24.76373)
			(xy 134.102348 -25.62733) (xy 134.101862 -25.654581) (xy 134.094106 -25.708529) (xy 134.078751 -25.760824)
			(xy 134.056109 -25.810401) (xy 134.026643 -25.856251) (xy 133.990952 -25.897442) (xy 133.949761 -25.933133)
			(xy 133.903911 -25.962599) (xy 133.854334 -25.985241) (xy 133.802039 -26.000596) (xy 133.748091 -26.008352)
			(xy 133.693589 -26.008352) (xy 133.639641 -26.000596) (xy 133.587346 -25.985241) (xy 133.537769 -25.962599)
			(xy 133.491919 -25.933133) (xy 133.450728 -25.897442) (xy 133.415037 -25.856251) (xy 133.385571 -25.810401)
			(xy 133.362929 -25.760824) (xy 133.347574 -25.708529) (xy 133.339818 -25.654581) (xy 133.339332 -25.62733)
			(xy 69.065849 -25.62733) (xy 69.064632 -25.637236) (xy 69.060986 -25.678621) (xy 69.046917 -25.760507)
			(xy 69.025275 -25.840725) (xy 68.996248 -25.918575) (xy 68.960089 -25.99338) (xy 68.917113 -26.064488)
			(xy 68.867694 -26.131279) (xy 68.812263 -26.193171) (xy 68.751303 -26.249626) (xy 68.685345 -26.300151)
			(xy 68.614964 -26.344307) (xy 68.540772 -26.381708) (xy 68.463416 -26.412028) (xy 68.38357 -26.435004)
			(xy 68.30193 -26.450436) (xy 68.219207 -26.458189) (xy 68.177664 -26.458672) (xy 68.133869 -26.458133)
			(xy 68.046704 -26.449518) (xy 67.960808 -26.432375) (xy 67.877014 -26.40687) (xy 67.796134 -26.37325)
			(xy 67.757294 -26.353008) (xy 67.745828 -26.34759) (xy 67.7205 -26.34759) (xy 67.709034 -26.353008)
			(xy 67.670181 -26.373222) (xy 67.589299 -26.406833) (xy 67.505508 -26.43234) (xy 67.419618 -26.449494)
			(xy 67.332457 -26.458131) (xy 67.288664 -26.458672) (xy 67.244869 -26.458133) (xy 67.157704 -26.449518)
			(xy 67.071808 -26.432375) (xy 66.988014 -26.40687) (xy 66.907134 -26.37325) (xy 66.868294 -26.353008)
			(xy 66.856828 -26.34759) (xy 66.8315 -26.34759) (xy 66.820034 -26.353008) (xy 66.781181 -26.373222)
			(xy 66.700299 -26.406833) (xy 66.616508 -26.43234) (xy 66.530618 -26.449494) (xy 66.443457 -26.458131)
			(xy 66.399664 -26.458672) (xy 66.358552 -26.458282) (xy 66.276678 -26.45069) (xy 66.195855 -26.435576)
			(xy 66.116771 -26.413067) (xy 66.040102 -26.383356) (xy 65.966502 -26.346696) (xy 65.8966 -26.3034)
			(xy 65.830991 -26.253838) (xy 65.770236 -26.198433) (xy 65.714853 -26.137658) (xy 65.665316 -26.072031)
			(xy 65.622046 -26.002113) (xy 65.585413 -25.928499) (xy 65.55573 -25.85182) (xy 65.53325 -25.772728)
			(xy 65.518165 -25.691899) (xy 65.510603 -25.610022) (xy 65.510156 -25.56891) (xy 53.67228 -25.56891)
			(xy 53.757322 -26.105358) (xy 53.75783 -26.112978) (xy 53.75783 -26.113486) (xy 53.757295 -26.123458)
			(xy 53.749585 -26.141858) (xy 53.735443 -26.155929) (xy 53.717005 -26.163546) (xy 53.70703 -26.164032)
			(xy 53.698 -26.163643) (xy 53.681043 -26.157441) (xy 53.667301 -26.145729) (xy 53.658489 -26.12997)
			(xy 53.656738 -26.121106) (xy 53.334666 -24.089106) (xy 53.332672 -24.079263) (xy 53.32221 -24.062141)
			(xy 53.305992 -24.050325) (xy 53.286487 -24.045615) (xy 53.2765 -24.046688) (xy 52.756308 -24.129238)
			(xy 52.74644 -24.131163) (xy 52.729294 -24.14164) (xy 52.717462 -24.157881) (xy 52.712746 -24.177414)
			(xy 52.71389 -24.187404) (xy 53.036216 -26.219658) (xy 53.036724 -26.227278) (xy 53.036724 -26.227786)
			(xy 53.036194 -26.237759) (xy 53.028484 -26.25616) (xy 53.01434 -26.270231) (xy 52.995899 -26.277847)
			(xy 52.985924 -26.278332) (xy 52.976894 -26.277948) (xy 52.959937 -26.271744) (xy 52.946195 -26.260031)
			(xy 52.937383 -26.24427) (xy 52.935632 -26.235406) (xy 52.597558 -24.102822) (xy 52.59705 -24.095202)
			(xy 32.501131 -24.095202) (xy 32.84121 -24.723344) (xy 34.532316 -24.723344) (xy 34.532316 -24.72309)
			(xy 34.532776 -24.713708) (xy 34.539524 -24.696198) (xy 34.552087 -24.682258) (xy 34.560256 -24.677624)
			(xy 35.212274 -24.349456) (xy 35.217591 -24.34697) (xy 35.229013 -24.344283) (xy 35.23488 -24.344122)
			(xy 35.235134 -24.344122) (xy 35.244518 -24.344562) (xy 35.262029 -24.351318) (xy 35.275968 -24.363889)
			(xy 35.2806 -24.372062) (xy 35.316522 -24.443436) (xy 47.696628 -24.443436) (xy 47.696628 -24.443182)
			(xy 47.697216 -24.432056) (xy 47.706695 -24.411925) (xy 47.723842 -24.397743) (xy 47.734474 -24.394414)
			(xy 48.440086 -24.207724) (xy 48.45304 -24.205946) (xy 48.453294 -24.205946) (xy 48.464417 -24.206535)
			(xy 48.48454 -24.216024) (xy 48.498725 -24.233165) (xy 48.502062 -24.243792) (xy 49.054766 -26.33091)
			(xy 49.056544 -26.343864) (xy 49.056544 -26.344118) (xy 49.05594 -26.354084) (xy 49.048255 -26.37248)
			(xy 49.034134 -26.386553) (xy 49.015712 -26.394174) (xy 49.005744 -26.394664) (xy 48.994584 -26.39405)
			(xy 48.974356 -26.384627) (xy 48.960084 -26.367473) (xy 48.956722 -26.356818) (xy 48.429926 -24.367744)
			(xy 48.4269 -24.358213) (xy 48.414794 -24.342322) (xy 48.397528 -24.332273) (xy 48.377732 -24.329596)
			(xy 48.36795 -24.331676) (xy 47.85868 -24.46655) (xy 47.849134 -24.469558) (xy 47.833221 -24.481664)
			(xy 47.823154 -24.49894) (xy 47.820466 -24.518753) (xy 47.822612 -24.528526) (xy 48.349154 -26.5176)
			(xy 48.350932 -26.530554) (xy 48.350932 -26.530808) (xy 48.350331 -26.540775) (xy 48.342647 -26.559172)
			(xy 48.328525 -26.573246) (xy 48.310101 -26.580866) (xy 48.300132 -26.581354) (xy 48.28897 -26.580757)
			(xy 48.268741 -26.571326) (xy 48.25447 -26.554166) (xy 48.25111 -26.543508) (xy 47.698406 -24.45639)
			(xy 47.696628 -24.443436) (xy 35.316522 -24.443436) (xy 36.251134 -26.30043) (xy 36.253605 -26.305753)
			(xy 36.256302 -26.31717) (xy 36.256468 -26.323036) (xy 36.256468 -26.32329) (xy 36.256072 -26.333315)
			(xy 36.248399 -26.351838) (xy 36.234219 -26.366011) (xy 36.215693 -26.373676) (xy 36.205668 -26.37409)
			(xy 36.196285 -26.373643) (xy 36.178775 -26.366888) (xy 36.164836 -26.354321) (xy 36.160202 -26.34615)
			(xy 35.235388 -24.508714) (xy 35.230431 -24.499988) (xy 35.215259 -24.48689) (xy 35.19623 -24.48059)
			(xy 35.176238 -24.482048) (xy 35.167062 -24.486108) (xy 34.696908 -24.722836) (xy 34.688165 -24.727766)
			(xy 34.675067 -24.742948) (xy 34.668771 -24.761986) (xy 34.670236 -24.781984) (xy 34.674302 -24.791162)
			(xy 35.599116 -26.628598) (xy 35.601576 -26.633925) (xy 35.60428 -26.645339) (xy 35.60445 -26.651204)
			(xy 35.60445 -26.651458) (xy 35.603879 -26.661457) (xy 35.596242 -26.679938) (xy 35.582115 -26.694091)
			(xy 35.563648 -26.70176) (xy 35.55365 -26.702258) (xy 35.544264 -26.70184) (xy 35.52675 -26.695075)
			(xy 35.512814 -26.682495) (xy 35.508184 -26.674318) (xy 34.53765 -24.74595) (xy 34.535171 -24.74063)
			(xy 34.532479 -24.729211) (xy 34.532316 -24.723344) (xy 32.84121 -24.723344) (xy 32.872426 -24.781002)
			(xy 32.875262 -24.786626) (xy 32.878338 -24.798836) (xy 32.878522 -24.805132) (xy 32.878039 -24.815139)
			(xy 32.870373 -24.833627) (xy 32.856219 -24.847778) (xy 32.837729 -24.855441) (xy 32.827722 -24.855932)
			(xy 32.818587 -24.855519) (xy 32.801475 -24.849116) (xy 32.787698 -24.837116) (xy 32.783018 -24.829262)
			(xy 31.80334 -23.02002) (xy 31.798162 -23.011432) (xy 31.782637 -22.998773) (xy 31.763448 -22.993023)
			(xy 31.74352 -22.99506) (xy 31.734506 -22.999446) (xy 31.328868 -23.21941) (xy 31.27121 -23.250906)
			(xy 31.26271 -23.256119) (xy 31.250177 -23.271597) (xy 31.244513 -23.29069) (xy 31.246577 -23.310498)
			(xy 31.25089 -23.319486) (xy 32.230568 -25.128728) (xy 32.233382 -25.134361) (xy 32.236471 -25.146564)
			(xy 32.236664 -25.152858) (xy 32.236245 -25.162881) (xy 32.228582 -25.181404) (xy 32.214409 -25.195579)
			(xy 32.195887 -25.203244) (xy 32.185864 -25.203658) (xy 32.176721 -25.203324) (xy 32.159602 -25.196891)
			(xy 32.145831 -25.184858) (xy 32.14116 -25.176988) (xy 31.113222 -23.278338) (xy 31.110402 -23.272707)
			(xy 31.107315 -23.260502) (xy 31.107126 -23.254208) (xy 28.548235 -23.254208) (xy 28.565348 -23.283418)
			(xy 28.568543 -23.289274) (xy 28.572014 -23.30215) (xy 28.572206 -23.308818) (xy 28.572206 -23.309072)
			(xy 28.571758 -23.319091) (xy 28.564098 -23.337606) (xy 28.549934 -23.351779) (xy 28.531424 -23.359451)
			(xy 28.521406 -23.359872) (xy 28.512558 -23.359465) (xy 28.495913 -23.353448) (xy 28.482286 -23.342155)
			(xy 28.477464 -23.334726) (xy 27.38628 -21.47189) (xy 27.383083 -21.466035) (xy 27.379614 -21.453158)
			(xy 27.379422 -21.44649) (xy 22.864579 -21.44649) (xy 23.46325 -22.340824) (xy 23.467181 -22.347206)
			(xy 23.471577 -22.361529) (xy 23.471886 -22.369018) (xy 23.471427 -22.379029) (xy 23.463758 -22.397524)
			(xy 23.449597 -22.411676) (xy 23.431097 -22.419333) (xy 23.421086 -22.419818) (xy 23.40853 -22.41919)
			(xy 23.386404 -22.407317) (xy 23.378922 -22.397212) (xy 22.234398 -20.687538) (xy 22.228451 -20.679483)
			(xy 22.211824 -20.668364) (xy 22.192206 -20.664458) (xy 22.172588 -20.668359) (xy 22.16404 -20.673568)
			(xy 22.027388 -20.765008) (xy 21.742146 -20.95627) (xy 21.726144 -20.966938) (xy 21.718097 -20.972876)
			(xy 21.707027 -20.989512) (xy 21.703144 -21.009113) (xy 21.707037 -21.028713) (xy 21.712174 -21.037296)
			(xy 22.856698 -22.74697) (xy 22.86065 -22.753341) (xy 22.865032 -22.767673) (xy 22.865334 -22.775164)
			(xy 22.864852 -22.785179) (xy 22.8572 -22.803688) (xy 22.843047 -22.817861) (xy 22.824548 -22.825538)
			(xy 22.814534 -22.825964) (xy 22.801985 -22.825289) (xy 22.779859 -22.813448) (xy 22.77237 -22.803358)
			(xy 21.571458 -21.009356) (xy 21.567512 -21.002982) (xy 21.563127 -20.988653) (xy 21.562822 -20.981162)
			(xy 0.509016 -20.981162) (xy 0.509016 -22.027896) (xy 16.790924 -22.027896) (xy 16.791563 -22.016014)
			(xy 16.802307 -21.994815) (xy 16.811498 -21.987256) (xy 17.396968 -21.551392) (xy 17.403642 -21.546737)
			(xy 17.419063 -21.541565) (xy 17.427194 -21.541232) (xy 17.439076 -21.541874) (xy 17.460275 -21.552615)
			(xy 17.467834 -21.561806) (xy 18.756884 -23.293578) (xy 18.761512 -23.300269) (xy 18.766699 -23.315677)
			(xy 18.767044 -23.323804) (xy 18.766516 -23.333806) (xy 18.758864 -23.35229) (xy 18.744723 -23.366441)
			(xy 18.726246 -23.374108) (xy 18.716244 -23.374604) (xy 18.704367 -23.373927) (xy 18.683168 -23.363209)
			(xy 18.675604 -23.35403) (xy 17.447006 -21.703792) (xy 17.440613 -21.696129) (xy 17.423495 -21.685919)
			(xy 17.403777 -21.68301) (xy 17.384441 -21.687843) (xy 17.37614 -21.693378) (xy 16.953484 -22.008084)
			(xy 16.945742 -22.014393) (xy 16.93554 -22.031544) (xy 16.932653 -22.051291) (xy 16.937517 -22.070646)
			(xy 16.94307 -22.07895) (xy 17.962342 -23.448518) (xy 20.534122 -23.448518) (xy 20.534803 -23.436355)
			(xy 20.54595 -23.414734) (xy 20.555458 -23.407116) (xy 21.151088 -22.985222) (xy 21.157682 -22.980911)
			(xy 21.17268 -22.976122) (xy 21.180552 -22.975824) (xy 21.192713 -22.976522) (xy 21.214335 -22.987657)
			(xy 21.221954 -22.99716) (xy 21.366946 -23.201884) (xy 25.724866 -23.201884) (xy 25.724866 -23.20163)
			(xy 25.725218 -23.193024) (xy 25.730911 -23.17678) (xy 25.741637 -23.163318) (xy 25.748742 -23.15845)
			(xy 26.367486 -22.7711) (xy 26.373585 -22.767579) (xy 26.387118 -22.763707) (xy 26.394156 -22.76348)
			(xy 26.39441 -22.76348) (xy 26.403019 -22.763799) (xy 26.419265 -22.769506) (xy 26.432725 -22.780245)
			(xy 26.43759 -22.787356) (xy 27.58313 -24.617426) (xy 27.58666 -24.62352) (xy 27.590528 -24.637057)
			(xy 27.59075 -24.644096) (xy 27.59075 -24.64435) (xy 27.590254 -24.654355) (xy 27.582587 -24.672838)
			(xy 27.568438 -24.686987) (xy 27.549955 -24.694654) (xy 27.53995 -24.69515) (xy 27.531346 -24.694777)
			(xy 27.515103 -24.689093) (xy 27.50164 -24.678375) (xy 27.49677 -24.671274) (xy 26.405332 -22.927564)
			(xy 26.399663 -22.919277) (xy 26.383332 -22.907622) (xy 26.363785 -22.903104) (xy 26.343996 -22.906409)
			(xy 26.335228 -22.911308) (xy 26.011632 -23.113746) (xy 26.008584 -23.115778) (xy 25.88895 -23.190708)
			(xy 25.880709 -23.196435) (xy 25.869055 -23.212744) (xy 25.864525 -23.232272) (xy 25.867809 -23.252046)
			(xy 25.872694 -23.260812) (xy 26.964386 -25.004776) (xy 26.967902 -25.010877) (xy 26.971777 -25.024408)
			(xy 26.972006 -25.031446) (xy 26.972006 -25.0317) (xy 26.971512 -25.041707) (xy 26.963854 -25.060197)
			(xy 26.949703 -25.07435) (xy 26.931213 -25.082011) (xy 26.921206 -25.0825) (xy 26.912602 -25.082135)
			(xy 26.896361 -25.076443) (xy 26.882897 -25.065725) (xy 26.878026 -25.058624) (xy 25.732486 -23.228554)
			(xy 25.728942 -23.222467) (xy 25.725084 -23.208925) (xy 25.724866 -23.201884) (xy 21.366946 -23.201884)
			(xy 22.469856 -24.759158) (xy 22.474192 -24.765737) (xy 22.478966 -24.780747) (xy 22.479254 -24.788622)
			(xy 22.478897 -24.79865) (xy 22.471211 -24.817177) (xy 22.457019 -24.83135) (xy 22.438483 -24.839011)
			(xy 22.428454 -24.839422) (xy 22.41629 -24.838741) (xy 22.394667 -24.827596) (xy 22.387052 -24.818086)
			(xy 21.197824 -23.138892) (xy 21.191605 -23.131036) (xy 21.174642 -23.120413) (xy 21.154907 -23.117085)
			(xy 21.135398 -23.121556) (xy 21.126958 -23.126954) (xy 20.69719 -23.431246) (xy 20.689274 -23.437398)
			(xy 20.678657 -23.454387) (xy 20.675344 -23.474146) (xy 20.679839 -23.493669) (xy 20.685252 -23.502112)
			(xy 21.874226 -25.181052) (xy 21.878557 -25.187634) (xy 21.883335 -25.202641) (xy 21.883624 -25.210516)
			(xy 21.883126 -25.220522) (xy 21.875465 -25.239009) (xy 21.861316 -25.253161) (xy 21.84283 -25.260824)
			(xy 21.832824 -25.261316) (xy 21.820657 -25.260655) (xy 21.799035 -25.249496) (xy 21.791422 -25.23998)
			(xy 20.54352 -23.477982) (xy 20.539197 -23.471395) (xy 20.534415 -23.456391) (xy 20.534122 -23.448518)
			(xy 17.962342 -23.448518) (xy 18.171414 -23.729442) (xy 18.17606 -23.736122) (xy 18.181237 -23.751538)
			(xy 18.181574 -23.759668) (xy 18.181153 -23.76969) (xy 18.173489 -23.788212) (xy 18.159317 -23.802386)
			(xy 18.140796 -23.810052) (xy 18.130774 -23.810468) (xy 18.11889 -23.809845) (xy 18.097691 -23.79909)
			(xy 18.090134 -23.789894) (xy 16.801084 -22.058122) (xy 16.796463 -22.051427) (xy 16.791271 -22.036022)
			(xy 16.790924 -22.027896) (xy 0.509016 -22.027896) (xy 0.509016 -29.026161) (xy 11.140205 -29.026161)
			(xy 11.147539 -28.866724) (xy 11.162812 -28.70785) (xy 11.185984 -28.549934) (xy 11.216999 -28.39337)
			(xy 11.255779 -28.238547) (xy 11.302228 -28.085849) (xy 11.35623 -27.935656) (xy 11.417652 -27.788341)
			(xy 11.48634 -27.644271) (xy 11.562123 -27.503804) (xy 11.644814 -27.367289) (xy 11.734207 -27.235065)
			(xy 11.830079 -27.107461) (xy 11.932193 -26.984794) (xy 12.040293 -26.86737) (xy 12.154112 -26.75548)
			(xy 12.273367 -26.649402) (xy 12.397761 -26.5494) (xy 12.526985 -26.455723) (xy 12.660717 -26.368604)
			(xy 12.798626 -26.288258) (xy 12.940368 -26.214886) (xy 13.085591 -26.148671) (xy 13.233934 -26.089776)
			(xy 13.385028 -26.038349) (xy 13.538498 -25.994517) (xy 13.693962 -25.958388) (xy 13.851033 -25.930054)
			(xy 14.009321 -25.909584) (xy 14.168433 -25.897029) (xy 14.327973 -25.892421) (xy 14.487544 -25.895771)
			(xy 14.64675 -25.90707) (xy 14.805195 -25.92629) (xy 14.962485 -25.953385) (xy 15.118229 -25.988285)
			(xy 15.272039 -26.030905) (xy 15.423535 -26.081139) (xy 15.572338 -26.138862) (xy 15.718078 -26.203929)
			(xy 15.860395 -26.27618) (xy 15.998933 -26.355436) (xy 16.133349 -26.441497) (xy 16.263308 -26.534152)
			(xy 16.388487 -26.633169) (xy 16.508575 -26.738303) (xy 16.623273 -26.849292) (xy 16.678148 -26.907236)
			(xy 17.470427 -27.75458) (xy 130.687572 -27.75458) (xy 130.687572 -26.76398) (xy 130.688058 -26.736729)
			(xy 130.695814 -26.682781) (xy 130.711169 -26.630486) (xy 130.733811 -26.580909) (xy 130.763277 -26.535059)
			(xy 130.798968 -26.493868) (xy 130.840159 -26.458177) (xy 130.886009 -26.428711) (xy 130.935586 -26.406069)
			(xy 130.987881 -26.390714) (xy 131.041829 -26.382958) (xy 131.096331 -26.382958) (xy 131.150279 -26.390714)
			(xy 131.202574 -26.406069) (xy 131.252151 -26.428711) (xy 131.298001 -26.458177) (xy 131.339192 -26.493868)
			(xy 131.374883 -26.535059) (xy 131.404349 -26.580909) (xy 131.426991 -26.630486) (xy 131.442346 -26.682781)
			(xy 131.450102 -26.736729) (xy 131.450588 -26.76398) (xy 131.450588 -26.76779) (xy 141.621764 -26.76779)
			(xy 141.621764 -25.90419) (xy 141.62225 -25.876921) (xy 141.630012 -25.822937) (xy 141.645377 -25.770607)
			(xy 141.668034 -25.720997) (xy 141.69752 -25.675116) (xy 141.733235 -25.633899) (xy 141.774452 -25.598184)
			(xy 141.820333 -25.568698) (xy 141.869943 -25.546041) (xy 141.922273 -25.530676) (xy 141.976257 -25.522914)
			(xy 142.030795 -25.522914) (xy 142.084779 -25.530676) (xy 142.137109 -25.546041) (xy 142.186719 -25.568698)
			(xy 142.2326 -25.598184) (xy 142.273817 -25.633899) (xy 142.309532 -25.675116) (xy 142.339018 -25.720997)
			(xy 142.361675 -25.770607) (xy 142.37704 -25.822937) (xy 142.384802 -25.876921) (xy 142.385288 -25.90419)
			(xy 142.385288 -26.634948) (xy 175.442372 -26.634948) (xy 175.442817 -26.593237) (xy 175.450618 -26.510181)
			(xy 175.466165 -26.428221) (xy 175.489321 -26.348077) (xy 175.519883 -26.270455) (xy 175.557582 -26.196038)
			(xy 175.602086 -26.125479) (xy 175.653004 -26.059399) (xy 175.709888 -25.99838) (xy 175.772239 -25.942957)
			(xy 175.805592 -25.917906) (xy 175.814178 -25.911009) (xy 175.82483 -25.891756) (xy 175.826166 -25.880822)
			(xy 175.829855 -25.839448) (xy 175.843941 -25.757582) (xy 175.865598 -25.677385) (xy 175.894637 -25.599556)
			(xy 175.930804 -25.524774) (xy 175.973785 -25.453688) (xy 176.023205 -25.386918) (xy 176.078634 -25.325046)
			(xy 176.13959 -25.268611) (xy 176.205541 -25.218103) (xy 176.275913 -25.173964) (xy 176.350094 -25.136576)
			(xy 176.427436 -25.106267) (xy 176.507267 -25.083299) (xy 176.588892 -25.067873) (xy 176.671599 -25.060123)
			(xy 176.713134 -25.05964) (xy 176.713642 -25.05964) (xy 176.757406 -25.060139) (xy 176.844513 -25.068717)
			(xy 176.930355 -25.085818) (xy 177.0141 -25.111273) (xy 177.094937 -25.144838) (xy 177.133758 -25.16505)
			(xy 177.145111 -25.170377) (xy 177.170157 -25.170377) (xy 177.18151 -25.16505) (xy 177.22038 -25.144826)
			(xy 177.301322 -25.111257) (xy 177.38517 -25.085803) (xy 177.471113 -25.068709) (xy 177.55832 -25.060143)
			(xy 177.602134 -25.05964) (xy 177.645949 -25.060116) (xy 177.733161 -25.068665) (xy 177.819109 -25.085756)
			(xy 177.902957 -25.111222) (xy 177.983891 -25.144816) (xy 178.022758 -25.16505) (xy 178.034111 -25.170377)
			(xy 178.059157 -25.170377) (xy 178.07051 -25.16505) (xy 178.10938 -25.144826) (xy 178.190322 -25.111257)
			(xy 178.27417 -25.085803) (xy 178.360113 -25.068709) (xy 178.44732 -25.060143) (xy 178.491134 -25.05964)
			(xy 178.541288 -25.060291) (xy 178.640969 -25.071493) (xy 178.690016 -25.081992) (xy 178.700529 -25.083816)
			(xy 178.72144 -25.079687) (xy 178.7389 -25.067462) (xy 178.74488 -25.058624) (xy 178.766746 -25.023211)
			(xy 178.816155 -24.956227) (xy 178.871604 -24.894151) (xy 178.932608 -24.837525) (xy 178.998633 -24.786843)
			(xy 179.069104 -24.742549) (xy 179.143403 -24.705031) (xy 179.220882 -24.674615) (xy 179.300862 -24.651569)
			(xy 179.382645 -24.636093) (xy 179.465517 -24.628322) (xy 179.507134 -24.62784) (xy 179.549484 -24.628249)
			(xy 179.633799 -24.636303) (xy 179.716968 -24.652336) (xy 179.798236 -24.676201) (xy 179.876867 -24.707683)
			(xy 179.95215 -24.746496) (xy 180.023403 -24.79229) (xy 180.08998 -24.844649) (xy 180.151278 -24.9031)
			(xy 180.206744 -24.967112) (xy 180.255873 -25.036107) (xy 180.298222 -25.10946) (xy 180.333407 -25.186506)
			(xy 180.361109 -25.266547) (xy 180.381077 -25.348859) (xy 180.39313 -25.432696) (xy 180.397161 -25.5173)
			(xy 180.39313 -25.601904) (xy 180.381077 -25.685741) (xy 180.361109 -25.768053) (xy 180.333407 -25.848094)
			(xy 180.298222 -25.92514) (xy 180.255873 -25.998493) (xy 180.206744 -26.067488) (xy 180.151278 -26.1315)
			(xy 180.08998 -26.189951) (xy 180.023403 -26.24231) (xy 179.95215 -26.288104) (xy 179.876867 -26.326917)
			(xy 179.798236 -26.358399) (xy 179.716968 -26.382264) (xy 179.633799 -26.398297) (xy 179.549484 -26.406351)
			(xy 179.507134 -26.406856) (xy 179.505864 -26.406856) (xy 179.456029 -26.406131) (xy 179.35699 -26.394927)
			(xy 179.308252 -26.384504) (xy 179.297742 -26.382653) (xy 179.276827 -26.386794) (xy 179.259367 -26.39903)
			(xy 179.253388 -26.407872) (xy 179.230217 -26.445289) (xy 179.177598 -26.515842) (xy 179.118275 -26.58086)
			(xy 179.052827 -26.639708) (xy 179.017676 -26.66619) (xy 179.009104 -26.673102) (xy 178.998441 -26.692343)
			(xy 178.997102 -26.703274) (xy 178.993441 -26.744651) (xy 178.979354 -26.826519) (xy 178.957697 -26.906717)
			(xy 178.928657 -26.984547) (xy 178.892489 -27.059331) (xy 178.849506 -27.130418) (xy 178.835198 -27.149749)
			(xy 180.032656 -27.149749) (xy 180.032656 -27.065027) (xy 180.040709 -26.98069) (xy 180.056743 -26.8975)
			(xy 180.080611 -26.81621) (xy 180.112099 -26.737558) (xy 180.150921 -26.662255) (xy 180.196724 -26.590983)
			(xy 180.249095 -26.524387) (xy 180.30756 -26.463072) (xy 180.371588 -26.407591) (xy 180.4406 -26.358448)
			(xy 180.51397 -26.316088) (xy 180.591035 -26.280893) (xy 180.671097 -26.253184) (xy 180.75343 -26.23321)
			(xy 180.837289 -26.221153) (xy 180.921914 -26.217122) (xy 181.006539 -26.221153) (xy 181.090398 -26.23321)
			(xy 181.172731 -26.253184) (xy 181.252793 -26.280893) (xy 181.329858 -26.316088) (xy 181.403228 -26.358448)
			(xy 181.47224 -26.407591) (xy 181.536268 -26.463072) (xy 181.594733 -26.524387) (xy 181.647104 -26.590983)
			(xy 181.692907 -26.662255) (xy 181.731729 -26.737558) (xy 181.763217 -26.81621) (xy 181.787085 -26.8975)
			(xy 181.803119 -26.98069) (xy 181.811172 -27.065027) (xy 181.811676 -27.107388) (xy 181.811172 -27.149749)
			(xy 181.803119 -27.234086) (xy 181.787085 -27.317276) (xy 181.763217 -27.398566) (xy 181.731729 -27.477218)
			(xy 181.692907 -27.552521) (xy 181.647104 -27.623793) (xy 181.594733 -27.690389) (xy 181.536268 -27.751704)
			(xy 181.47224 -27.807185) (xy 181.403228 -27.856328) (xy 181.329858 -27.898688) (xy 181.252793 -27.933883)
			(xy 181.172731 -27.961592) (xy 181.090398 -27.981566) (xy 181.006539 -27.993623) (xy 180.921914 -27.997655)
			(xy 180.837289 -27.993623) (xy 180.75343 -27.981566) (xy 180.671097 -27.961592) (xy 180.591035 -27.933883)
			(xy 180.51397 -27.898688) (xy 180.4406 -27.856328) (xy 180.371588 -27.807185) (xy 180.30756 -27.751704)
			(xy 180.249095 -27.690389) (xy 180.196724 -27.623793) (xy 180.150921 -27.552521) (xy 180.112099 -27.477218)
			(xy 180.080611 -27.398566) (xy 180.056743 -27.317276) (xy 180.040709 -27.234086) (xy 180.032656 -27.149749)
			(xy 178.835198 -27.149749) (xy 178.800084 -27.197189) (xy 178.744653 -27.259061) (xy 178.683695 -27.315497)
			(xy 178.617742 -27.366004) (xy 178.547367 -27.410143) (xy 178.473184 -27.447529) (xy 178.395839 -27.477837)
			(xy 178.316006 -27.500803) (xy 178.234379 -27.516227) (xy 178.15167 -27.523974) (xy 178.110134 -27.524456)
			(xy 178.109626 -27.524456) (xy 178.065862 -27.523929) (xy 177.978756 -27.515357) (xy 177.892915 -27.498263)
			(xy 177.809169 -27.472814) (xy 177.728331 -27.439255) (xy 177.68951 -27.419046) (xy 177.678157 -27.413719)
			(xy 177.653111 -27.413719) (xy 177.641758 -27.419046) (xy 177.602894 -27.439282) (xy 177.521951 -27.472849)
			(xy 177.438101 -27.498301) (xy 177.352156 -27.515391) (xy 177.264948 -27.523955) (xy 177.221134 -27.524456)
			(xy 177.177318 -27.523994) (xy 177.090106 -27.515442) (xy 177.004158 -27.498348) (xy 176.920311 -27.472879)
			(xy 176.839376 -27.439281) (xy 176.80051 -27.419046) (xy 176.789157 -27.413719) (xy 176.764111 -27.413719)
			(xy 176.752758 -27.419046) (xy 176.713921 -27.439222) (xy 176.633081 -27.472767) (xy 176.549339 -27.498216)
			(xy 176.463504 -27.515325) (xy 176.376404 -27.523927) (xy 176.332642 -27.524456) (xy 176.332134 -27.524456)
			(xy 176.291028 -27.523955) (xy 176.209165 -27.516374) (xy 176.128351 -27.501273) (xy 176.049275 -27.47878)
			(xy 175.972611 -27.449089) (xy 175.899013 -27.412452) (xy 175.829109 -27.369181) (xy 175.763495 -27.319646)
			(xy 175.702731 -27.264268) (xy 175.647335 -27.203522) (xy 175.597779 -27.137923) (xy 175.554486 -27.068033)
			(xy 175.517825 -26.994447) (xy 175.488109 -26.917792) (xy 175.465592 -26.838723) (xy 175.450465 -26.757914)
			(xy 175.442858 -26.676054) (xy 175.442372 -26.634948) (xy 142.385288 -26.634948) (xy 142.385288 -26.76779)
			(xy 142.384802 -26.795059) (xy 142.37704 -26.849043) (xy 142.361675 -26.901373) (xy 142.339018 -26.950983)
			(xy 142.309532 -26.996864) (xy 142.273817 -27.038081) (xy 142.2326 -27.073796) (xy 142.186719 -27.103282)
			(xy 142.137109 -27.125939) (xy 142.084779 -27.141304) (xy 142.030795 -27.149066) (xy 141.976257 -27.149066)
			(xy 141.922273 -27.141304) (xy 141.869943 -27.125939) (xy 141.820333 -27.103282) (xy 141.774452 -27.073796)
			(xy 141.733235 -27.038081) (xy 141.69752 -26.996864) (xy 141.668034 -26.950983) (xy 141.645377 -26.901373)
			(xy 141.630012 -26.849043) (xy 141.62225 -26.795059) (xy 141.621764 -26.76779) (xy 131.450588 -26.76779)
			(xy 131.450588 -27.75458) (xy 131.450102 -27.781831) (xy 131.442346 -27.835779) (xy 131.426991 -27.888074)
			(xy 131.404349 -27.937651) (xy 131.374883 -27.983501) (xy 131.339192 -28.024692) (xy 131.298001 -28.060383)
			(xy 131.252151 -28.089849) (xy 131.202574 -28.112491) (xy 131.150279 -28.127846) (xy 131.096331 -28.135602)
			(xy 131.041829 -28.135602) (xy 130.987881 -28.127846) (xy 130.935586 -28.112491) (xy 130.886009 -28.089849)
			(xy 130.840159 -28.060383) (xy 130.798968 -28.024692) (xy 130.763277 -27.983501) (xy 130.733811 -27.937651)
			(xy 130.711169 -27.888074) (xy 130.695814 -27.835779) (xy 130.688058 -27.781831) (xy 130.687572 -27.75458)
			(xy 17.470427 -27.75458) (xy 17.770856 -28.07589) (xy 17.824996 -28.134528) (xy 17.928078 -28.256394)
			(xy 18.024957 -28.383247) (xy 18.047824 -28.416504) (xy 43.966892 -28.416504) (xy 43.966892 -28.41625)
			(xy 43.96737 -28.405875) (xy 43.975537 -28.386802) (xy 43.990595 -28.37253) (xy 44.000166 -28.368498)
			(xy 44.685966 -28.118308) (xy 44.690142 -28.116885) (xy 44.698828 -28.115349) (xy 44.703238 -28.11526)
			(xy 44.703492 -28.11526) (xy 44.713876 -28.115663) (xy 44.732957 -28.123858) (xy 44.747223 -28.138949)
			(xy 44.751244 -28.148534) (xy 45.250888 -29.51861) (xy 101.326696 -29.51861) (xy 101.326696 -28.65501)
			(xy 101.327182 -28.627759) (xy 101.334938 -28.573811) (xy 101.350293 -28.521516) (xy 101.372935 -28.471939)
			(xy 101.402401 -28.426089) (xy 101.438092 -28.384898) (xy 101.479283 -28.349207) (xy 101.525133 -28.319741)
			(xy 101.57471 -28.297099) (xy 101.627005 -28.281744) (xy 101.680953 -28.273988) (xy 101.735455 -28.273988)
			(xy 101.789403 -28.281744) (xy 101.841698 -28.297099) (xy 101.891275 -28.319741) (xy 101.937125 -28.349207)
			(xy 101.978316 -28.384898) (xy 102.014007 -28.426089) (xy 102.043473 -28.471939) (xy 102.066115 -28.521516)
			(xy 102.08147 -28.573811) (xy 102.089226 -28.627759) (xy 102.089712 -28.65501) (xy 102.089712 -29.24302)
			(xy 135.551672 -29.24302) (xy 135.551672 -28.25242) (xy 135.552158 -28.225169) (xy 135.559914 -28.171221)
			(xy 135.575269 -28.118926) (xy 135.597911 -28.069349) (xy 135.627377 -28.023499) (xy 135.663068 -27.982308)
			(xy 135.704259 -27.946617) (xy 135.750109 -27.917151) (xy 135.799686 -27.894509) (xy 135.851981 -27.879154)
			(xy 135.905929 -27.871398) (xy 135.960431 -27.871398) (xy 136.014379 -27.879154) (xy 136.066674 -27.894509)
			(xy 136.116251 -27.917151) (xy 136.162101 -27.946617) (xy 136.203292 -27.982308) (xy 136.238983 -28.023499)
			(xy 136.268449 -28.069349) (xy 136.291091 -28.118926) (xy 136.306446 -28.171221) (xy 136.314202 -28.225169)
			(xy 136.314688 -28.25242) (xy 136.314688 -28.526871) (xy 139.853386 -28.526871) (xy 139.853386 -28.472329)
			(xy 139.861148 -28.418343) (xy 139.876513 -28.366011) (xy 139.89917 -28.316397) (xy 139.928656 -28.270513)
			(xy 139.964371 -28.229293) (xy 140.005589 -28.193574) (xy 140.051471 -28.164084) (xy 140.101082 -28.141424)
			(xy 140.153414 -28.126054) (xy 140.207399 -28.118289) (xy 140.23467 -28.1178) (xy 141.09827 -28.1178)
			(xy 141.12554 -28.118337) (xy 141.179524 -28.126095) (xy 141.231856 -28.141457) (xy 141.281468 -28.164111)
			(xy 141.32735 -28.193595) (xy 141.36857 -28.229309) (xy 141.404287 -28.270526) (xy 141.433775 -28.316406)
			(xy 141.456432 -28.366016) (xy 141.471798 -28.418346) (xy 141.479561 -28.47233) (xy 141.479561 -28.52687)
			(xy 141.471798 -28.580854) (xy 141.456432 -28.633184) (xy 141.433775 -28.682794) (xy 141.404287 -28.728674)
			(xy 141.36857 -28.769891) (xy 141.32735 -28.805605) (xy 141.281468 -28.835089) (xy 141.231856 -28.857743)
			(xy 141.179524 -28.873105) (xy 141.12554 -28.880863) (xy 141.09827 -28.881324) (xy 140.23467 -28.881324)
			(xy 140.207399 -28.880911) (xy 140.153414 -28.873146) (xy 140.101082 -28.857776) (xy 140.051471 -28.835116)
			(xy 140.005589 -28.805626) (xy 139.964371 -28.769907) (xy 139.928656 -28.728687) (xy 139.89917 -28.682803)
			(xy 139.876513 -28.633189) (xy 139.861148 -28.580857) (xy 139.853386 -28.526871) (xy 136.314688 -28.526871)
			(xy 136.314688 -29.24302) (xy 136.314202 -29.270271) (xy 136.306446 -29.324219) (xy 136.291091 -29.376514)
			(xy 136.268449 -29.426091) (xy 136.238983 -29.471941) (xy 136.203292 -29.513132) (xy 136.162101 -29.548823)
			(xy 136.116251 -29.578289) (xy 136.066674 -29.600931) (xy 136.014379 -29.616286) (xy 135.960431 -29.624042)
			(xy 135.905929 -29.624042) (xy 135.851981 -29.616286) (xy 135.799686 -29.600931) (xy 135.750109 -29.578289)
			(xy 135.704259 -29.548823) (xy 135.663068 -29.513132) (xy 135.627377 -29.471941) (xy 135.597911 -29.426091)
			(xy 135.575269 -29.376514) (xy 135.559914 -29.324219) (xy 135.552158 -29.270271) (xy 135.551672 -29.24302)
			(xy 102.089712 -29.24302) (xy 102.089712 -29.51861) (xy 102.089226 -29.545861) (xy 102.08147 -29.599809)
			(xy 102.066115 -29.652104) (xy 102.043473 -29.701681) (xy 102.014007 -29.747531) (xy 101.978316 -29.788722)
			(xy 101.937125 -29.824413) (xy 101.891275 -29.853879) (xy 101.841698 -29.876521) (xy 101.789403 -29.891876)
			(xy 101.735455 -29.899632) (xy 101.680953 -29.899632) (xy 101.627005 -29.891876) (xy 101.57471 -29.876521)
			(xy 101.525133 -29.853879) (xy 101.479283 -29.824413) (xy 101.438092 -29.788722) (xy 101.402401 -29.747531)
			(xy 101.372935 -29.701681) (xy 101.350293 -29.652104) (xy 101.334938 -29.599809) (xy 101.327182 -29.545861)
			(xy 101.326696 -29.51861) (xy 45.250888 -29.51861) (xy 45.475238 -30.1338) (xy 197.595716 -30.1338)
			(xy 197.599747 -30.049172) (xy 197.611805 -29.965311) (xy 197.631779 -29.882976) (xy 197.65949 -29.802912)
			(xy 197.694686 -29.725844) (xy 197.737048 -29.652472) (xy 197.786193 -29.583458) (xy 197.841676 -29.519429)
			(xy 197.902994 -29.460963) (xy 197.969592 -29.408591) (xy 198.040866 -29.362787) (xy 198.116172 -29.323965)
			(xy 198.194827 -29.292477) (xy 198.276119 -29.268609) (xy 198.359312 -29.252576) (xy 198.443652 -29.244524)
			(xy 198.486014 -29.244036) (xy 198.524304 -29.244437) (xy 198.600598 -29.251046) (xy 198.676041 -29.264197)
			(xy 198.750071 -29.283791) (xy 198.786242 -29.29636) (xy 198.794679 -29.299011) (xy 198.812349 -29.299011)
			(xy 198.820786 -29.29636) (xy 198.856961 -29.283808) (xy 198.930995 -29.264238) (xy 199.006435 -29.251093)
			(xy 199.082726 -29.244471) (xy 199.121014 -29.244036) (xy 199.159304 -29.244437) (xy 199.235598 -29.251046)
			(xy 199.311041 -29.264197) (xy 199.385071 -29.283791) (xy 199.421242 -29.29636) (xy 199.429679 -29.299011)
			(xy 199.447349 -29.299011) (xy 199.455786 -29.29636) (xy 199.491961 -29.283808) (xy 199.565995 -29.264238)
			(xy 199.641435 -29.251093) (xy 199.717726 -29.244471) (xy 199.756014 -29.244036) (xy 199.794304 -29.244437)
			(xy 199.870598 -29.251046) (xy 199.946041 -29.264197) (xy 200.020071 -29.283791) (xy 200.056242 -29.29636)
			(xy 200.064679 -29.299011) (xy 200.082349 -29.299011) (xy 200.090786 -29.29636) (xy 200.126961 -29.283808)
			(xy 200.200995 -29.264238) (xy 200.276435 -29.251093) (xy 200.352726 -29.244471) (xy 200.391014 -29.244036)
			(xy 200.431702 -29.244422) (xy 200.512738 -29.251848) (xy 200.592757 -29.266645) (xy 200.67109 -29.288689)
			(xy 200.747082 -29.317797) (xy 200.820096 -29.353725) (xy 200.889524 -29.396173) (xy 200.954784 -29.444785)
			(xy 201.015331 -29.499155) (xy 201.070657 -29.558829) (xy 201.120302 -29.623307) (xy 201.163849 -29.69205)
			(xy 201.200934 -29.764484) (xy 201.216514 -29.802074) (xy 201.22098 -29.811942) (xy 201.236608 -29.826918)
			(xy 201.256995 -29.83419) (xy 201.267822 -29.833824) (xy 201.286077 -29.832403) (xy 201.322664 -29.83088)
			(xy 201.340974 -29.830776) (xy 201.383338 -29.831187) (xy 201.467682 -29.839239) (xy 201.550879 -29.855272)
			(xy 201.632176 -29.87914) (xy 201.710835 -29.910629) (xy 201.786145 -29.949452) (xy 201.857423 -29.995258)
			(xy 201.924025 -30.047632) (xy 201.985346 -30.1061) (xy 202.040832 -30.170132) (xy 202.08998 -30.239149)
			(xy 202.132344 -30.312525) (xy 202.167542 -30.389596) (xy 202.195254 -30.469663) (xy 202.21523 -30.552003)
			(xy 202.227288 -30.635868) (xy 202.23132 -30.7205) (xy 202.227288 -30.805132) (xy 202.21523 -30.888997)
			(xy 202.195254 -30.971337) (xy 202.167542 -31.051404) (xy 202.132344 -31.128475) (xy 202.08998 -31.201851)
			(xy 202.040832 -31.270868) (xy 201.985346 -31.3349) (xy 201.924025 -31.393368) (xy 201.857423 -31.445742)
			(xy 201.786145 -31.491548) (xy 201.710835 -31.530371) (xy 201.632176 -31.56186) (xy 201.550879 -31.585728)
			(xy 201.467682 -31.601761) (xy 201.383338 -31.609813) (xy 201.340974 -31.6103) (xy 201.302684 -31.609905)
			(xy 201.226389 -31.603295) (xy 201.150947 -31.590142) (xy 201.076917 -31.570546) (xy 201.040746 -31.557976)
			(xy 201.032309 -31.555325) (xy 201.014639 -31.555325) (xy 201.006202 -31.557976) (xy 200.970027 -31.570528)
			(xy 200.895993 -31.590099) (xy 200.820553 -31.603244) (xy 200.744262 -31.609866) (xy 200.705974 -31.6103)
			(xy 200.667684 -31.609905) (xy 200.591389 -31.603295) (xy 200.515947 -31.590142) (xy 200.441917 -31.570546)
			(xy 200.405746 -31.557976) (xy 200.397309 -31.555325) (xy 200.379639 -31.555325) (xy 200.371202 -31.557976)
			(xy 200.335027 -31.570528) (xy 200.260993 -31.590099) (xy 200.185553 -31.603244) (xy 200.109262 -31.609866)
			(xy 200.070974 -31.6103) (xy 200.032684 -31.609905) (xy 199.956389 -31.603295) (xy 199.880947 -31.590142)
			(xy 199.806917 -31.570546) (xy 199.770746 -31.557976) (xy 199.762309 -31.555325) (xy 199.744639 -31.555325)
			(xy 199.736202 -31.557976) (xy 199.700027 -31.570528) (xy 199.625993 -31.590099) (xy 199.550553 -31.603244)
			(xy 199.474262 -31.609866) (xy 199.435974 -31.6103) (xy 199.395288 -31.609814) (xy 199.314256 -31.602396)
			(xy 199.23424 -31.587608) (xy 199.15591 -31.565572) (xy 199.07992 -31.536472) (xy 199.006906 -31.500553)
			(xy 198.937478 -31.458114) (xy 198.872217 -31.40951) (xy 198.81167 -31.355148) (xy 198.756341 -31.295482)
			(xy 198.706694 -31.231012) (xy 198.663144 -31.162275) (xy 198.626056 -31.089848) (xy 198.610474 -31.052262)
			(xy 198.605924 -31.042441) (xy 198.590335 -31.027459) (xy 198.569982 -31.020164) (xy 198.559166 -31.020512)
			(xy 198.540911 -31.021927) (xy 198.504324 -31.023454) (xy 198.486014 -31.02356) (xy 198.443652 -31.023076)
			(xy 198.359312 -31.015024) (xy 198.276119 -30.998991) (xy 198.194827 -30.975123) (xy 198.116172 -30.943635)
			(xy 198.040866 -30.904813) (xy 197.969592 -30.859009) (xy 197.902994 -30.806637) (xy 197.841676 -30.748171)
			(xy 197.786193 -30.684142) (xy 197.737048 -30.615128) (xy 197.694686 -30.541756) (xy 197.65949 -30.464688)
			(xy 197.631779 -30.384624) (xy 197.611805 -30.302289) (xy 197.599747 -30.218428) (xy 197.595716 -30.1338)
			(xy 45.475238 -30.1338) (xy 45.490892 -30.176724) (xy 45.492329 -30.180895) (xy 45.493856 -30.189585)
			(xy 45.49394 -30.193996) (xy 45.49394 -30.19425) (xy 45.493454 -30.204256) (xy 45.485785 -30.222741)
			(xy 45.471633 -30.236891) (xy 45.453146 -30.244556) (xy 45.44314 -30.24505) (xy 45.432759 -30.244616)
			(xy 45.413681 -30.236434) (xy 45.399412 -30.221356) (xy 45.395388 -30.211776) (xy 44.690792 -28.278836)
			(xy 44.686853 -28.269613) (xy 44.673278 -28.254881) (xy 44.655103 -28.246458) (xy 44.635088 -28.245626)
			(xy 44.625514 -28.24861) (xy 44.130468 -28.42895) (xy 44.121227 -28.432857) (xy 44.106488 -28.446438)
			(xy 44.098068 -28.464626) (xy 44.097248 -28.484652) (xy 44.100242 -28.494228) (xy 44.805092 -30.426914)
			(xy 44.806527 -30.431086) (xy 44.808055 -30.439775) (xy 44.80814 -30.444186) (xy 44.80814 -30.44444)
			(xy 44.807646 -30.454445) (xy 44.79998 -30.47293) (xy 44.78583 -30.48708) (xy 44.767345 -30.494746)
			(xy 44.75734 -30.49524) (xy 44.746958 -30.494812) (xy 44.727879 -30.486629) (xy 44.713611 -30.471548)
			(xy 44.709588 -30.461966) (xy 43.96994 -28.433776) (xy 43.968504 -28.429604) (xy 43.966976 -28.420915)
			(xy 43.966892 -28.416504) (xy 18.047824 -28.416504) (xy 18.115392 -28.514772) (xy 18.199158 -28.650641)
			(xy 18.276047 -28.790516) (xy 18.345869 -28.934051) (xy 18.408448 -29.080887) (xy 18.463631 -29.230661)
			(xy 18.511279 -29.382999) (xy 18.551274 -29.537523) (xy 18.583516 -29.693848) (xy 18.607926 -29.851586)
			(xy 18.624443 -30.010345) (xy 18.633025 -30.16973) (xy 18.633652 -30.329344) (xy 18.626321 -30.488792)
			(xy 18.611051 -30.647675) (xy 18.587881 -30.8056) (xy 18.556867 -30.962174) (xy 18.518086 -31.117007)
			(xy 18.471636 -31.269714) (xy 18.417631 -31.419917) (xy 18.356206 -31.56724) (xy 18.287514 -31.711318)
			(xy 18.211725 -31.851793) (xy 18.129028 -31.988316) (xy 18.039629 -32.120546) (xy 17.943749 -32.248156)
			(xy 17.841627 -32.370828) (xy 17.769183 -32.449516) (xy 43.055032 -32.449516) (xy 43.055522 -32.439584)
			(xy 43.06309 -32.421217) (xy 43.077062 -32.407096) (xy 43.08602 -32.40278) (xy 43.758104 -32.117538)
			(xy 43.762832 -32.115632) (xy 43.772819 -32.113586) (xy 43.777916 -32.113474) (xy 43.787846 -32.113974)
			(xy 43.806208 -32.121544) (xy 43.820332 -32.135508) (xy 43.824652 -32.144462) (xy 44.165413 -32.94761)
			(xy 102.642416 -32.94761) (xy 102.642416 -31.95701) (xy 102.642902 -31.929759) (xy 102.650658 -31.875811)
			(xy 102.666013 -31.823516) (xy 102.688655 -31.773939) (xy 102.718121 -31.728089) (xy 102.753812 -31.686898)
			(xy 102.795003 -31.651207) (xy 102.840853 -31.621741) (xy 102.89043 -31.599099) (xy 102.942725 -31.583744)
			(xy 102.996673 -31.575988) (xy 103.051175 -31.575988) (xy 103.105123 -31.583744) (xy 103.157418 -31.599099)
			(xy 103.206995 -31.621741) (xy 103.252845 -31.651207) (xy 103.294036 -31.686898) (xy 103.329727 -31.728089)
			(xy 103.359193 -31.773939) (xy 103.381835 -31.823516) (xy 103.39719 -31.875811) (xy 103.404946 -31.929759)
			(xy 103.405432 -31.95701) (xy 103.405432 -32.405066) (xy 105.659936 -32.405066) (xy 105.659936 -31.541466)
			(xy 105.660422 -31.514215) (xy 105.668178 -31.460267) (xy 105.683533 -31.407972) (xy 105.706175 -31.358395)
			(xy 105.735641 -31.312545) (xy 105.771332 -31.271354) (xy 105.812523 -31.235663) (xy 105.858373 -31.206197)
			(xy 105.90795 -31.183555) (xy 105.960245 -31.1682) (xy 106.014193 -31.160444) (xy 106.068695 -31.160444)
			(xy 106.122643 -31.1682) (xy 106.174938 -31.183555) (xy 106.224515 -31.206197) (xy 106.270365 -31.235663)
			(xy 106.311556 -31.271354) (xy 106.347247 -31.312545) (xy 106.376713 -31.358395) (xy 106.399355 -31.407972)
			(xy 106.41471 -31.460267) (xy 106.422466 -31.514215) (xy 106.422952 -31.541466) (xy 106.422952 -31.65856)
			(xy 140.278612 -31.65856) (xy 140.278612 -30.79496) (xy 140.279098 -30.767709) (xy 140.286854 -30.713761)
			(xy 140.302209 -30.661466) (xy 140.324851 -30.611889) (xy 140.354317 -30.566039) (xy 140.390008 -30.524848)
			(xy 140.431199 -30.489157) (xy 140.477049 -30.459691) (xy 140.526626 -30.437049) (xy 140.578921 -30.421694)
			(xy 140.632869 -30.413938) (xy 140.687371 -30.413938) (xy 140.741319 -30.421694) (xy 140.793614 -30.437049)
			(xy 140.843191 -30.459691) (xy 140.889041 -30.489157) (xy 140.930232 -30.524848) (xy 140.965923 -30.566039)
			(xy 140.995389 -30.611889) (xy 141.018031 -30.661466) (xy 141.033386 -30.713761) (xy 141.041142 -30.767709)
			(xy 141.041628 -30.79496) (xy 141.041628 -31.65856) (xy 141.041311 -31.67634) (xy 144.616932 -31.67634)
			(xy 144.616932 -30.81274) (xy 144.617418 -30.785489) (xy 144.625174 -30.731541) (xy 144.640529 -30.679246)
			(xy 144.663171 -30.629669) (xy 144.692637 -30.583819) (xy 144.728328 -30.542628) (xy 144.769519 -30.506937)
			(xy 144.815369 -30.477471) (xy 144.864946 -30.454829) (xy 144.917241 -30.439474) (xy 144.971189 -30.431718)
			(xy 145.025691 -30.431718) (xy 145.079639 -30.439474) (xy 145.131934 -30.454829) (xy 145.181511 -30.477471)
			(xy 145.227361 -30.506937) (xy 145.268552 -30.542628) (xy 145.304243 -30.583819) (xy 145.333709 -30.629669)
			(xy 145.356351 -30.679246) (xy 145.371706 -30.731541) (xy 145.379462 -30.785489) (xy 145.379948 -30.81274)
			(xy 145.379948 -31.67634) (xy 145.379462 -31.703591) (xy 145.371706 -31.757539) (xy 145.356351 -31.809834)
			(xy 145.333709 -31.859411) (xy 145.304243 -31.905261) (xy 145.268552 -31.946452) (xy 145.227361 -31.982143)
			(xy 145.181511 -32.011609) (xy 145.131934 -32.034251) (xy 145.079639 -32.049606) (xy 145.025691 -32.057362)
			(xy 144.971189 -32.057362) (xy 144.917241 -32.049606) (xy 144.864946 -32.034251) (xy 144.815369 -32.011609)
			(xy 144.769519 -31.982143) (xy 144.728328 -31.946452) (xy 144.692637 -31.905261) (xy 144.663171 -31.859411)
			(xy 144.640529 -31.809834) (xy 144.625174 -31.757539) (xy 144.617418 -31.703591) (xy 144.616932 -31.67634)
			(xy 141.041311 -31.67634) (xy 141.041142 -31.685811) (xy 141.033386 -31.739759) (xy 141.018031 -31.792054)
			(xy 140.995389 -31.841631) (xy 140.965923 -31.887481) (xy 140.930232 -31.928672) (xy 140.889041 -31.964363)
			(xy 140.843191 -31.993829) (xy 140.793614 -32.016471) (xy 140.741319 -32.031826) (xy 140.687371 -32.039582)
			(xy 140.632869 -32.039582) (xy 140.578921 -32.031826) (xy 140.526626 -32.016471) (xy 140.477049 -31.993829)
			(xy 140.431199 -31.964363) (xy 140.390008 -31.928672) (xy 140.354317 -31.887481) (xy 140.324851 -31.841631)
			(xy 140.302209 -31.792054) (xy 140.286854 -31.739759) (xy 140.279098 -31.685811) (xy 140.278612 -31.65856)
			(xy 106.422952 -31.65856) (xy 106.422952 -32.405066) (xy 106.422466 -32.432317) (xy 106.41471 -32.486265)
			(xy 106.399355 -32.53856) (xy 106.376713 -32.588137) (xy 106.347247 -32.633987) (xy 106.311556 -32.675178)
			(xy 106.270365 -32.710869) (xy 106.224515 -32.740335) (xy 106.174938 -32.762977) (xy 106.122643 -32.778332)
			(xy 106.068695 -32.786088) (xy 106.014193 -32.786088) (xy 105.960245 -32.778332) (xy 105.90795 -32.762977)
			(xy 105.858373 -32.740335) (xy 105.812523 -32.710869) (xy 105.771332 -32.675178) (xy 105.735641 -32.633987)
			(xy 105.706175 -32.588137) (xy 105.683533 -32.53856) (xy 105.668178 -32.486265) (xy 105.660422 -32.432317)
			(xy 105.659936 -32.405066) (xy 103.405432 -32.405066) (xy 103.405432 -32.94761) (xy 103.404946 -32.974861)
			(xy 103.39719 -33.028809) (xy 103.390276 -33.052356) (xy 119.734235 -33.052356) (xy 119.734235 -32.997844)
			(xy 119.741993 -32.943888) (xy 119.757352 -32.891585) (xy 119.779997 -32.842) (xy 119.80947 -32.796143)
			(xy 119.845169 -32.754947) (xy 119.886367 -32.719252) (xy 119.932226 -32.689783) (xy 119.981813 -32.667141)
			(xy 120.034117 -32.651787) (xy 120.088074 -32.644033) (xy 120.11533 -32.643572) (xy 120.97893 -32.643572)
			(xy 121.006178 -32.6441) (xy 121.06012 -32.65186) (xy 121.112408 -32.667217) (xy 121.161979 -32.689858)
			(xy 121.207823 -32.719324) (xy 121.249008 -32.755014) (xy 121.284694 -32.796201) (xy 121.314156 -32.842047)
			(xy 121.336794 -32.89162) (xy 121.352147 -32.943909) (xy 121.359902 -32.997852) (xy 121.359902 -33.052348)
			(xy 121.352147 -33.106291) (xy 121.336794 -33.15858) (xy 121.314156 -33.208153) (xy 121.284694 -33.253999)
			(xy 121.249008 -33.295186) (xy 121.207823 -33.330876) (xy 121.161979 -33.360342) (xy 121.112408 -33.382983)
			(xy 121.06012 -33.39834) (xy 121.006178 -33.4061) (xy 120.97893 -33.406588) (xy 120.11533 -33.406588)
			(xy 120.088074 -33.406167) (xy 120.034117 -33.398413) (xy 119.981813 -33.383059) (xy 119.932226 -33.360417)
			(xy 119.886367 -33.330948) (xy 119.845169 -33.295253) (xy 119.80947 -33.254057) (xy 119.779997 -33.2082)
			(xy 119.757352 -33.158615) (xy 119.741993 -33.106312) (xy 119.734235 -33.052356) (xy 103.390276 -33.052356)
			(xy 103.381835 -33.081104) (xy 103.359193 -33.130681) (xy 103.329727 -33.176531) (xy 103.294036 -33.217722)
			(xy 103.252845 -33.253413) (xy 103.206995 -33.282879) (xy 103.157418 -33.305521) (xy 103.105123 -33.320876)
			(xy 103.051175 -33.328632) (xy 102.996673 -33.328632) (xy 102.942725 -33.320876) (xy 102.89043 -33.305521)
			(xy 102.840853 -33.282879) (xy 102.795003 -33.253413) (xy 102.753812 -33.217722) (xy 102.718121 -33.176531)
			(xy 102.688655 -33.130681) (xy 102.666013 -33.081104) (xy 102.650658 -33.028809) (xy 102.642902 -32.974861)
			(xy 102.642416 -32.94761) (xy 44.165413 -32.94761) (xy 44.543353 -33.838388) (xy 122.111008 -33.838388)
			(xy 122.111008 -32.974788) (xy 122.111494 -32.947519) (xy 122.119256 -32.893535) (xy 122.134621 -32.841205)
			(xy 122.157278 -32.791595) (xy 122.186764 -32.745714) (xy 122.222479 -32.704497) (xy 122.263696 -32.668782)
			(xy 122.309577 -32.639296) (xy 122.359187 -32.616639) (xy 122.411517 -32.601274) (xy 122.465501 -32.593512)
			(xy 122.520039 -32.593512) (xy 122.574023 -32.601274) (xy 122.626353 -32.616639) (xy 122.675963 -32.639296)
			(xy 122.721844 -32.668782) (xy 122.763061 -32.704497) (xy 122.798776 -32.745714) (xy 122.828262 -32.791595)
			(xy 122.850919 -32.841205) (xy 122.866284 -32.893535) (xy 122.874046 -32.947519) (xy 122.874532 -32.974788)
			(xy 122.874532 -33.413556) (xy 124.175423 -33.413556) (xy 124.175423 -33.359044) (xy 124.183181 -33.305087)
			(xy 124.198539 -33.252783) (xy 124.221185 -33.203197) (xy 124.250658 -33.157339) (xy 124.286357 -33.116142)
			(xy 124.327555 -33.080446) (xy 124.373415 -33.050976) (xy 124.423002 -33.028332) (xy 124.475306 -33.012977)
			(xy 124.529264 -33.005222) (xy 124.55652 -33.00476) (xy 125.42012 -33.00476) (xy 125.447368 -33.005312)
			(xy 125.501309 -33.01307) (xy 125.553597 -33.028425) (xy 125.603167 -33.051066) (xy 125.649011 -33.08053)
			(xy 125.690196 -33.116218) (xy 125.725882 -33.157405) (xy 125.755344 -33.20325) (xy 125.777982 -33.252822)
			(xy 125.793335 -33.305111) (xy 125.80109 -33.359052) (xy 125.80109 -33.413548) (xy 125.793335 -33.467489)
			(xy 125.777982 -33.519778) (xy 125.755344 -33.56935) (xy 125.725882 -33.615195) (xy 125.690196 -33.656382)
			(xy 125.649011 -33.69207) (xy 125.603167 -33.721534) (xy 125.553597 -33.744175) (xy 125.501309 -33.75953)
			(xy 125.447368 -33.767288) (xy 125.42012 -33.767776) (xy 124.55652 -33.767776) (xy 124.529264 -33.767378)
			(xy 124.475306 -33.759623) (xy 124.423002 -33.744268) (xy 124.373415 -33.721624) (xy 124.327555 -33.692154)
			(xy 124.286357 -33.656458) (xy 124.250658 -33.615261) (xy 124.221185 -33.569403) (xy 124.198539 -33.519817)
			(xy 124.183181 -33.467513) (xy 124.175423 -33.413556) (xy 122.874532 -33.413556) (xy 122.874532 -33.838388)
			(xy 122.874046 -33.865657) (xy 122.866284 -33.919641) (xy 122.850919 -33.971971) (xy 122.828262 -34.021581)
			(xy 122.798776 -34.067462) (xy 122.763061 -34.108679) (xy 122.721844 -34.144394) (xy 122.675963 -34.17388)
			(xy 122.626353 -34.196537) (xy 122.574023 -34.211902) (xy 122.520039 -34.219664) (xy 122.465501 -34.219664)
			(xy 122.411517 -34.211902) (xy 122.359187 -34.196537) (xy 122.309577 -34.17388) (xy 122.263696 -34.144394)
			(xy 122.222479 -34.108679) (xy 122.186764 -34.067462) (xy 122.157278 -34.021581) (xy 122.134621 -33.971971)
			(xy 122.119256 -33.919641) (xy 122.111494 -33.865657) (xy 122.111008 -33.838388) (xy 44.543353 -33.838388)
			(xy 44.667932 -34.132012) (xy 44.669844 -34.136738) (xy 44.671886 -34.146726) (xy 44.671996 -34.151824)
			(xy 44.671532 -34.161834) (xy 44.663863 -34.180327) (xy 44.649703 -34.194479) (xy 44.631206 -34.202137)
			(xy 44.621196 -34.202624) (xy 44.611267 -34.202116) (xy 44.592905 -34.19455) (xy 44.578781 -34.180589)
			(xy 44.57446 -34.171636) (xy 43.770804 -32.277558) (xy 43.766496 -32.268517) (xy 43.752221 -32.254495)
			(xy 43.733667 -32.247) (xy 43.713657 -32.247175) (xy 43.704256 -32.250634) (xy 43.219116 -32.456628)
			(xy 43.210086 -32.46097) (xy 43.19604 -32.47523) (xy 43.188522 -32.493781) (xy 43.188676 -32.513796)
			(xy 43.192192 -32.523176) (xy 43.995848 -34.417254) (xy 43.99774 -34.421988) (xy 43.999795 -34.43197)
			(xy 43.999912 -34.437066) (xy 43.999453 -34.447084) (xy 43.991796 -34.465597) (xy 43.977636 -34.47977)
			(xy 43.959129 -34.487444) (xy 43.949112 -34.487866) (xy 43.93918 -34.48738) (xy 43.920812 -34.47981)
			(xy 43.906691 -34.465837) (xy 43.902376 -34.456878) (xy 43.059096 -32.469328) (xy 43.057196 -32.464597)
			(xy 43.055146 -32.454613) (xy 43.055032 -32.449516) (xy 17.769183 -32.449516) (xy 17.733517 -32.488256)
			(xy 17.619688 -32.60015) (xy 17.500423 -32.70623) (xy 17.376019 -32.806234) (xy 17.246784 -32.899911)
			(xy 17.11304 -32.98703) (xy 16.975119 -33.067374) (xy 16.833366 -33.140743) (xy 16.688131 -33.206955)
			(xy 16.539776 -33.265845) (xy 16.38867 -33.317266) (xy 16.235188 -33.361091) (xy 16.079713 -33.397211)
			(xy 15.922631 -33.425536) (xy 15.764332 -33.445995) (xy 15.605209 -33.458538) (xy 15.44566 -33.463134)
			(xy 15.286079 -33.459771) (xy 15.126865 -33.448457) (xy 14.968413 -33.42922) (xy 14.811116 -33.402109)
			(xy 14.655367 -33.367191) (xy 14.501552 -33.324553) (xy 14.350053 -33.2743) (xy 14.201248 -33.216557)
			(xy 14.055506 -33.151469) (xy 13.91319 -33.079197) (xy 13.774653 -32.999921) (xy 13.64024 -32.913837)
			(xy 13.510286 -32.82116) (xy 13.385112 -32.72212) (xy 13.265032 -32.616964) (xy 13.150342 -32.505953)
			(xy 13.095478 -32.447992) (xy 12.00277 -31.279592) (xy 11.948692 -31.220903) (xy 11.845626 -31.099035)
			(xy 11.748763 -30.972182) (xy 11.658343 -30.840658) (xy 11.574591 -30.704792) (xy 11.497716 -30.564919)
			(xy 11.427907 -30.421388) (xy 11.36534 -30.274557) (xy 11.310169 -30.124789) (xy 11.262532 -29.972457)
			(xy 11.222547 -29.81794) (xy 11.190314 -29.661623) (xy 11.165912 -29.503893) (xy 11.149402 -29.345143)
			(xy 11.140826 -29.185767) (xy 11.140205 -29.026161) (xy 0.509016 -29.026161) (xy 0.509016 -36.080556)
			(xy 122.143423 -36.080556) (xy 122.143423 -36.026044) (xy 122.151181 -35.972087) (xy 122.166539 -35.919783)
			(xy 122.189185 -35.870197) (xy 122.218658 -35.824339) (xy 122.254357 -35.783142) (xy 122.295555 -35.747446)
			(xy 122.341415 -35.717976) (xy 122.391002 -35.695332) (xy 122.443306 -35.679977) (xy 122.497264 -35.672222)
			(xy 122.52452 -35.67176) (xy 123.38812 -35.67176) (xy 123.415368 -35.672312) (xy 123.469309 -35.68007)
			(xy 123.521597 -35.695425) (xy 123.571167 -35.718066) (xy 123.617011 -35.74753) (xy 123.658196 -35.783218)
			(xy 123.693882 -35.824405) (xy 123.723344 -35.87025) (xy 123.745982 -35.919822) (xy 123.761335 -35.972111)
			(xy 123.76909 -36.026052) (xy 123.76909 -36.080548) (xy 123.761335 -36.134489) (xy 123.745982 -36.186778)
			(xy 123.723344 -36.23635) (xy 123.693882 -36.282195) (xy 123.658196 -36.323382) (xy 123.617011 -36.35907)
			(xy 123.571167 -36.388534) (xy 123.521597 -36.411175) (xy 123.469309 -36.42653) (xy 123.415368 -36.434288)
			(xy 123.38812 -36.434776) (xy 122.52452 -36.434776) (xy 122.497264 -36.434378) (xy 122.443306 -36.426623)
			(xy 122.391002 -36.411268) (xy 122.341415 -36.388624) (xy 122.295555 -36.359154) (xy 122.254357 -36.323458)
			(xy 122.218658 -36.282261) (xy 122.189185 -36.236403) (xy 122.166539 -36.186817) (xy 122.151181 -36.134513)
			(xy 122.143423 -36.080556) (xy 0.509016 -36.080556) (xy 0.509016 -39.23137) (xy 9.080235 -39.23137)
			(xy 9.080235 -39.10223) (xy 9.088185 -38.973335) (xy 9.104055 -38.845175) (xy 9.127784 -38.718234)
			(xy 9.159283 -38.592995) (xy 9.198432 -38.469932) (xy 9.245083 -38.349513) (xy 9.299058 -38.232194)
			(xy 9.360153 -38.11842) (xy 9.428136 -38.008623) (xy 9.50275 -37.90322) (xy 9.583711 -37.80261) (xy 9.670711 -37.707175)
			(xy 9.763422 -37.617276) (xy 9.861492 -37.533255) (xy 9.964547 -37.455431) (xy 10.072198 -37.384099)
			(xy 10.184037 -37.319529) (xy 10.299638 -37.261967) (xy 10.418563 -37.21163) (xy 10.540362 -37.16871)
			(xy 10.664572 -37.133369) (xy 10.790721 -37.105742) (xy 10.918333 -37.085933) (xy 11.046922 -37.074017)
			(xy 11.176 -37.070041) (xy 11.305078 -37.074017) (xy 11.433667 -37.085933) (xy 11.521898 -37.099629)
			(xy 170.60087 -37.099629) (xy 170.60087 -37.000299) (xy 170.608862 -36.901292) (xy 170.624796 -36.803249)
			(xy 170.648567 -36.706806) (xy 170.680022 -36.612588) (xy 170.718955 -36.521208) (xy 170.765116 -36.433256)
			(xy 170.818204 -36.349304) (xy 170.877875 -36.269895) (xy 170.943743 -36.195546) (xy 171.01538 -36.126738)
			(xy 171.092321 -36.063918) (xy 171.174067 -36.007493) (xy 171.260089 -35.957828) (xy 171.349828 -35.915246)
			(xy 171.442702 -35.880024) (xy 171.53811 -35.852388) (xy 171.635432 -35.83252) (xy 171.734037 -35.820547)
			(xy 171.833286 -35.816548) (xy 171.932535 -35.820547) (xy 172.03114 -35.83252) (xy 172.128462 -35.852388)
			(xy 172.22387 -35.880024) (xy 172.316744 -35.915246) (xy 172.406483 -35.957828) (xy 172.492505 -36.007493)
			(xy 172.574251 -36.063918) (xy 172.651192 -36.126738) (xy 172.722829 -36.195546) (xy 172.788697 -36.269895)
			(xy 172.848368 -36.349304) (xy 172.901456 -36.433256) (xy 172.947617 -36.521208) (xy 172.98655 -36.612588)
			(xy 173.018005 -36.706806) (xy 173.041776 -36.803249) (xy 173.05771 -36.901292) (xy 173.065702 -37.000299)
			(xy 173.066202 -37.049964) (xy 173.065702 -37.099629) (xy 173.05771 -37.198636) (xy 173.041776 -37.296679)
			(xy 173.034033 -37.328094) (xy 197.270624 -37.328094) (xy 197.271107 -37.28698) (xy 197.278695 -37.205103)
			(xy 197.293804 -37.124275) (xy 197.316307 -37.045187) (xy 197.346011 -36.968512) (xy 197.382664 -36.894904)
			(xy 197.425951 -36.824993) (xy 197.475504 -36.759373) (xy 197.5309 -36.698606) (xy 197.591667 -36.643209)
			(xy 197.657286 -36.593655) (xy 197.727197 -36.550367) (xy 197.800804 -36.513715) (xy 197.877479 -36.48401)
			(xy 197.956568 -36.461506) (xy 198.037395 -36.446396) (xy 198.119272 -36.438808) (xy 198.160386 -36.438332)
			(xy 198.203952 -36.438853) (xy 198.290667 -36.447372) (xy 198.376134 -36.464329) (xy 198.459533 -36.489562)
			(xy 198.540065 -36.522829) (xy 198.616958 -36.563811) (xy 198.689475 -36.612116) (xy 198.756921 -36.66728)
			(xy 198.81865 -36.728775) (xy 198.87407 -36.796011) (xy 198.922649 -36.868345) (xy 198.963923 -36.945081)
			(xy 198.997496 -37.025486) (xy 199.010778 -37.066982) (xy 199.013703 -37.075249) (xy 199.024271 -37.089233)
			(xy 199.038923 -37.098854) (xy 199.047354 -37.101272) (xy 199.088321 -37.111837) (xy 199.168226 -37.13965)
			(xy 199.24513 -37.174922) (xy 199.318339 -37.217334) (xy 199.387193 -37.266504) (xy 199.451068 -37.321986)
			(xy 199.509389 -37.383281) (xy 199.529427 -37.408809) (xy 207.619596 -37.408809) (xy 207.619596 -37.324087)
			(xy 207.627649 -37.23975) (xy 207.643683 -37.15656) (xy 207.667551 -37.07527) (xy 207.699039 -36.996618)
			(xy 207.737861 -36.921315) (xy 207.783664 -36.850043) (xy 207.836035 -36.783447) (xy 207.8945 -36.722132)
			(xy 207.958528 -36.666651) (xy 208.02754 -36.617508) (xy 208.10091 -36.575148) (xy 208.177975 -36.539953)
			(xy 208.258037 -36.512244) (xy 208.34037 -36.49227) (xy 208.424229 -36.480213) (xy 208.508854 -36.476182)
			(xy 208.593479 -36.480213) (xy 208.677338 -36.49227) (xy 208.759671 -36.512244) (xy 208.839733 -36.539953)
			(xy 208.916798 -36.575148) (xy 208.990168 -36.617508) (xy 209.05918 -36.666651) (xy 209.123208 -36.722132)
			(xy 209.181673 -36.783447) (xy 209.234044 -36.850043) (xy 209.279847 -36.921315) (xy 209.318669 -36.996618)
			(xy 209.350157 -37.07527) (xy 209.374025 -37.15656) (xy 209.390059 -37.23975) (xy 209.398112 -37.324087)
			(xy 209.398616 -37.366448) (xy 209.398112 -37.408809) (xy 209.390059 -37.493146) (xy 209.374025 -37.576336)
			(xy 209.350157 -37.657626) (xy 209.318669 -37.736278) (xy 209.279847 -37.811581) (xy 209.234044 -37.882853)
			(xy 209.181673 -37.949449) (xy 209.123208 -38.010764) (xy 209.05918 -38.066245) (xy 208.990168 -38.115388)
			(xy 208.916798 -38.157748) (xy 208.839733 -38.192943) (xy 208.759671 -38.220652) (xy 208.677338 -38.240626)
			(xy 208.593479 -38.252683) (xy 208.508854 -38.256715) (xy 208.424229 -38.252683) (xy 208.34037 -38.240626)
			(xy 208.258037 -38.220652) (xy 208.177975 -38.192943) (xy 208.10091 -38.157748) (xy 208.02754 -38.115388)
			(xy 207.958528 -38.066245) (xy 207.8945 -38.010764) (xy 207.836035 -37.949449) (xy 207.783664 -37.882853)
			(xy 207.737861 -37.811581) (xy 207.699039 -37.736278) (xy 207.667551 -37.657626) (xy 207.643683 -37.576336)
			(xy 207.627649 -37.493146) (xy 207.619596 -37.408809) (xy 199.529427 -37.408809) (xy 199.561629 -37.449835)
			(xy 199.607316 -37.521047) (xy 199.646037 -37.596273) (xy 199.677444 -37.674835) (xy 199.701252 -37.756024)
			(xy 199.717247 -37.839106) (xy 199.725284 -37.92333) (xy 199.725788 -37.965634) (xy 199.72532 -38.006748)
			(xy 199.71773 -38.088625) (xy 199.702618 -38.169453) (xy 199.680113 -38.248541) (xy 199.650407 -38.325216)
			(xy 199.613754 -38.398823) (xy 199.570465 -38.468734) (xy 199.520911 -38.534353) (xy 199.465514 -38.595119)
			(xy 199.404746 -38.650516) (xy 199.339127 -38.70007) (xy 199.269216 -38.743357) (xy 199.195608 -38.78001)
			(xy 199.118933 -38.809716) (xy 199.039845 -38.83222) (xy 198.959017 -38.847331) (xy 198.87714 -38.85492)
			(xy 198.836026 -38.855396) (xy 198.792461 -38.854844) (xy 198.705747 -38.846327) (xy 198.620282 -38.829372)
			(xy 198.536884 -38.804141) (xy 198.456353 -38.770876) (xy 198.379461 -38.729896) (xy 198.306944 -38.681594)
			(xy 198.239498 -38.626432) (xy 198.177769 -38.56494) (xy 198.122348 -38.497707) (xy 198.073767 -38.425377)
			(xy 198.032492 -38.348643) (xy 197.998917 -38.26824) (xy 197.985634 -38.226746) (xy 197.982688 -38.218487)
			(xy 197.97213 -38.204501) (xy 197.957486 -38.194877) (xy 197.949058 -38.192456) (xy 197.908101 -38.181857)
			(xy 197.828197 -38.154046) (xy 197.751293 -38.118776) (xy 197.678085 -38.076367) (xy 197.609232 -38.0272)
			(xy 197.545356 -37.97172) (xy 197.487035 -37.910428) (xy 197.434795 -37.843877) (xy 197.389107 -37.772668)
			(xy 197.350384 -37.697444) (xy 197.318976 -37.618885) (xy 197.295165 -37.537699) (xy 197.279169 -37.454619)
			(xy 197.271129 -37.370397) (xy 197.270624 -37.328094) (xy 173.034033 -37.328094) (xy 173.018005 -37.393122)
			(xy 172.98655 -37.48734) (xy 172.947617 -37.57872) (xy 172.901456 -37.666672) (xy 172.848368 -37.750624)
			(xy 172.788697 -37.830033) (xy 172.722829 -37.904382) (xy 172.651192 -37.97319) (xy 172.574251 -38.03601)
			(xy 172.492505 -38.092435) (xy 172.406483 -38.1421) (xy 172.316744 -38.184682) (xy 172.22387 -38.219904)
			(xy 172.128462 -38.24754) (xy 172.03114 -38.267408) (xy 171.932535 -38.279381) (xy 171.833286 -38.283381)
			(xy 171.734037 -38.279381) (xy 171.635432 -38.267408) (xy 171.53811 -38.24754) (xy 171.442702 -38.219904)
			(xy 171.349828 -38.184682) (xy 171.260089 -38.1421) (xy 171.174067 -38.092435) (xy 171.092321 -38.03601)
			(xy 171.01538 -37.97319) (xy 170.943743 -37.904382) (xy 170.877875 -37.830033) (xy 170.818204 -37.750624)
			(xy 170.765116 -37.666672) (xy 170.718955 -37.57872) (xy 170.680022 -37.48734) (xy 170.648567 -37.393122)
			(xy 170.624796 -37.296679) (xy 170.608862 -37.198636) (xy 170.60087 -37.099629) (xy 11.521898 -37.099629)
			(xy 11.561279 -37.105742) (xy 11.687428 -37.133369) (xy 11.811638 -37.16871) (xy 11.933437 -37.21163)
			(xy 12.052362 -37.261967) (xy 12.167963 -37.319529) (xy 12.279802 -37.384099) (xy 12.387453 -37.455431)
			(xy 12.490508 -37.533255) (xy 12.588578 -37.617276) (xy 12.681289 -37.707175) (xy 12.768289 -37.80261)
			(xy 12.84925 -37.90322) (xy 12.923864 -38.008623) (xy 12.991847 -38.11842) (xy 13.052942 -38.232194)
			(xy 13.106917 -38.349513) (xy 13.153568 -38.469932) (xy 13.192717 -38.592995) (xy 13.224216 -38.718234)
			(xy 13.247945 -38.845175) (xy 13.263815 -38.973335) (xy 13.271765 -39.10223) (xy 13.272262 -39.1668)
			(xy 13.271765 -39.23137) (xy 13.263815 -39.360265) (xy 13.256012 -39.423283) (xy 254.45872 -39.423283)
			(xy 254.45872 -39.338561) (xy 254.466773 -39.254224) (xy 254.482807 -39.171034) (xy 254.506675 -39.089744)
			(xy 254.538163 -39.011092) (xy 254.576985 -38.935789) (xy 254.622788 -38.864517) (xy 254.675159 -38.797921)
			(xy 254.733624 -38.736606) (xy 254.797652 -38.681125) (xy 254.866664 -38.631982) (xy 254.940034 -38.589622)
			(xy 255.017099 -38.554427) (xy 255.097161 -38.526718) (xy 255.179494 -38.506744) (xy 255.263353 -38.494687)
			(xy 255.347978 -38.490656) (xy 255.432603 -38.494687) (xy 255.516462 -38.506744) (xy 255.598795 -38.526718)
			(xy 255.678857 -38.554427) (xy 255.755922 -38.589622) (xy 255.829292 -38.631982) (xy 255.898304 -38.681125)
			(xy 255.962332 -38.736606) (xy 256.020797 -38.797921) (xy 256.073168 -38.864517) (xy 256.118971 -38.935789)
			(xy 256.157793 -39.011092) (xy 256.189281 -39.089744) (xy 256.213149 -39.171034) (xy 256.229183 -39.254224)
			(xy 256.237236 -39.338561) (xy 256.23774 -39.380922) (xy 256.237236 -39.423283) (xy 256.229183 -39.50762)
			(xy 256.213149 -39.59081) (xy 256.189281 -39.6721) (xy 256.157793 -39.750752) (xy 256.118971 -39.826055)
			(xy 256.073168 -39.897327) (xy 256.020797 -39.963923) (xy 255.962332 -40.025238) (xy 255.898304 -40.080719)
			(xy 255.829292 -40.129862) (xy 255.755922 -40.172222) (xy 255.678857 -40.207417) (xy 255.598795 -40.235126)
			(xy 255.516462 -40.2551) (xy 255.432603 -40.267157) (xy 255.347978 -40.271189) (xy 255.263353 -40.267157)
			(xy 255.179494 -40.2551) (xy 255.097161 -40.235126) (xy 255.017099 -40.207417) (xy 254.940034 -40.172222)
			(xy 254.866664 -40.129862) (xy 254.797652 -40.080719) (xy 254.733624 -40.025238) (xy 254.675159 -39.963923)
			(xy 254.622788 -39.897327) (xy 254.576985 -39.826055) (xy 254.538163 -39.750752) (xy 254.506675 -39.6721)
			(xy 254.482807 -39.59081) (xy 254.466773 -39.50762) (xy 254.45872 -39.423283) (xy 13.256012 -39.423283)
			(xy 13.247945 -39.488425) (xy 13.224216 -39.615366) (xy 13.192717 -39.740605) (xy 13.153568 -39.863668)
			(xy 13.106917 -39.984087) (xy 13.052942 -40.101406) (xy 12.991847 -40.21518) (xy 12.923864 -40.324977)
			(xy 12.84925 -40.43038) (xy 12.768289 -40.53099) (xy 12.681289 -40.626425) (xy 12.588578 -40.716324)
			(xy 12.490508 -40.800345) (xy 12.413317 -40.858637) (xy 24.936192 -40.858637) (xy 24.936192 -40.773915)
			(xy 24.944245 -40.689578) (xy 24.960279 -40.606388) (xy 24.984147 -40.525098) (xy 25.015635 -40.446446)
			(xy 25.054457 -40.371143) (xy 25.10026 -40.299871) (xy 25.152631 -40.233275) (xy 25.211096 -40.17196)
			(xy 25.275124 -40.116479) (xy 25.344136 -40.067336) (xy 25.417506 -40.024976) (xy 25.494571 -39.989781)
			(xy 25.574633 -39.962072) (xy 25.656966 -39.942098) (xy 25.740825 -39.930041) (xy 25.82545 -39.92601)
			(xy 25.910075 -39.930041) (xy 25.993934 -39.942098) (xy 26.076267 -39.962072) (xy 26.156329 -39.989781)
			(xy 26.233394 -40.024976) (xy 26.306764 -40.067336) (xy 26.375776 -40.116479) (xy 26.439804 -40.17196)
			(xy 26.498269 -40.233275) (xy 26.55064 -40.299871) (xy 26.596443 -40.371143) (xy 26.635265 -40.446446)
			(xy 26.666753 -40.525098) (xy 26.690621 -40.606388) (xy 26.706655 -40.689578) (xy 26.711938 -40.744902)
			(xy 235.083357 -40.744902) (xy 235.087362 -40.656994) (xy 235.099345 -40.569814) (xy 235.119205 -40.484085)
			(xy 235.14678 -40.400517) (xy 235.181839 -40.319803) (xy 235.224092 -40.242611) (xy 235.27319 -40.169582)
			(xy 235.328726 -40.10132) (xy 235.390238 -40.03839) (xy 235.457219 -39.981316) (xy 235.529112 -39.930568)
			(xy 235.605321 -39.886568) (xy 235.685216 -39.849681) (xy 235.768135 -39.820212) (xy 235.85339 -39.798405)
			(xy 235.940274 -39.784441) (xy 236.028068 -39.778435) (xy 236.116045 -39.780439) (xy 236.203475 -39.790434)
			(xy 236.289634 -39.808338) (xy 236.373808 -39.834002) (xy 236.455299 -39.867215) (xy 236.533433 -39.907701)
			(xy 236.607561 -39.955123) (xy 236.677069 -40.00909) (xy 236.741383 -40.069155) (xy 236.799967 -40.134819)
			(xy 236.852338 -40.205538) (xy 236.898061 -40.280726) (xy 236.936758 -40.359761) (xy 236.968107 -40.441987)
			(xy 236.991849 -40.526723) (xy 237.007787 -40.613267) (xy 237.015789 -40.700902) (xy 237.01629 -40.744902)
			(xy 237.015789 -40.788902) (xy 237.007787 -40.876537) (xy 236.994276 -40.9499) (xy 246.935452 -40.9499)
			(xy 246.939482 -40.865295) (xy 246.951537 -40.781456) (xy 246.971506 -40.699142) (xy 246.999209 -40.619099)
			(xy 247.034396 -40.542053) (xy 247.076747 -40.468699) (xy 247.125879 -40.399704) (xy 247.181347 -40.335692)
			(xy 247.242648 -40.277242) (xy 247.309228 -40.224883) (xy 247.380484 -40.179091) (xy 247.45577 -40.14028)
			(xy 247.534404 -40.1088) (xy 247.615675 -40.084938) (xy 247.698846 -40.06891) (xy 247.783163 -40.060859)
			(xy 247.825514 -40.060372) (xy 247.868043 -40.060872) (xy 247.952713 -40.068982) (xy 248.036223 -40.085137)
			(xy 248.11781 -40.109189) (xy 248.196728 -40.140918) (xy 248.272258 -40.180035) (xy 248.343709 -40.226182)
			(xy 248.41043 -40.278938) (xy 248.441464 -40.308022) (xy 248.441718 -40.308276) (xy 248.44904 -40.314652)
			(xy 248.467069 -40.321822) (xy 248.47677 -40.322246) (xy 248.557288 -40.321992) (xy 248.575576 -40.314626)
			(xy 248.582688 -40.307514) (xy 248.613778 -40.278057) (xy 248.680689 -40.224588) (xy 248.752429 -40.177798)
			(xy 248.828335 -40.13812) (xy 248.907704 -40.105923) (xy 248.9898 -40.081504) (xy 249.073863 -40.065089)
			(xy 249.159115 -40.056831) (xy 249.20194 -40.056308) (xy 249.202448 -40.056308) (xy 249.244796 -40.056782)
			(xy 249.329107 -40.064837) (xy 249.412272 -40.08087) (xy 249.493536 -40.104735) (xy 249.572163 -40.136216)
			(xy 249.647442 -40.175029) (xy 249.718691 -40.220821) (xy 249.785265 -40.273178) (xy 249.84656 -40.331627)
			(xy 249.902022 -40.395637) (xy 249.951149 -40.464629) (xy 249.993496 -40.537978) (xy 250.028678 -40.615021)
			(xy 250.056379 -40.695058) (xy 250.076346 -40.777367) (xy 250.088399 -40.8612) (xy 250.092429 -40.9458)
			(xy 250.088399 -41.0304) (xy 250.076346 -41.114233) (xy 250.056379 -41.196542) (xy 250.028678 -41.276579)
			(xy 249.993496 -41.353622) (xy 249.951149 -41.426971) (xy 249.902022 -41.495963) (xy 249.84656 -41.559973)
			(xy 249.785265 -41.618422) (xy 249.718691 -41.670779) (xy 249.647442 -41.716571) (xy 249.572163 -41.755384)
			(xy 249.493536 -41.786865) (xy 249.412272 -41.81073) (xy 249.329107 -41.826763) (xy 249.244796 -41.834818)
			(xy 249.202448 -41.835324) (xy 249.159919 -41.834822) (xy 249.07525 -41.826709) (xy 248.991741 -41.810552)
			(xy 248.910155 -41.7865) (xy 248.831237 -41.754771) (xy 248.755707 -41.715655) (xy 248.684255 -41.66951)
			(xy 248.617533 -41.616756) (xy 248.586498 -41.587674) (xy 248.586244 -41.58742) (xy 248.578903 -41.58107)
			(xy 248.560888 -41.573885) (xy 248.551192 -41.57345) (xy 248.470674 -41.573704) (xy 248.452386 -41.58107)
			(xy 248.445274 -41.588182) (xy 248.414201 -41.617657) (xy 248.347287 -41.671125) (xy 248.275544 -41.717913)
			(xy 248.199635 -41.757589) (xy 248.120264 -41.789784) (xy 248.038166 -41.8142) (xy 247.954101 -41.830612)
			(xy 247.868848 -41.838866) (xy 247.826022 -41.839388) (xy 247.825514 -41.839388) (xy 247.783163 -41.838941)
			(xy 247.698846 -41.83089) (xy 247.615675 -41.814862) (xy 247.534404 -41.791) (xy 247.45577 -41.75952)
			(xy 247.380484 -41.720709) (xy 247.309228 -41.674917) (xy 247.242648 -41.622558) (xy 247.181347 -41.564108)
			(xy 247.125879 -41.500096) (xy 247.076747 -41.431101) (xy 247.034396 -41.357747) (xy 246.999209 -41.280701)
			(xy 246.971506 -41.200658) (xy 246.951537 -41.118344) (xy 246.939482 -41.034505) (xy 246.935452 -40.9499)
			(xy 236.994276 -40.9499) (xy 236.991849 -40.963081) (xy 236.968107 -41.047817) (xy 236.936758 -41.130043)
			(xy 236.898061 -41.209078) (xy 236.852338 -41.284266) (xy 236.799967 -41.354985) (xy 236.741383 -41.420649)
			(xy 236.677069 -41.480714) (xy 236.607561 -41.534681) (xy 236.533433 -41.582103) (xy 236.455299 -41.622589)
			(xy 236.373808 -41.655802) (xy 236.289634 -41.681466) (xy 236.203475 -41.69937) (xy 236.116045 -41.709365)
			(xy 236.028068 -41.711369) (xy 235.940274 -41.705363) (xy 235.85339 -41.691399) (xy 235.768135 -41.669592)
			(xy 235.685216 -41.640123) (xy 235.605321 -41.603236) (xy 235.529112 -41.559236) (xy 235.457219 -41.508488)
			(xy 235.390238 -41.451414) (xy 235.328726 -41.388484) (xy 235.27319 -41.320222) (xy 235.224092 -41.247193)
			(xy 235.181839 -41.170001) (xy 235.14678 -41.089287) (xy 235.119205 -41.005719) (xy 235.099345 -40.91999)
			(xy 235.087362 -40.83281) (xy 235.083357 -40.744902) (xy 26.711938 -40.744902) (xy 26.714708 -40.773915)
			(xy 26.715212 -40.816276) (xy 26.714708 -40.858637) (xy 26.706655 -40.942974) (xy 26.690621 -41.026164)
			(xy 26.666753 -41.107454) (xy 26.635265 -41.186106) (xy 26.596443 -41.261409) (xy 26.55064 -41.332681)
			(xy 26.498269 -41.399277) (xy 26.439804 -41.460592) (xy 26.375776 -41.516073) (xy 26.306764 -41.565216)
			(xy 26.233394 -41.607576) (xy 26.156329 -41.642771) (xy 26.076267 -41.67048) (xy 25.993934 -41.690454)
			(xy 25.910075 -41.702511) (xy 25.82545 -41.706543) (xy 25.740825 -41.702511) (xy 25.656966 -41.690454)
			(xy 25.574633 -41.67048) (xy 25.494571 -41.642771) (xy 25.417506 -41.607576) (xy 25.344136 -41.565216)
			(xy 25.275124 -41.516073) (xy 25.211096 -41.460592) (xy 25.152631 -41.399277) (xy 25.10026 -41.332681)
			(xy 25.054457 -41.261409) (xy 25.015635 -41.186106) (xy 24.984147 -41.107454) (xy 24.960279 -41.026164)
			(xy 24.944245 -40.942974) (xy 24.936192 -40.858637) (xy 12.413317 -40.858637) (xy 12.387453 -40.878169)
			(xy 12.279802 -40.949501) (xy 12.167963 -41.014071) (xy 12.052362 -41.071633) (xy 11.933437 -41.12197)
			(xy 11.811638 -41.16489) (xy 11.687428 -41.200231) (xy 11.561279 -41.227858) (xy 11.433667 -41.247667)
			(xy 11.305078 -41.259583) (xy 11.176 -41.26356) (xy 11.046922 -41.259583) (xy 10.918333 -41.247667)
			(xy 10.790721 -41.227858) (xy 10.664572 -41.200231) (xy 10.540362 -41.16489) (xy 10.418563 -41.12197)
			(xy 10.299638 -41.071633) (xy 10.184037 -41.014071) (xy 10.072198 -40.949501) (xy 9.964547 -40.878169)
			(xy 9.861492 -40.800345) (xy 9.763422 -40.716324) (xy 9.670711 -40.626425) (xy 9.583711 -40.53099)
			(xy 9.50275 -40.43038) (xy 9.428136 -40.324977) (xy 9.360153 -40.21518) (xy 9.299058 -40.101406)
			(xy 9.245083 -39.984087) (xy 9.198432 -39.863668) (xy 9.159283 -39.740605) (xy 9.127784 -39.615366)
			(xy 9.104055 -39.488425) (xy 9.088185 -39.360265) (xy 9.080235 -39.23137) (xy 0.509016 -39.23137)
			(xy 0.509016 -43.481752) (xy 178.630072 -43.481752) (xy 178.630072 -42.618152) (xy 178.630558 -42.590883)
			(xy 178.63832 -42.536899) (xy 178.653685 -42.484569) (xy 178.676342 -42.434959) (xy 178.705828 -42.389078)
			(xy 178.741543 -42.347861) (xy 178.78276 -42.312146) (xy 178.828641 -42.28266) (xy 178.878251 -42.260003)
			(xy 178.930581 -42.244638) (xy 178.984565 -42.236876) (xy 179.039103 -42.236876) (xy 179.093087 -42.244638)
			(xy 179.145417 -42.260003) (xy 179.195027 -42.28266) (xy 179.240908 -42.312146) (xy 179.282125 -42.347861)
			(xy 179.31784 -42.389078) (xy 179.347326 -42.434959) (xy 179.369983 -42.484569) (xy 179.385348 -42.536899)
			(xy 179.39311 -42.590883) (xy 179.393596 -42.618152) (xy 179.393596 -43.481752) (xy 179.39311 -43.509021)
			(xy 179.385348 -43.563005) (xy 179.369983 -43.615335) (xy 179.347326 -43.664945) (xy 179.31784 -43.710826)
			(xy 179.282125 -43.752043) (xy 179.240908 -43.787758) (xy 179.195027 -43.817244) (xy 179.145417 -43.839901)
			(xy 179.093087 -43.855266) (xy 179.039103 -43.863028) (xy 178.984565 -43.863028) (xy 178.930581 -43.855266)
			(xy 178.878251 -43.839901) (xy 178.828641 -43.817244) (xy 178.78276 -43.787758) (xy 178.741543 -43.752043)
			(xy 178.705828 -43.710826) (xy 178.676342 -43.664945) (xy 178.653685 -43.615335) (xy 178.63832 -43.563005)
			(xy 178.630558 -43.509021) (xy 178.630072 -43.481752) (xy 0.509016 -43.481752) (xy 0.509016 -47.04994)
			(xy 59.582066 -47.04994) (xy 59.586045 -46.890389) (xy 59.597972 -46.731234) (xy 59.617818 -46.572872)
			(xy 59.645532 -46.415696) (xy 59.681047 -46.260096) (xy 59.724273 -46.10646) (xy 59.775104 -45.95517)
			(xy 59.833413 -45.806602) (xy 59.899054 -45.661125) (xy 59.971866 -45.519101) (xy 60.051666 -45.380882)
			(xy 60.138257 -45.246813) (xy 60.231423 -45.117227) (xy 60.330933 -44.992446) (xy 60.436538 -44.87278)
			(xy 60.547978 -44.758527) (xy 60.664973 -44.649971) (xy 60.787235 -44.547381) (xy 60.914458 -44.451014)
			(xy 61.046326 -44.361107) (xy 61.182512 -44.277886) (xy 61.322677 -44.201556) (xy 61.466472 -44.132307)
			(xy 61.613541 -44.070313) (xy 61.763517 -44.015726) (xy 61.916027 -43.968683) (xy 62.070693 -43.9293)
			(xy 62.227129 -43.897676) (xy 62.384947 -43.873888) (xy 62.543755 -43.857997) (xy 62.703158 -43.850041)
			(xy 62.782958 -43.849544) (xy 64.382904 -43.849544) (xy 64.462705 -43.850033) (xy 64.622107 -43.857989)
			(xy 64.780916 -43.87388) (xy 64.938734 -43.897668) (xy 65.095171 -43.929293) (xy 65.249837 -43.968675)
			(xy 65.402347 -44.015719) (xy 65.552323 -44.070306) (xy 65.699392 -44.132301) (xy 65.843188 -44.201549)
			(xy 65.983353 -44.277879) (xy 66.119539 -44.361101) (xy 66.251408 -44.451008) (xy 66.378631 -44.547376)
			(xy 66.500893 -44.649966) (xy 66.617889 -44.758522) (xy 66.729328 -44.872775) (xy 66.834934 -44.992442)
			(xy 66.934444 -45.117223) (xy 67.02761 -45.246809) (xy 67.114201 -45.380878) (xy 67.194001 -45.519097)
			(xy 67.266813 -45.661122) (xy 67.332455 -45.806599) (xy 67.390764 -45.955168) (xy 67.441595 -46.106458)
			(xy 67.484821 -46.260094) (xy 67.520336 -46.415694) (xy 67.54805 -46.572871) (xy 67.567896 -46.731233)
			(xy 67.579823 -46.890388) (xy 67.583802 -47.04994) (xy 89.78165 -47.04994) (xy 89.78563 -46.895439)
			(xy 89.797557 -46.741349) (xy 89.817402 -46.588076) (xy 89.84511 -46.436028) (xy 89.880608 -46.285609)
			(xy 89.923803 -46.137216) (xy 89.97458 -45.991243) (xy 90.032804 -45.848078) (xy 90.098321 -45.708101)
			(xy 90.170957 -45.571681) (xy 90.250519 -45.439181) (xy 90.336796 -45.310953) (xy 90.42956 -45.187337)
			(xy 90.528565 -45.068659) (xy 90.633548 -44.955236) (xy 90.74423 -44.847368) (xy 90.860319 -44.74534)
			(xy 90.981506 -44.649424) (xy 91.10747 -44.559873) (xy 91.237877 -44.476926) (xy 91.372381 -44.400801)
			(xy 91.510626 -44.331702) (xy 91.652244 -44.269811) (xy 91.796861 -44.215293) (xy 91.944092 -44.168291)
			(xy 92.093548 -44.128931) (xy 92.244832 -44.097317) (xy 92.397543 -44.073533) (xy 92.551275 -44.057642)
			(xy 92.705622 -44.049686) (xy 92.782898 -44.049188) (xy 94.383098 -44.049188) (xy 94.460374 -44.049669)
			(xy 94.614722 -44.057625) (xy 94.768456 -44.073516) (xy 94.921168 -44.0973) (xy 95.072452 -44.128914)
			(xy 95.221909 -44.168274) (xy 95.369142 -44.215276) (xy 95.513759 -44.269795) (xy 95.655379 -44.331686)
			(xy 95.793624 -44.400785) (xy 95.928129 -44.47691) (xy 96.058537 -44.559858) (xy 96.184502 -44.649409)
			(xy 96.30569 -44.745326) (xy 96.421779 -44.847354) (xy 96.532463 -44.955223) (xy 96.555487 -44.980098)
			(xy 181.659784 -44.980098) (xy 181.659784 -44.116498) (xy 181.66027 -44.089229) (xy 181.668032 -44.035245)
			(xy 181.683397 -43.982915) (xy 181.706054 -43.933305) (xy 181.73554 -43.887424) (xy 181.771255 -43.846207)
			(xy 181.812472 -43.810492) (xy 181.858353 -43.781006) (xy 181.907963 -43.758349) (xy 181.960293 -43.742984)
			(xy 182.014277 -43.735222) (xy 182.068815 -43.735222) (xy 182.122799 -43.742984) (xy 182.175129 -43.758349)
			(xy 182.224739 -43.781006) (xy 182.27062 -43.810492) (xy 182.311837 -43.846207) (xy 182.347552 -43.887424)
			(xy 182.377038 -43.933305) (xy 182.399695 -43.982915) (xy 182.412218 -44.025566) (xy 236.740192 -44.025566)
			(xy 236.74068 -43.984453) (xy 236.74827 -43.902577) (xy 236.763381 -43.82175) (xy 236.785886 -43.742663)
			(xy 236.815591 -43.665989) (xy 236.852243 -43.592383) (xy 236.895531 -43.522473) (xy 236.945083 -43.456854)
			(xy 237.000479 -43.396088) (xy 237.061245 -43.340691) (xy 237.126863 -43.291137) (xy 237.196773 -43.247849)
			(xy 237.270378 -43.211196) (xy 237.347052 -43.181489) (xy 237.426139 -43.158984) (xy 237.506965 -43.143872)
			(xy 237.588841 -43.136281) (xy 237.629954 -43.135804) (xy 237.672596 -43.136331) (xy 237.757484 -43.144543)
			(xy 237.841197 -43.160838) (xy 237.922968 -43.185068) (xy 237.962694 -43.200574) (xy 237.971356 -43.203655)
			(xy 237.989722 -43.204046) (xy 237.998508 -43.201336) (xy 238.034032 -43.189272) (xy 238.106663 -43.170452)
			(xy 238.18062 -43.157817) (xy 238.25538 -43.151455) (xy 238.292894 -43.151044) (xy 238.332166 -43.151496)
			(xy 238.410399 -43.158477) (xy 238.487712 -43.172332) (xy 238.563501 -43.192954) (xy 238.600488 -43.206162)
			(xy 238.609037 -43.208926) (xy 238.626991 -43.208926) (xy 238.63554 -43.206162) (xy 238.672533 -43.192975)
			(xy 238.748323 -43.172363) (xy 238.825633 -43.158506) (xy 238.903863 -43.151512) (xy 238.943134 -43.151044)
			(xy 238.981423 -43.151469) (xy 239.057717 -43.158071) (xy 239.133159 -43.171215) (xy 239.207191 -43.190803)
			(xy 239.243362 -43.203368) (xy 239.251799 -43.206019) (xy 239.269469 -43.206019) (xy 239.277906 -43.203368)
			(xy 239.314089 -43.190839) (xy 239.38812 -43.171262) (xy 239.463558 -43.158111) (xy 239.539846 -43.151482)
			(xy 239.578134 -43.151044) (xy 239.616423 -43.151469) (xy 239.692717 -43.158071) (xy 239.768159 -43.171215)
			(xy 239.842191 -43.190803) (xy 239.878362 -43.203368) (xy 239.886799 -43.206019) (xy 239.904469 -43.206019)
			(xy 239.912906 -43.203368) (xy 239.949089 -43.190839) (xy 240.02312 -43.171262) (xy 240.098558 -43.158111)
			(xy 240.174846 -43.151482) (xy 240.213134 -43.151044) (xy 240.25606 -43.151581) (xy 240.341511 -43.159862)
			(xy 240.425768 -43.176335) (xy 240.508046 -43.200846) (xy 240.587581 -43.233168) (xy 240.613613 -43.246802)
			(xy 243.62918 -43.246802) (xy 243.629584 -43.208512) (xy 243.636192 -43.132218) (xy 243.649342 -43.056775)
			(xy 243.668936 -42.982745) (xy 243.681504 -42.946574) (xy 243.684156 -42.938137) (xy 243.684156 -42.920466)
			(xy 243.681504 -42.91203) (xy 243.668959 -42.875853) (xy 243.649386 -42.80182) (xy 243.636239 -42.72638)
			(xy 243.629616 -42.65009) (xy 243.62918 -42.611802) (xy 243.629684 -42.569441) (xy 243.637737 -42.485104)
			(xy 243.653771 -42.401914) (xy 243.677639 -42.320624) (xy 243.709127 -42.241972) (xy 243.747949 -42.166669)
			(xy 243.793752 -42.095397) (xy 243.846123 -42.028801) (xy 243.904588 -41.967486) (xy 243.968616 -41.912005)
			(xy 244.037628 -41.862862) (xy 244.110998 -41.820502) (xy 244.188063 -41.785307) (xy 244.268125 -41.757598)
			(xy 244.350458 -41.737624) (xy 244.434317 -41.725567) (xy 244.518942 -41.721536) (xy 244.603567 -41.725567)
			(xy 244.687426 -41.737624) (xy 244.769759 -41.757598) (xy 244.849821 -41.785307) (xy 244.926886 -41.820502)
			(xy 245.000256 -41.862862) (xy 245.069268 -41.912005) (xy 245.133296 -41.967486) (xy 245.191761 -42.028801)
			(xy 245.244132 -42.095397) (xy 245.289935 -42.166669) (xy 245.328757 -42.241972) (xy 245.360245 -42.320624)
			(xy 245.384113 -42.401914) (xy 245.400147 -42.485104) (xy 245.4082 -42.569441) (xy 245.408704 -42.611802)
			(xy 245.408302 -42.650092) (xy 245.401694 -42.726386) (xy 245.388543 -42.801829) (xy 245.368949 -42.875859)
			(xy 245.35638 -42.91203) (xy 245.353727 -42.920466) (xy 245.353728 -42.938137) (xy 245.35638 -42.946574)
			(xy 245.368926 -42.982751) (xy 245.388499 -43.056784) (xy 245.401645 -43.132224) (xy 245.408269 -43.208514)
			(xy 245.408704 -43.246802) (xy 245.4082 -43.289163) (xy 245.400147 -43.3735) (xy 245.384113 -43.45669)
			(xy 245.360245 -43.53798) (xy 245.328757 -43.616632) (xy 245.289935 -43.691935) (xy 245.244132 -43.763207)
			(xy 245.191761 -43.829803) (xy 245.133296 -43.891118) (xy 245.069268 -43.946599) (xy 245.000256 -43.995742)
			(xy 244.926886 -44.038102) (xy 244.849821 -44.073297) (xy 244.769759 -44.101006) (xy 244.687426 -44.12098)
			(xy 244.603567 -44.133037) (xy 244.518942 -44.137069) (xy 244.434317 -44.133037) (xy 244.350458 -44.12098)
			(xy 244.268125 -44.101006) (xy 244.188063 -44.073297) (xy 244.110998 -44.038102) (xy 244.037628 -43.995742)
			(xy 243.968616 -43.946599) (xy 243.904588 -43.891118) (xy 243.846123 -43.829803) (xy 243.793752 -43.763207)
			(xy 243.747949 -43.691935) (xy 243.709127 -43.616632) (xy 243.677639 -43.53798) (xy 243.653771 -43.45669)
			(xy 243.637737 -43.3735) (xy 243.629684 -43.289163) (xy 243.62918 -43.246802) (xy 240.613613 -43.246802)
			(xy 240.663633 -43.272999) (xy 240.735496 -43.31997) (xy 240.802501 -43.373643) (xy 240.864025 -43.433521)
			(xy 240.919496 -43.499046) (xy 240.968398 -43.569608) (xy 241.010277 -43.644552) (xy 241.044744 -43.723182)
			(xy 241.071477 -43.804765) (xy 241.090229 -43.888544) (xy 241.096038 -43.931078) (xy 241.097792 -43.94092)
			(xy 241.107661 -43.958279) (xy 241.123386 -43.970587) (xy 241.132868 -43.97375) (xy 241.172506 -43.985287)
			(xy 241.249638 -44.014728) (xy 241.32371 -44.051189) (xy 241.394086 -44.094356) (xy 241.460159 -44.143858)
			(xy 241.521362 -44.199269) (xy 241.577167 -44.260112) (xy 241.627095 -44.325864) (xy 241.670716 -44.395959)
			(xy 241.707655 -44.469795) (xy 241.737594 -44.546735) (xy 241.760276 -44.626118) (xy 241.775505 -44.707261)
			(xy 241.78315 -44.789466) (xy 241.783616 -44.830746) (xy 241.783231 -44.871862) (xy 241.775639 -44.953744)
			(xy 241.760525 -45.034576) (xy 241.738017 -45.113668) (xy 241.708307 -45.190346) (xy 241.671649 -45.263956)
			(xy 241.628355 -45.333869) (xy 241.578796 -45.39949) (xy 241.523393 -45.460258) (xy 241.462619 -45.515654)
			(xy 241.396993 -45.565207) (xy 241.327075 -45.608494) (xy 241.253462 -45.645144) (xy 241.176781 -45.674846)
			(xy 241.097686 -45.697346) (xy 241.016853 -45.712452) (xy 240.93497 -45.720035) (xy 240.893854 -45.720508)
			(xy 240.848047 -45.719908) (xy 240.756919 -45.710469) (xy 240.667241 -45.691726) (xy 240.579961 -45.663878)
			(xy 240.537746 -45.646086) (xy 240.528923 -45.642621) (xy 240.509997 -45.641842) (xy 240.500916 -45.644562)
			(xy 240.454475 -45.659757) (xy 240.359116 -45.681105) (xy 240.261993 -45.691873) (xy 240.213134 -45.692568)
			(xy 240.174844 -45.692152) (xy 240.09855 -45.685547) (xy 240.023108 -45.672401) (xy 239.949077 -45.652811)
			(xy 239.912906 -45.640244) (xy 239.904469 -45.637593) (xy 239.886799 -45.637593) (xy 239.878362 -45.640244)
			(xy 239.842183 -45.652782) (xy 239.76815 -45.672357) (xy 239.692711 -45.685505) (xy 239.616422 -45.692131)
			(xy 239.578134 -45.692568) (xy 239.539844 -45.692152) (xy 239.46355 -45.685547) (xy 239.388108 -45.672401)
			(xy 239.314077 -45.652811) (xy 239.277906 -45.640244) (xy 239.269469 -45.637593) (xy 239.251799 -45.637593)
			(xy 239.243362 -45.640244) (xy 239.207183 -45.652782) (xy 239.13315 -45.672357) (xy 239.057711 -45.685505)
			(xy 238.981422 -45.692131) (xy 238.943134 -45.692568) (xy 238.903862 -45.692107) (xy 238.825629 -45.685129)
			(xy 238.748316 -45.671276) (xy 238.672527 -45.650657) (xy 238.63554 -45.63745) (xy 238.626991 -45.634686)
			(xy 238.609037 -45.634686) (xy 238.600488 -45.63745) (xy 238.563502 -45.650659) (xy 238.48771 -45.671265)
			(xy 238.410397 -45.685115) (xy 238.332165 -45.692103) (xy 238.292894 -45.692568) (xy 238.24936 -45.692039)
			(xy 238.16271 -45.683524) (xy 238.077306 -45.666586) (xy 237.993965 -45.641387) (xy 237.913484 -45.608168)
			(xy 237.87481 -45.588174) (xy 237.86657 -45.584248) (xy 237.848476 -45.581916) (xy 237.839504 -45.583602)
			(xy 237.790399 -45.594167) (xy 237.690592 -45.6055) (xy 237.640368 -45.606208) (xy 237.640114 -45.606208)
			(xy 237.599001 -45.605674) (xy 237.517127 -45.598088) (xy 237.436301 -45.582981) (xy 237.357214 -45.560481)
			(xy 237.280541 -45.53078) (xy 237.206935 -45.494131) (xy 237.137024 -45.450847) (xy 237.071406 -45.401297)
			(xy 237.010639 -45.345904) (xy 236.955242 -45.285141) (xy 236.905687 -45.219525) (xy 236.862399 -45.149618)
			(xy 236.825745 -45.076014) (xy 236.796038 -44.999343) (xy 236.773533 -44.920257) (xy 236.75842 -44.839433)
			(xy 236.750829 -44.757559) (xy 236.750352 -44.716446) (xy 236.750814 -44.676228) (xy 236.758123 -44.596123)
			(xy 236.772622 -44.517004) (xy 236.794193 -44.439513) (xy 236.80801 -44.40174) (xy 236.811025 -44.392621)
			(xy 236.810769 -44.373433) (xy 236.807502 -44.364402) (xy 236.791394 -44.324025) (xy 236.766206 -44.240819)
			(xy 236.749266 -44.15555) (xy 236.740738 -44.069034) (xy 236.740192 -44.025566) (xy 182.412218 -44.025566)
			(xy 182.41506 -44.035245) (xy 182.422822 -44.089229) (xy 182.423308 -44.116498) (xy 182.423308 -44.980098)
			(xy 182.422822 -45.007367) (xy 182.41506 -45.061351) (xy 182.399695 -45.113681) (xy 182.377038 -45.163291)
			(xy 182.347552 -45.209172) (xy 182.311837 -45.250389) (xy 182.27062 -45.286104) (xy 182.224739 -45.31559)
			(xy 182.175129 -45.338247) (xy 182.122799 -45.353612) (xy 182.068815 -45.361374) (xy 182.014277 -45.361374)
			(xy 181.960293 -45.353612) (xy 181.907963 -45.338247) (xy 181.858353 -45.31559) (xy 181.812472 -45.286104)
			(xy 181.771255 -45.250389) (xy 181.73554 -45.209172) (xy 181.706054 -45.163291) (xy 181.683397 -45.113681)
			(xy 181.668032 -45.061351) (xy 181.66027 -45.007367) (xy 181.659784 -44.980098) (xy 96.555487 -44.980098)
			(xy 96.637446 -45.068647) (xy 96.736452 -45.187325) (xy 96.829216 -45.310943) (xy 96.915495 -45.439171)
			(xy 96.995057 -45.571672) (xy 97.067693 -45.708092) (xy 97.133211 -45.848071) (xy 97.191435 -45.991237)
			(xy 97.242212 -46.13721) (xy 97.285407 -46.285604) (xy 97.320906 -46.436025) (xy 97.329238 -46.481746)
			(xy 178.630072 -46.481746) (xy 178.630072 -45.618146) (xy 178.630558 -45.590877) (xy 178.63832 -45.536893)
			(xy 178.653685 -45.484563) (xy 178.676342 -45.434953) (xy 178.705828 -45.389072) (xy 178.741543 -45.347855)
			(xy 178.78276 -45.31214) (xy 178.828641 -45.282654) (xy 178.878251 -45.259997) (xy 178.930581 -45.244632)
			(xy 178.984565 -45.23687) (xy 179.039103 -45.23687) (xy 179.093087 -45.244632) (xy 179.145417 -45.259997)
			(xy 179.195027 -45.282654) (xy 179.240908 -45.31214) (xy 179.282125 -45.347855) (xy 179.31784 -45.389072)
			(xy 179.347326 -45.434953) (xy 179.369983 -45.484563) (xy 179.385348 -45.536893) (xy 179.39311 -45.590877)
			(xy 179.393596 -45.618146) (xy 179.393596 -46.481746) (xy 179.39311 -46.509015) (xy 179.385348 -46.562999)
			(xy 179.369983 -46.615329) (xy 179.347326 -46.664939) (xy 179.31784 -46.71082) (xy 179.282125 -46.752037)
			(xy 179.240908 -46.787752) (xy 179.195027 -46.817238) (xy 179.145417 -46.839895) (xy 179.093087 -46.85526)
			(xy 179.039103 -46.863022) (xy 178.984565 -46.863022) (xy 178.930581 -46.85526) (xy 178.878251 -46.839895)
			(xy 178.828641 -46.817238) (xy 178.78276 -46.787752) (xy 178.741543 -46.752037) (xy 178.705828 -46.71082)
			(xy 178.676342 -46.664939) (xy 178.653685 -46.615329) (xy 178.63832 -46.562999) (xy 178.630558 -46.509015)
			(xy 178.630072 -46.481746) (xy 97.329238 -46.481746) (xy 97.348615 -46.588073) (xy 97.368459 -46.741347)
			(xy 97.380387 -46.895438) (xy 97.384366 -47.04994) (xy 97.380387 -47.204442) (xy 97.368459 -47.358533)
			(xy 97.348615 -47.511807) (xy 97.320906 -47.663855) (xy 97.285407 -47.814276) (xy 97.242212 -47.96267)
			(xy 97.219453 -48.028098) (xy 181.659784 -48.028098) (xy 181.659784 -47.164498) (xy 181.66027 -47.137229)
			(xy 181.668032 -47.083245) (xy 181.683397 -47.030915) (xy 181.706054 -46.981305) (xy 181.73554 -46.935424)
			(xy 181.771255 -46.894207) (xy 181.812472 -46.858492) (xy 181.858353 -46.829006) (xy 181.907963 -46.806349)
			(xy 181.960293 -46.790984) (xy 182.014277 -46.783222) (xy 182.068815 -46.783222) (xy 182.122799 -46.790984)
			(xy 182.175129 -46.806349) (xy 182.224739 -46.829006) (xy 182.27062 -46.858492) (xy 182.311837 -46.894207)
			(xy 182.347552 -46.935424) (xy 182.377038 -46.981305) (xy 182.399695 -47.030915) (xy 182.41506 -47.083245)
			(xy 182.422822 -47.137229) (xy 182.423308 -47.164498) (xy 182.423308 -48.028098) (xy 182.422822 -48.055367)
			(xy 182.41506 -48.109351) (xy 182.399695 -48.161681) (xy 182.377038 -48.211291) (xy 182.347552 -48.257172)
			(xy 182.311837 -48.298389) (xy 182.27062 -48.334104) (xy 182.224739 -48.36359) (xy 182.175129 -48.386247)
			(xy 182.122799 -48.401612) (xy 182.068815 -48.409374) (xy 182.014277 -48.409374) (xy 181.960293 -48.401612)
			(xy 181.907963 -48.386247) (xy 181.858353 -48.36359) (xy 181.812472 -48.334104) (xy 181.771255 -48.298389)
			(xy 181.73554 -48.257172) (xy 181.706054 -48.211291) (xy 181.683397 -48.161681) (xy 181.668032 -48.109351)
			(xy 181.66027 -48.055367) (xy 181.659784 -48.028098) (xy 97.219453 -48.028098) (xy 97.191435 -48.108643)
			(xy 97.133211 -48.251809) (xy 97.067693 -48.391788) (xy 96.995057 -48.528208) (xy 96.915495 -48.660709)
			(xy 96.829216 -48.788937) (xy 96.736452 -48.912555) (xy 96.637446 -49.031233) (xy 96.532463 -49.144657)
			(xy 96.421779 -49.252526) (xy 96.30569 -49.354554) (xy 96.184502 -49.450471) (xy 96.140518 -49.48174)
			(xy 178.630072 -49.48174) (xy 178.630072 -48.61814) (xy 178.630558 -48.590871) (xy 178.63832 -48.536887)
			(xy 178.653685 -48.484557) (xy 178.676342 -48.434947) (xy 178.705828 -48.389066) (xy 178.741543 -48.347849)
			(xy 178.78276 -48.312134) (xy 178.828641 -48.282648) (xy 178.878251 -48.259991) (xy 178.930581 -48.244626)
			(xy 178.984565 -48.236864) (xy 179.039103 -48.236864) (xy 179.093087 -48.244626) (xy 179.145417 -48.259991)
			(xy 179.195027 -48.282648) (xy 179.240908 -48.312134) (xy 179.282125 -48.347849) (xy 179.31784 -48.389066)
			(xy 179.347326 -48.434947) (xy 179.369983 -48.484557) (xy 179.385348 -48.536887) (xy 179.39311 -48.590871)
			(xy 179.393596 -48.61814) (xy 179.393596 -49.48174) (xy 179.39311 -49.509009) (xy 179.385348 -49.562993)
			(xy 179.369983 -49.615323) (xy 179.347326 -49.664933) (xy 179.31784 -49.710814) (xy 179.282125 -49.752031)
			(xy 179.240908 -49.787746) (xy 179.195027 -49.817232) (xy 179.145417 -49.839889) (xy 179.093087 -49.855254)
			(xy 179.039103 -49.863016) (xy 178.984565 -49.863016) (xy 178.930581 -49.855254) (xy 178.878251 -49.839889)
			(xy 178.828641 -49.817232) (xy 178.78276 -49.787746) (xy 178.741543 -49.752031) (xy 178.705828 -49.710814)
			(xy 178.676342 -49.664933) (xy 178.653685 -49.615323) (xy 178.63832 -49.562993) (xy 178.630558 -49.509009)
			(xy 178.630072 -49.48174) (xy 96.140518 -49.48174) (xy 96.058537 -49.540022) (xy 95.928129 -49.62297)
			(xy 95.793624 -49.699095) (xy 95.655379 -49.768194) (xy 95.513759 -49.830085) (xy 95.369142 -49.884604)
			(xy 95.221909 -49.931606) (xy 95.072452 -49.970966) (xy 94.921168 -50.00258) (xy 94.768456 -50.026364)
			(xy 94.614722 -50.042255) (xy 94.460374 -50.050211) (xy 94.383098 -50.0507) (xy 92.782898 -50.0507)
			(xy 92.705622 -50.050194) (xy 92.551275 -50.042238) (xy 92.397543 -50.026347) (xy 92.244832 -50.002563)
			(xy 92.093548 -49.970949) (xy 91.944092 -49.931589) (xy 91.796861 -49.884587) (xy 91.652244 -49.830069)
			(xy 91.510626 -49.768178) (xy 91.372381 -49.699079) (xy 91.237877 -49.622954) (xy 91.10747 -49.540007)
			(xy 90.981506 -49.450456) (xy 90.860319 -49.35454) (xy 90.74423 -49.252512) (xy 90.633548 -49.144644)
			(xy 90.528565 -49.031221) (xy 90.42956 -48.912543) (xy 90.336796 -48.788927) (xy 90.250519 -48.660699)
			(xy 90.170957 -48.528199) (xy 90.098321 -48.391779) (xy 90.032804 -48.251802) (xy 89.97458 -48.108637)
			(xy 89.923803 -47.962664) (xy 89.880608 -47.814271) (xy 89.84511 -47.663852) (xy 89.817402 -47.511804)
			(xy 89.797557 -47.358531) (xy 89.78563 -47.204441) (xy 89.78165 -47.04994) (xy 67.583802 -47.04994)
			(xy 67.579823 -47.209492) (xy 67.567896 -47.368647) (xy 67.54805 -47.527009) (xy 67.520336 -47.684186)
			(xy 67.484821 -47.839786) (xy 67.441595 -47.993422) (xy 67.390764 -48.144712) (xy 67.332455 -48.293281)
			(xy 67.266813 -48.438758) (xy 67.194001 -48.580783) (xy 67.114201 -48.719002) (xy 67.02761 -48.853071)
			(xy 66.934444 -48.982657) (xy 66.834934 -49.107438) (xy 66.729328 -49.227105) (xy 66.617889 -49.341358)
			(xy 66.500893 -49.449914) (xy 66.378631 -49.552504) (xy 66.251408 -49.648872) (xy 66.119539 -49.738779)
			(xy 65.983353 -49.822001) (xy 65.843188 -49.898331) (xy 65.699392 -49.967579) (xy 65.552323 -50.029574)
			(xy 65.402347 -50.084161) (xy 65.249837 -50.131205) (xy 65.095171 -50.170587) (xy 64.938734 -50.202212)
			(xy 64.780916 -50.226) (xy 64.622107 -50.241891) (xy 64.462705 -50.249847) (xy 64.382904 -50.250344)
			(xy 62.782958 -50.250344) (xy 62.703158 -50.249839) (xy 62.543755 -50.241883) (xy 62.384947 -50.225992)
			(xy 62.227129 -50.202204) (xy 62.070693 -50.17058) (xy 61.916027 -50.131197) (xy 61.763517 -50.084154)
			(xy 61.613541 -50.029567) (xy 61.466472 -49.967573) (xy 61.322677 -49.898324) (xy 61.182512 -49.821994)
			(xy 61.046326 -49.738773) (xy 60.914458 -49.648866) (xy 60.787235 -49.552499) (xy 60.664973 -49.449909)
			(xy 60.547978 -49.341353) (xy 60.436538 -49.2271) (xy 60.330933 -49.107434) (xy 60.231423 -48.982653)
			(xy 60.138257 -48.853067) (xy 60.051666 -48.718998) (xy 59.971866 -48.580779) (xy 59.899054 -48.438755)
			(xy 59.833413 -48.293278) (xy 59.775104 -48.14471) (xy 59.724273 -47.99342) (xy 59.681047 -47.839784)
			(xy 59.645532 -47.684184) (xy 59.617818 -47.527008) (xy 59.597972 -47.368646) (xy 59.586045 -47.209491)
			(xy 59.582066 -47.04994) (xy 0.509016 -47.04994) (xy 0.509016 -50.949098) (xy 181.659784 -50.949098)
			(xy 181.659784 -50.085498) (xy 181.66027 -50.058229) (xy 181.668032 -50.004245) (xy 181.683397 -49.951915)
			(xy 181.706054 -49.902305) (xy 181.73554 -49.856424) (xy 181.771255 -49.815207) (xy 181.812472 -49.779492)
			(xy 181.858353 -49.750006) (xy 181.907963 -49.727349) (xy 181.960293 -49.711984) (xy 182.014277 -49.704222)
			(xy 182.068815 -49.704222) (xy 182.122799 -49.711984) (xy 182.175129 -49.727349) (xy 182.224739 -49.750006)
			(xy 182.27062 -49.779492) (xy 182.311837 -49.815207) (xy 182.347552 -49.856424) (xy 182.377038 -49.902305)
			(xy 182.399695 -49.951915) (xy 182.41506 -50.004245) (xy 182.422822 -50.058229) (xy 182.423308 -50.085498)
			(xy 182.423308 -50.949098) (xy 182.422822 -50.976367) (xy 182.41506 -51.030351) (xy 182.399695 -51.082681)
			(xy 182.377038 -51.132291) (xy 182.347552 -51.178172) (xy 182.311837 -51.219389) (xy 182.27062 -51.255104)
			(xy 182.224739 -51.28459) (xy 182.175129 -51.307247) (xy 182.122799 -51.322612) (xy 182.068815 -51.330374)
			(xy 182.014277 -51.330374) (xy 181.960293 -51.322612) (xy 181.907963 -51.307247) (xy 181.858353 -51.28459)
			(xy 181.812472 -51.255104) (xy 181.771255 -51.219389) (xy 181.73554 -51.178172) (xy 181.706054 -51.132291)
			(xy 181.683397 -51.082681) (xy 181.668032 -51.030351) (xy 181.66027 -50.976367) (xy 181.659784 -50.949098)
			(xy 0.509016 -50.949098) (xy 0.509016 -52.481734) (xy 178.630072 -52.481734) (xy 178.630072 -51.618134)
			(xy 178.630558 -51.590865) (xy 178.63832 -51.536881) (xy 178.653685 -51.484551) (xy 178.676342 -51.434941)
			(xy 178.705828 -51.38906) (xy 178.741543 -51.347843) (xy 178.78276 -51.312128) (xy 178.828641 -51.282642)
			(xy 178.878251 -51.259985) (xy 178.930581 -51.24462) (xy 178.984565 -51.236858) (xy 179.039103 -51.236858)
			(xy 179.093087 -51.24462) (xy 179.145417 -51.259985) (xy 179.195027 -51.282642) (xy 179.240908 -51.312128)
			(xy 179.282125 -51.347843) (xy 179.31784 -51.38906) (xy 179.347326 -51.434941) (xy 179.369983 -51.484551)
			(xy 179.385348 -51.536881) (xy 179.39311 -51.590865) (xy 179.393596 -51.618134) (xy 179.393596 -51.999896)
			(xy 201.367397 -51.999896) (xy 201.371407 -51.837793) (xy 201.38343 -51.676088) (xy 201.403434 -51.515174)
			(xy 201.431372 -51.355447) (xy 201.467175 -51.197297) (xy 201.510755 -51.041111) (xy 201.562006 -50.887271)
			(xy 201.620802 -50.736154) (xy 201.687 -50.58813) (xy 201.760436 -50.44356) (xy 201.840933 -50.302799)
			(xy 201.928292 -50.166191) (xy 202.0223 -50.034071) (xy 202.122727 -49.906761) (xy 202.229327 -49.784573)
			(xy 202.341839 -49.667807) (xy 202.459987 -49.556748) (xy 202.583484 -49.451667) (xy 202.712026 -49.352823)
			(xy 202.845299 -49.260456) (xy 202.982977 -49.174793) (xy 203.124723 -49.096044) (xy 203.27019 -49.024401)
			(xy 203.419022 -48.960039) (xy 203.570854 -48.903117) (xy 203.725316 -48.853773) (xy 203.882029 -48.812128)
			(xy 204.04061 -48.778283) (xy 204.200671 -48.752323) (xy 204.361819 -48.73431) (xy 204.523661 -48.724289)
			(xy 204.685801 -48.722283) (xy 204.847842 -48.728299) (xy 205.009386 -48.74232) (xy 205.17004 -48.764313)
			(xy 205.32941 -48.794225) (xy 205.487105 -48.831981) (xy 205.64274 -48.877489) (xy 205.795934 -48.930639)
			(xy 205.946312 -48.9913) (xy 206.093507 -49.059323) (xy 206.237157 -49.134542) (xy 206.376912 -49.216773)
			(xy 206.512428 -49.305815) (xy 206.643376 -49.40145) (xy 206.769434 -49.503444) (xy 206.890294 -49.611547)
			(xy 207.00566 -49.725494) (xy 207.115249 -49.845008) (xy 207.218794 -49.969795) (xy 207.316041 -50.09955)
			(xy 207.406753 -50.233955) (xy 207.490706 -50.372682) (xy 207.567696 -50.515391) (xy 207.637535 -50.661732)
			(xy 207.70005 -50.811349) (xy 207.755091 -50.963874) (xy 207.802521 -51.118934) (xy 207.842224 -51.27615)
			(xy 207.874105 -51.435138) (xy 207.898083 -51.595507) (xy 207.914102 -51.756866) (xy 207.922121 -51.91882)
			(xy 207.922622 -51.999896) (xy 207.922121 -52.080972) (xy 207.921092 -52.10175) (xy 244.67947 -52.10175)
			(xy 244.679975 -52.075243) (xy 244.687334 -52.022743) (xy 244.701889 -51.971767) (xy 244.723361 -51.923297)
			(xy 244.751335 -51.878265) (xy 244.785274 -51.837539) (xy 244.824523 -51.801903) (xy 244.868327 -51.772043)
			(xy 244.915843 -51.748534) (xy 244.966156 -51.731829) (xy 244.992144 -51.726592) (xy 245.000543 -51.724726)
			(xy 245.015476 -51.716197) (xy 245.026755 -51.703216) (xy 245.030244 -51.69535) (xy 245.045663 -51.657494)
			(xy 245.082559 -51.584546) (xy 245.125992 -51.515291) (xy 245.175596 -51.450313) (xy 245.230952 -51.39016)
			(xy 245.291595 -51.335341) (xy 245.357011 -51.286316) (xy 245.426649 -51.2435) (xy 245.499922 -51.207254)
			(xy 245.576211 -51.177884) (xy 245.654873 -51.155637) (xy 245.735245 -51.140701) (xy 245.816648 -51.133203)
			(xy 245.857522 -51.13274) (xy 245.899843 -51.133258) (xy 245.984099 -51.14133) (xy 246.067208 -51.157371)
			(xy 246.148416 -51.181236) (xy 246.226989 -51.212708) (xy 246.302217 -51.251503) (xy 246.33809 -51.273964)
			(xy 246.346484 -51.278827) (xy 246.365522 -51.28248) (xy 246.38456 -51.278827) (xy 246.392954 -51.273964)
			(xy 246.42883 -51.25151) (xy 246.504063 -51.212731) (xy 246.582638 -51.181268) (xy 246.663845 -51.157405)
			(xy 246.74695 -51.141356) (xy 246.831202 -51.133268) (xy 246.873522 -51.13274) (xy 246.926862 -51.134518)
			(xy 246.938638 -51.134618) (xy 246.960306 -51.125466) (xy 246.975671 -51.107657) (xy 246.979186 -51.096418)
			(xy 246.990138 -51.056039) (xy 247.018713 -50.977397) (xy 247.054545 -50.901785) (xy 247.097317 -50.829872)
			(xy 247.146653 -50.762292) (xy 247.202115 -50.699642) (xy 247.263214 -50.642477) (xy 247.329411 -50.5913)
			(xy 247.40012 -50.546564) (xy 247.474717 -50.508665) (xy 247.552542 -50.477936) (xy 247.632909 -50.45465)
			(xy 247.715107 -50.439012) (xy 247.79841 -50.431161) (xy 247.840246 -50.430684) (xy 247.883752 -50.431235)
			(xy 247.970347 -50.439729) (xy 248.055699 -50.456641) (xy 248.138991 -50.481809) (xy 248.219426 -50.514992)
			(xy 248.296235 -50.555874) (xy 248.332752 -50.579528) (xy 248.341308 -50.584744) (xy 248.360946 -50.588653)
			(xy 248.380584 -50.584744) (xy 248.38914 -50.579528) (xy 248.425663 -50.555885) (xy 248.50248 -50.515022)
			(xy 248.582916 -50.481847) (xy 248.666204 -50.456676) (xy 248.751551 -50.439749) (xy 248.838142 -50.431227)
			(xy 248.881646 -50.430684) (xy 248.926403 -50.431259) (xy 249.015462 -50.440266) (xy 249.103167 -50.458165)
			(xy 249.188634 -50.484775) (xy 249.270999 -50.519828) (xy 249.349431 -50.562968) (xy 249.386598 -50.58791)
			(xy 249.394939 -50.593062) (xy 249.414052 -50.597328) (xy 249.433374 -50.594144) (xy 249.44197 -50.589434)
			(xy 249.4758 -50.569354) (xy 249.546346 -50.534523) (xy 249.619688 -50.506051) (xy 249.695257 -50.484158)
			(xy 249.772462 -50.469016) (xy 249.850701 -50.460742) (xy 249.890026 -50.45964) (xy 249.889772 -50.4444)
			(xy 249.889772 -50.443892) (xy 249.89024 -50.405527) (xy 249.896983 -50.329093) (xy 249.903234 -50.291238)
			(xy 249.904413 -50.282319) (xy 249.901131 -50.26464) (xy 249.891952 -50.249179) (xy 249.8852 -50.243232)
			(xy 249.851748 -50.215094) (xy 249.789907 -50.153305) (xy 249.734424 -50.08575) (xy 249.685833 -50.01308)
			(xy 249.644603 -49.935995) (xy 249.61113 -49.855239) (xy 249.585738 -49.771589) (xy 249.568671 -49.685852)
			(xy 249.560094 -49.598855) (xy 249.559572 -49.555146) (xy 249.560076 -49.512785) (xy 249.568129 -49.428448)
			(xy 249.584163 -49.345258) (xy 249.608031 -49.263968) (xy 249.639519 -49.185316) (xy 249.678341 -49.110013)
			(xy 249.724144 -49.038741) (xy 249.776515 -48.972145) (xy 249.83498 -48.91083) (xy 249.899008 -48.855349)
			(xy 249.96802 -48.806206) (xy 250.04139 -48.763846) (xy 250.118455 -48.728651) (xy 250.198517 -48.700942)
			(xy 250.28085 -48.680968) (xy 250.364709 -48.668911) (xy 250.449334 -48.66488) (xy 250.533959 -48.668911)
			(xy 250.617818 -48.680968) (xy 250.700151 -48.700942) (xy 250.780213 -48.728651) (xy 250.857278 -48.763846)
			(xy 250.930648 -48.806206) (xy 250.99966 -48.855349) (xy 251.063688 -48.91083) (xy 251.122153 -48.972145)
			(xy 251.174524 -49.038741) (xy 251.220327 -49.110013) (xy 251.259149 -49.185316) (xy 251.290637 -49.263968)
			(xy 251.314505 -49.345258) (xy 251.330539 -49.428448) (xy 251.338592 -49.512785) (xy 251.339096 -49.555146)
			(xy 251.338636 -49.593574) (xy 251.331894 -49.670136) (xy 251.325634 -49.708054) (xy 251.324473 -49.716974)
			(xy 251.32775 -49.73465) (xy 251.336921 -49.750111) (xy 251.343668 -49.75606) (xy 251.362142 -49.771471)
			(xy 251.397596 -49.803999) (xy 251.414534 -49.821084) (xy 251.422676 -49.828571) (xy 251.443355 -49.836348)
			(xy 251.454412 -49.83607) (xy 251.469822 -49.835031) (xy 251.50069 -49.833886) (xy 251.516134 -49.833784)
			(xy 251.557251 -49.834166) (xy 251.639133 -49.841757) (xy 251.719966 -49.85687) (xy 251.79906 -49.879378)
			(xy 251.875739 -49.909087) (xy 251.94935 -49.945745) (xy 252.019265 -49.989039) (xy 252.084886 -50.038598)
			(xy 252.145655 -50.094001) (xy 252.201053 -50.154775) (xy 252.250607 -50.220401) (xy 252.293894 -50.29032)
			(xy 252.330545 -50.363934) (xy 252.360248 -50.440616) (xy 252.382748 -50.519712) (xy 252.397854 -50.600546)
			(xy 252.405438 -50.682429) (xy 252.405896 -50.723546) (xy 252.405358 -50.767341) (xy 252.396743 -50.854506)
			(xy 252.379599 -50.940401) (xy 252.354094 -51.024196) (xy 252.320474 -51.105076) (xy 252.300232 -51.143916)
			(xy 252.29478 -51.15537) (xy 252.2948 -51.18071) (xy 252.300232 -51.192176) (xy 252.320452 -51.231026)
			(xy 252.354062 -51.311909) (xy 252.379567 -51.3957) (xy 252.39672 -51.481592) (xy 252.405355 -51.568752)
			(xy 252.405896 -51.612546) (xy 252.405358 -51.656341) (xy 252.396743 -51.743506) (xy 252.379599 -51.829401)
			(xy 252.354094 -51.913196) (xy 252.320474 -51.994076) (xy 252.317441 -51.999896) (xy 265.367523 -51.999896)
			(xy 265.371533 -51.837793) (xy 265.383556 -51.676088) (xy 265.40356 -51.515174) (xy 265.431498 -51.355447)
			(xy 265.467301 -51.197297) (xy 265.510881 -51.041111) (xy 265.562132 -50.887271) (xy 265.620928 -50.736154)
			(xy 265.687126 -50.58813) (xy 265.760562 -50.44356) (xy 265.841059 -50.302799) (xy 265.928418 -50.166191)
			(xy 266.022426 -50.034071) (xy 266.122853 -49.906761) (xy 266.229453 -49.784573) (xy 266.341965 -49.667807)
			(xy 266.460113 -49.556748) (xy 266.58361 -49.451667) (xy 266.712152 -49.352823) (xy 266.845425 -49.260456)
			(xy 266.983103 -49.174793) (xy 267.124849 -49.096044) (xy 267.270316 -49.024401) (xy 267.419148 -48.960039)
			(xy 267.57098 -48.903117) (xy 267.725442 -48.853773) (xy 267.882155 -48.812128) (xy 268.040736 -48.778283)
			(xy 268.200797 -48.752323) (xy 268.361945 -48.73431) (xy 268.523787 -48.724289) (xy 268.685927 -48.722283)
			(xy 268.847968 -48.728299) (xy 269.009512 -48.74232) (xy 269.170166 -48.764313) (xy 269.329536 -48.794225)
			(xy 269.487231 -48.831981) (xy 269.642866 -48.877489) (xy 269.79606 -48.930639) (xy 269.946438 -48.9913)
			(xy 270.093633 -49.059323) (xy 270.237283 -49.134542) (xy 270.377038 -49.216773) (xy 270.512554 -49.305815)
			(xy 270.643502 -49.40145) (xy 270.76956 -49.503444) (xy 270.89042 -49.611547) (xy 271.005786 -49.725494)
			(xy 271.115375 -49.845008) (xy 271.21892 -49.969795) (xy 271.316167 -50.09955) (xy 271.406879 -50.233955)
			(xy 271.490832 -50.372682) (xy 271.567822 -50.515391) (xy 271.637661 -50.661732) (xy 271.700176 -50.811349)
			(xy 271.755217 -50.963874) (xy 271.802647 -51.118934) (xy 271.84235 -51.27615) (xy 271.874231 -51.435138)
			(xy 271.898209 -51.595507) (xy 271.914228 -51.756866) (xy 271.922247 -51.91882) (xy 271.922748 -51.999896)
			(xy 271.922247 -52.080972) (xy 271.914228 -52.242926) (xy 271.898209 -52.404285) (xy 271.874231 -52.564654)
			(xy 271.84235 -52.723642) (xy 271.802647 -52.880858) (xy 271.755217 -53.035918) (xy 271.700176 -53.188443)
			(xy 271.637661 -53.33806) (xy 271.567822 -53.484401) (xy 271.490832 -53.62711) (xy 271.406879 -53.765837)
			(xy 271.316167 -53.900242) (xy 271.21892 -54.029997) (xy 271.115375 -54.154784) (xy 271.005786 -54.274298)
			(xy 270.89042 -54.388245) (xy 270.76956 -54.496348) (xy 270.643502 -54.598342) (xy 270.512554 -54.693977)
			(xy 270.377038 -54.783019) (xy 270.237283 -54.86525) (xy 270.093633 -54.940469) (xy 269.946438 -55.008492)
			(xy 269.79606 -55.069153) (xy 269.642866 -55.122303) (xy 269.487231 -55.167811) (xy 269.329536 -55.205567)
			(xy 269.170166 -55.235479) (xy 269.009512 -55.257472) (xy 268.847968 -55.271493) (xy 268.685927 -55.277509)
			(xy 268.523787 -55.275503) (xy 268.361945 -55.265482) (xy 268.200797 -55.247469) (xy 268.040736 -55.221509)
			(xy 267.882155 -55.187664) (xy 267.725442 -55.146019) (xy 267.57098 -55.096675) (xy 267.419148 -55.039753)
			(xy 267.270316 -54.975391) (xy 267.124849 -54.903748) (xy 266.983103 -54.824999) (xy 266.845425 -54.739336)
			(xy 266.712152 -54.646969) (xy 266.58361 -54.548125) (xy 266.460113 -54.443044) (xy 266.341965 -54.331985)
			(xy 266.229453 -54.215219) (xy 266.122853 -54.093031) (xy 266.022426 -53.965721) (xy 265.928418 -53.833601)
			(xy 265.841059 -53.696993) (xy 265.760562 -53.556232) (xy 265.687126 -53.411662) (xy 265.620928 -53.263638)
			(xy 265.562132 -53.112521) (xy 265.510881 -52.958681) (xy 265.467301 -52.802495) (xy 265.431498 -52.644345)
			(xy 265.40356 -52.484618) (xy 265.383556 -52.323704) (xy 265.371533 -52.161999) (xy 265.367523 -51.999896)
			(xy 252.317441 -51.999896) (xy 252.300232 -52.032916) (xy 252.29478 -52.04437) (xy 252.2948 -52.06971)
			(xy 252.300232 -52.081176) (xy 252.320452 -52.120026) (xy 252.354062 -52.200909) (xy 252.379567 -52.2847)
			(xy 252.39672 -52.370592) (xy 252.405355 -52.457752) (xy 252.405896 -52.501546) (xy 252.405431 -52.54266)
			(xy 252.39784 -52.624537) (xy 252.382728 -52.705364) (xy 252.360222 -52.784452) (xy 252.330515 -52.861127)
			(xy 252.293861 -52.934733) (xy 252.250573 -53.004644) (xy 252.201018 -53.070263) (xy 252.145621 -53.131029)
			(xy 252.084853 -53.186426) (xy 252.019234 -53.235979) (xy 251.949323 -53.279267) (xy 251.875716 -53.31592)
			(xy 251.799041 -53.345626) (xy 251.719952 -53.36813) (xy 251.639125 -53.383242) (xy 251.557248 -53.390832)
			(xy 251.516134 -53.391308) (xy 251.471924 -53.390745) (xy 251.383942 -53.381965) (xy 251.297264 -53.3645)
			(xy 251.212747 -53.33852) (xy 251.131225 -53.304282) (xy 251.053503 -53.262125) (xy 250.980346 -53.212465)
			(xy 250.912478 -53.15579) (xy 250.881134 -53.124608) (xy 250.873005 -53.117104) (xy 250.852316 -53.109337)
			(xy 250.841256 -53.109622) (xy 250.825846 -53.110663) (xy 250.794978 -53.111806) (xy 250.779534 -53.111908)
			(xy 250.737779 -53.111492) (xy 250.654637 -53.103677) (xy 250.572592 -53.088104) (xy 250.492369 -53.064909)
			(xy 250.414673 -53.034297) (xy 250.340188 -52.996537) (xy 250.269571 -52.951961) (xy 250.203442 -52.900963)
			(xy 250.142385 -52.843991) (xy 250.086937 -52.781547) (xy 250.037585 -52.714181) (xy 249.994765 -52.642486)
			(xy 249.958854 -52.567092) (xy 249.930167 -52.488665) (xy 249.908958 -52.407894) (xy 249.895413 -52.32549)
			(xy 249.892058 -52.283868) (xy 249.891061 -52.274773) (xy 249.88348 -52.258135) (xy 249.870549 -52.245209)
			(xy 249.853908 -52.237634) (xy 249.844814 -52.236624) (xy 249.805225 -52.23352) (xy 249.726783 -52.221122)
			(xy 249.649759 -52.201775) (xy 249.574769 -52.175634) (xy 249.50241 -52.142907) (xy 249.433259 -52.103855)
			(xy 249.400314 -52.081684) (xy 249.392012 -52.076461) (xy 249.372875 -52.072218) (xy 249.353539 -52.075433)
			(xy 249.344942 -52.08016) (xy 249.312459 -52.099495) (xy 249.244799 -52.133223) (xy 249.174522 -52.161088)
			(xy 249.13844 -52.172362) (xy 249.128616 -52.175851) (xy 249.112727 -52.189319) (xy 249.103444 -52.207965)
			(xy 249.102372 -52.218336) (xy 249.099675 -52.260463) (xy 249.087279 -52.34397) (xy 249.067027 -52.425926)
			(xy 249.039099 -52.505595) (xy 249.003748 -52.582258) (xy 248.961291 -52.655227) (xy 248.912112 -52.723845)
			(xy 248.856651 -52.787493) (xy 248.795409 -52.8456) (xy 248.728936 -52.897642) (xy 248.657831 -52.943151)
			(xy 248.582733 -52.981717) (xy 248.504319 -53.012994) (xy 248.423294 -53.036699) (xy 248.340387 -53.052621)
			(xy 248.256345 -53.060614) (xy 248.214134 -53.061108) (xy 248.171669 -53.060607) (xy 248.087125 -53.052507)
			(xy 248.003739 -53.036385) (xy 247.922268 -53.01239) (xy 247.843456 -52.98074) (xy 247.768018 -52.941722)
			(xy 247.696643 -52.895693) (xy 247.629979 -52.84307) (xy 247.568634 -52.784334) (xy 247.540526 -52.752498)
			(xy 247.534176 -52.745132) (xy 247.517412 -52.736496) (xy 247.429274 -52.726336) (xy 247.410986 -52.731416)
			(xy 247.403112 -52.737258) (xy 247.370277 -52.761024) (xy 247.301045 -52.803187) (xy 247.228263 -52.838875)
			(xy 247.152535 -52.867791) (xy 247.07449 -52.889697) (xy 246.994775 -52.904409) (xy 246.914052 -52.911805)
			(xy 246.873522 -52.912264) (xy 246.831202 -52.911724) (xy 246.746946 -52.903656) (xy 246.663838 -52.887619)
			(xy 246.58263 -52.863758) (xy 246.504056 -52.83229) (xy 246.428827 -52.793499) (xy 246.392954 -52.77104)
			(xy 246.38456 -52.766177) (xy 246.365522 -52.762524) (xy 246.346484 -52.766177) (xy 246.33809 -52.77104)
			(xy 246.302222 -52.793507) (xy 246.226987 -52.832285) (xy 246.148411 -52.863747) (xy 246.067203 -52.887609)
			(xy 245.984096 -52.903654) (xy 245.899842 -52.911738) (xy 245.857522 -52.912264) (xy 245.813221 -52.911666)
			(xy 245.725058 -52.90285) (xy 245.638208 -52.885314) (xy 245.553531 -52.85923) (xy 245.471867 -52.824858)
			(xy 245.394025 -52.782538) (xy 245.320775 -52.732689) (xy 245.252843 -52.675806) (xy 245.190903 -52.61245)
			(xy 245.135568 -52.543252) (xy 245.111016 -52.506372) (xy 245.106055 -52.499361) (xy 245.092457 -52.488884)
			(xy 245.076169 -52.483465) (xy 245.067582 -52.483258) (xy 245.060978 -52.483258) (xy 245.033722 -52.482865)
			(xy 244.979766 -52.475104) (xy 244.927464 -52.459743) (xy 244.87788 -52.437094) (xy 244.832025 -52.407619)
			(xy 244.790831 -52.371918) (xy 244.755138 -52.330717) (xy 244.725671 -52.284856) (xy 244.703032 -52.235269)
			(xy 244.68768 -52.182963) (xy 244.679929 -52.129006) (xy 244.67947 -52.10175) (xy 207.921092 -52.10175)
			(xy 207.914102 -52.242926) (xy 207.898083 -52.404285) (xy 207.874105 -52.564654) (xy 207.842224 -52.723642)
			(xy 207.802521 -52.880858) (xy 207.755091 -53.035918) (xy 207.70005 -53.188443) (xy 207.637535 -53.33806)
			(xy 207.567696 -53.484401) (xy 207.490706 -53.62711) (xy 207.406753 -53.765837) (xy 207.316041 -53.900242)
			(xy 207.218794 -54.029997) (xy 207.115249 -54.154784) (xy 207.00566 -54.274298) (xy 206.890294 -54.388245)
			(xy 206.769434 -54.496348) (xy 206.643376 -54.598342) (xy 206.512428 -54.693977) (xy 206.376912 -54.783019)
			(xy 206.237157 -54.86525) (xy 206.093507 -54.940469) (xy 205.946312 -55.008492) (xy 205.795934 -55.069153)
			(xy 205.64274 -55.122303) (xy 205.487105 -55.167811) (xy 205.32941 -55.205567) (xy 205.17004 -55.235479)
			(xy 205.009386 -55.257472) (xy 204.847842 -55.271493) (xy 204.685801 -55.277509) (xy 204.523661 -55.275503)
			(xy 204.361819 -55.265482) (xy 204.200671 -55.247469) (xy 204.04061 -55.221509) (xy 203.882029 -55.187664)
			(xy 203.725316 -55.146019) (xy 203.570854 -55.096675) (xy 203.419022 -55.039753) (xy 203.27019 -54.975391)
			(xy 203.124723 -54.903748) (xy 202.982977 -54.824999) (xy 202.845299 -54.739336) (xy 202.712026 -54.646969)
			(xy 202.583484 -54.548125) (xy 202.459987 -54.443044) (xy 202.341839 -54.331985) (xy 202.229327 -54.215219)
			(xy 202.122727 -54.093031) (xy 202.0223 -53.965721) (xy 201.928292 -53.833601) (xy 201.840933 -53.696993)
			(xy 201.760436 -53.556232) (xy 201.687 -53.411662) (xy 201.620802 -53.263638) (xy 201.562006 -53.112521)
			(xy 201.510755 -52.958681) (xy 201.467175 -52.802495) (xy 201.431372 -52.644345) (xy 201.403434 -52.484618)
			(xy 201.38343 -52.323704) (xy 201.371407 -52.161999) (xy 201.367397 -51.999896) (xy 179.393596 -51.999896)
			(xy 179.393596 -52.481734) (xy 179.39311 -52.509003) (xy 179.385348 -52.562987) (xy 179.369983 -52.615317)
			(xy 179.347326 -52.664927) (xy 179.31784 -52.710808) (xy 179.282125 -52.752025) (xy 179.240908 -52.78774)
			(xy 179.195027 -52.817226) (xy 179.145417 -52.839883) (xy 179.093087 -52.855248) (xy 179.039103 -52.86301)
			(xy 178.984565 -52.86301) (xy 178.930581 -52.855248) (xy 178.878251 -52.839883) (xy 178.828641 -52.817226)
			(xy 178.78276 -52.78774) (xy 178.741543 -52.752025) (xy 178.705828 -52.710808) (xy 178.676342 -52.664927)
			(xy 178.653685 -52.615317) (xy 178.63832 -52.562987) (xy 178.630558 -52.509003) (xy 178.630072 -52.481734)
			(xy 0.509016 -52.481734) (xy 0.509016 -53.954934) (xy 181.659784 -53.954934) (xy 181.659784 -53.091334)
			(xy 181.66027 -53.064065) (xy 181.668032 -53.010081) (xy 181.683397 -52.957751) (xy 181.706054 -52.908141)
			(xy 181.73554 -52.86226) (xy 181.771255 -52.821043) (xy 181.812472 -52.785328) (xy 181.858353 -52.755842)
			(xy 181.907963 -52.733185) (xy 181.960293 -52.71782) (xy 182.014277 -52.710058) (xy 182.068815 -52.710058)
			(xy 182.122799 -52.71782) (xy 182.175129 -52.733185) (xy 182.224739 -52.755842) (xy 182.27062 -52.785328)
			(xy 182.311837 -52.821043) (xy 182.347552 -52.86226) (xy 182.377038 -52.908141) (xy 182.399695 -52.957751)
			(xy 182.41506 -53.010081) (xy 182.422822 -53.064065) (xy 182.423308 -53.091334) (xy 182.423308 -53.954934)
			(xy 182.422822 -53.982203) (xy 182.41506 -54.036187) (xy 182.399695 -54.088517) (xy 182.377038 -54.138127)
			(xy 182.347552 -54.184008) (xy 182.311837 -54.225225) (xy 182.27062 -54.26094) (xy 182.224739 -54.290426)
			(xy 182.175129 -54.313083) (xy 182.122799 -54.328448) (xy 182.068815 -54.33621) (xy 182.014277 -54.33621)
			(xy 181.960293 -54.328448) (xy 181.907963 -54.313083) (xy 181.858353 -54.290426) (xy 181.812472 -54.26094)
			(xy 181.771255 -54.225225) (xy 181.73554 -54.184008) (xy 181.706054 -54.138127) (xy 181.683397 -54.088517)
			(xy 181.668032 -54.036187) (xy 181.66027 -53.982203) (xy 181.659784 -53.954934) (xy 0.509016 -53.954934)
			(xy 0.509016 -55.481728) (xy 178.630072 -55.481728) (xy 178.630072 -54.618128) (xy 178.630558 -54.590859)
			(xy 178.63832 -54.536875) (xy 178.653685 -54.484545) (xy 178.676342 -54.434935) (xy 178.705828 -54.389054)
			(xy 178.741543 -54.347837) (xy 178.78276 -54.312122) (xy 178.828641 -54.282636) (xy 178.878251 -54.259979)
			(xy 178.930581 -54.244614) (xy 178.984565 -54.236852) (xy 179.039103 -54.236852) (xy 179.093087 -54.244614)
			(xy 179.145417 -54.259979) (xy 179.195027 -54.282636) (xy 179.240908 -54.312122) (xy 179.282125 -54.347837)
			(xy 179.31784 -54.389054) (xy 179.347326 -54.434935) (xy 179.369983 -54.484545) (xy 179.385348 -54.536875)
			(xy 179.39311 -54.590859) (xy 179.393596 -54.618128) (xy 179.393596 -55.481728) (xy 179.39311 -55.508997)
			(xy 179.385348 -55.562981) (xy 179.369983 -55.615311) (xy 179.347326 -55.664921) (xy 179.31784 -55.710802)
			(xy 179.282125 -55.752019) (xy 179.240908 -55.787734) (xy 179.195027 -55.81722) (xy 179.145417 -55.839877)
			(xy 179.093087 -55.855242) (xy 179.039103 -55.863004) (xy 178.984565 -55.863004) (xy 178.930581 -55.855242)
			(xy 178.878251 -55.839877) (xy 178.828641 -55.81722) (xy 178.78276 -55.787734) (xy 178.741543 -55.752019)
			(xy 178.705828 -55.710802) (xy 178.676342 -55.664921) (xy 178.653685 -55.615311) (xy 178.63832 -55.562981)
			(xy 178.630558 -55.508997) (xy 178.630072 -55.481728) (xy 0.509016 -55.481728) (xy 0.509016 -57.094435)
			(xy 170.842169 -57.094435) (xy 170.842169 -57.005413) (xy 170.850149 -56.916749) (xy 170.866045 -56.829158)
			(xy 170.889728 -56.743343) (xy 170.921008 -56.659998) (xy 170.959634 -56.579792) (xy 171.005293 -56.503371)
			(xy 171.057619 -56.43135) (xy 171.11619 -56.36431) (xy 171.180535 -56.30279) (xy 171.250135 -56.247286)
			(xy 171.324431 -56.198244) (xy 171.402823 -56.156059) (xy 171.484682 -56.121071) (xy 171.569347 -56.093562)
			(xy 171.656137 -56.073752) (xy 171.744353 -56.061802) (xy 171.833286 -56.057809) (xy 171.922219 -56.061802)
			(xy 172.010435 -56.073752) (xy 172.097225 -56.093562) (xy 172.18189 -56.121071) (xy 172.263749 -56.156059)
			(xy 172.342141 -56.198244) (xy 172.416437 -56.247286) (xy 172.486037 -56.30279) (xy 172.550382 -56.36431)
			(xy 172.608953 -56.43135) (xy 172.661279 -56.503371) (xy 172.706938 -56.579792) (xy 172.745564 -56.659998)
			(xy 172.776844 -56.743343) (xy 172.800527 -56.829158) (xy 172.816423 -56.916749) (xy 172.824403 -57.005413)
			(xy 172.824902 -57.049924) (xy 172.824403 -57.094435) (xy 172.816423 -57.183099) (xy 172.800527 -57.27069)
			(xy 172.776844 -57.356505) (xy 172.745564 -57.43985) (xy 172.706938 -57.520056) (xy 172.661279 -57.596477)
			(xy 172.608953 -57.668498) (xy 172.550382 -57.735538) (xy 172.486037 -57.797058) (xy 172.416437 -57.852562)
			(xy 172.342141 -57.901604) (xy 172.263749 -57.943789) (xy 172.18189 -57.978777) (xy 172.097225 -58.006286)
			(xy 172.010435 -58.026096) (xy 171.922219 -58.038046) (xy 171.833286 -58.04204) (xy 171.744353 -58.038046)
			(xy 171.656137 -58.026096) (xy 171.569347 -58.006286) (xy 171.484682 -57.978777) (xy 171.402823 -57.943789)
			(xy 171.324431 -57.901604) (xy 171.250135 -57.852562) (xy 171.180535 -57.797058) (xy 171.11619 -57.735538)
			(xy 171.057619 -57.668498) (xy 171.005293 -57.596477) (xy 170.959634 -57.520056) (xy 170.921008 -57.43985)
			(xy 170.889728 -57.356505) (xy 170.866045 -57.27069) (xy 170.850149 -57.183099) (xy 170.842169 -57.094435)
			(xy 0.509016 -57.094435) (xy 0.509016 -60.375038) (xy 233.333297 -60.375038) (xy 233.337302 -60.28713)
			(xy 233.349285 -60.19995) (xy 233.369145 -60.114221) (xy 233.39672 -60.030653) (xy 233.431779 -59.949939)
			(xy 233.474032 -59.872747) (xy 233.52313 -59.799718) (xy 233.578666 -59.731456) (xy 233.640178 -59.668526)
			(xy 233.707159 -59.611452) (xy 233.779052 -59.560704) (xy 233.855261 -59.516704) (xy 233.935156 -59.479817)
			(xy 234.018075 -59.450348) (xy 234.10333 -59.428541) (xy 234.190214 -59.414577) (xy 234.278008 -59.408571)
			(xy 234.365985 -59.410575) (xy 234.453415 -59.42057) (xy 234.539574 -59.438474) (xy 234.623748 -59.464138)
			(xy 234.705239 -59.497351) (xy 234.783373 -59.537837) (xy 234.857501 -59.585259) (xy 234.927009 -59.639226)
			(xy 234.991323 -59.699291) (xy 235.049907 -59.764955) (xy 235.102278 -59.835674) (xy 235.148001 -59.910862)
			(xy 235.186698 -59.989897) (xy 235.218047 -60.072123) (xy 235.241789 -60.156859) (xy 235.257727 -60.243403)
			(xy 235.265729 -60.331038) (xy 235.26623 -60.375038) (xy 235.265729 -60.419038) (xy 235.257727 -60.506673)
			(xy 235.241789 -60.593217) (xy 235.218047 -60.677953) (xy 235.186698 -60.760179) (xy 235.148001 -60.839214)
			(xy 235.102278 -60.914402) (xy 235.049907 -60.985121) (xy 234.991323 -61.050785) (xy 234.927009 -61.11085)
			(xy 234.857501 -61.164817) (xy 234.783373 -61.212239) (xy 234.705239 -61.252725) (xy 234.623748 -61.285938)
			(xy 234.539574 -61.311602) (xy 234.453415 -61.329506) (xy 234.365985 -61.339501) (xy 234.278008 -61.341505)
			(xy 234.190214 -61.335499) (xy 234.10333 -61.321535) (xy 234.018075 -61.299728) (xy 233.935156 -61.270259)
			(xy 233.855261 -61.233372) (xy 233.779052 -61.189372) (xy 233.707159 -61.138624) (xy 233.640178 -61.08155)
			(xy 233.578666 -61.01862) (xy 233.52313 -60.950358) (xy 233.474032 -60.877329) (xy 233.431779 -60.800137)
			(xy 233.39672 -60.719423) (xy 233.369145 -60.635855) (xy 233.349285 -60.550126) (xy 233.337302 -60.462946)
			(xy 233.333297 -60.375038) (xy 0.509016 -60.375038) (xy 0.509016 -74.760836) (xy 39.554404 -74.760836)
			(xy 39.554404 -66.060828) (xy 39.554909 -65.955304) (xy 39.562993 -65.74441) (xy 39.579149 -65.533981)
			(xy 39.603352 -65.324324) (xy 39.635569 -65.115749) (xy 39.675751 -64.908561) (xy 39.723839 -64.703064)
			(xy 39.779763 -64.49956) (xy 39.84344 -64.298347) (xy 39.914778 -64.09972) (xy 39.993672 -63.903972)
			(xy 40.080005 -63.71139) (xy 40.173652 -63.522255) (xy 40.274474 -63.336846) (xy 40.382324 -63.155435)
			(xy 40.497043 -62.978288) (xy 40.618463 -62.805666) (xy 40.746406 -62.63782) (xy 40.880684 -62.474998)
			(xy 41.0211 -62.317439) (xy 41.167448 -62.165374) (xy 41.319513 -62.019026) (xy 41.477072 -61.87861)
			(xy 41.639894 -61.744332) (xy 41.80774 -61.616389) (xy 41.980362 -61.494969) (xy 42.157509 -61.38025)
			(xy 42.33892 -61.2724) (xy 42.524329 -61.171578) (xy 42.713464 -61.077931) (xy 42.906046 -60.991598)
			(xy 43.101794 -60.912704) (xy 43.300421 -60.841366) (xy 43.501634 -60.777689) (xy 43.705138 -60.721765)
			(xy 43.910635 -60.673677) (xy 44.117823 -60.633495) (xy 44.326398 -60.601278) (xy 44.536055 -60.577075)
			(xy 44.746484 -60.560919) (xy 44.957378 -60.552835) (xy 45.168426 -60.552835) (xy 45.37932 -60.560919)
			(xy 45.589749 -60.577075) (xy 45.799406 -60.601278) (xy 46.007981 -60.633495) (xy 46.215169 -60.673677)
			(xy 46.420666 -60.721765) (xy 46.62417 -60.777689) (xy 46.825383 -60.841366) (xy 47.02401 -60.912704)
			(xy 47.219758 -60.991598) (xy 47.41234 -61.077931) (xy 47.601475 -61.171578) (xy 47.786884 -61.2724)
			(xy 47.968295 -61.38025) (xy 48.145442 -61.494969) (xy 48.318064 -61.616389) (xy 48.48591 -61.744332)
			(xy 48.648732 -61.87861) (xy 48.806291 -62.019026) (xy 48.958356 -62.165374) (xy 49.104704 -62.317439)
			(xy 49.24512 -62.474998) (xy 49.379398 -62.63782) (xy 49.507341 -62.805666) (xy 49.628761 -62.978288)
			(xy 49.74348 -63.155435) (xy 49.85133 -63.336846) (xy 49.952152 -63.522255) (xy 50.045799 -63.71139)
			(xy 50.132132 -63.903972) (xy 50.211026 -64.09972) (xy 50.282364 -64.298347) (xy 50.346041 -64.49956)
			(xy 50.401965 -64.703064) (xy 50.450053 -64.908561) (xy 50.490235 -65.115749) (xy 50.522452 -65.324324)
			(xy 50.546655 -65.533981) (xy 50.562811 -65.74441) (xy 50.570895 -65.955304) (xy 50.5714 -66.060828)
			(xy 50.5714 -74.760836) (xy 50.571366 -74.767948) (xy 173.354492 -74.767948) (xy 173.354492 -66.06794)
			(xy 173.354997 -65.962416) (xy 173.363081 -65.751522) (xy 173.379237 -65.541093) (xy 173.40344 -65.331436)
			(xy 173.435657 -65.122861) (xy 173.475839 -64.915673) (xy 173.523927 -64.710176) (xy 173.579851 -64.506672)
			(xy 173.643528 -64.305459) (xy 173.714866 -64.106832) (xy 173.79376 -63.911084) (xy 173.880093 -63.718502)
			(xy 173.97374 -63.529367) (xy 174.074562 -63.343958) (xy 174.182412 -63.162547) (xy 174.297131 -62.9854)
			(xy 174.418551 -62.812778) (xy 174.546494 -62.644932) (xy 174.680772 -62.48211) (xy 174.821188 -62.324551)
			(xy 174.967536 -62.172486) (xy 175.119601 -62.026138) (xy 175.27716 -61.885722) (xy 175.439982 -61.751444)
			(xy 175.607828 -61.623501) (xy 175.78045 -61.502081) (xy 175.957597 -61.387362) (xy 176.139008 -61.279512)
			(xy 176.324417 -61.17869) (xy 176.513552 -61.085043) (xy 176.706134 -60.99871) (xy 176.901882 -60.919816)
			(xy 177.100509 -60.848478) (xy 177.301722 -60.784801) (xy 177.505226 -60.728877) (xy 177.710723 -60.680789)
			(xy 177.917911 -60.640607) (xy 178.126486 -60.60839) (xy 178.336143 -60.584187) (xy 178.546572 -60.568031)
			(xy 178.757466 -60.559947) (xy 178.968514 -60.559947) (xy 179.179408 -60.568031) (xy 179.389837 -60.584187)
			(xy 179.599494 -60.60839) (xy 179.808069 -60.640607) (xy 180.015257 -60.680789) (xy 180.220754 -60.728877)
			(xy 180.424258 -60.784801) (xy 180.625471 -60.848478) (xy 180.824098 -60.919816) (xy 181.019846 -60.99871)
			(xy 181.212428 -61.085043) (xy 181.401563 -61.17869) (xy 181.586972 -61.279512) (xy 181.768383 -61.387362)
			(xy 181.94553 -61.502081) (xy 182.118152 -61.623501) (xy 182.285998 -61.751444) (xy 182.44882 -61.885722)
			(xy 182.606379 -62.026138) (xy 182.758444 -62.172486) (xy 182.904792 -62.324551) (xy 183.045208 -62.48211)
			(xy 183.179486 -62.644932) (xy 183.307429 -62.812778) (xy 183.428849 -62.9854) (xy 183.543568 -63.162547)
			(xy 183.651418 -63.343958) (xy 183.75224 -63.529367) (xy 183.845887 -63.718502) (xy 183.93222 -63.911084)
			(xy 184.011114 -64.106832) (xy 184.082452 -64.305459) (xy 184.146129 -64.506672) (xy 184.202053 -64.710176)
			(xy 184.250141 -64.915673) (xy 184.290323 -65.122861) (xy 184.32254 -65.331436) (xy 184.346743 -65.541093)
			(xy 184.362899 -65.751522) (xy 184.370983 -65.962416) (xy 184.371488 -66.06794) (xy 184.371488 -74.760836)
			(xy 287.494472 -74.760836) (xy 287.494472 -66.060828) (xy 287.494977 -65.955304) (xy 287.503061 -65.74441)
			(xy 287.519217 -65.533981) (xy 287.54342 -65.324324) (xy 287.575637 -65.115749) (xy 287.615819 -64.908561)
			(xy 287.663907 -64.703064) (xy 287.719831 -64.49956) (xy 287.783508 -64.298347) (xy 287.854846 -64.09972)
			(xy 287.93374 -63.903972) (xy 288.020073 -63.71139) (xy 288.11372 -63.522255) (xy 288.214542 -63.336846)
			(xy 288.322392 -63.155435) (xy 288.437111 -62.978288) (xy 288.558531 -62.805666) (xy 288.686474 -62.63782)
			(xy 288.820752 -62.474998) (xy 288.961168 -62.317439) (xy 289.107516 -62.165374) (xy 289.259581 -62.019026)
			(xy 289.41714 -61.87861) (xy 289.579962 -61.744332) (xy 289.747808 -61.616389) (xy 289.92043 -61.494969)
			(xy 290.097577 -61.38025) (xy 290.278988 -61.2724) (xy 290.464397 -61.171578) (xy 290.653532 -61.077931)
			(xy 290.846114 -60.991598) (xy 291.041862 -60.912704) (xy 291.240489 -60.841366) (xy 291.441702 -60.777689)
			(xy 291.645206 -60.721765) (xy 291.850703 -60.673677) (xy 292.057891 -60.633495) (xy 292.266466 -60.601278)
			(xy 292.476123 -60.577075) (xy 292.686552 -60.560919) (xy 292.897446 -60.552835) (xy 293.108494 -60.552835)
			(xy 293.319388 -60.560919) (xy 293.529817 -60.577075) (xy 293.739474 -60.601278) (xy 293.948049 -60.633495)
			(xy 294.155237 -60.673677) (xy 294.360734 -60.721765) (xy 294.564238 -60.777689) (xy 294.765451 -60.841366)
			(xy 294.964078 -60.912704) (xy 295.159826 -60.991598) (xy 295.352408 -61.077931) (xy 295.541543 -61.171578)
			(xy 295.726952 -61.2724) (xy 295.908363 -61.38025) (xy 296.08551 -61.494969) (xy 296.258132 -61.616389)
			(xy 296.425978 -61.744332) (xy 296.5888 -61.87861) (xy 296.746359 -62.019026) (xy 296.898424 -62.165374)
			(xy 297.044772 -62.317439) (xy 297.185188 -62.474998) (xy 297.319466 -62.63782) (xy 297.447409 -62.805666)
			(xy 297.568829 -62.978288) (xy 297.683548 -63.155435) (xy 297.791398 -63.336846) (xy 297.89222 -63.522255)
			(xy 297.985867 -63.71139) (xy 298.0722 -63.903972) (xy 298.151094 -64.09972) (xy 298.222432 -64.298347)
			(xy 298.286109 -64.49956) (xy 298.342033 -64.703064) (xy 298.390121 -64.908561) (xy 298.430303 -65.115749)
			(xy 298.46252 -65.324324) (xy 298.486723 -65.533981) (xy 298.502879 -65.74441) (xy 298.510963 -65.955304)
			(xy 298.511468 -66.060828) (xy 298.511468 -74.760836) (xy 298.511434 -74.767948) (xy 421.29456 -74.767948)
			(xy 421.29456 -66.06794) (xy 421.295065 -65.962416) (xy 421.303149 -65.751522) (xy 421.319305 -65.541093)
			(xy 421.343508 -65.331436) (xy 421.375725 -65.122861) (xy 421.415907 -64.915673) (xy 421.463995 -64.710176)
			(xy 421.519919 -64.506672) (xy 421.583596 -64.305459) (xy 421.654934 -64.106832) (xy 421.733828 -63.911084)
			(xy 421.820161 -63.718502) (xy 421.913808 -63.529367) (xy 422.01463 -63.343958) (xy 422.12248 -63.162547)
			(xy 422.237199 -62.9854) (xy 422.358619 -62.812778) (xy 422.486562 -62.644932) (xy 422.62084 -62.48211)
			(xy 422.761256 -62.324551) (xy 422.907604 -62.172486) (xy 423.059669 -62.026138) (xy 423.217228 -61.885722)
			(xy 423.38005 -61.751444) (xy 423.547896 -61.623501) (xy 423.720518 -61.502081) (xy 423.897665 -61.387362)
			(xy 424.079076 -61.279512) (xy 424.264485 -61.17869) (xy 424.45362 -61.085043) (xy 424.646202 -60.99871)
			(xy 424.84195 -60.919816) (xy 425.040577 -60.848478) (xy 425.24179 -60.784801) (xy 425.445294 -60.728877)
			(xy 425.650791 -60.680789) (xy 425.857979 -60.640607) (xy 426.066554 -60.60839) (xy 426.276211 -60.584187)
			(xy 426.48664 -60.568031) (xy 426.697534 -60.559947) (xy 426.908582 -60.559947) (xy 427.119476 -60.568031)
			(xy 427.329905 -60.584187) (xy 427.539562 -60.60839) (xy 427.748137 -60.640607) (xy 427.955325 -60.680789)
			(xy 428.160822 -60.728877) (xy 428.364326 -60.784801) (xy 428.565539 -60.848478) (xy 428.764166 -60.919816)
			(xy 428.959914 -60.99871) (xy 429.152496 -61.085043) (xy 429.341631 -61.17869) (xy 429.52704 -61.279512)
			(xy 429.708451 -61.387362) (xy 429.885598 -61.502081) (xy 430.05822 -61.623501) (xy 430.226066 -61.751444)
			(xy 430.388888 -61.885722) (xy 430.546447 -62.026138) (xy 430.698512 -62.172486) (xy 430.84486 -62.324551)
			(xy 430.985276 -62.48211) (xy 431.119554 -62.644932) (xy 431.247497 -62.812778) (xy 431.368917 -62.9854)
			(xy 431.483636 -63.162547) (xy 431.591486 -63.343958) (xy 431.692308 -63.529367) (xy 431.785955 -63.718502)
			(xy 431.872288 -63.911084) (xy 431.951182 -64.106832) (xy 432.02252 -64.305459) (xy 432.086197 -64.506672)
			(xy 432.142121 -64.710176) (xy 432.190209 -64.915673) (xy 432.230391 -65.122861) (xy 432.262608 -65.331436)
			(xy 432.286811 -65.541093) (xy 432.302967 -65.751522) (xy 432.311051 -65.962416) (xy 432.311556 -66.06794)
			(xy 432.311556 -74.767948) (xy 432.311051 -74.873472) (xy 432.302967 -75.084366) (xy 432.286811 -75.294795)
			(xy 432.262608 -75.504452) (xy 432.230391 -75.713027) (xy 432.190209 -75.920215) (xy 432.142121 -76.125712)
			(xy 432.086197 -76.329216) (xy 432.02252 -76.530429) (xy 431.951182 -76.729056) (xy 431.872288 -76.924804)
			(xy 431.785955 -77.117386) (xy 431.692308 -77.306521) (xy 431.591486 -77.49193) (xy 431.483636 -77.673341)
			(xy 431.368917 -77.850488) (xy 431.247497 -78.02311) (xy 431.119554 -78.190956) (xy 430.985276 -78.353778)
			(xy 430.84486 -78.511337) (xy 430.698512 -78.663402) (xy 430.546447 -78.80975) (xy 430.388888 -78.950166)
			(xy 430.226066 -79.084444) (xy 430.05822 -79.212387) (xy 429.885598 -79.333807) (xy 429.708451 -79.448526)
			(xy 429.52704 -79.556376) (xy 429.341631 -79.657198) (xy 429.152496 -79.750845) (xy 428.959914 -79.837178)
			(xy 428.764166 -79.916072) (xy 428.565539 -79.98741) (xy 428.364326 -80.051087) (xy 428.160822 -80.107011)
			(xy 427.955325 -80.155099) (xy 427.748137 -80.195281) (xy 427.539562 -80.227498) (xy 427.329905 -80.251701)
			(xy 427.119476 -80.267857) (xy 426.908582 -80.275941) (xy 426.697534 -80.275941) (xy 426.48664 -80.267857)
			(xy 426.276211 -80.251701) (xy 426.066554 -80.227498) (xy 425.857979 -80.195281) (xy 425.650791 -80.155099)
			(xy 425.445294 -80.107011) (xy 425.24179 -80.051087) (xy 425.040577 -79.98741) (xy 424.84195 -79.916072)
			(xy 424.646202 -79.837178) (xy 424.45362 -79.750845) (xy 424.264485 -79.657198) (xy 424.079076 -79.556376)
			(xy 423.897665 -79.448526) (xy 423.720518 -79.333807) (xy 423.547896 -79.212387) (xy 423.38005 -79.084444)
			(xy 423.217228 -78.950166) (xy 423.059669 -78.80975) (xy 422.907604 -78.663402) (xy 422.761256 -78.511337)
			(xy 422.62084 -78.353778) (xy 422.486562 -78.190956) (xy 422.358619 -78.02311) (xy 422.237199 -77.850488)
			(xy 422.12248 -77.673341) (xy 422.01463 -77.49193) (xy 421.913808 -77.306521) (xy 421.820161 -77.117386)
			(xy 421.733828 -76.924804) (xy 421.654934 -76.729056) (xy 421.583596 -76.530429) (xy 421.519919 -76.329216)
			(xy 421.463995 -76.125712) (xy 421.415907 -75.920215) (xy 421.375725 -75.713027) (xy 421.343508 -75.504452)
			(xy 421.319305 -75.294795) (xy 421.303149 -75.084366) (xy 421.295065 -74.873472) (xy 421.29456 -74.767948)
			(xy 298.511434 -74.767948) (xy 298.510963 -74.86636) (xy 298.502879 -75.077254) (xy 298.486723 -75.287683)
			(xy 298.46252 -75.49734) (xy 298.430303 -75.705915) (xy 298.390121 -75.913103) (xy 298.342033 -76.1186)
			(xy 298.286109 -76.322104) (xy 298.222432 -76.523317) (xy 298.151094 -76.721944) (xy 298.0722 -76.917692)
			(xy 297.985867 -77.110274) (xy 297.89222 -77.299409) (xy 297.791398 -77.484818) (xy 297.683548 -77.666229)
			(xy 297.568829 -77.843376) (xy 297.447409 -78.015998) (xy 297.319466 -78.183844) (xy 297.185188 -78.346666)
			(xy 297.044772 -78.504225) (xy 296.898424 -78.65629) (xy 296.746359 -78.802638) (xy 296.5888 -78.943054)
			(xy 296.425978 -79.077332) (xy 296.258132 -79.205275) (xy 296.08551 -79.326695) (xy 295.908363 -79.441414)
			(xy 295.726952 -79.549264) (xy 295.541543 -79.650086) (xy 295.352408 -79.743733) (xy 295.159826 -79.830066)
			(xy 294.964078 -79.90896) (xy 294.765451 -79.980298) (xy 294.564238 -80.043975) (xy 294.360734 -80.099899)
			(xy 294.155237 -80.147987) (xy 293.948049 -80.188169) (xy 293.739474 -80.220386) (xy 293.529817 -80.244589)
			(xy 293.319388 -80.260745) (xy 293.108494 -80.268829) (xy 292.897446 -80.268829) (xy 292.686552 -80.260745)
			(xy 292.476123 -80.244589) (xy 292.266466 -80.220386) (xy 292.057891 -80.188169) (xy 291.850703 -80.147987)
			(xy 291.645206 -80.099899) (xy 291.441702 -80.043975) (xy 291.240489 -79.980298) (xy 291.041862 -79.90896)
			(xy 290.846114 -79.830066) (xy 290.653532 -79.743733) (xy 290.464397 -79.650086) (xy 290.278988 -79.549264)
			(xy 290.097577 -79.441414) (xy 289.92043 -79.326695) (xy 289.747808 -79.205275) (xy 289.579962 -79.077332)
			(xy 289.41714 -78.943054) (xy 289.259581 -78.802638) (xy 289.107516 -78.65629) (xy 288.961168 -78.504225)
			(xy 288.820752 -78.346666) (xy 288.686474 -78.183844) (xy 288.558531 -78.015998) (xy 288.437111 -77.843376)
			(xy 288.322392 -77.666229) (xy 288.214542 -77.484818) (xy 288.11372 -77.299409) (xy 288.020073 -77.110274)
			(xy 287.93374 -76.917692) (xy 287.854846 -76.721944) (xy 287.783508 -76.523317) (xy 287.719831 -76.322104)
			(xy 287.663907 -76.1186) (xy 287.615819 -75.913103) (xy 287.575637 -75.705915) (xy 287.54342 -75.49734)
			(xy 287.519217 -75.287683) (xy 287.503061 -75.077254) (xy 287.494977 -74.86636) (xy 287.494472 -74.760836)
			(xy 184.371488 -74.760836) (xy 184.371488 -74.767948) (xy 184.370983 -74.873472) (xy 184.362899 -75.084366)
			(xy 184.346743 -75.294795) (xy 184.32254 -75.504452) (xy 184.290323 -75.713027) (xy 184.250141 -75.920215)
			(xy 184.202053 -76.125712) (xy 184.146129 -76.329216) (xy 184.082452 -76.530429) (xy 184.011114 -76.729056)
			(xy 183.93222 -76.924804) (xy 183.845887 -77.117386) (xy 183.75224 -77.306521) (xy 183.651418 -77.49193)
			(xy 183.543568 -77.673341) (xy 183.428849 -77.850488) (xy 183.307429 -78.02311) (xy 183.179486 -78.190956)
			(xy 183.045208 -78.353778) (xy 182.904792 -78.511337) (xy 182.758444 -78.663402) (xy 182.606379 -78.80975)
			(xy 182.44882 -78.950166) (xy 182.285998 -79.084444) (xy 182.118152 -79.212387) (xy 181.94553 -79.333807)
			(xy 181.768383 -79.448526) (xy 181.586972 -79.556376) (xy 181.401563 -79.657198) (xy 181.212428 -79.750845)
			(xy 181.019846 -79.837178) (xy 180.824098 -79.916072) (xy 180.625471 -79.98741) (xy 180.424258 -80.051087)
			(xy 180.220754 -80.107011) (xy 180.015257 -80.155099) (xy 179.808069 -80.195281) (xy 179.599494 -80.227498)
			(xy 179.389837 -80.251701) (xy 179.179408 -80.267857) (xy 178.968514 -80.275941) (xy 178.757466 -80.275941)
			(xy 178.546572 -80.267857) (xy 178.336143 -80.251701) (xy 178.126486 -80.227498) (xy 177.917911 -80.195281)
			(xy 177.710723 -80.155099) (xy 177.505226 -80.107011) (xy 177.301722 -80.051087) (xy 177.100509 -79.98741)
			(xy 176.901882 -79.916072) (xy 176.706134 -79.837178) (xy 176.513552 -79.750845) (xy 176.324417 -79.657198)
			(xy 176.139008 -79.556376) (xy 175.957597 -79.448526) (xy 175.78045 -79.333807) (xy 175.607828 -79.212387)
			(xy 175.439982 -79.084444) (xy 175.27716 -78.950166) (xy 175.119601 -78.80975) (xy 174.967536 -78.663402)
			(xy 174.821188 -78.511337) (xy 174.680772 -78.353778) (xy 174.546494 -78.190956) (xy 174.418551 -78.02311)
			(xy 174.297131 -77.850488) (xy 174.182412 -77.673341) (xy 174.074562 -77.49193) (xy 173.97374 -77.306521)
			(xy 173.880093 -77.117386) (xy 173.79376 -76.924804) (xy 173.714866 -76.729056) (xy 173.643528 -76.530429)
			(xy 173.579851 -76.329216) (xy 173.523927 -76.125712) (xy 173.475839 -75.920215) (xy 173.435657 -75.713027)
			(xy 173.40344 -75.504452) (xy 173.379237 -75.294795) (xy 173.363081 -75.084366) (xy 173.354997 -74.873472)
			(xy 173.354492 -74.767948) (xy 50.571366 -74.767948) (xy 50.570895 -74.86636) (xy 50.562811 -75.077254)
			(xy 50.546655 -75.287683) (xy 50.522452 -75.49734) (xy 50.490235 -75.705915) (xy 50.450053 -75.913103)
			(xy 50.401965 -76.1186) (xy 50.346041 -76.322104) (xy 50.282364 -76.523317) (xy 50.211026 -76.721944)
			(xy 50.132132 -76.917692) (xy 50.045799 -77.110274) (xy 49.952152 -77.299409) (xy 49.85133 -77.484818)
			(xy 49.74348 -77.666229) (xy 49.628761 -77.843376) (xy 49.507341 -78.015998) (xy 49.379398 -78.183844)
			(xy 49.24512 -78.346666) (xy 49.104704 -78.504225) (xy 48.958356 -78.65629) (xy 48.806291 -78.802638)
			(xy 48.648732 -78.943054) (xy 48.48591 -79.077332) (xy 48.318064 -79.205275) (xy 48.145442 -79.326695)
			(xy 47.968295 -79.441414) (xy 47.786884 -79.549264) (xy 47.601475 -79.650086) (xy 47.41234 -79.743733)
			(xy 47.219758 -79.830066) (xy 47.02401 -79.90896) (xy 46.825383 -79.980298) (xy 46.62417 -80.043975)
			(xy 46.420666 -80.099899) (xy 46.215169 -80.147987) (xy 46.007981 -80.188169) (xy 45.799406 -80.220386)
			(xy 45.589749 -80.244589) (xy 45.37932 -80.260745) (xy 45.168426 -80.268829) (xy 44.957378 -80.268829)
			(xy 44.746484 -80.260745) (xy 44.536055 -80.244589) (xy 44.326398 -80.220386) (xy 44.117823 -80.188169)
			(xy 43.910635 -80.147987) (xy 43.705138 -80.099899) (xy 43.501634 -80.043975) (xy 43.300421 -79.980298)
			(xy 43.101794 -79.90896) (xy 42.906046 -79.830066) (xy 42.713464 -79.743733) (xy 42.524329 -79.650086)
			(xy 42.33892 -79.549264) (xy 42.157509 -79.441414) (xy 41.980362 -79.326695) (xy 41.80774 -79.205275)
			(xy 41.639894 -79.077332) (xy 41.477072 -78.943054) (xy 41.319513 -78.802638) (xy 41.167448 -78.65629)
			(xy 41.0211 -78.504225) (xy 40.880684 -78.346666) (xy 40.746406 -78.183844) (xy 40.618463 -78.015998)
			(xy 40.497043 -77.843376) (xy 40.382324 -77.666229) (xy 40.274474 -77.484818) (xy 40.173652 -77.299409)
			(xy 40.080005 -77.110274) (xy 39.993672 -76.917692) (xy 39.914778 -76.721944) (xy 39.84344 -76.523317)
			(xy 39.779763 -76.322104) (xy 39.723839 -76.1186) (xy 39.675751 -75.913103) (xy 39.635569 -75.705915)
			(xy 39.603352 -75.49734) (xy 39.579149 -75.287683) (xy 39.562993 -75.077254) (xy 39.554909 -74.86636)
			(xy 39.554404 -74.760836) (xy 0.509016 -74.760836) (xy 0.509016 -77.67193) (xy 0.5095 -77.725143)
			(xy 0.517108 -77.831296) (xy 0.532269 -77.936637) (xy 0.554904 -78.040627) (xy 0.584899 -78.142739)
			(xy 0.622101 -78.242451) (xy 0.666319 -78.339256) (xy 0.71733 -78.43266) (xy 0.774873 -78.522188)
			(xy 0.838654 -78.607384) (xy 0.90835 -78.687813) (xy 0.945642 -78.725776) (xy 1.77419 -79.554324)
			(xy 1.823612 -79.604428) (xy 1.917404 -79.709374) (xy 2.005163 -79.819414) (xy 2.086614 -79.934202)
			(xy 2.161501 -80.053377) (xy 2.229587 -80.176563) (xy 2.290658 -80.303374) (xy 2.344523 -80.433409)
			(xy 2.391012 -80.56626) (xy 2.429978 -80.701509) (xy 2.461299 -80.83873) (xy 2.484876 -80.977491)
			(xy 2.500635 -81.117356) (xy 2.508527 -81.257885) (xy 2.509012 -81.32826) (xy 2.509012 -81.691972)
			(xy 232.140715 -81.691972) (xy 232.145114 -81.518126) (xy 232.157548 -81.34467) (xy 232.177991 -81.171975)
			(xy 232.206398 -81.00041) (xy 232.242709 -80.830342) (xy 232.286847 -80.662135) (xy 232.338717 -80.49615)
			(xy 232.398207 -80.332741) (xy 232.465191 -80.172258) (xy 232.539525 -80.015044) (xy 232.62105 -79.861437)
			(xy 232.709592 -79.711764) (xy 232.804961 -79.566346) (xy 232.906953 -79.425495) (xy 233.015351 -79.289511)
			(xy 233.129921 -79.158685) (xy 233.250418 -79.033298) (xy 233.376586 -78.913618) (xy 233.508153 -78.799901)
			(xy 233.644839 -78.69239) (xy 233.715306 -78.641448) (xy 238.084614 -78.641448) (xy 238.155081 -78.69239)
			(xy 238.291767 -78.799901) (xy 238.423334 -78.913618) (xy 238.549502 -79.033298) (xy 238.669999 -79.158685)
			(xy 238.784569 -79.289511) (xy 238.892967 -79.425495) (xy 238.994959 -79.566346) (xy 239.090328 -79.711764)
			(xy 239.17887 -79.861437) (xy 239.260395 -80.015044) (xy 239.334729 -80.172258) (xy 239.401713 -80.332741)
			(xy 239.461203 -80.49615) (xy 239.513073 -80.662135) (xy 239.557211 -80.830342) (xy 239.593522 -81.00041)
			(xy 239.608937 -81.093507) (xy 398.275806 -81.093507) (xy 398.275806 -81.008785) (xy 398.283859 -80.924448)
			(xy 398.299893 -80.841258) (xy 398.323761 -80.759968) (xy 398.355249 -80.681316) (xy 398.394071 -80.606013)
			(xy 398.439874 -80.534741) (xy 398.492245 -80.468145) (xy 398.55071 -80.40683) (xy 398.614738 -80.351349)
			(xy 398.68375 -80.302206) (xy 398.75712 -80.259846) (xy 398.834185 -80.224651) (xy 398.914247 -80.196942)
			(xy 398.99658 -80.176968) (xy 399.080439 -80.164911) (xy 399.165064 -80.16088) (xy 399.249689 -80.164911)
			(xy 399.333548 -80.176968) (xy 399.415881 -80.196942) (xy 399.495943 -80.224651) (xy 399.573008 -80.259846)
			(xy 399.646378 -80.302206) (xy 399.71539 -80.351349) (xy 399.779418 -80.40683) (xy 399.837883 -80.468145)
			(xy 399.890254 -80.534741) (xy 399.936057 -80.606013) (xy 399.974879 -80.681316) (xy 400.006367 -80.759968)
			(xy 400.030235 -80.841258) (xy 400.046269 -80.924448) (xy 400.054322 -81.008785) (xy 400.054826 -81.051146)
			(xy 400.054322 -81.093507) (xy 400.046269 -81.177844) (xy 400.030235 -81.261034) (xy 400.006367 -81.342324)
			(xy 399.974879 -81.420976) (xy 399.936057 -81.496279) (xy 399.890254 -81.567551) (xy 399.837883 -81.634147)
			(xy 399.779418 -81.695462) (xy 399.71539 -81.750943) (xy 399.646378 -81.800086) (xy 399.573008 -81.842446)
			(xy 399.495943 -81.877641) (xy 399.415881 -81.90535) (xy 399.333548 -81.925324) (xy 399.249689 -81.937381)
			(xy 399.165064 -81.941413) (xy 399.080439 -81.937381) (xy 398.99658 -81.925324) (xy 398.914247 -81.90535)
			(xy 398.834185 -81.877641) (xy 398.75712 -81.842446) (xy 398.68375 -81.800086) (xy 398.614738 -81.750943)
			(xy 398.55071 -81.695462) (xy 398.492245 -81.634147) (xy 398.439874 -81.567551) (xy 398.394071 -81.496279)
			(xy 398.355249 -81.420976) (xy 398.323761 -81.342324) (xy 398.299893 -81.261034) (xy 398.283859 -81.177844)
			(xy 398.275806 -81.093507) (xy 239.608937 -81.093507) (xy 239.621929 -81.171975) (xy 239.642372 -81.34467)
			(xy 239.654806 -81.518126) (xy 239.659205 -81.691972) (xy 239.655559 -81.865835) (xy 239.643877 -82.039343)
			(xy 239.624183 -82.212126) (xy 239.596519 -82.383812) (xy 239.560945 -82.554036) (xy 239.517536 -82.722432)
			(xy 239.466387 -82.888641) (xy 239.407605 -83.052306) (xy 239.341317 -83.213078) (xy 239.267665 -83.370612)
			(xy 239.186806 -83.524571) (xy 239.098913 -83.674626) (xy 239.004175 -83.820455) (xy 238.902794 -83.961748)
			(xy 238.794987 -84.0982) (xy 238.680985 -84.229521) (xy 238.561032 -84.355429) (xy 238.435384 -84.475655)
			(xy 238.30431 -84.589941) (xy 238.168092 -84.698043) (xy 238.027019 -84.79973) (xy 237.881395 -84.894784)
			(xy 237.731531 -84.983001) (xy 237.577747 -85.064194) (xy 237.420373 -85.138187) (xy 237.259746 -85.204823)
			(xy 237.096208 -85.263959) (xy 236.930111 -85.315469) (xy 236.761809 -85.359242) (xy 236.591663 -85.395185)
			(xy 236.420037 -85.423221) (xy 236.247297 -85.443289) (xy 236.073815 -85.455348) (xy 235.89996 -85.45937)
			(xy 235.726105 -85.455348) (xy 235.552623 -85.443289) (xy 235.379883 -85.423221) (xy 235.208257 -85.395185)
			(xy 235.038111 -85.359242) (xy 234.869809 -85.315469) (xy 234.703712 -85.263959) (xy 234.540174 -85.204823)
			(xy 234.379547 -85.138187) (xy 234.222173 -85.064194) (xy 234.068389 -84.983001) (xy 233.918525 -84.894784)
			(xy 233.772901 -84.79973) (xy 233.631828 -84.698043) (xy 233.49561 -84.589941) (xy 233.364536 -84.475655)
			(xy 233.238888 -84.355429) (xy 233.118935 -84.229521) (xy 233.004933 -84.0982) (xy 232.897126 -83.961748)
			(xy 232.795745 -83.820455) (xy 232.701007 -83.674626) (xy 232.613114 -83.524571) (xy 232.532255 -83.370612)
			(xy 232.458603 -83.213078) (xy 232.392315 -83.052306) (xy 232.333533 -82.888641) (xy 232.282384 -82.722432)
			(xy 232.238975 -82.554036) (xy 232.203401 -82.383812) (xy 232.175737 -82.212126) (xy 232.156043 -82.039343)
			(xy 232.144361 -81.865835) (xy 232.140715 -81.691972) (xy 2.509012 -81.691972) (xy 2.509012 -84.065147)
			(xy 218.29831 -84.065147) (xy 218.29831 -84.010653) (xy 218.306065 -83.956712) (xy 218.321417 -83.904424)
			(xy 218.344054 -83.854854) (xy 218.373515 -83.809009) (xy 218.4092 -83.767823) (xy 218.450383 -83.732134)
			(xy 218.496225 -83.70267) (xy 218.545794 -83.680029) (xy 218.598081 -83.664672) (xy 218.652021 -83.656912)
			(xy 218.679268 -83.656424) (xy 219.542868 -83.656424) (xy 219.570125 -83.656821) (xy 219.624084 -83.664575)
			(xy 219.67639 -83.679929) (xy 219.725978 -83.702572) (xy 219.771839 -83.732041) (xy 219.813039 -83.767738)
			(xy 219.848739 -83.808935) (xy 219.878213 -83.854794) (xy 219.90086 -83.90438) (xy 219.916219 -83.956685)
			(xy 219.923977 -84.010643) (xy 219.923977 -84.065157) (xy 219.916219 -84.119115) (xy 219.90086 -84.17142)
			(xy 219.878213 -84.221006) (xy 219.848739 -84.266865) (xy 219.813039 -84.308062) (xy 219.771839 -84.343759)
			(xy 219.725978 -84.373228) (xy 219.67639 -84.395871) (xy 219.624084 -84.411225) (xy 219.570125 -84.418979)
			(xy 219.542868 -84.41944) (xy 218.679268 -84.41944) (xy 218.652021 -84.418888) (xy 218.598081 -84.411128)
			(xy 218.545794 -84.395771) (xy 218.496225 -84.37313) (xy 218.450383 -84.343666) (xy 218.4092 -84.307977)
			(xy 218.373515 -84.266791) (xy 218.344054 -84.220946) (xy 218.321417 -84.171376) (xy 218.306065 -84.119088)
			(xy 218.29831 -84.065147) (xy 2.509012 -84.065147) (xy 2.509012 -86.948548) (xy 217.344518 -86.948548)
			(xy 217.344518 -86.894052) (xy 217.352274 -86.84011) (xy 217.367627 -86.787821) (xy 217.390266 -86.738249)
			(xy 217.419729 -86.692404) (xy 217.455416 -86.651218) (xy 217.496602 -86.61553) (xy 217.542447 -86.586067)
			(xy 217.592019 -86.563428) (xy 217.644308 -86.548074) (xy 217.69825 -86.540318) (xy 217.725498 -86.539832)
			(xy 218.589098 -86.539832) (xy 218.616354 -86.540215) (xy 218.670311 -86.547972) (xy 218.722614 -86.56333)
			(xy 218.7722 -86.585975) (xy 218.818058 -86.615446) (xy 218.859255 -86.651143) (xy 218.894953 -86.69234)
			(xy 218.924424 -86.738198) (xy 218.947069 -86.787784) (xy 218.962427 -86.840087) (xy 218.970185 -86.894044)
			(xy 218.970185 -86.948556) (xy 218.962427 -87.002513) (xy 218.947069 -87.054816) (xy 218.924424 -87.104402)
			(xy 218.894953 -87.15026) (xy 218.859255 -87.191457) (xy 218.818058 -87.227154) (xy 218.7722 -87.256625)
			(xy 218.722614 -87.27927) (xy 218.670311 -87.294628) (xy 218.616354 -87.302385) (xy 218.589098 -87.302848)
			(xy 217.725498 -87.302848) (xy 217.69825 -87.302282) (xy 217.644308 -87.294526) (xy 217.592019 -87.279172)
			(xy 217.542447 -87.256533) (xy 217.496602 -87.22707) (xy 217.455416 -87.191382) (xy 217.419729 -87.150196)
			(xy 217.390266 -87.104351) (xy 217.367627 -87.054779) (xy 217.352274 -87.00249) (xy 217.344518 -86.948548)
			(xy 2.509012 -86.948548) (xy 2.509012 -106.447336) (xy 11.713464 -106.447336) (xy 11.713464 -105.456736)
			(xy 11.71395 -105.429467) (xy 11.721712 -105.375483) (xy 11.737077 -105.323153) (xy 11.759734 -105.273543)
			(xy 11.78922 -105.227662) (xy 11.824935 -105.186445) (xy 11.866152 -105.15073) (xy 11.912033 -105.121244)
			(xy 11.961643 -105.098587) (xy 12.013973 -105.083222) (xy 12.067957 -105.07546) (xy 12.122495 -105.07546)
			(xy 12.176479 -105.083222) (xy 12.228809 -105.098587) (xy 12.278419 -105.121244) (xy 12.3243 -105.15073)
			(xy 12.365517 -105.186445) (xy 12.401232 -105.227662) (xy 12.430718 -105.273543) (xy 12.453375 -105.323153)
			(xy 12.46874 -105.375483) (xy 12.476502 -105.429467) (xy 12.476988 -105.456736) (xy 12.476988 -105.664)
			(xy 15.57274 -105.664) (xy 15.57274 -104.6734) (xy 15.573226 -104.646131) (xy 15.580988 -104.592147)
			(xy 15.596353 -104.539817) (xy 15.61901 -104.490207) (xy 15.648496 -104.444326) (xy 15.684211 -104.403109)
			(xy 15.725428 -104.367394) (xy 15.771309 -104.337908) (xy 15.820919 -104.315251) (xy 15.873249 -104.299886)
			(xy 15.927233 -104.292124) (xy 15.981771 -104.292124) (xy 16.035755 -104.299886) (xy 16.088085 -104.315251)
			(xy 16.137695 -104.337908) (xy 16.146631 -104.343651) (xy 326.803 -104.343651) (xy 326.803 -104.258929)
			(xy 326.811053 -104.174592) (xy 326.827087 -104.091402) (xy 326.850955 -104.010112) (xy 326.882443 -103.93146)
			(xy 326.921265 -103.856157) (xy 326.967068 -103.784885) (xy 327.019439 -103.718289) (xy 327.077904 -103.656974)
			(xy 327.141932 -103.601493) (xy 327.210944 -103.55235) (xy 327.284314 -103.50999) (xy 327.361379 -103.474795)
			(xy 327.441441 -103.447086) (xy 327.523774 -103.427112) (xy 327.607633 -103.415055) (xy 327.692258 -103.411024)
			(xy 327.776883 -103.415055) (xy 327.860742 -103.427112) (xy 327.943075 -103.447086) (xy 328.023137 -103.474795)
			(xy 328.100202 -103.50999) (xy 328.173572 -103.55235) (xy 328.242584 -103.601493) (xy 328.306612 -103.656974)
			(xy 328.365077 -103.718289) (xy 328.417448 -103.784885) (xy 328.463251 -103.856157) (xy 328.502073 -103.93146)
			(xy 328.533561 -104.010112) (xy 328.557429 -104.091402) (xy 328.573463 -104.174592) (xy 328.581516 -104.258929)
			(xy 328.58202 -104.30129) (xy 328.581516 -104.343651) (xy 328.573463 -104.427988) (xy 328.557429 -104.511178)
			(xy 328.533561 -104.592468) (xy 328.502073 -104.67112) (xy 328.463251 -104.746423) (xy 328.417448 -104.817695)
			(xy 328.365077 -104.884291) (xy 328.306612 -104.945606) (xy 328.242584 -105.001087) (xy 328.173572 -105.05023)
			(xy 328.100202 -105.09259) (xy 328.023137 -105.127785) (xy 327.943075 -105.155494) (xy 327.860742 -105.175468)
			(xy 327.776883 -105.187525) (xy 327.692258 -105.191557) (xy 327.607633 -105.187525) (xy 327.523774 -105.175468)
			(xy 327.441441 -105.155494) (xy 327.361379 -105.127785) (xy 327.284314 -105.09259) (xy 327.210944 -105.05023)
			(xy 327.141932 -105.001087) (xy 327.077904 -104.945606) (xy 327.019439 -104.884291) (xy 326.967068 -104.817695)
			(xy 326.921265 -104.746423) (xy 326.882443 -104.67112) (xy 326.850955 -104.592468) (xy 326.827087 -104.511178)
			(xy 326.811053 -104.427988) (xy 326.803 -104.343651) (xy 16.146631 -104.343651) (xy 16.183576 -104.367394)
			(xy 16.224793 -104.403109) (xy 16.260508 -104.444326) (xy 16.289994 -104.490207) (xy 16.312651 -104.539817)
			(xy 16.328016 -104.592147) (xy 16.335778 -104.646131) (xy 16.336264 -104.6734) (xy 16.336264 -105.664)
			(xy 16.335778 -105.691269) (xy 16.328016 -105.745253) (xy 16.312651 -105.797583) (xy 16.289994 -105.847193)
			(xy 16.260508 -105.893074) (xy 16.224793 -105.934291) (xy 16.183576 -105.970006) (xy 16.137695 -105.999492)
			(xy 16.088085 -106.022149) (xy 16.035755 -106.037514) (xy 15.981771 -106.045276) (xy 15.927233 -106.045276)
			(xy 15.873249 -106.037514) (xy 15.820919 -106.022149) (xy 15.771309 -105.999492) (xy 15.725428 -105.970006)
			(xy 15.684211 -105.934291) (xy 15.648496 -105.893074) (xy 15.61901 -105.847193) (xy 15.596353 -105.797583)
			(xy 15.580988 -105.745253) (xy 15.573226 -105.691269) (xy 15.57274 -105.664) (xy 12.476988 -105.664)
			(xy 12.476988 -106.447336) (xy 12.476502 -106.474605) (xy 12.46874 -106.528589) (xy 12.453375 -106.580919)
			(xy 12.430718 -106.630529) (xy 12.401232 -106.67641) (xy 12.365517 -106.717627) (xy 12.3243 -106.753342)
			(xy 12.278419 -106.782828) (xy 12.228809 -106.805485) (xy 12.176479 -106.82085) (xy 12.122495 -106.828612)
			(xy 12.067957 -106.828612) (xy 12.013973 -106.82085) (xy 11.961643 -106.805485) (xy 11.912033 -106.782828)
			(xy 11.866152 -106.753342) (xy 11.824935 -106.717627) (xy 11.78922 -106.67641) (xy 11.759734 -106.630529)
			(xy 11.737077 -106.580919) (xy 11.721712 -106.528589) (xy 11.71395 -106.474605) (xy 11.713464 -106.447336)
			(xy 2.509012 -106.447336) (xy 2.509012 -108.943971) (xy 11.292822 -108.943971) (xy 11.292822 -108.889469)
			(xy 11.300578 -108.835522) (xy 11.315933 -108.783228) (xy 11.338574 -108.733651) (xy 11.36804 -108.687801)
			(xy 11.403731 -108.646611) (xy 11.444921 -108.61092) (xy 11.490771 -108.581454) (xy 11.540348 -108.558813)
			(xy 11.592642 -108.543458) (xy 11.646589 -108.535702) (xy 11.67384 -108.535216) (xy 12.53744 -108.535216)
			(xy 12.564692 -108.535694) (xy 12.61864 -108.54345) (xy 12.670935 -108.558806) (xy 12.720513 -108.581447)
			(xy 12.766364 -108.610914) (xy 12.807554 -108.646606) (xy 12.843246 -108.687796) (xy 12.872713 -108.733647)
			(xy 12.895354 -108.783225) (xy 12.91071 -108.83552) (xy 12.918466 -108.889468) (xy 12.918466 -108.943972)
			(xy 12.91071 -108.99792) (xy 12.895354 -109.050215) (xy 12.872713 -109.099793) (xy 12.843246 -109.145644)
			(xy 12.807554 -109.186834) (xy 12.766364 -109.222526) (xy 12.720513 -109.251993) (xy 12.670935 -109.274634)
			(xy 12.61864 -109.28999) (xy 12.564692 -109.297746) (xy 12.53744 -109.298232) (xy 11.67384 -109.298232)
			(xy 11.646589 -109.297738) (xy 11.592642 -109.289982) (xy 11.540348 -109.274627) (xy 11.490771 -109.251986)
			(xy 11.444921 -109.22252) (xy 11.403731 -109.186829) (xy 11.36804 -109.145639) (xy 11.338574 -109.099789)
			(xy 11.315933 -109.050212) (xy 11.300578 -108.997918) (xy 11.292822 -108.943971) (xy 2.509012 -108.943971)
			(xy 2.509012 -109.451973) (xy 15.092889 -109.451973) (xy 15.092889 -109.397467) (xy 15.100646 -109.343517)
			(xy 15.116002 -109.291219) (xy 15.138645 -109.241639) (xy 15.168113 -109.195786) (xy 15.203807 -109.154594)
			(xy 15.244999 -109.118901) (xy 15.290853 -109.089433) (xy 15.340433 -109.066791) (xy 15.39273 -109.051435)
			(xy 15.446681 -109.043679) (xy 15.473934 -109.043216) (xy 16.464534 -109.043216) (xy 16.491785 -109.043694)
			(xy 16.545733 -109.051451) (xy 16.598028 -109.066807) (xy 16.647605 -109.089448) (xy 16.693456 -109.118915)
			(xy 16.734646 -109.154607) (xy 16.770337 -109.195798) (xy 16.799804 -109.241648) (xy 16.822445 -109.291226)
			(xy 16.8378 -109.343521) (xy 16.845556 -109.397469) (xy 16.845556 -109.451971) (xy 16.8378 -109.505919)
			(xy 16.822445 -109.558214) (xy 16.799804 -109.607792) (xy 16.770337 -109.653642) (xy 16.734646 -109.694833)
			(xy 16.693456 -109.730525) (xy 16.647605 -109.759992) (xy 16.598028 -109.782633) (xy 16.545733 -109.797989)
			(xy 16.491785 -109.805746) (xy 16.464534 -109.806232) (xy 15.473934 -109.806232) (xy 15.446681 -109.805761)
			(xy 15.39273 -109.798005) (xy 15.340433 -109.782649) (xy 15.290853 -109.760007) (xy 15.244999 -109.730539)
			(xy 15.203807 -109.694846) (xy 15.168113 -109.653654) (xy 15.138645 -109.607801) (xy 15.116002 -109.558221)
			(xy 15.100646 -109.505923) (xy 15.092889 -109.451973) (xy 2.509012 -109.451973) (xy 2.509012 -114.734161)
			(xy 11.255226 -114.734161) (xy 11.255226 -114.679659) (xy 11.262982 -114.625711) (xy 11.278337 -114.573416)
			(xy 11.300979 -114.523839) (xy 11.330445 -114.477988) (xy 11.366136 -114.436798) (xy 11.407326 -114.401106)
			(xy 11.453177 -114.371639) (xy 11.502754 -114.348998) (xy 11.555049 -114.333643) (xy 11.608997 -114.325886)
			(xy 11.636248 -114.3254) (xy 12.499848 -114.3254) (xy 12.527101 -114.325867) (xy 12.581052 -114.333624)
			(xy 12.633349 -114.34898) (xy 12.68293 -114.371622) (xy 12.728783 -114.40109) (xy 12.769975 -114.436783)
			(xy 12.805669 -114.477976) (xy 12.835137 -114.523829) (xy 12.85778 -114.573409) (xy 12.873136 -114.625706)
			(xy 12.880893 -114.679657) (xy 12.880893 -114.734163) (xy 12.873136 -114.788114) (xy 12.85778 -114.840411)
			(xy 12.835137 -114.889991) (xy 12.805669 -114.935844) (xy 12.769975 -114.977037) (xy 12.728783 -115.01273)
			(xy 12.68293 -115.042198) (xy 12.633349 -115.06484) (xy 12.581052 -115.080196) (xy 12.527101 -115.087953)
			(xy 12.499848 -115.088416) (xy 11.636248 -115.088416) (xy 11.608997 -115.087934) (xy 11.555049 -115.080177)
			(xy 11.502754 -115.064822) (xy 11.453177 -115.042181) (xy 11.407326 -115.012714) (xy 11.366136 -114.977022)
			(xy 11.330445 -114.935832) (xy 11.300979 -114.889981) (xy 11.278337 -114.840404) (xy 11.262982 -114.788109)
			(xy 11.255226 -114.734161) (xy 2.509012 -114.734161) (xy 2.509012 -133.480302) (xy 20.179284 -133.480302)
			(xy 20.179284 -132.489702) (xy 20.17977 -132.462451) (xy 20.187526 -132.408503) (xy 20.202881 -132.356208)
			(xy 20.225523 -132.306631) (xy 20.254989 -132.260781) (xy 20.29068 -132.21959) (xy 20.331871 -132.183899)
			(xy 20.377721 -132.154433) (xy 20.427298 -132.131791) (xy 20.479593 -132.116436) (xy 20.533541 -132.10868)
			(xy 20.588043 -132.10868) (xy 20.641991 -132.116436) (xy 20.694286 -132.131791) (xy 20.743863 -132.154433)
			(xy 20.789713 -132.183899) (xy 20.830904 -132.21959) (xy 20.866595 -132.260781) (xy 20.896061 -132.306631)
			(xy 20.918703 -132.356208) (xy 20.934058 -132.408503) (xy 20.941814 -132.462451) (xy 20.9423 -132.489702)
			(xy 20.9423 -133.480302) (xy 20.941814 -133.507553) (xy 20.934058 -133.561501) (xy 20.918703 -133.613796)
			(xy 20.896061 -133.663373) (xy 20.866595 -133.709223) (xy 20.830904 -133.750414) (xy 20.789713 -133.786105)
			(xy 20.743863 -133.815571) (xy 20.694286 -133.838213) (xy 20.641991 -133.853568) (xy 20.588043 -133.861324)
			(xy 20.533541 -133.861324) (xy 20.479593 -133.853568) (xy 20.427298 -133.838213) (xy 20.377721 -133.815571)
			(xy 20.331871 -133.786105) (xy 20.29068 -133.750414) (xy 20.254989 -133.709223) (xy 20.225523 -133.663373)
			(xy 20.202881 -133.613796) (xy 20.187526 -133.561501) (xy 20.17977 -133.507553) (xy 20.179284 -133.480302)
			(xy 2.509012 -133.480302) (xy 2.509012 -138.001502) (xy 20.019264 -138.001502) (xy 20.019264 -137.010902)
			(xy 20.01975 -136.983651) (xy 20.027506 -136.929703) (xy 20.042861 -136.877408) (xy 20.065503 -136.827831)
			(xy 20.094969 -136.781981) (xy 20.13066 -136.74079) (xy 20.171851 -136.705099) (xy 20.217701 -136.675633)
			(xy 20.267278 -136.652991) (xy 20.319573 -136.637636) (xy 20.373521 -136.62988) (xy 20.428023 -136.62988)
			(xy 20.481971 -136.637636) (xy 20.534266 -136.652991) (xy 20.583843 -136.675633) (xy 20.629693 -136.705099)
			(xy 20.670884 -136.74079) (xy 20.706575 -136.781981) (xy 20.736041 -136.827831) (xy 20.758683 -136.877408)
			(xy 20.774038 -136.929703) (xy 20.781794 -136.983651) (xy 20.78228 -137.010902) (xy 20.78228 -138.001502)
			(xy 20.781794 -138.028753) (xy 20.774038 -138.082701) (xy 20.758683 -138.134996) (xy 20.736041 -138.184573)
			(xy 20.706575 -138.230423) (xy 20.670884 -138.271614) (xy 20.629693 -138.307305) (xy 20.583843 -138.336771)
			(xy 20.534266 -138.359413) (xy 20.481971 -138.374768) (xy 20.428023 -138.382524) (xy 20.373521 -138.382524)
			(xy 20.319573 -138.374768) (xy 20.267278 -138.359413) (xy 20.217701 -138.336771) (xy 20.171851 -138.307305)
			(xy 20.13066 -138.271614) (xy 20.094969 -138.230423) (xy 20.065503 -138.184573) (xy 20.042861 -138.134996)
			(xy 20.027506 -138.082701) (xy 20.01975 -138.028753) (xy 20.019264 -138.001502) (xy 2.509012 -138.001502)
			(xy 2.509012 -145.104166) (xy 163.29995 -145.104166) (xy 163.29995 -145.049634) (xy 163.30771 -144.995658)
			(xy 163.323072 -144.943336) (xy 163.345724 -144.893732) (xy 163.375204 -144.847856) (xy 163.410912 -144.806643)
			(xy 163.452121 -144.77093) (xy 163.497993 -144.741445) (xy 163.547595 -144.718788) (xy 163.599915 -144.70342)
			(xy 163.653891 -144.695653) (xy 163.681156 -144.695164) (xy 164.671756 -144.695164) (xy 164.699031 -144.695573)
			(xy 164.753026 -144.70333) (xy 164.805368 -144.718694) (xy 164.85499 -144.74135) (xy 164.900882 -144.770839)
			(xy 164.94211 -144.806559) (xy 164.977835 -144.847783) (xy 165.007329 -144.893672) (xy 165.029991 -144.943291)
			(xy 165.045361 -144.995631) (xy 165.053124 -145.049625) (xy 165.053124 -145.104175) (xy 165.045361 -145.158169)
			(xy 165.029991 -145.210509) (xy 165.007329 -145.260128) (xy 164.977835 -145.306017) (xy 164.94211 -145.347241)
			(xy 164.900882 -145.382961) (xy 164.85499 -145.41245) (xy 164.805368 -145.435106) (xy 164.753026 -145.45047)
			(xy 164.699031 -145.458227) (xy 164.671756 -145.458688) (xy 163.681156 -145.458688) (xy 163.653891 -145.458147)
			(xy 163.599915 -145.45038) (xy 163.547595 -145.435012) (xy 163.497993 -145.412355) (xy 163.452121 -145.38287)
			(xy 163.410912 -145.347157) (xy 163.375204 -145.305944) (xy 163.345724 -145.260068) (xy 163.323072 -145.210464)
			(xy 163.30771 -145.158142) (xy 163.29995 -145.104166) (xy 2.509012 -145.104166) (xy 2.509012 -153.765504)
			(xy 24.441921 -153.765504) (xy 24.445917 -153.555618) (xy 24.457902 -153.346036) (xy 24.477856 -153.137062)
			(xy 24.505752 -152.929) (xy 24.541549 -152.72215) (xy 24.585194 -152.516813) (xy 24.636626 -152.313287)
			(xy 24.695768 -152.111866) (xy 24.762536 -151.912843) (xy 24.836832 -151.716506) (xy 24.91855 -151.52314)
			(xy 25.007569 -151.333025) (xy 25.103762 -151.146437) (xy 25.206989 -150.963646) (xy 25.3171 -150.784918)
			(xy 25.433935 -150.610511) (xy 25.557325 -150.440679) (xy 25.687092 -150.275667) (xy 25.823046 -150.115716)
			(xy 25.964992 -149.961056) (xy 26.112722 -149.811912) (xy 26.266024 -149.668501) (xy 26.424674 -149.53103)
			(xy 26.588443 -149.399698) (xy 26.757093 -149.274697) (xy 26.930379 -149.156206) (xy 27.108051 -149.044399)
			(xy 27.289851 -148.939437) (xy 27.475515 -148.841472) (xy 27.664773 -148.750647) (xy 27.857353 -148.667093)
			(xy 28.052974 -148.59093) (xy 28.251352 -148.522271) (xy 28.452201 -148.461214) (xy 28.655228 -148.407847)
			(xy 28.860141 -148.362249) (xy 29.06664 -148.324484) (xy 29.274427 -148.294609) (xy 29.483202 -148.272666)
			(xy 29.69266 -148.258687) (xy 29.902499 -148.252692) (xy 30.112413 -148.254691) (xy 30.3221 -148.264679)
			(xy 30.531254 -148.282644) (xy 30.739572 -148.308558) (xy 30.946753 -148.342383) (xy 31.152497 -148.384072)
			(xy 31.356503 -148.433564) (xy 31.558478 -148.490786) (xy 31.758128 -148.555656) (xy 31.955163 -148.62808)
			(xy 32.149299 -148.707953) (xy 32.340252 -148.795159) (xy 32.527748 -148.889571) (xy 32.711513 -148.991053)
			(xy 32.891281 -149.099457) (xy 33.066792 -149.214627) (xy 33.237791 -149.336395) (xy 33.404031 -149.464584)
			(xy 33.56527 -149.59901) (xy 33.721274 -149.739477) (xy 33.871817 -149.885781) (xy 34.016681 -150.03771)
			(xy 34.155656 -150.195044) (xy 34.288541 -150.357555) (xy 34.415142 -150.525008) (xy 34.535277 -150.697158)
			(xy 34.648771 -150.873758) (xy 34.688915 -150.941786) (xy 108.742233 -150.941786) (xy 108.746238 -150.836037)
			(xy 108.758228 -150.730894) (xy 108.778137 -150.626959) (xy 108.805848 -150.524827) (xy 108.841205 -150.425083)
			(xy 108.884003 -150.328299) (xy 108.933999 -150.235029) (xy 108.990906 -150.145808) (xy 109.054397 -150.061145)
			(xy 109.124109 -149.981527) (xy 109.199643 -149.907409) (xy 109.280566 -149.839216) (xy 109.366415 -149.777338)
			(xy 109.456698 -149.722131) (xy 109.550897 -149.673909) (xy 109.648474 -149.632949) (xy 109.748869 -149.599487)
			(xy 109.851507 -149.573713) (xy 109.9558 -149.555775) (xy 110.061151 -149.545776) (xy 110.166957 -149.543773)
			(xy 110.272611 -149.549778) (xy 110.377508 -149.563757) (xy 110.481048 -149.585628) (xy 110.582637 -149.615268)
			(xy 110.681694 -149.652506) (xy 110.777651 -149.697128) (xy 110.869958 -149.74888) (xy 110.958087 -149.807465)
			(xy 111.041533 -149.872547) (xy 111.119817 -149.943753) (xy 111.187365 -150.015249) (xy 160.856694 -150.015249)
			(xy 160.856694 -149.960751) (xy 160.86445 -149.906808) (xy 160.879803 -149.854517) (xy 160.902441 -149.804944)
			(xy 160.931904 -149.759096) (xy 160.967592 -149.717909) (xy 161.008777 -149.682219) (xy 161.054623 -149.652753)
			(xy 161.104195 -149.630111) (xy 161.156484 -149.614755) (xy 161.210427 -149.606996) (xy 161.237676 -149.606508)
			(xy 162.228276 -149.606508) (xy 162.255531 -149.606937) (xy 162.309487 -149.614692) (xy 162.36179 -149.630046)
			(xy 162.411375 -149.652688) (xy 162.457233 -149.682157) (xy 162.498431 -149.717852) (xy 162.534128 -149.759047)
			(xy 162.5636 -149.804904) (xy 162.586245 -149.854488) (xy 162.601603 -149.90679) (xy 162.609361 -149.960745)
			(xy 162.609361 -149.967557) (xy 163.793819 -149.967557) (xy 163.793819 -149.913043) (xy 163.801578 -149.859084)
			(xy 163.816937 -149.806779) (xy 163.839584 -149.757192) (xy 163.869057 -149.711333) (xy 163.904758 -149.670135)
			(xy 163.945958 -149.634438) (xy 163.99182 -149.604968) (xy 164.041409 -149.582325) (xy 164.093716 -149.566971)
			(xy 164.147675 -149.559217) (xy 164.174932 -149.558756) (xy 165.165532 -149.558756) (xy 165.192779 -149.559316)
			(xy 165.246718 -149.567076) (xy 165.299004 -149.582432) (xy 165.348573 -149.605073) (xy 165.394415 -149.634537)
			(xy 165.435597 -149.670226) (xy 165.471282 -149.711411) (xy 165.500742 -149.757255) (xy 165.523379 -149.806826)
			(xy 165.538731 -149.859113) (xy 165.546486 -149.913053) (xy 165.546486 -149.967547) (xy 165.538731 -150.021487)
			(xy 165.523379 -150.073774) (xy 165.500742 -150.123345) (xy 165.471282 -150.169189) (xy 165.435597 -150.210374)
			(xy 165.394415 -150.246063) (xy 165.348573 -150.275527) (xy 165.299004 -150.298168) (xy 165.246718 -150.313524)
			(xy 165.192779 -150.321284) (xy 165.165532 -150.321772) (xy 164.174932 -150.321772) (xy 164.147675 -150.321383)
			(xy 164.093716 -150.313629) (xy 164.041409 -150.298275) (xy 163.99182 -150.275632) (xy 163.945958 -150.246162)
			(xy 163.904758 -150.210465) (xy 163.869057 -150.169267) (xy 163.839584 -150.123408) (xy 163.816937 -150.073821)
			(xy 163.801578 -150.021516) (xy 163.793819 -149.967557) (xy 162.609361 -149.967557) (xy 162.609361 -150.015255)
			(xy 162.601603 -150.06921) (xy 162.586245 -150.121512) (xy 162.5636 -150.171096) (xy 162.534128 -150.216953)
			(xy 162.498431 -150.258148) (xy 162.457233 -150.293843) (xy 162.411375 -150.323312) (xy 162.36179 -150.345954)
			(xy 162.309487 -150.361308) (xy 162.255531 -150.369063) (xy 162.228276 -150.369524) (xy 161.237676 -150.369524)
			(xy 161.210427 -150.369004) (xy 161.156484 -150.361245) (xy 161.104195 -150.345889) (xy 161.054623 -150.323247)
			(xy 161.008777 -150.293781) (xy 160.967592 -150.258091) (xy 160.931904 -150.216904) (xy 160.902441 -150.171056)
			(xy 160.879803 -150.121483) (xy 160.86445 -150.069192) (xy 160.856694 -150.015249) (xy 111.187365 -150.015249)
			(xy 111.192492 -150.020676) (xy 111.259142 -150.102876) (xy 111.319384 -150.18988) (xy 111.372873 -150.281191)
			(xy 111.419304 -150.376286) (xy 111.458409 -150.47462) (xy 111.489966 -150.575631) (xy 111.513793 -150.678738)
			(xy 111.529754 -150.783352) (xy 111.537758 -150.888874) (xy 111.538258 -150.941786) (xy 111.537758 -150.994698)
			(xy 111.529754 -151.10022) (xy 111.513793 -151.204834) (xy 111.489966 -151.307941) (xy 111.458409 -151.408952)
			(xy 111.419304 -151.507286) (xy 111.372873 -151.602381) (xy 111.319384 -151.693692) (xy 111.259142 -151.780696)
			(xy 111.192492 -151.862896) (xy 111.119817 -151.939819) (xy 111.041533 -152.011025) (xy 110.958087 -152.076107)
			(xy 110.869958 -152.134692) (xy 110.777651 -152.186444) (xy 110.681694 -152.231066) (xy 110.582637 -152.268304)
			(xy 110.481048 -152.297944) (xy 110.377508 -152.319815) (xy 110.272611 -152.333794) (xy 110.166957 -152.339799)
			(xy 110.061151 -152.337796) (xy 109.9558 -152.327797) (xy 109.851507 -152.309859) (xy 109.748869 -152.284085)
			(xy 109.648474 -152.250623) (xy 109.550897 -152.209663) (xy 109.456698 -152.161441) (xy 109.366415 -152.106234)
			(xy 109.280566 -152.044356) (xy 109.199643 -151.976163) (xy 109.124109 -151.902045) (xy 109.054397 -151.822427)
			(xy 108.990906 -151.737764) (xy 108.933999 -151.648543) (xy 108.884003 -151.555273) (xy 108.841205 -151.458489)
			(xy 108.805848 -151.358745) (xy 108.778137 -151.256613) (xy 108.758228 -151.152678) (xy 108.746238 -151.047535)
			(xy 108.742233 -150.941786) (xy 34.688915 -150.941786) (xy 34.755459 -151.05455) (xy 34.855186 -151.239273)
			(xy 34.947809 -151.427659) (xy 35.033193 -151.619434) (xy 35.111214 -151.814321) (xy 35.181759 -152.012037)
			(xy 35.244726 -152.212295) (xy 35.300023 -152.414805) (xy 35.34757 -152.619274) (xy 35.354948 -152.657556)
			(xy 115.368832 -152.657556) (xy 115.369254 -152.619267) (xy 115.375857 -152.542973) (xy 115.389002 -152.46753)
			(xy 115.40859 -152.393499) (xy 115.421156 -152.357328) (xy 115.423829 -152.348897) (xy 115.423815 -152.331221)
			(xy 115.421156 -152.322784) (xy 115.408624 -152.286603) (xy 115.389048 -152.212571) (xy 115.375898 -152.137132)
			(xy 115.36927 -152.060844) (xy 115.368832 -152.022556) (xy 115.369211 -151.981443) (xy 115.376803 -151.89957)
			(xy 115.391918 -151.818746) (xy 115.414428 -151.739662) (xy 115.44414 -151.662993) (xy 115.480801 -151.589393)
			(xy 115.524097 -151.51949) (xy 115.573659 -151.453881) (xy 115.629065 -151.393126) (xy 115.689841 -151.337743)
			(xy 115.755469 -151.288206) (xy 115.825388 -151.244936) (xy 115.899002 -151.208303) (xy 115.975683 -151.178621)
			(xy 116.054775 -151.156141) (xy 116.135605 -151.141056) (xy 116.217481 -151.133495) (xy 116.258594 -151.133048)
			(xy 116.29691 -151.133415) (xy 116.373264 -151.139947) (xy 116.448771 -151.153032) (xy 116.52287 -151.172572)
			(xy 116.559076 -151.185118) (xy 116.567392 -151.187704) (xy 116.584796 -151.187704) (xy 116.593112 -151.185118)
			(xy 116.629327 -151.172602) (xy 116.703427 -151.153078) (xy 116.778931 -151.139993) (xy 116.855279 -151.133443)
			(xy 116.893594 -151.133048) (xy 116.933808 -151.133478) (xy 117.01391 -151.140701) (xy 117.093031 -151.155132)
			(xy 117.170525 -151.176654) (xy 117.2083 -151.190452) (xy 117.217087 -151.193359) (xy 117.235581 -151.193359)
			(xy 117.244368 -151.190452) (xy 117.282145 -151.176662) (xy 117.359642 -151.155155) (xy 117.438762 -151.140723)
			(xy 117.518861 -151.133486) (xy 117.559074 -151.133048) (xy 117.59739 -151.133421) (xy 117.673744 -151.139951)
			(xy 117.74925 -151.153034) (xy 117.82335 -151.172573) (xy 117.859556 -151.185118) (xy 117.867872 -151.187704)
			(xy 117.885276 -151.187704) (xy 117.893592 -151.185118) (xy 117.929809 -151.172608) (xy 118.003908 -151.153082)
			(xy 118.079411 -151.139995) (xy 118.155759 -151.133444) (xy 118.194074 -151.133048) (xy 118.23239 -151.133421)
			(xy 118.308744 -151.139951) (xy 118.38425 -151.153034) (xy 118.45835 -151.172573) (xy 118.494556 -151.185118)
			(xy 118.502872 -151.187704) (xy 118.520276 -151.187704) (xy 118.528592 -151.185118) (xy 118.564809 -151.172608)
			(xy 118.638908 -151.153082) (xy 118.714411 -151.139995) (xy 118.790759 -151.133444) (xy 118.829074 -151.133048)
			(xy 118.86739 -151.133421) (xy 118.943744 -151.139951) (xy 119.01925 -151.153034) (xy 119.09335 -151.172573)
			(xy 119.129556 -151.185118) (xy 119.137872 -151.187704) (xy 119.155276 -151.187704) (xy 119.163592 -151.185118)
			(xy 119.199718 -151.172636) (xy 119.273629 -151.153143) (xy 119.348939 -151.140056) (xy 119.425093 -151.133472)
			(xy 119.463312 -151.133048) (xy 119.464074 -151.133048) (xy 119.505181 -151.133537) (xy 119.587043 -151.141119)
			(xy 119.667858 -151.156221) (xy 119.746934 -151.178714) (xy 119.823598 -151.208407) (xy 119.897196 -151.245045)
			(xy 119.9671 -151.288316) (xy 120.032714 -151.337852) (xy 120.093479 -151.39323) (xy 120.148875 -151.453978)
			(xy 120.198431 -151.519577) (xy 120.241724 -151.589468) (xy 120.278384 -151.663055) (xy 120.3081 -151.73971)
			(xy 120.330617 -151.818779) (xy 120.345743 -151.899589) (xy 120.35335 -151.98145) (xy 120.353836 -152.022556)
			(xy 120.353419 -152.060846) (xy 120.346814 -152.137139) (xy 120.333668 -152.212582) (xy 120.314078 -152.286613)
			(xy 120.301512 -152.322784) (xy 120.298884 -152.331226) (xy 120.29887 -152.348891) (xy 120.301512 -152.357328)
			(xy 120.314046 -152.393509) (xy 120.333622 -152.467541) (xy 120.346772 -152.542979) (xy 120.353399 -152.619268)
			(xy 120.353836 -152.657556) (xy 120.353306 -152.698665) (xy 120.345722 -152.780533) (xy 120.330616 -152.861351)
			(xy 120.308115 -152.940431) (xy 120.278413 -153.017096) (xy 120.241762 -153.090693) (xy 120.198476 -153.160594)
			(xy 120.148923 -153.226202) (xy 120.093528 -153.286957) (xy 120.032762 -153.34234) (xy 119.967144 -153.391879)
			(xy 119.897234 -153.435151) (xy 119.823629 -153.471786) (xy 119.746958 -153.501473) (xy 119.667874 -153.523957)
			(xy 119.587052 -153.539047) (xy 119.505183 -153.546614) (xy 119.464074 -153.547064) (xy 119.425757 -153.546706)
			(xy 119.349404 -153.540171) (xy 119.273897 -153.527084) (xy 119.199798 -153.507541) (xy 119.163592 -153.494994)
			(xy 119.155276 -153.492408) (xy 119.137872 -153.492408) (xy 119.129556 -153.494994) (xy 119.093344 -153.507519)
			(xy 119.019243 -153.527041) (xy 118.943738 -153.540123) (xy 118.867389 -153.546671) (xy 118.829074 -153.547064)
			(xy 118.790757 -153.546706) (xy 118.714404 -153.540171) (xy 118.638897 -153.527084) (xy 118.564798 -153.507541)
			(xy 118.528592 -153.494994) (xy 118.520276 -153.492408) (xy 118.502872 -153.492408) (xy 118.494556 -153.494994)
			(xy 118.458344 -153.507519) (xy 118.384243 -153.527041) (xy 118.308738 -153.540123) (xy 118.232389 -153.546671)
			(xy 118.194074 -153.547064) (xy 118.155757 -153.546706) (xy 118.079404 -153.540171) (xy 118.003897 -153.527084)
			(xy 117.929798 -153.507541) (xy 117.893592 -153.494994) (xy 117.885276 -153.492408) (xy 117.867872 -153.492408)
			(xy 117.859556 -153.494994) (xy 117.823344 -153.507519) (xy 117.749243 -153.527041) (xy 117.673738 -153.540123)
			(xy 117.597389 -153.546671) (xy 117.559074 -153.547064) (xy 117.51886 -153.546643) (xy 117.438758 -153.539418)
			(xy 117.359636 -153.524984) (xy 117.282143 -153.50346) (xy 117.244368 -153.48966) (xy 117.235581 -153.486753)
			(xy 117.217087 -153.486753) (xy 117.2083 -153.48966) (xy 117.170526 -153.50346) (xy 117.093029 -153.524965)
			(xy 117.013907 -153.539393) (xy 116.933807 -153.546627) (xy 116.893594 -153.547064) (xy 116.855277 -153.5467)
			(xy 116.778924 -153.540167) (xy 116.703417 -153.527082) (xy 116.629318 -153.50754) (xy 116.593112 -153.494994)
			(xy 116.584796 -153.492408) (xy 116.567392 -153.492408) (xy 116.559076 -153.494994) (xy 116.522953 -153.507485)
			(xy 116.449041 -153.526976) (xy 116.37373 -153.54006) (xy 116.297575 -153.546641) (xy 116.259356 -153.547064)
			(xy 116.258594 -153.547064) (xy 116.217487 -153.546593) (xy 116.135624 -153.539008) (xy 116.05481 -153.523904)
			(xy 115.975734 -153.501409) (xy 115.89907 -153.471714) (xy 115.825473 -153.435075) (xy 115.755569 -153.391802)
			(xy 115.689955 -153.342264) (xy 115.629192 -153.286885) (xy 115.573796 -153.226137) (xy 115.52424 -153.160537)
			(xy 115.480947 -153.090646) (xy 115.444287 -153.017059) (xy 115.414571 -152.940403) (xy 115.392053 -152.861333)
			(xy 115.376926 -152.780524) (xy 115.369318 -152.698663) (xy 115.368832 -152.657556) (xy 35.354948 -152.657556)
			(xy 35.387298 -152.825405) (xy 35.41915 -153.032898) (xy 35.44308 -153.241454) (xy 35.459052 -153.45077)
			(xy 35.467044 -153.660542) (xy 35.467544 -153.765504) (xy 35.467044 -153.870466) (xy 35.459052 -154.080238)
			(xy 35.44308 -154.289554) (xy 35.422918 -154.465274) (xy 127.823468 -154.465274) (xy 127.824038 -154.420505)
			(xy 127.833047 -154.33142) (xy 127.850949 -154.243689) (xy 127.877566 -154.158197) (xy 127.894588 -154.116786)
			(xy 127.89817 -154.1072) (xy 127.89816 -154.086753) (xy 127.894588 -154.077162) (xy 127.87754 -154.03576)
			(xy 127.850909 -153.95027) (xy 127.833008 -153.862535) (xy 127.824018 -153.773445) (xy 127.823468 -153.728674)
			(xy 127.824038 -153.683905) (xy 127.833047 -153.59482) (xy 127.850949 -153.507089) (xy 127.877566 -153.421597)
			(xy 127.894588 -153.380186) (xy 127.89817 -153.3706) (xy 127.89816 -153.350153) (xy 127.894588 -153.340562)
			(xy 127.87754 -153.29916) (xy 127.850909 -153.21367) (xy 127.833008 -153.125935) (xy 127.824018 -153.036845)
			(xy 127.823468 -152.992074) (xy 127.823874 -152.950958) (xy 127.831464 -152.869076) (xy 127.846576 -152.788245)
			(xy 127.869082 -152.709152) (xy 127.898791 -152.632473) (xy 127.935447 -152.558863) (xy 127.978739 -152.488949)
			(xy 128.028297 -152.423328) (xy 128.083699 -152.362559) (xy 128.144471 -152.307161) (xy 128.210095 -152.257607)
			(xy 128.280012 -152.21432) (xy 128.353625 -152.177668) (xy 128.430305 -152.147965) (xy 128.509399 -152.125463)
			(xy 128.590232 -152.110356) (xy 128.672114 -152.102771) (xy 128.71323 -152.102312) (xy 128.754841 -152.102773)
			(xy 128.837698 -152.110553) (xy 128.919467 -152.126031) (xy 128.999435 -152.149074) (xy 129.076903 -152.179479)
			(xy 129.151195 -152.216982) (xy 129.186686 -152.23871) (xy 129.195829 -152.243863) (xy 129.216542 -152.24708)
			(xy 129.236814 -152.241752) (xy 129.24536 -152.235662) (xy 129.278989 -152.209671) (xy 129.350383 -152.163546)
			(xy 129.425854 -152.124445) (xy 129.504712 -152.092724) (xy 129.586237 -152.068675) (xy 129.669685 -152.052515)
			(xy 129.754295 -152.044393) (xy 129.796794 -152.043892) (xy 129.837907 -152.044419) (xy 129.919782 -152.052005)
			(xy 130.000607 -152.067113) (xy 130.079694 -152.089613) (xy 130.156368 -152.119315) (xy 130.229974 -152.155965)
			(xy 130.299884 -152.19925) (xy 130.365503 -152.2488) (xy 130.42627 -152.304193) (xy 130.481667 -152.364957)
			(xy 130.531221 -152.430573) (xy 130.57451 -152.500481) (xy 130.611164 -152.574085) (xy 130.64087 -152.650756)
			(xy 130.663376 -152.729842) (xy 130.678488 -152.810667) (xy 130.686079 -152.892541) (xy 130.686556 -152.933654)
			(xy 130.685993 -152.978424) (xy 130.676983 -153.067509) (xy 130.659077 -153.15524) (xy 130.632459 -153.240731)
			(xy 130.615436 -153.282142) (xy 130.611899 -153.291741) (xy 130.611882 -153.312176) (xy 130.615436 -153.321766)
			(xy 130.63244 -153.363117) (xy 130.659051 -153.448479) (xy 130.676958 -153.536082) (xy 130.68598 -153.625039)
			(xy 130.686556 -153.669746) (xy 130.686556 -153.670762) (xy 130.686302 -153.682192) (xy 130.712781 -153.688138)
			(xy 130.765016 -153.702881) (xy 130.790696 -153.711656) (xy 130.798893 -153.71417) (xy 130.816027 -153.71417)
			(xy 130.824224 -153.711656) (xy 130.85944 -153.699695) (xy 130.931444 -153.681041) (xy 131.004765 -153.668532)
			(xy 131.07888 -153.662259) (xy 131.11607 -153.661872) (xy 131.153259 -153.662271) (xy 131.227372 -153.668558)
			(xy 131.300692 -153.681065) (xy 131.372698 -153.699703) (xy 131.407916 -153.711656) (xy 131.416113 -153.71417)
			(xy 131.433247 -153.71417) (xy 131.441444 -153.711656) (xy 131.476659 -153.699689) (xy 131.548662 -153.681037)
			(xy 131.621984 -153.66853) (xy 131.6961 -153.662258) (xy 131.73329 -153.661872) (xy 131.77523 -153.662267)
			(xy 131.858732 -153.670239) (xy 131.941097 -153.686113) (xy 132.02158 -153.709744) (xy 132.099453 -153.740919)
			(xy 132.165372 -153.774902) (xy 188.441847 -153.774902) (xy 188.445843 -153.565016) (xy 188.457828 -153.355434)
			(xy 188.477782 -153.14646) (xy 188.505678 -152.938398) (xy 188.541475 -152.731548) (xy 188.58512 -152.526211)
			(xy 188.636552 -152.322685) (xy 188.695694 -152.121264) (xy 188.762462 -151.922241) (xy 188.836758 -151.725904)
			(xy 188.918476 -151.532538) (xy 189.007495 -151.342423) (xy 189.103688 -151.155835) (xy 189.206915 -150.973044)
			(xy 189.317026 -150.794316) (xy 189.433861 -150.619909) (xy 189.557251 -150.450077) (xy 189.687018 -150.285065)
			(xy 189.822972 -150.125114) (xy 189.964918 -149.970454) (xy 190.112648 -149.82131) (xy 190.26595 -149.677899)
			(xy 190.4246 -149.540428) (xy 190.588369 -149.409096) (xy 190.757019 -149.284095) (xy 190.930305 -149.165604)
			(xy 191.107977 -149.053797) (xy 191.289777 -148.948835) (xy 191.475441 -148.85087) (xy 191.664699 -148.760045)
			(xy 191.857279 -148.676491) (xy 192.0529 -148.600328) (xy 192.251278 -148.531669) (xy 192.452127 -148.470612)
			(xy 192.655154 -148.417245) (xy 192.860067 -148.371647) (xy 193.066566 -148.333882) (xy 193.274353 -148.304007)
			(xy 193.483128 -148.282064) (xy 193.692586 -148.268085) (xy 193.902425 -148.26209) (xy 194.112339 -148.264089)
			(xy 194.322026 -148.274077) (xy 194.53118 -148.292042) (xy 194.739498 -148.317956) (xy 194.946679 -148.351781)
			(xy 195.152423 -148.39347) (xy 195.356429 -148.442962) (xy 195.558404 -148.500184) (xy 195.758054 -148.565054)
			(xy 195.955089 -148.637478) (xy 196.149225 -148.717351) (xy 196.340178 -148.804557) (xy 196.527674 -148.898969)
			(xy 196.711439 -149.000451) (xy 196.891207 -149.108855) (xy 197.066718 -149.224025) (xy 197.237717 -149.345793)
			(xy 197.403957 -149.473982) (xy 197.565196 -149.608408) (xy 197.7212 -149.748875) (xy 197.871743 -149.895179)
			(xy 198.016607 -150.047108) (xy 198.155582 -150.204442) (xy 198.288467 -150.366953) (xy 198.415068 -150.534406)
			(xy 198.535203 -150.706556) (xy 198.648697 -150.883156) (xy 198.755385 -151.063948) (xy 198.855112 -151.248671)
			(xy 198.947735 -151.437057) (xy 199.033119 -151.628832) (xy 199.11114 -151.823719) (xy 199.181685 -152.021435)
			(xy 199.244652 -152.221693) (xy 199.299949 -152.424203) (xy 199.347496 -152.628672) (xy 199.387224 -152.834803)
			(xy 199.419076 -153.042296) (xy 199.443006 -153.250852) (xy 199.458978 -153.460168) (xy 199.46697 -153.66994)
			(xy 199.467428 -153.766012) (xy 272.382243 -153.766012) (xy 272.386239 -153.556126) (xy 272.398224 -153.346544)
			(xy 272.418178 -153.13757) (xy 272.446074 -152.929508) (xy 272.481871 -152.722658) (xy 272.525516 -152.517321)
			(xy 272.576948 -152.313795) (xy 272.63609 -152.112374) (xy 272.702858 -151.913351) (xy 272.777154 -151.717014)
			(xy 272.858872 -151.523648) (xy 272.947891 -151.333533) (xy 273.044084 -151.146945) (xy 273.147311 -150.964154)
			(xy 273.257422 -150.785426) (xy 273.374257 -150.611019) (xy 273.497647 -150.441187) (xy 273.627414 -150.276175)
			(xy 273.763368 -150.116224) (xy 273.905314 -149.961564) (xy 274.053044 -149.81242) (xy 274.206346 -149.669009)
			(xy 274.364996 -149.531538) (xy 274.528765 -149.400206) (xy 274.697415 -149.275205) (xy 274.870701 -149.156714)
			(xy 275.048373 -149.044907) (xy 275.230173 -148.939945) (xy 275.415837 -148.84198) (xy 275.605095 -148.751155)
			(xy 275.797675 -148.667601) (xy 275.993296 -148.591438) (xy 276.191674 -148.522779) (xy 276.392523 -148.461722)
			(xy 276.59555 -148.408355) (xy 276.800463 -148.362757) (xy 277.006962 -148.324992) (xy 277.214749 -148.295117)
			(xy 277.423524 -148.273174) (xy 277.632982 -148.259195) (xy 277.842821 -148.2532) (xy 278.052735 -148.255199)
			(xy 278.262422 -148.265187) (xy 278.471576 -148.283152) (xy 278.679894 -148.309066) (xy 278.887075 -148.342891)
			(xy 279.092819 -148.38458) (xy 279.296825 -148.434072) (xy 279.4988 -148.491294) (xy 279.69845 -148.556164)
			(xy 279.895485 -148.628588) (xy 280.089621 -148.708461) (xy 280.280574 -148.795667) (xy 280.46807 -148.890079)
			(xy 280.651835 -148.991561) (xy 280.831603 -149.099965) (xy 281.007114 -149.215135) (xy 281.178113 -149.336903)
			(xy 281.344353 -149.465092) (xy 281.505592 -149.599518) (xy 281.661596 -149.739985) (xy 281.812139 -149.886289)
			(xy 281.957003 -150.038218) (xy 282.095978 -150.195552) (xy 282.228863 -150.358063) (xy 282.355464 -150.525516)
			(xy 282.475599 -150.697666) (xy 282.589093 -150.874266) (xy 282.695781 -151.055058) (xy 282.795508 -151.239781)
			(xy 282.888131 -151.428167) (xy 282.973515 -151.619942) (xy 283.051536 -151.814829) (xy 283.122081 -152.012545)
			(xy 283.185048 -152.212803) (xy 283.240345 -152.415313) (xy 283.287892 -152.619782) (xy 283.305746 -152.71242)
			(xy 358.186997 -152.71242) (xy 358.191002 -152.606671) (xy 358.202992 -152.501528) (xy 358.222901 -152.397593)
			(xy 358.250612 -152.295461) (xy 358.285969 -152.195717) (xy 358.328767 -152.098933) (xy 358.378763 -152.005663)
			(xy 358.43567 -151.916442) (xy 358.499161 -151.831779) (xy 358.568873 -151.752161) (xy 358.644407 -151.678043)
			(xy 358.72533 -151.60985) (xy 358.811179 -151.547972) (xy 358.901462 -151.492765) (xy 358.995661 -151.444543)
			(xy 359.093238 -151.403583) (xy 359.193633 -151.370121) (xy 359.296271 -151.344347) (xy 359.400564 -151.326409)
			(xy 359.505915 -151.31641) (xy 359.611721 -151.314407) (xy 359.717375 -151.320412) (xy 359.822272 -151.334391)
			(xy 359.925812 -151.356262) (xy 360.027401 -151.385902) (xy 360.126458 -151.42314) (xy 360.222415 -151.467762)
			(xy 360.314722 -151.519514) (xy 360.402851 -151.578099) (xy 360.486297 -151.643181) (xy 360.564581 -151.714387)
			(xy 360.637256 -151.79131) (xy 360.703906 -151.87351) (xy 360.764148 -151.960514) (xy 360.817637 -152.051825)
			(xy 360.864068 -152.14692) (xy 360.903173 -152.245254) (xy 360.93473 -152.346265) (xy 360.958557 -152.449372)
			(xy 360.974518 -152.553986) (xy 360.982522 -152.659508) (xy 360.983022 -152.71242) (xy 360.982522 -152.765332)
			(xy 360.974518 -152.870854) (xy 360.958557 -152.975468) (xy 360.93473 -153.078575) (xy 360.903173 -153.179586)
			(xy 360.864068 -153.27792) (xy 360.817637 -153.373015) (xy 360.764148 -153.464326) (xy 360.703906 -153.55133)
			(xy 360.637256 -153.63353) (xy 360.564581 -153.710453) (xy 360.486297 -153.781659) (xy 360.402851 -153.846741)
			(xy 360.314722 -153.905326) (xy 360.222415 -153.957078) (xy 360.126458 -154.0017) (xy 360.027401 -154.038938)
			(xy 359.925812 -154.068578) (xy 359.822272 -154.090449) (xy 359.717375 -154.104428) (xy 359.611721 -154.110433)
			(xy 359.505915 -154.10843) (xy 359.400564 -154.098431) (xy 359.296271 -154.080493) (xy 359.193633 -154.054719)
			(xy 359.093238 -154.021257) (xy 358.995661 -153.980297) (xy 358.901462 -153.932075) (xy 358.811179 -153.876868)
			(xy 358.72533 -153.81499) (xy 358.644407 -153.746797) (xy 358.568873 -153.672679) (xy 358.499161 -153.593061)
			(xy 358.43567 -153.508398) (xy 358.378763 -153.419177) (xy 358.328767 -153.325907) (xy 358.285969 -153.229123)
			(xy 358.250612 -153.129379) (xy 358.222901 -153.027247) (xy 358.202992 -152.923312) (xy 358.191002 -152.818169)
			(xy 358.186997 -152.71242) (xy 283.305746 -152.71242) (xy 283.32762 -152.825913) (xy 283.359472 -153.033406)
			(xy 283.383402 -153.241962) (xy 283.399374 -153.451278) (xy 283.407366 -153.66105) (xy 283.407866 -153.766012)
			(xy 283.407366 -153.870974) (xy 283.399374 -154.080746) (xy 283.383402 -154.290062) (xy 283.359472 -154.498618)
			(xy 283.32762 -154.706111) (xy 283.287892 -154.912242) (xy 283.240345 -155.116711) (xy 283.185048 -155.319221)
			(xy 283.122081 -155.519479) (xy 283.051536 -155.717195) (xy 282.973515 -155.912082) (xy 282.888131 -156.103857)
			(xy 282.795508 -156.292243) (xy 282.695781 -156.476966) (xy 282.589093 -156.657758) (xy 282.475599 -156.834358)
			(xy 282.355464 -157.006508) (xy 282.228863 -157.173961) (xy 282.095978 -157.336472) (xy 281.957003 -157.493806)
			(xy 281.812139 -157.645735) (xy 281.661596 -157.792039) (xy 281.505592 -157.932506) (xy 281.344353 -158.066932)
			(xy 281.178113 -158.195121) (xy 281.007114 -158.316889) (xy 280.831603 -158.432059) (xy 280.651835 -158.540463)
			(xy 280.46807 -158.641945) (xy 280.280574 -158.736357) (xy 280.089621 -158.823563) (xy 279.895485 -158.903436)
			(xy 279.69845 -158.97586) (xy 279.4988 -159.04073) (xy 279.382794 -159.073596) (xy 343.127076 -159.073596)
			(xy 343.127653 -159.028827) (xy 343.136659 -158.939742) (xy 343.15456 -158.852011) (xy 343.181175 -158.766519)
			(xy 343.198196 -158.725108) (xy 343.201765 -158.715518) (xy 343.201764 -158.695074) (xy 343.198196 -158.685484)
			(xy 343.181156 -158.644079) (xy 343.154522 -158.55859) (xy 343.136619 -158.470856) (xy 343.127627 -158.381767)
			(xy 343.127076 -158.336996) (xy 343.127653 -158.292227) (xy 343.136659 -158.203142) (xy 343.15456 -158.115411)
			(xy 343.181175 -158.029919) (xy 343.198196 -157.988508) (xy 343.201765 -157.978918) (xy 343.201764 -157.958474)
			(xy 343.198196 -157.948884) (xy 343.181156 -157.907479) (xy 343.154522 -157.82199) (xy 343.136619 -157.734256)
			(xy 343.127627 -157.645167) (xy 343.127076 -157.600396) (xy 343.127549 -157.559286) (xy 343.135137 -157.477416)
			(xy 343.150247 -157.396596) (xy 343.172752 -157.317516) (xy 343.202459 -157.240849) (xy 343.239114 -157.167252)
			(xy 343.282404 -157.097351) (xy 343.33196 -157.031743) (xy 343.387359 -156.970988) (xy 343.448129 -156.915605)
			(xy 343.51375 -156.866067) (xy 343.583663 -156.822796) (xy 343.657271 -156.786161) (xy 343.733945 -156.756475)
			(xy 343.813032 -156.733992) (xy 343.893856 -156.718903) (xy 343.975728 -156.711337) (xy 344.016838 -156.710888)
			(xy 344.058442 -156.711362) (xy 344.14129 -156.719094) (xy 344.223055 -156.734524) (xy 344.303022 -156.757517)
			(xy 344.380495 -156.787874) (xy 344.454797 -156.825328) (xy 344.490294 -156.847032) (xy 344.499434 -156.852189)
			(xy 344.520149 -156.855402) (xy 344.540422 -156.850073) (xy 344.548968 -156.843984) (xy 344.582592 -156.818029)
			(xy 344.653971 -156.771973) (xy 344.729414 -156.73293) (xy 344.808235 -156.701255) (xy 344.889716 -156.677237)
			(xy 344.973116 -156.661094) (xy 345.057674 -156.652974) (xy 345.100148 -156.652468) (xy 345.100402 -156.652468)
			(xy 345.14151 -156.652911) (xy 345.223374 -156.660496) (xy 345.30419 -156.6756) (xy 345.383268 -156.698096)
			(xy 345.459933 -156.727791) (xy 345.533532 -156.764433) (xy 345.603437 -156.807707) (xy 345.669051 -156.857246)
			(xy 345.729816 -156.912627) (xy 345.785212 -156.973378) (xy 345.806812 -157.001972) (xy 386.403596 -157.001972)
			(xy 386.40399 -156.963682) (xy 386.410601 -156.887387) (xy 386.423753 -156.811945) (xy 386.44335 -156.737915)
			(xy 386.45592 -156.701744) (xy 386.458586 -156.693311) (xy 386.458577 -156.675637) (xy 386.45592 -156.6672)
			(xy 386.443367 -156.631026) (xy 386.423796 -156.556991) (xy 386.410652 -156.481551) (xy 386.40403 -156.40526)
			(xy 386.403596 -156.366972) (xy 386.404015 -156.328179) (xy 386.410791 -156.25089) (xy 386.424264 -156.174482)
			(xy 386.44433 -156.099536) (xy 386.45719 -156.062934) (xy 386.459858 -156.054502) (xy 386.459846 -156.036827)
			(xy 386.45719 -156.02839) (xy 386.444324 -155.991789) (xy 386.424239 -155.916847) (xy 386.410766 -155.840438)
			(xy 386.404005 -155.763146) (xy 386.403596 -155.724352) (xy 386.404014 -155.686062) (xy 386.410618 -155.609769)
			(xy 386.423763 -155.534326) (xy 386.443354 -155.460295) (xy 386.45592 -155.424124) (xy 386.458596 -155.415693)
			(xy 386.45858 -155.398017) (xy 386.45592 -155.38958) (xy 386.443389 -155.353398) (xy 386.423812 -155.279367)
			(xy 386.410662 -155.203928) (xy 386.404034 -155.12764) (xy 386.403596 -155.089352) (xy 386.40407 -155.049438)
			(xy 386.411294 -154.969935) (xy 386.425601 -154.891398) (xy 386.446874 -154.814455) (xy 386.460492 -154.776932)
			(xy 386.463345 -154.768269) (xy 386.463329 -154.750041) (xy 386.460492 -154.741372) (xy 386.44684 -154.70386)
			(xy 386.425547 -154.626919) (xy 386.411244 -154.548377) (xy 386.404048 -154.468869) (xy 386.403596 -154.428952)
			(xy 386.404014 -154.390662) (xy 386.410618 -154.314369) (xy 386.423763 -154.238926) (xy 386.443354 -154.164895)
			(xy 386.45592 -154.128724) (xy 386.458596 -154.120293) (xy 386.45858 -154.102617) (xy 386.45592 -154.09418)
			(xy 386.443389 -154.057998) (xy 386.423812 -153.983967) (xy 386.410662 -153.908528) (xy 386.404034 -153.83224)
			(xy 386.403596 -153.793952) (xy 386.404007 -153.75284) (xy 386.411599 -153.670969) (xy 386.426714 -153.590147)
			(xy 386.449223 -153.511065) (xy 386.478934 -153.434397) (xy 386.515593 -153.360799) (xy 386.558887 -153.290897)
			(xy 386.608448 -153.225289) (xy 386.663851 -153.164535) (xy 386.724625 -153.109152) (xy 386.79025 -153.059614)
			(xy 386.860166 -153.016344) (xy 386.933777 -152.97971) (xy 387.010455 -152.950026) (xy 387.089545 -152.927544)
			(xy 387.170372 -152.912457) (xy 387.252246 -152.904893) (xy 387.293358 -152.904444) (xy 387.331674 -152.904822)
			(xy 387.408027 -152.91135) (xy 387.483534 -152.924432) (xy 387.557634 -152.94397) (xy 387.59384 -152.956514)
			(xy 387.602156 -152.9591) (xy 387.61956 -152.9591) (xy 387.627876 -152.956514) (xy 387.663994 -152.944008)
			(xy 387.737908 -152.924522) (xy 387.81322 -152.911442) (xy 387.889376 -152.904865) (xy 387.927596 -152.904444)
			(xy 387.928358 -152.904444) (xy 387.969464 -152.904953) (xy 388.051326 -152.912533) (xy 388.13214 -152.927634)
			(xy 388.211216 -152.950125) (xy 388.28788 -152.979816) (xy 388.361478 -153.016453) (xy 388.431382 -153.059723)
			(xy 388.496996 -153.109258) (xy 388.55776 -153.164634) (xy 388.613157 -153.225381) (xy 388.662713 -153.290979)
			(xy 388.706006 -153.360869) (xy 388.742667 -153.434454) (xy 388.772383 -153.511109) (xy 388.7949 -153.590177)
			(xy 388.810027 -153.670986) (xy 388.817634 -153.752846) (xy 388.817889 -153.774394) (xy 436.382169 -153.774394)
			(xy 436.386165 -153.564508) (xy 436.39815 -153.354926) (xy 436.418104 -153.145952) (xy 436.446 -152.93789)
			(xy 436.481797 -152.73104) (xy 436.525442 -152.525703) (xy 436.576874 -152.322177) (xy 436.636016 -152.120756)
			(xy 436.702784 -151.921733) (xy 436.77708 -151.725396) (xy 436.858798 -151.53203) (xy 436.947817 -151.341915)
			(xy 437.04401 -151.155327) (xy 437.147237 -150.972536) (xy 437.257348 -150.793808) (xy 437.374183 -150.619401)
			(xy 437.497573 -150.449569) (xy 437.62734 -150.284557) (xy 437.763294 -150.124606) (xy 437.90524 -149.969946)
			(xy 438.05297 -149.820802) (xy 438.206272 -149.677391) (xy 438.364922 -149.53992) (xy 438.528691 -149.408588)
			(xy 438.697341 -149.283587) (xy 438.870627 -149.165096) (xy 439.048299 -149.053289) (xy 439.230099 -148.948327)
			(xy 439.415763 -148.850362) (xy 439.605021 -148.759537) (xy 439.797601 -148.675983) (xy 439.993222 -148.59982)
			(xy 440.1916 -148.531161) (xy 440.392449 -148.470104) (xy 440.595476 -148.416737) (xy 440.800389 -148.371139)
			(xy 441.006888 -148.333374) (xy 441.214675 -148.303499) (xy 441.42345 -148.281556) (xy 441.632908 -148.267577)
			(xy 441.842747 -148.261582) (xy 442.052661 -148.263581) (xy 442.262348 -148.273569) (xy 442.471502 -148.291534)
			(xy 442.67982 -148.317448) (xy 442.887001 -148.351273) (xy 443.092745 -148.392962) (xy 443.296751 -148.442454)
			(xy 443.498726 -148.499676) (xy 443.698376 -148.564546) (xy 443.895411 -148.63697) (xy 444.089547 -148.716843)
			(xy 444.2805 -148.804049) (xy 444.467996 -148.898461) (xy 444.651761 -148.999943) (xy 444.831529 -149.108347)
			(xy 445.00704 -149.223517) (xy 445.178039 -149.345285) (xy 445.344279 -149.473474) (xy 445.505518 -149.6079)
			(xy 445.661522 -149.748367) (xy 445.812065 -149.894671) (xy 445.956929 -150.0466) (xy 446.095904 -150.203934)
			(xy 446.228789 -150.366445) (xy 446.35539 -150.533898) (xy 446.475525 -150.706048) (xy 446.589019 -150.882648)
			(xy 446.695707 -151.06344) (xy 446.795434 -151.248163) (xy 446.888057 -151.436549) (xy 446.973441 -151.628324)
			(xy 447.051462 -151.823211) (xy 447.122007 -152.020927) (xy 447.184974 -152.221185) (xy 447.240271 -152.423695)
			(xy 447.287818 -152.628164) (xy 447.327546 -152.834295) (xy 447.359398 -153.041788) (xy 447.383328 -153.250344)
			(xy 447.3993 -153.45966) (xy 447.407292 -153.669432) (xy 447.407792 -153.774394) (xy 447.407292 -153.879356)
			(xy 447.3993 -154.089128) (xy 447.383328 -154.298444) (xy 447.359398 -154.507) (xy 447.327546 -154.714493)
			(xy 447.287818 -154.920624) (xy 447.240271 -155.125093) (xy 447.184974 -155.327603) (xy 447.122007 -155.527861)
			(xy 447.051462 -155.725577) (xy 446.973441 -155.920464) (xy 446.888057 -156.112239) (xy 446.795434 -156.300625)
			(xy 446.695707 -156.485348) (xy 446.589019 -156.66614) (xy 446.475525 -156.84274) (xy 446.35539 -157.01489)
			(xy 446.228789 -157.182343) (xy 446.095904 -157.344854) (xy 445.956929 -157.502188) (xy 445.812065 -157.654117)
			(xy 445.661522 -157.800421) (xy 445.505518 -157.940888) (xy 445.344279 -158.075314) (xy 445.178039 -158.203503)
			(xy 445.00704 -158.325271) (xy 444.831529 -158.440441) (xy 444.651761 -158.548845) (xy 444.467996 -158.650327)
			(xy 444.2805 -158.744739) (xy 444.089547 -158.831945) (xy 443.895411 -158.911818) (xy 443.698376 -158.984242)
			(xy 443.498726 -159.049112) (xy 443.296751 -159.106334) (xy 443.092745 -159.155826) (xy 442.887001 -159.197515)
			(xy 442.67982 -159.23134) (xy 442.471502 -159.257254) (xy 442.262348 -159.275219) (xy 442.052661 -159.285207)
			(xy 441.842747 -159.287206) (xy 441.632908 -159.281211) (xy 441.42345 -159.267232) (xy 441.214675 -159.245289)
			(xy 441.006888 -159.215414) (xy 440.800389 -159.177649) (xy 440.595476 -159.132051) (xy 440.392449 -159.078684)
			(xy 440.1916 -159.017627) (xy 439.993222 -158.948968) (xy 439.797601 -158.872805) (xy 439.605021 -158.789251)
			(xy 439.415763 -158.698426) (xy 439.230099 -158.600461) (xy 439.048299 -158.495499) (xy 438.870627 -158.383692)
			(xy 438.697341 -158.265201) (xy 438.528691 -158.1402) (xy 438.364922 -158.008868) (xy 438.206272 -157.871397)
			(xy 438.05297 -157.727986) (xy 437.90524 -157.578842) (xy 437.763294 -157.424182) (xy 437.62734 -157.264231)
			(xy 437.497573 -157.099219) (xy 437.374183 -156.929387) (xy 437.257348 -156.75498) (xy 437.147237 -156.576252)
			(xy 437.04401 -156.393461) (xy 436.947817 -156.206873) (xy 436.858798 -156.016758) (xy 436.77708 -155.823392)
			(xy 436.702784 -155.627055) (xy 436.636016 -155.428032) (xy 436.576874 -155.226611) (xy 436.525442 -155.023085)
			(xy 436.481797 -154.817748) (xy 436.446 -154.610898) (xy 436.418104 -154.402836) (xy 436.39815 -154.193862)
			(xy 436.386165 -153.98428) (xy 436.382169 -153.774394) (xy 388.817889 -153.774394) (xy 388.81812 -153.793952)
			(xy 388.817702 -153.832242) (xy 388.811098 -153.908535) (xy 388.797953 -153.983978) (xy 388.778362 -154.058009)
			(xy 388.765796 -154.09418) (xy 388.763168 -154.102623) (xy 388.763152 -154.120288) (xy 388.765796 -154.128724)
			(xy 388.778328 -154.164905) (xy 388.797905 -154.238937) (xy 388.811055 -154.314375) (xy 388.817683 -154.390664)
			(xy 388.81812 -154.428952) (xy 388.817646 -154.468866) (xy 388.810422 -154.548369) (xy 388.796115 -154.626906)
			(xy 388.774842 -154.703849) (xy 388.761224 -154.741372) (xy 388.758419 -154.750047) (xy 388.758403 -154.768264)
			(xy 388.761224 -154.776932) (xy 388.774878 -154.814443) (xy 388.79617 -154.891385) (xy 388.810472 -154.969927)
			(xy 388.817668 -155.049435) (xy 388.81812 -155.089352) (xy 388.817702 -155.127642) (xy 388.811098 -155.203935)
			(xy 388.797953 -155.279378) (xy 388.778362 -155.353409) (xy 388.765796 -155.38958) (xy 388.763168 -155.398023)
			(xy 388.763152 -155.415688) (xy 388.765796 -155.424124) (xy 388.778328 -155.460305) (xy 388.797905 -155.534337)
			(xy 388.811055 -155.609775) (xy 388.817683 -155.686064) (xy 388.81812 -155.724352) (xy 388.817677 -155.763144)
			(xy 388.810908 -155.840433) (xy 388.797442 -155.916841) (xy 388.777382 -155.991787) (xy 388.764526 -156.02839)
			(xy 388.761895 -156.036832) (xy 388.761883 -156.054497) (xy 388.764526 -156.062934) (xy 388.7774 -156.099532)
			(xy 388.797482 -156.174476) (xy 388.810953 -156.250885) (xy 388.817712 -156.328178) (xy 388.81812 -156.366972)
			(xy 388.817708 -156.405262) (xy 388.811103 -156.481556) (xy 388.797955 -156.556998) (xy 388.778363 -156.631029)
			(xy 388.765796 -156.6672) (xy 388.763157 -156.67564) (xy 388.763148 -156.693308) (xy 388.765796 -156.701744)
			(xy 388.778334 -156.737923) (xy 388.797909 -156.811956) (xy 388.811058 -156.887395) (xy 388.817683 -156.963684)
			(xy 388.81812 -157.001972) (xy 388.817621 -157.043082) (xy 388.810036 -157.124951) (xy 388.794928 -157.20577)
			(xy 388.772425 -157.284851) (xy 388.742721 -157.361517) (xy 388.706068 -157.435115) (xy 388.66278 -157.505016)
			(xy 388.613226 -157.570624) (xy 388.557828 -157.631379) (xy 388.49706 -157.686762) (xy 388.43144 -157.736301)
			(xy 388.361528 -157.779573) (xy 388.287921 -157.816208) (xy 388.211248 -157.845893) (xy 388.132162 -157.868377)
			(xy 388.051339 -157.883465) (xy 387.969468 -157.891031) (xy 387.928358 -157.89148) (xy 387.890041 -157.891126)
			(xy 387.813688 -157.88459) (xy 387.738181 -157.871501) (xy 387.664082 -157.851957) (xy 387.627876 -157.83941)
			(xy 387.61956 -157.836824) (xy 387.602156 -157.836824) (xy 387.59384 -157.83941) (xy 387.557721 -157.851912)
			(xy 387.483807 -157.871399) (xy 387.408495 -157.88448) (xy 387.33234 -157.891059) (xy 387.29412 -157.89148)
			(xy 387.293358 -157.89148) (xy 387.252251 -157.891028) (xy 387.170388 -157.88344) (xy 387.089574 -157.868332)
			(xy 387.010498 -157.845835) (xy 386.933835 -157.816138) (xy 386.860238 -157.779497) (xy 386.790335 -157.736222)
			(xy 386.724722 -157.686684) (xy 386.663959 -157.631304) (xy 386.608563 -157.570555) (xy 386.559008 -157.504955)
			(xy 386.515715 -157.435063) (xy 386.479055 -157.361475) (xy 386.449338 -157.28482) (xy 386.42682 -157.20575)
			(xy 386.411692 -157.12494) (xy 386.404083 -157.043079) (xy 386.403596 -157.001972) (xy 345.806812 -157.001972)
			(xy 345.834767 -157.03898) (xy 345.878059 -157.108874) (xy 345.914719 -157.182463) (xy 345.944433 -157.259121)
			(xy 345.966949 -157.338193) (xy 345.982074 -157.419006) (xy 345.989679 -157.500868) (xy 345.990164 -157.541976)
			(xy 345.989609 -157.586746) (xy 345.980596 -157.675831) (xy 345.962689 -157.763562) (xy 345.936068 -157.849053)
			(xy 345.919044 -157.890464) (xy 345.915494 -157.900059) (xy 345.915485 -157.920497) (xy 345.919044 -157.930088)
			(xy 345.936056 -157.971436) (xy 345.962665 -158.056799) (xy 345.980569 -158.144403) (xy 345.989589 -158.233361)
			(xy 345.990164 -158.278068) (xy 345.990164 -158.279084) (xy 345.98991 -158.290514) (xy 346.016389 -158.296459)
			(xy 346.068624 -158.311202) (xy 346.094304 -158.319978) (xy 346.102501 -158.322492) (xy 346.119635 -158.322492)
			(xy 346.127832 -158.319978) (xy 346.163048 -158.308033) (xy 346.235059 -158.289446) (xy 346.308381 -158.277006)
			(xy 346.382492 -158.2708) (xy 346.419678 -158.270448) (xy 346.456862 -158.27082) (xy 346.53097 -158.277041)
			(xy 346.60429 -158.289483) (xy 346.676301 -158.308056) (xy 346.711524 -158.319978) (xy 346.719721 -158.322492)
			(xy 346.736855 -158.322492) (xy 346.745052 -158.319978) (xy 346.780146 -158.308069) (xy 346.851906 -158.289524)
			(xy 346.924971 -158.277084) (xy 346.998824 -158.270837) (xy 347.035882 -158.270448) (xy 347.036898 -158.270448)
			(xy 347.078822 -158.270999) (xy 347.162292 -158.278969) (xy 347.244625 -158.294837) (xy 347.325078 -158.31846)
			(xy 347.40292 -158.349624) (xy 347.477448 -158.388045) (xy 347.547987 -158.433377) (xy 347.613896 -158.485209)
			(xy 347.674581 -158.543071) (xy 347.72949 -158.60644) (xy 347.778127 -158.674741) (xy 347.820052 -158.747357)
			(xy 347.854884 -158.823628) (xy 347.882308 -158.902865) (xy 347.902076 -158.984351) (xy 347.914009 -159.067346)
			(xy 347.917999 -159.1511) (xy 347.914009 -159.234854) (xy 347.902076 -159.317849) (xy 347.882308 -159.399335)
			(xy 347.854884 -159.478572) (xy 347.820052 -159.554843) (xy 347.778127 -159.627459) (xy 347.72949 -159.69576)
			(xy 347.674581 -159.759129) (xy 347.613896 -159.816991) (xy 347.547987 -159.868823) (xy 347.477448 -159.914155)
			(xy 347.40292 -159.952576) (xy 347.325078 -159.98374) (xy 347.244625 -160.007363) (xy 347.162292 -160.023231)
			(xy 347.078822 -160.031201) (xy 347.036898 -160.031684) (xy 347.035882 -160.031684) (xy 346.998825 -160.031285)
			(xy 346.924976 -160.025019) (xy 346.851913 -160.012575) (xy 346.780153 -159.994041) (xy 346.745052 -159.982154)
			(xy 346.736855 -159.97964) (xy 346.719721 -159.97964) (xy 346.711524 -159.982154) (xy 346.684116 -159.991499)
			(xy 346.628318 -160.007008) (xy 346.600018 -160.013142) (xy 346.590235 -160.015622) (xy 346.573598 -160.027019)
			(xy 346.562626 -160.04394) (xy 346.560394 -160.053782) (xy 346.550929 -160.102889) (xy 346.522417 -160.19875)
			(xy 346.503498 -160.245044) (xy 346.499892 -160.254619) (xy 346.499745 -160.275056) (xy 346.503244 -160.284668)
			(xy 346.520278 -160.326041) (xy 346.546893 -160.41147) (xy 346.564794 -160.499139) (xy 346.5738 -160.588163)
			(xy 346.574364 -160.632902) (xy 346.574364 -160.633156) (xy 346.57386 -160.675504) (xy 346.565809 -160.759818)
			(xy 346.54978 -160.842984) (xy 346.525919 -160.924251) (xy 346.49444 -161.002881) (xy 346.455629 -161.078162)
			(xy 346.409839 -161.149414) (xy 346.357483 -161.21599) (xy 346.299035 -161.277288) (xy 346.235025 -161.332753)
			(xy 346.166033 -161.381882) (xy 346.092683 -161.424231) (xy 346.01564 -161.459415) (xy 345.935601 -161.487117)
			(xy 345.853292 -161.507085) (xy 345.769457 -161.519138) (xy 345.684856 -161.523169) (xy 345.600255 -161.519138)
			(xy 345.51642 -161.507085) (xy 345.434111 -161.487117) (xy 345.354072 -161.459415) (xy 345.277029 -161.424231)
			(xy 345.203679 -161.381882) (xy 345.134687 -161.332753) (xy 345.070677 -161.277288) (xy 345.012229 -161.21599)
			(xy 344.959873 -161.149414) (xy 344.914083 -161.078162) (xy 344.875272 -161.002881) (xy 344.843793 -160.924251)
			(xy 344.819932 -160.842984) (xy 344.803903 -160.759818) (xy 344.795852 -160.675504) (xy 344.795348 -160.633156)
			(xy 344.795348 -160.632902) (xy 344.795938 -160.588164) (xy 344.804948 -160.499143) (xy 344.822847 -160.411476)
			(xy 344.849453 -160.326048) (xy 344.866468 -160.284668) (xy 344.870056 -160.275084) (xy 344.87004 -160.254635)
			(xy 344.866468 -160.245044) (xy 344.849433 -160.203637) (xy 344.822801 -160.118148) (xy 344.804897 -160.030415)
			(xy 344.795901 -159.941327) (xy 344.795348 -159.896556) (xy 344.795678 -159.859467) (xy 344.801776 -159.78554)
			(xy 344.814009 -159.712377) (xy 344.82278 -159.676338) (xy 344.824538 -159.668008) (xy 344.823098 -159.651057)
			(xy 344.816174 -159.635517) (xy 344.810588 -159.629094) (xy 344.770202 -159.586168) (xy 344.758264 -159.588708)
			(xy 344.749364 -159.591023) (xy 344.733871 -159.600904) (xy 344.728038 -159.608012) (xy 344.702891 -159.640664)
			(xy 344.647483 -159.701681) (xy 344.586669 -159.757312) (xy 344.520971 -159.807081) (xy 344.450952 -159.850561)
			(xy 344.377213 -159.887379) (xy 344.300384 -159.917221) (xy 344.221125 -159.93983) (xy 344.140115 -159.955012)
			(xy 344.058048 -159.962637) (xy 344.016838 -159.963104) (xy 343.975733 -159.962551) (xy 343.893874 -159.954971)
			(xy 343.813062 -159.939871) (xy 343.733989 -159.917381) (xy 343.657327 -159.887692) (xy 343.583731 -159.851057)
			(xy 343.513829 -159.807789) (xy 343.448216 -159.758257) (xy 343.387452 -159.702884) (xy 343.332056 -159.642141)
			(xy 343.2825 -159.576547) (xy 343.239206 -159.506661) (xy 343.202543 -159.433078) (xy 343.172826 -159.356428)
			(xy 343.150306 -159.277363) (xy 343.135175 -159.196557) (xy 343.127564 -159.114701) (xy 343.127076 -159.073596)
			(xy 279.382794 -159.073596) (xy 279.296825 -159.097952) (xy 279.092819 -159.147444) (xy 278.887075 -159.189133)
			(xy 278.679894 -159.222958) (xy 278.471576 -159.248872) (xy 278.262422 -159.266837) (xy 278.052735 -159.276825)
			(xy 277.842821 -159.278824) (xy 277.632982 -159.272829) (xy 277.423524 -159.25885) (xy 277.214749 -159.236907)
			(xy 277.006962 -159.207032) (xy 276.800463 -159.169267) (xy 276.59555 -159.123669) (xy 276.392523 -159.070302)
			(xy 276.191674 -159.009245) (xy 275.993296 -158.940586) (xy 275.797675 -158.864423) (xy 275.605095 -158.780869)
			(xy 275.415837 -158.690044) (xy 275.230173 -158.592079) (xy 275.048373 -158.487117) (xy 274.870701 -158.37531)
			(xy 274.697415 -158.256819) (xy 274.528765 -158.131818) (xy 274.364996 -158.000486) (xy 274.206346 -157.863015)
			(xy 274.053044 -157.719604) (xy 273.905314 -157.57046) (xy 273.763368 -157.4158) (xy 273.627414 -157.255849)
			(xy 273.497647 -157.090837) (xy 273.374257 -156.921005) (xy 273.257422 -156.746598) (xy 273.147311 -156.56787)
			(xy 273.044084 -156.385079) (xy 272.947891 -156.198491) (xy 272.858872 -156.008376) (xy 272.777154 -155.81501)
			(xy 272.702858 -155.618673) (xy 272.63609 -155.41965) (xy 272.576948 -155.218229) (xy 272.525516 -155.014703)
			(xy 272.481871 -154.809366) (xy 272.446074 -154.602516) (xy 272.418178 -154.394454) (xy 272.398224 -154.18548)
			(xy 272.386239 -153.975898) (xy 272.382243 -153.766012) (xy 199.467428 -153.766012) (xy 199.46747 -153.774902)
			(xy 199.46697 -153.879864) (xy 199.458978 -154.089636) (xy 199.443006 -154.298952) (xy 199.419076 -154.507508)
			(xy 199.387224 -154.715001) (xy 199.347496 -154.921132) (xy 199.299949 -155.125601) (xy 199.244652 -155.328111)
			(xy 199.181685 -155.528369) (xy 199.11114 -155.726085) (xy 199.033119 -155.920972) (xy 198.947735 -156.112747)
			(xy 198.855112 -156.301133) (xy 198.755385 -156.485856) (xy 198.648697 -156.666648) (xy 198.535203 -156.843248)
			(xy 198.415068 -157.015398) (xy 198.288467 -157.182851) (xy 198.155582 -157.345362) (xy 198.016607 -157.502696)
			(xy 197.871743 -157.654625) (xy 197.7212 -157.800929) (xy 197.565196 -157.941396) (xy 197.403957 -158.075822)
			(xy 197.237717 -158.204011) (xy 197.066718 -158.325779) (xy 196.891207 -158.440949) (xy 196.711439 -158.549353)
			(xy 196.527674 -158.650835) (xy 196.340178 -158.745247) (xy 196.149225 -158.832453) (xy 195.955089 -158.912326)
			(xy 195.758054 -158.98475) (xy 195.558404 -159.04962) (xy 195.356429 -159.106842) (xy 195.152423 -159.156334)
			(xy 194.946679 -159.198023) (xy 194.739498 -159.231848) (xy 194.53118 -159.257762) (xy 194.322026 -159.275727)
			(xy 194.112339 -159.285715) (xy 193.902425 -159.287714) (xy 193.692586 -159.281719) (xy 193.483128 -159.26774)
			(xy 193.274353 -159.245797) (xy 193.066566 -159.215922) (xy 192.860067 -159.178157) (xy 192.655154 -159.132559)
			(xy 192.452127 -159.079192) (xy 192.251278 -159.018135) (xy 192.0529 -158.949476) (xy 191.857279 -158.873313)
			(xy 191.664699 -158.789759) (xy 191.475441 -158.698934) (xy 191.289777 -158.600969) (xy 191.107977 -158.496007)
			(xy 190.930305 -158.3842) (xy 190.757019 -158.265709) (xy 190.588369 -158.140708) (xy 190.4246 -158.009376)
			(xy 190.26595 -157.871905) (xy 190.112648 -157.728494) (xy 189.964918 -157.57935) (xy 189.822972 -157.42469)
			(xy 189.687018 -157.264739) (xy 189.557251 -157.099727) (xy 189.433861 -156.929895) (xy 189.317026 -156.755488)
			(xy 189.206915 -156.57676) (xy 189.103688 -156.393969) (xy 189.007495 -156.207381) (xy 188.918476 -156.017266)
			(xy 188.836758 -155.8239) (xy 188.762462 -155.627563) (xy 188.695694 -155.42854) (xy 188.636552 -155.227119)
			(xy 188.58512 -155.023593) (xy 188.541475 -154.818256) (xy 188.505678 -154.611406) (xy 188.477782 -154.403344)
			(xy 188.457828 -154.19437) (xy 188.445843 -153.984788) (xy 188.441847 -153.774902) (xy 132.165372 -153.774902)
			(xy 132.17401 -153.779355) (xy 132.244575 -153.824704) (xy 132.31051 -153.876555) (xy 132.371218 -153.934439)
			(xy 132.426149 -153.997832) (xy 132.474805 -154.066159) (xy 132.516746 -154.138802) (xy 132.551591 -154.215103)
			(xy 132.579026 -154.29437) (xy 132.598802 -154.375887) (xy 132.61074 -154.458914) (xy 132.614731 -154.5427)
			(xy 132.61074 -154.626486) (xy 132.598802 -154.709513) (xy 132.579026 -154.79103) (xy 132.551591 -154.870297)
			(xy 132.516746 -154.946598) (xy 132.474805 -155.019241) (xy 132.426149 -155.087568) (xy 132.371218 -155.150961)
			(xy 132.31051 -155.208845) (xy 132.244575 -155.260696) (xy 132.17401 -155.306045) (xy 132.099453 -155.344481)
			(xy 132.02158 -155.375656) (xy 131.941097 -155.399287) (xy 131.858732 -155.415161) (xy 131.77523 -155.423133)
			(xy 131.73329 -155.423616) (xy 131.6961 -155.423229) (xy 131.621987 -155.416939) (xy 131.548668 -155.404428)
			(xy 131.476662 -155.385787) (xy 131.441444 -155.373832) (xy 131.433247 -155.371318) (xy 131.416113 -155.371318)
			(xy 131.407916 -155.373832) (xy 131.374578 -155.385154) (xy 131.306486 -155.403082) (xy 131.237181 -155.41552)
			(xy 131.202176 -155.419298) (xy 131.192163 -155.420682) (xy 131.174401 -155.43031) (xy 131.161723 -155.446041)
			(xy 131.158488 -155.45562) (xy 131.151035 -155.480306) (xy 131.133624 -155.528851) (xy 131.12369 -155.552648)
			(xy 131.120082 -155.562222) (xy 131.119936 -155.58266) (xy 131.123436 -155.592272) (xy 131.140471 -155.633645)
			(xy 131.167086 -155.719073) (xy 131.184987 -155.806743) (xy 131.193992 -155.895767) (xy 131.194556 -155.940506)
			(xy 131.194556 -155.94076) (xy 131.194052 -155.983108) (xy 131.186001 -156.067422) (xy 131.169972 -156.150588)
			(xy 131.146111 -156.231855) (xy 131.114632 -156.310485) (xy 131.075821 -156.385766) (xy 131.030031 -156.457018)
			(xy 130.977675 -156.523594) (xy 130.919227 -156.584892) (xy 130.855217 -156.640357) (xy 130.786225 -156.689486)
			(xy 130.712875 -156.731835) (xy 130.635832 -156.767019) (xy 130.555793 -156.794721) (xy 130.473484 -156.814689)
			(xy 130.389649 -156.826742) (xy 130.305048 -156.830773) (xy 130.220447 -156.826742) (xy 130.136612 -156.814689)
			(xy 130.054303 -156.794721) (xy 129.974264 -156.767019) (xy 129.897221 -156.731835) (xy 129.823871 -156.689486)
			(xy 129.754879 -156.640357) (xy 129.690869 -156.584892) (xy 129.632421 -156.523594) (xy 129.580065 -156.457018)
			(xy 129.534275 -156.385766) (xy 129.495464 -156.310485) (xy 129.463985 -156.231855) (xy 129.440124 -156.150588)
			(xy 129.424095 -156.067422) (xy 129.416044 -155.983108) (xy 129.41554 -155.94076) (xy 129.41554 -155.940506)
			(xy 129.416091 -155.895767) (xy 129.425111 -155.806745) (xy 129.443021 -155.719078) (xy 129.46964 -155.633651)
			(xy 129.48666 -155.592272) (xy 129.490247 -155.582688) (xy 129.490232 -155.562239) (xy 129.48666 -155.552648)
			(xy 129.471663 -155.516314) (xy 129.447353 -155.441557) (xy 129.429731 -155.364948) (xy 129.418932 -155.287083)
			(xy 129.416556 -155.247848) (xy 129.415794 -155.233878) (xy 129.400046 -155.21051) (xy 129.29235 -155.160472)
			(xy 129.264664 -155.16352) (xy 129.253234 -155.172156) (xy 129.220015 -155.196974) (xy 129.149739 -155.241)
			(xy 129.075668 -155.27829) (xy 128.998447 -155.308521) (xy 128.918747 -155.33143) (xy 128.83726 -155.346818)
			(xy 128.754694 -155.354552) (xy 128.71323 -155.355036) (xy 128.672115 -155.354573) (xy 128.590235 -155.346988)
			(xy 128.509404 -155.33188) (xy 128.430313 -155.309379) (xy 128.353635 -155.279675) (xy 128.280025 -155.243023)
			(xy 128.210111 -155.199735) (xy 128.144489 -155.150181) (xy 128.08372 -155.094783) (xy 128.028322 -155.034014)
			(xy 127.978767 -154.968393) (xy 127.935479 -154.898479) (xy 127.898826 -154.824869) (xy 127.869122 -154.748191)
			(xy 127.84662 -154.669099) (xy 127.831512 -154.588269) (xy 127.823927 -154.506389) (xy 127.823468 -154.465274)
			(xy 35.422918 -154.465274) (xy 35.41915 -154.49811) (xy 35.387298 -154.705603) (xy 35.34757 -154.911734)
			(xy 35.300023 -155.116203) (xy 35.244726 -155.318713) (xy 35.181759 -155.518971) (xy 35.111214 -155.716687)
			(xy 35.033193 -155.911574) (xy 34.947809 -156.103349) (xy 34.855186 -156.291735) (xy 34.755459 -156.476458)
			(xy 34.648771 -156.65725) (xy 34.535277 -156.83385) (xy 34.415142 -157.006) (xy 34.288541 -157.173453)
			(xy 34.155656 -157.335964) (xy 34.016681 -157.493298) (xy 33.871817 -157.645227) (xy 33.721274 -157.791531)
			(xy 33.56527 -157.931998) (xy 33.404031 -158.066424) (xy 33.237791 -158.194613) (xy 33.066792 -158.316381)
			(xy 32.891281 -158.431551) (xy 32.711513 -158.539955) (xy 32.527748 -158.641437) (xy 32.340252 -158.735849)
			(xy 32.149299 -158.823055) (xy 31.955163 -158.902928) (xy 31.758128 -158.975352) (xy 31.558478 -159.040222)
			(xy 31.356503 -159.097444) (xy 31.152497 -159.146936) (xy 30.946753 -159.188625) (xy 30.739572 -159.22245)
			(xy 30.531254 -159.248364) (xy 30.3221 -159.266329) (xy 30.112413 -159.276317) (xy 29.902499 -159.278316)
			(xy 29.69266 -159.272321) (xy 29.483202 -159.258342) (xy 29.274427 -159.236399) (xy 29.06664 -159.206524)
			(xy 28.860141 -159.168759) (xy 28.655228 -159.123161) (xy 28.452201 -159.069794) (xy 28.251352 -159.008737)
			(xy 28.052974 -158.940078) (xy 27.857353 -158.863915) (xy 27.664773 -158.780361) (xy 27.475515 -158.689536)
			(xy 27.289851 -158.591571) (xy 27.108051 -158.486609) (xy 26.930379 -158.374802) (xy 26.757093 -158.256311)
			(xy 26.588443 -158.13131) (xy 26.424674 -157.999978) (xy 26.266024 -157.862507) (xy 26.112722 -157.719096)
			(xy 25.964992 -157.569952) (xy 25.823046 -157.415292) (xy 25.687092 -157.255341) (xy 25.557325 -157.090329)
			(xy 25.433935 -156.920497) (xy 25.3171 -156.74609) (xy 25.206989 -156.567362) (xy 25.103762 -156.384571)
			(xy 25.007569 -156.197983) (xy 24.91855 -156.007868) (xy 24.836832 -155.814502) (xy 24.762536 -155.618165)
			(xy 24.695768 -155.419142) (xy 24.636626 -155.217721) (xy 24.585194 -155.014195) (xy 24.541549 -154.808858)
			(xy 24.505752 -154.602008) (xy 24.477856 -154.393946) (xy 24.457902 -154.184972) (xy 24.445917 -153.97539)
			(xy 24.441921 -153.765504) (xy 2.509012 -153.765504) (xy 2.509012 -164.097716) (xy 86.129368 -164.097716)
			(xy 86.129877 -164.05494) (xy 86.138089 -163.969783) (xy 86.154448 -163.88581) (xy 86.178803 -163.803797)
			(xy 86.194392 -163.76396) (xy 86.19746 -163.755511) (xy 86.19811 -163.737557) (xy 86.195662 -163.728908)
			(xy 86.181097 -163.683434) (xy 86.160666 -163.590154) (xy 86.150355 -163.495221) (xy 86.149688 -163.447476)
			(xy 86.150084 -163.409186) (xy 86.156694 -163.332892) (xy 86.169846 -163.257449) (xy 86.189443 -163.183419)
			(xy 86.202012 -163.147248) (xy 86.204676 -163.138815) (xy 86.204669 -163.121141) (xy 86.202012 -163.112704)
			(xy 86.18946 -163.076529) (xy 86.169889 -163.002495) (xy 86.156744 -162.927055) (xy 86.150122 -162.850764)
			(xy 86.149688 -162.812476) (xy 86.15013 -162.771365) (xy 86.157719 -162.689494) (xy 86.172832 -162.608673)
			(xy 86.195339 -162.529592) (xy 86.225048 -162.452925) (xy 86.261705 -162.379327) (xy 86.304997 -162.309425)
			(xy 86.354555 -162.243817) (xy 86.409957 -162.183063) (xy 86.470728 -162.12768) (xy 86.536351 -162.078142)
			(xy 86.606266 -162.034871) (xy 86.679876 -161.998237) (xy 86.756552 -161.968552) (xy 86.83564 -161.94607)
			(xy 86.916466 -161.930982) (xy 86.998339 -161.923417) (xy 87.03945 -161.922968) (xy 87.077766 -161.923352)
			(xy 87.154119 -161.92988) (xy 87.229626 -161.94296) (xy 87.303725 -161.962495) (xy 87.339932 -161.975038)
			(xy 87.348248 -161.977624) (xy 87.365652 -161.977624) (xy 87.373968 -161.975038) (xy 87.410177 -161.962503)
			(xy 87.484279 -161.942985) (xy 87.559785 -161.929905) (xy 87.636135 -161.92336) (xy 87.67445 -161.922968)
			(xy 87.712766 -161.923352) (xy 87.789119 -161.92988) (xy 87.864626 -161.94296) (xy 87.938725 -161.962495)
			(xy 87.974932 -161.975038) (xy 87.983248 -161.977624) (xy 88.000652 -161.977624) (xy 88.008968 -161.975038)
			(xy 88.045177 -161.962503) (xy 88.119279 -161.942985) (xy 88.194785 -161.929905) (xy 88.271135 -161.92336)
			(xy 88.30945 -161.922968) (xy 88.347766 -161.923352) (xy 88.424119 -161.92988) (xy 88.499626 -161.94296)
			(xy 88.573725 -161.962495) (xy 88.609932 -161.975038) (xy 88.618248 -161.977624) (xy 88.635652 -161.977624)
			(xy 88.643968 -161.975038) (xy 88.680177 -161.962503) (xy 88.754279 -161.942985) (xy 88.829785 -161.929905)
			(xy 88.906135 -161.92336) (xy 88.94445 -161.922968) (xy 88.982766 -161.923352) (xy 89.059119 -161.92988)
			(xy 89.134626 -161.94296) (xy 89.208725 -161.962495) (xy 89.244932 -161.975038) (xy 89.253248 -161.977624)
			(xy 89.270652 -161.977624) (xy 89.278968 -161.975038) (xy 89.315177 -161.962503) (xy 89.389279 -161.942985)
			(xy 89.464785 -161.929905) (xy 89.541135 -161.92336) (xy 89.57945 -161.922968) (xy 89.62106 -161.923438)
			(xy 89.703917 -161.931201) (xy 89.785687 -161.946663) (xy 89.865658 -161.96969) (xy 89.90457 -161.984436)
			(xy 89.913248 -161.987466) (xy 89.931617 -161.98771) (xy 89.940384 -161.984944) (xy 89.976385 -161.972506)
			(xy 90.050053 -161.953122) (xy 90.125108 -161.940106) (xy 90.201001 -161.933552) (xy 90.239088 -161.933128)
			(xy 90.23985 -161.933128) (xy 90.280956 -161.93366) (xy 90.362817 -161.94124) (xy 90.443629 -161.956339)
			(xy 90.522705 -161.97883) (xy 90.599368 -162.008519) (xy 90.672965 -162.045155) (xy 90.742868 -162.088423)
			(xy 90.808482 -162.137957) (xy 90.869246 -162.193332) (xy 90.924643 -162.254076) (xy 90.974199 -162.319673)
			(xy 91.017492 -162.389561) (xy 91.054154 -162.463145) (xy 91.08387 -162.539798) (xy 91.106389 -162.618865)
			(xy 91.121517 -162.699672) (xy 91.129125 -162.781531) (xy 91.129612 -162.822636) (xy 91.12919 -162.860925)
			(xy 91.122588 -162.937219) (xy 91.109443 -163.012662) (xy 91.089854 -163.086693) (xy 91.077288 -163.122864)
			(xy 91.076082 -163.126674) (xy 119.365268 -163.126674) (xy 119.365838 -163.081905) (xy 119.374847 -162.99282)
			(xy 119.392749 -162.905089) (xy 119.419366 -162.819597) (xy 119.436388 -162.778186) (xy 119.43997 -162.7686)
			(xy 119.43996 -162.748153) (xy 119.436388 -162.738562) (xy 119.41934 -162.69716) (xy 119.392709 -162.61167)
			(xy 119.374808 -162.523935) (xy 119.365818 -162.434845) (xy 119.365268 -162.390074) (xy 119.365838 -162.345305)
			(xy 119.374847 -162.25622) (xy 119.392749 -162.168489) (xy 119.419366 -162.082997) (xy 119.436388 -162.041586)
			(xy 119.43997 -162.032) (xy 119.43996 -162.011553) (xy 119.436388 -162.001962) (xy 119.41934 -161.96056)
			(xy 119.392709 -161.87507) (xy 119.374808 -161.787335) (xy 119.365818 -161.698245) (xy 119.365268 -161.653474)
			(xy 119.365674 -161.612358) (xy 119.373264 -161.530476) (xy 119.388376 -161.449645) (xy 119.410882 -161.370552)
			(xy 119.440591 -161.293873) (xy 119.477247 -161.220263) (xy 119.520539 -161.150349) (xy 119.570097 -161.084728)
			(xy 119.625499 -161.023959) (xy 119.686271 -160.968561) (xy 119.751895 -160.919007) (xy 119.821812 -160.87572)
			(xy 119.895425 -160.839068) (xy 119.972105 -160.809365) (xy 120.051199 -160.786863) (xy 120.132032 -160.771756)
			(xy 120.213914 -160.764171) (xy 120.25503 -160.763712) (xy 120.296641 -160.764173) (xy 120.379498 -160.771953)
			(xy 120.461267 -160.787431) (xy 120.541235 -160.810474) (xy 120.618703 -160.840879) (xy 120.692995 -160.878382)
			(xy 120.728486 -160.90011) (xy 120.737629 -160.905263) (xy 120.758342 -160.90848) (xy 120.778614 -160.903152)
			(xy 120.78716 -160.897062) (xy 120.820789 -160.871071) (xy 120.892183 -160.824946) (xy 120.967654 -160.785845)
			(xy 121.046512 -160.754124) (xy 121.128037 -160.730075) (xy 121.211485 -160.713915) (xy 121.296095 -160.705793)
			(xy 121.338594 -160.705292) (xy 121.379707 -160.705819) (xy 121.461582 -160.713405) (xy 121.542407 -160.728513)
			(xy 121.621494 -160.751013) (xy 121.698168 -160.780715) (xy 121.771774 -160.817365) (xy 121.841684 -160.86065)
			(xy 121.907303 -160.9102) (xy 121.96807 -160.965593) (xy 122.023467 -161.026357) (xy 122.073021 -161.091973)
			(xy 122.11631 -161.161881) (xy 122.152964 -161.235485) (xy 122.18267 -161.312156) (xy 122.205176 -161.391242)
			(xy 122.220288 -161.472067) (xy 122.227879 -161.553941) (xy 122.228356 -161.595054) (xy 122.227793 -161.639824)
			(xy 122.218783 -161.728909) (xy 122.200877 -161.81664) (xy 122.174259 -161.902131) (xy 122.157236 -161.943542)
			(xy 122.153699 -161.953141) (xy 122.153682 -161.973576) (xy 122.157236 -161.983166) (xy 122.17424 -162.024517)
			(xy 122.200851 -162.109879) (xy 122.218758 -162.197482) (xy 122.22778 -162.286439) (xy 122.228356 -162.331146)
			(xy 122.228356 -162.332162) (xy 122.228102 -162.343592) (xy 122.254581 -162.349538) (xy 122.306816 -162.364281)
			(xy 122.332496 -162.373056) (xy 122.340693 -162.37557) (xy 122.357827 -162.37557) (xy 122.366024 -162.373056)
			(xy 122.40124 -162.361095) (xy 122.473244 -162.342441) (xy 122.546565 -162.329932) (xy 122.62068 -162.323659)
			(xy 122.65787 -162.323272) (xy 122.695059 -162.323671) (xy 122.769172 -162.329958) (xy 122.842492 -162.342465)
			(xy 122.914498 -162.361103) (xy 122.949716 -162.373056) (xy 122.957913 -162.37557) (xy 122.975047 -162.37557)
			(xy 122.983244 -162.373056) (xy 123.018459 -162.361089) (xy 123.090462 -162.342437) (xy 123.163784 -162.32993)
			(xy 123.2379 -162.323658) (xy 123.27509 -162.323272) (xy 123.31703 -162.323667) (xy 123.400532 -162.331639)
			(xy 123.482897 -162.347513) (xy 123.56338 -162.371144) (xy 123.641253 -162.402319) (xy 123.71581 -162.440755)
			(xy 123.786375 -162.486104) (xy 123.85231 -162.537955) (xy 123.913018 -162.595839) (xy 123.913877 -162.59683)
			(xy 376.471695 -162.59683) (xy 376.4757 -162.491081) (xy 376.48769 -162.385938) (xy 376.507599 -162.282003)
			(xy 376.53531 -162.179871) (xy 376.570667 -162.080127) (xy 376.613465 -161.983343) (xy 376.663461 -161.890073)
			(xy 376.720368 -161.800852) (xy 376.783859 -161.716189) (xy 376.853571 -161.636571) (xy 376.929105 -161.562453)
			(xy 377.010028 -161.49426) (xy 377.095877 -161.432382) (xy 377.18616 -161.377175) (xy 377.280359 -161.328953)
			(xy 377.377936 -161.287993) (xy 377.478331 -161.254531) (xy 377.580969 -161.228757) (xy 377.685262 -161.210819)
			(xy 377.790613 -161.20082) (xy 377.896419 -161.198817) (xy 378.002073 -161.204822) (xy 378.10697 -161.218801)
			(xy 378.21051 -161.240672) (xy 378.312099 -161.270312) (xy 378.411156 -161.30755) (xy 378.507113 -161.352172)
			(xy 378.59942 -161.403924) (xy 378.687549 -161.462509) (xy 378.770995 -161.527591) (xy 378.849279 -161.598797)
			(xy 378.921954 -161.67572) (xy 378.988604 -161.75792) (xy 379.048846 -161.844924) (xy 379.102335 -161.936235)
			(xy 379.148766 -162.03133) (xy 379.187871 -162.129664) (xy 379.219428 -162.230675) (xy 379.243255 -162.333782)
			(xy 379.259216 -162.438396) (xy 379.26722 -162.543918) (xy 379.26772 -162.59683) (xy 379.26722 -162.649742)
			(xy 379.266995 -162.65271) (xy 385.808735 -162.65271) (xy 385.81274 -162.546961) (xy 385.82473 -162.441818)
			(xy 385.844639 -162.337883) (xy 385.87235 -162.235751) (xy 385.907707 -162.136007) (xy 385.950505 -162.039223)
			(xy 386.000501 -161.945953) (xy 386.057408 -161.856732) (xy 386.120899 -161.772069) (xy 386.190611 -161.692451)
			(xy 386.266145 -161.618333) (xy 386.347068 -161.55014) (xy 386.432917 -161.488262) (xy 386.5232 -161.433055)
			(xy 386.617399 -161.384833) (xy 386.714976 -161.343873) (xy 386.815371 -161.310411) (xy 386.918009 -161.284637)
			(xy 387.022302 -161.266699) (xy 387.127653 -161.2567) (xy 387.233459 -161.254697) (xy 387.339113 -161.260702)
			(xy 387.44401 -161.274681) (xy 387.54755 -161.296552) (xy 387.649139 -161.326192) (xy 387.748196 -161.36343)
			(xy 387.844153 -161.408052) (xy 387.93646 -161.459804) (xy 388.024589 -161.518389) (xy 388.108035 -161.583471)
			(xy 388.186319 -161.654677) (xy 388.231017 -161.701988) (xy 409.929076 -161.701988) (xy 409.92965 -161.657219)
			(xy 409.938657 -161.568134) (xy 409.956559 -161.480403) (xy 409.983175 -161.394911) (xy 410.000196 -161.3535)
			(xy 410.00377 -161.343912) (xy 410.003765 -161.323466) (xy 410.000196 -161.313876) (xy 409.983153 -161.272472)
			(xy 409.956521 -161.186983) (xy 409.938618 -161.099248) (xy 409.929627 -161.010159) (xy 409.929076 -160.965388)
			(xy 409.92965 -160.920619) (xy 409.938657 -160.831534) (xy 409.956559 -160.743803) (xy 409.983175 -160.658311)
			(xy 410.000196 -160.6169) (xy 410.00377 -160.607312) (xy 410.003765 -160.586866) (xy 410.000196 -160.577276)
			(xy 409.983153 -160.535872) (xy 409.956521 -160.450383) (xy 409.938618 -160.362648) (xy 409.929627 -160.273559)
			(xy 409.929076 -160.228788) (xy 409.929541 -160.187678) (xy 409.93713 -160.105808) (xy 409.952241 -160.024988)
			(xy 409.974747 -159.945907) (xy 410.004454 -159.869241) (xy 410.041109 -159.795643) (xy 410.0844 -159.725742)
			(xy 410.133957 -159.660134) (xy 410.189357 -159.59938) (xy 410.250127 -159.543997) (xy 410.315748 -159.494459)
			(xy 410.385662 -159.451187) (xy 410.45927 -159.414553) (xy 410.535944 -159.384867) (xy 410.615031 -159.362384)
			(xy 410.695856 -159.347295) (xy 410.777728 -159.339729) (xy 410.818838 -159.33928) (xy 410.860442 -159.339755)
			(xy 410.94329 -159.347487) (xy 411.025054 -159.362917) (xy 411.105022 -159.38591) (xy 411.182495 -159.416266)
			(xy 411.256796 -159.45372) (xy 411.292294 -159.475424) (xy 411.301434 -159.480582) (xy 411.322149 -159.483796)
			(xy 411.342422 -159.478466) (xy 411.350968 -159.472376) (xy 411.384591 -159.44642) (xy 411.45597 -159.400364)
			(xy 411.531414 -159.361321) (xy 411.610235 -159.329647) (xy 411.691716 -159.305629) (xy 411.775116 -159.289486)
			(xy 411.859674 -159.281366) (xy 411.902148 -159.28086) (xy 411.902402 -159.28086) (xy 411.943509 -159.281311)
			(xy 412.025374 -159.288895) (xy 412.106189 -159.304) (xy 412.185267 -159.326496) (xy 412.261931 -159.356191)
			(xy 412.33553 -159.392831) (xy 412.405434 -159.436106) (xy 412.471048 -159.485644) (xy 412.531813 -159.541025)
			(xy 412.587209 -159.601775) (xy 412.636764 -159.667376) (xy 412.680057 -159.737269) (xy 412.716716 -159.810858)
			(xy 412.746431 -159.887515) (xy 412.768947 -159.966587) (xy 412.784073 -160.047398) (xy 412.791679 -160.129261)
			(xy 412.792164 -160.170368) (xy 412.791606 -160.215138) (xy 412.782594 -160.304223) (xy 412.764688 -160.391954)
			(xy 412.738068 -160.477445) (xy 412.721044 -160.518856) (xy 412.717498 -160.528452) (xy 412.717487 -160.548889)
			(xy 412.721044 -160.55848) (xy 412.738053 -160.599829) (xy 412.764663 -160.685192) (xy 412.782568 -160.772795)
			(xy 412.791589 -160.861753) (xy 412.792164 -160.90646) (xy 412.792164 -160.907476) (xy 412.79191 -160.918906)
			(xy 412.818389 -160.924851) (xy 412.870624 -160.939594) (xy 412.896304 -160.94837) (xy 412.904501 -160.950884)
			(xy 412.921635 -160.950884) (xy 412.929832 -160.94837) (xy 412.96505 -160.936429) (xy 413.037059 -160.91784)
			(xy 413.110382 -160.905398) (xy 413.184492 -160.899192) (xy 413.221678 -160.89884) (xy 413.258862 -160.899213)
			(xy 413.33297 -160.905434) (xy 413.40629 -160.917875) (xy 413.478301 -160.936448) (xy 413.513524 -160.94837)
			(xy 413.521721 -160.950884) (xy 413.538855 -160.950884) (xy 413.547052 -160.94837) (xy 413.582146 -160.93646)
			(xy 413.653906 -160.917916) (xy 413.726971 -160.905476) (xy 413.800824 -160.899229) (xy 413.837882 -160.89884)
			(xy 413.838898 -160.89884) (xy 413.880822 -160.899407) (xy 413.964291 -160.907377) (xy 414.046623 -160.923245)
			(xy 414.127075 -160.946868) (xy 414.204917 -160.978031) (xy 414.279444 -161.016452) (xy 414.349982 -161.061784)
			(xy 414.415891 -161.113615) (xy 414.476575 -161.171477) (xy 414.531484 -161.234845) (xy 414.580121 -161.303146)
			(xy 414.622045 -161.37576) (xy 414.656876 -161.452031) (xy 414.684301 -161.531268) (xy 414.704068 -161.612752)
			(xy 414.716001 -161.695747) (xy 414.719991 -161.7795) (xy 414.716001 -161.863253) (xy 414.704068 -161.946248)
			(xy 414.684301 -162.027732) (xy 414.656876 -162.106969) (xy 414.622045 -162.18324) (xy 414.580121 -162.255854)
			(xy 414.531484 -162.324155) (xy 414.476575 -162.387523) (xy 414.415891 -162.445385) (xy 414.349982 -162.497216)
			(xy 414.279444 -162.542548) (xy 414.204917 -162.580969) (xy 414.127075 -162.612132) (xy 414.046623 -162.635755)
			(xy 413.964291 -162.651623) (xy 413.880822 -162.659593) (xy 413.838898 -162.660076) (xy 413.837882 -162.660076)
			(xy 413.800825 -162.659672) (xy 413.726976 -162.653407) (xy 413.653913 -162.640964) (xy 413.582153 -162.622432)
			(xy 413.547052 -162.610546) (xy 413.538855 -162.608032) (xy 413.521721 -162.608032) (xy 413.513524 -162.610546)
			(xy 413.484638 -162.620383) (xy 413.425785 -162.636529) (xy 413.395922 -162.642804) (xy 413.386334 -162.645159)
			(xy 413.369889 -162.656054) (xy 413.358796 -162.672367) (xy 413.356298 -162.68192) (xy 413.34617 -162.726275)
			(xy 413.318046 -162.812805) (xy 413.300164 -162.85464) (xy 413.296347 -162.864579) (xy 413.296353 -162.885846)
			(xy 413.300164 -162.895788) (xy 413.318394 -162.938388) (xy 413.346909 -163.026556) (xy 413.366099 -163.117213)
			(xy 413.375757 -163.209373) (xy 413.376364 -163.255706) (xy 413.376364 -163.256214) (xy 413.37586 -163.298562)
			(xy 413.367809 -163.382876) (xy 413.35178 -163.466042) (xy 413.327919 -163.547309) (xy 413.29644 -163.625939)
			(xy 413.257629 -163.70122) (xy 413.230169 -163.74395) (xy 431.840894 -163.74395) (xy 431.840894 -163.68945)
			(xy 431.84865 -163.635505) (xy 431.864004 -163.583213) (xy 431.886644 -163.533639) (xy 431.916109 -163.48779)
			(xy 431.951798 -163.446602) (xy 431.992986 -163.410912) (xy 432.038833 -163.381447) (xy 432.088408 -163.358807)
			(xy 432.140699 -163.343452) (xy 432.194644 -163.335695) (xy 432.221894 -163.335208) (xy 433.212494 -163.335208)
			(xy 433.239748 -163.335638) (xy 433.293702 -163.343395) (xy 433.346003 -163.358751) (xy 433.395586 -163.381394)
			(xy 433.441442 -163.410863) (xy 433.482637 -163.446559) (xy 433.518333 -163.487753) (xy 433.547803 -163.533609)
			(xy 433.570447 -163.583191) (xy 433.585804 -163.635492) (xy 433.593561 -163.689446) (xy 433.593561 -163.743954)
			(xy 433.585804 -163.797908) (xy 433.570447 -163.850209) (xy 433.547803 -163.899791) (xy 433.518333 -163.945647)
			(xy 433.482637 -163.986841) (xy 433.441442 -164.022537) (xy 433.395586 -164.052006) (xy 433.346003 -164.074649)
			(xy 433.293702 -164.090005) (xy 433.239748 -164.097762) (xy 433.212494 -164.098224) (xy 432.221894 -164.098224)
			(xy 432.194644 -164.097705) (xy 432.140699 -164.089948) (xy 432.088408 -164.074593) (xy 432.038833 -164.051953)
			(xy 431.992986 -164.022488) (xy 431.951798 -163.986798) (xy 431.916109 -163.94561) (xy 431.886644 -163.899761)
			(xy 431.864004 -163.850187) (xy 431.84865 -163.797895) (xy 431.840894 -163.74395) (xy 413.230169 -163.74395)
			(xy 413.211839 -163.772472) (xy 413.159483 -163.839048) (xy 413.101035 -163.900346) (xy 413.037025 -163.955811)
			(xy 412.968033 -164.00494) (xy 412.894683 -164.047289) (xy 412.81764 -164.082473) (xy 412.737601 -164.110175)
			(xy 412.655292 -164.130143) (xy 412.571457 -164.142196) (xy 412.486856 -164.146227) (xy 412.402255 -164.142196)
			(xy 412.31842 -164.130143) (xy 412.236111 -164.110175) (xy 412.156072 -164.082473) (xy 412.079029 -164.047289)
			(xy 412.005679 -164.00494) (xy 411.936687 -163.955811) (xy 411.872677 -163.900346) (xy 411.814229 -163.839048)
			(xy 411.761873 -163.772472) (xy 411.716083 -163.70122) (xy 411.677272 -163.625939) (xy 411.645793 -163.547309)
			(xy 411.621932 -163.466042) (xy 411.605903 -163.382876) (xy 411.597852 -163.298562) (xy 411.597348 -163.256214)
			(xy 411.597348 -163.255706) (xy 411.597963 -163.209374) (xy 411.607632 -163.117217) (xy 411.626825 -163.026563)
			(xy 411.655334 -162.938394) (xy 411.673548 -162.895788) (xy 411.677348 -162.885844) (xy 411.677353 -162.864582)
			(xy 411.673548 -162.85464) (xy 411.655311 -162.811974) (xy 411.626764 -162.723684) (xy 411.607569 -162.632899)
			(xy 411.597934 -162.54061) (xy 411.597348 -162.494214) (xy 411.597953 -162.446404) (xy 411.608131 -162.351329)
			(xy 411.617668 -162.304476) (xy 411.61964 -162.292071) (xy 411.612727 -162.267957) (xy 411.60446 -162.258502)
			(xy 411.56382 -162.216338) (xy 411.560264 -162.2171) (xy 411.551416 -162.219411) (xy 411.536053 -162.229303)
			(xy 411.530292 -162.236404) (xy 411.505145 -162.269057) (xy 411.449744 -162.330083) (xy 411.388935 -162.385722)
			(xy 411.323239 -162.435497) (xy 411.253221 -162.478981) (xy 411.17948 -162.515801) (xy 411.102649 -162.545642)
			(xy 411.023387 -162.568246) (xy 410.942373 -162.583421) (xy 410.860303 -162.591036) (xy 410.819092 -162.591496)
			(xy 410.818838 -162.591496) (xy 410.777733 -162.590951) (xy 410.695873 -162.583371) (xy 410.615061 -162.568271)
			(xy 410.535987 -162.54578) (xy 410.459325 -162.516091) (xy 410.385729 -162.479456) (xy 410.315826 -162.436187)
			(xy 410.250213 -162.386655) (xy 410.18945 -162.331281) (xy 410.134053 -162.270538) (xy 410.084497 -162.204943)
			(xy 410.041203 -162.135056) (xy 410.004541 -162.061473) (xy 409.974824 -161.984822) (xy 409.952304 -161.905756)
			(xy 409.937174 -161.82495) (xy 409.929564 -161.743093) (xy 409.929076 -161.701988) (xy 388.231017 -161.701988)
			(xy 388.258994 -161.7316) (xy 388.325644 -161.8138) (xy 388.385886 -161.900804) (xy 388.439375 -161.992115)
			(xy 388.485806 -162.08721) (xy 388.524911 -162.185544) (xy 388.556468 -162.286555) (xy 388.580295 -162.389662)
			(xy 388.596256 -162.494276) (xy 388.60426 -162.599798) (xy 388.60476 -162.65271) (xy 388.60426 -162.705622)
			(xy 388.596256 -162.811144) (xy 388.580295 -162.915758) (xy 388.556468 -163.018865) (xy 388.524911 -163.119876)
			(xy 388.485806 -163.21821) (xy 388.439375 -163.313305) (xy 388.385886 -163.404616) (xy 388.325644 -163.49162)
			(xy 388.258994 -163.57382) (xy 388.186319 -163.650743) (xy 388.108035 -163.721949) (xy 388.024589 -163.787031)
			(xy 387.93646 -163.845616) (xy 387.844153 -163.897368) (xy 387.748196 -163.94199) (xy 387.649139 -163.979228)
			(xy 387.54755 -164.008868) (xy 387.44401 -164.030739) (xy 387.339113 -164.044718) (xy 387.233459 -164.050723)
			(xy 387.127653 -164.04872) (xy 387.022302 -164.038721) (xy 386.918009 -164.020783) (xy 386.815371 -163.995009)
			(xy 386.714976 -163.961547) (xy 386.617399 -163.920587) (xy 386.5232 -163.872365) (xy 386.432917 -163.817158)
			(xy 386.347068 -163.75528) (xy 386.266145 -163.687087) (xy 386.190611 -163.612969) (xy 386.120899 -163.533351)
			(xy 386.057408 -163.448688) (xy 386.000501 -163.359467) (xy 385.950505 -163.266197) (xy 385.907707 -163.169413)
			(xy 385.87235 -163.069669) (xy 385.844639 -162.967537) (xy 385.82473 -162.863602) (xy 385.81274 -162.758459)
			(xy 385.808735 -162.65271) (xy 379.266995 -162.65271) (xy 379.259216 -162.755264) (xy 379.243255 -162.859878)
			(xy 379.219428 -162.962985) (xy 379.187871 -163.063996) (xy 379.148766 -163.16233) (xy 379.102335 -163.257425)
			(xy 379.048846 -163.348736) (xy 378.988604 -163.43574) (xy 378.921954 -163.51794) (xy 378.849279 -163.594863)
			(xy 378.770995 -163.666069) (xy 378.687549 -163.731151) (xy 378.59942 -163.789736) (xy 378.507113 -163.841488)
			(xy 378.411156 -163.88611) (xy 378.312099 -163.923348) (xy 378.21051 -163.952988) (xy 378.10697 -163.974859)
			(xy 378.002073 -163.988838) (xy 377.896419 -163.994843) (xy 377.790613 -163.99284) (xy 377.685262 -163.982841)
			(xy 377.580969 -163.964903) (xy 377.478331 -163.939129) (xy 377.377936 -163.905667) (xy 377.280359 -163.864707)
			(xy 377.18616 -163.816485) (xy 377.095877 -163.761278) (xy 377.010028 -163.6994) (xy 376.929105 -163.631207)
			(xy 376.853571 -163.557089) (xy 376.783859 -163.477471) (xy 376.720368 -163.392808) (xy 376.663461 -163.303587)
			(xy 376.613465 -163.210317) (xy 376.570667 -163.113533) (xy 376.53531 -163.013789) (xy 376.507599 -162.911657)
			(xy 376.48769 -162.807722) (xy 376.4757 -162.702579) (xy 376.471695 -162.59683) (xy 123.913877 -162.59683)
			(xy 123.967949 -162.659232) (xy 124.016605 -162.727559) (xy 124.058546 -162.800202) (xy 124.093391 -162.876503)
			(xy 124.120826 -162.95577) (xy 124.140602 -163.037287) (xy 124.15254 -163.120314) (xy 124.156531 -163.2041)
			(xy 124.15254 -163.287886) (xy 124.140602 -163.370913) (xy 124.120826 -163.45243) (xy 124.093391 -163.531697)
			(xy 124.058546 -163.607998) (xy 124.016605 -163.680641) (xy 123.967949 -163.748968) (xy 123.913018 -163.812361)
			(xy 123.85231 -163.870245) (xy 123.786375 -163.922096) (xy 123.71581 -163.967445) (xy 123.641253 -164.005881)
			(xy 123.56338 -164.037056) (xy 123.482897 -164.060687) (xy 123.400532 -164.076561) (xy 123.31703 -164.084533)
			(xy 123.27509 -164.085016) (xy 123.2379 -164.084629) (xy 123.163787 -164.078339) (xy 123.090468 -164.065828)
			(xy 123.018462 -164.047187) (xy 122.983244 -164.035232) (xy 122.975047 -164.032718) (xy 122.957913 -164.032718)
			(xy 122.949716 -164.035232) (xy 122.907233 -164.049509) (xy 122.820068 -164.070379) (xy 122.775726 -164.076888)
			(xy 122.765804 -164.078672) (xy 122.748385 -164.088778) (xy 122.736231 -164.104835) (xy 122.733308 -164.11448)
			(xy 122.724748 -164.14638) (xy 122.70352 -164.20893) (xy 122.69089 -164.239448) (xy 122.687282 -164.249022)
			(xy 122.687136 -164.26946) (xy 122.690636 -164.279072) (xy 122.707671 -164.320445) (xy 122.734286 -164.405873)
			(xy 122.752187 -164.493543) (xy 122.756237 -164.53358) (xy 365.854996 -164.53358) (xy 365.855358 -164.495263)
			(xy 365.861892 -164.41891) (xy 365.874978 -164.343403) (xy 365.89452 -164.269304) (xy 365.907066 -164.233098)
			(xy 365.909662 -164.224784) (xy 365.909655 -164.207378) (xy 365.907066 -164.199062) (xy 365.894569 -164.162941)
			(xy 365.875081 -164.089028) (xy 365.861998 -164.013717) (xy 365.855418 -163.937561) (xy 365.854996 -163.899342)
			(xy 365.854996 -163.89858) (xy 365.855448 -163.857477) (xy 365.863034 -163.775622) (xy 365.878141 -163.694816)
			(xy 365.900639 -163.615749) (xy 365.930337 -163.539095) (xy 365.966981 -163.465508) (xy 366.010258 -163.395615)
			(xy 366.059799 -163.330014) (xy 366.115181 -163.269264) (xy 366.175933 -163.213883) (xy 366.241535 -163.164344)
			(xy 366.311429 -163.121069) (xy 366.385017 -163.084427) (xy 366.461672 -163.054732) (xy 366.54074 -163.032236)
			(xy 366.621546 -163.017131) (xy 366.703401 -163.009546) (xy 366.744504 -163.009072) (xy 366.745266 -163.009072)
			(xy 366.783487 -163.009474) (xy 366.859645 -163.01604) (xy 366.934958 -163.029126) (xy 367.008868 -163.048635)
			(xy 367.044986 -163.061142) (xy 367.053302 -163.063728) (xy 367.070706 -163.063728) (xy 367.079022 -163.061142)
			(xy 367.115235 -163.04862) (xy 367.189336 -163.029098) (xy 367.26484 -163.016015) (xy 367.341189 -163.009466)
			(xy 367.379504 -163.009072) (xy 367.419718 -163.009498) (xy 367.49982 -163.016721) (xy 367.578942 -163.031153)
			(xy 367.656435 -163.052677) (xy 367.69421 -163.066476) (xy 367.702997 -163.069383) (xy 367.721491 -163.069383)
			(xy 367.730278 -163.066476) (xy 367.768054 -163.052684) (xy 367.845551 -163.031177) (xy 367.924672 -163.016746)
			(xy 368.004771 -163.00951) (xy 368.044984 -163.009072) (xy 368.0833 -163.009446) (xy 368.159653 -163.015977)
			(xy 368.23516 -163.029059) (xy 368.309259 -163.048598) (xy 368.345466 -163.061142) (xy 368.353782 -163.063728)
			(xy 368.371186 -163.063728) (xy 368.379502 -163.061142) (xy 368.415717 -163.048626) (xy 368.489817 -163.029103)
			(xy 368.565321 -163.016017) (xy 368.641669 -163.009467) (xy 368.679984 -163.009072) (xy 368.7183 -163.009446)
			(xy 368.794653 -163.015977) (xy 368.87016 -163.029059) (xy 368.944259 -163.048598) (xy 368.980466 -163.061142)
			(xy 368.988782 -163.063728) (xy 369.006186 -163.063728) (xy 369.014502 -163.061142) (xy 369.050717 -163.048626)
			(xy 369.124817 -163.029103) (xy 369.200321 -163.016017) (xy 369.276669 -163.009467) (xy 369.314984 -163.009072)
			(xy 369.3533 -163.009446) (xy 369.429653 -163.015977) (xy 369.50516 -163.029059) (xy 369.579259 -163.048598)
			(xy 369.615466 -163.061142) (xy 369.623782 -163.063728) (xy 369.641186 -163.063728) (xy 369.649502 -163.061142)
			(xy 369.685565 -163.048673) (xy 369.759352 -163.029204) (xy 369.834533 -163.016119) (xy 369.910559 -163.009515)
			(xy 369.948714 -163.009072) (xy 369.949984 -163.009072) (xy 369.994754 -163.009635) (xy 370.083841 -163.018637)
			(xy 370.171573 -163.03654) (xy 370.257063 -163.063164) (xy 370.298472 -163.080192) (xy 370.308063 -163.083757)
			(xy 370.328505 -163.083757) (xy 370.338096 -163.080192) (xy 370.379479 -163.063183) (xy 370.464904 -163.036561)
			(xy 370.55257 -163.018653) (xy 370.641592 -163.00964) (xy 370.68633 -163.009072) (xy 370.686584 -163.009072)
			(xy 370.727686 -163.009582) (xy 370.809538 -163.017165) (xy 370.890342 -163.032268) (xy 370.969408 -163.054763)
			(xy 371.046061 -163.084457) (xy 371.119647 -163.121096) (xy 371.189538 -163.16437) (xy 371.255139 -163.213907)
			(xy 371.315889 -163.269286) (xy 371.37127 -163.330033) (xy 371.42081 -163.395632) (xy 371.464086 -163.465522)
			(xy 371.500729 -163.539106) (xy 371.530426 -163.615758) (xy 371.552923 -163.694823) (xy 371.56803 -163.775626)
			(xy 371.575616 -163.857478) (xy 371.576092 -163.89858) (xy 371.576092 -163.899342) (xy 371.575679 -163.937562)
			(xy 371.569116 -164.013721) (xy 371.556033 -164.089033) (xy 371.536527 -164.162943) (xy 371.524022 -164.199062)
			(xy 371.521447 -164.207381) (xy 371.52144 -164.224782) (xy 371.524022 -164.233098) (xy 371.536535 -164.269314)
			(xy 371.55606 -164.343414) (xy 371.569146 -164.418917) (xy 371.575697 -164.495265) (xy 371.576092 -164.53358)
			(xy 371.575734 -164.571323) (xy 371.569392 -164.646543) (xy 371.556692 -164.720953) (xy 371.537726 -164.794018)
			(xy 371.525546 -164.829744) (xy 371.522818 -164.838516) (xy 371.52307 -164.85687) (xy 371.526054 -164.865558)
			(xy 371.541045 -164.904681) (xy 371.564495 -164.985121) (xy 371.58028 -165.067409) (xy 371.588259 -165.150817)
			(xy 371.588792 -165.19271) (xy 371.588792 -165.19398) (xy 371.588329 -165.235083) (xy 371.580745 -165.316939)
			(xy 371.565641 -165.397747) (xy 371.543146 -165.476815) (xy 371.51345 -165.553471) (xy 371.476808 -165.62706)
			(xy 371.433533 -165.696954) (xy 371.383993 -165.762556) (xy 371.328611 -165.823308) (xy 371.267859 -165.87869)
			(xy 371.202257 -165.92823) (xy 371.132363 -165.971506) (xy 371.058775 -166.008149) (xy 370.982119 -166.037844)
			(xy 370.90305 -166.06034) (xy 370.822243 -166.075445) (xy 370.740387 -166.083029) (xy 370.699284 -166.083488)
			(xy 370.69903 -166.083488) (xy 370.654291 -166.082927) (xy 370.56527 -166.07391) (xy 370.477602 -166.056003)
			(xy 370.392175 -166.029387) (xy 370.350796 -166.012368) (xy 370.341205 -166.008803) (xy 370.320763 -166.008803)
			(xy 370.311172 -166.012368) (xy 370.269762 -166.029396) (xy 370.184274 -166.056029) (xy 370.096542 -166.073935)
			(xy 370.007454 -166.082933) (xy 369.962684 -166.083488) (xy 369.961414 -166.083488) (xy 369.923257 -166.083067)
			(xy 369.847228 -166.076479) (xy 369.772044 -166.063393) (xy 369.69826 -166.043906) (xy 369.662202 -166.031418)
			(xy 369.653886 -166.028832) (xy 369.636482 -166.028832) (xy 369.628166 -166.031418) (xy 369.591953 -166.043941)
			(xy 369.517852 -166.063463) (xy 369.442348 -166.076546) (xy 369.365999 -166.083094) (xy 369.327684 -166.083488)
			(xy 369.289367 -166.083126) (xy 369.213014 -166.076592) (xy 369.137507 -166.063506) (xy 369.063408 -166.043964)
			(xy 369.027202 -166.031418) (xy 369.018886 -166.028832) (xy 369.001482 -166.028832) (xy 368.993166 -166.031418)
			(xy 368.956953 -166.043941) (xy 368.882852 -166.063463) (xy 368.807348 -166.076546) (xy 368.730999 -166.083094)
			(xy 368.692684 -166.083488) (xy 368.654367 -166.083126) (xy 368.578014 -166.076592) (xy 368.502507 -166.063506)
			(xy 368.428408 -166.043964) (xy 368.392202 -166.031418) (xy 368.383886 -166.028832) (xy 368.366482 -166.028832)
			(xy 368.358166 -166.031418) (xy 368.321953 -166.043941) (xy 368.247852 -166.063463) (xy 368.172348 -166.076546)
			(xy 368.095999 -166.083094) (xy 368.057684 -166.083488) (xy 368.01747 -166.083062) (xy 367.937368 -166.075838)
			(xy 367.858246 -166.061406) (xy 367.780753 -166.039883) (xy 367.742978 -166.026084) (xy 367.734191 -166.023177)
			(xy 367.715697 -166.023177) (xy 367.70691 -166.026084) (xy 367.669134 -166.039877) (xy 367.591637 -166.061385)
			(xy 367.512517 -166.075815) (xy 367.432417 -166.083051) (xy 367.392204 -166.083488) (xy 367.353888 -166.08312)
			(xy 367.277534 -166.076588) (xy 367.202027 -166.063503) (xy 367.127928 -166.043963) (xy 367.091722 -166.031418)
			(xy 367.083406 -166.028832) (xy 367.066002 -166.028832) (xy 367.057686 -166.031418) (xy 367.021563 -166.043908)
			(xy 366.947651 -166.063398) (xy 366.87234 -166.076483) (xy 366.796185 -166.083065) (xy 366.757966 -166.083488)
			(xy 366.757204 -166.083488) (xy 366.7161 -166.083044) (xy 366.634244 -166.075459) (xy 366.553436 -166.060354)
			(xy 366.474367 -166.037857) (xy 366.397711 -166.00816) (xy 366.324122 -165.971516) (xy 366.254228 -165.928239)
			(xy 366.188625 -165.878698) (xy 366.127874 -165.823315) (xy 366.072492 -165.762562) (xy 366.022951 -165.696959)
			(xy 365.979676 -165.627064) (xy 365.943034 -165.553475) (xy 365.913338 -165.476818) (xy 365.890843 -165.397748)
			(xy 365.875739 -165.316941) (xy 365.868155 -165.235084) (xy 365.867696 -165.19398) (xy 365.867696 -165.192964)
			(xy 365.868115 -165.155349) (xy 365.874496 -165.080389) (xy 365.887191 -165.006237) (xy 365.906111 -164.933424)
			(xy 365.918242 -164.897816) (xy 365.920992 -164.889049) (xy 365.920727 -164.87069) (xy 365.917734 -164.862002)
			(xy 365.902679 -164.822733) (xy 365.879172 -164.741978) (xy 365.863391 -164.659366) (xy 365.855475 -164.575633)
			(xy 365.854996 -164.53358) (xy 122.756237 -164.53358) (xy 122.761192 -164.582567) (xy 122.761756 -164.627306)
			(xy 122.761756 -164.62756) (xy 122.761252 -164.669908) (xy 122.753201 -164.754222) (xy 122.737172 -164.837388)
			(xy 122.713311 -164.918655) (xy 122.681832 -164.997285) (xy 122.643021 -165.072566) (xy 122.597231 -165.143818)
			(xy 122.544875 -165.210394) (xy 122.486427 -165.271692) (xy 122.422417 -165.327157) (xy 122.353425 -165.376286)
			(xy 122.280075 -165.418635) (xy 122.203032 -165.453819) (xy 122.122993 -165.481521) (xy 122.040684 -165.501489)
			(xy 121.956849 -165.513542) (xy 121.872248 -165.517573) (xy 121.787647 -165.513542) (xy 121.703812 -165.501489)
			(xy 121.621503 -165.481521) (xy 121.541464 -165.453819) (xy 121.464421 -165.418635) (xy 121.391071 -165.376286)
			(xy 121.322079 -165.327157) (xy 121.258069 -165.271692) (xy 121.199621 -165.210394) (xy 121.147265 -165.143818)
			(xy 121.101475 -165.072566) (xy 121.062664 -164.997285) (xy 121.031185 -164.918655) (xy 121.007324 -164.837388)
			(xy 120.991295 -164.754222) (xy 120.983244 -164.669908) (xy 120.98274 -164.62756) (xy 120.98274 -164.627306)
			(xy 120.983291 -164.582567) (xy 120.992311 -164.493545) (xy 121.010221 -164.405878) (xy 121.03684 -164.320451)
			(xy 121.05386 -164.279072) (xy 121.057447 -164.269488) (xy 121.057432 -164.249039) (xy 121.05386 -164.239448)
			(xy 121.037012 -164.19848) (xy 121.010567 -164.113931) (xy 120.992664 -164.027171) (xy 120.983478 -163.939061)
			(xy 120.98274 -163.89477) (xy 120.982373 -163.885212) (xy 120.975335 -163.867438) (xy 120.962255 -163.853496)
			(xy 120.953784 -163.84905) (xy 120.870726 -163.809934) (xy 120.861899 -163.806187) (xy 120.842781 -163.804911)
			(xy 120.824539 -163.810771) (xy 120.816878 -163.816538) (xy 120.782853 -163.843559) (xy 120.710459 -163.891613)
			(xy 120.633724 -163.93238) (xy 120.55338 -163.965469) (xy 120.470192 -163.990568) (xy 120.384953 -164.007435)
			(xy 120.298476 -164.01591) (xy 120.25503 -164.016436) (xy 120.213915 -164.015973) (xy 120.132035 -164.008388)
			(xy 120.051204 -163.99328) (xy 119.972113 -163.970779) (xy 119.895435 -163.941075) (xy 119.821825 -163.904423)
			(xy 119.751911 -163.861135) (xy 119.686289 -163.811581) (xy 119.62552 -163.756183) (xy 119.570122 -163.695414)
			(xy 119.520567 -163.629793) (xy 119.477279 -163.559879) (xy 119.440626 -163.486269) (xy 119.410922 -163.409591)
			(xy 119.38842 -163.330499) (xy 119.373312 -163.249669) (xy 119.365727 -163.167789) (xy 119.365268 -163.126674)
			(xy 91.076082 -163.126674) (xy 91.074618 -163.131296) (xy 91.074629 -163.148971) (xy 91.077288 -163.157408)
			(xy 91.089816 -163.193591) (xy 91.109393 -163.267622) (xy 91.122545 -163.34306) (xy 91.129174 -163.419348)
			(xy 91.129612 -163.457636) (xy 91.129114 -163.500412) (xy 91.120898 -163.585569) (xy 91.104536 -163.669543)
			(xy 91.080178 -163.751555) (xy 91.064588 -163.791392) (xy 91.061544 -163.799848) (xy 91.060879 -163.817795)
			(xy 91.063318 -163.826444) (xy 91.07787 -163.871922) (xy 91.098306 -163.9652) (xy 91.108623 -164.060131)
			(xy 91.109292 -164.107876) (xy 91.108825 -164.148987) (xy 91.101239 -164.230857) (xy 91.08613 -164.311679)
			(xy 91.063626 -164.390761) (xy 91.033921 -164.467428) (xy 90.997266 -164.541027) (xy 90.953976 -164.610929)
			(xy 90.904419 -164.676538) (xy 90.849019 -164.737293) (xy 90.788249 -164.792677) (xy 90.722626 -164.842215)
			(xy 90.652712 -164.885486) (xy 90.579103 -164.92212) (xy 90.502427 -164.951804) (xy 90.423339 -164.974286)
			(xy 90.342514 -164.989373) (xy 90.260641 -164.996936) (xy 90.21953 -164.997384) (xy 90.177921 -164.996892)
			(xy 90.095064 -164.989136) (xy 90.013294 -164.97368) (xy 89.933323 -164.950659) (xy 89.89441 -164.935916)
			(xy 89.88572 -164.932926) (xy 89.867362 -164.932654) (xy 89.858596 -164.935408) (xy 89.822497 -164.947854)
			(xy 89.748643 -164.967275) (xy 89.673397 -164.980297) (xy 89.597312 -164.986825) (xy 89.55913 -164.987224)
			(xy 89.520814 -164.986846) (xy 89.444461 -164.980317) (xy 89.368954 -164.967235) (xy 89.294855 -164.947698)
			(xy 89.258648 -164.935154) (xy 89.250332 -164.932568) (xy 89.232928 -164.932568) (xy 89.224612 -164.935154)
			(xy 89.188396 -164.947666) (xy 89.114296 -164.96719) (xy 89.038793 -164.980277) (xy 88.962445 -164.986828)
			(xy 88.92413 -164.987224) (xy 88.885814 -164.986846) (xy 88.809461 -164.980317) (xy 88.733954 -164.967235)
			(xy 88.659855 -164.947698) (xy 88.623648 -164.935154) (xy 88.615332 -164.932568) (xy 88.597928 -164.932568)
			(xy 88.589612 -164.935154) (xy 88.553396 -164.947666) (xy 88.479296 -164.96719) (xy 88.403793 -164.980277)
			(xy 88.327445 -164.986828) (xy 88.28913 -164.987224) (xy 88.250814 -164.986846) (xy 88.174461 -164.980317)
			(xy 88.098954 -164.967235) (xy 88.024855 -164.947698) (xy 87.988648 -164.935154) (xy 87.980332 -164.932568)
			(xy 87.962928 -164.932568) (xy 87.954612 -164.935154) (xy 87.918396 -164.947666) (xy 87.844296 -164.96719)
			(xy 87.768793 -164.980277) (xy 87.692445 -164.986828) (xy 87.65413 -164.987224) (xy 87.615814 -164.986846)
			(xy 87.539461 -164.980317) (xy 87.463954 -164.967235) (xy 87.389855 -164.947698) (xy 87.353648 -164.935154)
			(xy 87.345332 -164.932568) (xy 87.327928 -164.932568) (xy 87.319612 -164.935154) (xy 87.283487 -164.947638)
			(xy 87.209575 -164.96713) (xy 87.134265 -164.980216) (xy 87.058111 -164.9868) (xy 87.019892 -164.987224)
			(xy 87.01913 -164.987224) (xy 86.978023 -164.986759) (xy 86.896158 -164.979177) (xy 86.815342 -164.964075)
			(xy 86.736265 -164.941581) (xy 86.659599 -164.911888) (xy 86.586 -164.875249) (xy 86.516095 -164.831976)
			(xy 86.45048 -164.782438) (xy 86.389716 -164.727058) (xy 86.334319 -164.666309) (xy 86.284763 -164.600708)
			(xy 86.241471 -164.530815) (xy 86.204811 -164.457226) (xy 86.175097 -164.380569) (xy 86.152582 -164.301497)
			(xy 86.137457 -164.220686) (xy 86.129853 -164.138823) (xy 86.129368 -164.097716) (xy 2.509012 -164.097716)
			(xy 2.509012 -166.86276) (xy 61.046868 -166.86276) (xy 61.047433 -166.81799) (xy 61.056443 -166.728905)
			(xy 61.074347 -166.641174) (xy 61.100966 -166.555683) (xy 61.117988 -166.514272) (xy 61.121578 -166.504688)
			(xy 61.121563 -166.484239) (xy 61.117988 -166.474648) (xy 61.100968 -166.433235) (xy 61.074329 -166.347749)
			(xy 61.05642 -166.260018) (xy 61.047422 -166.17093) (xy 61.046868 -166.12616) (xy 61.047433 -166.08139)
			(xy 61.056443 -165.992305) (xy 61.074347 -165.904574) (xy 61.100966 -165.819083) (xy 61.117988 -165.777672)
			(xy 61.121578 -165.768088) (xy 61.121563 -165.747639) (xy 61.117988 -165.738048) (xy 61.100968 -165.696635)
			(xy 61.074329 -165.611149) (xy 61.05642 -165.523418) (xy 61.047422 -165.43433) (xy 61.046868 -165.38956)
			(xy 61.047314 -165.348449) (xy 61.054905 -165.266579) (xy 61.070019 -165.185759) (xy 61.092527 -165.106679)
			(xy 61.122236 -165.030013) (xy 61.158893 -164.956415) (xy 61.202185 -164.886514) (xy 61.251743 -164.820907)
			(xy 61.307144 -164.760153) (xy 61.367915 -164.70477) (xy 61.433537 -164.655232) (xy 61.503451 -164.611961)
			(xy 61.57706 -164.575327) (xy 61.653735 -164.545641) (xy 61.732822 -164.523157) (xy 61.813647 -164.508068)
			(xy 61.895519 -164.500502) (xy 61.93663 -164.500052) (xy 61.978234 -164.500535) (xy 62.061081 -164.508266)
			(xy 62.142846 -164.523695) (xy 62.222813 -164.546687) (xy 62.300286 -164.577041) (xy 62.374588 -164.614493)
			(xy 62.410086 -164.636196) (xy 62.419228 -164.641351) (xy 62.439942 -164.644569) (xy 62.460215 -164.639239)
			(xy 62.46876 -164.633148) (xy 62.502383 -164.607191) (xy 62.573762 -164.561136) (xy 62.649206 -164.522094)
			(xy 62.728027 -164.49042) (xy 62.809509 -164.466402) (xy 62.892908 -164.450259) (xy 62.977466 -164.442138)
			(xy 63.01994 -164.441632) (xy 63.020194 -164.441632) (xy 63.0613 -164.442118) (xy 63.143163 -164.449702)
			(xy 63.223977 -164.464805) (xy 63.303052 -164.487299) (xy 63.379716 -164.516993) (xy 63.453313 -164.553631)
			(xy 63.523217 -164.596903) (xy 63.58883 -164.64644) (xy 63.649594 -164.701818) (xy 63.70499 -164.762565)
			(xy 63.754546 -164.828164) (xy 63.797839 -164.898054) (xy 63.8345 -164.971641) (xy 63.864216 -165.048295)
			(xy 63.886734 -165.127364) (xy 63.901861 -165.208173) (xy 63.909469 -165.290034) (xy 63.909956 -165.33114)
			(xy 63.909389 -165.375909) (xy 63.900379 -165.464994) (xy 63.882475 -165.552725) (xy 63.855858 -165.638217)
			(xy 63.838836 -165.679628) (xy 63.83525 -165.689212) (xy 63.835264 -165.709661) (xy 63.838836 -165.719252)
			(xy 63.855836 -165.760605) (xy 63.882448 -165.845966) (xy 63.900356 -165.933568) (xy 63.903248 -165.962076)
			(xy 81.591411 -165.962076) (xy 81.595416 -165.856327) (xy 81.607406 -165.751184) (xy 81.627315 -165.647249)
			(xy 81.655026 -165.545117) (xy 81.690383 -165.445373) (xy 81.733181 -165.348589) (xy 81.783177 -165.255319)
			(xy 81.840084 -165.166098) (xy 81.903575 -165.081435) (xy 81.973287 -165.001817) (xy 82.048821 -164.927699)
			(xy 82.129744 -164.859506) (xy 82.215593 -164.797628) (xy 82.305876 -164.742421) (xy 82.400075 -164.694199)
			(xy 82.497652 -164.653239) (xy 82.598047 -164.619777) (xy 82.700685 -164.594003) (xy 82.804978 -164.576065)
			(xy 82.910329 -164.566066) (xy 83.016135 -164.564063) (xy 83.121789 -164.570068) (xy 83.226686 -164.584047)
			(xy 83.330226 -164.605918) (xy 83.431815 -164.635558) (xy 83.530872 -164.672796) (xy 83.626829 -164.717418)
			(xy 83.719136 -164.76917) (xy 83.807265 -164.827755) (xy 83.890711 -164.892837) (xy 83.968995 -164.964043)
			(xy 84.04167 -165.040966) (xy 84.10832 -165.123166) (xy 84.168562 -165.21017) (xy 84.222051 -165.301481)
			(xy 84.268482 -165.396576) (xy 84.307587 -165.49491) (xy 84.339144 -165.595921) (xy 84.362971 -165.699028)
			(xy 84.378932 -165.803642) (xy 84.386936 -165.909164) (xy 84.387436 -165.962076) (xy 90.989411 -165.962076)
			(xy 90.993416 -165.856327) (xy 91.005406 -165.751184) (xy 91.025315 -165.647249) (xy 91.053026 -165.545117)
			(xy 91.088383 -165.445373) (xy 91.131181 -165.348589) (xy 91.181177 -165.255319) (xy 91.238084 -165.166098)
			(xy 91.301575 -165.081435) (xy 91.371287 -165.001817) (xy 91.446821 -164.927699) (xy 91.527744 -164.859506)
			(xy 91.613593 -164.797628) (xy 91.703876 -164.742421) (xy 91.798075 -164.694199) (xy 91.895652 -164.653239)
			(xy 91.996047 -164.619777) (xy 92.098685 -164.594003) (xy 92.202978 -164.576065) (xy 92.308329 -164.566066)
			(xy 92.414135 -164.564063) (xy 92.519789 -164.570068) (xy 92.624686 -164.584047) (xy 92.728226 -164.605918)
			(xy 92.829815 -164.635558) (xy 92.928872 -164.672796) (xy 93.024829 -164.717418) (xy 93.117136 -164.76917)
			(xy 93.205265 -164.827755) (xy 93.288711 -164.892837) (xy 93.366995 -164.964043) (xy 93.43967 -165.040966)
			(xy 93.50632 -165.123166) (xy 93.566562 -165.21017) (xy 93.620051 -165.301481) (xy 93.666482 -165.396576)
			(xy 93.705587 -165.49491) (xy 93.737144 -165.595921) (xy 93.760971 -165.699028) (xy 93.776932 -165.803642)
			(xy 93.784936 -165.909164) (xy 93.785436 -165.962076) (xy 93.784936 -166.014988) (xy 93.776932 -166.12051)
			(xy 93.760971 -166.225124) (xy 93.737144 -166.328231) (xy 93.705587 -166.429242) (xy 93.666482 -166.527576)
			(xy 93.620051 -166.622671) (xy 93.566562 -166.713982) (xy 93.50632 -166.800986) (xy 93.43967 -166.883186)
			(xy 93.366995 -166.960109) (xy 93.288711 -167.031315) (xy 93.205265 -167.096397) (xy 93.117136 -167.154982)
			(xy 93.024829 -167.206734) (xy 92.928872 -167.251356) (xy 92.829815 -167.288594) (xy 92.728226 -167.318234)
			(xy 92.624686 -167.340105) (xy 92.519789 -167.354084) (xy 92.414135 -167.360089) (xy 92.308329 -167.358086)
			(xy 92.202978 -167.348087) (xy 92.098685 -167.330149) (xy 91.996047 -167.304375) (xy 91.895652 -167.270913)
			(xy 91.798075 -167.229953) (xy 91.703876 -167.181731) (xy 91.613593 -167.126524) (xy 91.527744 -167.064646)
			(xy 91.446821 -166.996453) (xy 91.371287 -166.922335) (xy 91.301575 -166.842717) (xy 91.238084 -166.758054)
			(xy 91.181177 -166.668833) (xy 91.131181 -166.575563) (xy 91.088383 -166.478779) (xy 91.053026 -166.379035)
			(xy 91.025315 -166.276903) (xy 91.005406 -166.172968) (xy 90.993416 -166.067825) (xy 90.989411 -165.962076)
			(xy 84.387436 -165.962076) (xy 84.386936 -166.014988) (xy 84.378932 -166.12051) (xy 84.362971 -166.225124)
			(xy 84.339144 -166.328231) (xy 84.307587 -166.429242) (xy 84.268482 -166.527576) (xy 84.222051 -166.622671)
			(xy 84.168562 -166.713982) (xy 84.10832 -166.800986) (xy 84.04167 -166.883186) (xy 83.968995 -166.960109)
			(xy 83.890711 -167.031315) (xy 83.807265 -167.096397) (xy 83.719136 -167.154982) (xy 83.626829 -167.206734)
			(xy 83.530872 -167.251356) (xy 83.431815 -167.288594) (xy 83.330226 -167.318234) (xy 83.226686 -167.340105)
			(xy 83.121789 -167.354084) (xy 83.016135 -167.360089) (xy 82.910329 -167.358086) (xy 82.804978 -167.348087)
			(xy 82.700685 -167.330149) (xy 82.598047 -167.304375) (xy 82.497652 -167.270913) (xy 82.400075 -167.229953)
			(xy 82.305876 -167.181731) (xy 82.215593 -167.126524) (xy 82.129744 -167.064646) (xy 82.048821 -166.996453)
			(xy 81.973287 -166.922335) (xy 81.903575 -166.842717) (xy 81.840084 -166.758054) (xy 81.783177 -166.668833)
			(xy 81.733181 -166.575563) (xy 81.690383 -166.478779) (xy 81.655026 -166.379035) (xy 81.627315 -166.276903)
			(xy 81.607406 -166.172968) (xy 81.595416 -166.067825) (xy 81.591411 -165.962076) (xy 63.903248 -165.962076)
			(xy 63.909379 -166.022525) (xy 63.909956 -166.067232) (xy 63.909956 -166.068248) (xy 63.909702 -166.079678)
			(xy 63.936181 -166.085625) (xy 63.988416 -166.100367) (xy 64.014096 -166.109142) (xy 64.022293 -166.111656)
			(xy 64.039427 -166.111656) (xy 64.047624 -166.109142) (xy 64.082842 -166.097202) (xy 64.154852 -166.078613)
			(xy 64.228174 -166.066171) (xy 64.302285 -166.059965) (xy 64.33947 -166.059612) (xy 64.376654 -166.059989)
			(xy 64.450761 -166.066209) (xy 64.524081 -166.078649) (xy 64.596093 -166.097221) (xy 64.631316 -166.109142)
			(xy 64.639513 -166.111656) (xy 64.656647 -166.111656) (xy 64.664844 -166.109142) (xy 64.699939 -166.097233)
			(xy 64.771698 -166.078689) (xy 64.844763 -166.066249) (xy 64.918616 -166.060001) (xy 64.955674 -166.059612)
			(xy 64.95669 -166.059612) (xy 64.998618 -166.060035) (xy 65.082094 -166.068005) (xy 65.164434 -166.083874)
			(xy 65.244893 -166.107498) (xy 65.322742 -166.138663) (xy 65.397276 -166.177087) (xy 65.46782 -166.222422)
			(xy 65.533735 -166.274258) (xy 65.594424 -166.332124) (xy 65.649338 -166.395498) (xy 65.69798 -166.463804)
			(xy 65.739908 -166.536425) (xy 65.774743 -166.612703) (xy 65.802169 -166.691946) (xy 65.821939 -166.773438)
			(xy 65.833873 -166.85644) (xy 65.837863 -166.9402) (xy 65.833873 -167.02396) (xy 65.821939 -167.106962)
			(xy 65.802169 -167.188454) (xy 65.774743 -167.267697) (xy 65.739908 -167.343975) (xy 65.69798 -167.416596)
			(xy 65.688295 -167.430196) (xy 351.432876 -167.430196) (xy 351.433453 -167.385427) (xy 351.442459 -167.296342)
			(xy 351.46036 -167.208611) (xy 351.486975 -167.123119) (xy 351.503996 -167.081708) (xy 351.507565 -167.072118)
			(xy 351.507564 -167.051674) (xy 351.503996 -167.042084) (xy 351.486956 -167.000679) (xy 351.460322 -166.91519)
			(xy 351.442419 -166.827456) (xy 351.433427 -166.738367) (xy 351.432876 -166.693596) (xy 351.433453 -166.648827)
			(xy 351.442459 -166.559742) (xy 351.46036 -166.472011) (xy 351.486975 -166.386519) (xy 351.503996 -166.345108)
			(xy 351.507565 -166.335518) (xy 351.507564 -166.315074) (xy 351.503996 -166.305484) (xy 351.486956 -166.264079)
			(xy 351.460322 -166.17859) (xy 351.442419 -166.090856) (xy 351.433427 -166.001767) (xy 351.432876 -165.956996)
			(xy 351.433349 -165.915886) (xy 351.440937 -165.834016) (xy 351.456047 -165.753196) (xy 351.478552 -165.674116)
			(xy 351.508259 -165.597449) (xy 351.544914 -165.523852) (xy 351.588204 -165.453951) (xy 351.63776 -165.388343)
			(xy 351.693159 -165.327588) (xy 351.753929 -165.272205) (xy 351.81955 -165.222667) (xy 351.889463 -165.179396)
			(xy 351.963071 -165.142761) (xy 352.039745 -165.113075) (xy 352.118832 -165.090592) (xy 352.199656 -165.075503)
			(xy 352.281528 -165.067937) (xy 352.322638 -165.067488) (xy 352.364242 -165.067962) (xy 352.44709 -165.075694)
			(xy 352.528855 -165.091124) (xy 352.608822 -165.114117) (xy 352.686295 -165.144474) (xy 352.760597 -165.181928)
			(xy 352.796094 -165.203632) (xy 352.805234 -165.208789) (xy 352.825949 -165.212002) (xy 352.846222 -165.206673)
			(xy 352.854768 -165.200584) (xy 352.888392 -165.174629) (xy 352.959771 -165.128573) (xy 353.035214 -165.08953)
			(xy 353.114035 -165.057855) (xy 353.195516 -165.033837) (xy 353.278916 -165.017694) (xy 353.363474 -165.009574)
			(xy 353.405948 -165.009068) (xy 353.406202 -165.009068) (xy 353.44731 -165.009511) (xy 353.529174 -165.017096)
			(xy 353.60999 -165.0322) (xy 353.689068 -165.054696) (xy 353.765733 -165.084391) (xy 353.839332 -165.121033)
			(xy 353.909237 -165.164307) (xy 353.974851 -165.213846) (xy 354.035616 -165.269227) (xy 354.091012 -165.329978)
			(xy 354.140567 -165.39558) (xy 354.183859 -165.465474) (xy 354.220519 -165.539063) (xy 354.250233 -165.615721)
			(xy 354.272749 -165.694793) (xy 354.287874 -165.775606) (xy 354.295479 -165.857468) (xy 354.295964 -165.898576)
			(xy 354.295409 -165.943346) (xy 354.286396 -166.032431) (xy 354.268489 -166.120162) (xy 354.241868 -166.205653)
			(xy 354.224844 -166.247064) (xy 354.221294 -166.256659) (xy 354.221285 -166.277097) (xy 354.224844 -166.286688)
			(xy 354.241856 -166.328036) (xy 354.268465 -166.413399) (xy 354.286369 -166.501003) (xy 354.289105 -166.527988)
			(xy 401.547076 -166.527988) (xy 401.54765 -166.483219) (xy 401.556657 -166.394134) (xy 401.574559 -166.306403)
			(xy 401.601175 -166.220911) (xy 401.618196 -166.1795) (xy 401.62177 -166.169912) (xy 401.621765 -166.149466)
			(xy 401.618196 -166.139876) (xy 401.601153 -166.098472) (xy 401.574521 -166.012983) (xy 401.556618 -165.925248)
			(xy 401.547627 -165.836159) (xy 401.547076 -165.791388) (xy 401.54765 -165.746619) (xy 401.556657 -165.657534)
			(xy 401.574559 -165.569803) (xy 401.601175 -165.484311) (xy 401.618196 -165.4429) (xy 401.62177 -165.433312)
			(xy 401.621765 -165.412866) (xy 401.618196 -165.403276) (xy 401.601153 -165.361872) (xy 401.574521 -165.276383)
			(xy 401.556618 -165.188648) (xy 401.547627 -165.099559) (xy 401.547076 -165.054788) (xy 401.547541 -165.013678)
			(xy 401.55513 -164.931808) (xy 401.570241 -164.850988) (xy 401.592747 -164.771907) (xy 401.622454 -164.695241)
			(xy 401.659109 -164.621643) (xy 401.7024 -164.551742) (xy 401.751957 -164.486134) (xy 401.807357 -164.42538)
			(xy 401.868127 -164.369997) (xy 401.933748 -164.320459) (xy 402.003662 -164.277187) (xy 402.07727 -164.240553)
			(xy 402.153944 -164.210867) (xy 402.233031 -164.188384) (xy 402.313856 -164.173295) (xy 402.395728 -164.165729)
			(xy 402.436838 -164.16528) (xy 402.478442 -164.165755) (xy 402.56129 -164.173487) (xy 402.643054 -164.188917)
			(xy 402.723022 -164.21191) (xy 402.800495 -164.242266) (xy 402.874796 -164.27972) (xy 402.910294 -164.301424)
			(xy 402.919434 -164.306582) (xy 402.940149 -164.309796) (xy 402.960422 -164.304466) (xy 402.968968 -164.298376)
			(xy 403.002591 -164.27242) (xy 403.07397 -164.226364) (xy 403.149414 -164.187321) (xy 403.228235 -164.155647)
			(xy 403.309716 -164.131629) (xy 403.393116 -164.115486) (xy 403.477674 -164.107366) (xy 403.520148 -164.10686)
			(xy 403.520402 -164.10686) (xy 403.561509 -164.107311) (xy 403.643374 -164.114895) (xy 403.724189 -164.13)
			(xy 403.803267 -164.152496) (xy 403.879931 -164.182191) (xy 403.95353 -164.218831) (xy 404.023434 -164.262106)
			(xy 404.089048 -164.311644) (xy 404.149813 -164.367025) (xy 404.205209 -164.427775) (xy 404.254764 -164.493376)
			(xy 404.298057 -164.563269) (xy 404.334716 -164.636858) (xy 404.364431 -164.713515) (xy 404.386947 -164.792587)
			(xy 404.402073 -164.873398) (xy 404.409679 -164.955261) (xy 404.410164 -164.996368) (xy 404.409606 -165.041138)
			(xy 404.400594 -165.130223) (xy 404.382688 -165.217954) (xy 404.356068 -165.303445) (xy 404.339044 -165.344856)
			(xy 404.335498 -165.354452) (xy 404.335487 -165.374889) (xy 404.339044 -165.38448) (xy 404.356053 -165.425829)
			(xy 404.382663 -165.511192) (xy 404.400568 -165.598795) (xy 404.409589 -165.687753) (xy 404.410164 -165.73246)
			(xy 404.410164 -165.733476) (xy 404.40991 -165.744906) (xy 404.436389 -165.750851) (xy 404.488624 -165.765594)
			(xy 404.514304 -165.77437) (xy 404.522501 -165.776884) (xy 404.539635 -165.776884) (xy 404.547832 -165.77437)
			(xy 404.58305 -165.762429) (xy 404.655059 -165.74384) (xy 404.728382 -165.731398) (xy 404.802492 -165.725192)
			(xy 404.839678 -165.72484) (xy 404.876862 -165.725213) (xy 404.95097 -165.731434) (xy 405.02429 -165.743875)
			(xy 405.096301 -165.762448) (xy 405.131524 -165.77437) (xy 405.139721 -165.776884) (xy 405.156855 -165.776884)
			(xy 405.165052 -165.77437) (xy 405.200146 -165.76246) (xy 405.271906 -165.743916) (xy 405.344971 -165.731476)
			(xy 405.418824 -165.725229) (xy 405.455882 -165.72484) (xy 405.456898 -165.72484) (xy 405.498822 -165.725407)
			(xy 405.582291 -165.733377) (xy 405.664623 -165.749245) (xy 405.745075 -165.772868) (xy 405.822917 -165.804031)
			(xy 405.897444 -165.842452) (xy 405.967982 -165.887784) (xy 406.033891 -165.939615) (xy 406.094575 -165.997477)
			(xy 406.149484 -166.060845) (xy 406.198121 -166.129146) (xy 406.240045 -166.20176) (xy 406.274876 -166.278031)
			(xy 406.302301 -166.357268) (xy 406.322068 -166.438752) (xy 406.334001 -166.521747) (xy 406.337991 -166.6055)
			(xy 406.334001 -166.689253) (xy 406.322068 -166.772248) (xy 406.302301 -166.853732) (xy 406.274876 -166.932969)
			(xy 406.240045 -167.00924) (xy 406.198121 -167.081854) (xy 406.149484 -167.150155) (xy 406.094575 -167.213523)
			(xy 406.033891 -167.271385) (xy 405.967982 -167.323216) (xy 405.897444 -167.368548) (xy 405.822917 -167.406969)
			(xy 405.745075 -167.438132) (xy 405.664623 -167.461755) (xy 405.582291 -167.477623) (xy 405.498822 -167.485593)
			(xy 405.456898 -167.486076) (xy 405.455882 -167.486076) (xy 405.418825 -167.485672) (xy 405.344976 -167.479407)
			(xy 405.271913 -167.466964) (xy 405.200153 -167.448432) (xy 405.165052 -167.436546) (xy 405.156855 -167.434032)
			(xy 405.139721 -167.434032) (xy 405.131524 -167.436546) (xy 405.102638 -167.446383) (xy 405.043785 -167.462529)
			(xy 405.013922 -167.468804) (xy 405.004334 -167.471159) (xy 404.987889 -167.482054) (xy 404.976796 -167.498367)
			(xy 404.974298 -167.50792) (xy 404.96417 -167.552275) (xy 404.936046 -167.638805) (xy 404.918164 -167.68064)
			(xy 404.914347 -167.690579) (xy 404.914353 -167.711846) (xy 404.918164 -167.721788) (xy 404.936394 -167.764388)
			(xy 404.964909 -167.852556) (xy 404.984099 -167.943213) (xy 404.993757 -168.035373) (xy 404.994364 -168.081706)
			(xy 404.994364 -168.082214) (xy 404.99386 -168.124562) (xy 404.985809 -168.208876) (xy 404.96978 -168.292042)
			(xy 404.945919 -168.373309) (xy 404.91444 -168.451939) (xy 404.875629 -168.52722) (xy 404.829839 -168.598472)
			(xy 404.777483 -168.665048) (xy 404.719035 -168.726346) (xy 404.655025 -168.781811) (xy 404.586033 -168.83094)
			(xy 404.512683 -168.873289) (xy 404.43564 -168.908473) (xy 404.355601 -168.936175) (xy 404.273292 -168.956143)
			(xy 404.189457 -168.968196) (xy 404.104856 -168.972227) (xy 404.020255 -168.968196) (xy 403.93642 -168.956143)
			(xy 403.854111 -168.936175) (xy 403.774072 -168.908473) (xy 403.697029 -168.873289) (xy 403.623679 -168.83094)
			(xy 403.554687 -168.781811) (xy 403.490677 -168.726346) (xy 403.432229 -168.665048) (xy 403.379873 -168.598472)
			(xy 403.334083 -168.52722) (xy 403.295272 -168.451939) (xy 403.263793 -168.373309) (xy 403.239932 -168.292042)
			(xy 403.223903 -168.208876) (xy 403.215852 -168.124562) (xy 403.215348 -168.082214) (xy 403.215348 -168.081706)
			(xy 403.215963 -168.035374) (xy 403.225632 -167.943217) (xy 403.244825 -167.852563) (xy 403.273334 -167.764394)
			(xy 403.291548 -167.721788) (xy 403.295348 -167.711844) (xy 403.295353 -167.690582) (xy 403.291548 -167.68064)
			(xy 403.273311 -167.637974) (xy 403.244764 -167.549684) (xy 403.225569 -167.458899) (xy 403.215934 -167.36661)
			(xy 403.215348 -167.320214) (xy 403.215953 -167.272404) (xy 403.226131 -167.177329) (xy 403.235668 -167.130476)
			(xy 403.23764 -167.118071) (xy 403.230727 -167.093957) (xy 403.22246 -167.084502) (xy 403.18182 -167.042338)
			(xy 403.178264 -167.0431) (xy 403.169416 -167.045411) (xy 403.154053 -167.055303) (xy 403.148292 -167.062404)
			(xy 403.123145 -167.095057) (xy 403.067744 -167.156083) (xy 403.006935 -167.211722) (xy 402.941239 -167.261497)
			(xy 402.871221 -167.304981) (xy 402.79748 -167.341801) (xy 402.720649 -167.371642) (xy 402.641387 -167.394246)
			(xy 402.560373 -167.409421) (xy 402.478303 -167.417036) (xy 402.437092 -167.417496) (xy 402.436838 -167.417496)
			(xy 402.395733 -167.416951) (xy 402.313873 -167.409371) (xy 402.233061 -167.394271) (xy 402.153987 -167.37178)
			(xy 402.077325 -167.342091) (xy 402.003729 -167.305456) (xy 401.933826 -167.262187) (xy 401.868213 -167.212655)
			(xy 401.80745 -167.157281) (xy 401.752053 -167.096538) (xy 401.702497 -167.030943) (xy 401.659203 -166.961056)
			(xy 401.622541 -166.887473) (xy 401.592824 -166.810822) (xy 401.570304 -166.731756) (xy 401.555174 -166.65095)
			(xy 401.547564 -166.569093) (xy 401.547076 -166.527988) (xy 354.289105 -166.527988) (xy 354.295389 -166.589961)
			(xy 354.295964 -166.634668) (xy 354.295964 -166.635684) (xy 354.29571 -166.647114) (xy 354.322189 -166.653059)
			(xy 354.374424 -166.667802) (xy 354.400104 -166.676578) (xy 354.408301 -166.679092) (xy 354.425435 -166.679092)
			(xy 354.433632 -166.676578) (xy 354.468848 -166.664633) (xy 354.540859 -166.646046) (xy 354.614181 -166.633606)
			(xy 354.688292 -166.6274) (xy 354.725478 -166.627048) (xy 354.762662 -166.62742) (xy 354.83677 -166.633641)
			(xy 354.91009 -166.646083) (xy 354.982101 -166.664656) (xy 355.017324 -166.676578) (xy 355.025521 -166.679092)
			(xy 355.042655 -166.679092) (xy 355.050852 -166.676578) (xy 355.085946 -166.664669) (xy 355.157706 -166.646124)
			(xy 355.230771 -166.633684) (xy 355.304624 -166.627437) (xy 355.341682 -166.627048) (xy 355.342698 -166.627048)
			(xy 355.384622 -166.627599) (xy 355.468092 -166.635569) (xy 355.550425 -166.651437) (xy 355.630878 -166.67506)
			(xy 355.70872 -166.706224) (xy 355.783248 -166.744645) (xy 355.853787 -166.789977) (xy 355.919696 -166.841809)
			(xy 355.980381 -166.899671) (xy 356.03529 -166.96304) (xy 356.083927 -167.031341) (xy 356.125852 -167.103957)
			(xy 356.160684 -167.180228) (xy 356.188108 -167.259465) (xy 356.207876 -167.340951) (xy 356.219809 -167.423946)
			(xy 356.223799 -167.5077) (xy 356.219809 -167.591454) (xy 356.207876 -167.674449) (xy 356.188108 -167.755935)
			(xy 356.160684 -167.835172) (xy 356.125852 -167.911443) (xy 356.083927 -167.984059) (xy 356.03529 -168.05236)
			(xy 355.980381 -168.115729) (xy 355.919696 -168.173591) (xy 355.853787 -168.225423) (xy 355.783248 -168.270755)
			(xy 355.70872 -168.309176) (xy 355.630878 -168.34034) (xy 355.550425 -168.363963) (xy 355.468092 -168.379831)
			(xy 355.384622 -168.387801) (xy 355.342698 -168.388284) (xy 355.341682 -168.388284) (xy 355.304625 -168.387885)
			(xy 355.230776 -168.381619) (xy 355.157713 -168.369175) (xy 355.085953 -168.350641) (xy 355.050852 -168.338754)
			(xy 355.042655 -168.33624) (xy 355.025521 -168.33624) (xy 355.017324 -168.338754) (xy 354.989546 -168.348208)
			(xy 354.932984 -168.363843) (xy 354.904294 -168.369996) (xy 354.894532 -168.372423) (xy 354.877923 -168.383747)
			(xy 354.866932 -168.400579) (xy 354.86467 -168.410382) (xy 354.855142 -168.457509) (xy 354.827269 -168.549532)
			(xy 354.809044 -168.594024) (xy 354.805459 -168.603609) (xy 354.805473 -168.624057) (xy 354.809044 -168.633648)
			(xy 354.826071 -168.675024) (xy 354.852688 -168.760451) (xy 354.870591 -168.84812) (xy 354.879599 -168.937143)
			(xy 354.880164 -168.981882) (xy 354.880164 -168.982136) (xy 354.87966 -169.024484) (xy 354.871609 -169.108798)
			(xy 354.85558 -169.191964) (xy 354.831719 -169.273231) (xy 354.80024 -169.351861) (xy 354.761429 -169.427142)
			(xy 354.715639 -169.498394) (xy 354.663283 -169.56497) (xy 354.604835 -169.626268) (xy 354.540825 -169.681733)
			(xy 354.471833 -169.730862) (xy 354.398483 -169.773211) (xy 354.32144 -169.808395) (xy 354.241401 -169.836097)
			(xy 354.159092 -169.856065) (xy 354.075257 -169.868118) (xy 353.990656 -169.872149) (xy 353.906055 -169.868118)
			(xy 353.82222 -169.856065) (xy 353.739911 -169.836097) (xy 353.659872 -169.808395) (xy 353.582829 -169.773211)
			(xy 353.509479 -169.730862) (xy 353.440487 -169.681733) (xy 353.376477 -169.626268) (xy 353.318029 -169.56497)
			(xy 353.265673 -169.498394) (xy 353.219883 -169.427142) (xy 353.181072 -169.351861) (xy 353.149593 -169.273231)
			(xy 353.125732 -169.191964) (xy 353.109703 -169.108798) (xy 353.101652 -169.024484) (xy 353.101148 -168.982136)
			(xy 353.101148 -168.981882) (xy 353.101731 -168.937144) (xy 353.110743 -168.848123) (xy 353.128644 -168.760456)
			(xy 353.155252 -168.675028) (xy 353.172268 -168.633648) (xy 353.175811 -168.624051) (xy 353.175824 -168.603615)
			(xy 353.172268 -168.594024) (xy 353.155227 -168.55262) (xy 353.128597 -168.46713) (xy 353.110694 -168.379396)
			(xy 353.1017 -168.290307) (xy 353.101148 -168.245536) (xy 353.101148 -168.24452) (xy 353.101526 -168.208908)
			(xy 353.107261 -168.137915) (xy 353.118654 -168.067607) (xy 353.126802 -168.032938) (xy 353.128529 -168.024629)
			(xy 353.126997 -168.007741) (xy 353.119979 -167.992303) (xy 353.114356 -167.985948) (xy 353.07397 -167.943276)
			(xy 353.064064 -167.945308) (xy 353.055164 -167.947623) (xy 353.039671 -167.957504) (xy 353.033838 -167.964612)
			(xy 353.008691 -167.997264) (xy 352.953283 -168.058281) (xy 352.892469 -168.113912) (xy 352.826771 -168.163681)
			(xy 352.756752 -168.207161) (xy 352.683013 -168.243979) (xy 352.606184 -168.273821) (xy 352.526925 -168.29643)
			(xy 352.445915 -168.311612) (xy 352.363848 -168.319237) (xy 352.322638 -168.319704) (xy 352.281533 -168.319151)
			(xy 352.199674 -168.311571) (xy 352.118862 -168.296471) (xy 352.039789 -168.273981) (xy 351.963127 -168.244292)
			(xy 351.889531 -168.207657) (xy 351.819629 -168.164389) (xy 351.754016 -168.114857) (xy 351.693252 -168.059484)
			(xy 351.637856 -167.998741) (xy 351.5883 -167.933147) (xy 351.545006 -167.863261) (xy 351.508343 -167.789678)
			(xy 351.478626 -167.713028) (xy 351.456106 -167.633963) (xy 351.440975 -167.553157) (xy 351.433364 -167.471301)
			(xy 351.432876 -167.430196) (xy 65.688295 -167.430196) (xy 65.649338 -167.484902) (xy 65.594424 -167.548276)
			(xy 65.533735 -167.606142) (xy 65.46782 -167.657978) (xy 65.397276 -167.703313) (xy 65.322742 -167.741737)
			(xy 65.244893 -167.772902) (xy 65.164434 -167.796526) (xy 65.082094 -167.812395) (xy 64.998618 -167.820365)
			(xy 64.95669 -167.820848) (xy 64.955674 -167.820848) (xy 64.918617 -167.820448) (xy 64.844768 -167.814181)
			(xy 64.771705 -167.801738) (xy 64.699945 -167.783204) (xy 64.664844 -167.771318) (xy 64.656647 -167.768804)
			(xy 64.639513 -167.768804) (xy 64.631316 -167.771318) (xy 64.597889 -167.782662) (xy 64.529607 -167.80059)
			(xy 64.494918 -167.807132) (xy 64.484907 -167.809437) (xy 64.467748 -167.820693) (xy 64.456372 -167.837772)
			(xy 64.454024 -167.847772) (xy 64.44452 -167.895628) (xy 64.416383 -167.989057) (xy 64.39789 -168.034208)
			(xy 64.394248 -168.043772) (xy 64.394124 -168.064219) (xy 64.397636 -168.073832) (xy 64.414658 -168.11521)
			(xy 64.441276 -168.200636) (xy 64.459181 -168.288304) (xy 64.46819 -168.377327) (xy 64.468756 -168.422066)
			(xy 64.468756 -168.42232) (xy 64.468252 -168.464668) (xy 64.460201 -168.548982) (xy 64.444172 -168.632148)
			(xy 64.420311 -168.713415) (xy 64.388832 -168.792045) (xy 64.350021 -168.867326) (xy 64.304231 -168.938578)
			(xy 64.251875 -169.005154) (xy 64.193427 -169.066452) (xy 64.129417 -169.121917) (xy 64.060425 -169.171046)
			(xy 63.987075 -169.213395) (xy 63.910032 -169.248579) (xy 63.829993 -169.276281) (xy 63.747684 -169.296249)
			(xy 63.663849 -169.308302) (xy 63.579248 -169.312333) (xy 63.494647 -169.308302) (xy 63.410812 -169.296249)
			(xy 63.328503 -169.276281) (xy 63.248464 -169.248579) (xy 63.171421 -169.213395) (xy 63.098071 -169.171046)
			(xy 63.029079 -169.121917) (xy 62.965069 -169.066452) (xy 62.906621 -169.005154) (xy 62.854265 -168.938578)
			(xy 62.808475 -168.867326) (xy 62.769664 -168.792045) (xy 62.738185 -168.713415) (xy 62.714324 -168.632148)
			(xy 62.698295 -168.548982) (xy 62.690244 -168.464668) (xy 62.68974 -168.42232) (xy 62.68974 -168.422066)
			(xy 62.690311 -168.377328) (xy 62.699325 -168.288306) (xy 62.71723 -168.200639) (xy 62.743842 -168.115211)
			(xy 62.76086 -168.073832) (xy 62.764412 -168.064238) (xy 62.76442 -168.043799) (xy 62.76086 -168.034208)
			(xy 62.743813 -167.992806) (xy 62.717185 -167.907315) (xy 62.699284 -167.81958) (xy 62.690292 -167.730491)
			(xy 62.68974 -167.68572) (xy 62.68974 -167.685466) (xy 62.689833 -167.667858) (xy 62.691229 -167.632668)
			(xy 62.692534 -167.615108) (xy 62.692907 -167.605036) (xy 62.68662 -167.585904) (xy 62.673425 -167.57069)
			(xy 62.664594 -167.565832) (xy 62.566296 -167.516556) (xy 62.535816 -167.520366) (xy 62.524132 -167.53078)
			(xy 62.493735 -167.556935) (xy 62.428993 -167.604263) (xy 62.360251 -167.645567) (xy 62.288069 -167.680512)
			(xy 62.213032 -167.708812) (xy 62.135751 -167.730238) (xy 62.056854 -167.744617) (xy 61.976982 -167.75183)
			(xy 61.936884 -167.752268) (xy 61.93663 -167.752268) (xy 61.895524 -167.751759) (xy 61.813662 -167.744177)
			(xy 61.732849 -167.729076) (xy 61.653773 -167.706584) (xy 61.57711 -167.676893) (xy 61.503513 -167.640256)
			(xy 61.433609 -167.596985) (xy 61.367995 -167.547451) (xy 61.307231 -167.492074) (xy 61.251835 -167.431328)
			(xy 61.202279 -167.36573) (xy 61.158986 -167.295841) (xy 61.122325 -167.222256) (xy 61.092608 -167.145602)
			(xy 61.07009 -167.066534) (xy 61.054963 -166.985725) (xy 61.047355 -166.903866) (xy 61.046868 -166.86276)
			(xy 2.509012 -166.86276) (xy 2.509012 -170.29303) (xy 8.7249 -170.29303) (xy 8.7249 -169.42943) (xy 8.725386 -169.402179)
			(xy 8.733142 -169.348231) (xy 8.748497 -169.295936) (xy 8.771139 -169.246359) (xy 8.800605 -169.200509)
			(xy 8.836296 -169.159318) (xy 8.877487 -169.123627) (xy 8.923337 -169.094161) (xy 8.972914 -169.071519)
			(xy 9.025209 -169.056164) (xy 9.079157 -169.048408) (xy 9.133659 -169.048408) (xy 9.187607 -169.056164)
			(xy 9.239902 -169.071519) (xy 9.289479 -169.094161) (xy 9.335329 -169.123627) (xy 9.37652 -169.159318)
			(xy 9.412211 -169.200509) (xy 9.441677 -169.246359) (xy 9.464319 -169.295936) (xy 9.479674 -169.348231)
			(xy 9.48743 -169.402179) (xy 9.487916 -169.42943) (xy 9.487916 -169.857674) (xy 111.084868 -169.857674)
			(xy 111.085438 -169.812905) (xy 111.094447 -169.72382) (xy 111.112349 -169.636089) (xy 111.138966 -169.550597)
			(xy 111.155988 -169.509186) (xy 111.15957 -169.4996) (xy 111.15956 -169.479153) (xy 111.155988 -169.469562)
			(xy 111.13894 -169.42816) (xy 111.112309 -169.34267) (xy 111.094408 -169.254935) (xy 111.085418 -169.165845)
			(xy 111.084868 -169.121074) (xy 111.085438 -169.076305) (xy 111.094447 -168.98722) (xy 111.112349 -168.899489)
			(xy 111.138966 -168.813997) (xy 111.155988 -168.772586) (xy 111.15957 -168.763) (xy 111.15956 -168.742553)
			(xy 111.155988 -168.732962) (xy 111.13894 -168.69156) (xy 111.112309 -168.60607) (xy 111.094408 -168.518335)
			(xy 111.085418 -168.429245) (xy 111.084868 -168.384474) (xy 111.085274 -168.343358) (xy 111.092864 -168.261476)
			(xy 111.107976 -168.180645) (xy 111.130482 -168.101552) (xy 111.160191 -168.024873) (xy 111.196847 -167.951263)
			(xy 111.240139 -167.881349) (xy 111.289697 -167.815728) (xy 111.345099 -167.754959) (xy 111.405871 -167.699561)
			(xy 111.471495 -167.650007) (xy 111.541412 -167.60672) (xy 111.615025 -167.570068) (xy 111.691705 -167.540365)
			(xy 111.770799 -167.517863) (xy 111.851632 -167.502756) (xy 111.933514 -167.495171) (xy 111.97463 -167.494712)
			(xy 112.016241 -167.495173) (xy 112.099098 -167.502953) (xy 112.180867 -167.518431) (xy 112.260835 -167.541474)
			(xy 112.338303 -167.571879) (xy 112.412595 -167.609382) (xy 112.448086 -167.63111) (xy 112.457229 -167.636263)
			(xy 112.477942 -167.63948) (xy 112.498214 -167.634152) (xy 112.50676 -167.628062) (xy 112.540389 -167.602071)
			(xy 112.611783 -167.555946) (xy 112.687254 -167.516845) (xy 112.766112 -167.485124) (xy 112.847637 -167.461075)
			(xy 112.931085 -167.444915) (xy 113.015695 -167.436793) (xy 113.058194 -167.436292) (xy 113.099307 -167.436819)
			(xy 113.181182 -167.444405) (xy 113.262007 -167.459513) (xy 113.341094 -167.482013) (xy 113.417768 -167.511715)
			(xy 113.491374 -167.548365) (xy 113.561284 -167.59165) (xy 113.626903 -167.6412) (xy 113.68767 -167.696593)
			(xy 113.743067 -167.757357) (xy 113.792621 -167.822973) (xy 113.83591 -167.892881) (xy 113.872564 -167.966485)
			(xy 113.90227 -168.043156) (xy 113.924776 -168.122242) (xy 113.939888 -168.203067) (xy 113.947479 -168.284941)
			(xy 113.947956 -168.326054) (xy 113.947393 -168.370824) (xy 113.938383 -168.459909) (xy 113.920477 -168.54764)
			(xy 113.893859 -168.633131) (xy 113.876836 -168.674542) (xy 113.873299 -168.684141) (xy 113.873282 -168.704576)
			(xy 113.876836 -168.714166) (xy 113.89384 -168.755517) (xy 113.920451 -168.840879) (xy 113.938358 -168.928482)
			(xy 113.94738 -169.017439) (xy 113.947956 -169.062146) (xy 113.947956 -169.063162) (xy 113.947702 -169.074592)
			(xy 113.974181 -169.080538) (xy 114.026416 -169.095281) (xy 114.052096 -169.104056) (xy 114.060293 -169.10657)
			(xy 114.077427 -169.10657) (xy 114.085624 -169.104056) (xy 114.12084 -169.092095) (xy 114.192844 -169.073441)
			(xy 114.266165 -169.060932) (xy 114.34028 -169.054659) (xy 114.37747 -169.054272) (xy 114.414659 -169.054671)
			(xy 114.488772 -169.060958) (xy 114.562092 -169.073465) (xy 114.634098 -169.092103) (xy 114.669316 -169.104056)
			(xy 114.677513 -169.10657) (xy 114.694647 -169.10657) (xy 114.702844 -169.104056) (xy 114.738059 -169.092089)
			(xy 114.810062 -169.073437) (xy 114.883384 -169.06093) (xy 114.9575 -169.054658) (xy 114.99469 -169.054272)
			(xy 115.03663 -169.054667) (xy 115.120132 -169.062639) (xy 115.202497 -169.078513) (xy 115.28298 -169.102144)
			(xy 115.360853 -169.133319) (xy 115.43541 -169.171755) (xy 115.505975 -169.217104) (xy 115.57191 -169.268955)
			(xy 115.632618 -169.326839) (xy 115.687549 -169.390232) (xy 115.736205 -169.458559) (xy 115.778146 -169.531202)
			(xy 115.812991 -169.607503) (xy 115.840426 -169.68677) (xy 115.860202 -169.768287) (xy 115.87214 -169.851314)
			(xy 115.876131 -169.9351) (xy 115.87214 -170.018886) (xy 115.860202 -170.101913) (xy 115.840426 -170.18343)
			(xy 115.812991 -170.262697) (xy 115.778146 -170.338998) (xy 115.736205 -170.411641) (xy 115.687549 -170.479968)
			(xy 115.632618 -170.543361) (xy 115.57191 -170.601245) (xy 115.505975 -170.653096) (xy 115.498571 -170.657854)
			(xy 161.052951 -170.657854) (xy 161.052951 -170.603346) (xy 161.060709 -170.549393) (xy 161.076066 -170.497093)
			(xy 161.09871 -170.447511) (xy 161.12818 -170.401657) (xy 161.163876 -170.360463) (xy 161.205071 -170.324769)
			(xy 161.250927 -170.295301) (xy 161.30051 -170.27266) (xy 161.352811 -170.257305) (xy 161.406764 -170.24955)
			(xy 161.434018 -170.249088) (xy 162.297618 -170.249088) (xy 162.324868 -170.249583) (xy 162.378813 -170.257342)
			(xy 162.431105 -170.272698) (xy 162.48068 -170.29534) (xy 162.526528 -170.324806) (xy 162.567715 -170.360498)
			(xy 162.603404 -170.401687) (xy 162.632869 -170.447536) (xy 162.655508 -170.497111) (xy 162.670862 -170.549404)
			(xy 162.678618 -170.60335) (xy 162.678618 -170.65785) (xy 162.670862 -170.711796) (xy 162.655508 -170.764089)
			(xy 162.632869 -170.813664) (xy 162.603404 -170.859513) (xy 162.567715 -170.900702) (xy 162.526528 -170.936394)
			(xy 162.48068 -170.96586) (xy 162.431105 -170.988502) (xy 162.378813 -171.003858) (xy 162.324868 -171.011617)
			(xy 162.297618 -171.012104) (xy 161.434018 -171.012104) (xy 161.406764 -171.01165) (xy 161.352811 -171.003895)
			(xy 161.30051 -170.98854) (xy 161.250927 -170.965899) (xy 161.205071 -170.936431) (xy 161.163876 -170.900737)
			(xy 161.12818 -170.859543) (xy 161.09871 -170.813689) (xy 161.076066 -170.764107) (xy 161.060709 -170.711807)
			(xy 161.052951 -170.657854) (xy 115.498571 -170.657854) (xy 115.43541 -170.698445) (xy 115.360853 -170.736881)
			(xy 115.28298 -170.768056) (xy 115.202497 -170.791687) (xy 115.120132 -170.807561) (xy 115.03663 -170.815533)
			(xy 114.99469 -170.816016) (xy 114.9575 -170.815629) (xy 114.883387 -170.809339) (xy 114.810068 -170.796828)
			(xy 114.738062 -170.778187) (xy 114.702844 -170.766232) (xy 114.694647 -170.763718) (xy 114.677513 -170.763718)
			(xy 114.669316 -170.766232) (xy 114.625188 -170.781068) (xy 114.534574 -170.80245) (xy 114.488468 -170.808904)
			(xy 114.478735 -170.810567) (xy 114.461516 -170.820188) (xy 114.449244 -170.83563) (xy 114.44605 -170.844972)
			(xy 114.43848 -170.870441) (xy 114.420685 -170.920512) (xy 114.41049 -170.945048) (xy 114.406882 -170.954622)
			(xy 114.406736 -170.97506) (xy 114.410236 -170.984672) (xy 114.427271 -171.026045) (xy 114.453886 -171.111473)
			(xy 114.471787 -171.199143) (xy 114.480792 -171.288167) (xy 114.481356 -171.332906) (xy 114.481356 -171.33316)
			(xy 114.480852 -171.375508) (xy 114.472801 -171.459822) (xy 114.456772 -171.542988) (xy 114.432911 -171.624255)
			(xy 114.401432 -171.702885) (xy 114.362621 -171.778166) (xy 114.316831 -171.849418) (xy 114.264475 -171.915994)
			(xy 114.206027 -171.977292) (xy 114.142017 -172.032757) (xy 114.073025 -172.081886) (xy 113.999675 -172.124235)
			(xy 113.922632 -172.159419) (xy 113.842593 -172.187121) (xy 113.760284 -172.207089) (xy 113.676449 -172.219142)
			(xy 113.591848 -172.223173) (xy 113.507247 -172.219142) (xy 113.423412 -172.207089) (xy 113.341103 -172.187121)
			(xy 113.261064 -172.159419) (xy 113.184021 -172.124235) (xy 113.110671 -172.081886) (xy 113.041679 -172.032757)
			(xy 112.977669 -171.977292) (xy 112.919221 -171.915994) (xy 112.866865 -171.849418) (xy 112.821075 -171.778166)
			(xy 112.782264 -171.702885) (xy 112.750785 -171.624255) (xy 112.726924 -171.542988) (xy 112.710895 -171.459822)
			(xy 112.702844 -171.375508) (xy 112.70234 -171.33316) (xy 112.70234 -171.332906) (xy 112.702891 -171.288167)
			(xy 112.711911 -171.199145) (xy 112.729821 -171.111478) (xy 112.75644 -171.026051) (xy 112.77346 -170.984672)
			(xy 112.777047 -170.975088) (xy 112.777032 -170.954639) (xy 112.77346 -170.945048) (xy 112.757652 -170.906707)
			(xy 112.732373 -170.827716) (xy 112.714548 -170.746717) (xy 112.70433 -170.664411) (xy 112.702594 -170.622976)
			(xy 112.702594 -170.622722) (xy 112.701955 -170.613271) (xy 112.694549 -170.595846) (xy 112.681333 -170.582289)
			(xy 112.672876 -170.578018) (xy 112.589818 -170.540172) (xy 112.581121 -170.536666) (xy 112.562416 -170.535564)
			(xy 112.544562 -170.541248) (xy 112.536986 -170.546776) (xy 112.536986 -170.54703) (xy 112.536478 -170.54703)
			(xy 112.502475 -170.574102) (xy 112.430107 -170.622247) (xy 112.353386 -170.663099) (xy 112.273043 -170.696267)
			(xy 112.189846 -170.721435) (xy 112.104591 -170.738363) (xy 112.01809 -170.746889) (xy 111.97463 -170.747436)
			(xy 111.933515 -170.746973) (xy 111.851635 -170.739388) (xy 111.770804 -170.72428) (xy 111.691713 -170.701779)
			(xy 111.615035 -170.672075) (xy 111.541425 -170.635423) (xy 111.471511 -170.592135) (xy 111.405889 -170.542581)
			(xy 111.34512 -170.487183) (xy 111.289722 -170.426414) (xy 111.240167 -170.360793) (xy 111.196879 -170.290879)
			(xy 111.160226 -170.217269) (xy 111.130522 -170.140591) (xy 111.10802 -170.061499) (xy 111.092912 -169.980669)
			(xy 111.085327 -169.898789) (xy 111.084868 -169.857674) (xy 9.487916 -169.857674) (xy 9.487916 -170.29303)
			(xy 9.48743 -170.320281) (xy 9.479674 -170.374229) (xy 9.464319 -170.426524) (xy 9.441677 -170.476101)
			(xy 9.412211 -170.521951) (xy 9.37652 -170.563142) (xy 9.335329 -170.598833) (xy 9.289479 -170.628299)
			(xy 9.239902 -170.650941) (xy 9.187607 -170.666296) (xy 9.133659 -170.674052) (xy 9.079157 -170.674052)
			(xy 9.025209 -170.666296) (xy 8.972914 -170.650941) (xy 8.923337 -170.628299) (xy 8.877487 -170.598833)
			(xy 8.836296 -170.563142) (xy 8.800605 -170.521951) (xy 8.771139 -170.476101) (xy 8.748497 -170.426524)
			(xy 8.733142 -170.374229) (xy 8.725386 -170.320281) (xy 8.7249 -170.29303) (xy 2.509012 -170.29303)
			(xy 2.509012 -173.07814) (xy 8.7249 -173.07814) (xy 8.7249 -172.21454) (xy 8.725386 -172.187289)
			(xy 8.733142 -172.133341) (xy 8.748497 -172.081046) (xy 8.771139 -172.031469) (xy 8.800605 -171.985619)
			(xy 8.836296 -171.944428) (xy 8.877487 -171.908737) (xy 8.923337 -171.879271) (xy 8.972914 -171.856629)
			(xy 9.025209 -171.841274) (xy 9.079157 -171.833518) (xy 9.133659 -171.833518) (xy 9.187607 -171.841274)
			(xy 9.239902 -171.856629) (xy 9.289479 -171.879271) (xy 9.335329 -171.908737) (xy 9.37652 -171.944428)
			(xy 9.412211 -171.985619) (xy 9.441677 -172.031469) (xy 9.464319 -172.081046) (xy 9.479674 -172.133341)
			(xy 9.48743 -172.187289) (xy 9.487916 -172.21454) (xy 9.487916 -173.07814) (xy 9.48743 -173.105391)
			(xy 9.479674 -173.159339) (xy 9.464319 -173.211634) (xy 9.441677 -173.261211) (xy 9.412211 -173.307061)
			(xy 9.37652 -173.348252) (xy 9.335329 -173.383943) (xy 9.289479 -173.413409) (xy 9.239902 -173.436051)
			(xy 9.187607 -173.451406) (xy 9.133659 -173.459162) (xy 9.079157 -173.459162) (xy 9.025209 -173.451406)
			(xy 8.972914 -173.436051) (xy 8.923337 -173.413409) (xy 8.877487 -173.383943) (xy 8.836296 -173.348252)
			(xy 8.800605 -173.307061) (xy 8.771139 -173.261211) (xy 8.748497 -173.211634) (xy 8.733142 -173.159339)
			(xy 8.725386 -173.105391) (xy 8.7249 -173.07814) (xy 2.509012 -173.07814) (xy 2.509012 -175.848264)
			(xy 8.7249 -175.848264) (xy 8.7249 -174.984664) (xy 8.725386 -174.957413) (xy 8.733142 -174.903465)
			(xy 8.748497 -174.85117) (xy 8.771139 -174.801593) (xy 8.800605 -174.755743) (xy 8.836296 -174.714552)
			(xy 8.877487 -174.678861) (xy 8.923337 -174.649395) (xy 8.972914 -174.626753) (xy 9.025209 -174.611398)
			(xy 9.079157 -174.603642) (xy 9.133659 -174.603642) (xy 9.187607 -174.611398) (xy 9.239902 -174.626753)
			(xy 9.289479 -174.649395) (xy 9.335329 -174.678861) (xy 9.37652 -174.714552) (xy 9.412211 -174.755743)
			(xy 9.441677 -174.801593) (xy 9.464319 -174.85117) (xy 9.479674 -174.903465) (xy 9.48743 -174.957413)
			(xy 9.487916 -174.984664) (xy 9.487916 -175.559974) (xy 69.360288 -175.559974) (xy 69.360857 -175.515205)
			(xy 69.369865 -175.42612) (xy 69.387768 -175.338388) (xy 69.414386 -175.252897) (xy 69.431408 -175.211486)
			(xy 69.434989 -175.2019) (xy 69.43498 -175.181453) (xy 69.431408 -175.171862) (xy 69.414355 -175.130462)
			(xy 69.387726 -175.044971) (xy 69.369827 -174.957236) (xy 69.360838 -174.868145) (xy 69.360288 -174.823374)
			(xy 69.360857 -174.778605) (xy 69.369865 -174.68952) (xy 69.387768 -174.601788) (xy 69.414386 -174.516297)
			(xy 69.431408 -174.474886) (xy 69.434989 -174.4653) (xy 69.43498 -174.444853) (xy 69.431408 -174.435262)
			(xy 69.414355 -174.393862) (xy 69.387726 -174.308371) (xy 69.369827 -174.220636) (xy 69.360838 -174.131545)
			(xy 69.360288 -174.086774) (xy 69.360674 -174.045657) (xy 69.368264 -173.963775) (xy 69.383377 -173.882942)
			(xy 69.405884 -173.803848) (xy 69.435593 -173.727169) (xy 69.47225 -173.653557) (xy 69.515543 -173.583643)
			(xy 69.565103 -173.518021) (xy 69.620506 -173.457252) (xy 69.681279 -173.401854) (xy 69.746905 -173.3523)
			(xy 69.816824 -173.309013) (xy 69.890438 -173.272362) (xy 69.96712 -173.24266) (xy 70.046216 -173.220159)
			(xy 70.12705 -173.205053) (xy 70.208933 -173.19747) (xy 70.25005 -173.197012) (xy 70.29166 -173.197513)
			(xy 70.374516 -173.205285) (xy 70.456284 -173.220756) (xy 70.536252 -173.243791) (xy 70.613721 -173.274189)
			(xy 70.688014 -173.311686) (xy 70.723506 -173.33341) (xy 70.73264 -173.338581) (xy 70.753359 -173.341792)
			(xy 70.773635 -173.336456) (xy 70.78218 -173.330362) (xy 70.815836 -173.304408) (xy 70.887226 -173.258279)
			(xy 70.962691 -173.219173) (xy 71.041544 -173.187448) (xy 71.123065 -173.163392) (xy 71.20651 -173.147226)
			(xy 71.291116 -173.139097) (xy 71.333614 -173.138592) (xy 71.374727 -173.139099) (xy 71.456602 -173.146687)
			(xy 71.537428 -173.161797) (xy 71.616516 -173.1843) (xy 71.693189 -173.214003) (xy 71.703445 -173.21911)
			(xy 393.739116 -173.21911) (xy 393.739743 -173.172708) (xy 393.749432 -173.08041) (xy 393.768686 -172.989625)
			(xy 393.797294 -172.90134) (xy 393.81557 -172.858684) (xy 393.819371 -172.84874) (xy 393.819374 -172.827478)
			(xy 393.81557 -172.817536) (xy 393.797307 -172.774875) (xy 393.768715 -172.686587) (xy 393.749458 -172.595804)
			(xy 393.739745 -172.503511) (xy 393.739116 -172.45711) (xy 393.739622 -172.415997) (xy 393.747208 -172.33412)
			(xy 393.762316 -172.253293) (xy 393.784818 -172.174205) (xy 393.81452 -172.097531) (xy 393.851171 -172.023924)
			(xy 393.894457 -171.954012) (xy 393.944008 -171.888393) (xy 393.999403 -171.827626) (xy 394.060168 -171.772229)
			(xy 394.125786 -171.722675) (xy 394.195696 -171.679387) (xy 394.269301 -171.642733) (xy 394.345975 -171.613028)
			(xy 394.425062 -171.590524) (xy 394.505889 -171.575413) (xy 394.587765 -171.567824) (xy 394.628878 -171.567348)
			(xy 394.670013 -171.567796) (xy 394.75193 -171.575416) (xy 394.832794 -171.590566) (xy 394.911913 -171.613115)
			(xy 394.988614 -171.642872) (xy 395.06224 -171.679583) (xy 395.132163 -171.722933) (xy 395.197785 -171.772553)
			(xy 395.258547 -171.828019) (xy 395.313929 -171.888856) (xy 395.339062 -171.921424) (xy 395.345281 -171.928954)
			(xy 395.36201 -171.939002) (xy 395.371574 -171.940982) (xy 395.41286 -171.948033) (xy 395.493962 -171.968978)
			(xy 395.572736 -171.997455) (xy 395.648484 -172.033212) (xy 395.720535 -172.075931) (xy 395.78825 -172.125234)
			(xy 395.851031 -172.180685) (xy 395.908321 -172.241793) (xy 395.959613 -172.308015) (xy 396.004452 -172.378766)
			(xy 396.042441 -172.453419) (xy 396.073244 -172.531313) (xy 396.096588 -172.611757) (xy 396.112266 -172.69404)
			(xy 396.120139 -172.777432) (xy 396.12062 -172.819314) (xy 396.120152 -172.860082) (xy 396.112652 -172.941273)
			(xy 396.097752 -173.021436) (xy 396.075577 -173.099899) (xy 396.046313 -173.176003) (xy 396.028672 -173.21276)
			(xy 396.024359 -173.222451) (xy 396.023438 -173.243625) (xy 396.026894 -173.253654) (xy 396.041217 -173.292003)
			(xy 396.063564 -173.370761) (xy 396.07857 -173.451241) (xy 396.086111 -173.53276) (xy 396.086584 -173.573694)
			(xy 396.086007 -173.618463) (xy 396.077001 -173.707548) (xy 396.0591 -173.795279) (xy 396.032485 -173.880771)
			(xy 396.015464 -173.922182) (xy 396.011903 -173.931774) (xy 396.0119 -173.952215) (xy 396.015464 -173.961806)
			(xy 396.032477 -174.003153) (xy 396.059087 -174.088517) (xy 396.076991 -174.17612) (xy 396.08601 -174.265079)
			(xy 396.086584 -174.309786) (xy 396.086584 -174.310802) (xy 396.08633 -174.322232) (xy 396.112809 -174.328178)
			(xy 396.165044 -174.342921) (xy 396.190724 -174.351696) (xy 396.198921 -174.35421) (xy 396.216055 -174.35421)
			(xy 396.224252 -174.351696) (xy 396.259466 -174.339729) (xy 396.33147 -174.321076) (xy 396.404792 -174.308569)
			(xy 396.478908 -174.302297) (xy 396.516098 -174.301912) (xy 396.553288 -174.302301) (xy 396.627401 -174.30859)
			(xy 396.70072 -174.3211) (xy 396.772726 -174.339741) (xy 396.807944 -174.351696) (xy 396.816141 -174.35421)
			(xy 396.833275 -174.35421) (xy 396.841472 -174.351696) (xy 396.876685 -174.339723) (xy 396.948689 -174.321072)
			(xy 397.022011 -174.308567) (xy 397.096127 -174.302297) (xy 397.133318 -174.301912) (xy 397.175254 -174.302444)
			(xy 397.258746 -174.310418) (xy 397.341102 -174.326292) (xy 397.421577 -174.349923) (xy 397.49944 -174.381096)
			(xy 397.573988 -174.41953) (xy 397.644545 -174.464875) (xy 397.710473 -174.516722) (xy 397.771173 -174.574601)
			(xy 397.826097 -174.637988) (xy 397.874747 -174.706309) (xy 397.916683 -174.778944) (xy 397.951524 -174.855237)
			(xy 397.978955 -174.934497) (xy 397.998729 -175.016005) (xy 398.010665 -175.099023) (xy 398.014656 -175.1828)
			(xy 398.010665 -175.266577) (xy 397.998729 -175.349595) (xy 397.978955 -175.431103) (xy 397.951524 -175.510363)
			(xy 397.916683 -175.586656) (xy 397.874747 -175.659291) (xy 397.826097 -175.727612) (xy 397.771173 -175.790999)
			(xy 397.710473 -175.848878) (xy 397.644545 -175.900725) (xy 397.573988 -175.94607) (xy 397.49944 -175.984504)
			(xy 397.421577 -176.015677) (xy 397.341102 -176.039308) (xy 397.258746 -176.055182) (xy 397.175254 -176.063156)
			(xy 397.133318 -176.063656) (xy 397.096129 -176.063259) (xy 397.022016 -176.056971) (xy 396.948696 -176.044464)
			(xy 396.87669 -176.025825) (xy 396.841472 -176.013872) (xy 396.833275 -176.011358) (xy 396.816141 -176.011358)
			(xy 396.807944 -176.013872) (xy 396.778999 -176.023726) (xy 396.720017 -176.039869) (xy 396.690088 -176.04613)
			(xy 396.680511 -176.048515) (xy 396.664071 -176.059402) (xy 396.652972 -176.0757) (xy 396.650464 -176.085246)
			(xy 396.640294 -176.12901) (xy 396.612299 -176.21439) (xy 396.594584 -176.25568) (xy 396.590807 -176.265631)
			(xy 396.590789 -176.286886) (xy 396.594584 -176.296828) (xy 396.612789 -176.339438) (xy 396.641312 -176.427603)
			(xy 396.660509 -176.518256) (xy 396.670174 -176.610414) (xy 396.670784 -176.656746) (xy 396.670784 -176.657254)
			(xy 396.67028 -176.699602) (xy 396.662229 -176.783916) (xy 396.6462 -176.867082) (xy 396.622339 -176.948349)
			(xy 396.59086 -177.026979) (xy 396.552049 -177.10226) (xy 396.506259 -177.173512) (xy 396.453903 -177.240088)
			(xy 396.395455 -177.301386) (xy 396.331445 -177.356851) (xy 396.262453 -177.40598) (xy 396.189103 -177.448329)
			(xy 396.11206 -177.483513) (xy 396.032021 -177.511215) (xy 395.949712 -177.531183) (xy 395.865877 -177.543236)
			(xy 395.781276 -177.547267) (xy 395.696675 -177.543236) (xy 395.61284 -177.531183) (xy 395.530531 -177.511215)
			(xy 395.450492 -177.483513) (xy 395.373449 -177.448329) (xy 395.300099 -177.40598) (xy 395.231107 -177.356851)
			(xy 395.167097 -177.301386) (xy 395.108649 -177.240088) (xy 395.056293 -177.173512) (xy 395.010503 -177.10226)
			(xy 394.971692 -177.026979) (xy 394.940213 -176.948349) (xy 394.916352 -176.867082) (xy 394.900323 -176.783916)
			(xy 394.892272 -176.699602) (xy 394.891768 -176.657254) (xy 394.891768 -176.656746) (xy 394.892395 -176.610415)
			(xy 394.902061 -176.518257) (xy 394.92125 -176.427603) (xy 394.949756 -176.339434) (xy 394.967968 -176.296828)
			(xy 394.971802 -176.286894) (xy 394.971784 -176.265622) (xy 394.967968 -176.25568) (xy 394.949707 -176.213025)
			(xy 394.921167 -176.12473) (xy 394.901979 -176.033943) (xy 394.89235 -175.941651) (xy 394.891768 -175.895254)
			(xy 394.89209 -175.858508) (xy 394.898067 -175.785262) (xy 394.903706 -175.74895) (xy 394.905149 -175.737024)
			(xy 394.898112 -175.714088) (xy 394.890244 -175.705008) (xy 394.824966 -175.637698) (xy 394.80236 -175.629824)
			(xy 394.790168 -175.631602) (xy 394.760779 -175.635286) (xy 394.701676 -175.63923) (xy 394.672058 -175.639476)
			(xy 394.630944 -175.639027) (xy 394.549066 -175.631436) (xy 394.468237 -175.616324) (xy 394.389148 -175.593818)
			(xy 394.312473 -175.564111) (xy 394.238865 -175.527456) (xy 394.168954 -175.484166) (xy 394.103335 -175.434611)
			(xy 394.042568 -175.379212) (xy 393.987171 -175.318444) (xy 393.937618 -175.252823) (xy 393.89433 -175.18291)
			(xy 393.857678 -175.109302) (xy 393.827973 -175.032625) (xy 393.80547 -174.953535) (xy 393.79036 -174.872707)
			(xy 393.782772 -174.790829) (xy 393.782296 -174.749714) (xy 393.782296 -174.749206) (xy 393.782815 -174.706532)
			(xy 393.791014 -174.621579) (xy 393.807309 -174.537801) (xy 393.83155 -174.455968) (xy 393.847066 -174.416212)
			(xy 393.850705 -174.406179) (xy 393.85003 -174.384863) (xy 393.845796 -174.375064) (xy 393.828734 -174.338786)
			(xy 393.800425 -174.263775) (xy 393.778984 -174.18652) (xy 393.764586 -174.107649) (xy 393.757348 -174.027801)
			(xy 393.756896 -173.987714) (xy 393.757452 -173.943459) (xy 393.766275 -173.855391) (xy 393.783795 -173.768633)
			(xy 393.809839 -173.684042) (xy 393.826492 -173.643036) (xy 393.830085 -173.632871) (xy 393.829579 -173.611348)
			(xy 393.825476 -173.60138) (xy 393.808875 -173.565511) (xy 393.781358 -173.491412) (xy 393.760529 -173.415162)
			(xy 393.746554 -173.337364) (xy 393.739543 -173.258632) (xy 393.739116 -173.21911) (xy 71.703445 -173.21911)
			(xy 71.766795 -173.250654) (xy 71.836706 -173.29394) (xy 71.902324 -173.343492) (xy 71.963091 -173.398886)
			(xy 72.018488 -173.459651) (xy 72.068042 -173.525268) (xy 72.11133 -173.595177) (xy 72.147984 -173.668781)
			(xy 72.17769 -173.745454) (xy 72.200196 -173.82454) (xy 72.215308 -173.905366) (xy 72.222899 -173.987241)
			(xy 72.223376 -174.028354) (xy 72.22282 -174.073124) (xy 72.213808 -174.162209) (xy 72.195901 -174.24994)
			(xy 72.16928 -174.335431) (xy 72.152256 -174.376842) (xy 72.148718 -174.38644) (xy 72.148701 -174.406876)
			(xy 72.152256 -174.416466) (xy 72.169272 -174.457846) (xy 72.195896 -174.543271) (xy 72.213802 -174.630939)
			(xy 72.222811 -174.719961) (xy 72.223376 -174.7647) (xy 72.223376 -174.765208) (xy 72.223122 -174.77867)
			(xy 72.249601 -174.784615) (xy 72.301836 -174.799358) (xy 72.327516 -174.808134) (xy 72.335713 -174.810648)
			(xy 72.352847 -174.810648) (xy 72.361044 -174.808134) (xy 72.39626 -174.796188) (xy 72.46827 -174.777601)
			(xy 72.541593 -174.765161) (xy 72.615704 -174.758956) (xy 72.65289 -174.758604) (xy 72.690074 -174.75897)
			(xy 72.764182 -174.765192) (xy 72.837502 -174.777635) (xy 72.909513 -174.796211) (xy 72.944736 -174.808134)
			(xy 72.952933 -174.810648) (xy 72.970067 -174.810648) (xy 72.978264 -174.808134) (xy 73.013366 -174.796247)
			(xy 73.085122 -174.777697) (xy 73.158185 -174.765251) (xy 73.232036 -174.758997) (xy 73.269094 -174.758604)
			(xy 73.27011 -174.758604) (xy 73.312036 -174.759059) (xy 73.395508 -174.767031) (xy 73.477845 -174.7829)
			(xy 73.5583 -174.806525) (xy 73.636145 -174.83769) (xy 73.710676 -174.876114) (xy 73.781216 -174.921448)
			(xy 73.847128 -174.973283) (xy 73.907814 -175.031148) (xy 73.962725 -175.094519) (xy 74.011364 -175.162823)
			(xy 74.053289 -175.235441) (xy 74.088123 -175.311716) (xy 74.115548 -175.390956) (xy 74.135316 -175.472444)
			(xy 74.14725 -175.555443) (xy 74.15124 -175.6392) (xy 74.14725 -175.722957) (xy 74.135316 -175.805956)
			(xy 74.115548 -175.887444) (xy 74.088123 -175.966684) (xy 74.053289 -176.042959) (xy 74.01685 -176.106074)
			(xy 102.855268 -176.106074) (xy 102.855838 -176.061305) (xy 102.864847 -175.97222) (xy 102.882749 -175.884489)
			(xy 102.909366 -175.798997) (xy 102.926388 -175.757586) (xy 102.92997 -175.748) (xy 102.92996 -175.727553)
			(xy 102.926388 -175.717962) (xy 102.90934 -175.67656) (xy 102.882709 -175.59107) (xy 102.864808 -175.503335)
			(xy 102.855818 -175.414245) (xy 102.855268 -175.369474) (xy 102.855838 -175.324705) (xy 102.864847 -175.23562)
			(xy 102.882749 -175.147889) (xy 102.909366 -175.062397) (xy 102.926388 -175.020986) (xy 102.92997 -175.0114)
			(xy 102.92996 -174.990953) (xy 102.926388 -174.981362) (xy 102.90934 -174.93996) (xy 102.882709 -174.85447)
			(xy 102.864808 -174.766735) (xy 102.855818 -174.677645) (xy 102.855268 -174.632874) (xy 102.855674 -174.591758)
			(xy 102.863264 -174.509876) (xy 102.878376 -174.429045) (xy 102.900882 -174.349952) (xy 102.930591 -174.273273)
			(xy 102.967247 -174.199663) (xy 103.010539 -174.129749) (xy 103.060097 -174.064128) (xy 103.115499 -174.003359)
			(xy 103.176271 -173.947961) (xy 103.241895 -173.898407) (xy 103.311812 -173.85512) (xy 103.385425 -173.818468)
			(xy 103.462105 -173.788765) (xy 103.541199 -173.766263) (xy 103.622032 -173.751156) (xy 103.703914 -173.743571)
			(xy 103.74503 -173.743112) (xy 103.786641 -173.743573) (xy 103.869498 -173.751353) (xy 103.951267 -173.766831)
			(xy 104.031235 -173.789874) (xy 104.108703 -173.820279) (xy 104.182995 -173.857782) (xy 104.218486 -173.87951)
			(xy 104.227629 -173.884663) (xy 104.248342 -173.88788) (xy 104.268614 -173.882552) (xy 104.27716 -173.876462)
			(xy 104.310789 -173.850471) (xy 104.382183 -173.804346) (xy 104.457654 -173.765245) (xy 104.536512 -173.733524)
			(xy 104.618037 -173.709475) (xy 104.701485 -173.693315) (xy 104.786095 -173.685193) (xy 104.828594 -173.684692)
			(xy 104.869707 -173.685219) (xy 104.951582 -173.692805) (xy 105.032407 -173.707913) (xy 105.111494 -173.730413)
			(xy 105.188168 -173.760115) (xy 105.261774 -173.796765) (xy 105.331684 -173.84005) (xy 105.397303 -173.8896)
			(xy 105.45807 -173.944993) (xy 105.513467 -174.005757) (xy 105.563021 -174.071373) (xy 105.60631 -174.141281)
			(xy 105.642964 -174.214885) (xy 105.67267 -174.291556) (xy 105.695176 -174.370642) (xy 105.710288 -174.451467)
			(xy 105.717879 -174.533341) (xy 105.718356 -174.574454) (xy 105.717793 -174.619224) (xy 105.708783 -174.708309)
			(xy 105.690877 -174.79604) (xy 105.664259 -174.881531) (xy 105.647236 -174.922942) (xy 105.643699 -174.932541)
			(xy 105.643682 -174.952976) (xy 105.647236 -174.962566) (xy 105.66424 -175.003917) (xy 105.690851 -175.089279)
			(xy 105.708758 -175.176882) (xy 105.71778 -175.265839) (xy 105.718356 -175.310546) (xy 105.718356 -175.311562)
			(xy 105.718102 -175.322992) (xy 105.744581 -175.328938) (xy 105.796816 -175.343681) (xy 105.822496 -175.352456)
			(xy 105.830693 -175.35497) (xy 105.847827 -175.35497) (xy 105.856024 -175.352456) (xy 105.89124 -175.340495)
			(xy 105.963244 -175.321841) (xy 106.036565 -175.309332) (xy 106.11068 -175.303059) (xy 106.14787 -175.302672)
			(xy 106.185059 -175.303071) (xy 106.259172 -175.309358) (xy 106.332492 -175.321865) (xy 106.404498 -175.340503)
			(xy 106.439716 -175.352456) (xy 106.447913 -175.35497) (xy 106.465047 -175.35497) (xy 106.473244 -175.352456)
			(xy 106.508459 -175.340489) (xy 106.580462 -175.321837) (xy 106.653784 -175.30933) (xy 106.7279 -175.303058)
			(xy 106.76509 -175.302672) (xy 106.80703 -175.303067) (xy 106.890532 -175.311039) (xy 106.972897 -175.326913)
			(xy 107.05338 -175.350544) (xy 107.131253 -175.381719) (xy 107.20581 -175.420155) (xy 107.276375 -175.465504)
			(xy 107.34231 -175.517355) (xy 107.403018 -175.575239) (xy 107.457949 -175.638632) (xy 107.505577 -175.705516)
			(xy 359.713276 -175.705516) (xy 359.713826 -175.660746) (xy 359.72284 -175.571661) (xy 359.740749 -175.48393)
			(xy 359.767371 -175.398439) (xy 359.784396 -175.357028) (xy 359.787954 -175.347435) (xy 359.78796 -175.326994)
			(xy 359.784396 -175.317404) (xy 359.767362 -175.275997) (xy 359.740727 -175.190508) (xy 359.722822 -175.102775)
			(xy 359.713828 -175.013687) (xy 359.713276 -174.968916) (xy 359.713826 -174.924146) (xy 359.72284 -174.835061)
			(xy 359.740749 -174.74733) (xy 359.767371 -174.661839) (xy 359.784396 -174.620428) (xy 359.787954 -174.610835)
			(xy 359.78796 -174.590394) (xy 359.784396 -174.580804) (xy 359.767362 -174.539397) (xy 359.740727 -174.453908)
			(xy 359.722822 -174.366175) (xy 359.713828 -174.277087) (xy 359.713276 -174.232316) (xy 359.713768 -174.191206)
			(xy 359.721354 -174.109337) (xy 359.736463 -174.028517) (xy 359.758966 -173.949437) (xy 359.788671 -173.872771)
			(xy 359.825324 -173.799173) (xy 359.868613 -173.729272) (xy 359.918168 -173.663664) (xy 359.973567 -173.602909)
			(xy 360.034335 -173.547526) (xy 360.099955 -173.497988) (xy 360.169867 -173.454716) (xy 360.243474 -173.418081)
			(xy 360.320148 -173.388396) (xy 360.399234 -173.365912) (xy 360.480057 -173.350823) (xy 360.561928 -173.343257)
			(xy 360.603038 -173.342808) (xy 360.644642 -173.343279) (xy 360.72749 -173.351011) (xy 360.809255 -173.366441)
			(xy 360.889223 -173.389435) (xy 360.966695 -173.419793) (xy 361.040997 -173.457248) (xy 361.076494 -173.478952)
			(xy 361.08563 -173.48412) (xy 361.106349 -173.487339) (xy 361.126625 -173.482001) (xy 361.135168 -173.475904)
			(xy 361.168794 -173.449952) (xy 361.240172 -173.403895) (xy 361.315615 -173.364851) (xy 361.394436 -173.333176)
			(xy 361.475917 -173.309157) (xy 361.559316 -173.293014) (xy 361.643874 -173.284894) (xy 361.686348 -173.284388)
			(xy 361.686602 -173.284388) (xy 361.72771 -173.284811) (xy 361.809576 -173.292396) (xy 361.890393 -173.307501)
			(xy 361.969472 -173.329998) (xy 362.046138 -173.359694) (xy 362.119738 -173.396336) (xy 362.189643 -173.439612)
			(xy 362.255258 -173.489152) (xy 362.316023 -173.544534) (xy 362.371419 -173.605287) (xy 362.420974 -173.67089)
			(xy 362.464266 -173.740786) (xy 362.500925 -173.814377) (xy 362.530638 -173.891036) (xy 362.553153 -173.97011)
			(xy 362.568276 -174.050924) (xy 362.57588 -174.132788) (xy 362.576364 -174.173896) (xy 362.575781 -174.218665)
			(xy 362.566776 -174.307749) (xy 362.548877 -174.395481) (xy 362.522264 -174.480972) (xy 362.505244 -174.522384)
			(xy 362.501683 -174.531976) (xy 362.501681 -174.552417) (xy 362.505244 -174.562008) (xy 362.522284 -174.603413)
			(xy 362.548917 -174.688902) (xy 362.56682 -174.776636) (xy 362.575812 -174.865725) (xy 362.576364 -174.910496)
			(xy 362.575094 -174.953676) (xy 362.575044 -174.965402) (xy 362.584373 -174.986895) (xy 362.602231 -175.002063)
			(xy 362.613448 -175.005492) (xy 362.632331 -175.010413) (xy 362.669682 -175.021721) (xy 362.688124 -175.028098)
			(xy 362.696321 -175.030612) (xy 362.713455 -175.030612) (xy 362.721652 -175.028098) (xy 362.756876 -175.016176)
			(xy 362.828883 -174.997583) (xy 362.902204 -174.985136) (xy 362.976313 -174.978924) (xy 363.013498 -174.978568)
			(xy 363.050682 -174.978934) (xy 363.12479 -174.985156) (xy 363.19811 -174.997599) (xy 363.270121 -175.016175)
			(xy 363.305344 -175.028098) (xy 363.313541 -175.030612) (xy 363.330675 -175.030612) (xy 363.338872 -175.028098)
			(xy 363.373974 -175.016212) (xy 363.44573 -174.997661) (xy 363.518793 -174.985214) (xy 363.592644 -174.978961)
			(xy 363.629702 -174.978568) (xy 363.630718 -174.978568) (xy 363.672642 -174.979095) (xy 363.75611 -174.987067)
			(xy 363.838443 -175.002937) (xy 363.918894 -175.026561) (xy 363.996736 -175.057726) (xy 364.071262 -175.096148)
			(xy 364.141799 -175.141481) (xy 364.207708 -175.193313) (xy 364.268391 -175.251175) (xy 364.323299 -175.314544)
			(xy 364.371935 -175.382845) (xy 364.413859 -175.45546) (xy 364.44869 -175.531731) (xy 364.476114 -175.610968)
			(xy 364.495881 -175.692452) (xy 364.507814 -175.775447) (xy 364.511804 -175.8592) (xy 364.507814 -175.942953)
			(xy 364.495881 -176.025948) (xy 364.476114 -176.107432) (xy 364.44869 -176.186669) (xy 364.413859 -176.26294)
			(xy 364.371935 -176.335555) (xy 364.323299 -176.403856) (xy 364.268391 -176.467225) (xy 364.207708 -176.525087)
			(xy 364.141799 -176.576919) (xy 364.071262 -176.622252) (xy 363.996736 -176.660674) (xy 363.918894 -176.691839)
			(xy 363.838443 -176.715463) (xy 363.75611 -176.731333) (xy 363.672642 -176.739305) (xy 363.630718 -176.739804)
			(xy 363.629702 -176.739804) (xy 363.592645 -176.739398) (xy 363.518796 -176.733134) (xy 363.445733 -176.720692)
			(xy 363.373973 -176.70216) (xy 363.338872 -176.690274) (xy 363.330675 -176.68776) (xy 363.313541 -176.68776)
			(xy 363.305344 -176.690274) (xy 363.271298 -176.701763) (xy 363.201741 -176.719817) (xy 363.166406 -176.726342)
			(xy 363.157048 -176.728326) (xy 363.140733 -176.738296) (xy 363.129218 -176.75356) (xy 363.126274 -176.762664)
			(xy 363.118487 -176.78918) (xy 363.100057 -176.841287) (xy 363.089444 -176.866804) (xy 363.085871 -176.876392)
			(xy 363.085877 -176.896837) (xy 363.089444 -176.906428) (xy 363.106465 -176.947806) (xy 363.133084 -177.033233)
			(xy 363.150988 -177.120901) (xy 363.159998 -177.209923) (xy 363.160564 -177.254662) (xy 363.160564 -177.254916)
			(xy 363.16006 -177.297264) (xy 363.152009 -177.381578) (xy 363.13598 -177.464744) (xy 363.112119 -177.546011)
			(xy 363.08064 -177.624641) (xy 363.041829 -177.699922) (xy 362.996039 -177.771174) (xy 362.943683 -177.83775)
			(xy 362.885235 -177.899048) (xy 362.821225 -177.954513) (xy 362.752233 -178.003642) (xy 362.678883 -178.045991)
			(xy 362.60184 -178.081175) (xy 362.521801 -178.108877) (xy 362.439492 -178.128845) (xy 362.355657 -178.140898)
			(xy 362.271056 -178.144929) (xy 362.186455 -178.140898) (xy 362.10262 -178.128845) (xy 362.020311 -178.108877)
			(xy 361.940272 -178.081175) (xy 361.863229 -178.045991) (xy 361.789879 -178.003642) (xy 361.720887 -177.954513)
			(xy 361.656877 -177.899048) (xy 361.598429 -177.83775) (xy 361.546073 -177.771174) (xy 361.500283 -177.699922)
			(xy 361.461472 -177.624641) (xy 361.429993 -177.546011) (xy 361.406132 -177.464744) (xy 361.390103 -177.381578)
			(xy 361.382052 -177.297264) (xy 361.381548 -177.254916) (xy 361.381548 -177.254662) (xy 361.382124 -177.209924)
			(xy 361.391138 -177.120903) (xy 361.409041 -177.033235) (xy 361.435651 -176.947807) (xy 361.452668 -176.906428)
			(xy 361.456222 -176.896834) (xy 361.456228 -176.876395) (xy 361.452668 -176.866804) (xy 361.435658 -176.825422)
			(xy 361.409036 -176.739997) (xy 361.391129 -176.65233) (xy 361.382115 -176.563308) (xy 361.381548 -176.51857)
			(xy 361.381548 -176.518316) (xy 361.38189 -176.482968) (xy 361.387504 -176.412495) (xy 361.39869 -176.34269)
			(xy 361.406694 -176.308258) (xy 361.409002 -176.295757) (xy 361.402463 -176.271224) (xy 361.394248 -176.261522)
			(xy 361.353608 -176.218596) (xy 361.34421 -176.220628) (xy 361.335443 -176.222892) (xy 361.32021 -176.232657)
			(xy 361.314492 -176.239678) (xy 361.289344 -176.272353) (xy 361.233931 -176.333418) (xy 361.173106 -176.389094)
			(xy 361.10739 -176.438902) (xy 361.037347 -176.482416) (xy 360.963578 -176.519263) (xy 360.886716 -176.549126)
			(xy 360.807421 -176.571748) (xy 360.726373 -176.586937) (xy 360.644268 -176.594561) (xy 360.603038 -176.595024)
			(xy 360.561931 -176.594551) (xy 360.480067 -176.58697) (xy 360.399251 -176.571868) (xy 360.320173 -176.549375)
			(xy 360.243508 -176.519683) (xy 360.169909 -176.483044) (xy 360.100004 -176.439772) (xy 360.034389 -176.390235)
			(xy 359.973624 -176.334856) (xy 359.918228 -176.274107) (xy 359.868672 -176.208506) (xy 359.825379 -176.138613)
			(xy 359.78872 -176.065025) (xy 359.759005 -175.988368) (xy 359.73649 -175.909296) (xy 359.721365 -175.828485)
			(xy 359.713761 -175.746623) (xy 359.713276 -175.705516) (xy 107.505577 -175.705516) (xy 107.506605 -175.706959)
			(xy 107.548546 -175.779602) (xy 107.583391 -175.855903) (xy 107.610826 -175.93517) (xy 107.630602 -176.016687)
			(xy 107.64254 -176.099714) (xy 107.646531 -176.1835) (xy 107.64254 -176.267286) (xy 107.630602 -176.350313)
			(xy 107.610826 -176.43183) (xy 107.583391 -176.511097) (xy 107.548546 -176.587398) (xy 107.506605 -176.660041)
			(xy 107.457949 -176.728368) (xy 107.403018 -176.791761) (xy 107.34231 -176.849645) (xy 107.276375 -176.901496)
			(xy 107.20581 -176.946845) (xy 107.131253 -176.985281) (xy 107.05338 -177.016456) (xy 106.972897 -177.040087)
			(xy 106.890532 -177.055961) (xy 106.80703 -177.063933) (xy 106.76509 -177.064416) (xy 106.7279 -177.064029)
			(xy 106.653787 -177.057739) (xy 106.580468 -177.045228) (xy 106.508462 -177.026587) (xy 106.473244 -177.014632)
			(xy 106.465047 -177.012118) (xy 106.447913 -177.012118) (xy 106.439716 -177.014632) (xy 106.394061 -177.029945)
			(xy 106.300252 -177.051713) (xy 106.252518 -177.058066) (xy 106.242041 -177.059824) (xy 106.223772 -177.070618)
			(xy 106.211473 -177.087908) (xy 106.20883 -177.098198) (xy 106.199325 -177.142161) (xy 106.1726 -177.22805)
			(xy 106.15549 -177.269648) (xy 106.151882 -177.279222) (xy 106.151736 -177.29966) (xy 106.155236 -177.309272)
			(xy 106.172271 -177.350645) (xy 106.198886 -177.436073) (xy 106.216787 -177.523743) (xy 106.225792 -177.612767)
			(xy 106.226356 -177.657506) (xy 106.226356 -177.65776) (xy 106.225852 -177.700108) (xy 106.217801 -177.784422)
			(xy 106.201772 -177.867588) (xy 106.177911 -177.948855) (xy 106.146432 -178.027485) (xy 106.107621 -178.102766)
			(xy 106.061831 -178.174018) (xy 106.009475 -178.240594) (xy 105.951027 -178.301892) (xy 105.887017 -178.357357)
			(xy 105.818025 -178.406486) (xy 105.744675 -178.448835) (xy 105.667632 -178.484019) (xy 105.587593 -178.511721)
			(xy 105.505284 -178.531689) (xy 105.421449 -178.543742) (xy 105.336848 -178.547773) (xy 105.252247 -178.543742)
			(xy 105.168412 -178.531689) (xy 105.086103 -178.511721) (xy 105.006064 -178.484019) (xy 104.929021 -178.448835)
			(xy 104.855671 -178.406486) (xy 104.786679 -178.357357) (xy 104.722669 -178.301892) (xy 104.664221 -178.240594)
			(xy 104.611865 -178.174018) (xy 104.566075 -178.102766) (xy 104.527264 -178.027485) (xy 104.495785 -177.948855)
			(xy 104.471924 -177.867588) (xy 104.455895 -177.784422) (xy 104.447844 -177.700108) (xy 104.44734 -177.65776)
			(xy 104.44734 -177.657506) (xy 104.447891 -177.612767) (xy 104.456911 -177.523745) (xy 104.474821 -177.436078)
			(xy 104.50144 -177.350651) (xy 104.51846 -177.309272) (xy 104.522047 -177.299688) (xy 104.522032 -177.279239)
			(xy 104.51846 -177.269648) (xy 104.501426 -177.228241) (xy 104.474794 -177.142752) (xy 104.456889 -177.055019)
			(xy 104.447894 -176.965931) (xy 104.44734 -176.92116) (xy 104.447594 -176.89703) (xy 104.44745 -176.887477)
			(xy 104.440882 -176.869548) (xy 104.428227 -176.855249) (xy 104.419908 -176.850548) (xy 104.33812 -176.808638)
			(xy 104.329507 -176.804642) (xy 104.310627 -176.802733) (xy 104.292347 -176.807824) (xy 104.284526 -176.81321)
			(xy 104.284526 -176.813464) (xy 104.284018 -176.813464) (xy 104.250823 -176.838169) (xy 104.180649 -176.882028)
			(xy 104.106709 -176.919187) (xy 104.029639 -176.949324) (xy 103.950105 -176.97218) (xy 103.868793 -176.987556)
			(xy 103.786406 -176.995321) (xy 103.74503 -176.995836) (xy 103.703915 -176.995373) (xy 103.622035 -176.987788)
			(xy 103.541204 -176.97268) (xy 103.462113 -176.950179) (xy 103.385435 -176.920475) (xy 103.311825 -176.883823)
			(xy 103.241911 -176.840535) (xy 103.176289 -176.790981) (xy 103.11552 -176.735583) (xy 103.060122 -176.674814)
			(xy 103.010567 -176.609193) (xy 102.967279 -176.539279) (xy 102.930626 -176.465669) (xy 102.900922 -176.388991)
			(xy 102.87842 -176.309899) (xy 102.863312 -176.229069) (xy 102.855727 -176.147189) (xy 102.855268 -176.106074)
			(xy 74.01685 -176.106074) (xy 74.011364 -176.115577) (xy 73.962725 -176.183881) (xy 73.907814 -176.247252)
			(xy 73.847128 -176.305117) (xy 73.781216 -176.356952) (xy 73.710676 -176.402286) (xy 73.636145 -176.44071)
			(xy 73.5583 -176.471875) (xy 73.477845 -176.4955) (xy 73.395508 -176.511369) (xy 73.312036 -176.519341)
			(xy 73.27011 -176.51984) (xy 73.269094 -176.51984) (xy 73.232037 -176.519434) (xy 73.158188 -176.51317)
			(xy 73.085125 -176.500728) (xy 73.013365 -176.482196) (xy 72.978264 -176.47031) (xy 72.970067 -176.467796)
			(xy 72.952933 -176.467796) (xy 72.944736 -176.47031) (xy 72.910756 -176.481853) (xy 72.841327 -176.500034)
			(xy 72.806052 -176.506632) (xy 72.796116 -176.508916) (xy 72.779041 -176.520017) (xy 72.767603 -176.536869)
			(xy 72.765158 -176.546764) (xy 72.755578 -176.591455) (xy 72.728473 -176.67875) (xy 72.711056 -176.721008)
			(xy 72.70748 -176.730595) (xy 72.707488 -176.751041) (xy 72.711056 -176.760632) (xy 72.728073 -176.802012)
			(xy 72.754694 -176.887437) (xy 72.7726 -176.975105) (xy 72.78161 -177.064127) (xy 72.782176 -177.108866)
			(xy 72.782176 -177.10912) (xy 72.781672 -177.151468) (xy 72.773621 -177.235782) (xy 72.757592 -177.318948)
			(xy 72.733731 -177.400215) (xy 72.702252 -177.478845) (xy 72.663441 -177.554126) (xy 72.617651 -177.625378)
			(xy 72.565295 -177.691954) (xy 72.506847 -177.753252) (xy 72.442837 -177.808717) (xy 72.373845 -177.857846)
			(xy 72.300495 -177.900195) (xy 72.223452 -177.935379) (xy 72.143413 -177.963081) (xy 72.061104 -177.983049)
			(xy 71.977269 -177.995102) (xy 71.892668 -177.999133) (xy 71.808067 -177.995102) (xy 71.724232 -177.983049)
			(xy 71.641923 -177.963081) (xy 71.561884 -177.935379) (xy 71.484841 -177.900195) (xy 71.411491 -177.857846)
			(xy 71.342499 -177.808717) (xy 71.278489 -177.753252) (xy 71.220041 -177.691954) (xy 71.167685 -177.625378)
			(xy 71.121895 -177.554126) (xy 71.083084 -177.478845) (xy 71.051605 -177.400215) (xy 71.027744 -177.318948)
			(xy 71.011715 -177.235782) (xy 71.003664 -177.151468) (xy 71.00316 -177.10912) (xy 71.00316 -177.108866)
			(xy 71.003737 -177.064128) (xy 71.01275 -176.975107) (xy 71.030653 -176.887439) (xy 71.057263 -176.802011)
			(xy 71.07428 -176.760632) (xy 71.077831 -176.751038) (xy 71.077839 -176.730599) (xy 71.07428 -176.721008)
			(xy 71.057235 -176.679605) (xy 71.030605 -176.594115) (xy 71.012704 -176.50638) (xy 71.003712 -176.417291)
			(xy 71.00316 -176.37252) (xy 71.00316 -176.371758) (xy 71.003227 -176.356824) (xy 71.004242 -176.326972)
			(xy 71.005192 -176.312068) (xy 71.005427 -176.302019) (xy 70.999034 -176.282984) (xy 70.985815 -176.267867)
			(xy 70.976998 -176.263046) (xy 70.8787 -176.214532) (xy 70.84822 -176.218596) (xy 70.83679 -176.228756)
			(xy 70.806403 -176.254854) (xy 70.741691 -176.302073) (xy 70.672994 -176.343279) (xy 70.60087 -176.378141)
			(xy 70.525902 -176.406374) (xy 70.4487 -176.427751) (xy 70.369887 -176.442098) (xy 70.290104 -176.449298)
			(xy 70.25005 -176.449736) (xy 70.208935 -176.449254) (xy 70.127056 -176.441671) (xy 70.046226 -176.426565)
			(xy 69.967134 -176.404065) (xy 69.890456 -176.374363) (xy 69.816846 -176.337712) (xy 69.746932 -176.294426)
			(xy 69.68131 -176.244873) (xy 69.620541 -176.189476) (xy 69.565143 -176.128708) (xy 69.515588 -176.063088)
			(xy 69.472299 -175.993175) (xy 69.435647 -175.919566) (xy 69.405943 -175.842889) (xy 69.383441 -175.763798)
			(xy 69.368332 -175.682968) (xy 69.360747 -175.601089) (xy 69.360288 -175.559974) (xy 9.487916 -175.559974)
			(xy 9.487916 -175.848264) (xy 9.48743 -175.875515) (xy 9.479674 -175.929463) (xy 9.464319 -175.981758)
			(xy 9.441677 -176.031335) (xy 9.412211 -176.077185) (xy 9.37652 -176.118376) (xy 9.335329 -176.154067)
			(xy 9.289479 -176.183533) (xy 9.239902 -176.206175) (xy 9.187607 -176.22153) (xy 9.133659 -176.229286)
			(xy 9.079157 -176.229286) (xy 9.025209 -176.22153) (xy 8.972914 -176.206175) (xy 8.923337 -176.183533)
			(xy 8.877487 -176.154067) (xy 8.836296 -176.118376) (xy 8.800605 -176.077185) (xy 8.771139 -176.031335)
			(xy 8.748497 -175.981758) (xy 8.733142 -175.929463) (xy 8.725386 -175.875515) (xy 8.7249 -175.848264)
			(xy 2.509012 -175.848264) (xy 2.509012 -178.618388) (xy 8.7249 -178.618388) (xy 8.7249 -177.754788)
			(xy 8.725386 -177.727537) (xy 8.733142 -177.673589) (xy 8.748497 -177.621294) (xy 8.771139 -177.571717)
			(xy 8.800605 -177.525867) (xy 8.836296 -177.484676) (xy 8.877487 -177.448985) (xy 8.923337 -177.419519)
			(xy 8.972914 -177.396877) (xy 9.025209 -177.381522) (xy 9.079157 -177.373766) (xy 9.133659 -177.373766)
			(xy 9.187607 -177.381522) (xy 9.239902 -177.396877) (xy 9.289479 -177.419519) (xy 9.335329 -177.448985)
			(xy 9.37652 -177.484676) (xy 9.412211 -177.525867) (xy 9.441677 -177.571717) (xy 9.464319 -177.621294)
			(xy 9.479674 -177.673589) (xy 9.48743 -177.727537) (xy 9.487916 -177.754788) (xy 9.487916 -178.618388)
			(xy 9.48743 -178.645639) (xy 9.479674 -178.699587) (xy 9.464319 -178.751882) (xy 9.44304 -178.798474)
			(xy 77.963268 -178.798474) (xy 77.963886 -178.752072) (xy 77.973579 -178.659774) (xy 77.992835 -178.568989)
			(xy 78.021445 -178.480704) (xy 78.039722 -178.438048) (xy 78.043541 -178.42811) (xy 78.043531 -178.406843)
			(xy 78.039722 -178.3969) (xy 78.021451 -178.354243) (xy 77.99286 -178.265953) (xy 77.973605 -178.175169)
			(xy 77.963896 -178.082875) (xy 77.963268 -178.036474) (xy 77.963674 -177.995358) (xy 77.971264 -177.913476)
			(xy 77.986376 -177.832645) (xy 78.008882 -177.753552) (xy 78.038591 -177.676873) (xy 78.075247 -177.603263)
			(xy 78.118539 -177.533349) (xy 78.168097 -177.467728) (xy 78.223499 -177.406959) (xy 78.284271 -177.351561)
			(xy 78.349895 -177.302007) (xy 78.419812 -177.25872) (xy 78.493425 -177.222068) (xy 78.570105 -177.192365)
			(xy 78.649199 -177.169863) (xy 78.730032 -177.154756) (xy 78.811914 -177.147171) (xy 78.85303 -177.146712)
			(xy 78.893848 -177.147168) (xy 78.975141 -177.154659) (xy 79.055405 -177.169568) (xy 79.133966 -177.191768)
			(xy 79.210162 -177.221072) (xy 79.283352 -177.257234) (xy 79.352922 -177.29995) (xy 79.418285 -177.348861)
			(xy 79.478892 -177.403555) (xy 79.534233 -177.463571) (xy 79.559404 -177.495708) (xy 79.565179 -177.502627)
			(xy 79.580393 -177.512264) (xy 79.589122 -177.514504) (xy 79.631283 -177.524073) (xy 79.713687 -177.550242)
			(xy 79.793163 -177.584282) (xy 79.868962 -177.625872) (xy 79.940368 -177.67462) (xy 80.006708 -177.730066)
			(xy 80.067355 -177.791686) (xy 80.121738 -177.8589) (xy 80.169343 -177.931073) (xy 80.209721 -178.007525)
			(xy 80.242492 -178.087533) (xy 80.267345 -178.170343) (xy 80.284047 -178.255173) (xy 80.29244 -178.341224)
			(xy 80.292956 -178.384454) (xy 80.292766 -178.411062) (xy 80.289588 -178.464184) (xy 80.286606 -178.490626)
			(xy 80.285833 -178.501873) (xy 80.292962 -178.523233) (xy 80.300322 -178.531774) (xy 80.329261 -178.562798)
			(xy 80.381784 -178.629432) (xy 80.427728 -178.700761) (xy 80.466676 -178.776139) (xy 80.498274 -178.854881)
			(xy 80.522235 -178.936272) (xy 80.538342 -179.019574) (xy 80.546449 -179.104032) (xy 80.546956 -179.146454)
			(xy 80.546393 -179.191224) (xy 80.537383 -179.280309) (xy 80.519477 -179.36804) (xy 80.492859 -179.453531)
			(xy 80.475836 -179.494942) (xy 80.472299 -179.504541) (xy 80.472282 -179.524976) (xy 80.475836 -179.534566)
			(xy 80.49284 -179.575917) (xy 80.519451 -179.661279) (xy 80.537358 -179.748882) (xy 80.54638 -179.837839)
			(xy 80.546956 -179.882546) (xy 80.546956 -179.883562) (xy 80.546702 -179.894992) (xy 80.573181 -179.900938)
			(xy 80.625416 -179.915681) (xy 80.651096 -179.924456) (xy 80.659293 -179.92697) (xy 80.676427 -179.92697)
			(xy 80.684624 -179.924456) (xy 80.71984 -179.912495) (xy 80.791844 -179.893841) (xy 80.865165 -179.881332)
			(xy 80.93928 -179.875059) (xy 80.97647 -179.874672) (xy 81.013659 -179.875071) (xy 81.087772 -179.881358)
			(xy 81.161092 -179.893865) (xy 81.233098 -179.912503) (xy 81.268316 -179.924456) (xy 81.276513 -179.92697)
			(xy 81.293647 -179.92697) (xy 81.301844 -179.924456) (xy 81.337059 -179.912489) (xy 81.409062 -179.893837)
			(xy 81.482384 -179.88133) (xy 81.5565 -179.875058) (xy 81.59369 -179.874672) (xy 81.63563 -179.875067)
			(xy 81.719132 -179.883039) (xy 81.801497 -179.898913) (xy 81.88198 -179.922544) (xy 81.959853 -179.953719)
			(xy 82.03441 -179.992155) (xy 82.104975 -180.037504) (xy 82.17091 -180.089355) (xy 82.231618 -180.147239)
			(xy 82.286549 -180.210632) (xy 82.335205 -180.278959) (xy 82.377146 -180.351602) (xy 82.411991 -180.427903)
			(xy 82.439426 -180.50717) (xy 82.459202 -180.588687) (xy 82.462267 -180.610002) (xy 86.081108 -180.610002)
			(xy 86.081685 -180.565233) (xy 86.090691 -180.476148) (xy 86.108592 -180.388417) (xy 86.135207 -180.302925)
			(xy 86.152228 -180.261514) (xy 86.155792 -180.251923) (xy 86.155793 -180.231481) (xy 86.152228 -180.22189)
			(xy 86.135186 -180.180486) (xy 86.108554 -180.094996) (xy 86.090651 -180.007262) (xy 86.081659 -179.918173)
			(xy 86.081108 -179.873402) (xy 86.081685 -179.828633) (xy 86.090691 -179.739548) (xy 86.108592 -179.651817)
			(xy 86.135207 -179.566325) (xy 86.152228 -179.524914) (xy 86.155792 -179.515323) (xy 86.155793 -179.494881)
			(xy 86.152228 -179.48529) (xy 86.135186 -179.443886) (xy 86.108554 -179.358396) (xy 86.090651 -179.270662)
			(xy 86.081659 -179.181573) (xy 86.081108 -179.136802) (xy 86.081615 -179.095689) (xy 86.089201 -179.013813)
			(xy 86.10431 -178.932986) (xy 86.126812 -178.853898) (xy 86.156515 -178.777224) (xy 86.193165 -178.703617)
			(xy 86.236451 -178.633706) (xy 86.286003 -178.568087) (xy 86.341397 -178.50732) (xy 86.402163 -178.451923)
			(xy 86.46778 -178.402369) (xy 86.537689 -178.359081) (xy 86.611295 -178.322428) (xy 86.687968 -178.292722)
			(xy 86.767055 -178.270217) (xy 86.847881 -178.255106) (xy 86.929757 -178.247516) (xy 86.97087 -178.24704)
			(xy 87.01248 -178.247527) (xy 87.095336 -178.255301) (xy 87.177105 -178.270774) (xy 87.257073 -178.293812)
			(xy 87.334542 -178.324213) (xy 87.408835 -178.361712) (xy 87.444326 -178.383438) (xy 87.453453 -178.388623)
			(xy 87.474176 -178.391826) (xy 87.494454 -178.386485) (xy 87.503 -178.38039) (xy 87.536641 -178.354416)
			(xy 87.608034 -178.30829) (xy 87.683503 -178.269188) (xy 87.762359 -178.237466) (xy 87.843882 -178.213414)
			(xy 87.927328 -178.19725) (xy 88.011936 -178.189124) (xy 88.054434 -178.18862) (xy 88.095548 -178.18908)
			(xy 88.177426 -178.19667) (xy 88.258254 -178.211782) (xy 88.337343 -178.234287) (xy 88.414018 -178.263994)
			(xy 88.487625 -178.300648) (xy 88.557536 -178.343937) (xy 88.623155 -178.393491) (xy 88.683922 -178.448889)
			(xy 88.739319 -178.509657) (xy 88.788872 -178.575277) (xy 88.83216 -178.645189) (xy 88.868813 -178.718797)
			(xy 88.898518 -178.795473) (xy 88.921021 -178.874562) (xy 88.936132 -178.95539) (xy 88.94372 -179.037268)
			(xy 88.944196 -179.078382) (xy 88.943648 -179.123152) (xy 88.934633 -179.212238) (xy 88.916724 -179.299969)
			(xy 88.890101 -179.38546) (xy 88.873076 -179.42687) (xy 88.869521 -179.436464) (xy 88.869514 -179.456904)
			(xy 88.873076 -179.466494) (xy 88.890086 -179.507843) (xy 88.916696 -179.593206) (xy 88.934602 -179.680809)
			(xy 88.943621 -179.769767) (xy 88.944196 -179.814474) (xy 88.944196 -179.81549) (xy 88.943942 -179.82692)
			(xy 88.970422 -179.832862) (xy 89.022656 -179.847607) (xy 89.048336 -179.856384) (xy 89.056533 -179.858898)
			(xy 89.073667 -179.858898) (xy 89.081864 -179.856384) (xy 89.117077 -179.844413) (xy 89.189082 -179.825761)
			(xy 89.262404 -179.813256) (xy 89.33652 -179.806985) (xy 89.37371 -179.8066) (xy 89.4109 -179.806986)
			(xy 89.485013 -179.813277) (xy 89.558333 -179.825787) (xy 89.630338 -179.844429) (xy 89.665556 -179.856384)
			(xy 89.673753 -179.858898) (xy 89.690887 -179.858898) (xy 89.699084 -179.856384) (xy 89.734295 -179.844408)
			(xy 89.8063 -179.825757) (xy 89.879623 -179.813253) (xy 89.953739 -179.806984) (xy 89.99093 -179.8066)
			(xy 90.032865 -179.807156) (xy 90.116355 -179.815131) (xy 90.198709 -179.831006) (xy 90.279182 -179.854637)
			(xy 90.357043 -179.885811) (xy 90.431589 -179.924244) (xy 90.502144 -179.969589) (xy 90.56807 -180.021436)
			(xy 90.628768 -180.079314) (xy 90.683691 -180.1427) (xy 90.732339 -180.211019) (xy 90.774274 -180.283653)
			(xy 90.809114 -180.359944) (xy 90.836544 -180.439202) (xy 90.856317 -180.520708) (xy 90.868253 -180.603725)
			(xy 90.869375 -180.627274) (xy 94.473268 -180.627274) (xy 94.473838 -180.582505) (xy 94.482847 -180.49342)
			(xy 94.500749 -180.405689) (xy 94.527366 -180.320197) (xy 94.544388 -180.278786) (xy 94.54797 -180.2692)
			(xy 94.54796 -180.248753) (xy 94.544388 -180.239162) (xy 94.52734 -180.19776) (xy 94.500709 -180.11227)
			(xy 94.482808 -180.024535) (xy 94.473818 -179.935445) (xy 94.473268 -179.890674) (xy 94.473838 -179.845905)
			(xy 94.482847 -179.75682) (xy 94.500749 -179.669089) (xy 94.527366 -179.583597) (xy 94.544388 -179.542186)
			(xy 94.54797 -179.5326) (xy 94.54796 -179.512153) (xy 94.544388 -179.502562) (xy 94.52734 -179.46116)
			(xy 94.500709 -179.37567) (xy 94.482808 -179.287935) (xy 94.473818 -179.198845) (xy 94.473268 -179.154074)
			(xy 94.473674 -179.112958) (xy 94.481264 -179.031076) (xy 94.496376 -178.950245) (xy 94.518882 -178.871152)
			(xy 94.548591 -178.794473) (xy 94.585247 -178.720863) (xy 94.628539 -178.650949) (xy 94.678097 -178.585328)
			(xy 94.733499 -178.524559) (xy 94.794271 -178.469161) (xy 94.859895 -178.419607) (xy 94.929812 -178.37632)
			(xy 95.003425 -178.339668) (xy 95.080105 -178.309965) (xy 95.159199 -178.287463) (xy 95.240032 -178.272356)
			(xy 95.321914 -178.264771) (xy 95.36303 -178.264312) (xy 95.404641 -178.264773) (xy 95.487498 -178.272553)
			(xy 95.569267 -178.288031) (xy 95.649235 -178.311074) (xy 95.726703 -178.341479) (xy 95.800995 -178.378982)
			(xy 95.836486 -178.40071) (xy 95.845629 -178.405863) (xy 95.866342 -178.40908) (xy 95.886614 -178.403752)
			(xy 95.89516 -178.397662) (xy 95.928789 -178.371671) (xy 96.000183 -178.325546) (xy 96.075654 -178.286445)
			(xy 96.154512 -178.254724) (xy 96.236037 -178.230675) (xy 96.319485 -178.214515) (xy 96.404095 -178.206393)
			(xy 96.446594 -178.205892) (xy 96.487707 -178.206419) (xy 96.569582 -178.214005) (xy 96.650407 -178.229113)
			(xy 96.729494 -178.251613) (xy 96.806168 -178.281315) (xy 96.879774 -178.317965) (xy 96.949684 -178.36125)
			(xy 97.015303 -178.4108) (xy 97.07607 -178.466193) (xy 97.131467 -178.526957) (xy 97.181021 -178.592573)
			(xy 97.22431 -178.662481) (xy 97.260964 -178.736085) (xy 97.29067 -178.812756) (xy 97.313176 -178.891842)
			(xy 97.328288 -178.972667) (xy 97.335879 -179.054541) (xy 97.336356 -179.095654) (xy 97.335793 -179.140424)
			(xy 97.329275 -179.204874) (xy 368.074448 -179.204874) (xy 368.075006 -179.161932) (xy 368.083288 -179.076448)
			(xy 368.099773 -178.99216) (xy 368.124306 -178.909855) (xy 368.15666 -178.830297) (xy 368.196533 -178.75423)
			(xy 368.243554 -178.682361) (xy 368.297284 -178.615359) (xy 368.357224 -178.55385) (xy 368.422813 -178.498405)
			(xy 368.493443 -178.449542) (xy 368.568454 -178.407716) (xy 368.607594 -178.390042) (xy 368.615999 -178.385919)
			(xy 368.629281 -178.372745) (xy 368.633502 -178.364388) (xy 368.645948 -178.33721) (xy 368.64947 -178.328554)
			(xy 368.650638 -178.309919) (xy 368.648234 -178.300888) (xy 368.635415 -178.257999) (xy 368.617464 -178.170297)
			(xy 368.608423 -178.081234) (xy 368.607848 -178.036474) (xy 368.608352 -177.994113) (xy 368.616405 -177.909776)
			(xy 368.632439 -177.826586) (xy 368.656307 -177.745296) (xy 368.687795 -177.666644) (xy 368.726617 -177.591341)
			(xy 368.77242 -177.520069) (xy 368.824791 -177.453473) (xy 368.883256 -177.392158) (xy 368.947284 -177.336677)
			(xy 369.016296 -177.287534) (xy 369.089666 -177.245174) (xy 369.166731 -177.209979) (xy 369.246793 -177.18227)
			(xy 369.329126 -177.162296) (xy 369.412985 -177.150239) (xy 369.49761 -177.146208) (xy 369.582235 -177.150239)
			(xy 369.666094 -177.162296) (xy 369.748427 -177.18227) (xy 369.828489 -177.209979) (xy 369.905554 -177.245174)
			(xy 369.978924 -177.287534) (xy 370.047936 -177.336677) (xy 370.111964 -177.392158) (xy 370.170429 -177.453473)
			(xy 370.2228 -177.520069) (xy 370.268603 -177.591341) (xy 370.307425 -177.666644) (xy 370.338913 -177.745296)
			(xy 370.362781 -177.826586) (xy 370.378815 -177.909776) (xy 370.386868 -177.994113) (xy 370.387372 -178.036474)
			(xy 370.387372 -178.036728) (xy 370.386948 -178.075094) (xy 370.380306 -178.151538) (xy 370.367099 -178.227125)
			(xy 370.357654 -178.264312) (xy 370.35562 -178.273261) (xy 370.357441 -178.291512) (xy 370.365595 -178.307941)
			(xy 370.37903 -178.320427) (xy 370.387372 -178.324256) (xy 370.427603 -178.341379) (xy 370.50477 -178.382506)
			(xy 370.577528 -178.431007) (xy 370.645175 -178.486413) (xy 370.707059 -178.548191) (xy 370.762582 -178.615743)
			(xy 370.811207 -178.688417) (xy 370.852467 -178.765513) (xy 370.885962 -178.846285) (xy 370.911369 -178.929954)
			(xy 370.928442 -179.015713) (xy 370.937018 -179.102733) (xy 370.937536 -179.146454) (xy 370.936975 -179.191224)
			(xy 370.927964 -179.280309) (xy 370.910058 -179.36804) (xy 370.883439 -179.453531) (xy 370.866416 -179.494942)
			(xy 370.86288 -179.504541) (xy 370.862862 -179.524975) (xy 370.866416 -179.534566) (xy 370.883441 -179.575977)
			(xy 370.910078 -179.661464) (xy 370.927986 -179.749196) (xy 370.936982 -179.838284) (xy 370.937536 -179.883054)
			(xy 370.937282 -179.903882) (xy 370.937631 -179.91519) (xy 370.946776 -179.935848) (xy 370.963889 -179.950596)
			(xy 370.97462 -179.954174) (xy 370.989618 -179.95835) (xy 371.019344 -179.967623) (xy 371.034056 -179.972716)
			(xy 371.042253 -179.97523) (xy 371.059387 -179.97523) (xy 371.067584 -179.972716) (xy 371.102796 -179.960741)
			(xy 371.174801 -179.94209) (xy 371.248123 -179.929585) (xy 371.322239 -179.923316) (xy 371.35943 -179.922932)
			(xy 371.396619 -179.923339) (xy 371.470732 -179.929623) (xy 371.544052 -179.942128) (xy 371.616058 -179.960764)
			(xy 371.651276 -179.972716) (xy 371.659473 -179.97523) (xy 371.676607 -179.97523) (xy 371.684804 -179.972716)
			(xy 371.720023 -179.960763) (xy 371.792025 -179.942106) (xy 371.865345 -179.929595) (xy 371.93946 -179.923319)
			(xy 371.97665 -179.922932) (xy 372.01859 -179.923405) (xy 372.10209 -179.931374) (xy 372.184455 -179.947244)
			(xy 372.264938 -179.970872) (xy 372.34281 -180.002043) (xy 372.417367 -180.040476) (xy 372.487932 -180.085822)
			(xy 372.553868 -180.137671) (xy 372.614576 -180.195553) (xy 372.669507 -180.258944) (xy 372.718163 -180.327269)
			(xy 372.760105 -180.39991) (xy 372.794951 -180.476209) (xy 372.822386 -180.555475) (xy 372.842162 -180.63699)
			(xy 372.848069 -180.678074) (xy 376.477276 -180.678074) (xy 376.477846 -180.633305) (xy 376.486854 -180.54422)
			(xy 376.504757 -180.456489) (xy 376.531374 -180.370997) (xy 376.548396 -180.329586) (xy 376.551978 -180.32)
			(xy 376.551968 -180.299553) (xy 376.548396 -180.289962) (xy 376.531349 -180.24856) (xy 376.504717 -180.16307)
			(xy 376.486816 -180.075335) (xy 376.477826 -179.986245) (xy 376.477276 -179.941474) (xy 376.477846 -179.896705)
			(xy 376.486854 -179.80762) (xy 376.504757 -179.719889) (xy 376.531374 -179.634397) (xy 376.548396 -179.592986)
			(xy 376.551978 -179.5834) (xy 376.551968 -179.562953) (xy 376.548396 -179.553362) (xy 376.531349 -179.51196)
			(xy 376.504717 -179.42647) (xy 376.486816 -179.338735) (xy 376.477826 -179.249645) (xy 376.477276 -179.204874)
			(xy 376.477674 -179.163758) (xy 376.485264 -179.081876) (xy 376.500376 -179.001043) (xy 376.522883 -178.92195)
			(xy 376.552591 -178.845272) (xy 376.589248 -178.771661) (xy 376.632541 -178.701747) (xy 376.682099 -178.636125)
			(xy 376.737501 -178.575356) (xy 376.798274 -178.519958) (xy 376.863899 -178.470404) (xy 376.933817 -178.427117)
			(xy 377.00743 -178.390466) (xy 377.084111 -178.360763) (xy 377.163206 -178.338262) (xy 377.244039 -178.323155)
			(xy 377.325922 -178.315571) (xy 377.367038 -178.315112) (xy 377.408648 -178.315619) (xy 377.491503 -178.323389)
			(xy 377.573272 -178.338859) (xy 377.65324 -178.361894) (xy 377.730709 -178.392291) (xy 377.805002 -178.429786)
			(xy 377.840494 -178.45151) (xy 377.849633 -178.45667) (xy 377.870349 -178.459885) (xy 377.890623 -178.454554)
			(xy 377.899168 -178.448462) (xy 377.932829 -178.422514) (xy 378.004217 -178.376384) (xy 378.079682 -178.337278)
			(xy 378.158534 -178.305551) (xy 378.240054 -178.281495) (xy 378.323498 -178.265328) (xy 378.408104 -178.257198)
			(xy 378.450602 -178.256692) (xy 378.491715 -178.257211) (xy 378.57359 -178.264798) (xy 378.654416 -178.279906)
			(xy 378.733503 -178.302408) (xy 378.810176 -178.33211) (xy 378.883782 -178.368761) (xy 378.953693 -178.412046)
			(xy 379.019312 -178.461597) (xy 379.080078 -178.51699) (xy 379.135475 -178.577755) (xy 379.185029 -178.643371)
			(xy 379.228318 -178.713279) (xy 379.264972 -178.786883) (xy 379.294678 -178.863555) (xy 379.317184 -178.942641)
			(xy 379.332296 -179.023466) (xy 379.339887 -179.105341) (xy 379.340364 -179.146454) (xy 379.339801 -179.191224)
			(xy 379.330791 -179.280309) (xy 379.312886 -179.36804) (xy 379.286267 -179.453531) (xy 379.269244 -179.494942)
			(xy 379.265706 -179.50454) (xy 379.265689 -179.524976) (xy 379.269244 -179.534566) (xy 379.286249 -179.575917)
			(xy 379.31286 -179.661279) (xy 379.330766 -179.748882) (xy 379.339788 -179.837839) (xy 379.340364 -179.882546)
			(xy 379.340364 -179.883562) (xy 379.34011 -179.894992) (xy 379.366589 -179.900938) (xy 379.418824 -179.915681)
			(xy 379.444504 -179.924456) (xy 379.452701 -179.92697) (xy 379.469835 -179.92697) (xy 379.478032 -179.924456)
			(xy 379.513248 -179.912493) (xy 379.585251 -179.893839) (xy 379.658572 -179.881331) (xy 379.732688 -179.875058)
			(xy 379.769878 -179.874672) (xy 379.807067 -179.875069) (xy 379.88118 -179.881356) (xy 379.9545 -179.893864)
			(xy 380.026506 -179.912502) (xy 380.061724 -179.924456) (xy 380.069921 -179.92697) (xy 380.087055 -179.92697)
			(xy 380.095252 -179.924456) (xy 380.130466 -179.912487) (xy 380.20247 -179.893835) (xy 380.275792 -179.881329)
			(xy 380.349908 -179.875057) (xy 380.387098 -179.874672) (xy 380.429038 -179.875067) (xy 380.512539 -179.88304)
			(xy 380.594904 -179.898915) (xy 380.675386 -179.922546) (xy 380.753258 -179.953722) (xy 380.827814 -179.992158)
			(xy 380.898379 -180.037507) (xy 380.964314 -180.089358) (xy 381.025021 -180.147242) (xy 381.079951 -180.210635)
			(xy 381.128607 -180.278962) (xy 381.170547 -180.351604) (xy 381.205392 -180.427905) (xy 381.232827 -180.507172)
			(xy 381.252602 -180.588688) (xy 381.26454 -180.671715) (xy 381.264843 -180.678074) (xy 384.808476 -180.678074)
			(xy 384.809046 -180.633305) (xy 384.818054 -180.54422) (xy 384.835957 -180.456489) (xy 384.862574 -180.370997)
			(xy 384.879596 -180.329586) (xy 384.883178 -180.32) (xy 384.883168 -180.299553) (xy 384.879596 -180.289962)
			(xy 384.862549 -180.24856) (xy 384.835917 -180.16307) (xy 384.818016 -180.075335) (xy 384.809026 -179.986245)
			(xy 384.808476 -179.941474) (xy 384.809046 -179.896705) (xy 384.818054 -179.80762) (xy 384.835957 -179.719889)
			(xy 384.862574 -179.634397) (xy 384.879596 -179.592986) (xy 384.883178 -179.5834) (xy 384.883168 -179.562953)
			(xy 384.879596 -179.553362) (xy 384.862549 -179.51196) (xy 384.835917 -179.42647) (xy 384.818016 -179.338735)
			(xy 384.809026 -179.249645) (xy 384.808476 -179.204874) (xy 384.808874 -179.163758) (xy 384.816464 -179.081876)
			(xy 384.831576 -179.001043) (xy 384.854083 -178.92195) (xy 384.883791 -178.845272) (xy 384.920448 -178.771661)
			(xy 384.963741 -178.701747) (xy 385.013299 -178.636125) (xy 385.068701 -178.575356) (xy 385.129474 -178.519958)
			(xy 385.195099 -178.470404) (xy 385.265017 -178.427117) (xy 385.33863 -178.390466) (xy 385.415311 -178.360763)
			(xy 385.494406 -178.338262) (xy 385.575239 -178.323155) (xy 385.657122 -178.315571) (xy 385.698238 -178.315112)
			(xy 385.739848 -178.315619) (xy 385.822703 -178.323389) (xy 385.904472 -178.338859) (xy 385.98444 -178.361894)
			(xy 386.061909 -178.392291) (xy 386.136202 -178.429786) (xy 386.171694 -178.45151) (xy 386.180833 -178.45667)
			(xy 386.201549 -178.459885) (xy 386.221823 -178.454554) (xy 386.230368 -178.448462) (xy 386.264029 -178.422514)
			(xy 386.335417 -178.376384) (xy 386.410882 -178.337278) (xy 386.489734 -178.305551) (xy 386.571254 -178.281495)
			(xy 386.654698 -178.265328) (xy 386.739304 -178.257198) (xy 386.781802 -178.256692) (xy 386.822915 -178.257211)
			(xy 386.90479 -178.264798) (xy 386.985616 -178.279906) (xy 387.064703 -178.302408) (xy 387.141376 -178.33211)
			(xy 387.214982 -178.368761) (xy 387.284893 -178.412046) (xy 387.350512 -178.461597) (xy 387.411278 -178.51699)
			(xy 387.466675 -178.577755) (xy 387.516229 -178.643371) (xy 387.559518 -178.713279) (xy 387.596172 -178.786883)
			(xy 387.625878 -178.863555) (xy 387.648384 -178.942641) (xy 387.663496 -179.023466) (xy 387.671087 -179.105341)
			(xy 387.671564 -179.146454) (xy 387.671001 -179.191224) (xy 387.661991 -179.280309) (xy 387.644086 -179.36804)
			(xy 387.617467 -179.453531) (xy 387.600444 -179.494942) (xy 387.596906 -179.50454) (xy 387.596889 -179.524976)
			(xy 387.600444 -179.534566) (xy 387.617449 -179.575917) (xy 387.64406 -179.661279) (xy 387.661966 -179.748882)
			(xy 387.670988 -179.837839) (xy 387.671564 -179.882546) (xy 387.671564 -179.883562) (xy 387.67131 -179.894992)
			(xy 387.697789 -179.900938) (xy 387.750024 -179.915681) (xy 387.775704 -179.924456) (xy 387.783901 -179.92697)
			(xy 387.801035 -179.92697) (xy 387.809232 -179.924456) (xy 387.844448 -179.912493) (xy 387.916451 -179.893839)
			(xy 387.989772 -179.881331) (xy 388.063888 -179.875058) (xy 388.101078 -179.874672) (xy 388.138267 -179.875069)
			(xy 388.21238 -179.881356) (xy 388.2857 -179.893864) (xy 388.357706 -179.912502) (xy 388.392924 -179.924456)
			(xy 388.401121 -179.92697) (xy 388.418255 -179.92697) (xy 388.426452 -179.924456) (xy 388.461666 -179.912487)
			(xy 388.53367 -179.893835) (xy 388.606992 -179.881329) (xy 388.681108 -179.875057) (xy 388.718298 -179.874672)
			(xy 388.760238 -179.875067) (xy 388.843739 -179.88304) (xy 388.926104 -179.898915) (xy 389.006586 -179.922546)
			(xy 389.084458 -179.953722) (xy 389.159014 -179.992158) (xy 389.229579 -180.037507) (xy 389.295514 -180.089358)
			(xy 389.356221 -180.147242) (xy 389.411151 -180.210635) (xy 389.459807 -180.278962) (xy 389.501747 -180.351604)
			(xy 389.536592 -180.427905) (xy 389.564027 -180.507172) (xy 389.583802 -180.588688) (xy 389.59574 -180.671715)
			(xy 389.599731 -180.7555) (xy 389.59574 -180.839285) (xy 389.583802 -180.922312) (xy 389.564027 -181.003828)
			(xy 389.536592 -181.083095) (xy 389.501747 -181.159396) (xy 389.459807 -181.232038) (xy 389.411151 -181.300365)
			(xy 389.356221 -181.363758) (xy 389.295514 -181.421642) (xy 389.229579 -181.473493) (xy 389.159014 -181.518842)
			(xy 389.084458 -181.557278) (xy 389.006586 -181.588454) (xy 388.926104 -181.612085) (xy 388.843739 -181.62796)
			(xy 388.760238 -181.635933) (xy 388.718298 -181.636416) (xy 388.681108 -181.636027) (xy 388.606996 -181.629737)
			(xy 388.533676 -181.617227) (xy 388.46167 -181.598587) (xy 388.426452 -181.586632) (xy 388.418255 -181.584118)
			(xy 388.401121 -181.584118) (xy 388.392924 -181.586632) (xy 388.365208 -181.596078) (xy 388.308773 -181.611711)
			(xy 388.280148 -181.617874) (xy 388.270401 -181.620348) (xy 388.25379 -181.63165) (xy 388.242792 -181.648464)
			(xy 388.240524 -181.65826) (xy 388.231054 -181.705587) (xy 388.203179 -181.797995) (xy 388.184898 -181.842664)
			(xy 388.181281 -181.852235) (xy 388.18114 -181.872676) (xy 388.184644 -181.882288) (xy 388.201684 -181.923659)
			(xy 388.228298 -182.009088) (xy 388.246197 -182.096758) (xy 388.255201 -182.185783) (xy 388.255764 -182.230522)
			(xy 388.255764 -182.230776) (xy 388.25526 -182.273124) (xy 388.247209 -182.357438) (xy 388.23118 -182.440604)
			(xy 388.207319 -182.521871) (xy 388.17584 -182.600501) (xy 388.137029 -182.675782) (xy 388.091239 -182.747034)
			(xy 388.038883 -182.81361) (xy 387.980435 -182.874908) (xy 387.916425 -182.930373) (xy 387.847433 -182.979502)
			(xy 387.774083 -183.021851) (xy 387.69704 -183.057035) (xy 387.617001 -183.084737) (xy 387.534692 -183.104705)
			(xy 387.450857 -183.116758) (xy 387.366256 -183.120789) (xy 387.281655 -183.116758) (xy 387.19782 -183.104705)
			(xy 387.115511 -183.084737) (xy 387.035472 -183.057035) (xy 386.958429 -183.021851) (xy 386.885079 -182.979502)
			(xy 386.816087 -182.930373) (xy 386.752077 -182.874908) (xy 386.693629 -182.81361) (xy 386.641273 -182.747034)
			(xy 386.595483 -182.675782) (xy 386.556672 -182.600501) (xy 386.525193 -182.521871) (xy 386.501332 -182.440604)
			(xy 386.485303 -182.357438) (xy 386.477252 -182.273124) (xy 386.476748 -182.230776) (xy 386.476748 -182.230522)
			(xy 386.477311 -182.185784) (xy 386.486329 -182.096762) (xy 386.504235 -182.009095) (xy 386.53085 -181.923667)
			(xy 386.547868 -181.882288) (xy 386.551445 -181.872701) (xy 386.551436 -181.852255) (xy 386.547868 -181.842664)
			(xy 386.53084 -181.801254) (xy 386.504206 -181.715766) (xy 386.4863 -181.628034) (xy 386.477302 -181.538946)
			(xy 386.476748 -181.494176) (xy 386.476748 -181.493668) (xy 386.47711 -181.457839) (xy 386.482902 -181.386415)
			(xy 386.49442 -181.315688) (xy 386.502656 -181.280816) (xy 386.504356 -181.272508) (xy 386.502799 -181.255633)
			(xy 386.495808 -181.240195) (xy 386.49021 -181.233826) (xy 386.44957 -181.1909) (xy 386.43941 -181.193186)
			(xy 386.430637 -181.195432) (xy 386.415405 -181.205208) (xy 386.409692 -181.212236) (xy 386.384552 -181.244927)
			(xy 386.329156 -181.306026) (xy 386.268343 -181.361734) (xy 386.202634 -181.411575) (xy 386.132593 -181.455119)
			(xy 386.058822 -181.491993) (xy 385.981955 -181.521881) (xy 385.902652 -181.544524) (xy 385.821593 -181.55973)
			(xy 385.739474 -181.567368) (xy 385.698238 -181.567836) (xy 385.657123 -181.567365) (xy 385.575243 -181.559781)
			(xy 385.494413 -181.544674) (xy 385.415321 -181.522173) (xy 385.338643 -181.49247) (xy 385.265033 -181.455819)
			(xy 385.195119 -181.412532) (xy 385.129497 -181.362978) (xy 385.068728 -181.30758) (xy 385.01333 -181.246812)
			(xy 384.963775 -181.181191) (xy 384.920487 -181.111277) (xy 384.883834 -181.037668) (xy 384.854131 -180.96099)
			(xy 384.831629 -180.881899) (xy 384.81652 -180.801068) (xy 384.808935 -180.719189) (xy 384.808476 -180.678074)
			(xy 381.264843 -180.678074) (xy 381.268531 -180.7555) (xy 381.26454 -180.839285) (xy 381.252602 -180.922312)
			(xy 381.232827 -181.003828) (xy 381.205392 -181.083095) (xy 381.170547 -181.159396) (xy 381.128607 -181.232038)
			(xy 381.079951 -181.300365) (xy 381.025021 -181.363758) (xy 380.964314 -181.421642) (xy 380.898379 -181.473493)
			(xy 380.827814 -181.518842) (xy 380.753258 -181.557278) (xy 380.675386 -181.588454) (xy 380.594904 -181.612085)
			(xy 380.512539 -181.62796) (xy 380.429038 -181.635933) (xy 380.387098 -181.636416) (xy 380.349908 -181.636027)
			(xy 380.275796 -181.629737) (xy 380.202476 -181.617227) (xy 380.13047 -181.598587) (xy 380.095252 -181.586632)
			(xy 380.087055 -181.584118) (xy 380.069921 -181.584118) (xy 380.061724 -181.586632) (xy 380.034008 -181.596078)
			(xy 379.977573 -181.611711) (xy 379.948948 -181.617874) (xy 379.939201 -181.620348) (xy 379.92259 -181.63165)
			(xy 379.911592 -181.648464) (xy 379.909324 -181.65826) (xy 379.899854 -181.705587) (xy 379.871979 -181.797995)
			(xy 379.853698 -181.842664) (xy 379.850081 -181.852235) (xy 379.84994 -181.872676) (xy 379.853444 -181.882288)
			(xy 379.870484 -181.923659) (xy 379.897098 -182.009088) (xy 379.914997 -182.096758) (xy 379.924001 -182.185783)
			(xy 379.924564 -182.230522) (xy 379.924564 -182.230776) (xy 379.92406 -182.273124) (xy 379.916009 -182.357438)
			(xy 379.89998 -182.440604) (xy 379.876119 -182.521871) (xy 379.84464 -182.600501) (xy 379.805829 -182.675782)
			(xy 379.760039 -182.747034) (xy 379.707683 -182.81361) (xy 379.649235 -182.874908) (xy 379.585225 -182.930373)
			(xy 379.516233 -182.979502) (xy 379.442883 -183.021851) (xy 379.36584 -183.057035) (xy 379.285801 -183.084737)
			(xy 379.203492 -183.104705) (xy 379.119657 -183.116758) (xy 379.035056 -183.120789) (xy 378.950455 -183.116758)
			(xy 378.86662 -183.104705) (xy 378.784311 -183.084737) (xy 378.704272 -183.057035) (xy 378.627229 -183.021851)
			(xy 378.553879 -182.979502) (xy 378.484887 -182.930373) (xy 378.420877 -182.874908) (xy 378.362429 -182.81361)
			(xy 378.310073 -182.747034) (xy 378.264283 -182.675782) (xy 378.225472 -182.600501) (xy 378.193993 -182.521871)
			(xy 378.170132 -182.440604) (xy 378.154103 -182.357438) (xy 378.146052 -182.273124) (xy 378.145548 -182.230776)
			(xy 378.145548 -182.230522) (xy 378.146111 -182.185784) (xy 378.155129 -182.096762) (xy 378.173035 -182.009095)
			(xy 378.19965 -181.923667) (xy 378.216668 -181.882288) (xy 378.220245 -181.872701) (xy 378.220236 -181.852255)
			(xy 378.216668 -181.842664) (xy 378.19964 -181.801254) (xy 378.173006 -181.715766) (xy 378.1551 -181.628034)
			(xy 378.146102 -181.538946) (xy 378.145548 -181.494176) (xy 378.145548 -181.493668) (xy 378.14591 -181.457839)
			(xy 378.151702 -181.386415) (xy 378.16322 -181.315688) (xy 378.171456 -181.280816) (xy 378.173156 -181.272508)
			(xy 378.171599 -181.255633) (xy 378.164608 -181.240195) (xy 378.15901 -181.233826) (xy 378.11837 -181.1909)
			(xy 378.10821 -181.193186) (xy 378.099437 -181.195432) (xy 378.084205 -181.205208) (xy 378.078492 -181.212236)
			(xy 378.053352 -181.244927) (xy 377.997956 -181.306026) (xy 377.937143 -181.361734) (xy 377.871434 -181.411575)
			(xy 377.801393 -181.455119) (xy 377.727622 -181.491993) (xy 377.650755 -181.521881) (xy 377.571452 -181.544524)
			(xy 377.490393 -181.55973) (xy 377.408274 -181.567368) (xy 377.367038 -181.567836) (xy 377.325923 -181.567365)
			(xy 377.244043 -181.559781) (xy 377.163213 -181.544674) (xy 377.084121 -181.522173) (xy 377.007443 -181.49247)
			(xy 376.933833 -181.455819) (xy 376.863919 -181.412532) (xy 376.798297 -181.362978) (xy 376.737528 -181.30758)
			(xy 376.68213 -181.246812) (xy 376.632575 -181.181191) (xy 376.589287 -181.111277) (xy 376.552634 -181.037668)
			(xy 376.522931 -180.96099) (xy 376.500429 -180.881899) (xy 376.48532 -180.801068) (xy 376.477735 -180.719189)
			(xy 376.477276 -180.678074) (xy 372.848069 -180.678074) (xy 372.8541 -180.720015) (xy 372.858091 -180.8038)
			(xy 372.8541 -180.887585) (xy 372.842162 -180.97061) (xy 372.822386 -181.052125) (xy 372.794951 -181.131391)
			(xy 372.760105 -181.20769) (xy 372.718163 -181.280331) (xy 372.669507 -181.348656) (xy 372.614576 -181.412047)
			(xy 372.553868 -181.469929) (xy 372.487932 -181.521778) (xy 372.417367 -181.567124) (xy 372.34281 -181.605557)
			(xy 372.264938 -181.636728) (xy 372.184455 -181.660356) (xy 372.10209 -181.676226) (xy 372.01859 -181.684195)
			(xy 371.97665 -181.684676) (xy 371.939461 -181.684274) (xy 371.865348 -181.677988) (xy 371.792028 -181.665482)
			(xy 371.720022 -181.646845) (xy 371.684804 -181.634892) (xy 371.676607 -181.632378) (xy 371.659473 -181.632378)
			(xy 371.651276 -181.634892) (xy 371.611916 -181.648156) (xy 371.531285 -181.66812) (xy 371.449135 -181.680416)
			(xy 371.40769 -181.683152) (xy 371.397889 -181.684131) (xy 371.380113 -181.692579) (xy 371.36683 -181.707102)
			(xy 371.362986 -181.716172) (xy 371.348 -181.753764) (xy 371.344428 -181.763418) (xy 371.344429 -181.783987)
			(xy 371.348 -181.793642) (xy 371.365038 -181.835014) (xy 371.391656 -181.920442) (xy 371.409557 -182.008112)
			(xy 371.418559 -182.097137) (xy 371.41912 -182.141876) (xy 371.418616 -182.184237) (xy 371.410563 -182.268574)
			(xy 371.394529 -182.351764) (xy 371.370661 -182.433054) (xy 371.339173 -182.511706) (xy 371.300351 -182.587009)
			(xy 371.254548 -182.658281) (xy 371.202177 -182.724877) (xy 371.143712 -182.786192) (xy 371.079684 -182.841673)
			(xy 371.010672 -182.890816) (xy 370.937302 -182.933176) (xy 370.860237 -182.968371) (xy 370.780175 -182.99608)
			(xy 370.697842 -183.016054) (xy 370.613983 -183.028111) (xy 370.529358 -183.032143) (xy 370.444733 -183.028111)
			(xy 370.360874 -183.016054) (xy 370.278541 -182.99608) (xy 370.198479 -182.968371) (xy 370.121414 -182.933176)
			(xy 370.048044 -182.890816) (xy 369.979032 -182.841673) (xy 369.915004 -182.786192) (xy 369.856539 -182.724877)
			(xy 369.804168 -182.658281) (xy 369.758365 -182.587009) (xy 369.719543 -182.511706) (xy 369.688055 -182.433054)
			(xy 369.664187 -182.351764) (xy 369.648153 -182.268574) (xy 369.6401 -182.184237) (xy 369.639596 -182.141876)
			(xy 369.640165 -182.097107) (xy 369.649173 -182.008022) (xy 369.667076 -181.92029) (xy 369.693694 -181.834799)
			(xy 369.710716 -181.793388) (xy 369.714296 -181.783802) (xy 369.714287 -181.763355) (xy 369.710716 -181.753764)
			(xy 369.693665 -181.712364) (xy 369.667035 -181.626872) (xy 369.649135 -181.539137) (xy 369.640146 -181.450047)
			(xy 369.639596 -181.405276) (xy 369.639771 -181.384669) (xy 369.641804 -181.343504) (xy 369.64366 -181.32298)
			(xy 369.644023 -181.312283) (xy 369.63707 -181.292069) (xy 369.630198 -181.283864) (xy 369.57127 -181.22011)
			(xy 369.551204 -181.211728) (xy 369.540282 -181.211982) (xy 369.523264 -181.212236) (xy 369.522756 -181.212236)
			(xy 369.481649 -181.211766) (xy 369.399787 -181.204159) (xy 369.318976 -181.189032) (xy 369.239905 -181.166515)
			(xy 369.163248 -181.136799) (xy 369.08966 -181.100138) (xy 369.019768 -181.056844) (xy 368.954168 -181.007287)
			(xy 368.893419 -180.95189) (xy 368.83804 -180.891125) (xy 368.788503 -180.825509) (xy 368.745231 -180.755604)
			(xy 368.708592 -180.682005) (xy 368.678899 -180.605339) (xy 368.656406 -180.526261) (xy 368.641304 -180.445446)
			(xy 368.633721 -180.363581) (xy 368.633248 -180.322474) (xy 368.6337 -180.283493) (xy 368.640575 -180.205835)
			(xy 368.654226 -180.129077) (xy 368.663982 -180.091334) (xy 368.666037 -180.082278) (xy 368.664208 -180.063813)
			(xy 368.655908 -180.047218) (xy 368.642231 -180.034679) (xy 368.633756 -180.030882) (xy 368.596114 -180.015301)
			(xy 368.523548 -179.97826) (xy 368.454673 -179.934739) (xy 368.390066 -179.885102) (xy 368.330268 -179.829767)
			(xy 368.27578 -179.769195) (xy 368.227059 -179.703896) (xy 368.184512 -179.634415) (xy 368.148496 -179.561335)
			(xy 368.119314 -179.485268) (xy 368.097208 -179.406851) (xy 368.082365 -179.326741) (xy 368.074909 -179.24561)
			(xy 368.074448 -179.204874) (xy 97.329275 -179.204874) (xy 97.326783 -179.229509) (xy 97.308877 -179.31724)
			(xy 97.282259 -179.402731) (xy 97.265236 -179.444142) (xy 97.261699 -179.453741) (xy 97.261682 -179.474176)
			(xy 97.265236 -179.483766) (xy 97.28224 -179.525117) (xy 97.308851 -179.610479) (xy 97.326758 -179.698082)
			(xy 97.33578 -179.787039) (xy 97.336356 -179.831746) (xy 97.336356 -179.832762) (xy 97.336102 -179.844192)
			(xy 97.362581 -179.850138) (xy 97.414816 -179.864881) (xy 97.440496 -179.873656) (xy 97.448693 -179.87617)
			(xy 97.465827 -179.87617) (xy 97.474024 -179.873656) (xy 97.50924 -179.861695) (xy 97.581244 -179.843041)
			(xy 97.654565 -179.830532) (xy 97.72868 -179.824259) (xy 97.76587 -179.823872) (xy 97.803059 -179.824271)
			(xy 97.877172 -179.830558) (xy 97.950492 -179.843065) (xy 98.022498 -179.861703) (xy 98.057716 -179.873656)
			(xy 98.065913 -179.87617) (xy 98.083047 -179.87617) (xy 98.091244 -179.873656) (xy 98.126459 -179.861689)
			(xy 98.198462 -179.843037) (xy 98.271784 -179.83053) (xy 98.3459 -179.824258) (xy 98.38309 -179.823872)
			(xy 98.42503 -179.824267) (xy 98.508532 -179.832239) (xy 98.590897 -179.848113) (xy 98.67138 -179.871744)
			(xy 98.749253 -179.902919) (xy 98.82381 -179.941355) (xy 98.894375 -179.986704) (xy 98.96031 -180.038555)
			(xy 99.021018 -180.096439) (xy 99.075949 -180.159832) (xy 99.124605 -180.228159) (xy 99.166546 -180.300802)
			(xy 99.201391 -180.377103) (xy 99.228826 -180.45637) (xy 99.248602 -180.537887) (xy 99.26054 -180.620914)
			(xy 99.264531 -180.7047) (xy 99.26054 -180.788486) (xy 99.248602 -180.871513) (xy 99.228826 -180.95303)
			(xy 99.201391 -181.032297) (xy 99.166546 -181.108598) (xy 99.124605 -181.181241) (xy 99.075949 -181.249568)
			(xy 99.021018 -181.312961) (xy 98.96031 -181.370845) (xy 98.894375 -181.422696) (xy 98.82381 -181.468045)
			(xy 98.749253 -181.506481) (xy 98.67138 -181.537656) (xy 98.590897 -181.561287) (xy 98.508532 -181.577161)
			(xy 98.42503 -181.585133) (xy 98.38309 -181.585616) (xy 98.3459 -181.585229) (xy 98.271787 -181.578939)
			(xy 98.198468 -181.566428) (xy 98.126462 -181.547787) (xy 98.091244 -181.535832) (xy 98.083047 -181.533318)
			(xy 98.065913 -181.533318) (xy 98.057716 -181.535832) (xy 98.015534 -181.549982) (xy 97.929009 -181.570726)
			(xy 97.884996 -181.577234) (xy 97.875031 -181.57898) (xy 97.85759 -181.589205) (xy 97.845466 -181.605383)
			(xy 97.842578 -181.61508) (xy 97.833805 -181.648299) (xy 97.811813 -181.713397) (xy 97.798636 -181.745128)
			(xy 97.79505 -181.754712) (xy 97.795064 -181.775161) (xy 97.798636 -181.784752) (xy 97.815664 -181.826127)
			(xy 97.842281 -181.911555) (xy 97.860184 -181.999224) (xy 97.869191 -182.088247) (xy 97.869756 -182.132986)
			(xy 97.869756 -182.13324) (xy 97.869252 -182.175588) (xy 97.861201 -182.259902) (xy 97.845172 -182.343068)
			(xy 97.821311 -182.424335) (xy 97.789832 -182.502965) (xy 97.751021 -182.578246) (xy 97.705231 -182.649498)
			(xy 97.652875 -182.716074) (xy 97.594427 -182.777372) (xy 97.530417 -182.832837) (xy 97.461425 -182.881966)
			(xy 97.388075 -182.924315) (xy 97.311032 -182.959499) (xy 97.230993 -182.987201) (xy 97.148684 -183.007169)
			(xy 97.064849 -183.019222) (xy 96.980248 -183.023253) (xy 96.895647 -183.019222) (xy 96.811812 -183.007169)
			(xy 96.729503 -182.987201) (xy 96.649464 -182.959499) (xy 96.572421 -182.924315) (xy 96.499071 -182.881966)
			(xy 96.430079 -182.832837) (xy 96.366069 -182.777372) (xy 96.307621 -182.716074) (xy 96.255265 -182.649498)
			(xy 96.209475 -182.578246) (xy 96.170664 -182.502965) (xy 96.139185 -182.424335) (xy 96.115324 -182.343068)
			(xy 96.099295 -182.259902) (xy 96.091244 -182.175588) (xy 96.09074 -182.13324) (xy 96.09074 -182.132986)
			(xy 96.091318 -182.088248) (xy 96.10033 -181.999226) (xy 96.118232 -181.911559) (xy 96.144843 -181.826131)
			(xy 96.16186 -181.784752) (xy 96.165401 -181.775154) (xy 96.165416 -181.754718) (xy 96.16186 -181.745128)
			(xy 96.144825 -181.703755) (xy 96.11821 -181.618327) (xy 96.100309 -181.530657) (xy 96.091304 -181.441633)
			(xy 96.09074 -181.396894) (xy 96.09074 -181.395878) (xy 96.090368 -181.38632) (xy 96.083332 -181.368547)
			(xy 96.070254 -181.354605) (xy 96.061784 -181.350158) (xy 95.965264 -181.304184) (xy 95.936308 -181.30774)
			(xy 95.924878 -181.317138) (xy 95.890853 -181.344159) (xy 95.818459 -181.392213) (xy 95.741724 -181.43298)
			(xy 95.66138 -181.466069) (xy 95.578192 -181.491168) (xy 95.492953 -181.508035) (xy 95.406476 -181.51651)
			(xy 95.36303 -181.517036) (xy 95.321915 -181.516573) (xy 95.240035 -181.508988) (xy 95.159204 -181.49388)
			(xy 95.080113 -181.471379) (xy 95.003435 -181.441675) (xy 94.929825 -181.405023) (xy 94.859911 -181.361735)
			(xy 94.794289 -181.312181) (xy 94.73352 -181.256783) (xy 94.678122 -181.196014) (xy 94.628567 -181.130393)
			(xy 94.585279 -181.060479) (xy 94.548626 -180.986869) (xy 94.518922 -180.910191) (xy 94.49642 -180.831099)
			(xy 94.481312 -180.750269) (xy 94.473727 -180.668389) (xy 94.473268 -180.627274) (xy 90.869375 -180.627274)
			(xy 90.872244 -180.6875) (xy 90.868253 -180.771275) (xy 90.856317 -180.854292) (xy 90.836544 -180.935798)
			(xy 90.809114 -181.015056) (xy 90.774274 -181.091347) (xy 90.732339 -181.163981) (xy 90.683691 -181.2323)
			(xy 90.628768 -181.295686) (xy 90.56807 -181.353564) (xy 90.502144 -181.405411) (xy 90.431589 -181.450756)
			(xy 90.357043 -181.489189) (xy 90.279182 -181.520363) (xy 90.198709 -181.543994) (xy 90.116355 -181.559869)
			(xy 90.032865 -181.567844) (xy 89.99093 -181.568344) (xy 89.953741 -181.567944) (xy 89.879628 -181.561657)
			(xy 89.806308 -181.54915) (xy 89.734302 -181.530513) (xy 89.699084 -181.51856) (xy 89.690887 -181.516046)
			(xy 89.673753 -181.516046) (xy 89.665556 -181.51856) (xy 89.630433 -181.5305) (xy 89.558617 -181.54912)
			(xy 89.485489 -181.561626) (xy 89.411567 -181.56793) (xy 89.374472 -181.568344) (xy 89.372948 -181.568344)
			(xy 89.365328 -181.56809) (xy 89.355809 -181.6135) (xy 89.328579 -181.702202) (xy 89.310972 -181.745128)
			(xy 89.307384 -181.754712) (xy 89.307399 -181.775161) (xy 89.310972 -181.784752) (xy 89.327996 -181.826163)
			(xy 89.354632 -181.91165) (xy 89.37254 -181.999382) (xy 89.381538 -182.08847) (xy 89.382092 -182.13324)
			(xy 89.381588 -182.175601) (xy 89.373535 -182.259938) (xy 89.357501 -182.343128) (xy 89.333633 -182.424418)
			(xy 89.302145 -182.50307) (xy 89.263323 -182.578373) (xy 89.21752 -182.649645) (xy 89.165149 -182.716241)
			(xy 89.106684 -182.777556) (xy 89.042656 -182.833037) (xy 88.973644 -182.88218) (xy 88.900274 -182.92454)
			(xy 88.823209 -182.959735) (xy 88.743147 -182.987444) (xy 88.660814 -183.007418) (xy 88.576955 -183.019475)
			(xy 88.49233 -183.023507) (xy 88.407705 -183.019475) (xy 88.323846 -183.007418) (xy 88.241513 -182.987444)
			(xy 88.161451 -182.959735) (xy 88.084386 -182.92454) (xy 88.011016 -182.88218) (xy 87.942004 -182.833037)
			(xy 87.877976 -182.777556) (xy 87.819511 -182.716241) (xy 87.76714 -182.649645) (xy 87.721337 -182.578373)
			(xy 87.682515 -182.50307) (xy 87.651027 -182.424418) (xy 87.627159 -182.343128) (xy 87.611125 -182.259938)
			(xy 87.603072 -182.175601) (xy 87.602568 -182.13324) (xy 87.603127 -182.08847) (xy 87.612138 -181.999385)
			(xy 87.630045 -181.911654) (xy 87.656665 -181.826163) (xy 87.673688 -181.784752) (xy 87.677232 -181.775155)
			(xy 87.677247 -181.754718) (xy 87.673688 -181.745128) (xy 87.65877 -181.708939) (xy 87.634581 -181.634489)
			(xy 87.617023 -181.558202) (xy 87.606232 -181.480668) (xy 87.603838 -181.441598) (xy 87.602983 -181.432757)
			(xy 87.596138 -181.416387) (xy 87.58411 -181.403342) (xy 87.576406 -181.398926) (xy 87.486236 -181.352444)
			(xy 87.459312 -181.35346) (xy 87.447882 -181.360826) (xy 87.412209 -181.38294) (xy 87.337447 -181.421096)
			(xy 87.259425 -181.452047) (xy 87.178837 -181.475518) (xy 87.096397 -181.4913) (xy 87.012838 -181.499253)
			(xy 86.97087 -181.499764) (xy 86.929755 -181.499316) (xy 86.847877 -181.491726) (xy 86.767048 -181.476614)
			(xy 86.687959 -181.454109) (xy 86.611283 -181.424402) (xy 86.537675 -181.387748) (xy 86.467763 -181.344458)
			(xy 86.402144 -181.294902) (xy 86.341376 -181.239504) (xy 86.28598 -181.178735) (xy 86.236426 -181.113114)
			(xy 86.193139 -181.043201) (xy 86.156487 -180.969592) (xy 86.126782 -180.892915) (xy 86.10428 -180.813824)
			(xy 86.08917 -180.732995) (xy 86.081583 -180.651117) (xy 86.081108 -180.610002) (xy 82.462267 -180.610002)
			(xy 82.47114 -180.671714) (xy 82.475131 -180.7555) (xy 82.47114 -180.839286) (xy 82.459202 -180.922313)
			(xy 82.439426 -181.00383) (xy 82.411991 -181.083097) (xy 82.377146 -181.159398) (xy 82.335205 -181.232041)
			(xy 82.286549 -181.300368) (xy 82.231618 -181.363761) (xy 82.17091 -181.421645) (xy 82.104975 -181.473496)
			(xy 82.03441 -181.518845) (xy 81.959853 -181.557281) (xy 81.88198 -181.588456) (xy 81.801497 -181.612087)
			(xy 81.719132 -181.627961) (xy 81.63563 -181.635933) (xy 81.59369 -181.636416) (xy 81.5565 -181.636029)
			(xy 81.482387 -181.629739) (xy 81.409068 -181.617228) (xy 81.337062 -181.598587) (xy 81.301844 -181.586632)
			(xy 81.293647 -181.584118) (xy 81.276513 -181.584118) (xy 81.268316 -181.586632) (xy 81.24011 -181.596266)
			(xy 81.182657 -181.612157) (xy 81.153508 -181.618382) (xy 81.143879 -181.620834) (xy 81.127394 -181.631892)
			(xy 81.116335 -181.648377) (xy 81.113884 -181.658006) (xy 81.104396 -181.702491) (xy 81.07755 -181.789404)
			(xy 81.06029 -181.831488) (xy 81.056659 -181.841055) (xy 81.056528 -181.861499) (xy 81.060036 -181.871112)
			(xy 81.077051 -181.912492) (xy 81.103672 -181.997918) (xy 81.121578 -182.085585) (xy 81.130589 -182.174608)
			(xy 81.131156 -182.219346) (xy 81.131156 -182.2196) (xy 81.130652 -182.261948) (xy 81.122601 -182.346262)
			(xy 81.106572 -182.429428) (xy 81.082711 -182.510695) (xy 81.051232 -182.589325) (xy 81.012421 -182.664606)
			(xy 80.966631 -182.735858) (xy 80.914275 -182.802434) (xy 80.855827 -182.863732) (xy 80.791817 -182.919197)
			(xy 80.722825 -182.968326) (xy 80.649475 -183.010675) (xy 80.572432 -183.045859) (xy 80.492393 -183.073561)
			(xy 80.410084 -183.093529) (xy 80.326249 -183.105582) (xy 80.241648 -183.109613) (xy 80.157047 -183.105582)
			(xy 80.073212 -183.093529) (xy 79.990903 -183.073561) (xy 79.910864 -183.045859) (xy 79.833821 -183.010675)
			(xy 79.760471 -182.968326) (xy 79.691479 -182.919197) (xy 79.627469 -182.863732) (xy 79.569021 -182.802434)
			(xy 79.516665 -182.735858) (xy 79.470875 -182.664606) (xy 79.432064 -182.589325) (xy 79.400585 -182.510695)
			(xy 79.376724 -182.429428) (xy 79.360695 -182.346262) (xy 79.352644 -182.261948) (xy 79.35214 -182.2196)
			(xy 79.35214 -182.219346) (xy 79.352704 -182.174608) (xy 79.361721 -182.085586) (xy 79.379627 -181.997918)
			(xy 79.406242 -181.912491) (xy 79.42326 -181.871112) (xy 79.426824 -181.861521) (xy 79.426824 -181.841079)
			(xy 79.42326 -181.831488) (xy 79.406239 -181.790076) (xy 79.379604 -181.704589) (xy 79.361695 -181.616857)
			(xy 79.352696 -181.52777) (xy 79.35214 -181.483) (xy 79.35214 -181.482746) (xy 79.352599 -181.44258)
			(xy 79.359845 -181.362574) (xy 79.366618 -181.32298) (xy 79.366618 -181.322726) (xy 79.368105 -181.310829)
			(xy 79.361202 -181.287898) (xy 79.35341 -181.278784) (xy 79.287878 -181.210204) (xy 79.265018 -181.202076)
			(xy 79.252826 -181.203854) (xy 79.222877 -181.207733) (xy 79.162627 -181.21193) (xy 79.13243 -181.212236)
			(xy 79.091315 -181.211773) (xy 79.009435 -181.204188) (xy 78.928604 -181.18908) (xy 78.849513 -181.166579)
			(xy 78.772835 -181.136875) (xy 78.699225 -181.100223) (xy 78.629311 -181.056935) (xy 78.563689 -181.007381)
			(xy 78.50292 -180.951983) (xy 78.447522 -180.891214) (xy 78.397967 -180.825593) (xy 78.354679 -180.755679)
			(xy 78.318026 -180.682069) (xy 78.288322 -180.605391) (xy 78.26582 -180.526299) (xy 78.250712 -180.445469)
			(xy 78.243127 -180.363589) (xy 78.242668 -180.322474) (xy 78.242668 -180.321966) (xy 78.243175 -180.279292)
			(xy 78.251378 -180.194339) (xy 78.267677 -180.110561) (xy 78.291921 -180.028728) (xy 78.307438 -179.988972)
			(xy 78.311043 -179.978929) (xy 78.310391 -179.957622) (xy 78.306168 -179.947824) (xy 78.289089 -179.911553)
			(xy 78.260784 -179.836541) (xy 78.239347 -179.759284) (xy 78.224953 -179.680411) (xy 78.217719 -179.600562)
			(xy 78.217268 -179.560474) (xy 78.21746 -179.533866) (xy 78.220637 -179.480744) (xy 78.223618 -179.454302)
			(xy 78.224368 -179.443055) (xy 78.217254 -179.421697) (xy 78.209902 -179.413154) (xy 78.180933 -179.382157)
			(xy 78.128411 -179.31552) (xy 78.082469 -179.244186) (xy 78.043525 -179.168805) (xy 78.011931 -179.090059)
			(xy 77.987974 -179.008663) (xy 77.971872 -178.925358) (xy 77.963772 -178.840898) (xy 77.963268 -178.798474)
			(xy 9.44304 -178.798474) (xy 9.441677 -178.801459) (xy 9.412211 -178.847309) (xy 9.37652 -178.8885)
			(xy 9.335329 -178.924191) (xy 9.289479 -178.953657) (xy 9.239902 -178.976299) (xy 9.187607 -178.991654)
			(xy 9.133659 -178.99941) (xy 9.079157 -178.99941) (xy 9.025209 -178.991654) (xy 8.972914 -178.976299)
			(xy 8.923337 -178.953657) (xy 8.877487 -178.924191) (xy 8.836296 -178.8885) (xy 8.800605 -178.847309)
			(xy 8.771139 -178.801459) (xy 8.748497 -178.751882) (xy 8.733142 -178.699587) (xy 8.725386 -178.645639)
			(xy 8.7249 -178.618388) (xy 2.509012 -178.618388) (xy 2.509012 -190.64715) (xy 220.414866 -190.64715)
			(xy 220.414866 -190.59265) (xy 220.422621 -190.538705) (xy 220.437974 -190.486413) (xy 220.460612 -190.436837)
			(xy 220.490075 -190.390988) (xy 220.525762 -190.349798) (xy 220.566948 -190.314105) (xy 220.612793 -190.284636)
			(xy 220.662366 -190.261992) (xy 220.714656 -190.246632) (xy 220.7686 -190.238869) (xy 220.79585 -190.23838)
			(xy 221.78645 -190.23838) (xy 221.813704 -190.238864) (xy 221.867659 -190.246615) (xy 221.919961 -190.261966)
			(xy 221.969546 -190.284605) (xy 222.015404 -190.314071) (xy 222.056601 -190.349763) (xy 222.092299 -190.390956)
			(xy 222.121771 -190.43681) (xy 222.144416 -190.486392) (xy 222.159775 -190.538692) (xy 222.167533 -190.592646)
			(xy 222.167533 -190.647154) (xy 222.159775 -190.701108) (xy 222.144416 -190.753408) (xy 222.121771 -190.80299)
			(xy 222.092299 -190.848844) (xy 222.056601 -190.890037) (xy 222.015404 -190.925729) (xy 221.969546 -190.955195)
			(xy 221.919961 -190.977834) (xy 221.867659 -190.993185) (xy 221.813704 -191.000936) (xy 221.78645 -191.001396)
			(xy 220.79585 -191.001396) (xy 220.7686 -191.000931) (xy 220.714656 -190.993168) (xy 220.662366 -190.977808)
			(xy 220.612793 -190.955164) (xy 220.566948 -190.925695) (xy 220.525762 -190.890002) (xy 220.490075 -190.848812)
			(xy 220.460612 -190.802963) (xy 220.437974 -190.753387) (xy 220.422621 -190.701095) (xy 220.414866 -190.64715)
			(xy 2.509012 -190.64715) (xy 2.509012 -194.296284) (xy 255.545336 -194.296284) (xy 255.545336 -193.432684)
			(xy 255.545822 -193.405415) (xy 255.553584 -193.351431) (xy 255.568949 -193.299101) (xy 255.591606 -193.249491)
			(xy 255.621092 -193.20361) (xy 255.656807 -193.162393) (xy 255.698024 -193.126678) (xy 255.743905 -193.097192)
			(xy 255.793515 -193.074535) (xy 255.845845 -193.05917) (xy 255.899829 -193.051408) (xy 255.954367 -193.051408)
			(xy 256.008351 -193.05917) (xy 256.060681 -193.074535) (xy 256.110291 -193.097192) (xy 256.156172 -193.126678)
			(xy 256.197389 -193.162393) (xy 256.233104 -193.20361) (xy 256.26259 -193.249491) (xy 256.285247 -193.299101)
			(xy 256.300612 -193.351431) (xy 256.308374 -193.405415) (xy 256.30886 -193.432684) (xy 256.30886 -194.296284)
			(xy 256.308374 -194.323553) (xy 256.300612 -194.377537) (xy 256.285247 -194.429867) (xy 256.26259 -194.479477)
			(xy 256.25414 -194.492626) (xy 260.09346 -194.492626) (xy 260.09346 -193.502026) (xy 260.093946 -193.474757)
			(xy 260.101708 -193.420773) (xy 260.117073 -193.368443) (xy 260.13973 -193.318833) (xy 260.169216 -193.272952)
			(xy 260.204931 -193.231735) (xy 260.246148 -193.19602) (xy 260.292029 -193.166534) (xy 260.341639 -193.143877)
			(xy 260.393969 -193.128512) (xy 260.447953 -193.12075) (xy 260.502491 -193.12075) (xy 260.556475 -193.128512)
			(xy 260.608805 -193.143877) (xy 260.658415 -193.166534) (xy 260.704296 -193.19602) (xy 260.745513 -193.231735)
			(xy 260.781228 -193.272952) (xy 260.810714 -193.318833) (xy 260.833371 -193.368443) (xy 260.848736 -193.420773)
			(xy 260.856498 -193.474757) (xy 260.856984 -193.502026) (xy 260.856984 -194.492626) (xy 260.856498 -194.519895)
			(xy 260.848736 -194.573879) (xy 260.833371 -194.626209) (xy 260.810714 -194.675819) (xy 260.781228 -194.7217)
			(xy 260.745513 -194.762917) (xy 260.704296 -194.798632) (xy 260.658415 -194.828118) (xy 260.608805 -194.850775)
			(xy 260.556475 -194.86614) (xy 260.502491 -194.873902) (xy 260.447953 -194.873902) (xy 260.393969 -194.86614)
			(xy 260.341639 -194.850775) (xy 260.292029 -194.828118) (xy 260.246148 -194.798632) (xy 260.204931 -194.762917)
			(xy 260.169216 -194.7217) (xy 260.13973 -194.675819) (xy 260.117073 -194.626209) (xy 260.101708 -194.573879)
			(xy 260.093946 -194.519895) (xy 260.09346 -194.492626) (xy 256.25414 -194.492626) (xy 256.233104 -194.525358)
			(xy 256.197389 -194.566575) (xy 256.156172 -194.60229) (xy 256.110291 -194.631776) (xy 256.060681 -194.654433)
			(xy 256.008351 -194.669798) (xy 255.954367 -194.67756) (xy 255.899829 -194.67756) (xy 255.845845 -194.669798)
			(xy 255.793515 -194.654433) (xy 255.743905 -194.631776) (xy 255.698024 -194.60229) (xy 255.656807 -194.566575)
			(xy 255.621092 -194.525358) (xy 255.591606 -194.479477) (xy 255.568949 -194.429867) (xy 255.553584 -194.377537)
			(xy 255.545822 -194.323553) (xy 255.545336 -194.296284) (xy 2.509012 -194.296284) (xy 2.509012 -197.07352)
			(xy 255.545336 -197.07352) (xy 255.545336 -196.20992) (xy 255.545822 -196.182651) (xy 255.553584 -196.128667)
			(xy 255.568949 -196.076337) (xy 255.591606 -196.026727) (xy 255.621092 -195.980846) (xy 255.656807 -195.939629)
			(xy 255.698024 -195.903914) (xy 255.743905 -195.874428) (xy 255.793515 -195.851771) (xy 255.845845 -195.836406)
			(xy 255.899829 -195.828644) (xy 255.954367 -195.828644) (xy 256.008351 -195.836406) (xy 256.060681 -195.851771)
			(xy 256.110291 -195.874428) (xy 256.156172 -195.903914) (xy 256.197389 -195.939629) (xy 256.233104 -195.980846)
			(xy 256.26259 -196.026727) (xy 256.285247 -196.076337) (xy 256.300612 -196.128667) (xy 256.308374 -196.182651)
			(xy 256.30886 -196.20992) (xy 256.30886 -197.07352) (xy 256.308374 -197.100789) (xy 256.300612 -197.154773)
			(xy 256.285247 -197.207103) (xy 256.26259 -197.256713) (xy 256.233104 -197.302594) (xy 256.197389 -197.343811)
			(xy 256.156172 -197.379526) (xy 256.110291 -197.409012) (xy 256.060681 -197.431669) (xy 256.008351 -197.447034)
			(xy 255.954367 -197.454796) (xy 255.899829 -197.454796) (xy 255.845845 -197.447034) (xy 255.793515 -197.431669)
			(xy 255.743905 -197.409012) (xy 255.698024 -197.379526) (xy 255.656807 -197.343811) (xy 255.621092 -197.302594)
			(xy 255.591606 -197.256713) (xy 255.568949 -197.207103) (xy 255.553584 -197.154773) (xy 255.545822 -197.100789)
			(xy 255.545336 -197.07352) (xy 2.509012 -197.07352) (xy 2.509012 -199.868028) (xy 255.545336 -199.868028)
			(xy 255.545336 -199.004428) (xy 255.545822 -198.977159) (xy 255.553584 -198.923175) (xy 255.568949 -198.870845)
			(xy 255.591606 -198.821235) (xy 255.621092 -198.775354) (xy 255.656807 -198.734137) (xy 255.698024 -198.698422)
			(xy 255.743905 -198.668936) (xy 255.793515 -198.646279) (xy 255.845845 -198.630914) (xy 255.899829 -198.623152)
			(xy 255.954367 -198.623152) (xy 256.008351 -198.630914) (xy 256.060681 -198.646279) (xy 256.110291 -198.668936)
			(xy 256.156172 -198.698422) (xy 256.197389 -198.734137) (xy 256.233104 -198.775354) (xy 256.26259 -198.821235)
			(xy 256.285247 -198.870845) (xy 256.300612 -198.923175) (xy 256.308374 -198.977159) (xy 256.30886 -199.004428)
			(xy 256.30886 -199.868028) (xy 256.308374 -199.895297) (xy 256.300612 -199.949281) (xy 256.285247 -200.001611)
			(xy 256.26259 -200.051221) (xy 256.233104 -200.097102) (xy 256.197389 -200.138319) (xy 256.156172 -200.174034)
			(xy 256.110291 -200.20352) (xy 256.060681 -200.226177) (xy 256.008351 -200.241542) (xy 255.954367 -200.249304)
			(xy 255.899829 -200.249304) (xy 255.845845 -200.241542) (xy 255.793515 -200.226177) (xy 255.743905 -200.20352)
			(xy 255.698024 -200.174034) (xy 255.656807 -200.138319) (xy 255.621092 -200.097102) (xy 255.591606 -200.051221)
			(xy 255.568949 -200.001611) (xy 255.553584 -199.949281) (xy 255.545822 -199.895297) (xy 255.545336 -199.868028)
			(xy 2.509012 -199.868028) (xy 2.509012 -202.662536) (xy 255.545336 -202.662536) (xy 255.545336 -201.798936)
			(xy 255.545822 -201.771667) (xy 255.553584 -201.717683) (xy 255.568949 -201.665353) (xy 255.591606 -201.615743)
			(xy 255.621092 -201.569862) (xy 255.656807 -201.528645) (xy 255.698024 -201.49293) (xy 255.743905 -201.463444)
			(xy 255.793515 -201.440787) (xy 255.845845 -201.425422) (xy 255.899829 -201.41766) (xy 255.954367 -201.41766)
			(xy 256.008351 -201.425422) (xy 256.060681 -201.440787) (xy 256.110291 -201.463444) (xy 256.156172 -201.49293)
			(xy 256.197389 -201.528645) (xy 256.233104 -201.569862) (xy 256.26259 -201.615743) (xy 256.285247 -201.665353)
			(xy 256.300612 -201.717683) (xy 256.308374 -201.771667) (xy 256.30886 -201.798936) (xy 256.30886 -202.662536)
			(xy 256.308374 -202.689805) (xy 256.300612 -202.743789) (xy 256.285247 -202.796119) (xy 256.26259 -202.845729)
			(xy 256.233104 -202.89161) (xy 256.197389 -202.932827) (xy 256.156172 -202.968542) (xy 256.110291 -202.998028)
			(xy 256.060681 -203.020685) (xy 256.008351 -203.03605) (xy 255.954367 -203.043812) (xy 255.899829 -203.043812)
			(xy 255.845845 -203.03605) (xy 255.793515 -203.020685) (xy 255.743905 -202.998028) (xy 255.698024 -202.968542)
			(xy 255.656807 -202.932827) (xy 255.621092 -202.89161) (xy 255.591606 -202.845729) (xy 255.568949 -202.796119)
			(xy 255.553584 -202.743789) (xy 255.545822 -202.689805) (xy 255.545336 -202.662536) (xy 2.509012 -202.662536)
			(xy 2.509012 -205.439772) (xy 255.545336 -205.439772) (xy 255.545336 -204.576172) (xy 255.545822 -204.548903)
			(xy 255.553584 -204.494919) (xy 255.568949 -204.442589) (xy 255.591606 -204.392979) (xy 255.621092 -204.347098)
			(xy 255.656807 -204.305881) (xy 255.698024 -204.270166) (xy 255.743905 -204.24068) (xy 255.793515 -204.218023)
			(xy 255.845845 -204.202658) (xy 255.899829 -204.194896) (xy 255.954367 -204.194896) (xy 256.008351 -204.202658)
			(xy 256.060681 -204.218023) (xy 256.110291 -204.24068) (xy 256.156172 -204.270166) (xy 256.197389 -204.305881)
			(xy 256.233104 -204.347098) (xy 256.26259 -204.392979) (xy 256.285247 -204.442589) (xy 256.300612 -204.494919)
			(xy 256.308374 -204.548903) (xy 256.30886 -204.576172) (xy 256.30886 -205.439772) (xy 256.308374 -205.467041)
			(xy 256.300612 -205.521025) (xy 256.285247 -205.573355) (xy 256.26259 -205.622965) (xy 256.233104 -205.668846)
			(xy 256.197389 -205.710063) (xy 256.156172 -205.745778) (xy 256.110291 -205.775264) (xy 256.060681 -205.797921)
			(xy 256.008351 -205.813286) (xy 255.954367 -205.821048) (xy 255.899829 -205.821048) (xy 255.845845 -205.813286)
			(xy 255.793515 -205.797921) (xy 255.743905 -205.775264) (xy 255.698024 -205.745778) (xy 255.656807 -205.710063)
			(xy 255.621092 -205.668846) (xy 255.591606 -205.622965) (xy 255.568949 -205.573355) (xy 255.553584 -205.521025)
			(xy 255.545822 -205.467041) (xy 255.545336 -205.439772) (xy 2.509012 -205.439772) (xy 2.509012 -207.499458)
			(xy 97.408492 -207.499458) (xy 97.408492 -206.635858) (xy 97.408978 -206.608589) (xy 97.41674 -206.554605)
			(xy 97.432105 -206.502275) (xy 97.454762 -206.452665) (xy 97.484248 -206.406784) (xy 97.519963 -206.365567)
			(xy 97.56118 -206.329852) (xy 97.607061 -206.300366) (xy 97.656671 -206.277709) (xy 97.709001 -206.262344)
			(xy 97.762985 -206.254582) (xy 97.817523 -206.254582) (xy 97.871507 -206.262344) (xy 97.923837 -206.277709)
			(xy 97.973447 -206.300366) (xy 98.019328 -206.329852) (xy 98.060545 -206.365567) (xy 98.09626 -206.406784)
			(xy 98.125746 -206.452665) (xy 98.148403 -206.502275) (xy 98.163768 -206.554605) (xy 98.17153 -206.608589)
			(xy 98.172016 -206.635858) (xy 98.172016 -207.499458) (xy 98.17153 -207.526727) (xy 98.163768 -207.580711)
			(xy 98.148403 -207.633041) (xy 98.125746 -207.682651) (xy 98.09626 -207.728532) (xy 98.060545 -207.769749)
			(xy 98.019328 -207.805464) (xy 97.973447 -207.83495) (xy 97.923837 -207.857607) (xy 97.871507 -207.872972)
			(xy 97.817523 -207.880734) (xy 97.762985 -207.880734) (xy 97.709001 -207.872972) (xy 97.656671 -207.857607)
			(xy 97.607061 -207.83495) (xy 97.56118 -207.805464) (xy 97.519963 -207.769749) (xy 97.484248 -207.728532)
			(xy 97.454762 -207.682651) (xy 97.432105 -207.633041) (xy 97.41674 -207.580711) (xy 97.408978 -207.526727)
			(xy 97.408492 -207.499458) (xy 2.509012 -207.499458) (xy 2.509012 -209.023458) (xy 94.105984 -209.023458)
			(xy 94.105984 -208.159858) (xy 94.10647 -208.132589) (xy 94.114232 -208.078605) (xy 94.129597 -208.026275)
			(xy 94.152254 -207.976665) (xy 94.18174 -207.930784) (xy 94.217455 -207.889567) (xy 94.258672 -207.853852)
			(xy 94.304553 -207.824366) (xy 94.354163 -207.801709) (xy 94.406493 -207.786344) (xy 94.460477 -207.778582)
			(xy 94.515015 -207.778582) (xy 94.568999 -207.786344) (xy 94.621329 -207.801709) (xy 94.670939 -207.824366)
			(xy 94.71682 -207.853852) (xy 94.758037 -207.889567) (xy 94.793752 -207.930784) (xy 94.823238 -207.976665)
			(xy 94.845895 -208.026275) (xy 94.86126 -208.078605) (xy 94.869022 -208.132589) (xy 94.869508 -208.159858)
			(xy 94.869508 -208.217008) (xy 255.545336 -208.217008) (xy 255.545336 -207.353408) (xy 255.545822 -207.326139)
			(xy 255.553584 -207.272155) (xy 255.568949 -207.219825) (xy 255.591606 -207.170215) (xy 255.621092 -207.124334)
			(xy 255.656807 -207.083117) (xy 255.698024 -207.047402) (xy 255.743905 -207.017916) (xy 255.793515 -206.995259)
			(xy 255.845845 -206.979894) (xy 255.899829 -206.972132) (xy 255.954367 -206.972132) (xy 256.008351 -206.979894)
			(xy 256.060681 -206.995259) (xy 256.110291 -207.017916) (xy 256.156172 -207.047402) (xy 256.197389 -207.083117)
			(xy 256.233104 -207.124334) (xy 256.26259 -207.170215) (xy 256.285247 -207.219825) (xy 256.300612 -207.272155)
			(xy 256.308374 -207.326139) (xy 256.30886 -207.353408) (xy 256.30886 -208.217008) (xy 256.308374 -208.244277)
			(xy 256.300612 -208.298261) (xy 256.285247 -208.350591) (xy 256.26259 -208.400201) (xy 256.233104 -208.446082)
			(xy 256.197389 -208.487299) (xy 256.156172 -208.523014) (xy 256.110291 -208.5525) (xy 256.060681 -208.575157)
			(xy 256.008351 -208.590522) (xy 255.954367 -208.598284) (xy 255.899829 -208.598284) (xy 255.845845 -208.590522)
			(xy 255.793515 -208.575157) (xy 255.743905 -208.5525) (xy 255.698024 -208.523014) (xy 255.656807 -208.487299)
			(xy 255.621092 -208.446082) (xy 255.591606 -208.400201) (xy 255.568949 -208.350591) (xy 255.553584 -208.298261)
			(xy 255.545822 -208.244277) (xy 255.545336 -208.217008) (xy 94.869508 -208.217008) (xy 94.869508 -209.023458)
			(xy 94.869022 -209.050727) (xy 94.86126 -209.104711) (xy 94.845895 -209.157041) (xy 94.823238 -209.206651)
			(xy 94.793752 -209.252532) (xy 94.758037 -209.293749) (xy 94.71682 -209.329464) (xy 94.670939 -209.35895)
			(xy 94.621329 -209.381607) (xy 94.568999 -209.396972) (xy 94.515015 -209.404734) (xy 94.460477 -209.404734)
			(xy 94.406493 -209.396972) (xy 94.354163 -209.381607) (xy 94.304553 -209.35895) (xy 94.258672 -209.329464)
			(xy 94.217455 -209.293749) (xy 94.18174 -209.252532) (xy 94.152254 -209.206651) (xy 94.129597 -209.157041)
			(xy 94.114232 -209.104711) (xy 94.10647 -209.050727) (xy 94.105984 -209.023458) (xy 2.509012 -209.023458)
			(xy 2.509012 -212.98027) (xy 78.81214 -212.98027) (xy 78.81617 -212.837935) (xy 78.828245 -212.696055)
			(xy 78.848328 -212.555087) (xy 78.876355 -212.41548) (xy 78.912235 -212.277682) (xy 78.955853 -212.142135)
			(xy 79.00707 -212.009273) (xy 79.065721 -211.879521) (xy 79.131619 -211.753295) (xy 79.204553 -211.630999)
			(xy 79.28429 -211.513026) (xy 79.370572 -211.399753) (xy 79.463125 -211.291542) (xy 79.561652 -211.188741)
			(xy 79.665837 -211.091679) (xy 79.775346 -211.000667) (xy 79.889829 -210.915995) (xy 80.008919 -210.837937)
			(xy 80.132234 -210.766741) (xy 80.25938 -210.702635) (xy 80.389949 -210.645826) (xy 80.523523 -210.596494)
			(xy 80.659674 -210.554798) (xy 80.797965 -210.520872) (xy 80.937955 -210.494824) (xy 81.079194 -210.476738)
			(xy 81.22123 -210.466671) (xy 81.363608 -210.464656) (xy 81.505872 -210.470699) (xy 81.647566 -210.484781)
			(xy 81.788236 -210.506857) (xy 81.927433 -210.536857) (xy 82.064709 -210.574683) (xy 82.199625 -210.620215)
			(xy 82.331749 -210.673306) (xy 82.460658 -210.733788) (xy 82.585939 -210.801466) (xy 82.70719 -210.876123)
			(xy 82.824023 -210.957521) (xy 82.936064 -211.045398) (xy 83.042954 -211.139473) (xy 83.144351 -211.239445)
			(xy 83.239929 -211.344993) (xy 83.329383 -211.455779) (xy 83.412425 -211.571448) (xy 83.488791 -211.691631)
			(xy 83.558235 -211.815941) (xy 83.620535 -211.943982) (xy 83.675491 -212.075341) (xy 83.69835 -212.140038)
			(xy 94.106492 -212.140038) (xy 94.106492 -211.276438) (xy 94.106978 -211.249187) (xy 94.114734 -211.195239)
			(xy 94.130089 -211.142944) (xy 94.152731 -211.093367) (xy 94.182197 -211.047517) (xy 94.217888 -211.006326)
			(xy 94.259079 -210.970635) (xy 94.304929 -210.941169) (xy 94.354506 -210.918527) (xy 94.406801 -210.903172)
			(xy 94.460749 -210.895416) (xy 94.515251 -210.895416) (xy 94.569199 -210.903172) (xy 94.621494 -210.918527)
			(xy 94.671071 -210.941169) (xy 94.716921 -210.970635) (xy 94.758112 -211.006326) (xy 94.793803 -211.047517)
			(xy 94.823269 -211.093367) (xy 94.845911 -211.142944) (xy 94.861266 -211.195239) (xy 94.869022 -211.249187)
			(xy 94.869508 -211.276438) (xy 94.869508 -212.140038) (xy 94.869022 -212.167289) (xy 94.861266 -212.221237)
			(xy 94.845911 -212.273532) (xy 94.823269 -212.323109) (xy 94.793803 -212.368959) (xy 94.758112 -212.41015)
			(xy 94.716921 -212.445841) (xy 94.671071 -212.475307) (xy 94.621494 -212.497949) (xy 94.569199 -212.513304)
			(xy 94.515251 -212.52106) (xy 94.460749 -212.52106) (xy 94.406801 -212.513304) (xy 94.354506 -212.497949)
			(xy 94.304929 -212.475307) (xy 94.259079 -212.445841) (xy 94.217888 -212.41015) (xy 94.182197 -212.368959)
			(xy 94.152731 -212.323109) (xy 94.130089 -212.273532) (xy 94.114734 -212.221237) (xy 94.106978 -212.167289)
			(xy 94.106492 -212.140038) (xy 83.69835 -212.140038) (xy 83.722928 -212.2096) (xy 83.762692 -212.346327)
			(xy 83.794658 -212.485085) (xy 83.818723 -212.625429) (xy 83.834809 -212.76691) (xy 83.842864 -212.909074)
			(xy 83.843368 -212.98027) (xy 140.011408 -212.98027) (xy 140.015438 -212.837906) (xy 140.027516 -212.695998)
			(xy 140.047604 -212.555001) (xy 140.075636 -212.415366) (xy 140.111523 -212.27754) (xy 140.15515 -212.141966)
			(xy 140.206377 -212.009077) (xy 140.26504 -211.879298) (xy 140.330952 -211.753047) (xy 140.403901 -211.630727)
			(xy 140.483653 -211.51273) (xy 140.569953 -211.399434) (xy 140.662525 -211.291201) (xy 140.761071 -211.188379)
			(xy 140.865277 -211.091298) (xy 140.974809 -211.000267) (xy 141.089315 -210.915579) (xy 141.208429 -210.837504)
			(xy 141.331769 -210.766294) (xy 141.45894 -210.702175) (xy 141.589536 -210.645354) (xy 141.723136 -210.596013)
			(xy 141.859315 -210.554308) (xy 141.997634 -210.520375) (xy 142.137652 -210.494322) (xy 142.278919 -210.476232)
			(xy 142.420984 -210.466163) (xy 142.563391 -210.464148) (xy 142.705684 -210.470192) (xy 142.847406 -210.484278)
			(xy 142.988105 -210.506358) (xy 143.12733 -210.536363) (xy 143.264634 -210.574197) (xy 143.399577 -210.619738)
			(xy 143.531728 -210.672841) (xy 143.660663 -210.733335) (xy 143.785969 -210.801026) (xy 143.907245 -210.875699)
			(xy 144.024101 -210.957113) (xy 144.093464 -211.011516) (xy 255.545336 -211.011516) (xy 255.545336 -210.147916)
			(xy 255.545822 -210.120647) (xy 255.553584 -210.066663) (xy 255.568949 -210.014333) (xy 255.591606 -209.964723)
			(xy 255.621092 -209.918842) (xy 255.656807 -209.877625) (xy 255.698024 -209.84191) (xy 255.743905 -209.812424)
			(xy 255.793515 -209.789767) (xy 255.845845 -209.774402) (xy 255.899829 -209.76664) (xy 255.954367 -209.76664)
			(xy 256.008351 -209.774402) (xy 256.060681 -209.789767) (xy 256.110291 -209.812424) (xy 256.156172 -209.84191)
			(xy 256.197389 -209.877625) (xy 256.233104 -209.918842) (xy 256.26259 -209.964723) (xy 256.285247 -210.014333)
			(xy 256.300612 -210.066663) (xy 256.308374 -210.120647) (xy 256.30886 -210.147916) (xy 256.30886 -211.011516)
			(xy 256.308374 -211.038785) (xy 256.300612 -211.092769) (xy 256.285247 -211.145099) (xy 256.26259 -211.194709)
			(xy 256.233104 -211.24059) (xy 256.197389 -211.281807) (xy 256.156172 -211.317522) (xy 256.110291 -211.347008)
			(xy 256.060681 -211.369665) (xy 256.008351 -211.38503) (xy 255.954367 -211.392792) (xy 255.899829 -211.392792)
			(xy 255.845845 -211.38503) (xy 255.793515 -211.369665) (xy 255.743905 -211.347008) (xy 255.698024 -211.317522)
			(xy 255.656807 -211.281807) (xy 255.621092 -211.24059) (xy 255.591606 -211.194709) (xy 255.568949 -211.145099)
			(xy 255.553584 -211.092769) (xy 255.545822 -211.038785) (xy 255.545336 -211.011516) (xy 144.093464 -211.011516)
			(xy 144.136165 -211.045007) (xy 144.243077 -211.139101) (xy 144.344494 -211.239093) (xy 144.440091 -211.344662)
			(xy 144.529563 -211.455471) (xy 144.612622 -211.571164) (xy 144.689003 -211.691371) (xy 144.758461 -211.815706)
			(xy 144.820774 -211.943772) (xy 144.875741 -212.075159) (xy 144.923187 -212.209444) (xy 144.96296 -212.346199)
			(xy 144.994932 -212.484985) (xy 145.019002 -212.625357) (xy 145.035091 -212.766867) (xy 145.043148 -212.909059)
			(xy 145.043652 -212.98027) (xy 145.043148 -213.051481) (xy 145.035091 -213.193673) (xy 145.019002 -213.335183)
			(xy 144.994932 -213.475555) (xy 144.96296 -213.614341) (xy 144.923187 -213.751096) (xy 144.90378 -213.806024)
			(xy 255.545336 -213.806024) (xy 255.545336 -212.942424) (xy 255.545822 -212.915155) (xy 255.553584 -212.861171)
			(xy 255.568949 -212.808841) (xy 255.591606 -212.759231) (xy 255.621092 -212.71335) (xy 255.656807 -212.672133)
			(xy 255.698024 -212.636418) (xy 255.743905 -212.606932) (xy 255.793515 -212.584275) (xy 255.845845 -212.56891)
			(xy 255.899829 -212.561148) (xy 255.954367 -212.561148) (xy 256.008351 -212.56891) (xy 256.060681 -212.584275)
			(xy 256.110291 -212.606932) (xy 256.156172 -212.636418) (xy 256.197389 -212.672133) (xy 256.233104 -212.71335)
			(xy 256.26259 -212.759231) (xy 256.285247 -212.808841) (xy 256.300612 -212.861171) (xy 256.308374 -212.915155)
			(xy 256.30886 -212.942424) (xy 256.30886 -212.980016) (xy 326.752208 -212.980016) (xy 326.756238 -212.837681)
			(xy 326.768313 -212.695801) (xy 326.788396 -212.554833) (xy 326.816423 -212.415226) (xy 326.852303 -212.277428)
			(xy 326.895921 -212.141881) (xy 326.947138 -212.009019) (xy 327.005789 -211.879267) (xy 327.071687 -211.753041)
			(xy 327.144621 -211.630745) (xy 327.224358 -211.512772) (xy 327.31064 -211.399499) (xy 327.403193 -211.291288)
			(xy 327.50172 -211.188487) (xy 327.605905 -211.091425) (xy 327.715414 -211.000413) (xy 327.829897 -210.915741)
			(xy 327.948987 -210.837683) (xy 328.072302 -210.766487) (xy 328.199448 -210.702381) (xy 328.330017 -210.645572)
			(xy 328.463591 -210.59624) (xy 328.599742 -210.554544) (xy 328.738033 -210.520618) (xy 328.878023 -210.49457)
			(xy 329.019262 -210.476484) (xy 329.161298 -210.466417) (xy 329.303676 -210.464402) (xy 329.44594 -210.470445)
			(xy 329.587634 -210.484527) (xy 329.728304 -210.506603) (xy 329.867501 -210.536603) (xy 330.004777 -210.574429)
			(xy 330.139693 -210.619961) (xy 330.271817 -210.673052) (xy 330.400726 -210.733534) (xy 330.526007 -210.801212)
			(xy 330.647258 -210.875869) (xy 330.764091 -210.957267) (xy 330.876132 -211.045144) (xy 330.983022 -211.139219)
			(xy 331.084419 -211.239191) (xy 331.179997 -211.344739) (xy 331.269451 -211.455525) (xy 331.352493 -211.571194)
			(xy 331.428859 -211.691377) (xy 331.498303 -211.815687) (xy 331.560603 -211.943728) (xy 331.615559 -212.075087)
			(xy 331.662996 -212.209346) (xy 331.70276 -212.346073) (xy 331.734726 -212.484831) (xy 331.758791 -212.625175)
			(xy 331.774877 -212.766656) (xy 331.782932 -212.90882) (xy 331.783436 -212.980016) (xy 387.951476 -212.980016)
			(xy 387.955506 -212.837652) (xy 387.967584 -212.695744) (xy 387.987672 -212.554747) (xy 388.015704 -212.415112)
			(xy 388.051591 -212.277286) (xy 388.095218 -212.141712) (xy 388.146445 -212.008823) (xy 388.205108 -211.879044)
			(xy 388.27102 -211.752793) (xy 388.343969 -211.630473) (xy 388.423721 -211.512476) (xy 388.510021 -211.39918)
			(xy 388.602593 -211.290947) (xy 388.701139 -211.188125) (xy 388.805345 -211.091044) (xy 388.914877 -211.000013)
			(xy 389.029383 -210.915325) (xy 389.148497 -210.83725) (xy 389.271837 -210.76604) (xy 389.399008 -210.701921)
			(xy 389.529604 -210.6451) (xy 389.663204 -210.595759) (xy 389.799383 -210.554054) (xy 389.937702 -210.520121)
			(xy 390.07772 -210.494068) (xy 390.218987 -210.475978) (xy 390.361052 -210.465909) (xy 390.503459 -210.463894)
			(xy 390.645752 -210.469938) (xy 390.787474 -210.484024) (xy 390.928173 -210.506104) (xy 391.067398 -210.536109)
			(xy 391.204702 -210.573943) (xy 391.339645 -210.619484) (xy 391.471796 -210.672587) (xy 391.600731 -210.733081)
			(xy 391.726037 -210.800772) (xy 391.847313 -210.875445) (xy 391.964169 -210.956859) (xy 392.076233 -211.044753)
			(xy 392.183145 -211.138847) (xy 392.284562 -211.238839) (xy 392.380159 -211.344408) (xy 392.469631 -211.455217)
			(xy 392.55269 -211.57091) (xy 392.629071 -211.691117) (xy 392.698529 -211.815452) (xy 392.760842 -211.943518)
			(xy 392.815809 -212.074905) (xy 392.863255 -212.20919) (xy 392.903028 -212.345945) (xy 392.935 -212.484731)
			(xy 392.95907 -212.625103) (xy 392.975159 -212.766613) (xy 392.983216 -212.908805) (xy 392.98372 -212.980016)
			(xy 392.983216 -213.051227) (xy 392.975159 -213.193419) (xy 392.95907 -213.334929) (xy 392.935 -213.475301)
			(xy 392.903028 -213.614087) (xy 392.863255 -213.750842) (xy 392.815809 -213.885127) (xy 392.760842 -214.016514)
			(xy 392.698529 -214.14458) (xy 392.629071 -214.268915) (xy 392.55269 -214.389122) (xy 392.469631 -214.504815)
			(xy 392.380159 -214.615624) (xy 392.284562 -214.721193) (xy 392.183145 -214.821185) (xy 392.076233 -214.915279)
			(xy 391.964169 -215.003173) (xy 391.847313 -215.084587) (xy 391.726037 -215.15926) (xy 391.600731 -215.226951)
			(xy 391.471796 -215.287445) (xy 391.339645 -215.340548) (xy 391.204702 -215.386089) (xy 391.067398 -215.423923)
			(xy 390.928173 -215.453928) (xy 390.787474 -215.476008) (xy 390.645752 -215.490094) (xy 390.503459 -215.496138)
			(xy 390.361052 -215.494123) (xy 390.218987 -215.484054) (xy 390.07772 -215.465964) (xy 389.937702 -215.439911)
			(xy 389.799383 -215.405978) (xy 389.663204 -215.364273) (xy 389.529604 -215.314932) (xy 389.399008 -215.258111)
			(xy 389.271837 -215.193992) (xy 389.148497 -215.122782) (xy 389.029383 -215.044707) (xy 388.914877 -214.960019)
			(xy 388.805345 -214.868988) (xy 388.701139 -214.771907) (xy 388.602593 -214.669085) (xy 388.510021 -214.560852)
			(xy 388.423721 -214.447556) (xy 388.343969 -214.329559) (xy 388.27102 -214.207239) (xy 388.205108 -214.080988)
			(xy 388.146445 -213.951209) (xy 388.095218 -213.81832) (xy 388.051591 -213.682746) (xy 388.015704 -213.54492)
			(xy 387.987672 -213.405285) (xy 387.967584 -213.264288) (xy 387.955506 -213.12238) (xy 387.951476 -212.980016)
			(xy 331.783436 -212.980016) (xy 331.782932 -213.051212) (xy 331.774877 -213.193376) (xy 331.758791 -213.334857)
			(xy 331.734726 -213.475201) (xy 331.70276 -213.613959) (xy 331.662996 -213.750686) (xy 331.615559 -213.884945)
			(xy 331.560603 -214.016304) (xy 331.498303 -214.144345) (xy 331.428859 -214.268655) (xy 331.352493 -214.388838)
			(xy 331.269451 -214.504507) (xy 331.179997 -214.615293) (xy 331.084419 -214.720841) (xy 330.983022 -214.820813)
			(xy 330.876132 -214.914888) (xy 330.764091 -215.002765) (xy 330.647258 -215.084163) (xy 330.526007 -215.15882)
			(xy 330.400726 -215.226498) (xy 330.271817 -215.28698) (xy 330.139693 -215.340071) (xy 330.004777 -215.385603)
			(xy 329.867501 -215.423429) (xy 329.728304 -215.453429) (xy 329.587634 -215.475505) (xy 329.44594 -215.489587)
			(xy 329.303676 -215.49563) (xy 329.161298 -215.493615) (xy 329.019262 -215.483548) (xy 328.878023 -215.465462)
			(xy 328.738033 -215.439414) (xy 328.599742 -215.405488) (xy 328.463591 -215.363792) (xy 328.330017 -215.31446)
			(xy 328.199448 -215.257651) (xy 328.072302 -215.193545) (xy 327.948987 -215.122349) (xy 327.829897 -215.044291)
			(xy 327.715414 -214.959619) (xy 327.605905 -214.868607) (xy 327.50172 -214.771545) (xy 327.403193 -214.668744)
			(xy 327.31064 -214.560533) (xy 327.224358 -214.44726) (xy 327.144621 -214.329287) (xy 327.071687 -214.206991)
			(xy 327.005789 -214.080765) (xy 326.947138 -213.951013) (xy 326.895921 -213.818151) (xy 326.852303 -213.682604)
			(xy 326.816423 -213.544806) (xy 326.788396 -213.405199) (xy 326.768313 -213.264231) (xy 326.756238 -213.122351)
			(xy 326.752208 -212.980016) (xy 256.30886 -212.980016) (xy 256.30886 -213.806024) (xy 256.308374 -213.833293)
			(xy 256.300612 -213.887277) (xy 256.285247 -213.939607) (xy 256.26259 -213.989217) (xy 256.233104 -214.035098)
			(xy 256.197389 -214.076315) (xy 256.156172 -214.11203) (xy 256.110291 -214.141516) (xy 256.060681 -214.164173)
			(xy 256.008351 -214.179538) (xy 255.954367 -214.1873) (xy 255.899829 -214.1873) (xy 255.845845 -214.179538)
			(xy 255.793515 -214.164173) (xy 255.743905 -214.141516) (xy 255.698024 -214.11203) (xy 255.656807 -214.076315)
			(xy 255.621092 -214.035098) (xy 255.591606 -213.989217) (xy 255.568949 -213.939607) (xy 255.553584 -213.887277)
			(xy 255.545822 -213.833293) (xy 255.545336 -213.806024) (xy 144.90378 -213.806024) (xy 144.875741 -213.885381)
			(xy 144.820774 -214.016768) (xy 144.758461 -214.144834) (xy 144.689003 -214.269169) (xy 144.612622 -214.389376)
			(xy 144.529563 -214.505069) (xy 144.440091 -214.615878) (xy 144.344494 -214.721447) (xy 144.243077 -214.821439)
			(xy 144.136165 -214.915533) (xy 144.024101 -215.003427) (xy 143.907245 -215.084841) (xy 143.785969 -215.159514)
			(xy 143.660663 -215.227205) (xy 143.531728 -215.287699) (xy 143.399577 -215.340802) (xy 143.264634 -215.386343)
			(xy 143.12733 -215.424177) (xy 142.988105 -215.454182) (xy 142.847406 -215.476262) (xy 142.705684 -215.490348)
			(xy 142.563391 -215.496392) (xy 142.420984 -215.494377) (xy 142.278919 -215.484308) (xy 142.137652 -215.466218)
			(xy 141.997634 -215.440165) (xy 141.859315 -215.406232) (xy 141.723136 -215.364527) (xy 141.589536 -215.315186)
			(xy 141.45894 -215.258365) (xy 141.331769 -215.194246) (xy 141.208429 -215.123036) (xy 141.089315 -215.044961)
			(xy 140.974809 -214.960273) (xy 140.865277 -214.869242) (xy 140.761071 -214.772161) (xy 140.662525 -214.669339)
			(xy 140.569953 -214.561106) (xy 140.483653 -214.44781) (xy 140.403901 -214.329813) (xy 140.330952 -214.207493)
			(xy 140.26504 -214.081242) (xy 140.206377 -213.951463) (xy 140.15515 -213.818574) (xy 140.111523 -213.683)
			(xy 140.075636 -213.545174) (xy 140.047604 -213.405539) (xy 140.027516 -213.264542) (xy 140.015438 -213.122634)
			(xy 140.011408 -212.98027) (xy 83.843368 -212.98027) (xy 83.842864 -213.051466) (xy 83.834809 -213.19363)
			(xy 83.818723 -213.335111) (xy 83.794658 -213.475455) (xy 83.762692 -213.614213) (xy 83.722928 -213.75094)
			(xy 83.675491 -213.885199) (xy 83.620535 -214.016558) (xy 83.558235 -214.144599) (xy 83.488791 -214.268909)
			(xy 83.412425 -214.389092) (xy 83.329383 -214.504761) (xy 83.239929 -214.615547) (xy 83.144351 -214.721095)
			(xy 83.042954 -214.821067) (xy 82.936064 -214.915142) (xy 82.837488 -214.992458) (xy 94.106492 -214.992458)
			(xy 94.106492 -214.128858) (xy 94.106978 -214.101607) (xy 94.114734 -214.047659) (xy 94.130089 -213.995364)
			(xy 94.152731 -213.945787) (xy 94.182197 -213.899937) (xy 94.217888 -213.858746) (xy 94.259079 -213.823055)
			(xy 94.304929 -213.793589) (xy 94.354506 -213.770947) (xy 94.406801 -213.755592) (xy 94.460749 -213.747836)
			(xy 94.515251 -213.747836) (xy 94.569199 -213.755592) (xy 94.621494 -213.770947) (xy 94.671071 -213.793589)
			(xy 94.716921 -213.823055) (xy 94.758112 -213.858746) (xy 94.793803 -213.899937) (xy 94.823269 -213.945787)
			(xy 94.845911 -213.995364) (xy 94.861266 -214.047659) (xy 94.869022 -214.101607) (xy 94.869508 -214.128858)
			(xy 94.869508 -214.992458) (xy 94.869022 -215.019709) (xy 94.861266 -215.073657) (xy 94.845911 -215.125952)
			(xy 94.823269 -215.175529) (xy 94.793803 -215.221379) (xy 94.758112 -215.26257) (xy 94.716921 -215.298261)
			(xy 94.671071 -215.327727) (xy 94.621494 -215.350369) (xy 94.569199 -215.365724) (xy 94.515251 -215.37348)
			(xy 94.460749 -215.37348) (xy 94.406801 -215.365724) (xy 94.354506 -215.350369) (xy 94.304929 -215.327727)
			(xy 94.259079 -215.298261) (xy 94.217888 -215.26257) (xy 94.182197 -215.221379) (xy 94.152731 -215.175529)
			(xy 94.130089 -215.125952) (xy 94.114734 -215.073657) (xy 94.106978 -215.019709) (xy 94.106492 -214.992458)
			(xy 82.837488 -214.992458) (xy 82.824023 -215.003019) (xy 82.70719 -215.084417) (xy 82.585939 -215.159074)
			(xy 82.460658 -215.226752) (xy 82.331749 -215.287234) (xy 82.199625 -215.340325) (xy 82.064709 -215.385857)
			(xy 81.927433 -215.423683) (xy 81.788236 -215.453683) (xy 81.647566 -215.475759) (xy 81.505872 -215.489841)
			(xy 81.363608 -215.495884) (xy 81.22123 -215.493869) (xy 81.079194 -215.483802) (xy 80.937955 -215.465716)
			(xy 80.797965 -215.439668) (xy 80.659674 -215.405742) (xy 80.523523 -215.364046) (xy 80.389949 -215.314714)
			(xy 80.25938 -215.257905) (xy 80.132234 -215.193799) (xy 80.008919 -215.122603) (xy 79.889829 -215.044545)
			(xy 79.775346 -214.959873) (xy 79.665837 -214.868861) (xy 79.561652 -214.771799) (xy 79.463125 -214.668998)
			(xy 79.370572 -214.560787) (xy 79.28429 -214.447514) (xy 79.204553 -214.329541) (xy 79.131619 -214.207245)
			(xy 79.065721 -214.081019) (xy 79.00707 -213.951267) (xy 78.955853 -213.818405) (xy 78.912235 -213.682858)
			(xy 78.876355 -213.54506) (xy 78.848328 -213.405453) (xy 78.828245 -213.264485) (xy 78.81617 -213.122605)
			(xy 78.81214 -212.98027) (xy 2.509012 -212.98027) (xy 2.509012 -217.548574) (xy 338.152884 -217.548574)
			(xy 338.152884 -217.494026) (xy 338.160647 -217.440032) (xy 338.176017 -217.387693) (xy 338.198679 -217.338074)
			(xy 338.228172 -217.292186) (xy 338.263897 -217.250963) (xy 338.305125 -217.215244) (xy 338.351016 -217.185756)
			(xy 338.400638 -217.1631) (xy 338.452979 -217.147737) (xy 338.506973 -217.13998) (xy 338.534248 -217.13952)
			(xy 339.550248 -217.13952) (xy 339.577514 -217.140046) (xy 339.63149 -217.147813) (xy 339.683811 -217.163181)
			(xy 339.733413 -217.185839) (xy 339.779286 -217.215325) (xy 339.820495 -217.251039) (xy 339.856204 -217.292253)
			(xy 339.885684 -217.338129) (xy 339.908336 -217.387734) (xy 339.923698 -217.440057) (xy 339.931458 -217.494034)
			(xy 339.931458 -217.548566) (xy 339.923698 -217.602543) (xy 339.908336 -217.654866) (xy 339.885684 -217.704471)
			(xy 339.856204 -217.750347) (xy 339.820495 -217.791561) (xy 339.779286 -217.827275) (xy 339.733413 -217.856761)
			(xy 339.683811 -217.879419) (xy 339.63149 -217.894787) (xy 339.577514 -217.902554) (xy 339.550248 -217.903044)
			(xy 338.534248 -217.903044) (xy 338.506973 -217.90262) (xy 338.452979 -217.894863) (xy 338.400638 -217.8795)
			(xy 338.351016 -217.856844) (xy 338.305125 -217.827356) (xy 338.263897 -217.791637) (xy 338.228172 -217.750414)
			(xy 338.198679 -217.704526) (xy 338.176017 -217.654907) (xy 338.160647 -217.602568) (xy 338.152884 -217.548574)
			(xy 2.509012 -217.548574) (xy 2.509012 -219.820372) (xy 129.049982 -219.820372) (xy 129.049982 -219.765828)
			(xy 129.057745 -219.71184) (xy 129.073111 -219.659505) (xy 129.095769 -219.609891) (xy 129.125257 -219.564005)
			(xy 129.160975 -219.522783) (xy 129.202196 -219.487064) (xy 129.24808 -219.457575) (xy 129.297694 -219.434915)
			(xy 129.350028 -219.419547) (xy 129.404016 -219.411783) (xy 129.431288 -219.411296) (xy 130.447288 -219.411296)
			(xy 130.474557 -219.411843) (xy 130.528539 -219.419602) (xy 130.580867 -219.434966) (xy 130.630476 -219.45762)
			(xy 130.676357 -219.487104) (xy 130.717574 -219.522818) (xy 130.753288 -219.564034) (xy 130.782774 -219.609913)
			(xy 130.80543 -219.659522) (xy 130.820795 -219.711849) (xy 130.828557 -219.765831) (xy 130.828557 -219.820369)
			(xy 130.820795 -219.874351) (xy 130.80543 -219.926678) (xy 130.782774 -219.976287) (xy 130.753288 -220.022166)
			(xy 130.717574 -220.063382) (xy 130.676357 -220.099096) (xy 130.630476 -220.12858) (xy 130.580867 -220.151234)
			(xy 130.528539 -220.166598) (xy 130.474557 -220.174357) (xy 130.447288 -220.17482) (xy 129.431288 -220.17482)
			(xy 129.404016 -220.174417) (xy 129.350028 -220.166653) (xy 129.297694 -220.151285) (xy 129.24808 -220.128625)
			(xy 129.202196 -220.099136) (xy 129.160975 -220.063417) (xy 129.125257 -220.022195) (xy 129.095769 -219.976309)
			(xy 129.073111 -219.926695) (xy 129.057745 -219.87436) (xy 129.049982 -219.820372) (xy 2.509012 -219.820372)
			(xy 2.509012 -258.880356) (xy 67.312036 -258.880356) (xy 67.316066 -258.738021) (xy 67.328141 -258.596141)
			(xy 67.348224 -258.455173) (xy 67.376251 -258.315566) (xy 67.412131 -258.177768) (xy 67.455749 -258.042221)
			(xy 67.506966 -257.909359) (xy 67.565617 -257.779607) (xy 67.631515 -257.653381) (xy 67.704449 -257.531085)
			(xy 67.784186 -257.413112) (xy 67.870468 -257.299839) (xy 67.963021 -257.191628) (xy 68.061548 -257.088827)
			(xy 68.165733 -256.991765) (xy 68.275242 -256.900753) (xy 68.389725 -256.816081) (xy 68.508815 -256.738023)
			(xy 68.63213 -256.666827) (xy 68.759276 -256.602721) (xy 68.889845 -256.545912) (xy 69.023419 -256.49658)
			(xy 69.15957 -256.454884) (xy 69.297861 -256.420958) (xy 69.437851 -256.39491) (xy 69.57909 -256.376824)
			(xy 69.721126 -256.366757) (xy 69.863504 -256.364742) (xy 70.005768 -256.370785) (xy 70.147462 -256.384867)
			(xy 70.288132 -256.406943) (xy 70.427329 -256.436943) (xy 70.564605 -256.474769) (xy 70.699521 -256.520301)
			(xy 70.831645 -256.573392) (xy 70.960554 -256.633874) (xy 71.085835 -256.701552) (xy 71.207086 -256.776209)
			(xy 71.323919 -256.857607) (xy 71.43596 -256.945484) (xy 71.54285 -257.039559) (xy 71.644247 -257.139531)
			(xy 71.739825 -257.245079) (xy 71.829279 -257.355865) (xy 71.912321 -257.471534) (xy 71.988687 -257.591717)
			(xy 72.058131 -257.716027) (xy 72.120431 -257.844068) (xy 72.175387 -257.975427) (xy 72.222824 -258.109686)
			(xy 72.262588 -258.246413) (xy 72.294554 -258.385171) (xy 72.318619 -258.525515) (xy 72.334705 -258.666996)
			(xy 72.34276 -258.80916) (xy 72.343264 -258.880356) (xy 151.51202 -258.880356) (xy 151.51605 -258.738021)
			(xy 151.528125 -258.596141) (xy 151.548208 -258.455173) (xy 151.576235 -258.315566) (xy 151.612115 -258.177768)
			(xy 151.655733 -258.042221) (xy 151.70695 -257.909359) (xy 151.765601 -257.779607) (xy 151.831499 -257.653381)
			(xy 151.904433 -257.531085) (xy 151.98417 -257.413112) (xy 152.070452 -257.299839) (xy 152.163005 -257.191628)
			(xy 152.261532 -257.088827) (xy 152.365717 -256.991765) (xy 152.475226 -256.900753) (xy 152.589709 -256.816081)
			(xy 152.708799 -256.738023) (xy 152.832114 -256.666827) (xy 152.95926 -256.602721) (xy 153.089829 -256.545912)
			(xy 153.223403 -256.49658) (xy 153.359554 -256.454884) (xy 153.497845 -256.420958) (xy 153.637835 -256.39491)
			(xy 153.779074 -256.376824) (xy 153.92111 -256.366757) (xy 154.063488 -256.364742) (xy 154.205752 -256.370785)
			(xy 154.347446 -256.384867) (xy 154.488116 -256.406943) (xy 154.627313 -256.436943) (xy 154.764589 -256.474769)
			(xy 154.899505 -256.520301) (xy 155.031629 -256.573392) (xy 155.160538 -256.633874) (xy 155.285819 -256.701552)
			(xy 155.40707 -256.776209) (xy 155.523903 -256.857607) (xy 155.635944 -256.945484) (xy 155.742834 -257.039559)
			(xy 155.844231 -257.139531) (xy 155.939809 -257.245079) (xy 156.029263 -257.355865) (xy 156.112305 -257.471534)
			(xy 156.188671 -257.591717) (xy 156.258115 -257.716027) (xy 156.320415 -257.844068) (xy 156.375371 -257.975427)
			(xy 156.422808 -258.109686) (xy 156.462572 -258.246413) (xy 156.494538 -258.385171) (xy 156.518603 -258.525515)
			(xy 156.534689 -258.666996) (xy 156.542744 -258.80916) (xy 156.543246 -258.880102) (xy 315.252104 -258.880102)
			(xy 315.256134 -258.737767) (xy 315.268209 -258.595887) (xy 315.288292 -258.454919) (xy 315.316319 -258.315312)
			(xy 315.352199 -258.177514) (xy 315.395817 -258.041967) (xy 315.447034 -257.909105) (xy 315.505685 -257.779353)
			(xy 315.571583 -257.653127) (xy 315.644517 -257.530831) (xy 315.724254 -257.412858) (xy 315.810536 -257.299585)
			(xy 315.903089 -257.191374) (xy 316.001616 -257.088573) (xy 316.105801 -256.991511) (xy 316.21531 -256.900499)
			(xy 316.329793 -256.815827) (xy 316.448883 -256.737769) (xy 316.572198 -256.666573) (xy 316.699344 -256.602467)
			(xy 316.829913 -256.545658) (xy 316.963487 -256.496326) (xy 317.099638 -256.45463) (xy 317.237929 -256.420704)
			(xy 317.377919 -256.394656) (xy 317.519158 -256.37657) (xy 317.661194 -256.366503) (xy 317.803572 -256.364488)
			(xy 317.945836 -256.370531) (xy 318.08753 -256.384613) (xy 318.2282 -256.406689) (xy 318.367397 -256.436689)
			(xy 318.504673 -256.474515) (xy 318.639589 -256.520047) (xy 318.771713 -256.573138) (xy 318.900622 -256.63362)
			(xy 319.025903 -256.701298) (xy 319.147154 -256.775955) (xy 319.263987 -256.857353) (xy 319.376028 -256.94523)
			(xy 319.482918 -257.039305) (xy 319.584315 -257.139277) (xy 319.679893 -257.244825) (xy 319.769347 -257.355611)
			(xy 319.852389 -257.47128) (xy 319.928755 -257.591463) (xy 319.998199 -257.715773) (xy 320.060499 -257.843814)
			(xy 320.115455 -257.975173) (xy 320.162892 -258.109432) (xy 320.202656 -258.246159) (xy 320.234622 -258.384917)
			(xy 320.258687 -258.525261) (xy 320.274773 -258.666742) (xy 320.282828 -258.808906) (xy 320.283332 -258.880102)
			(xy 399.452088 -258.880102) (xy 399.456118 -258.737767) (xy 399.468193 -258.595887) (xy 399.488276 -258.454919)
			(xy 399.516303 -258.315312) (xy 399.552183 -258.177514) (xy 399.595801 -258.041967) (xy 399.647018 -257.909105)
			(xy 399.705669 -257.779353) (xy 399.771567 -257.653127) (xy 399.844501 -257.530831) (xy 399.924238 -257.412858)
			(xy 400.01052 -257.299585) (xy 400.103073 -257.191374) (xy 400.2016 -257.088573) (xy 400.305785 -256.991511)
			(xy 400.415294 -256.900499) (xy 400.529777 -256.815827) (xy 400.648867 -256.737769) (xy 400.772182 -256.666573)
			(xy 400.899328 -256.602467) (xy 401.029897 -256.545658) (xy 401.163471 -256.496326) (xy 401.299622 -256.45463)
			(xy 401.437913 -256.420704) (xy 401.577903 -256.394656) (xy 401.719142 -256.37657) (xy 401.861178 -256.366503)
			(xy 402.003556 -256.364488) (xy 402.14582 -256.370531) (xy 402.287514 -256.384613) (xy 402.428184 -256.406689)
			(xy 402.567381 -256.436689) (xy 402.704657 -256.474515) (xy 402.839573 -256.520047) (xy 402.971697 -256.573138)
			(xy 403.100606 -256.63362) (xy 403.225887 -256.701298) (xy 403.347138 -256.775955) (xy 403.463971 -256.857353)
			(xy 403.576012 -256.94523) (xy 403.682902 -257.039305) (xy 403.784299 -257.139277) (xy 403.879877 -257.244825)
			(xy 403.969331 -257.355611) (xy 404.052373 -257.47128) (xy 404.128739 -257.591463) (xy 404.198183 -257.715773)
			(xy 404.260483 -257.843814) (xy 404.315439 -257.975173) (xy 404.362876 -258.109432) (xy 404.40264 -258.246159)
			(xy 404.434606 -258.384917) (xy 404.458671 -258.525261) (xy 404.474757 -258.666742) (xy 404.482812 -258.808906)
			(xy 404.483316 -258.880102) (xy 404.482812 -258.951298) (xy 404.474757 -259.093462) (xy 404.458671 -259.234943)
			(xy 404.434606 -259.375287) (xy 404.40264 -259.514045) (xy 404.362876 -259.650772) (xy 404.315439 -259.785031)
			(xy 404.260483 -259.91639) (xy 404.198183 -260.044431) (xy 404.128739 -260.168741) (xy 404.052373 -260.288924)
			(xy 403.969331 -260.404593) (xy 403.879877 -260.515379) (xy 403.784299 -260.620927) (xy 403.682902 -260.720899)
			(xy 403.576012 -260.814974) (xy 403.463971 -260.902851) (xy 403.347138 -260.984249) (xy 403.225887 -261.058906)
			(xy 403.100606 -261.126584) (xy 402.971697 -261.187066) (xy 402.839573 -261.240157) (xy 402.704657 -261.285689)
			(xy 402.567381 -261.323515) (xy 402.428184 -261.353515) (xy 402.287514 -261.375591) (xy 402.14582 -261.389673)
			(xy 402.003556 -261.395716) (xy 401.861178 -261.393701) (xy 401.719142 -261.383634) (xy 401.577903 -261.365548)
			(xy 401.437913 -261.3395) (xy 401.299622 -261.305574) (xy 401.163471 -261.263878) (xy 401.029897 -261.214546)
			(xy 400.899328 -261.157737) (xy 400.772182 -261.093631) (xy 400.648867 -261.022435) (xy 400.529777 -260.944377)
			(xy 400.415294 -260.859705) (xy 400.305785 -260.768693) (xy 400.2016 -260.671631) (xy 400.103073 -260.56883)
			(xy 400.01052 -260.460619) (xy 399.924238 -260.347346) (xy 399.844501 -260.229373) (xy 399.771567 -260.107077)
			(xy 399.705669 -259.980851) (xy 399.647018 -259.851099) (xy 399.595801 -259.718237) (xy 399.552183 -259.58269)
			(xy 399.516303 -259.444892) (xy 399.488276 -259.305285) (xy 399.468193 -259.164317) (xy 399.456118 -259.022437)
			(xy 399.452088 -258.880102) (xy 320.283332 -258.880102) (xy 320.282828 -258.951298) (xy 320.274773 -259.093462)
			(xy 320.258687 -259.234943) (xy 320.234622 -259.375287) (xy 320.202656 -259.514045) (xy 320.162892 -259.650772)
			(xy 320.115455 -259.785031) (xy 320.060499 -259.91639) (xy 319.998199 -260.044431) (xy 319.928755 -260.168741)
			(xy 319.852389 -260.288924) (xy 319.769347 -260.404593) (xy 319.679893 -260.515379) (xy 319.584315 -260.620927)
			(xy 319.482918 -260.720899) (xy 319.376028 -260.814974) (xy 319.263987 -260.902851) (xy 319.147154 -260.984249)
			(xy 319.025903 -261.058906) (xy 318.900622 -261.126584) (xy 318.771713 -261.187066) (xy 318.639589 -261.240157)
			(xy 318.504673 -261.285689) (xy 318.367397 -261.323515) (xy 318.2282 -261.353515) (xy 318.08753 -261.375591)
			(xy 317.945836 -261.389673) (xy 317.803572 -261.395716) (xy 317.661194 -261.393701) (xy 317.519158 -261.383634)
			(xy 317.377919 -261.365548) (xy 317.237929 -261.3395) (xy 317.099638 -261.305574) (xy 316.963487 -261.263878)
			(xy 316.829913 -261.214546) (xy 316.699344 -261.157737) (xy 316.572198 -261.093631) (xy 316.448883 -261.022435)
			(xy 316.329793 -260.944377) (xy 316.21531 -260.859705) (xy 316.105801 -260.768693) (xy 316.001616 -260.671631)
			(xy 315.903089 -260.56883) (xy 315.810536 -260.460619) (xy 315.724254 -260.347346) (xy 315.644517 -260.229373)
			(xy 315.571583 -260.107077) (xy 315.505685 -259.980851) (xy 315.447034 -259.851099) (xy 315.395817 -259.718237)
			(xy 315.352199 -259.58269) (xy 315.316319 -259.444892) (xy 315.288292 -259.305285) (xy 315.268209 -259.164317)
			(xy 315.256134 -259.022437) (xy 315.252104 -258.880102) (xy 156.543246 -258.880102) (xy 156.543248 -258.880356)
			(xy 156.542744 -258.951552) (xy 156.534689 -259.093716) (xy 156.518603 -259.235197) (xy 156.494538 -259.375541)
			(xy 156.462572 -259.514299) (xy 156.422808 -259.651026) (xy 156.375371 -259.785285) (xy 156.320415 -259.916644)
			(xy 156.258115 -260.044685) (xy 156.188671 -260.168995) (xy 156.112305 -260.289178) (xy 156.029263 -260.404847)
			(xy 155.939809 -260.515633) (xy 155.844231 -260.621181) (xy 155.742834 -260.721153) (xy 155.635944 -260.815228)
			(xy 155.523903 -260.903105) (xy 155.40707 -260.984503) (xy 155.285819 -261.05916) (xy 155.160538 -261.126838)
			(xy 155.031629 -261.18732) (xy 154.899505 -261.240411) (xy 154.764589 -261.285943) (xy 154.627313 -261.323769)
			(xy 154.488116 -261.353769) (xy 154.347446 -261.375845) (xy 154.205752 -261.389927) (xy 154.063488 -261.39597)
			(xy 153.92111 -261.393955) (xy 153.779074 -261.383888) (xy 153.637835 -261.365802) (xy 153.497845 -261.339754)
			(xy 153.359554 -261.305828) (xy 153.223403 -261.264132) (xy 153.089829 -261.2148) (xy 152.95926 -261.157991)
			(xy 152.832114 -261.093885) (xy 152.708799 -261.022689) (xy 152.589709 -260.944631) (xy 152.475226 -260.859959)
			(xy 152.365717 -260.768947) (xy 152.261532 -260.671885) (xy 152.163005 -260.569084) (xy 152.070452 -260.460873)
			(xy 151.98417 -260.3476) (xy 151.904433 -260.229627) (xy 151.831499 -260.107331) (xy 151.765601 -259.981105)
			(xy 151.70695 -259.851353) (xy 151.655733 -259.718491) (xy 151.612115 -259.582944) (xy 151.576235 -259.445146)
			(xy 151.548208 -259.305539) (xy 151.528125 -259.164571) (xy 151.51605 -259.022691) (xy 151.51202 -258.880356)
			(xy 72.343264 -258.880356) (xy 72.34276 -258.951552) (xy 72.334705 -259.093716) (xy 72.318619 -259.235197)
			(xy 72.294554 -259.375541) (xy 72.262588 -259.514299) (xy 72.222824 -259.651026) (xy 72.175387 -259.785285)
			(xy 72.120431 -259.916644) (xy 72.058131 -260.044685) (xy 71.988687 -260.168995) (xy 71.912321 -260.289178)
			(xy 71.829279 -260.404847) (xy 71.739825 -260.515633) (xy 71.644247 -260.621181) (xy 71.54285 -260.721153)
			(xy 71.43596 -260.815228) (xy 71.323919 -260.903105) (xy 71.207086 -260.984503) (xy 71.085835 -261.05916)
			(xy 70.960554 -261.126838) (xy 70.831645 -261.18732) (xy 70.699521 -261.240411) (xy 70.564605 -261.285943)
			(xy 70.427329 -261.323769) (xy 70.288132 -261.353769) (xy 70.147462 -261.375845) (xy 70.005768 -261.389927)
			(xy 69.863504 -261.39597) (xy 69.721126 -261.393955) (xy 69.57909 -261.383888) (xy 69.437851 -261.365802)
			(xy 69.297861 -261.339754) (xy 69.15957 -261.305828) (xy 69.023419 -261.264132) (xy 68.889845 -261.2148)
			(xy 68.759276 -261.157991) (xy 68.63213 -261.093885) (xy 68.508815 -261.022689) (xy 68.389725 -260.944631)
			(xy 68.275242 -260.859959) (xy 68.165733 -260.768947) (xy 68.061548 -260.671885) (xy 67.963021 -260.569084)
			(xy 67.870468 -260.460873) (xy 67.784186 -260.3476) (xy 67.704449 -260.229627) (xy 67.631515 -260.107331)
			(xy 67.565617 -259.981105) (xy 67.506966 -259.851353) (xy 67.455749 -259.718491) (xy 67.412131 -259.582944)
			(xy 67.376251 -259.445146) (xy 67.348224 -259.305539) (xy 67.328141 -259.164571) (xy 67.316066 -259.022691)
			(xy 67.312036 -258.880356) (xy 2.509012 -258.880356) (xy 2.509012 -269.226284) (xy 108.485698 -269.226284)
			(xy 108.489652 -269.177311) (xy 108.50141 -269.129607) (xy 108.520668 -269.084406) (xy 108.546927 -269.04288)
			(xy 108.579508 -269.006104) (xy 108.617566 -268.97503) (xy 108.660116 -268.950464) (xy 108.706055 -268.933042)
			(xy 108.754195 -268.923214) (xy 108.803287 -268.921236) (xy 108.852061 -268.927158) (xy 108.899253 -268.940827)
			(xy 108.943642 -268.96189) (xy 108.984077 -268.9898) (xy 109.019511 -269.023835) (xy 109.049027 -269.063114)
			(xy 109.07186 -269.106618) (xy 109.087419 -269.153222) (xy 109.0953 -269.201718) (xy 109.095794 -269.226284)
			(xy 109.425752 -269.226284) (xy 109.429706 -269.177311) (xy 109.441464 -269.129607) (xy 109.460722 -269.084406)
			(xy 109.486981 -269.04288) (xy 109.519562 -269.006104) (xy 109.55762 -268.97503) (xy 109.60017 -268.950464)
			(xy 109.646109 -268.933042) (xy 109.694249 -268.923214) (xy 109.743341 -268.921236) (xy 109.792115 -268.927158)
			(xy 109.839307 -268.940827) (xy 109.883696 -268.96189) (xy 109.924131 -268.9898) (xy 109.959565 -269.023835)
			(xy 109.989081 -269.063114) (xy 110.011914 -269.106618) (xy 110.027473 -269.153222) (xy 110.035354 -269.201718)
			(xy 110.035848 -269.226284) (xy 114.119418 -269.226284) (xy 114.123372 -269.177311) (xy 114.13513 -269.129607)
			(xy 114.154388 -269.084406) (xy 114.180647 -269.04288) (xy 114.213228 -269.006104) (xy 114.251286 -268.97503)
			(xy 114.293836 -268.950464) (xy 114.339775 -268.933042) (xy 114.387915 -268.923214) (xy 114.437007 -268.921236)
			(xy 114.485781 -268.927158) (xy 114.532973 -268.940827) (xy 114.577362 -268.96189) (xy 114.617797 -268.9898)
			(xy 114.653231 -269.023835) (xy 114.682747 -269.063114) (xy 114.70558 -269.106618) (xy 114.721139 -269.153222)
			(xy 114.72902 -269.201718) (xy 114.729514 -269.226284) (xy 115.059472 -269.226284) (xy 115.063426 -269.177311)
			(xy 115.075184 -269.129607) (xy 115.094442 -269.084406) (xy 115.120701 -269.04288) (xy 115.153282 -269.006104)
			(xy 115.19134 -268.97503) (xy 115.23389 -268.950464) (xy 115.279829 -268.933042) (xy 115.327969 -268.923214)
			(xy 115.377061 -268.921236) (xy 115.425835 -268.927158) (xy 115.473027 -268.940827) (xy 115.517416 -268.96189)
			(xy 115.557851 -268.9898) (xy 115.593285 -269.023835) (xy 115.622801 -269.063114) (xy 115.645634 -269.106618)
			(xy 115.661193 -269.153222) (xy 115.669074 -269.201718) (xy 115.669563 -269.22603) (xy 356.425766 -269.22603)
			(xy 356.42972 -269.177057) (xy 356.441478 -269.129353) (xy 356.460736 -269.084152) (xy 356.486995 -269.042626)
			(xy 356.519576 -269.00585) (xy 356.557634 -268.974776) (xy 356.600184 -268.95021) (xy 356.646123 -268.932788)
			(xy 356.694263 -268.92296) (xy 356.743355 -268.920982) (xy 356.792129 -268.926904) (xy 356.839321 -268.940573)
			(xy 356.88371 -268.961636) (xy 356.924145 -268.989546) (xy 356.959579 -269.023581) (xy 356.989095 -269.06286)
			(xy 357.011928 -269.106364) (xy 357.027487 -269.152968) (xy 357.035368 -269.201464) (xy 357.035862 -269.22603)
			(xy 357.36582 -269.22603) (xy 357.369774 -269.177057) (xy 357.381532 -269.129353) (xy 357.40079 -269.084152)
			(xy 357.427049 -269.042626) (xy 357.45963 -269.00585) (xy 357.497688 -268.974776) (xy 357.540238 -268.95021)
			(xy 357.586177 -268.932788) (xy 357.634317 -268.92296) (xy 357.683409 -268.920982) (xy 357.732183 -268.926904)
			(xy 357.779375 -268.940573) (xy 357.823764 -268.961636) (xy 357.864199 -268.989546) (xy 357.899633 -269.023581)
			(xy 357.929149 -269.06286) (xy 357.951982 -269.106364) (xy 357.967541 -269.152968) (xy 357.975422 -269.201464)
			(xy 357.975916 -269.22603) (xy 362.059486 -269.22603) (xy 362.06344 -269.177057) (xy 362.075198 -269.129353)
			(xy 362.094456 -269.084152) (xy 362.120715 -269.042626) (xy 362.153296 -269.00585) (xy 362.191354 -268.974776)
			(xy 362.233904 -268.95021) (xy 362.279843 -268.932788) (xy 362.327983 -268.92296) (xy 362.377075 -268.920982)
			(xy 362.425849 -268.926904) (xy 362.473041 -268.940573) (xy 362.51743 -268.961636) (xy 362.557865 -268.989546)
			(xy 362.593299 -269.023581) (xy 362.622815 -269.06286) (xy 362.645648 -269.106364) (xy 362.661207 -269.152968)
			(xy 362.669088 -269.201464) (xy 362.669582 -269.22603) (xy 362.99954 -269.22603) (xy 363.003494 -269.177057)
			(xy 363.015252 -269.129353) (xy 363.03451 -269.084152) (xy 363.060769 -269.042626) (xy 363.09335 -269.00585)
			(xy 363.131408 -268.974776) (xy 363.173958 -268.95021) (xy 363.219897 -268.932788) (xy 363.268037 -268.92296)
			(xy 363.317129 -268.920982) (xy 363.365903 -268.926904) (xy 363.413095 -268.940573) (xy 363.457484 -268.961636)
			(xy 363.497919 -268.989546) (xy 363.533353 -269.023581) (xy 363.562869 -269.06286) (xy 363.585702 -269.106364)
			(xy 363.601261 -269.152968) (xy 363.609142 -269.201464) (xy 363.609636 -269.22603) (xy 363.609142 -269.250596)
			(xy 363.601261 -269.299092) (xy 363.585702 -269.345696) (xy 363.562869 -269.3892) (xy 363.533353 -269.428479)
			(xy 363.497919 -269.462514) (xy 363.457484 -269.490424) (xy 363.413095 -269.511487) (xy 363.365903 -269.525156)
			(xy 363.317129 -269.531078) (xy 363.268037 -269.5291) (xy 363.219897 -269.519272) (xy 363.173958 -269.50185)
			(xy 363.131408 -269.477284) (xy 363.09335 -269.44621) (xy 363.060769 -269.409434) (xy 363.03451 -269.367908)
			(xy 363.015252 -269.322707) (xy 363.003494 -269.275003) (xy 362.99954 -269.22603) (xy 362.669582 -269.22603)
			(xy 362.669088 -269.250596) (xy 362.661207 -269.299092) (xy 362.645648 -269.345696) (xy 362.622815 -269.3892)
			(xy 362.593299 -269.428479) (xy 362.557865 -269.462514) (xy 362.51743 -269.490424) (xy 362.473041 -269.511487)
			(xy 362.425849 -269.525156) (xy 362.377075 -269.531078) (xy 362.327983 -269.5291) (xy 362.279843 -269.519272)
			(xy 362.233904 -269.50185) (xy 362.191354 -269.477284) (xy 362.153296 -269.44621) (xy 362.120715 -269.409434)
			(xy 362.094456 -269.367908) (xy 362.075198 -269.322707) (xy 362.06344 -269.275003) (xy 362.059486 -269.22603)
			(xy 357.975916 -269.22603) (xy 357.975422 -269.250596) (xy 357.967541 -269.299092) (xy 357.951982 -269.345696)
			(xy 357.929149 -269.3892) (xy 357.899633 -269.428479) (xy 357.864199 -269.462514) (xy 357.823764 -269.490424)
			(xy 357.779375 -269.511487) (xy 357.732183 -269.525156) (xy 357.683409 -269.531078) (xy 357.634317 -269.5291)
			(xy 357.586177 -269.519272) (xy 357.540238 -269.50185) (xy 357.497688 -269.477284) (xy 357.45963 -269.44621)
			(xy 357.427049 -269.409434) (xy 357.40079 -269.367908) (xy 357.381532 -269.322707) (xy 357.369774 -269.275003)
			(xy 357.36582 -269.22603) (xy 357.035862 -269.22603) (xy 357.035368 -269.250596) (xy 357.027487 -269.299092)
			(xy 357.011928 -269.345696) (xy 356.989095 -269.3892) (xy 356.959579 -269.428479) (xy 356.924145 -269.462514)
			(xy 356.88371 -269.490424) (xy 356.839321 -269.511487) (xy 356.792129 -269.525156) (xy 356.743355 -269.531078)
			(xy 356.694263 -269.5291) (xy 356.646123 -269.519272) (xy 356.600184 -269.50185) (xy 356.557634 -269.477284)
			(xy 356.519576 -269.44621) (xy 356.486995 -269.409434) (xy 356.460736 -269.367908) (xy 356.441478 -269.322707)
			(xy 356.42972 -269.275003) (xy 356.425766 -269.22603) (xy 115.669563 -269.22603) (xy 115.669568 -269.226284)
			(xy 115.669074 -269.25085) (xy 115.661193 -269.299346) (xy 115.645634 -269.34595) (xy 115.622801 -269.389454)
			(xy 115.593285 -269.428733) (xy 115.557851 -269.462768) (xy 115.517416 -269.490678) (xy 115.473027 -269.511741)
			(xy 115.425835 -269.52541) (xy 115.377061 -269.531332) (xy 115.327969 -269.529354) (xy 115.279829 -269.519526)
			(xy 115.23389 -269.502104) (xy 115.19134 -269.477538) (xy 115.153282 -269.446464) (xy 115.120701 -269.409688)
			(xy 115.094442 -269.368162) (xy 115.075184 -269.322961) (xy 115.063426 -269.275257) (xy 115.059472 -269.226284)
			(xy 114.729514 -269.226284) (xy 114.72902 -269.25085) (xy 114.721139 -269.299346) (xy 114.70558 -269.34595)
			(xy 114.682747 -269.389454) (xy 114.653231 -269.428733) (xy 114.617797 -269.462768) (xy 114.577362 -269.490678)
			(xy 114.532973 -269.511741) (xy 114.485781 -269.52541) (xy 114.437007 -269.531332) (xy 114.387915 -269.529354)
			(xy 114.339775 -269.519526) (xy 114.293836 -269.502104) (xy 114.251286 -269.477538) (xy 114.213228 -269.446464)
			(xy 114.180647 -269.409688) (xy 114.154388 -269.368162) (xy 114.13513 -269.322961) (xy 114.123372 -269.275257)
			(xy 114.119418 -269.226284) (xy 110.035848 -269.226284) (xy 110.035354 -269.25085) (xy 110.027473 -269.299346)
			(xy 110.011914 -269.34595) (xy 109.989081 -269.389454) (xy 109.959565 -269.428733) (xy 109.924131 -269.462768)
			(xy 109.883696 -269.490678) (xy 109.839307 -269.511741) (xy 109.792115 -269.52541) (xy 109.743341 -269.531332)
			(xy 109.694249 -269.529354) (xy 109.646109 -269.519526) (xy 109.60017 -269.502104) (xy 109.55762 -269.477538)
			(xy 109.519562 -269.446464) (xy 109.486981 -269.409688) (xy 109.460722 -269.368162) (xy 109.441464 -269.322961)
			(xy 109.429706 -269.275257) (xy 109.425752 -269.226284) (xy 109.095794 -269.226284) (xy 109.0953 -269.25085)
			(xy 109.087419 -269.299346) (xy 109.07186 -269.34595) (xy 109.049027 -269.389454) (xy 109.019511 -269.428733)
			(xy 108.984077 -269.462768) (xy 108.943642 -269.490678) (xy 108.899253 -269.511741) (xy 108.852061 -269.52541)
			(xy 108.803287 -269.531332) (xy 108.754195 -269.529354) (xy 108.706055 -269.519526) (xy 108.660116 -269.502104)
			(xy 108.617566 -269.477538) (xy 108.579508 -269.446464) (xy 108.546927 -269.409688) (xy 108.520668 -269.368162)
			(xy 108.50141 -269.322961) (xy 108.489652 -269.275257) (xy 108.485698 -269.226284) (xy 2.509012 -269.226284)
			(xy 2.509012 -270.03629) (xy 97.675712 -270.03629) (xy 97.679666 -269.987317) (xy 97.691424 -269.939613)
			(xy 97.710682 -269.894412) (xy 97.736941 -269.852886) (xy 97.769522 -269.81611) (xy 97.80758 -269.785036)
			(xy 97.85013 -269.76047) (xy 97.896069 -269.743048) (xy 97.944209 -269.73322) (xy 97.993301 -269.731242)
			(xy 98.042075 -269.737164) (xy 98.089267 -269.750833) (xy 98.133656 -269.771896) (xy 98.174091 -269.799806)
			(xy 98.209525 -269.833841) (xy 98.239041 -269.87312) (xy 98.261874 -269.916624) (xy 98.277433 -269.963228)
			(xy 98.285314 -270.011724) (xy 98.285808 -270.03629) (xy 98.615766 -270.03629) (xy 98.61972 -269.987317)
			(xy 98.631478 -269.939613) (xy 98.650736 -269.894412) (xy 98.676995 -269.852886) (xy 98.709576 -269.81611)
			(xy 98.747634 -269.785036) (xy 98.790184 -269.76047) (xy 98.836123 -269.743048) (xy 98.884263 -269.73322)
			(xy 98.933355 -269.731242) (xy 98.982129 -269.737164) (xy 99.029321 -269.750833) (xy 99.07371 -269.771896)
			(xy 99.114145 -269.799806) (xy 99.149579 -269.833841) (xy 99.179095 -269.87312) (xy 99.201928 -269.916624)
			(xy 99.217487 -269.963228) (xy 99.225368 -270.011724) (xy 99.225862 -270.03629) (xy 100.49562 -270.03629)
			(xy 100.499574 -269.987317) (xy 100.511332 -269.939613) (xy 100.53059 -269.894412) (xy 100.556849 -269.852886)
			(xy 100.58943 -269.81611) (xy 100.627488 -269.785036) (xy 100.670038 -269.76047) (xy 100.715977 -269.743048)
			(xy 100.764117 -269.73322) (xy 100.813209 -269.731242) (xy 100.861983 -269.737164) (xy 100.909175 -269.750833)
			(xy 100.953564 -269.771896) (xy 100.993999 -269.799806) (xy 101.029433 -269.833841) (xy 101.058949 -269.87312)
			(xy 101.081782 -269.916624) (xy 101.097341 -269.963228) (xy 101.105222 -270.011724) (xy 101.105716 -270.03629)
			(xy 101.435674 -270.03629) (xy 101.439628 -269.987317) (xy 101.451386 -269.939613) (xy 101.470644 -269.894412)
			(xy 101.496903 -269.852886) (xy 101.529484 -269.81611) (xy 101.567542 -269.785036) (xy 101.610092 -269.76047)
			(xy 101.656031 -269.743048) (xy 101.704171 -269.73322) (xy 101.753263 -269.731242) (xy 101.802037 -269.737164)
			(xy 101.849229 -269.750833) (xy 101.893618 -269.771896) (xy 101.934053 -269.799806) (xy 101.969487 -269.833841)
			(xy 101.999003 -269.87312) (xy 102.021836 -269.916624) (xy 102.037395 -269.963228) (xy 102.045276 -270.011724)
			(xy 102.04577 -270.03629) (xy 103.315782 -270.03629) (xy 103.319736 -269.987317) (xy 103.331494 -269.939613)
			(xy 103.350752 -269.894412) (xy 103.377011 -269.852886) (xy 103.409592 -269.81611) (xy 103.44765 -269.785036)
			(xy 103.4902 -269.76047) (xy 103.536139 -269.743048) (xy 103.584279 -269.73322) (xy 103.633371 -269.731242)
			(xy 103.682145 -269.737164) (xy 103.729337 -269.750833) (xy 103.773726 -269.771896) (xy 103.814161 -269.799806)
			(xy 103.849595 -269.833841) (xy 103.879111 -269.87312) (xy 103.901944 -269.916624) (xy 103.917503 -269.963228)
			(xy 103.925384 -270.011724) (xy 103.925878 -270.03629) (xy 104.255836 -270.03629) (xy 104.25979 -269.987317)
			(xy 104.271548 -269.939613) (xy 104.290806 -269.894412) (xy 104.317065 -269.852886) (xy 104.349646 -269.81611)
			(xy 104.387704 -269.785036) (xy 104.430254 -269.76047) (xy 104.476193 -269.743048) (xy 104.524333 -269.73322)
			(xy 104.573425 -269.731242) (xy 104.622199 -269.737164) (xy 104.669391 -269.750833) (xy 104.71378 -269.771896)
			(xy 104.754215 -269.799806) (xy 104.789649 -269.833841) (xy 104.819165 -269.87312) (xy 104.841998 -269.916624)
			(xy 104.857557 -269.963228) (xy 104.865438 -270.011724) (xy 104.865932 -270.03629) (xy 106.13569 -270.03629)
			(xy 106.139644 -269.987317) (xy 106.151402 -269.939613) (xy 106.17066 -269.894412) (xy 106.196919 -269.852886)
			(xy 106.2295 -269.81611) (xy 106.267558 -269.785036) (xy 106.310108 -269.76047) (xy 106.356047 -269.743048)
			(xy 106.404187 -269.73322) (xy 106.453279 -269.731242) (xy 106.502053 -269.737164) (xy 106.549245 -269.750833)
			(xy 106.593634 -269.771896) (xy 106.634069 -269.799806) (xy 106.669503 -269.833841) (xy 106.699019 -269.87312)
			(xy 106.721852 -269.916624) (xy 106.737411 -269.963228) (xy 106.745292 -270.011724) (xy 106.745786 -270.03629)
			(xy 107.075744 -270.03629) (xy 107.079698 -269.987317) (xy 107.091456 -269.939613) (xy 107.110714 -269.894412)
			(xy 107.136973 -269.852886) (xy 107.169554 -269.81611) (xy 107.207612 -269.785036) (xy 107.250162 -269.76047)
			(xy 107.296101 -269.743048) (xy 107.344241 -269.73322) (xy 107.393333 -269.731242) (xy 107.442107 -269.737164)
			(xy 107.489299 -269.750833) (xy 107.533688 -269.771896) (xy 107.574123 -269.799806) (xy 107.609557 -269.833841)
			(xy 107.639073 -269.87312) (xy 107.661906 -269.916624) (xy 107.677465 -269.963228) (xy 107.685346 -270.011724)
			(xy 107.68584 -270.03629) (xy 116.469426 -270.03629) (xy 116.47338 -269.987317) (xy 116.485138 -269.939613)
			(xy 116.504396 -269.894412) (xy 116.530655 -269.852886) (xy 116.563236 -269.81611) (xy 116.601294 -269.785036)
			(xy 116.643844 -269.76047) (xy 116.689783 -269.743048) (xy 116.737923 -269.73322) (xy 116.787015 -269.731242)
			(xy 116.835789 -269.737164) (xy 116.882981 -269.750833) (xy 116.92737 -269.771896) (xy 116.967805 -269.799806)
			(xy 117.003239 -269.833841) (xy 117.032755 -269.87312) (xy 117.055588 -269.916624) (xy 117.071147 -269.963228)
			(xy 117.079028 -270.011724) (xy 117.079522 -270.03629) (xy 117.40948 -270.03629) (xy 117.413434 -269.987317)
			(xy 117.425192 -269.939613) (xy 117.44445 -269.894412) (xy 117.470709 -269.852886) (xy 117.50329 -269.81611)
			(xy 117.541348 -269.785036) (xy 117.583898 -269.76047) (xy 117.629837 -269.743048) (xy 117.677977 -269.73322)
			(xy 117.727069 -269.731242) (xy 117.775843 -269.737164) (xy 117.823035 -269.750833) (xy 117.867424 -269.771896)
			(xy 117.907859 -269.799806) (xy 117.943293 -269.833841) (xy 117.972809 -269.87312) (xy 117.995642 -269.916624)
			(xy 118.011201 -269.963228) (xy 118.019082 -270.011724) (xy 118.019576 -270.03629) (xy 119.289334 -270.03629)
			(xy 119.293288 -269.987317) (xy 119.305046 -269.939613) (xy 119.324304 -269.894412) (xy 119.350563 -269.852886)
			(xy 119.383144 -269.81611) (xy 119.421202 -269.785036) (xy 119.463752 -269.76047) (xy 119.509691 -269.743048)
			(xy 119.557831 -269.73322) (xy 119.606923 -269.731242) (xy 119.655697 -269.737164) (xy 119.702889 -269.750833)
			(xy 119.747278 -269.771896) (xy 119.787713 -269.799806) (xy 119.823147 -269.833841) (xy 119.852663 -269.87312)
			(xy 119.875496 -269.916624) (xy 119.891055 -269.963228) (xy 119.898936 -270.011724) (xy 119.89943 -270.03629)
			(xy 120.229388 -270.03629) (xy 120.233342 -269.987317) (xy 120.2451 -269.939613) (xy 120.264358 -269.894412)
			(xy 120.290617 -269.852886) (xy 120.323198 -269.81611) (xy 120.361256 -269.785036) (xy 120.403806 -269.76047)
			(xy 120.449745 -269.743048) (xy 120.497885 -269.73322) (xy 120.546977 -269.731242) (xy 120.595751 -269.737164)
			(xy 120.642943 -269.750833) (xy 120.687332 -269.771896) (xy 120.727767 -269.799806) (xy 120.763201 -269.833841)
			(xy 120.792717 -269.87312) (xy 120.81555 -269.916624) (xy 120.831109 -269.963228) (xy 120.83899 -270.011724)
			(xy 120.839484 -270.03629) (xy 122.109496 -270.03629) (xy 122.11345 -269.987317) (xy 122.125208 -269.939613)
			(xy 122.144466 -269.894412) (xy 122.170725 -269.852886) (xy 122.203306 -269.81611) (xy 122.241364 -269.785036)
			(xy 122.283914 -269.76047) (xy 122.329853 -269.743048) (xy 122.377993 -269.73322) (xy 122.427085 -269.731242)
			(xy 122.475859 -269.737164) (xy 122.523051 -269.750833) (xy 122.56744 -269.771896) (xy 122.607875 -269.799806)
			(xy 122.643309 -269.833841) (xy 122.672825 -269.87312) (xy 122.695658 -269.916624) (xy 122.711217 -269.963228)
			(xy 122.719098 -270.011724) (xy 122.719592 -270.03629) (xy 123.04955 -270.03629) (xy 123.053504 -269.987317)
			(xy 123.065262 -269.939613) (xy 123.08452 -269.894412) (xy 123.110779 -269.852886) (xy 123.14336 -269.81611)
			(xy 123.181418 -269.785036) (xy 123.223968 -269.76047) (xy 123.269907 -269.743048) (xy 123.318047 -269.73322)
			(xy 123.367139 -269.731242) (xy 123.415913 -269.737164) (xy 123.463105 -269.750833) (xy 123.507494 -269.771896)
			(xy 123.547929 -269.799806) (xy 123.583363 -269.833841) (xy 123.612879 -269.87312) (xy 123.635712 -269.916624)
			(xy 123.651271 -269.963228) (xy 123.659152 -270.011724) (xy 123.659646 -270.03629) (xy 124.929404 -270.03629)
			(xy 124.933358 -269.987317) (xy 124.945116 -269.939613) (xy 124.964374 -269.894412) (xy 124.990633 -269.852886)
			(xy 125.023214 -269.81611) (xy 125.061272 -269.785036) (xy 125.103822 -269.76047) (xy 125.149761 -269.743048)
			(xy 125.197901 -269.73322) (xy 125.246993 -269.731242) (xy 125.295767 -269.737164) (xy 125.342959 -269.750833)
			(xy 125.387348 -269.771896) (xy 125.427783 -269.799806) (xy 125.463217 -269.833841) (xy 125.492733 -269.87312)
			(xy 125.515566 -269.916624) (xy 125.531125 -269.963228) (xy 125.539006 -270.011724) (xy 125.5395 -270.03629)
			(xy 125.869458 -270.03629) (xy 125.873412 -269.987317) (xy 125.88517 -269.939613) (xy 125.904428 -269.894412)
			(xy 125.930687 -269.852886) (xy 125.963268 -269.81611) (xy 126.001326 -269.785036) (xy 126.043876 -269.76047)
			(xy 126.089815 -269.743048) (xy 126.137955 -269.73322) (xy 126.187047 -269.731242) (xy 126.235821 -269.737164)
			(xy 126.283013 -269.750833) (xy 126.327402 -269.771896) (xy 126.367837 -269.799806) (xy 126.403271 -269.833841)
			(xy 126.432787 -269.87312) (xy 126.45562 -269.916624) (xy 126.471179 -269.963228) (xy 126.47906 -270.011724)
			(xy 126.479549 -270.036036) (xy 345.61578 -270.036036) (xy 345.619734 -269.987063) (xy 345.631492 -269.939359)
			(xy 345.65075 -269.894158) (xy 345.677009 -269.852632) (xy 345.70959 -269.815856) (xy 345.747648 -269.784782)
			(xy 345.790198 -269.760216) (xy 345.836137 -269.742794) (xy 345.884277 -269.732966) (xy 345.933369 -269.730988)
			(xy 345.982143 -269.73691) (xy 346.029335 -269.750579) (xy 346.073724 -269.771642) (xy 346.114159 -269.799552)
			(xy 346.149593 -269.833587) (xy 346.179109 -269.872866) (xy 346.201942 -269.91637) (xy 346.217501 -269.962974)
			(xy 346.225382 -270.01147) (xy 346.225876 -270.036036) (xy 346.555834 -270.036036) (xy 346.559788 -269.987063)
			(xy 346.571546 -269.939359) (xy 346.590804 -269.894158) (xy 346.617063 -269.852632) (xy 346.649644 -269.815856)
			(xy 346.687702 -269.784782) (xy 346.730252 -269.760216) (xy 346.776191 -269.742794) (xy 346.824331 -269.732966)
			(xy 346.873423 -269.730988) (xy 346.922197 -269.73691) (xy 346.969389 -269.750579) (xy 347.013778 -269.771642)
			(xy 347.054213 -269.799552) (xy 347.089647 -269.833587) (xy 347.119163 -269.872866) (xy 347.141996 -269.91637)
			(xy 347.157555 -269.962974) (xy 347.165436 -270.01147) (xy 347.16593 -270.036036) (xy 348.435688 -270.036036)
			(xy 348.439642 -269.987063) (xy 348.4514 -269.939359) (xy 348.470658 -269.894158) (xy 348.496917 -269.852632)
			(xy 348.529498 -269.815856) (xy 348.567556 -269.784782) (xy 348.610106 -269.760216) (xy 348.656045 -269.742794)
			(xy 348.704185 -269.732966) (xy 348.753277 -269.730988) (xy 348.802051 -269.73691) (xy 348.849243 -269.750579)
			(xy 348.893632 -269.771642) (xy 348.934067 -269.799552) (xy 348.969501 -269.833587) (xy 348.999017 -269.872866)
			(xy 349.02185 -269.91637) (xy 349.037409 -269.962974) (xy 349.04529 -270.01147) (xy 349.045784 -270.036036)
			(xy 349.375742 -270.036036) (xy 349.379696 -269.987063) (xy 349.391454 -269.939359) (xy 349.410712 -269.894158)
			(xy 349.436971 -269.852632) (xy 349.469552 -269.815856) (xy 349.50761 -269.784782) (xy 349.55016 -269.760216)
			(xy 349.596099 -269.742794) (xy 349.644239 -269.732966) (xy 349.693331 -269.730988) (xy 349.742105 -269.73691)
			(xy 349.789297 -269.750579) (xy 349.833686 -269.771642) (xy 349.874121 -269.799552) (xy 349.909555 -269.833587)
			(xy 349.939071 -269.872866) (xy 349.961904 -269.91637) (xy 349.977463 -269.962974) (xy 349.985344 -270.01147)
			(xy 349.985838 -270.036036) (xy 351.25585 -270.036036) (xy 351.259804 -269.987063) (xy 351.271562 -269.939359)
			(xy 351.29082 -269.894158) (xy 351.317079 -269.852632) (xy 351.34966 -269.815856) (xy 351.387718 -269.784782)
			(xy 351.430268 -269.760216) (xy 351.476207 -269.742794) (xy 351.524347 -269.732966) (xy 351.573439 -269.730988)
			(xy 351.622213 -269.73691) (xy 351.669405 -269.750579) (xy 351.713794 -269.771642) (xy 351.754229 -269.799552)
			(xy 351.789663 -269.833587) (xy 351.819179 -269.872866) (xy 351.842012 -269.91637) (xy 351.857571 -269.962974)
			(xy 351.865452 -270.01147) (xy 351.865946 -270.036036) (xy 352.195904 -270.036036) (xy 352.199858 -269.987063)
			(xy 352.211616 -269.939359) (xy 352.230874 -269.894158) (xy 352.257133 -269.852632) (xy 352.289714 -269.815856)
			(xy 352.327772 -269.784782) (xy 352.370322 -269.760216) (xy 352.416261 -269.742794) (xy 352.464401 -269.732966)
			(xy 352.513493 -269.730988) (xy 352.562267 -269.73691) (xy 352.609459 -269.750579) (xy 352.653848 -269.771642)
			(xy 352.694283 -269.799552) (xy 352.729717 -269.833587) (xy 352.759233 -269.872866) (xy 352.782066 -269.91637)
			(xy 352.797625 -269.962974) (xy 352.805506 -270.01147) (xy 352.806 -270.036036) (xy 354.075758 -270.036036)
			(xy 354.079712 -269.987063) (xy 354.09147 -269.939359) (xy 354.110728 -269.894158) (xy 354.136987 -269.852632)
			(xy 354.169568 -269.815856) (xy 354.207626 -269.784782) (xy 354.250176 -269.760216) (xy 354.296115 -269.742794)
			(xy 354.344255 -269.732966) (xy 354.393347 -269.730988) (xy 354.442121 -269.73691) (xy 354.489313 -269.750579)
			(xy 354.533702 -269.771642) (xy 354.574137 -269.799552) (xy 354.609571 -269.833587) (xy 354.639087 -269.872866)
			(xy 354.66192 -269.91637) (xy 354.677479 -269.962974) (xy 354.68536 -270.01147) (xy 354.685854 -270.036036)
			(xy 355.015812 -270.036036) (xy 355.019766 -269.987063) (xy 355.031524 -269.939359) (xy 355.050782 -269.894158)
			(xy 355.077041 -269.852632) (xy 355.109622 -269.815856) (xy 355.14768 -269.784782) (xy 355.19023 -269.760216)
			(xy 355.236169 -269.742794) (xy 355.284309 -269.732966) (xy 355.333401 -269.730988) (xy 355.382175 -269.73691)
			(xy 355.429367 -269.750579) (xy 355.473756 -269.771642) (xy 355.514191 -269.799552) (xy 355.549625 -269.833587)
			(xy 355.579141 -269.872866) (xy 355.601974 -269.91637) (xy 355.617533 -269.962974) (xy 355.625414 -270.01147)
			(xy 355.625908 -270.036036) (xy 364.409494 -270.036036) (xy 364.413448 -269.987063) (xy 364.425206 -269.939359)
			(xy 364.444464 -269.894158) (xy 364.470723 -269.852632) (xy 364.503304 -269.815856) (xy 364.541362 -269.784782)
			(xy 364.583912 -269.760216) (xy 364.629851 -269.742794) (xy 364.677991 -269.732966) (xy 364.727083 -269.730988)
			(xy 364.775857 -269.73691) (xy 364.823049 -269.750579) (xy 364.867438 -269.771642) (xy 364.907873 -269.799552)
			(xy 364.943307 -269.833587) (xy 364.972823 -269.872866) (xy 364.995656 -269.91637) (xy 365.011215 -269.962974)
			(xy 365.019096 -270.01147) (xy 365.01959 -270.036036) (xy 365.349548 -270.036036) (xy 365.353502 -269.987063)
			(xy 365.36526 -269.939359) (xy 365.384518 -269.894158) (xy 365.410777 -269.852632) (xy 365.443358 -269.815856)
			(xy 365.481416 -269.784782) (xy 365.523966 -269.760216) (xy 365.569905 -269.742794) (xy 365.618045 -269.732966)
			(xy 365.667137 -269.730988) (xy 365.715911 -269.73691) (xy 365.763103 -269.750579) (xy 365.807492 -269.771642)
			(xy 365.847927 -269.799552) (xy 365.883361 -269.833587) (xy 365.912877 -269.872866) (xy 365.93571 -269.91637)
			(xy 365.951269 -269.962974) (xy 365.95915 -270.01147) (xy 365.959644 -270.036036) (xy 367.229402 -270.036036)
			(xy 367.233356 -269.987063) (xy 367.245114 -269.939359) (xy 367.264372 -269.894158) (xy 367.290631 -269.852632)
			(xy 367.323212 -269.815856) (xy 367.36127 -269.784782) (xy 367.40382 -269.760216) (xy 367.449759 -269.742794)
			(xy 367.497899 -269.732966) (xy 367.546991 -269.730988) (xy 367.595765 -269.73691) (xy 367.642957 -269.750579)
			(xy 367.687346 -269.771642) (xy 367.727781 -269.799552) (xy 367.763215 -269.833587) (xy 367.792731 -269.872866)
			(xy 367.815564 -269.91637) (xy 367.831123 -269.962974) (xy 367.839004 -270.01147) (xy 367.839498 -270.036036)
			(xy 368.169456 -270.036036) (xy 368.17341 -269.987063) (xy 368.185168 -269.939359) (xy 368.204426 -269.894158)
			(xy 368.230685 -269.852632) (xy 368.263266 -269.815856) (xy 368.301324 -269.784782) (xy 368.343874 -269.760216)
			(xy 368.389813 -269.742794) (xy 368.437953 -269.732966) (xy 368.487045 -269.730988) (xy 368.535819 -269.73691)
			(xy 368.583011 -269.750579) (xy 368.6274 -269.771642) (xy 368.667835 -269.799552) (xy 368.703269 -269.833587)
			(xy 368.732785 -269.872866) (xy 368.755618 -269.91637) (xy 368.771177 -269.962974) (xy 368.779058 -270.01147)
			(xy 368.779552 -270.036036) (xy 370.049564 -270.036036) (xy 370.053518 -269.987063) (xy 370.065276 -269.939359)
			(xy 370.084534 -269.894158) (xy 370.110793 -269.852632) (xy 370.143374 -269.815856) (xy 370.181432 -269.784782)
			(xy 370.223982 -269.760216) (xy 370.269921 -269.742794) (xy 370.318061 -269.732966) (xy 370.367153 -269.730988)
			(xy 370.415927 -269.73691) (xy 370.463119 -269.750579) (xy 370.507508 -269.771642) (xy 370.547943 -269.799552)
			(xy 370.583377 -269.833587) (xy 370.612893 -269.872866) (xy 370.635726 -269.91637) (xy 370.651285 -269.962974)
			(xy 370.659166 -270.01147) (xy 370.65966 -270.036036) (xy 370.989618 -270.036036) (xy 370.993572 -269.987063)
			(xy 371.00533 -269.939359) (xy 371.024588 -269.894158) (xy 371.050847 -269.852632) (xy 371.083428 -269.815856)
			(xy 371.121486 -269.784782) (xy 371.164036 -269.760216) (xy 371.209975 -269.742794) (xy 371.258115 -269.732966)
			(xy 371.307207 -269.730988) (xy 371.355981 -269.73691) (xy 371.403173 -269.750579) (xy 371.447562 -269.771642)
			(xy 371.487997 -269.799552) (xy 371.523431 -269.833587) (xy 371.552947 -269.872866) (xy 371.57578 -269.91637)
			(xy 371.591339 -269.962974) (xy 371.59922 -270.01147) (xy 371.599714 -270.036036) (xy 372.869472 -270.036036)
			(xy 372.873426 -269.987063) (xy 372.885184 -269.939359) (xy 372.904442 -269.894158) (xy 372.930701 -269.852632)
			(xy 372.963282 -269.815856) (xy 373.00134 -269.784782) (xy 373.04389 -269.760216) (xy 373.089829 -269.742794)
			(xy 373.137969 -269.732966) (xy 373.187061 -269.730988) (xy 373.235835 -269.73691) (xy 373.283027 -269.750579)
			(xy 373.327416 -269.771642) (xy 373.367851 -269.799552) (xy 373.403285 -269.833587) (xy 373.432801 -269.872866)
			(xy 373.455634 -269.91637) (xy 373.471193 -269.962974) (xy 373.479074 -270.01147) (xy 373.479568 -270.036036)
			(xy 373.809526 -270.036036) (xy 373.81348 -269.987063) (xy 373.825238 -269.939359) (xy 373.844496 -269.894158)
			(xy 373.870755 -269.852632) (xy 373.903336 -269.815856) (xy 373.941394 -269.784782) (xy 373.983944 -269.760216)
			(xy 374.029883 -269.742794) (xy 374.078023 -269.732966) (xy 374.127115 -269.730988) (xy 374.175889 -269.73691)
			(xy 374.223081 -269.750579) (xy 374.26747 -269.771642) (xy 374.307905 -269.799552) (xy 374.343339 -269.833587)
			(xy 374.372855 -269.872866) (xy 374.395688 -269.91637) (xy 374.411247 -269.962974) (xy 374.419128 -270.01147)
			(xy 374.419622 -270.036036) (xy 374.419128 -270.060602) (xy 374.411247 -270.109098) (xy 374.395688 -270.155702)
			(xy 374.372855 -270.199206) (xy 374.343339 -270.238485) (xy 374.307905 -270.27252) (xy 374.26747 -270.30043)
			(xy 374.223081 -270.321493) (xy 374.175889 -270.335162) (xy 374.127115 -270.341084) (xy 374.078023 -270.339106)
			(xy 374.029883 -270.329278) (xy 373.983944 -270.311856) (xy 373.941394 -270.28729) (xy 373.903336 -270.256216)
			(xy 373.870755 -270.21944) (xy 373.844496 -270.177914) (xy 373.825238 -270.132713) (xy 373.81348 -270.085009)
			(xy 373.809526 -270.036036) (xy 373.479568 -270.036036) (xy 373.479074 -270.060602) (xy 373.471193 -270.109098)
			(xy 373.455634 -270.155702) (xy 373.432801 -270.199206) (xy 373.403285 -270.238485) (xy 373.367851 -270.27252)
			(xy 373.327416 -270.30043) (xy 373.283027 -270.321493) (xy 373.235835 -270.335162) (xy 373.187061 -270.341084)
			(xy 373.137969 -270.339106) (xy 373.089829 -270.329278) (xy 373.04389 -270.311856) (xy 373.00134 -270.28729)
			(xy 372.963282 -270.256216) (xy 372.930701 -270.21944) (xy 372.904442 -270.177914) (xy 372.885184 -270.132713)
			(xy 372.873426 -270.085009) (xy 372.869472 -270.036036) (xy 371.599714 -270.036036) (xy 371.59922 -270.060602)
			(xy 371.591339 -270.109098) (xy 371.57578 -270.155702) (xy 371.552947 -270.199206) (xy 371.523431 -270.238485)
			(xy 371.487997 -270.27252) (xy 371.447562 -270.30043) (xy 371.403173 -270.321493) (xy 371.355981 -270.335162)
			(xy 371.307207 -270.341084) (xy 371.258115 -270.339106) (xy 371.209975 -270.329278) (xy 371.164036 -270.311856)
			(xy 371.121486 -270.28729) (xy 371.083428 -270.256216) (xy 371.050847 -270.21944) (xy 371.024588 -270.177914)
			(xy 371.00533 -270.132713) (xy 370.993572 -270.085009) (xy 370.989618 -270.036036) (xy 370.65966 -270.036036)
			(xy 370.659166 -270.060602) (xy 370.651285 -270.109098) (xy 370.635726 -270.155702) (xy 370.612893 -270.199206)
			(xy 370.583377 -270.238485) (xy 370.547943 -270.27252) (xy 370.507508 -270.30043) (xy 370.463119 -270.321493)
			(xy 370.415927 -270.335162) (xy 370.367153 -270.341084) (xy 370.318061 -270.339106) (xy 370.269921 -270.329278)
			(xy 370.223982 -270.311856) (xy 370.181432 -270.28729) (xy 370.143374 -270.256216) (xy 370.110793 -270.21944)
			(xy 370.084534 -270.177914) (xy 370.065276 -270.132713) (xy 370.053518 -270.085009) (xy 370.049564 -270.036036)
			(xy 368.779552 -270.036036) (xy 368.779058 -270.060602) (xy 368.771177 -270.109098) (xy 368.755618 -270.155702)
			(xy 368.732785 -270.199206) (xy 368.703269 -270.238485) (xy 368.667835 -270.27252) (xy 368.6274 -270.30043)
			(xy 368.583011 -270.321493) (xy 368.535819 -270.335162) (xy 368.487045 -270.341084) (xy 368.437953 -270.339106)
			(xy 368.389813 -270.329278) (xy 368.343874 -270.311856) (xy 368.301324 -270.28729) (xy 368.263266 -270.256216)
			(xy 368.230685 -270.21944) (xy 368.204426 -270.177914) (xy 368.185168 -270.132713) (xy 368.17341 -270.085009)
			(xy 368.169456 -270.036036) (xy 367.839498 -270.036036) (xy 367.839004 -270.060602) (xy 367.831123 -270.109098)
			(xy 367.815564 -270.155702) (xy 367.792731 -270.199206) (xy 367.763215 -270.238485) (xy 367.727781 -270.27252)
			(xy 367.687346 -270.30043) (xy 367.642957 -270.321493) (xy 367.595765 -270.335162) (xy 367.546991 -270.341084)
			(xy 367.497899 -270.339106) (xy 367.449759 -270.329278) (xy 367.40382 -270.311856) (xy 367.36127 -270.28729)
			(xy 367.323212 -270.256216) (xy 367.290631 -270.21944) (xy 367.264372 -270.177914) (xy 367.245114 -270.132713)
			(xy 367.233356 -270.085009) (xy 367.229402 -270.036036) (xy 365.959644 -270.036036) (xy 365.95915 -270.060602)
			(xy 365.951269 -270.109098) (xy 365.93571 -270.155702) (xy 365.912877 -270.199206) (xy 365.883361 -270.238485)
			(xy 365.847927 -270.27252) (xy 365.807492 -270.30043) (xy 365.763103 -270.321493) (xy 365.715911 -270.335162)
			(xy 365.667137 -270.341084) (xy 365.618045 -270.339106) (xy 365.569905 -270.329278) (xy 365.523966 -270.311856)
			(xy 365.481416 -270.28729) (xy 365.443358 -270.256216) (xy 365.410777 -270.21944) (xy 365.384518 -270.177914)
			(xy 365.36526 -270.132713) (xy 365.353502 -270.085009) (xy 365.349548 -270.036036) (xy 365.01959 -270.036036)
			(xy 365.019096 -270.060602) (xy 365.011215 -270.109098) (xy 364.995656 -270.155702) (xy 364.972823 -270.199206)
			(xy 364.943307 -270.238485) (xy 364.907873 -270.27252) (xy 364.867438 -270.30043) (xy 364.823049 -270.321493)
			(xy 364.775857 -270.335162) (xy 364.727083 -270.341084) (xy 364.677991 -270.339106) (xy 364.629851 -270.329278)
			(xy 364.583912 -270.311856) (xy 364.541362 -270.28729) (xy 364.503304 -270.256216) (xy 364.470723 -270.21944)
			(xy 364.444464 -270.177914) (xy 364.425206 -270.132713) (xy 364.413448 -270.085009) (xy 364.409494 -270.036036)
			(xy 355.625908 -270.036036) (xy 355.625414 -270.060602) (xy 355.617533 -270.109098) (xy 355.601974 -270.155702)
			(xy 355.579141 -270.199206) (xy 355.549625 -270.238485) (xy 355.514191 -270.27252) (xy 355.473756 -270.30043)
			(xy 355.429367 -270.321493) (xy 355.382175 -270.335162) (xy 355.333401 -270.341084) (xy 355.284309 -270.339106)
			(xy 355.236169 -270.329278) (xy 355.19023 -270.311856) (xy 355.14768 -270.28729) (xy 355.109622 -270.256216)
			(xy 355.077041 -270.21944) (xy 355.050782 -270.177914) (xy 355.031524 -270.132713) (xy 355.019766 -270.085009)
			(xy 355.015812 -270.036036) (xy 354.685854 -270.036036) (xy 354.68536 -270.060602) (xy 354.677479 -270.109098)
			(xy 354.66192 -270.155702) (xy 354.639087 -270.199206) (xy 354.609571 -270.238485) (xy 354.574137 -270.27252)
			(xy 354.533702 -270.30043) (xy 354.489313 -270.321493) (xy 354.442121 -270.335162) (xy 354.393347 -270.341084)
			(xy 354.344255 -270.339106) (xy 354.296115 -270.329278) (xy 354.250176 -270.311856) (xy 354.207626 -270.28729)
			(xy 354.169568 -270.256216) (xy 354.136987 -270.21944) (xy 354.110728 -270.177914) (xy 354.09147 -270.132713)
			(xy 354.079712 -270.085009) (xy 354.075758 -270.036036) (xy 352.806 -270.036036) (xy 352.805506 -270.060602)
			(xy 352.797625 -270.109098) (xy 352.782066 -270.155702) (xy 352.759233 -270.199206) (xy 352.729717 -270.238485)
			(xy 352.694283 -270.27252) (xy 352.653848 -270.30043) (xy 352.609459 -270.321493) (xy 352.562267 -270.335162)
			(xy 352.513493 -270.341084) (xy 352.464401 -270.339106) (xy 352.416261 -270.329278) (xy 352.370322 -270.311856)
			(xy 352.327772 -270.28729) (xy 352.289714 -270.256216) (xy 352.257133 -270.21944) (xy 352.230874 -270.177914)
			(xy 352.211616 -270.132713) (xy 352.199858 -270.085009) (xy 352.195904 -270.036036) (xy 351.865946 -270.036036)
			(xy 351.865452 -270.060602) (xy 351.857571 -270.109098) (xy 351.842012 -270.155702) (xy 351.819179 -270.199206)
			(xy 351.789663 -270.238485) (xy 351.754229 -270.27252) (xy 351.713794 -270.30043) (xy 351.669405 -270.321493)
			(xy 351.622213 -270.335162) (xy 351.573439 -270.341084) (xy 351.524347 -270.339106) (xy 351.476207 -270.329278)
			(xy 351.430268 -270.311856) (xy 351.387718 -270.28729) (xy 351.34966 -270.256216) (xy 351.317079 -270.21944)
			(xy 351.29082 -270.177914) (xy 351.271562 -270.132713) (xy 351.259804 -270.085009) (xy 351.25585 -270.036036)
			(xy 349.985838 -270.036036) (xy 349.985344 -270.060602) (xy 349.977463 -270.109098) (xy 349.961904 -270.155702)
			(xy 349.939071 -270.199206) (xy 349.909555 -270.238485) (xy 349.874121 -270.27252) (xy 349.833686 -270.30043)
			(xy 349.789297 -270.321493) (xy 349.742105 -270.335162) (xy 349.693331 -270.341084) (xy 349.644239 -270.339106)
			(xy 349.596099 -270.329278) (xy 349.55016 -270.311856) (xy 349.50761 -270.28729) (xy 349.469552 -270.256216)
			(xy 349.436971 -270.21944) (xy 349.410712 -270.177914) (xy 349.391454 -270.132713) (xy 349.379696 -270.085009)
			(xy 349.375742 -270.036036) (xy 349.045784 -270.036036) (xy 349.04529 -270.060602) (xy 349.037409 -270.109098)
			(xy 349.02185 -270.155702) (xy 348.999017 -270.199206) (xy 348.969501 -270.238485) (xy 348.934067 -270.27252)
			(xy 348.893632 -270.30043) (xy 348.849243 -270.321493) (xy 348.802051 -270.335162) (xy 348.753277 -270.341084)
			(xy 348.704185 -270.339106) (xy 348.656045 -270.329278) (xy 348.610106 -270.311856) (xy 348.567556 -270.28729)
			(xy 348.529498 -270.256216) (xy 348.496917 -270.21944) (xy 348.470658 -270.177914) (xy 348.4514 -270.132713)
			(xy 348.439642 -270.085009) (xy 348.435688 -270.036036) (xy 347.16593 -270.036036) (xy 347.165436 -270.060602)
			(xy 347.157555 -270.109098) (xy 347.141996 -270.155702) (xy 347.119163 -270.199206) (xy 347.089647 -270.238485)
			(xy 347.054213 -270.27252) (xy 347.013778 -270.30043) (xy 346.969389 -270.321493) (xy 346.922197 -270.335162)
			(xy 346.873423 -270.341084) (xy 346.824331 -270.339106) (xy 346.776191 -270.329278) (xy 346.730252 -270.311856)
			(xy 346.687702 -270.28729) (xy 346.649644 -270.256216) (xy 346.617063 -270.21944) (xy 346.590804 -270.177914)
			(xy 346.571546 -270.132713) (xy 346.559788 -270.085009) (xy 346.555834 -270.036036) (xy 346.225876 -270.036036)
			(xy 346.225382 -270.060602) (xy 346.217501 -270.109098) (xy 346.201942 -270.155702) (xy 346.179109 -270.199206)
			(xy 346.149593 -270.238485) (xy 346.114159 -270.27252) (xy 346.073724 -270.30043) (xy 346.029335 -270.321493)
			(xy 345.982143 -270.335162) (xy 345.933369 -270.341084) (xy 345.884277 -270.339106) (xy 345.836137 -270.329278)
			(xy 345.790198 -270.311856) (xy 345.747648 -270.28729) (xy 345.70959 -270.256216) (xy 345.677009 -270.21944)
			(xy 345.65075 -270.177914) (xy 345.631492 -270.132713) (xy 345.619734 -270.085009) (xy 345.61578 -270.036036)
			(xy 126.479549 -270.036036) (xy 126.479554 -270.03629) (xy 126.47906 -270.060856) (xy 126.471179 -270.109352)
			(xy 126.45562 -270.155956) (xy 126.432787 -270.19946) (xy 126.403271 -270.238739) (xy 126.367837 -270.272774)
			(xy 126.327402 -270.300684) (xy 126.283013 -270.321747) (xy 126.235821 -270.335416) (xy 126.187047 -270.341338)
			(xy 126.137955 -270.33936) (xy 126.089815 -270.329532) (xy 126.043876 -270.31211) (xy 126.001326 -270.287544)
			(xy 125.963268 -270.25647) (xy 125.930687 -270.219694) (xy 125.904428 -270.178168) (xy 125.88517 -270.132967)
			(xy 125.873412 -270.085263) (xy 125.869458 -270.03629) (xy 125.5395 -270.03629) (xy 125.539006 -270.060856)
			(xy 125.531125 -270.109352) (xy 125.515566 -270.155956) (xy 125.492733 -270.19946) (xy 125.463217 -270.238739)
			(xy 125.427783 -270.272774) (xy 125.387348 -270.300684) (xy 125.342959 -270.321747) (xy 125.295767 -270.335416)
			(xy 125.246993 -270.341338) (xy 125.197901 -270.33936) (xy 125.149761 -270.329532) (xy 125.103822 -270.31211)
			(xy 125.061272 -270.287544) (xy 125.023214 -270.25647) (xy 124.990633 -270.219694) (xy 124.964374 -270.178168)
			(xy 124.945116 -270.132967) (xy 124.933358 -270.085263) (xy 124.929404 -270.03629) (xy 123.659646 -270.03629)
			(xy 123.659152 -270.060856) (xy 123.651271 -270.109352) (xy 123.635712 -270.155956) (xy 123.612879 -270.19946)
			(xy 123.583363 -270.238739) (xy 123.547929 -270.272774) (xy 123.507494 -270.300684) (xy 123.463105 -270.321747)
			(xy 123.415913 -270.335416) (xy 123.367139 -270.341338) (xy 123.318047 -270.33936) (xy 123.269907 -270.329532)
			(xy 123.223968 -270.31211) (xy 123.181418 -270.287544) (xy 123.14336 -270.25647) (xy 123.110779 -270.219694)
			(xy 123.08452 -270.178168) (xy 123.065262 -270.132967) (xy 123.053504 -270.085263) (xy 123.04955 -270.03629)
			(xy 122.719592 -270.03629) (xy 122.719098 -270.060856) (xy 122.711217 -270.109352) (xy 122.695658 -270.155956)
			(xy 122.672825 -270.19946) (xy 122.643309 -270.238739) (xy 122.607875 -270.272774) (xy 122.56744 -270.300684)
			(xy 122.523051 -270.321747) (xy 122.475859 -270.335416) (xy 122.427085 -270.341338) (xy 122.377993 -270.33936)
			(xy 122.329853 -270.329532) (xy 122.283914 -270.31211) (xy 122.241364 -270.287544) (xy 122.203306 -270.25647)
			(xy 122.170725 -270.219694) (xy 122.144466 -270.178168) (xy 122.125208 -270.132967) (xy 122.11345 -270.085263)
			(xy 122.109496 -270.03629) (xy 120.839484 -270.03629) (xy 120.83899 -270.060856) (xy 120.831109 -270.109352)
			(xy 120.81555 -270.155956) (xy 120.792717 -270.19946) (xy 120.763201 -270.238739) (xy 120.727767 -270.272774)
			(xy 120.687332 -270.300684) (xy 120.642943 -270.321747) (xy 120.595751 -270.335416) (xy 120.546977 -270.341338)
			(xy 120.497885 -270.33936) (xy 120.449745 -270.329532) (xy 120.403806 -270.31211) (xy 120.361256 -270.287544)
			(xy 120.323198 -270.25647) (xy 120.290617 -270.219694) (xy 120.264358 -270.178168) (xy 120.2451 -270.132967)
			(xy 120.233342 -270.085263) (xy 120.229388 -270.03629) (xy 119.89943 -270.03629) (xy 119.898936 -270.060856)
			(xy 119.891055 -270.109352) (xy 119.875496 -270.155956) (xy 119.852663 -270.19946) (xy 119.823147 -270.238739)
			(xy 119.787713 -270.272774) (xy 119.747278 -270.300684) (xy 119.702889 -270.321747) (xy 119.655697 -270.335416)
			(xy 119.606923 -270.341338) (xy 119.557831 -270.33936) (xy 119.509691 -270.329532) (xy 119.463752 -270.31211)
			(xy 119.421202 -270.287544) (xy 119.383144 -270.25647) (xy 119.350563 -270.219694) (xy 119.324304 -270.178168)
			(xy 119.305046 -270.132967) (xy 119.293288 -270.085263) (xy 119.289334 -270.03629) (xy 118.019576 -270.03629)
			(xy 118.019082 -270.060856) (xy 118.011201 -270.109352) (xy 117.995642 -270.155956) (xy 117.972809 -270.19946)
			(xy 117.943293 -270.238739) (xy 117.907859 -270.272774) (xy 117.867424 -270.300684) (xy 117.823035 -270.321747)
			(xy 117.775843 -270.335416) (xy 117.727069 -270.341338) (xy 117.677977 -270.33936) (xy 117.629837 -270.329532)
			(xy 117.583898 -270.31211) (xy 117.541348 -270.287544) (xy 117.50329 -270.25647) (xy 117.470709 -270.219694)
			(xy 117.44445 -270.178168) (xy 117.425192 -270.132967) (xy 117.413434 -270.085263) (xy 117.40948 -270.03629)
			(xy 117.079522 -270.03629) (xy 117.079028 -270.060856) (xy 117.071147 -270.109352) (xy 117.055588 -270.155956)
			(xy 117.032755 -270.19946) (xy 117.003239 -270.238739) (xy 116.967805 -270.272774) (xy 116.92737 -270.300684)
			(xy 116.882981 -270.321747) (xy 116.835789 -270.335416) (xy 116.787015 -270.341338) (xy 116.737923 -270.33936)
			(xy 116.689783 -270.329532) (xy 116.643844 -270.31211) (xy 116.601294 -270.287544) (xy 116.563236 -270.25647)
			(xy 116.530655 -270.219694) (xy 116.504396 -270.178168) (xy 116.485138 -270.132967) (xy 116.47338 -270.085263)
			(xy 116.469426 -270.03629) (xy 107.68584 -270.03629) (xy 107.685346 -270.060856) (xy 107.677465 -270.109352)
			(xy 107.661906 -270.155956) (xy 107.639073 -270.19946) (xy 107.609557 -270.238739) (xy 107.574123 -270.272774)
			(xy 107.533688 -270.300684) (xy 107.489299 -270.321747) (xy 107.442107 -270.335416) (xy 107.393333 -270.341338)
			(xy 107.344241 -270.33936) (xy 107.296101 -270.329532) (xy 107.250162 -270.31211) (xy 107.207612 -270.287544)
			(xy 107.169554 -270.25647) (xy 107.136973 -270.219694) (xy 107.110714 -270.178168) (xy 107.091456 -270.132967)
			(xy 107.079698 -270.085263) (xy 107.075744 -270.03629) (xy 106.745786 -270.03629) (xy 106.745292 -270.060856)
			(xy 106.737411 -270.109352) (xy 106.721852 -270.155956) (xy 106.699019 -270.19946) (xy 106.669503 -270.238739)
			(xy 106.634069 -270.272774) (xy 106.593634 -270.300684) (xy 106.549245 -270.321747) (xy 106.502053 -270.335416)
			(xy 106.453279 -270.341338) (xy 106.404187 -270.33936) (xy 106.356047 -270.329532) (xy 106.310108 -270.31211)
			(xy 106.267558 -270.287544) (xy 106.2295 -270.25647) (xy 106.196919 -270.219694) (xy 106.17066 -270.178168)
			(xy 106.151402 -270.132967) (xy 106.139644 -270.085263) (xy 106.13569 -270.03629) (xy 104.865932 -270.03629)
			(xy 104.865438 -270.060856) (xy 104.857557 -270.109352) (xy 104.841998 -270.155956) (xy 104.819165 -270.19946)
			(xy 104.789649 -270.238739) (xy 104.754215 -270.272774) (xy 104.71378 -270.300684) (xy 104.669391 -270.321747)
			(xy 104.622199 -270.335416) (xy 104.573425 -270.341338) (xy 104.524333 -270.33936) (xy 104.476193 -270.329532)
			(xy 104.430254 -270.31211) (xy 104.387704 -270.287544) (xy 104.349646 -270.25647) (xy 104.317065 -270.219694)
			(xy 104.290806 -270.178168) (xy 104.271548 -270.132967) (xy 104.25979 -270.085263) (xy 104.255836 -270.03629)
			(xy 103.925878 -270.03629) (xy 103.925384 -270.060856) (xy 103.917503 -270.109352) (xy 103.901944 -270.155956)
			(xy 103.879111 -270.19946) (xy 103.849595 -270.238739) (xy 103.814161 -270.272774) (xy 103.773726 -270.300684)
			(xy 103.729337 -270.321747) (xy 103.682145 -270.335416) (xy 103.633371 -270.341338) (xy 103.584279 -270.33936)
			(xy 103.536139 -270.329532) (xy 103.4902 -270.31211) (xy 103.44765 -270.287544) (xy 103.409592 -270.25647)
			(xy 103.377011 -270.219694) (xy 103.350752 -270.178168) (xy 103.331494 -270.132967) (xy 103.319736 -270.085263)
			(xy 103.315782 -270.03629) (xy 102.04577 -270.03629) (xy 102.045276 -270.060856) (xy 102.037395 -270.109352)
			(xy 102.021836 -270.155956) (xy 101.999003 -270.19946) (xy 101.969487 -270.238739) (xy 101.934053 -270.272774)
			(xy 101.893618 -270.300684) (xy 101.849229 -270.321747) (xy 101.802037 -270.335416) (xy 101.753263 -270.341338)
			(xy 101.704171 -270.33936) (xy 101.656031 -270.329532) (xy 101.610092 -270.31211) (xy 101.567542 -270.287544)
			(xy 101.529484 -270.25647) (xy 101.496903 -270.219694) (xy 101.470644 -270.178168) (xy 101.451386 -270.132967)
			(xy 101.439628 -270.085263) (xy 101.435674 -270.03629) (xy 101.105716 -270.03629) (xy 101.105222 -270.060856)
			(xy 101.097341 -270.109352) (xy 101.081782 -270.155956) (xy 101.058949 -270.19946) (xy 101.029433 -270.238739)
			(xy 100.993999 -270.272774) (xy 100.953564 -270.300684) (xy 100.909175 -270.321747) (xy 100.861983 -270.335416)
			(xy 100.813209 -270.341338) (xy 100.764117 -270.33936) (xy 100.715977 -270.329532) (xy 100.670038 -270.31211)
			(xy 100.627488 -270.287544) (xy 100.58943 -270.25647) (xy 100.556849 -270.219694) (xy 100.53059 -270.178168)
			(xy 100.511332 -270.132967) (xy 100.499574 -270.085263) (xy 100.49562 -270.03629) (xy 99.225862 -270.03629)
			(xy 99.225368 -270.060856) (xy 99.217487 -270.109352) (xy 99.201928 -270.155956) (xy 99.179095 -270.19946)
			(xy 99.149579 -270.238739) (xy 99.114145 -270.272774) (xy 99.07371 -270.300684) (xy 99.029321 -270.321747)
			(xy 98.982129 -270.335416) (xy 98.933355 -270.341338) (xy 98.884263 -270.33936) (xy 98.836123 -270.329532)
			(xy 98.790184 -270.31211) (xy 98.747634 -270.287544) (xy 98.709576 -270.25647) (xy 98.676995 -270.219694)
			(xy 98.650736 -270.178168) (xy 98.631478 -270.132967) (xy 98.61972 -270.085263) (xy 98.615766 -270.03629)
			(xy 98.285808 -270.03629) (xy 98.285314 -270.060856) (xy 98.277433 -270.109352) (xy 98.261874 -270.155956)
			(xy 98.239041 -270.19946) (xy 98.209525 -270.238739) (xy 98.174091 -270.272774) (xy 98.133656 -270.300684)
			(xy 98.089267 -270.321747) (xy 98.042075 -270.335416) (xy 97.993301 -270.341338) (xy 97.944209 -270.33936)
			(xy 97.896069 -270.329532) (xy 97.85013 -270.31211) (xy 97.80758 -270.287544) (xy 97.769522 -270.25647)
			(xy 97.736941 -270.219694) (xy 97.710682 -270.178168) (xy 97.691424 -270.132967) (xy 97.679666 -270.085263)
			(xy 97.675712 -270.03629) (xy 2.509012 -270.03629) (xy 2.509012 -270.846296) (xy 108.485698 -270.846296)
			(xy 108.489652 -270.797323) (xy 108.50141 -270.749619) (xy 108.520668 -270.704418) (xy 108.546927 -270.662892)
			(xy 108.579508 -270.626116) (xy 108.617566 -270.595042) (xy 108.660116 -270.570476) (xy 108.706055 -270.553054)
			(xy 108.754195 -270.543226) (xy 108.803287 -270.541248) (xy 108.852061 -270.54717) (xy 108.899253 -270.560839)
			(xy 108.943642 -270.581902) (xy 108.984077 -270.609812) (xy 109.019511 -270.643847) (xy 109.049027 -270.683126)
			(xy 109.07186 -270.72663) (xy 109.087419 -270.773234) (xy 109.0953 -270.82173) (xy 109.095794 -270.846296)
			(xy 109.425752 -270.846296) (xy 109.429706 -270.797323) (xy 109.441464 -270.749619) (xy 109.460722 -270.704418)
			(xy 109.486981 -270.662892) (xy 109.519562 -270.626116) (xy 109.55762 -270.595042) (xy 109.60017 -270.570476)
			(xy 109.646109 -270.553054) (xy 109.694249 -270.543226) (xy 109.743341 -270.541248) (xy 109.792115 -270.54717)
			(xy 109.839307 -270.560839) (xy 109.883696 -270.581902) (xy 109.924131 -270.609812) (xy 109.959565 -270.643847)
			(xy 109.989081 -270.683126) (xy 110.011914 -270.72663) (xy 110.027473 -270.773234) (xy 110.035354 -270.82173)
			(xy 110.035848 -270.846296) (xy 114.119418 -270.846296) (xy 114.123372 -270.797323) (xy 114.13513 -270.749619)
			(xy 114.154388 -270.704418) (xy 114.180647 -270.662892) (xy 114.213228 -270.626116) (xy 114.251286 -270.595042)
			(xy 114.293836 -270.570476) (xy 114.339775 -270.553054) (xy 114.387915 -270.543226) (xy 114.437007 -270.541248)
			(xy 114.485781 -270.54717) (xy 114.532973 -270.560839) (xy 114.577362 -270.581902) (xy 114.617797 -270.609812)
			(xy 114.653231 -270.643847) (xy 114.682747 -270.683126) (xy 114.70558 -270.72663) (xy 114.721139 -270.773234)
			(xy 114.72902 -270.82173) (xy 114.729514 -270.846296) (xy 115.059472 -270.846296) (xy 115.063426 -270.797323)
			(xy 115.075184 -270.749619) (xy 115.094442 -270.704418) (xy 115.120701 -270.662892) (xy 115.153282 -270.626116)
			(xy 115.19134 -270.595042) (xy 115.23389 -270.570476) (xy 115.279829 -270.553054) (xy 115.327969 -270.543226)
			(xy 115.377061 -270.541248) (xy 115.425835 -270.54717) (xy 115.473027 -270.560839) (xy 115.517416 -270.581902)
			(xy 115.557851 -270.609812) (xy 115.593285 -270.643847) (xy 115.622801 -270.683126) (xy 115.645634 -270.72663)
			(xy 115.661193 -270.773234) (xy 115.669074 -270.82173) (xy 115.669563 -270.846042) (xy 356.425766 -270.846042)
			(xy 356.42972 -270.797069) (xy 356.441478 -270.749365) (xy 356.460736 -270.704164) (xy 356.486995 -270.662638)
			(xy 356.519576 -270.625862) (xy 356.557634 -270.594788) (xy 356.600184 -270.570222) (xy 356.646123 -270.5528)
			(xy 356.694263 -270.542972) (xy 356.743355 -270.540994) (xy 356.792129 -270.546916) (xy 356.839321 -270.560585)
			(xy 356.88371 -270.581648) (xy 356.924145 -270.609558) (xy 356.959579 -270.643593) (xy 356.989095 -270.682872)
			(xy 357.011928 -270.726376) (xy 357.027487 -270.77298) (xy 357.035368 -270.821476) (xy 357.035862 -270.846042)
			(xy 357.36582 -270.846042) (xy 357.369774 -270.797069) (xy 357.381532 -270.749365) (xy 357.40079 -270.704164)
			(xy 357.427049 -270.662638) (xy 357.45963 -270.625862) (xy 357.497688 -270.594788) (xy 357.540238 -270.570222)
			(xy 357.586177 -270.5528) (xy 357.634317 -270.542972) (xy 357.683409 -270.540994) (xy 357.732183 -270.546916)
			(xy 357.779375 -270.560585) (xy 357.823764 -270.581648) (xy 357.864199 -270.609558) (xy 357.899633 -270.643593)
			(xy 357.929149 -270.682872) (xy 357.951982 -270.726376) (xy 357.967541 -270.77298) (xy 357.975422 -270.821476)
			(xy 357.975916 -270.846042) (xy 362.059486 -270.846042) (xy 362.06344 -270.797069) (xy 362.075198 -270.749365)
			(xy 362.094456 -270.704164) (xy 362.120715 -270.662638) (xy 362.153296 -270.625862) (xy 362.191354 -270.594788)
			(xy 362.233904 -270.570222) (xy 362.279843 -270.5528) (xy 362.327983 -270.542972) (xy 362.377075 -270.540994)
			(xy 362.425849 -270.546916) (xy 362.473041 -270.560585) (xy 362.51743 -270.581648) (xy 362.557865 -270.609558)
			(xy 362.593299 -270.643593) (xy 362.622815 -270.682872) (xy 362.645648 -270.726376) (xy 362.661207 -270.77298)
			(xy 362.669088 -270.821476) (xy 362.669582 -270.846042) (xy 362.99954 -270.846042) (xy 363.003494 -270.797069)
			(xy 363.015252 -270.749365) (xy 363.03451 -270.704164) (xy 363.060769 -270.662638) (xy 363.09335 -270.625862)
			(xy 363.131408 -270.594788) (xy 363.173958 -270.570222) (xy 363.219897 -270.5528) (xy 363.268037 -270.542972)
			(xy 363.317129 -270.540994) (xy 363.365903 -270.546916) (xy 363.413095 -270.560585) (xy 363.457484 -270.581648)
			(xy 363.497919 -270.609558) (xy 363.533353 -270.643593) (xy 363.562869 -270.682872) (xy 363.585702 -270.726376)
			(xy 363.601261 -270.77298) (xy 363.609142 -270.821476) (xy 363.609636 -270.846042) (xy 363.609142 -270.870608)
			(xy 363.601261 -270.919104) (xy 363.585702 -270.965708) (xy 363.562869 -271.009212) (xy 363.533353 -271.048491)
			(xy 363.497919 -271.082526) (xy 363.457484 -271.110436) (xy 363.413095 -271.131499) (xy 363.365903 -271.145168)
			(xy 363.317129 -271.15109) (xy 363.268037 -271.149112) (xy 363.219897 -271.139284) (xy 363.173958 -271.121862)
			(xy 363.131408 -271.097296) (xy 363.09335 -271.066222) (xy 363.060769 -271.029446) (xy 363.03451 -270.98792)
			(xy 363.015252 -270.942719) (xy 363.003494 -270.895015) (xy 362.99954 -270.846042) (xy 362.669582 -270.846042)
			(xy 362.669088 -270.870608) (xy 362.661207 -270.919104) (xy 362.645648 -270.965708) (xy 362.622815 -271.009212)
			(xy 362.593299 -271.048491) (xy 362.557865 -271.082526) (xy 362.51743 -271.110436) (xy 362.473041 -271.131499)
			(xy 362.425849 -271.145168) (xy 362.377075 -271.15109) (xy 362.327983 -271.149112) (xy 362.279843 -271.139284)
			(xy 362.233904 -271.121862) (xy 362.191354 -271.097296) (xy 362.153296 -271.066222) (xy 362.120715 -271.029446)
			(xy 362.094456 -270.98792) (xy 362.075198 -270.942719) (xy 362.06344 -270.895015) (xy 362.059486 -270.846042)
			(xy 357.975916 -270.846042) (xy 357.975422 -270.870608) (xy 357.967541 -270.919104) (xy 357.951982 -270.965708)
			(xy 357.929149 -271.009212) (xy 357.899633 -271.048491) (xy 357.864199 -271.082526) (xy 357.823764 -271.110436)
			(xy 357.779375 -271.131499) (xy 357.732183 -271.145168) (xy 357.683409 -271.15109) (xy 357.634317 -271.149112)
			(xy 357.586177 -271.139284) (xy 357.540238 -271.121862) (xy 357.497688 -271.097296) (xy 357.45963 -271.066222)
			(xy 357.427049 -271.029446) (xy 357.40079 -270.98792) (xy 357.381532 -270.942719) (xy 357.369774 -270.895015)
			(xy 357.36582 -270.846042) (xy 357.035862 -270.846042) (xy 357.035368 -270.870608) (xy 357.027487 -270.919104)
			(xy 357.011928 -270.965708) (xy 356.989095 -271.009212) (xy 356.959579 -271.048491) (xy 356.924145 -271.082526)
			(xy 356.88371 -271.110436) (xy 356.839321 -271.131499) (xy 356.792129 -271.145168) (xy 356.743355 -271.15109)
			(xy 356.694263 -271.149112) (xy 356.646123 -271.139284) (xy 356.600184 -271.121862) (xy 356.557634 -271.097296)
			(xy 356.519576 -271.066222) (xy 356.486995 -271.029446) (xy 356.460736 -270.98792) (xy 356.441478 -270.942719)
			(xy 356.42972 -270.895015) (xy 356.425766 -270.846042) (xy 115.669563 -270.846042) (xy 115.669568 -270.846296)
			(xy 115.669074 -270.870862) (xy 115.661193 -270.919358) (xy 115.645634 -270.965962) (xy 115.622801 -271.009466)
			(xy 115.593285 -271.048745) (xy 115.557851 -271.08278) (xy 115.517416 -271.11069) (xy 115.473027 -271.131753)
			(xy 115.425835 -271.145422) (xy 115.377061 -271.151344) (xy 115.327969 -271.149366) (xy 115.279829 -271.139538)
			(xy 115.23389 -271.122116) (xy 115.19134 -271.09755) (xy 115.153282 -271.066476) (xy 115.120701 -271.0297)
			(xy 115.094442 -270.988174) (xy 115.075184 -270.942973) (xy 115.063426 -270.895269) (xy 115.059472 -270.846296)
			(xy 114.729514 -270.846296) (xy 114.72902 -270.870862) (xy 114.721139 -270.919358) (xy 114.70558 -270.965962)
			(xy 114.682747 -271.009466) (xy 114.653231 -271.048745) (xy 114.617797 -271.08278) (xy 114.577362 -271.11069)
			(xy 114.532973 -271.131753) (xy 114.485781 -271.145422) (xy 114.437007 -271.151344) (xy 114.387915 -271.149366)
			(xy 114.339775 -271.139538) (xy 114.293836 -271.122116) (xy 114.251286 -271.09755) (xy 114.213228 -271.066476)
			(xy 114.180647 -271.0297) (xy 114.154388 -270.988174) (xy 114.13513 -270.942973) (xy 114.123372 -270.895269)
			(xy 114.119418 -270.846296) (xy 110.035848 -270.846296) (xy 110.035354 -270.870862) (xy 110.027473 -270.919358)
			(xy 110.011914 -270.965962) (xy 109.989081 -271.009466) (xy 109.959565 -271.048745) (xy 109.924131 -271.08278)
			(xy 109.883696 -271.11069) (xy 109.839307 -271.131753) (xy 109.792115 -271.145422) (xy 109.743341 -271.151344)
			(xy 109.694249 -271.149366) (xy 109.646109 -271.139538) (xy 109.60017 -271.122116) (xy 109.55762 -271.09755)
			(xy 109.519562 -271.066476) (xy 109.486981 -271.0297) (xy 109.460722 -270.988174) (xy 109.441464 -270.942973)
			(xy 109.429706 -270.895269) (xy 109.425752 -270.846296) (xy 109.095794 -270.846296) (xy 109.0953 -270.870862)
			(xy 109.087419 -270.919358) (xy 109.07186 -270.965962) (xy 109.049027 -271.009466) (xy 109.019511 -271.048745)
			(xy 108.984077 -271.08278) (xy 108.943642 -271.11069) (xy 108.899253 -271.131753) (xy 108.852061 -271.145422)
			(xy 108.803287 -271.151344) (xy 108.754195 -271.149366) (xy 108.706055 -271.139538) (xy 108.660116 -271.122116)
			(xy 108.617566 -271.09755) (xy 108.579508 -271.066476) (xy 108.546927 -271.0297) (xy 108.520668 -270.988174)
			(xy 108.50141 -270.942973) (xy 108.489652 -270.895269) (xy 108.485698 -270.846296) (xy 2.509012 -270.846296)
			(xy 2.509012 -271.656302) (xy 97.675712 -271.656302) (xy 97.679666 -271.607329) (xy 97.691424 -271.559625)
			(xy 97.710682 -271.514424) (xy 97.736941 -271.472898) (xy 97.769522 -271.436122) (xy 97.80758 -271.405048)
			(xy 97.85013 -271.380482) (xy 97.896069 -271.36306) (xy 97.944209 -271.353232) (xy 97.993301 -271.351254)
			(xy 98.042075 -271.357176) (xy 98.089267 -271.370845) (xy 98.133656 -271.391908) (xy 98.174091 -271.419818)
			(xy 98.209525 -271.453853) (xy 98.239041 -271.493132) (xy 98.261874 -271.536636) (xy 98.277433 -271.58324)
			(xy 98.285314 -271.631736) (xy 98.285808 -271.656302) (xy 98.615766 -271.656302) (xy 98.61972 -271.607329)
			(xy 98.631478 -271.559625) (xy 98.650736 -271.514424) (xy 98.676995 -271.472898) (xy 98.709576 -271.436122)
			(xy 98.747634 -271.405048) (xy 98.790184 -271.380482) (xy 98.836123 -271.36306) (xy 98.884263 -271.353232)
			(xy 98.933355 -271.351254) (xy 98.982129 -271.357176) (xy 99.029321 -271.370845) (xy 99.07371 -271.391908)
			(xy 99.114145 -271.419818) (xy 99.149579 -271.453853) (xy 99.179095 -271.493132) (xy 99.201928 -271.536636)
			(xy 99.217487 -271.58324) (xy 99.225368 -271.631736) (xy 99.225862 -271.656302) (xy 100.49562 -271.656302)
			(xy 100.499574 -271.607329) (xy 100.511332 -271.559625) (xy 100.53059 -271.514424) (xy 100.556849 -271.472898)
			(xy 100.58943 -271.436122) (xy 100.627488 -271.405048) (xy 100.670038 -271.380482) (xy 100.715977 -271.36306)
			(xy 100.764117 -271.353232) (xy 100.813209 -271.351254) (xy 100.861983 -271.357176) (xy 100.909175 -271.370845)
			(xy 100.953564 -271.391908) (xy 100.993999 -271.419818) (xy 101.029433 -271.453853) (xy 101.058949 -271.493132)
			(xy 101.081782 -271.536636) (xy 101.097341 -271.58324) (xy 101.105222 -271.631736) (xy 101.105716 -271.656302)
			(xy 101.435674 -271.656302) (xy 101.439628 -271.607329) (xy 101.451386 -271.559625) (xy 101.470644 -271.514424)
			(xy 101.496903 -271.472898) (xy 101.529484 -271.436122) (xy 101.567542 -271.405048) (xy 101.610092 -271.380482)
			(xy 101.656031 -271.36306) (xy 101.704171 -271.353232) (xy 101.753263 -271.351254) (xy 101.802037 -271.357176)
			(xy 101.849229 -271.370845) (xy 101.893618 -271.391908) (xy 101.934053 -271.419818) (xy 101.969487 -271.453853)
			(xy 101.999003 -271.493132) (xy 102.021836 -271.536636) (xy 102.037395 -271.58324) (xy 102.045276 -271.631736)
			(xy 102.04577 -271.656302) (xy 103.315782 -271.656302) (xy 103.319736 -271.607329) (xy 103.331494 -271.559625)
			(xy 103.350752 -271.514424) (xy 103.377011 -271.472898) (xy 103.409592 -271.436122) (xy 103.44765 -271.405048)
			(xy 103.4902 -271.380482) (xy 103.536139 -271.36306) (xy 103.584279 -271.353232) (xy 103.633371 -271.351254)
			(xy 103.682145 -271.357176) (xy 103.729337 -271.370845) (xy 103.773726 -271.391908) (xy 103.814161 -271.419818)
			(xy 103.849595 -271.453853) (xy 103.879111 -271.493132) (xy 103.901944 -271.536636) (xy 103.917503 -271.58324)
			(xy 103.925384 -271.631736) (xy 103.925878 -271.656302) (xy 104.255836 -271.656302) (xy 104.25979 -271.607329)
			(xy 104.271548 -271.559625) (xy 104.290806 -271.514424) (xy 104.317065 -271.472898) (xy 104.349646 -271.436122)
			(xy 104.387704 -271.405048) (xy 104.430254 -271.380482) (xy 104.476193 -271.36306) (xy 104.524333 -271.353232)
			(xy 104.573425 -271.351254) (xy 104.622199 -271.357176) (xy 104.669391 -271.370845) (xy 104.71378 -271.391908)
			(xy 104.754215 -271.419818) (xy 104.789649 -271.453853) (xy 104.819165 -271.493132) (xy 104.841998 -271.536636)
			(xy 104.857557 -271.58324) (xy 104.865438 -271.631736) (xy 104.865932 -271.656302) (xy 106.13569 -271.656302)
			(xy 106.139644 -271.607329) (xy 106.151402 -271.559625) (xy 106.17066 -271.514424) (xy 106.196919 -271.472898)
			(xy 106.2295 -271.436122) (xy 106.267558 -271.405048) (xy 106.310108 -271.380482) (xy 106.356047 -271.36306)
			(xy 106.404187 -271.353232) (xy 106.453279 -271.351254) (xy 106.502053 -271.357176) (xy 106.549245 -271.370845)
			(xy 106.593634 -271.391908) (xy 106.634069 -271.419818) (xy 106.669503 -271.453853) (xy 106.699019 -271.493132)
			(xy 106.721852 -271.536636) (xy 106.737411 -271.58324) (xy 106.745292 -271.631736) (xy 106.745786 -271.656302)
			(xy 107.075744 -271.656302) (xy 107.079698 -271.607329) (xy 107.091456 -271.559625) (xy 107.110714 -271.514424)
			(xy 107.136973 -271.472898) (xy 107.169554 -271.436122) (xy 107.207612 -271.405048) (xy 107.250162 -271.380482)
			(xy 107.296101 -271.36306) (xy 107.344241 -271.353232) (xy 107.393333 -271.351254) (xy 107.442107 -271.357176)
			(xy 107.489299 -271.370845) (xy 107.533688 -271.391908) (xy 107.574123 -271.419818) (xy 107.609557 -271.453853)
			(xy 107.639073 -271.493132) (xy 107.661906 -271.536636) (xy 107.677465 -271.58324) (xy 107.685346 -271.631736)
			(xy 107.68584 -271.656302) (xy 116.469426 -271.656302) (xy 116.47338 -271.607329) (xy 116.485138 -271.559625)
			(xy 116.504396 -271.514424) (xy 116.530655 -271.472898) (xy 116.563236 -271.436122) (xy 116.601294 -271.405048)
			(xy 116.643844 -271.380482) (xy 116.689783 -271.36306) (xy 116.737923 -271.353232) (xy 116.787015 -271.351254)
			(xy 116.835789 -271.357176) (xy 116.882981 -271.370845) (xy 116.92737 -271.391908) (xy 116.967805 -271.419818)
			(xy 117.003239 -271.453853) (xy 117.032755 -271.493132) (xy 117.055588 -271.536636) (xy 117.071147 -271.58324)
			(xy 117.079028 -271.631736) (xy 117.079522 -271.656302) (xy 117.40948 -271.656302) (xy 117.413434 -271.607329)
			(xy 117.425192 -271.559625) (xy 117.44445 -271.514424) (xy 117.470709 -271.472898) (xy 117.50329 -271.436122)
			(xy 117.541348 -271.405048) (xy 117.583898 -271.380482) (xy 117.629837 -271.36306) (xy 117.677977 -271.353232)
			(xy 117.727069 -271.351254) (xy 117.775843 -271.357176) (xy 117.823035 -271.370845) (xy 117.867424 -271.391908)
			(xy 117.907859 -271.419818) (xy 117.943293 -271.453853) (xy 117.972809 -271.493132) (xy 117.995642 -271.536636)
			(xy 118.011201 -271.58324) (xy 118.019082 -271.631736) (xy 118.019576 -271.656302) (xy 119.289334 -271.656302)
			(xy 119.293288 -271.607329) (xy 119.305046 -271.559625) (xy 119.324304 -271.514424) (xy 119.350563 -271.472898)
			(xy 119.383144 -271.436122) (xy 119.421202 -271.405048) (xy 119.463752 -271.380482) (xy 119.509691 -271.36306)
			(xy 119.557831 -271.353232) (xy 119.606923 -271.351254) (xy 119.655697 -271.357176) (xy 119.702889 -271.370845)
			(xy 119.747278 -271.391908) (xy 119.787713 -271.419818) (xy 119.823147 -271.453853) (xy 119.852663 -271.493132)
			(xy 119.875496 -271.536636) (xy 119.891055 -271.58324) (xy 119.898936 -271.631736) (xy 119.89943 -271.656302)
			(xy 120.229388 -271.656302) (xy 120.233342 -271.607329) (xy 120.2451 -271.559625) (xy 120.264358 -271.514424)
			(xy 120.290617 -271.472898) (xy 120.323198 -271.436122) (xy 120.361256 -271.405048) (xy 120.403806 -271.380482)
			(xy 120.449745 -271.36306) (xy 120.497885 -271.353232) (xy 120.546977 -271.351254) (xy 120.595751 -271.357176)
			(xy 120.642943 -271.370845) (xy 120.687332 -271.391908) (xy 120.727767 -271.419818) (xy 120.763201 -271.453853)
			(xy 120.792717 -271.493132) (xy 120.81555 -271.536636) (xy 120.831109 -271.58324) (xy 120.83899 -271.631736)
			(xy 120.839484 -271.656302) (xy 122.109496 -271.656302) (xy 122.11345 -271.607329) (xy 122.125208 -271.559625)
			(xy 122.144466 -271.514424) (xy 122.170725 -271.472898) (xy 122.203306 -271.436122) (xy 122.241364 -271.405048)
			(xy 122.283914 -271.380482) (xy 122.329853 -271.36306) (xy 122.377993 -271.353232) (xy 122.427085 -271.351254)
			(xy 122.475859 -271.357176) (xy 122.523051 -271.370845) (xy 122.56744 -271.391908) (xy 122.607875 -271.419818)
			(xy 122.643309 -271.453853) (xy 122.672825 -271.493132) (xy 122.695658 -271.536636) (xy 122.711217 -271.58324)
			(xy 122.719098 -271.631736) (xy 122.719592 -271.656302) (xy 123.04955 -271.656302) (xy 123.053504 -271.607329)
			(xy 123.065262 -271.559625) (xy 123.08452 -271.514424) (xy 123.110779 -271.472898) (xy 123.14336 -271.436122)
			(xy 123.181418 -271.405048) (xy 123.223968 -271.380482) (xy 123.269907 -271.36306) (xy 123.318047 -271.353232)
			(xy 123.367139 -271.351254) (xy 123.415913 -271.357176) (xy 123.463105 -271.370845) (xy 123.507494 -271.391908)
			(xy 123.547929 -271.419818) (xy 123.583363 -271.453853) (xy 123.612879 -271.493132) (xy 123.635712 -271.536636)
			(xy 123.651271 -271.58324) (xy 123.659152 -271.631736) (xy 123.659646 -271.656302) (xy 124.929404 -271.656302)
			(xy 124.933358 -271.607329) (xy 124.945116 -271.559625) (xy 124.964374 -271.514424) (xy 124.990633 -271.472898)
			(xy 125.023214 -271.436122) (xy 125.061272 -271.405048) (xy 125.103822 -271.380482) (xy 125.149761 -271.36306)
			(xy 125.197901 -271.353232) (xy 125.246993 -271.351254) (xy 125.295767 -271.357176) (xy 125.342959 -271.370845)
			(xy 125.387348 -271.391908) (xy 125.427783 -271.419818) (xy 125.463217 -271.453853) (xy 125.492733 -271.493132)
			(xy 125.515566 -271.536636) (xy 125.531125 -271.58324) (xy 125.539006 -271.631736) (xy 125.5395 -271.656302)
			(xy 125.869458 -271.656302) (xy 125.873412 -271.607329) (xy 125.88517 -271.559625) (xy 125.904428 -271.514424)
			(xy 125.930687 -271.472898) (xy 125.963268 -271.436122) (xy 126.001326 -271.405048) (xy 126.043876 -271.380482)
			(xy 126.089815 -271.36306) (xy 126.137955 -271.353232) (xy 126.187047 -271.351254) (xy 126.235821 -271.357176)
			(xy 126.283013 -271.370845) (xy 126.327402 -271.391908) (xy 126.367837 -271.419818) (xy 126.403271 -271.453853)
			(xy 126.432787 -271.493132) (xy 126.45562 -271.536636) (xy 126.471179 -271.58324) (xy 126.47906 -271.631736)
			(xy 126.479549 -271.656048) (xy 345.61578 -271.656048) (xy 345.619734 -271.607075) (xy 345.631492 -271.559371)
			(xy 345.65075 -271.51417) (xy 345.677009 -271.472644) (xy 345.70959 -271.435868) (xy 345.747648 -271.404794)
			(xy 345.790198 -271.380228) (xy 345.836137 -271.362806) (xy 345.884277 -271.352978) (xy 345.933369 -271.351)
			(xy 345.982143 -271.356922) (xy 346.029335 -271.370591) (xy 346.073724 -271.391654) (xy 346.114159 -271.419564)
			(xy 346.149593 -271.453599) (xy 346.179109 -271.492878) (xy 346.201942 -271.536382) (xy 346.217501 -271.582986)
			(xy 346.225382 -271.631482) (xy 346.225876 -271.656048) (xy 346.555834 -271.656048) (xy 346.559788 -271.607075)
			(xy 346.571546 -271.559371) (xy 346.590804 -271.51417) (xy 346.617063 -271.472644) (xy 346.649644 -271.435868)
			(xy 346.687702 -271.404794) (xy 346.730252 -271.380228) (xy 346.776191 -271.362806) (xy 346.824331 -271.352978)
			(xy 346.873423 -271.351) (xy 346.922197 -271.356922) (xy 346.969389 -271.370591) (xy 347.013778 -271.391654)
			(xy 347.054213 -271.419564) (xy 347.089647 -271.453599) (xy 347.119163 -271.492878) (xy 347.141996 -271.536382)
			(xy 347.157555 -271.582986) (xy 347.165436 -271.631482) (xy 347.16593 -271.656048) (xy 348.435688 -271.656048)
			(xy 348.439642 -271.607075) (xy 348.4514 -271.559371) (xy 348.470658 -271.51417) (xy 348.496917 -271.472644)
			(xy 348.529498 -271.435868) (xy 348.567556 -271.404794) (xy 348.610106 -271.380228) (xy 348.656045 -271.362806)
			(xy 348.704185 -271.352978) (xy 348.753277 -271.351) (xy 348.802051 -271.356922) (xy 348.849243 -271.370591)
			(xy 348.893632 -271.391654) (xy 348.934067 -271.419564) (xy 348.969501 -271.453599) (xy 348.999017 -271.492878)
			(xy 349.02185 -271.536382) (xy 349.037409 -271.582986) (xy 349.04529 -271.631482) (xy 349.045784 -271.656048)
			(xy 349.375742 -271.656048) (xy 349.379696 -271.607075) (xy 349.391454 -271.559371) (xy 349.410712 -271.51417)
			(xy 349.436971 -271.472644) (xy 349.469552 -271.435868) (xy 349.50761 -271.404794) (xy 349.55016 -271.380228)
			(xy 349.596099 -271.362806) (xy 349.644239 -271.352978) (xy 349.693331 -271.351) (xy 349.742105 -271.356922)
			(xy 349.789297 -271.370591) (xy 349.833686 -271.391654) (xy 349.874121 -271.419564) (xy 349.909555 -271.453599)
			(xy 349.939071 -271.492878) (xy 349.961904 -271.536382) (xy 349.977463 -271.582986) (xy 349.985344 -271.631482)
			(xy 349.985838 -271.656048) (xy 351.25585 -271.656048) (xy 351.259804 -271.607075) (xy 351.271562 -271.559371)
			(xy 351.29082 -271.51417) (xy 351.317079 -271.472644) (xy 351.34966 -271.435868) (xy 351.387718 -271.404794)
			(xy 351.430268 -271.380228) (xy 351.476207 -271.362806) (xy 351.524347 -271.352978) (xy 351.573439 -271.351)
			(xy 351.622213 -271.356922) (xy 351.669405 -271.370591) (xy 351.713794 -271.391654) (xy 351.754229 -271.419564)
			(xy 351.789663 -271.453599) (xy 351.819179 -271.492878) (xy 351.842012 -271.536382) (xy 351.857571 -271.582986)
			(xy 351.865452 -271.631482) (xy 351.865946 -271.656048) (xy 352.195904 -271.656048) (xy 352.199858 -271.607075)
			(xy 352.211616 -271.559371) (xy 352.230874 -271.51417) (xy 352.257133 -271.472644) (xy 352.289714 -271.435868)
			(xy 352.327772 -271.404794) (xy 352.370322 -271.380228) (xy 352.416261 -271.362806) (xy 352.464401 -271.352978)
			(xy 352.513493 -271.351) (xy 352.562267 -271.356922) (xy 352.609459 -271.370591) (xy 352.653848 -271.391654)
			(xy 352.694283 -271.419564) (xy 352.729717 -271.453599) (xy 352.759233 -271.492878) (xy 352.782066 -271.536382)
			(xy 352.797625 -271.582986) (xy 352.805506 -271.631482) (xy 352.806 -271.656048) (xy 354.075758 -271.656048)
			(xy 354.079712 -271.607075) (xy 354.09147 -271.559371) (xy 354.110728 -271.51417) (xy 354.136987 -271.472644)
			(xy 354.169568 -271.435868) (xy 354.207626 -271.404794) (xy 354.250176 -271.380228) (xy 354.296115 -271.362806)
			(xy 354.344255 -271.352978) (xy 354.393347 -271.351) (xy 354.442121 -271.356922) (xy 354.489313 -271.370591)
			(xy 354.533702 -271.391654) (xy 354.574137 -271.419564) (xy 354.609571 -271.453599) (xy 354.639087 -271.492878)
			(xy 354.66192 -271.536382) (xy 354.677479 -271.582986) (xy 354.68536 -271.631482) (xy 354.685854 -271.656048)
			(xy 355.015812 -271.656048) (xy 355.019766 -271.607075) (xy 355.031524 -271.559371) (xy 355.050782 -271.51417)
			(xy 355.077041 -271.472644) (xy 355.109622 -271.435868) (xy 355.14768 -271.404794) (xy 355.19023 -271.380228)
			(xy 355.236169 -271.362806) (xy 355.284309 -271.352978) (xy 355.333401 -271.351) (xy 355.382175 -271.356922)
			(xy 355.429367 -271.370591) (xy 355.473756 -271.391654) (xy 355.514191 -271.419564) (xy 355.549625 -271.453599)
			(xy 355.579141 -271.492878) (xy 355.601974 -271.536382) (xy 355.617533 -271.582986) (xy 355.625414 -271.631482)
			(xy 355.625908 -271.656048) (xy 364.409494 -271.656048) (xy 364.413448 -271.607075) (xy 364.425206 -271.559371)
			(xy 364.444464 -271.51417) (xy 364.470723 -271.472644) (xy 364.503304 -271.435868) (xy 364.541362 -271.404794)
			(xy 364.583912 -271.380228) (xy 364.629851 -271.362806) (xy 364.677991 -271.352978) (xy 364.727083 -271.351)
			(xy 364.775857 -271.356922) (xy 364.823049 -271.370591) (xy 364.867438 -271.391654) (xy 364.907873 -271.419564)
			(xy 364.943307 -271.453599) (xy 364.972823 -271.492878) (xy 364.995656 -271.536382) (xy 365.011215 -271.582986)
			(xy 365.019096 -271.631482) (xy 365.01959 -271.656048) (xy 365.349548 -271.656048) (xy 365.353502 -271.607075)
			(xy 365.36526 -271.559371) (xy 365.384518 -271.51417) (xy 365.410777 -271.472644) (xy 365.443358 -271.435868)
			(xy 365.481416 -271.404794) (xy 365.523966 -271.380228) (xy 365.569905 -271.362806) (xy 365.618045 -271.352978)
			(xy 365.667137 -271.351) (xy 365.715911 -271.356922) (xy 365.763103 -271.370591) (xy 365.807492 -271.391654)
			(xy 365.847927 -271.419564) (xy 365.883361 -271.453599) (xy 365.912877 -271.492878) (xy 365.93571 -271.536382)
			(xy 365.951269 -271.582986) (xy 365.95915 -271.631482) (xy 365.959644 -271.656048) (xy 367.229402 -271.656048)
			(xy 367.233356 -271.607075) (xy 367.245114 -271.559371) (xy 367.264372 -271.51417) (xy 367.290631 -271.472644)
			(xy 367.323212 -271.435868) (xy 367.36127 -271.404794) (xy 367.40382 -271.380228) (xy 367.449759 -271.362806)
			(xy 367.497899 -271.352978) (xy 367.546991 -271.351) (xy 367.595765 -271.356922) (xy 367.642957 -271.370591)
			(xy 367.687346 -271.391654) (xy 367.727781 -271.419564) (xy 367.763215 -271.453599) (xy 367.792731 -271.492878)
			(xy 367.815564 -271.536382) (xy 367.831123 -271.582986) (xy 367.839004 -271.631482) (xy 367.839498 -271.656048)
			(xy 368.169456 -271.656048) (xy 368.17341 -271.607075) (xy 368.185168 -271.559371) (xy 368.204426 -271.51417)
			(xy 368.230685 -271.472644) (xy 368.263266 -271.435868) (xy 368.301324 -271.404794) (xy 368.343874 -271.380228)
			(xy 368.389813 -271.362806) (xy 368.437953 -271.352978) (xy 368.487045 -271.351) (xy 368.535819 -271.356922)
			(xy 368.583011 -271.370591) (xy 368.6274 -271.391654) (xy 368.667835 -271.419564) (xy 368.703269 -271.453599)
			(xy 368.732785 -271.492878) (xy 368.755618 -271.536382) (xy 368.771177 -271.582986) (xy 368.779058 -271.631482)
			(xy 368.779552 -271.656048) (xy 370.049564 -271.656048) (xy 370.053518 -271.607075) (xy 370.065276 -271.559371)
			(xy 370.084534 -271.51417) (xy 370.110793 -271.472644) (xy 370.143374 -271.435868) (xy 370.181432 -271.404794)
			(xy 370.223982 -271.380228) (xy 370.269921 -271.362806) (xy 370.318061 -271.352978) (xy 370.367153 -271.351)
			(xy 370.415927 -271.356922) (xy 370.463119 -271.370591) (xy 370.507508 -271.391654) (xy 370.547943 -271.419564)
			(xy 370.583377 -271.453599) (xy 370.612893 -271.492878) (xy 370.635726 -271.536382) (xy 370.651285 -271.582986)
			(xy 370.659166 -271.631482) (xy 370.65966 -271.656048) (xy 370.989618 -271.656048) (xy 370.993572 -271.607075)
			(xy 371.00533 -271.559371) (xy 371.024588 -271.51417) (xy 371.050847 -271.472644) (xy 371.083428 -271.435868)
			(xy 371.121486 -271.404794) (xy 371.164036 -271.380228) (xy 371.209975 -271.362806) (xy 371.258115 -271.352978)
			(xy 371.307207 -271.351) (xy 371.355981 -271.356922) (xy 371.403173 -271.370591) (xy 371.447562 -271.391654)
			(xy 371.487997 -271.419564) (xy 371.523431 -271.453599) (xy 371.552947 -271.492878) (xy 371.57578 -271.536382)
			(xy 371.591339 -271.582986) (xy 371.59922 -271.631482) (xy 371.599714 -271.656048) (xy 372.869472 -271.656048)
			(xy 372.873426 -271.607075) (xy 372.885184 -271.559371) (xy 372.904442 -271.51417) (xy 372.930701 -271.472644)
			(xy 372.963282 -271.435868) (xy 373.00134 -271.404794) (xy 373.04389 -271.380228) (xy 373.089829 -271.362806)
			(xy 373.137969 -271.352978) (xy 373.187061 -271.351) (xy 373.235835 -271.356922) (xy 373.283027 -271.370591)
			(xy 373.327416 -271.391654) (xy 373.367851 -271.419564) (xy 373.403285 -271.453599) (xy 373.432801 -271.492878)
			(xy 373.455634 -271.536382) (xy 373.471193 -271.582986) (xy 373.479074 -271.631482) (xy 373.479568 -271.656048)
			(xy 373.809526 -271.656048) (xy 373.81348 -271.607075) (xy 373.825238 -271.559371) (xy 373.844496 -271.51417)
			(xy 373.870755 -271.472644) (xy 373.903336 -271.435868) (xy 373.941394 -271.404794) (xy 373.983944 -271.380228)
			(xy 374.029883 -271.362806) (xy 374.078023 -271.352978) (xy 374.127115 -271.351) (xy 374.175889 -271.356922)
			(xy 374.223081 -271.370591) (xy 374.26747 -271.391654) (xy 374.307905 -271.419564) (xy 374.343339 -271.453599)
			(xy 374.372855 -271.492878) (xy 374.395688 -271.536382) (xy 374.411247 -271.582986) (xy 374.419128 -271.631482)
			(xy 374.419622 -271.656048) (xy 374.419128 -271.680614) (xy 374.411247 -271.72911) (xy 374.395688 -271.775714)
			(xy 374.372855 -271.819218) (xy 374.343339 -271.858497) (xy 374.307905 -271.892532) (xy 374.26747 -271.920442)
			(xy 374.223081 -271.941505) (xy 374.175889 -271.955174) (xy 374.127115 -271.961096) (xy 374.078023 -271.959118)
			(xy 374.029883 -271.94929) (xy 373.983944 -271.931868) (xy 373.941394 -271.907302) (xy 373.903336 -271.876228)
			(xy 373.870755 -271.839452) (xy 373.844496 -271.797926) (xy 373.825238 -271.752725) (xy 373.81348 -271.705021)
			(xy 373.809526 -271.656048) (xy 373.479568 -271.656048) (xy 373.479074 -271.680614) (xy 373.471193 -271.72911)
			(xy 373.455634 -271.775714) (xy 373.432801 -271.819218) (xy 373.403285 -271.858497) (xy 373.367851 -271.892532)
			(xy 373.327416 -271.920442) (xy 373.283027 -271.941505) (xy 373.235835 -271.955174) (xy 373.187061 -271.961096)
			(xy 373.137969 -271.959118) (xy 373.089829 -271.94929) (xy 373.04389 -271.931868) (xy 373.00134 -271.907302)
			(xy 372.963282 -271.876228) (xy 372.930701 -271.839452) (xy 372.904442 -271.797926) (xy 372.885184 -271.752725)
			(xy 372.873426 -271.705021) (xy 372.869472 -271.656048) (xy 371.599714 -271.656048) (xy 371.59922 -271.680614)
			(xy 371.591339 -271.72911) (xy 371.57578 -271.775714) (xy 371.552947 -271.819218) (xy 371.523431 -271.858497)
			(xy 371.487997 -271.892532) (xy 371.447562 -271.920442) (xy 371.403173 -271.941505) (xy 371.355981 -271.955174)
			(xy 371.307207 -271.961096) (xy 371.258115 -271.959118) (xy 371.209975 -271.94929) (xy 371.164036 -271.931868)
			(xy 371.121486 -271.907302) (xy 371.083428 -271.876228) (xy 371.050847 -271.839452) (xy 371.024588 -271.797926)
			(xy 371.00533 -271.752725) (xy 370.993572 -271.705021) (xy 370.989618 -271.656048) (xy 370.65966 -271.656048)
			(xy 370.659166 -271.680614) (xy 370.651285 -271.72911) (xy 370.635726 -271.775714) (xy 370.612893 -271.819218)
			(xy 370.583377 -271.858497) (xy 370.547943 -271.892532) (xy 370.507508 -271.920442) (xy 370.463119 -271.941505)
			(xy 370.415927 -271.955174) (xy 370.367153 -271.961096) (xy 370.318061 -271.959118) (xy 370.269921 -271.94929)
			(xy 370.223982 -271.931868) (xy 370.181432 -271.907302) (xy 370.143374 -271.876228) (xy 370.110793 -271.839452)
			(xy 370.084534 -271.797926) (xy 370.065276 -271.752725) (xy 370.053518 -271.705021) (xy 370.049564 -271.656048)
			(xy 368.779552 -271.656048) (xy 368.779058 -271.680614) (xy 368.771177 -271.72911) (xy 368.755618 -271.775714)
			(xy 368.732785 -271.819218) (xy 368.703269 -271.858497) (xy 368.667835 -271.892532) (xy 368.6274 -271.920442)
			(xy 368.583011 -271.941505) (xy 368.535819 -271.955174) (xy 368.487045 -271.961096) (xy 368.437953 -271.959118)
			(xy 368.389813 -271.94929) (xy 368.343874 -271.931868) (xy 368.301324 -271.907302) (xy 368.263266 -271.876228)
			(xy 368.230685 -271.839452) (xy 368.204426 -271.797926) (xy 368.185168 -271.752725) (xy 368.17341 -271.705021)
			(xy 368.169456 -271.656048) (xy 367.839498 -271.656048) (xy 367.839004 -271.680614) (xy 367.831123 -271.72911)
			(xy 367.815564 -271.775714) (xy 367.792731 -271.819218) (xy 367.763215 -271.858497) (xy 367.727781 -271.892532)
			(xy 367.687346 -271.920442) (xy 367.642957 -271.941505) (xy 367.595765 -271.955174) (xy 367.546991 -271.961096)
			(xy 367.497899 -271.959118) (xy 367.449759 -271.94929) (xy 367.40382 -271.931868) (xy 367.36127 -271.907302)
			(xy 367.323212 -271.876228) (xy 367.290631 -271.839452) (xy 367.264372 -271.797926) (xy 367.245114 -271.752725)
			(xy 367.233356 -271.705021) (xy 367.229402 -271.656048) (xy 365.959644 -271.656048) (xy 365.95915 -271.680614)
			(xy 365.951269 -271.72911) (xy 365.93571 -271.775714) (xy 365.912877 -271.819218) (xy 365.883361 -271.858497)
			(xy 365.847927 -271.892532) (xy 365.807492 -271.920442) (xy 365.763103 -271.941505) (xy 365.715911 -271.955174)
			(xy 365.667137 -271.961096) (xy 365.618045 -271.959118) (xy 365.569905 -271.94929) (xy 365.523966 -271.931868)
			(xy 365.481416 -271.907302) (xy 365.443358 -271.876228) (xy 365.410777 -271.839452) (xy 365.384518 -271.797926)
			(xy 365.36526 -271.752725) (xy 365.353502 -271.705021) (xy 365.349548 -271.656048) (xy 365.01959 -271.656048)
			(xy 365.019096 -271.680614) (xy 365.011215 -271.72911) (xy 364.995656 -271.775714) (xy 364.972823 -271.819218)
			(xy 364.943307 -271.858497) (xy 364.907873 -271.892532) (xy 364.867438 -271.920442) (xy 364.823049 -271.941505)
			(xy 364.775857 -271.955174) (xy 364.727083 -271.961096) (xy 364.677991 -271.959118) (xy 364.629851 -271.94929)
			(xy 364.583912 -271.931868) (xy 364.541362 -271.907302) (xy 364.503304 -271.876228) (xy 364.470723 -271.839452)
			(xy 364.444464 -271.797926) (xy 364.425206 -271.752725) (xy 364.413448 -271.705021) (xy 364.409494 -271.656048)
			(xy 355.625908 -271.656048) (xy 355.625414 -271.680614) (xy 355.617533 -271.72911) (xy 355.601974 -271.775714)
			(xy 355.579141 -271.819218) (xy 355.549625 -271.858497) (xy 355.514191 -271.892532) (xy 355.473756 -271.920442)
			(xy 355.429367 -271.941505) (xy 355.382175 -271.955174) (xy 355.333401 -271.961096) (xy 355.284309 -271.959118)
			(xy 355.236169 -271.94929) (xy 355.19023 -271.931868) (xy 355.14768 -271.907302) (xy 355.109622 -271.876228)
			(xy 355.077041 -271.839452) (xy 355.050782 -271.797926) (xy 355.031524 -271.752725) (xy 355.019766 -271.705021)
			(xy 355.015812 -271.656048) (xy 354.685854 -271.656048) (xy 354.68536 -271.680614) (xy 354.677479 -271.72911)
			(xy 354.66192 -271.775714) (xy 354.639087 -271.819218) (xy 354.609571 -271.858497) (xy 354.574137 -271.892532)
			(xy 354.533702 -271.920442) (xy 354.489313 -271.941505) (xy 354.442121 -271.955174) (xy 354.393347 -271.961096)
			(xy 354.344255 -271.959118) (xy 354.296115 -271.94929) (xy 354.250176 -271.931868) (xy 354.207626 -271.907302)
			(xy 354.169568 -271.876228) (xy 354.136987 -271.839452) (xy 354.110728 -271.797926) (xy 354.09147 -271.752725)
			(xy 354.079712 -271.705021) (xy 354.075758 -271.656048) (xy 352.806 -271.656048) (xy 352.805506 -271.680614)
			(xy 352.797625 -271.72911) (xy 352.782066 -271.775714) (xy 352.759233 -271.819218) (xy 352.729717 -271.858497)
			(xy 352.694283 -271.892532) (xy 352.653848 -271.920442) (xy 352.609459 -271.941505) (xy 352.562267 -271.955174)
			(xy 352.513493 -271.961096) (xy 352.464401 -271.959118) (xy 352.416261 -271.94929) (xy 352.370322 -271.931868)
			(xy 352.327772 -271.907302) (xy 352.289714 -271.876228) (xy 352.257133 -271.839452) (xy 352.230874 -271.797926)
			(xy 352.211616 -271.752725) (xy 352.199858 -271.705021) (xy 352.195904 -271.656048) (xy 351.865946 -271.656048)
			(xy 351.865452 -271.680614) (xy 351.857571 -271.72911) (xy 351.842012 -271.775714) (xy 351.819179 -271.819218)
			(xy 351.789663 -271.858497) (xy 351.754229 -271.892532) (xy 351.713794 -271.920442) (xy 351.669405 -271.941505)
			(xy 351.622213 -271.955174) (xy 351.573439 -271.961096) (xy 351.524347 -271.959118) (xy 351.476207 -271.94929)
			(xy 351.430268 -271.931868) (xy 351.387718 -271.907302) (xy 351.34966 -271.876228) (xy 351.317079 -271.839452)
			(xy 351.29082 -271.797926) (xy 351.271562 -271.752725) (xy 351.259804 -271.705021) (xy 351.25585 -271.656048)
			(xy 349.985838 -271.656048) (xy 349.985344 -271.680614) (xy 349.977463 -271.72911) (xy 349.961904 -271.775714)
			(xy 349.939071 -271.819218) (xy 349.909555 -271.858497) (xy 349.874121 -271.892532) (xy 349.833686 -271.920442)
			(xy 349.789297 -271.941505) (xy 349.742105 -271.955174) (xy 349.693331 -271.961096) (xy 349.644239 -271.959118)
			(xy 349.596099 -271.94929) (xy 349.55016 -271.931868) (xy 349.50761 -271.907302) (xy 349.469552 -271.876228)
			(xy 349.436971 -271.839452) (xy 349.410712 -271.797926) (xy 349.391454 -271.752725) (xy 349.379696 -271.705021)
			(xy 349.375742 -271.656048) (xy 349.045784 -271.656048) (xy 349.04529 -271.680614) (xy 349.037409 -271.72911)
			(xy 349.02185 -271.775714) (xy 348.999017 -271.819218) (xy 348.969501 -271.858497) (xy 348.934067 -271.892532)
			(xy 348.893632 -271.920442) (xy 348.849243 -271.941505) (xy 348.802051 -271.955174) (xy 348.753277 -271.961096)
			(xy 348.704185 -271.959118) (xy 348.656045 -271.94929) (xy 348.610106 -271.931868) (xy 348.567556 -271.907302)
			(xy 348.529498 -271.876228) (xy 348.496917 -271.839452) (xy 348.470658 -271.797926) (xy 348.4514 -271.752725)
			(xy 348.439642 -271.705021) (xy 348.435688 -271.656048) (xy 347.16593 -271.656048) (xy 347.165436 -271.680614)
			(xy 347.157555 -271.72911) (xy 347.141996 -271.775714) (xy 347.119163 -271.819218) (xy 347.089647 -271.858497)
			(xy 347.054213 -271.892532) (xy 347.013778 -271.920442) (xy 346.969389 -271.941505) (xy 346.922197 -271.955174)
			(xy 346.873423 -271.961096) (xy 346.824331 -271.959118) (xy 346.776191 -271.94929) (xy 346.730252 -271.931868)
			(xy 346.687702 -271.907302) (xy 346.649644 -271.876228) (xy 346.617063 -271.839452) (xy 346.590804 -271.797926)
			(xy 346.571546 -271.752725) (xy 346.559788 -271.705021) (xy 346.555834 -271.656048) (xy 346.225876 -271.656048)
			(xy 346.225382 -271.680614) (xy 346.217501 -271.72911) (xy 346.201942 -271.775714) (xy 346.179109 -271.819218)
			(xy 346.149593 -271.858497) (xy 346.114159 -271.892532) (xy 346.073724 -271.920442) (xy 346.029335 -271.941505)
			(xy 345.982143 -271.955174) (xy 345.933369 -271.961096) (xy 345.884277 -271.959118) (xy 345.836137 -271.94929)
			(xy 345.790198 -271.931868) (xy 345.747648 -271.907302) (xy 345.70959 -271.876228) (xy 345.677009 -271.839452)
			(xy 345.65075 -271.797926) (xy 345.631492 -271.752725) (xy 345.619734 -271.705021) (xy 345.61578 -271.656048)
			(xy 126.479549 -271.656048) (xy 126.479554 -271.656302) (xy 126.47906 -271.680868) (xy 126.471179 -271.729364)
			(xy 126.45562 -271.775968) (xy 126.432787 -271.819472) (xy 126.403271 -271.858751) (xy 126.367837 -271.892786)
			(xy 126.327402 -271.920696) (xy 126.283013 -271.941759) (xy 126.235821 -271.955428) (xy 126.187047 -271.96135)
			(xy 126.137955 -271.959372) (xy 126.089815 -271.949544) (xy 126.043876 -271.932122) (xy 126.001326 -271.907556)
			(xy 125.963268 -271.876482) (xy 125.930687 -271.839706) (xy 125.904428 -271.79818) (xy 125.88517 -271.752979)
			(xy 125.873412 -271.705275) (xy 125.869458 -271.656302) (xy 125.5395 -271.656302) (xy 125.539006 -271.680868)
			(xy 125.531125 -271.729364) (xy 125.515566 -271.775968) (xy 125.492733 -271.819472) (xy 125.463217 -271.858751)
			(xy 125.427783 -271.892786) (xy 125.387348 -271.920696) (xy 125.342959 -271.941759) (xy 125.295767 -271.955428)
			(xy 125.246993 -271.96135) (xy 125.197901 -271.959372) (xy 125.149761 -271.949544) (xy 125.103822 -271.932122)
			(xy 125.061272 -271.907556) (xy 125.023214 -271.876482) (xy 124.990633 -271.839706) (xy 124.964374 -271.79818)
			(xy 124.945116 -271.752979) (xy 124.933358 -271.705275) (xy 124.929404 -271.656302) (xy 123.659646 -271.656302)
			(xy 123.659152 -271.680868) (xy 123.651271 -271.729364) (xy 123.635712 -271.775968) (xy 123.612879 -271.819472)
			(xy 123.583363 -271.858751) (xy 123.547929 -271.892786) (xy 123.507494 -271.920696) (xy 123.463105 -271.941759)
			(xy 123.415913 -271.955428) (xy 123.367139 -271.96135) (xy 123.318047 -271.959372) (xy 123.269907 -271.949544)
			(xy 123.223968 -271.932122) (xy 123.181418 -271.907556) (xy 123.14336 -271.876482) (xy 123.110779 -271.839706)
			(xy 123.08452 -271.79818) (xy 123.065262 -271.752979) (xy 123.053504 -271.705275) (xy 123.04955 -271.656302)
			(xy 122.719592 -271.656302) (xy 122.719098 -271.680868) (xy 122.711217 -271.729364) (xy 122.695658 -271.775968)
			(xy 122.672825 -271.819472) (xy 122.643309 -271.858751) (xy 122.607875 -271.892786) (xy 122.56744 -271.920696)
			(xy 122.523051 -271.941759) (xy 122.475859 -271.955428) (xy 122.427085 -271.96135) (xy 122.377993 -271.959372)
			(xy 122.329853 -271.949544) (xy 122.283914 -271.932122) (xy 122.241364 -271.907556) (xy 122.203306 -271.876482)
			(xy 122.170725 -271.839706) (xy 122.144466 -271.79818) (xy 122.125208 -271.752979) (xy 122.11345 -271.705275)
			(xy 122.109496 -271.656302) (xy 120.839484 -271.656302) (xy 120.83899 -271.680868) (xy 120.831109 -271.729364)
			(xy 120.81555 -271.775968) (xy 120.792717 -271.819472) (xy 120.763201 -271.858751) (xy 120.727767 -271.892786)
			(xy 120.687332 -271.920696) (xy 120.642943 -271.941759) (xy 120.595751 -271.955428) (xy 120.546977 -271.96135)
			(xy 120.497885 -271.959372) (xy 120.449745 -271.949544) (xy 120.403806 -271.932122) (xy 120.361256 -271.907556)
			(xy 120.323198 -271.876482) (xy 120.290617 -271.839706) (xy 120.264358 -271.79818) (xy 120.2451 -271.752979)
			(xy 120.233342 -271.705275) (xy 120.229388 -271.656302) (xy 119.89943 -271.656302) (xy 119.898936 -271.680868)
			(xy 119.891055 -271.729364) (xy 119.875496 -271.775968) (xy 119.852663 -271.819472) (xy 119.823147 -271.858751)
			(xy 119.787713 -271.892786) (xy 119.747278 -271.920696) (xy 119.702889 -271.941759) (xy 119.655697 -271.955428)
			(xy 119.606923 -271.96135) (xy 119.557831 -271.959372) (xy 119.509691 -271.949544) (xy 119.463752 -271.932122)
			(xy 119.421202 -271.907556) (xy 119.383144 -271.876482) (xy 119.350563 -271.839706) (xy 119.324304 -271.79818)
			(xy 119.305046 -271.752979) (xy 119.293288 -271.705275) (xy 119.289334 -271.656302) (xy 118.019576 -271.656302)
			(xy 118.019082 -271.680868) (xy 118.011201 -271.729364) (xy 117.995642 -271.775968) (xy 117.972809 -271.819472)
			(xy 117.943293 -271.858751) (xy 117.907859 -271.892786) (xy 117.867424 -271.920696) (xy 117.823035 -271.941759)
			(xy 117.775843 -271.955428) (xy 117.727069 -271.96135) (xy 117.677977 -271.959372) (xy 117.629837 -271.949544)
			(xy 117.583898 -271.932122) (xy 117.541348 -271.907556) (xy 117.50329 -271.876482) (xy 117.470709 -271.839706)
			(xy 117.44445 -271.79818) (xy 117.425192 -271.752979) (xy 117.413434 -271.705275) (xy 117.40948 -271.656302)
			(xy 117.079522 -271.656302) (xy 117.079028 -271.680868) (xy 117.071147 -271.729364) (xy 117.055588 -271.775968)
			(xy 117.032755 -271.819472) (xy 117.003239 -271.858751) (xy 116.967805 -271.892786) (xy 116.92737 -271.920696)
			(xy 116.882981 -271.941759) (xy 116.835789 -271.955428) (xy 116.787015 -271.96135) (xy 116.737923 -271.959372)
			(xy 116.689783 -271.949544) (xy 116.643844 -271.932122) (xy 116.601294 -271.907556) (xy 116.563236 -271.876482)
			(xy 116.530655 -271.839706) (xy 116.504396 -271.79818) (xy 116.485138 -271.752979) (xy 116.47338 -271.705275)
			(xy 116.469426 -271.656302) (xy 107.68584 -271.656302) (xy 107.685346 -271.680868) (xy 107.677465 -271.729364)
			(xy 107.661906 -271.775968) (xy 107.639073 -271.819472) (xy 107.609557 -271.858751) (xy 107.574123 -271.892786)
			(xy 107.533688 -271.920696) (xy 107.489299 -271.941759) (xy 107.442107 -271.955428) (xy 107.393333 -271.96135)
			(xy 107.344241 -271.959372) (xy 107.296101 -271.949544) (xy 107.250162 -271.932122) (xy 107.207612 -271.907556)
			(xy 107.169554 -271.876482) (xy 107.136973 -271.839706) (xy 107.110714 -271.79818) (xy 107.091456 -271.752979)
			(xy 107.079698 -271.705275) (xy 107.075744 -271.656302) (xy 106.745786 -271.656302) (xy 106.745292 -271.680868)
			(xy 106.737411 -271.729364) (xy 106.721852 -271.775968) (xy 106.699019 -271.819472) (xy 106.669503 -271.858751)
			(xy 106.634069 -271.892786) (xy 106.593634 -271.920696) (xy 106.549245 -271.941759) (xy 106.502053 -271.955428)
			(xy 106.453279 -271.96135) (xy 106.404187 -271.959372) (xy 106.356047 -271.949544) (xy 106.310108 -271.932122)
			(xy 106.267558 -271.907556) (xy 106.2295 -271.876482) (xy 106.196919 -271.839706) (xy 106.17066 -271.79818)
			(xy 106.151402 -271.752979) (xy 106.139644 -271.705275) (xy 106.13569 -271.656302) (xy 104.865932 -271.656302)
			(xy 104.865438 -271.680868) (xy 104.857557 -271.729364) (xy 104.841998 -271.775968) (xy 104.819165 -271.819472)
			(xy 104.789649 -271.858751) (xy 104.754215 -271.892786) (xy 104.71378 -271.920696) (xy 104.669391 -271.941759)
			(xy 104.622199 -271.955428) (xy 104.573425 -271.96135) (xy 104.524333 -271.959372) (xy 104.476193 -271.949544)
			(xy 104.430254 -271.932122) (xy 104.387704 -271.907556) (xy 104.349646 -271.876482) (xy 104.317065 -271.839706)
			(xy 104.290806 -271.79818) (xy 104.271548 -271.752979) (xy 104.25979 -271.705275) (xy 104.255836 -271.656302)
			(xy 103.925878 -271.656302) (xy 103.925384 -271.680868) (xy 103.917503 -271.729364) (xy 103.901944 -271.775968)
			(xy 103.879111 -271.819472) (xy 103.849595 -271.858751) (xy 103.814161 -271.892786) (xy 103.773726 -271.920696)
			(xy 103.729337 -271.941759) (xy 103.682145 -271.955428) (xy 103.633371 -271.96135) (xy 103.584279 -271.959372)
			(xy 103.536139 -271.949544) (xy 103.4902 -271.932122) (xy 103.44765 -271.907556) (xy 103.409592 -271.876482)
			(xy 103.377011 -271.839706) (xy 103.350752 -271.79818) (xy 103.331494 -271.752979) (xy 103.319736 -271.705275)
			(xy 103.315782 -271.656302) (xy 102.04577 -271.656302) (xy 102.045276 -271.680868) (xy 102.037395 -271.729364)
			(xy 102.021836 -271.775968) (xy 101.999003 -271.819472) (xy 101.969487 -271.858751) (xy 101.934053 -271.892786)
			(xy 101.893618 -271.920696) (xy 101.849229 -271.941759) (xy 101.802037 -271.955428) (xy 101.753263 -271.96135)
			(xy 101.704171 -271.959372) (xy 101.656031 -271.949544) (xy 101.610092 -271.932122) (xy 101.567542 -271.907556)
			(xy 101.529484 -271.876482) (xy 101.496903 -271.839706) (xy 101.470644 -271.79818) (xy 101.451386 -271.752979)
			(xy 101.439628 -271.705275) (xy 101.435674 -271.656302) (xy 101.105716 -271.656302) (xy 101.105222 -271.680868)
			(xy 101.097341 -271.729364) (xy 101.081782 -271.775968) (xy 101.058949 -271.819472) (xy 101.029433 -271.858751)
			(xy 100.993999 -271.892786) (xy 100.953564 -271.920696) (xy 100.909175 -271.941759) (xy 100.861983 -271.955428)
			(xy 100.813209 -271.96135) (xy 100.764117 -271.959372) (xy 100.715977 -271.949544) (xy 100.670038 -271.932122)
			(xy 100.627488 -271.907556) (xy 100.58943 -271.876482) (xy 100.556849 -271.839706) (xy 100.53059 -271.79818)
			(xy 100.511332 -271.752979) (xy 100.499574 -271.705275) (xy 100.49562 -271.656302) (xy 99.225862 -271.656302)
			(xy 99.225368 -271.680868) (xy 99.217487 -271.729364) (xy 99.201928 -271.775968) (xy 99.179095 -271.819472)
			(xy 99.149579 -271.858751) (xy 99.114145 -271.892786) (xy 99.07371 -271.920696) (xy 99.029321 -271.941759)
			(xy 98.982129 -271.955428) (xy 98.933355 -271.96135) (xy 98.884263 -271.959372) (xy 98.836123 -271.949544)
			(xy 98.790184 -271.932122) (xy 98.747634 -271.907556) (xy 98.709576 -271.876482) (xy 98.676995 -271.839706)
			(xy 98.650736 -271.79818) (xy 98.631478 -271.752979) (xy 98.61972 -271.705275) (xy 98.615766 -271.656302)
			(xy 98.285808 -271.656302) (xy 98.285314 -271.680868) (xy 98.277433 -271.729364) (xy 98.261874 -271.775968)
			(xy 98.239041 -271.819472) (xy 98.209525 -271.858751) (xy 98.174091 -271.892786) (xy 98.133656 -271.920696)
			(xy 98.089267 -271.941759) (xy 98.042075 -271.955428) (xy 97.993301 -271.96135) (xy 97.944209 -271.959372)
			(xy 97.896069 -271.949544) (xy 97.85013 -271.932122) (xy 97.80758 -271.907556) (xy 97.769522 -271.876482)
			(xy 97.736941 -271.839706) (xy 97.710682 -271.79818) (xy 97.691424 -271.752979) (xy 97.679666 -271.705275)
			(xy 97.675712 -271.656302) (xy 2.509012 -271.656302) (xy 2.509012 -272.466308) (xy 108.485698 -272.466308)
			(xy 108.489652 -272.417335) (xy 108.50141 -272.369631) (xy 108.520668 -272.32443) (xy 108.546927 -272.282904)
			(xy 108.579508 -272.246128) (xy 108.617566 -272.215054) (xy 108.660116 -272.190488) (xy 108.706055 -272.173066)
			(xy 108.754195 -272.163238) (xy 108.803287 -272.16126) (xy 108.852061 -272.167182) (xy 108.899253 -272.180851)
			(xy 108.943642 -272.201914) (xy 108.984077 -272.229824) (xy 109.019511 -272.263859) (xy 109.049027 -272.303138)
			(xy 109.07186 -272.346642) (xy 109.087419 -272.393246) (xy 109.0953 -272.441742) (xy 109.095794 -272.466308)
			(xy 109.425752 -272.466308) (xy 109.429706 -272.417335) (xy 109.441464 -272.369631) (xy 109.460722 -272.32443)
			(xy 109.486981 -272.282904) (xy 109.519562 -272.246128) (xy 109.55762 -272.215054) (xy 109.60017 -272.190488)
			(xy 109.646109 -272.173066) (xy 109.694249 -272.163238) (xy 109.743341 -272.16126) (xy 109.792115 -272.167182)
			(xy 109.839307 -272.180851) (xy 109.883696 -272.201914) (xy 109.924131 -272.229824) (xy 109.959565 -272.263859)
			(xy 109.989081 -272.303138) (xy 110.011914 -272.346642) (xy 110.027473 -272.393246) (xy 110.035354 -272.441742)
			(xy 110.035848 -272.466308) (xy 114.119418 -272.466308) (xy 114.123372 -272.417335) (xy 114.13513 -272.369631)
			(xy 114.154388 -272.32443) (xy 114.180647 -272.282904) (xy 114.213228 -272.246128) (xy 114.251286 -272.215054)
			(xy 114.293836 -272.190488) (xy 114.339775 -272.173066) (xy 114.387915 -272.163238) (xy 114.437007 -272.16126)
			(xy 114.485781 -272.167182) (xy 114.532973 -272.180851) (xy 114.577362 -272.201914) (xy 114.617797 -272.229824)
			(xy 114.653231 -272.263859) (xy 114.682747 -272.303138) (xy 114.70558 -272.346642) (xy 114.721139 -272.393246)
			(xy 114.72902 -272.441742) (xy 114.729514 -272.466308) (xy 115.059472 -272.466308) (xy 115.063426 -272.417335)
			(xy 115.075184 -272.369631) (xy 115.094442 -272.32443) (xy 115.120701 -272.282904) (xy 115.153282 -272.246128)
			(xy 115.19134 -272.215054) (xy 115.23389 -272.190488) (xy 115.279829 -272.173066) (xy 115.327969 -272.163238)
			(xy 115.377061 -272.16126) (xy 115.425835 -272.167182) (xy 115.473027 -272.180851) (xy 115.517416 -272.201914)
			(xy 115.557851 -272.229824) (xy 115.593285 -272.263859) (xy 115.622801 -272.303138) (xy 115.645634 -272.346642)
			(xy 115.661193 -272.393246) (xy 115.669074 -272.441742) (xy 115.669563 -272.466054) (xy 356.425766 -272.466054)
			(xy 356.42972 -272.417081) (xy 356.441478 -272.369377) (xy 356.460736 -272.324176) (xy 356.486995 -272.28265)
			(xy 356.519576 -272.245874) (xy 356.557634 -272.2148) (xy 356.600184 -272.190234) (xy 356.646123 -272.172812)
			(xy 356.694263 -272.162984) (xy 356.743355 -272.161006) (xy 356.792129 -272.166928) (xy 356.839321 -272.180597)
			(xy 356.88371 -272.20166) (xy 356.924145 -272.22957) (xy 356.959579 -272.263605) (xy 356.989095 -272.302884)
			(xy 357.011928 -272.346388) (xy 357.027487 -272.392992) (xy 357.035368 -272.441488) (xy 357.035862 -272.466054)
			(xy 357.36582 -272.466054) (xy 357.369774 -272.417081) (xy 357.381532 -272.369377) (xy 357.40079 -272.324176)
			(xy 357.427049 -272.28265) (xy 357.45963 -272.245874) (xy 357.497688 -272.2148) (xy 357.540238 -272.190234)
			(xy 357.586177 -272.172812) (xy 357.634317 -272.162984) (xy 357.683409 -272.161006) (xy 357.732183 -272.166928)
			(xy 357.779375 -272.180597) (xy 357.823764 -272.20166) (xy 357.864199 -272.22957) (xy 357.899633 -272.263605)
			(xy 357.929149 -272.302884) (xy 357.951982 -272.346388) (xy 357.967541 -272.392992) (xy 357.975422 -272.441488)
			(xy 357.975916 -272.466054) (xy 362.059486 -272.466054) (xy 362.06344 -272.417081) (xy 362.075198 -272.369377)
			(xy 362.094456 -272.324176) (xy 362.120715 -272.28265) (xy 362.153296 -272.245874) (xy 362.191354 -272.2148)
			(xy 362.233904 -272.190234) (xy 362.279843 -272.172812) (xy 362.327983 -272.162984) (xy 362.377075 -272.161006)
			(xy 362.425849 -272.166928) (xy 362.473041 -272.180597) (xy 362.51743 -272.20166) (xy 362.557865 -272.22957)
			(xy 362.593299 -272.263605) (xy 362.622815 -272.302884) (xy 362.645648 -272.346388) (xy 362.661207 -272.392992)
			(xy 362.669088 -272.441488) (xy 362.669582 -272.466054) (xy 362.99954 -272.466054) (xy 363.003494 -272.417081)
			(xy 363.015252 -272.369377) (xy 363.03451 -272.324176) (xy 363.060769 -272.28265) (xy 363.09335 -272.245874)
			(xy 363.131408 -272.2148) (xy 363.173958 -272.190234) (xy 363.219897 -272.172812) (xy 363.268037 -272.162984)
			(xy 363.317129 -272.161006) (xy 363.365903 -272.166928) (xy 363.413095 -272.180597) (xy 363.457484 -272.20166)
			(xy 363.497919 -272.22957) (xy 363.533353 -272.263605) (xy 363.562869 -272.302884) (xy 363.585702 -272.346388)
			(xy 363.601261 -272.392992) (xy 363.609142 -272.441488) (xy 363.609636 -272.466054) (xy 363.609142 -272.49062)
			(xy 363.601261 -272.539116) (xy 363.585702 -272.58572) (xy 363.562869 -272.629224) (xy 363.533353 -272.668503)
			(xy 363.497919 -272.702538) (xy 363.457484 -272.730448) (xy 363.413095 -272.751511) (xy 363.365903 -272.76518)
			(xy 363.317129 -272.771102) (xy 363.268037 -272.769124) (xy 363.219897 -272.759296) (xy 363.173958 -272.741874)
			(xy 363.131408 -272.717308) (xy 363.09335 -272.686234) (xy 363.060769 -272.649458) (xy 363.03451 -272.607932)
			(xy 363.015252 -272.562731) (xy 363.003494 -272.515027) (xy 362.99954 -272.466054) (xy 362.669582 -272.466054)
			(xy 362.669088 -272.49062) (xy 362.661207 -272.539116) (xy 362.645648 -272.58572) (xy 362.622815 -272.629224)
			(xy 362.593299 -272.668503) (xy 362.557865 -272.702538) (xy 362.51743 -272.730448) (xy 362.473041 -272.751511)
			(xy 362.425849 -272.76518) (xy 362.377075 -272.771102) (xy 362.327983 -272.769124) (xy 362.279843 -272.759296)
			(xy 362.233904 -272.741874) (xy 362.191354 -272.717308) (xy 362.153296 -272.686234) (xy 362.120715 -272.649458)
			(xy 362.094456 -272.607932) (xy 362.075198 -272.562731) (xy 362.06344 -272.515027) (xy 362.059486 -272.466054)
			(xy 357.975916 -272.466054) (xy 357.975422 -272.49062) (xy 357.967541 -272.539116) (xy 357.951982 -272.58572)
			(xy 357.929149 -272.629224) (xy 357.899633 -272.668503) (xy 357.864199 -272.702538) (xy 357.823764 -272.730448)
			(xy 357.779375 -272.751511) (xy 357.732183 -272.76518) (xy 357.683409 -272.771102) (xy 357.634317 -272.769124)
			(xy 357.586177 -272.759296) (xy 357.540238 -272.741874) (xy 357.497688 -272.717308) (xy 357.45963 -272.686234)
			(xy 357.427049 -272.649458) (xy 357.40079 -272.607932) (xy 357.381532 -272.562731) (xy 357.369774 -272.515027)
			(xy 357.36582 -272.466054) (xy 357.035862 -272.466054) (xy 357.035368 -272.49062) (xy 357.027487 -272.539116)
			(xy 357.011928 -272.58572) (xy 356.989095 -272.629224) (xy 356.959579 -272.668503) (xy 356.924145 -272.702538)
			(xy 356.88371 -272.730448) (xy 356.839321 -272.751511) (xy 356.792129 -272.76518) (xy 356.743355 -272.771102)
			(xy 356.694263 -272.769124) (xy 356.646123 -272.759296) (xy 356.600184 -272.741874) (xy 356.557634 -272.717308)
			(xy 356.519576 -272.686234) (xy 356.486995 -272.649458) (xy 356.460736 -272.607932) (xy 356.441478 -272.562731)
			(xy 356.42972 -272.515027) (xy 356.425766 -272.466054) (xy 115.669563 -272.466054) (xy 115.669568 -272.466308)
			(xy 115.669074 -272.490874) (xy 115.661193 -272.53937) (xy 115.645634 -272.585974) (xy 115.622801 -272.629478)
			(xy 115.593285 -272.668757) (xy 115.557851 -272.702792) (xy 115.517416 -272.730702) (xy 115.473027 -272.751765)
			(xy 115.425835 -272.765434) (xy 115.377061 -272.771356) (xy 115.327969 -272.769378) (xy 115.279829 -272.75955)
			(xy 115.23389 -272.742128) (xy 115.19134 -272.717562) (xy 115.153282 -272.686488) (xy 115.120701 -272.649712)
			(xy 115.094442 -272.608186) (xy 115.075184 -272.562985) (xy 115.063426 -272.515281) (xy 115.059472 -272.466308)
			(xy 114.729514 -272.466308) (xy 114.72902 -272.490874) (xy 114.721139 -272.53937) (xy 114.70558 -272.585974)
			(xy 114.682747 -272.629478) (xy 114.653231 -272.668757) (xy 114.617797 -272.702792) (xy 114.577362 -272.730702)
			(xy 114.532973 -272.751765) (xy 114.485781 -272.765434) (xy 114.437007 -272.771356) (xy 114.387915 -272.769378)
			(xy 114.339775 -272.75955) (xy 114.293836 -272.742128) (xy 114.251286 -272.717562) (xy 114.213228 -272.686488)
			(xy 114.180647 -272.649712) (xy 114.154388 -272.608186) (xy 114.13513 -272.562985) (xy 114.123372 -272.515281)
			(xy 114.119418 -272.466308) (xy 110.035848 -272.466308) (xy 110.035354 -272.490874) (xy 110.027473 -272.53937)
			(xy 110.011914 -272.585974) (xy 109.989081 -272.629478) (xy 109.959565 -272.668757) (xy 109.924131 -272.702792)
			(xy 109.883696 -272.730702) (xy 109.839307 -272.751765) (xy 109.792115 -272.765434) (xy 109.743341 -272.771356)
			(xy 109.694249 -272.769378) (xy 109.646109 -272.75955) (xy 109.60017 -272.742128) (xy 109.55762 -272.717562)
			(xy 109.519562 -272.686488) (xy 109.486981 -272.649712) (xy 109.460722 -272.608186) (xy 109.441464 -272.562985)
			(xy 109.429706 -272.515281) (xy 109.425752 -272.466308) (xy 109.095794 -272.466308) (xy 109.0953 -272.490874)
			(xy 109.087419 -272.53937) (xy 109.07186 -272.585974) (xy 109.049027 -272.629478) (xy 109.019511 -272.668757)
			(xy 108.984077 -272.702792) (xy 108.943642 -272.730702) (xy 108.899253 -272.751765) (xy 108.852061 -272.765434)
			(xy 108.803287 -272.771356) (xy 108.754195 -272.769378) (xy 108.706055 -272.75955) (xy 108.660116 -272.742128)
			(xy 108.617566 -272.717562) (xy 108.579508 -272.686488) (xy 108.546927 -272.649712) (xy 108.520668 -272.608186)
			(xy 108.50141 -272.562985) (xy 108.489652 -272.515281) (xy 108.485698 -272.466308) (xy 2.509012 -272.466308)
			(xy 2.509012 -273.276314) (xy 97.675712 -273.276314) (xy 97.679666 -273.227341) (xy 97.691424 -273.179637)
			(xy 97.710682 -273.134436) (xy 97.736941 -273.09291) (xy 97.769522 -273.056134) (xy 97.80758 -273.02506)
			(xy 97.85013 -273.000494) (xy 97.896069 -272.983072) (xy 97.944209 -272.973244) (xy 97.993301 -272.971266)
			(xy 98.042075 -272.977188) (xy 98.089267 -272.990857) (xy 98.133656 -273.01192) (xy 98.174091 -273.03983)
			(xy 98.209525 -273.073865) (xy 98.239041 -273.113144) (xy 98.261874 -273.156648) (xy 98.277433 -273.203252)
			(xy 98.285314 -273.251748) (xy 98.285808 -273.276314) (xy 98.615766 -273.276314) (xy 98.61972 -273.227341)
			(xy 98.631478 -273.179637) (xy 98.650736 -273.134436) (xy 98.676995 -273.09291) (xy 98.709576 -273.056134)
			(xy 98.747634 -273.02506) (xy 98.790184 -273.000494) (xy 98.836123 -272.983072) (xy 98.884263 -272.973244)
			(xy 98.933355 -272.971266) (xy 98.982129 -272.977188) (xy 99.029321 -272.990857) (xy 99.07371 -273.01192)
			(xy 99.114145 -273.03983) (xy 99.149579 -273.073865) (xy 99.179095 -273.113144) (xy 99.201928 -273.156648)
			(xy 99.217487 -273.203252) (xy 99.225368 -273.251748) (xy 99.225862 -273.276314) (xy 100.49562 -273.276314)
			(xy 100.499574 -273.227341) (xy 100.511332 -273.179637) (xy 100.53059 -273.134436) (xy 100.556849 -273.09291)
			(xy 100.58943 -273.056134) (xy 100.627488 -273.02506) (xy 100.670038 -273.000494) (xy 100.715977 -272.983072)
			(xy 100.764117 -272.973244) (xy 100.813209 -272.971266) (xy 100.861983 -272.977188) (xy 100.909175 -272.990857)
			(xy 100.953564 -273.01192) (xy 100.993999 -273.03983) (xy 101.029433 -273.073865) (xy 101.058949 -273.113144)
			(xy 101.081782 -273.156648) (xy 101.097341 -273.203252) (xy 101.105222 -273.251748) (xy 101.105716 -273.276314)
			(xy 101.435674 -273.276314) (xy 101.439628 -273.227341) (xy 101.451386 -273.179637) (xy 101.470644 -273.134436)
			(xy 101.496903 -273.09291) (xy 101.529484 -273.056134) (xy 101.567542 -273.02506) (xy 101.610092 -273.000494)
			(xy 101.656031 -272.983072) (xy 101.704171 -272.973244) (xy 101.753263 -272.971266) (xy 101.802037 -272.977188)
			(xy 101.849229 -272.990857) (xy 101.893618 -273.01192) (xy 101.934053 -273.03983) (xy 101.969487 -273.073865)
			(xy 101.999003 -273.113144) (xy 102.021836 -273.156648) (xy 102.037395 -273.203252) (xy 102.045276 -273.251748)
			(xy 102.04577 -273.276314) (xy 103.315782 -273.276314) (xy 103.319736 -273.227341) (xy 103.331494 -273.179637)
			(xy 103.350752 -273.134436) (xy 103.377011 -273.09291) (xy 103.409592 -273.056134) (xy 103.44765 -273.02506)
			(xy 103.4902 -273.000494) (xy 103.536139 -272.983072) (xy 103.584279 -272.973244) (xy 103.633371 -272.971266)
			(xy 103.682145 -272.977188) (xy 103.729337 -272.990857) (xy 103.773726 -273.01192) (xy 103.814161 -273.03983)
			(xy 103.849595 -273.073865) (xy 103.879111 -273.113144) (xy 103.901944 -273.156648) (xy 103.917503 -273.203252)
			(xy 103.925384 -273.251748) (xy 103.925878 -273.276314) (xy 104.255836 -273.276314) (xy 104.25979 -273.227341)
			(xy 104.271548 -273.179637) (xy 104.290806 -273.134436) (xy 104.317065 -273.09291) (xy 104.349646 -273.056134)
			(xy 104.387704 -273.02506) (xy 104.430254 -273.000494) (xy 104.476193 -272.983072) (xy 104.524333 -272.973244)
			(xy 104.573425 -272.971266) (xy 104.622199 -272.977188) (xy 104.669391 -272.990857) (xy 104.71378 -273.01192)
			(xy 104.754215 -273.03983) (xy 104.789649 -273.073865) (xy 104.819165 -273.113144) (xy 104.841998 -273.156648)
			(xy 104.857557 -273.203252) (xy 104.865438 -273.251748) (xy 104.865932 -273.276314) (xy 106.13569 -273.276314)
			(xy 106.139644 -273.227341) (xy 106.151402 -273.179637) (xy 106.17066 -273.134436) (xy 106.196919 -273.09291)
			(xy 106.2295 -273.056134) (xy 106.267558 -273.02506) (xy 106.310108 -273.000494) (xy 106.356047 -272.983072)
			(xy 106.404187 -272.973244) (xy 106.453279 -272.971266) (xy 106.502053 -272.977188) (xy 106.549245 -272.990857)
			(xy 106.593634 -273.01192) (xy 106.634069 -273.03983) (xy 106.669503 -273.073865) (xy 106.699019 -273.113144)
			(xy 106.721852 -273.156648) (xy 106.737411 -273.203252) (xy 106.745292 -273.251748) (xy 106.745786 -273.276314)
			(xy 107.075744 -273.276314) (xy 107.079698 -273.227341) (xy 107.091456 -273.179637) (xy 107.110714 -273.134436)
			(xy 107.136973 -273.09291) (xy 107.169554 -273.056134) (xy 107.207612 -273.02506) (xy 107.250162 -273.000494)
			(xy 107.296101 -272.983072) (xy 107.344241 -272.973244) (xy 107.393333 -272.971266) (xy 107.442107 -272.977188)
			(xy 107.489299 -272.990857) (xy 107.533688 -273.01192) (xy 107.574123 -273.03983) (xy 107.609557 -273.073865)
			(xy 107.639073 -273.113144) (xy 107.661906 -273.156648) (xy 107.677465 -273.203252) (xy 107.685346 -273.251748)
			(xy 107.68584 -273.276314) (xy 116.469426 -273.276314) (xy 116.47338 -273.227341) (xy 116.485138 -273.179637)
			(xy 116.504396 -273.134436) (xy 116.530655 -273.09291) (xy 116.563236 -273.056134) (xy 116.601294 -273.02506)
			(xy 116.643844 -273.000494) (xy 116.689783 -272.983072) (xy 116.737923 -272.973244) (xy 116.787015 -272.971266)
			(xy 116.835789 -272.977188) (xy 116.882981 -272.990857) (xy 116.92737 -273.01192) (xy 116.967805 -273.03983)
			(xy 117.003239 -273.073865) (xy 117.032755 -273.113144) (xy 117.055588 -273.156648) (xy 117.071147 -273.203252)
			(xy 117.079028 -273.251748) (xy 117.079522 -273.276314) (xy 117.40948 -273.276314) (xy 117.413434 -273.227341)
			(xy 117.425192 -273.179637) (xy 117.44445 -273.134436) (xy 117.470709 -273.09291) (xy 117.50329 -273.056134)
			(xy 117.541348 -273.02506) (xy 117.583898 -273.000494) (xy 117.629837 -272.983072) (xy 117.677977 -272.973244)
			(xy 117.727069 -272.971266) (xy 117.775843 -272.977188) (xy 117.823035 -272.990857) (xy 117.867424 -273.01192)
			(xy 117.907859 -273.03983) (xy 117.943293 -273.073865) (xy 117.972809 -273.113144) (xy 117.995642 -273.156648)
			(xy 118.011201 -273.203252) (xy 118.019082 -273.251748) (xy 118.019576 -273.276314) (xy 119.289334 -273.276314)
			(xy 119.293288 -273.227341) (xy 119.305046 -273.179637) (xy 119.324304 -273.134436) (xy 119.350563 -273.09291)
			(xy 119.383144 -273.056134) (xy 119.421202 -273.02506) (xy 119.463752 -273.000494) (xy 119.509691 -272.983072)
			(xy 119.557831 -272.973244) (xy 119.606923 -272.971266) (xy 119.655697 -272.977188) (xy 119.702889 -272.990857)
			(xy 119.747278 -273.01192) (xy 119.787713 -273.03983) (xy 119.823147 -273.073865) (xy 119.852663 -273.113144)
			(xy 119.875496 -273.156648) (xy 119.891055 -273.203252) (xy 119.898936 -273.251748) (xy 119.89943 -273.276314)
			(xy 120.229388 -273.276314) (xy 120.233342 -273.227341) (xy 120.2451 -273.179637) (xy 120.264358 -273.134436)
			(xy 120.290617 -273.09291) (xy 120.323198 -273.056134) (xy 120.361256 -273.02506) (xy 120.403806 -273.000494)
			(xy 120.449745 -272.983072) (xy 120.497885 -272.973244) (xy 120.546977 -272.971266) (xy 120.595751 -272.977188)
			(xy 120.642943 -272.990857) (xy 120.687332 -273.01192) (xy 120.727767 -273.03983) (xy 120.763201 -273.073865)
			(xy 120.792717 -273.113144) (xy 120.81555 -273.156648) (xy 120.831109 -273.203252) (xy 120.83899 -273.251748)
			(xy 120.839484 -273.276314) (xy 122.109496 -273.276314) (xy 122.11345 -273.227341) (xy 122.125208 -273.179637)
			(xy 122.144466 -273.134436) (xy 122.170725 -273.09291) (xy 122.203306 -273.056134) (xy 122.241364 -273.02506)
			(xy 122.283914 -273.000494) (xy 122.329853 -272.983072) (xy 122.377993 -272.973244) (xy 122.427085 -272.971266)
			(xy 122.475859 -272.977188) (xy 122.523051 -272.990857) (xy 122.56744 -273.01192) (xy 122.607875 -273.03983)
			(xy 122.643309 -273.073865) (xy 122.672825 -273.113144) (xy 122.695658 -273.156648) (xy 122.711217 -273.203252)
			(xy 122.719098 -273.251748) (xy 122.719592 -273.276314) (xy 123.04955 -273.276314) (xy 123.053504 -273.227341)
			(xy 123.065262 -273.179637) (xy 123.08452 -273.134436) (xy 123.110779 -273.09291) (xy 123.14336 -273.056134)
			(xy 123.181418 -273.02506) (xy 123.223968 -273.000494) (xy 123.269907 -272.983072) (xy 123.318047 -272.973244)
			(xy 123.367139 -272.971266) (xy 123.415913 -272.977188) (xy 123.463105 -272.990857) (xy 123.507494 -273.01192)
			(xy 123.547929 -273.03983) (xy 123.583363 -273.073865) (xy 123.612879 -273.113144) (xy 123.635712 -273.156648)
			(xy 123.651271 -273.203252) (xy 123.659152 -273.251748) (xy 123.659646 -273.276314) (xy 124.929404 -273.276314)
			(xy 124.933358 -273.227341) (xy 124.945116 -273.179637) (xy 124.964374 -273.134436) (xy 124.990633 -273.09291)
			(xy 125.023214 -273.056134) (xy 125.061272 -273.02506) (xy 125.103822 -273.000494) (xy 125.149761 -272.983072)
			(xy 125.197901 -272.973244) (xy 125.246993 -272.971266) (xy 125.295767 -272.977188) (xy 125.342959 -272.990857)
			(xy 125.387348 -273.01192) (xy 125.427783 -273.03983) (xy 125.463217 -273.073865) (xy 125.492733 -273.113144)
			(xy 125.515566 -273.156648) (xy 125.531125 -273.203252) (xy 125.539006 -273.251748) (xy 125.5395 -273.276314)
			(xy 125.869458 -273.276314) (xy 125.873412 -273.227341) (xy 125.88517 -273.179637) (xy 125.904428 -273.134436)
			(xy 125.930687 -273.09291) (xy 125.963268 -273.056134) (xy 126.001326 -273.02506) (xy 126.043876 -273.000494)
			(xy 126.089815 -272.983072) (xy 126.137955 -272.973244) (xy 126.187047 -272.971266) (xy 126.235821 -272.977188)
			(xy 126.283013 -272.990857) (xy 126.327402 -273.01192) (xy 126.367837 -273.03983) (xy 126.403271 -273.073865)
			(xy 126.432787 -273.113144) (xy 126.45562 -273.156648) (xy 126.471179 -273.203252) (xy 126.47906 -273.251748)
			(xy 126.479549 -273.27606) (xy 345.61578 -273.27606) (xy 345.619734 -273.227087) (xy 345.631492 -273.179383)
			(xy 345.65075 -273.134182) (xy 345.677009 -273.092656) (xy 345.70959 -273.05588) (xy 345.747648 -273.024806)
			(xy 345.790198 -273.00024) (xy 345.836137 -272.982818) (xy 345.884277 -272.97299) (xy 345.933369 -272.971012)
			(xy 345.982143 -272.976934) (xy 346.029335 -272.990603) (xy 346.073724 -273.011666) (xy 346.114159 -273.039576)
			(xy 346.149593 -273.073611) (xy 346.179109 -273.11289) (xy 346.201942 -273.156394) (xy 346.217501 -273.202998)
			(xy 346.225382 -273.251494) (xy 346.225876 -273.27606) (xy 346.555834 -273.27606) (xy 346.559788 -273.227087)
			(xy 346.571546 -273.179383) (xy 346.590804 -273.134182) (xy 346.617063 -273.092656) (xy 346.649644 -273.05588)
			(xy 346.687702 -273.024806) (xy 346.730252 -273.00024) (xy 346.776191 -272.982818) (xy 346.824331 -272.97299)
			(xy 346.873423 -272.971012) (xy 346.922197 -272.976934) (xy 346.969389 -272.990603) (xy 347.013778 -273.011666)
			(xy 347.054213 -273.039576) (xy 347.089647 -273.073611) (xy 347.119163 -273.11289) (xy 347.141996 -273.156394)
			(xy 347.157555 -273.202998) (xy 347.165436 -273.251494) (xy 347.16593 -273.27606) (xy 348.435688 -273.27606)
			(xy 348.439642 -273.227087) (xy 348.4514 -273.179383) (xy 348.470658 -273.134182) (xy 348.496917 -273.092656)
			(xy 348.529498 -273.05588) (xy 348.567556 -273.024806) (xy 348.610106 -273.00024) (xy 348.656045 -272.982818)
			(xy 348.704185 -272.97299) (xy 348.753277 -272.971012) (xy 348.802051 -272.976934) (xy 348.849243 -272.990603)
			(xy 348.893632 -273.011666) (xy 348.934067 -273.039576) (xy 348.969501 -273.073611) (xy 348.999017 -273.11289)
			(xy 349.02185 -273.156394) (xy 349.037409 -273.202998) (xy 349.04529 -273.251494) (xy 349.045784 -273.27606)
			(xy 349.375742 -273.27606) (xy 349.379696 -273.227087) (xy 349.391454 -273.179383) (xy 349.410712 -273.134182)
			(xy 349.436971 -273.092656) (xy 349.469552 -273.05588) (xy 349.50761 -273.024806) (xy 349.55016 -273.00024)
			(xy 349.596099 -272.982818) (xy 349.644239 -272.97299) (xy 349.693331 -272.971012) (xy 349.742105 -272.976934)
			(xy 349.789297 -272.990603) (xy 349.833686 -273.011666) (xy 349.874121 -273.039576) (xy 349.909555 -273.073611)
			(xy 349.939071 -273.11289) (xy 349.961904 -273.156394) (xy 349.977463 -273.202998) (xy 349.985344 -273.251494)
			(xy 349.985838 -273.27606) (xy 351.25585 -273.27606) (xy 351.259804 -273.227087) (xy 351.271562 -273.179383)
			(xy 351.29082 -273.134182) (xy 351.317079 -273.092656) (xy 351.34966 -273.05588) (xy 351.387718 -273.024806)
			(xy 351.430268 -273.00024) (xy 351.476207 -272.982818) (xy 351.524347 -272.97299) (xy 351.573439 -272.971012)
			(xy 351.622213 -272.976934) (xy 351.669405 -272.990603) (xy 351.713794 -273.011666) (xy 351.754229 -273.039576)
			(xy 351.789663 -273.073611) (xy 351.819179 -273.11289) (xy 351.842012 -273.156394) (xy 351.857571 -273.202998)
			(xy 351.865452 -273.251494) (xy 351.865946 -273.27606) (xy 352.195904 -273.27606) (xy 352.199858 -273.227087)
			(xy 352.211616 -273.179383) (xy 352.230874 -273.134182) (xy 352.257133 -273.092656) (xy 352.289714 -273.05588)
			(xy 352.327772 -273.024806) (xy 352.370322 -273.00024) (xy 352.416261 -272.982818) (xy 352.464401 -272.97299)
			(xy 352.513493 -272.971012) (xy 352.562267 -272.976934) (xy 352.609459 -272.990603) (xy 352.653848 -273.011666)
			(xy 352.694283 -273.039576) (xy 352.729717 -273.073611) (xy 352.759233 -273.11289) (xy 352.782066 -273.156394)
			(xy 352.797625 -273.202998) (xy 352.805506 -273.251494) (xy 352.806 -273.27606) (xy 354.075758 -273.27606)
			(xy 354.079712 -273.227087) (xy 354.09147 -273.179383) (xy 354.110728 -273.134182) (xy 354.136987 -273.092656)
			(xy 354.169568 -273.05588) (xy 354.207626 -273.024806) (xy 354.250176 -273.00024) (xy 354.296115 -272.982818)
			(xy 354.344255 -272.97299) (xy 354.393347 -272.971012) (xy 354.442121 -272.976934) (xy 354.489313 -272.990603)
			(xy 354.533702 -273.011666) (xy 354.574137 -273.039576) (xy 354.609571 -273.073611) (xy 354.639087 -273.11289)
			(xy 354.66192 -273.156394) (xy 354.677479 -273.202998) (xy 354.68536 -273.251494) (xy 354.685854 -273.27606)
			(xy 355.015812 -273.27606) (xy 355.019766 -273.227087) (xy 355.031524 -273.179383) (xy 355.050782 -273.134182)
			(xy 355.077041 -273.092656) (xy 355.109622 -273.05588) (xy 355.14768 -273.024806) (xy 355.19023 -273.00024)
			(xy 355.236169 -272.982818) (xy 355.284309 -272.97299) (xy 355.333401 -272.971012) (xy 355.382175 -272.976934)
			(xy 355.429367 -272.990603) (xy 355.473756 -273.011666) (xy 355.514191 -273.039576) (xy 355.549625 -273.073611)
			(xy 355.579141 -273.11289) (xy 355.601974 -273.156394) (xy 355.617533 -273.202998) (xy 355.625414 -273.251494)
			(xy 355.625908 -273.27606) (xy 364.409494 -273.27606) (xy 364.413448 -273.227087) (xy 364.425206 -273.179383)
			(xy 364.444464 -273.134182) (xy 364.470723 -273.092656) (xy 364.503304 -273.05588) (xy 364.541362 -273.024806)
			(xy 364.583912 -273.00024) (xy 364.629851 -272.982818) (xy 364.677991 -272.97299) (xy 364.727083 -272.971012)
			(xy 364.775857 -272.976934) (xy 364.823049 -272.990603) (xy 364.867438 -273.011666) (xy 364.907873 -273.039576)
			(xy 364.943307 -273.073611) (xy 364.972823 -273.11289) (xy 364.995656 -273.156394) (xy 365.011215 -273.202998)
			(xy 365.019096 -273.251494) (xy 365.01959 -273.27606) (xy 365.349548 -273.27606) (xy 365.353502 -273.227087)
			(xy 365.36526 -273.179383) (xy 365.384518 -273.134182) (xy 365.410777 -273.092656) (xy 365.443358 -273.05588)
			(xy 365.481416 -273.024806) (xy 365.523966 -273.00024) (xy 365.569905 -272.982818) (xy 365.618045 -272.97299)
			(xy 365.667137 -272.971012) (xy 365.715911 -272.976934) (xy 365.763103 -272.990603) (xy 365.807492 -273.011666)
			(xy 365.847927 -273.039576) (xy 365.883361 -273.073611) (xy 365.912877 -273.11289) (xy 365.93571 -273.156394)
			(xy 365.951269 -273.202998) (xy 365.95915 -273.251494) (xy 365.959644 -273.27606) (xy 367.229402 -273.27606)
			(xy 367.233356 -273.227087) (xy 367.245114 -273.179383) (xy 367.264372 -273.134182) (xy 367.290631 -273.092656)
			(xy 367.323212 -273.05588) (xy 367.36127 -273.024806) (xy 367.40382 -273.00024) (xy 367.449759 -272.982818)
			(xy 367.497899 -272.97299) (xy 367.546991 -272.971012) (xy 367.595765 -272.976934) (xy 367.642957 -272.990603)
			(xy 367.687346 -273.011666) (xy 367.727781 -273.039576) (xy 367.763215 -273.073611) (xy 367.792731 -273.11289)
			(xy 367.815564 -273.156394) (xy 367.831123 -273.202998) (xy 367.839004 -273.251494) (xy 367.839498 -273.27606)
			(xy 368.169456 -273.27606) (xy 368.17341 -273.227087) (xy 368.185168 -273.179383) (xy 368.204426 -273.134182)
			(xy 368.230685 -273.092656) (xy 368.263266 -273.05588) (xy 368.301324 -273.024806) (xy 368.343874 -273.00024)
			(xy 368.389813 -272.982818) (xy 368.437953 -272.97299) (xy 368.487045 -272.971012) (xy 368.535819 -272.976934)
			(xy 368.583011 -272.990603) (xy 368.6274 -273.011666) (xy 368.667835 -273.039576) (xy 368.703269 -273.073611)
			(xy 368.732785 -273.11289) (xy 368.755618 -273.156394) (xy 368.771177 -273.202998) (xy 368.779058 -273.251494)
			(xy 368.779552 -273.27606) (xy 370.049564 -273.27606) (xy 370.053518 -273.227087) (xy 370.065276 -273.179383)
			(xy 370.084534 -273.134182) (xy 370.110793 -273.092656) (xy 370.143374 -273.05588) (xy 370.181432 -273.024806)
			(xy 370.223982 -273.00024) (xy 370.269921 -272.982818) (xy 370.318061 -272.97299) (xy 370.367153 -272.971012)
			(xy 370.415927 -272.976934) (xy 370.463119 -272.990603) (xy 370.507508 -273.011666) (xy 370.547943 -273.039576)
			(xy 370.583377 -273.073611) (xy 370.612893 -273.11289) (xy 370.635726 -273.156394) (xy 370.651285 -273.202998)
			(xy 370.659166 -273.251494) (xy 370.65966 -273.27606) (xy 370.989618 -273.27606) (xy 370.993572 -273.227087)
			(xy 371.00533 -273.179383) (xy 371.024588 -273.134182) (xy 371.050847 -273.092656) (xy 371.083428 -273.05588)
			(xy 371.121486 -273.024806) (xy 371.164036 -273.00024) (xy 371.209975 -272.982818) (xy 371.258115 -272.97299)
			(xy 371.307207 -272.971012) (xy 371.355981 -272.976934) (xy 371.403173 -272.990603) (xy 371.447562 -273.011666)
			(xy 371.487997 -273.039576) (xy 371.523431 -273.073611) (xy 371.552947 -273.11289) (xy 371.57578 -273.156394)
			(xy 371.591339 -273.202998) (xy 371.59922 -273.251494) (xy 371.599714 -273.27606) (xy 372.869472 -273.27606)
			(xy 372.873426 -273.227087) (xy 372.885184 -273.179383) (xy 372.904442 -273.134182) (xy 372.930701 -273.092656)
			(xy 372.963282 -273.05588) (xy 373.00134 -273.024806) (xy 373.04389 -273.00024) (xy 373.089829 -272.982818)
			(xy 373.137969 -272.97299) (xy 373.187061 -272.971012) (xy 373.235835 -272.976934) (xy 373.283027 -272.990603)
			(xy 373.327416 -273.011666) (xy 373.367851 -273.039576) (xy 373.403285 -273.073611) (xy 373.432801 -273.11289)
			(xy 373.455634 -273.156394) (xy 373.471193 -273.202998) (xy 373.479074 -273.251494) (xy 373.479568 -273.27606)
			(xy 373.809526 -273.27606) (xy 373.81348 -273.227087) (xy 373.825238 -273.179383) (xy 373.844496 -273.134182)
			(xy 373.870755 -273.092656) (xy 373.903336 -273.05588) (xy 373.941394 -273.024806) (xy 373.983944 -273.00024)
			(xy 374.029883 -272.982818) (xy 374.078023 -272.97299) (xy 374.127115 -272.971012) (xy 374.175889 -272.976934)
			(xy 374.223081 -272.990603) (xy 374.26747 -273.011666) (xy 374.307905 -273.039576) (xy 374.343339 -273.073611)
			(xy 374.372855 -273.11289) (xy 374.395688 -273.156394) (xy 374.411247 -273.202998) (xy 374.419128 -273.251494)
			(xy 374.419622 -273.27606) (xy 374.419128 -273.300626) (xy 374.411247 -273.349122) (xy 374.395688 -273.395726)
			(xy 374.372855 -273.43923) (xy 374.343339 -273.478509) (xy 374.307905 -273.512544) (xy 374.26747 -273.540454)
			(xy 374.223081 -273.561517) (xy 374.175889 -273.575186) (xy 374.127115 -273.581108) (xy 374.078023 -273.57913)
			(xy 374.029883 -273.569302) (xy 373.983944 -273.55188) (xy 373.941394 -273.527314) (xy 373.903336 -273.49624)
			(xy 373.870755 -273.459464) (xy 373.844496 -273.417938) (xy 373.825238 -273.372737) (xy 373.81348 -273.325033)
			(xy 373.809526 -273.27606) (xy 373.479568 -273.27606) (xy 373.479074 -273.300626) (xy 373.471193 -273.349122)
			(xy 373.455634 -273.395726) (xy 373.432801 -273.43923) (xy 373.403285 -273.478509) (xy 373.367851 -273.512544)
			(xy 373.327416 -273.540454) (xy 373.283027 -273.561517) (xy 373.235835 -273.575186) (xy 373.187061 -273.581108)
			(xy 373.137969 -273.57913) (xy 373.089829 -273.569302) (xy 373.04389 -273.55188) (xy 373.00134 -273.527314)
			(xy 372.963282 -273.49624) (xy 372.930701 -273.459464) (xy 372.904442 -273.417938) (xy 372.885184 -273.372737)
			(xy 372.873426 -273.325033) (xy 372.869472 -273.27606) (xy 371.599714 -273.27606) (xy 371.59922 -273.300626)
			(xy 371.591339 -273.349122) (xy 371.57578 -273.395726) (xy 371.552947 -273.43923) (xy 371.523431 -273.478509)
			(xy 371.487997 -273.512544) (xy 371.447562 -273.540454) (xy 371.403173 -273.561517) (xy 371.355981 -273.575186)
			(xy 371.307207 -273.581108) (xy 371.258115 -273.57913) (xy 371.209975 -273.569302) (xy 371.164036 -273.55188)
			(xy 371.121486 -273.527314) (xy 371.083428 -273.49624) (xy 371.050847 -273.459464) (xy 371.024588 -273.417938)
			(xy 371.00533 -273.372737) (xy 370.993572 -273.325033) (xy 370.989618 -273.27606) (xy 370.65966 -273.27606)
			(xy 370.659166 -273.300626) (xy 370.651285 -273.349122) (xy 370.635726 -273.395726) (xy 370.612893 -273.43923)
			(xy 370.583377 -273.478509) (xy 370.547943 -273.512544) (xy 370.507508 -273.540454) (xy 370.463119 -273.561517)
			(xy 370.415927 -273.575186) (xy 370.367153 -273.581108) (xy 370.318061 -273.57913) (xy 370.269921 -273.569302)
			(xy 370.223982 -273.55188) (xy 370.181432 -273.527314) (xy 370.143374 -273.49624) (xy 370.110793 -273.459464)
			(xy 370.084534 -273.417938) (xy 370.065276 -273.372737) (xy 370.053518 -273.325033) (xy 370.049564 -273.27606)
			(xy 368.779552 -273.27606) (xy 368.779058 -273.300626) (xy 368.771177 -273.349122) (xy 368.755618 -273.395726)
			(xy 368.732785 -273.43923) (xy 368.703269 -273.478509) (xy 368.667835 -273.512544) (xy 368.6274 -273.540454)
			(xy 368.583011 -273.561517) (xy 368.535819 -273.575186) (xy 368.487045 -273.581108) (xy 368.437953 -273.57913)
			(xy 368.389813 -273.569302) (xy 368.343874 -273.55188) (xy 368.301324 -273.527314) (xy 368.263266 -273.49624)
			(xy 368.230685 -273.459464) (xy 368.204426 -273.417938) (xy 368.185168 -273.372737) (xy 368.17341 -273.325033)
			(xy 368.169456 -273.27606) (xy 367.839498 -273.27606) (xy 367.839004 -273.300626) (xy 367.831123 -273.349122)
			(xy 367.815564 -273.395726) (xy 367.792731 -273.43923) (xy 367.763215 -273.478509) (xy 367.727781 -273.512544)
			(xy 367.687346 -273.540454) (xy 367.642957 -273.561517) (xy 367.595765 -273.575186) (xy 367.546991 -273.581108)
			(xy 367.497899 -273.57913) (xy 367.449759 -273.569302) (xy 367.40382 -273.55188) (xy 367.36127 -273.527314)
			(xy 367.323212 -273.49624) (xy 367.290631 -273.459464) (xy 367.264372 -273.417938) (xy 367.245114 -273.372737)
			(xy 367.233356 -273.325033) (xy 367.229402 -273.27606) (xy 365.959644 -273.27606) (xy 365.95915 -273.300626)
			(xy 365.951269 -273.349122) (xy 365.93571 -273.395726) (xy 365.912877 -273.43923) (xy 365.883361 -273.478509)
			(xy 365.847927 -273.512544) (xy 365.807492 -273.540454) (xy 365.763103 -273.561517) (xy 365.715911 -273.575186)
			(xy 365.667137 -273.581108) (xy 365.618045 -273.57913) (xy 365.569905 -273.569302) (xy 365.523966 -273.55188)
			(xy 365.481416 -273.527314) (xy 365.443358 -273.49624) (xy 365.410777 -273.459464) (xy 365.384518 -273.417938)
			(xy 365.36526 -273.372737) (xy 365.353502 -273.325033) (xy 365.349548 -273.27606) (xy 365.01959 -273.27606)
			(xy 365.019096 -273.300626) (xy 365.011215 -273.349122) (xy 364.995656 -273.395726) (xy 364.972823 -273.43923)
			(xy 364.943307 -273.478509) (xy 364.907873 -273.512544) (xy 364.867438 -273.540454) (xy 364.823049 -273.561517)
			(xy 364.775857 -273.575186) (xy 364.727083 -273.581108) (xy 364.677991 -273.57913) (xy 364.629851 -273.569302)
			(xy 364.583912 -273.55188) (xy 364.541362 -273.527314) (xy 364.503304 -273.49624) (xy 364.470723 -273.459464)
			(xy 364.444464 -273.417938) (xy 364.425206 -273.372737) (xy 364.413448 -273.325033) (xy 364.409494 -273.27606)
			(xy 355.625908 -273.27606) (xy 355.625414 -273.300626) (xy 355.617533 -273.349122) (xy 355.601974 -273.395726)
			(xy 355.579141 -273.43923) (xy 355.549625 -273.478509) (xy 355.514191 -273.512544) (xy 355.473756 -273.540454)
			(xy 355.429367 -273.561517) (xy 355.382175 -273.575186) (xy 355.333401 -273.581108) (xy 355.284309 -273.57913)
			(xy 355.236169 -273.569302) (xy 355.19023 -273.55188) (xy 355.14768 -273.527314) (xy 355.109622 -273.49624)
			(xy 355.077041 -273.459464) (xy 355.050782 -273.417938) (xy 355.031524 -273.372737) (xy 355.019766 -273.325033)
			(xy 355.015812 -273.27606) (xy 354.685854 -273.27606) (xy 354.68536 -273.300626) (xy 354.677479 -273.349122)
			(xy 354.66192 -273.395726) (xy 354.639087 -273.43923) (xy 354.609571 -273.478509) (xy 354.574137 -273.512544)
			(xy 354.533702 -273.540454) (xy 354.489313 -273.561517) (xy 354.442121 -273.575186) (xy 354.393347 -273.581108)
			(xy 354.344255 -273.57913) (xy 354.296115 -273.569302) (xy 354.250176 -273.55188) (xy 354.207626 -273.527314)
			(xy 354.169568 -273.49624) (xy 354.136987 -273.459464) (xy 354.110728 -273.417938) (xy 354.09147 -273.372737)
			(xy 354.079712 -273.325033) (xy 354.075758 -273.27606) (xy 352.806 -273.27606) (xy 352.805506 -273.300626)
			(xy 352.797625 -273.349122) (xy 352.782066 -273.395726) (xy 352.759233 -273.43923) (xy 352.729717 -273.478509)
			(xy 352.694283 -273.512544) (xy 352.653848 -273.540454) (xy 352.609459 -273.561517) (xy 352.562267 -273.575186)
			(xy 352.513493 -273.581108) (xy 352.464401 -273.57913) (xy 352.416261 -273.569302) (xy 352.370322 -273.55188)
			(xy 352.327772 -273.527314) (xy 352.289714 -273.49624) (xy 352.257133 -273.459464) (xy 352.230874 -273.417938)
			(xy 352.211616 -273.372737) (xy 352.199858 -273.325033) (xy 352.195904 -273.27606) (xy 351.865946 -273.27606)
			(xy 351.865452 -273.300626) (xy 351.857571 -273.349122) (xy 351.842012 -273.395726) (xy 351.819179 -273.43923)
			(xy 351.789663 -273.478509) (xy 351.754229 -273.512544) (xy 351.713794 -273.540454) (xy 351.669405 -273.561517)
			(xy 351.622213 -273.575186) (xy 351.573439 -273.581108) (xy 351.524347 -273.57913) (xy 351.476207 -273.569302)
			(xy 351.430268 -273.55188) (xy 351.387718 -273.527314) (xy 351.34966 -273.49624) (xy 351.317079 -273.459464)
			(xy 351.29082 -273.417938) (xy 351.271562 -273.372737) (xy 351.259804 -273.325033) (xy 351.25585 -273.27606)
			(xy 349.985838 -273.27606) (xy 349.985344 -273.300626) (xy 349.977463 -273.349122) (xy 349.961904 -273.395726)
			(xy 349.939071 -273.43923) (xy 349.909555 -273.478509) (xy 349.874121 -273.512544) (xy 349.833686 -273.540454)
			(xy 349.789297 -273.561517) (xy 349.742105 -273.575186) (xy 349.693331 -273.581108) (xy 349.644239 -273.57913)
			(xy 349.596099 -273.569302) (xy 349.55016 -273.55188) (xy 349.50761 -273.527314) (xy 349.469552 -273.49624)
			(xy 349.436971 -273.459464) (xy 349.410712 -273.417938) (xy 349.391454 -273.372737) (xy 349.379696 -273.325033)
			(xy 349.375742 -273.27606) (xy 349.045784 -273.27606) (xy 349.04529 -273.300626) (xy 349.037409 -273.349122)
			(xy 349.02185 -273.395726) (xy 348.999017 -273.43923) (xy 348.969501 -273.478509) (xy 348.934067 -273.512544)
			(xy 348.893632 -273.540454) (xy 348.849243 -273.561517) (xy 348.802051 -273.575186) (xy 348.753277 -273.581108)
			(xy 348.704185 -273.57913) (xy 348.656045 -273.569302) (xy 348.610106 -273.55188) (xy 348.567556 -273.527314)
			(xy 348.529498 -273.49624) (xy 348.496917 -273.459464) (xy 348.470658 -273.417938) (xy 348.4514 -273.372737)
			(xy 348.439642 -273.325033) (xy 348.435688 -273.27606) (xy 347.16593 -273.27606) (xy 347.165436 -273.300626)
			(xy 347.157555 -273.349122) (xy 347.141996 -273.395726) (xy 347.119163 -273.43923) (xy 347.089647 -273.478509)
			(xy 347.054213 -273.512544) (xy 347.013778 -273.540454) (xy 346.969389 -273.561517) (xy 346.922197 -273.575186)
			(xy 346.873423 -273.581108) (xy 346.824331 -273.57913) (xy 346.776191 -273.569302) (xy 346.730252 -273.55188)
			(xy 346.687702 -273.527314) (xy 346.649644 -273.49624) (xy 346.617063 -273.459464) (xy 346.590804 -273.417938)
			(xy 346.571546 -273.372737) (xy 346.559788 -273.325033) (xy 346.555834 -273.27606) (xy 346.225876 -273.27606)
			(xy 346.225382 -273.300626) (xy 346.217501 -273.349122) (xy 346.201942 -273.395726) (xy 346.179109 -273.43923)
			(xy 346.149593 -273.478509) (xy 346.114159 -273.512544) (xy 346.073724 -273.540454) (xy 346.029335 -273.561517)
			(xy 345.982143 -273.575186) (xy 345.933369 -273.581108) (xy 345.884277 -273.57913) (xy 345.836137 -273.569302)
			(xy 345.790198 -273.55188) (xy 345.747648 -273.527314) (xy 345.70959 -273.49624) (xy 345.677009 -273.459464)
			(xy 345.65075 -273.417938) (xy 345.631492 -273.372737) (xy 345.619734 -273.325033) (xy 345.61578 -273.27606)
			(xy 126.479549 -273.27606) (xy 126.479554 -273.276314) (xy 126.47906 -273.30088) (xy 126.471179 -273.349376)
			(xy 126.45562 -273.39598) (xy 126.432787 -273.439484) (xy 126.403271 -273.478763) (xy 126.367837 -273.512798)
			(xy 126.327402 -273.540708) (xy 126.283013 -273.561771) (xy 126.235821 -273.57544) (xy 126.187047 -273.581362)
			(xy 126.137955 -273.579384) (xy 126.089815 -273.569556) (xy 126.043876 -273.552134) (xy 126.001326 -273.527568)
			(xy 125.963268 -273.496494) (xy 125.930687 -273.459718) (xy 125.904428 -273.418192) (xy 125.88517 -273.372991)
			(xy 125.873412 -273.325287) (xy 125.869458 -273.276314) (xy 125.5395 -273.276314) (xy 125.539006 -273.30088)
			(xy 125.531125 -273.349376) (xy 125.515566 -273.39598) (xy 125.492733 -273.439484) (xy 125.463217 -273.478763)
			(xy 125.427783 -273.512798) (xy 125.387348 -273.540708) (xy 125.342959 -273.561771) (xy 125.295767 -273.57544)
			(xy 125.246993 -273.581362) (xy 125.197901 -273.579384) (xy 125.149761 -273.569556) (xy 125.103822 -273.552134)
			(xy 125.061272 -273.527568) (xy 125.023214 -273.496494) (xy 124.990633 -273.459718) (xy 124.964374 -273.418192)
			(xy 124.945116 -273.372991) (xy 124.933358 -273.325287) (xy 124.929404 -273.276314) (xy 123.659646 -273.276314)
			(xy 123.659152 -273.30088) (xy 123.651271 -273.349376) (xy 123.635712 -273.39598) (xy 123.612879 -273.439484)
			(xy 123.583363 -273.478763) (xy 123.547929 -273.512798) (xy 123.507494 -273.540708) (xy 123.463105 -273.561771)
			(xy 123.415913 -273.57544) (xy 123.367139 -273.581362) (xy 123.318047 -273.579384) (xy 123.269907 -273.569556)
			(xy 123.223968 -273.552134) (xy 123.181418 -273.527568) (xy 123.14336 -273.496494) (xy 123.110779 -273.459718)
			(xy 123.08452 -273.418192) (xy 123.065262 -273.372991) (xy 123.053504 -273.325287) (xy 123.04955 -273.276314)
			(xy 122.719592 -273.276314) (xy 122.719098 -273.30088) (xy 122.711217 -273.349376) (xy 122.695658 -273.39598)
			(xy 122.672825 -273.439484) (xy 122.643309 -273.478763) (xy 122.607875 -273.512798) (xy 122.56744 -273.540708)
			(xy 122.523051 -273.561771) (xy 122.475859 -273.57544) (xy 122.427085 -273.581362) (xy 122.377993 -273.579384)
			(xy 122.329853 -273.569556) (xy 122.283914 -273.552134) (xy 122.241364 -273.527568) (xy 122.203306 -273.496494)
			(xy 122.170725 -273.459718) (xy 122.144466 -273.418192) (xy 122.125208 -273.372991) (xy 122.11345 -273.325287)
			(xy 122.109496 -273.276314) (xy 120.839484 -273.276314) (xy 120.83899 -273.30088) (xy 120.831109 -273.349376)
			(xy 120.81555 -273.39598) (xy 120.792717 -273.439484) (xy 120.763201 -273.478763) (xy 120.727767 -273.512798)
			(xy 120.687332 -273.540708) (xy 120.642943 -273.561771) (xy 120.595751 -273.57544) (xy 120.546977 -273.581362)
			(xy 120.497885 -273.579384) (xy 120.449745 -273.569556) (xy 120.403806 -273.552134) (xy 120.361256 -273.527568)
			(xy 120.323198 -273.496494) (xy 120.290617 -273.459718) (xy 120.264358 -273.418192) (xy 120.2451 -273.372991)
			(xy 120.233342 -273.325287) (xy 120.229388 -273.276314) (xy 119.89943 -273.276314) (xy 119.898936 -273.30088)
			(xy 119.891055 -273.349376) (xy 119.875496 -273.39598) (xy 119.852663 -273.439484) (xy 119.823147 -273.478763)
			(xy 119.787713 -273.512798) (xy 119.747278 -273.540708) (xy 119.702889 -273.561771) (xy 119.655697 -273.57544)
			(xy 119.606923 -273.581362) (xy 119.557831 -273.579384) (xy 119.509691 -273.569556) (xy 119.463752 -273.552134)
			(xy 119.421202 -273.527568) (xy 119.383144 -273.496494) (xy 119.350563 -273.459718) (xy 119.324304 -273.418192)
			(xy 119.305046 -273.372991) (xy 119.293288 -273.325287) (xy 119.289334 -273.276314) (xy 118.019576 -273.276314)
			(xy 118.019082 -273.30088) (xy 118.011201 -273.349376) (xy 117.995642 -273.39598) (xy 117.972809 -273.439484)
			(xy 117.943293 -273.478763) (xy 117.907859 -273.512798) (xy 117.867424 -273.540708) (xy 117.823035 -273.561771)
			(xy 117.775843 -273.57544) (xy 117.727069 -273.581362) (xy 117.677977 -273.579384) (xy 117.629837 -273.569556)
			(xy 117.583898 -273.552134) (xy 117.541348 -273.527568) (xy 117.50329 -273.496494) (xy 117.470709 -273.459718)
			(xy 117.44445 -273.418192) (xy 117.425192 -273.372991) (xy 117.413434 -273.325287) (xy 117.40948 -273.276314)
			(xy 117.079522 -273.276314) (xy 117.079028 -273.30088) (xy 117.071147 -273.349376) (xy 117.055588 -273.39598)
			(xy 117.032755 -273.439484) (xy 117.003239 -273.478763) (xy 116.967805 -273.512798) (xy 116.92737 -273.540708)
			(xy 116.882981 -273.561771) (xy 116.835789 -273.57544) (xy 116.787015 -273.581362) (xy 116.737923 -273.579384)
			(xy 116.689783 -273.569556) (xy 116.643844 -273.552134) (xy 116.601294 -273.527568) (xy 116.563236 -273.496494)
			(xy 116.530655 -273.459718) (xy 116.504396 -273.418192) (xy 116.485138 -273.372991) (xy 116.47338 -273.325287)
			(xy 116.469426 -273.276314) (xy 107.68584 -273.276314) (xy 107.685346 -273.30088) (xy 107.677465 -273.349376)
			(xy 107.661906 -273.39598) (xy 107.639073 -273.439484) (xy 107.609557 -273.478763) (xy 107.574123 -273.512798)
			(xy 107.533688 -273.540708) (xy 107.489299 -273.561771) (xy 107.442107 -273.57544) (xy 107.393333 -273.581362)
			(xy 107.344241 -273.579384) (xy 107.296101 -273.569556) (xy 107.250162 -273.552134) (xy 107.207612 -273.527568)
			(xy 107.169554 -273.496494) (xy 107.136973 -273.459718) (xy 107.110714 -273.418192) (xy 107.091456 -273.372991)
			(xy 107.079698 -273.325287) (xy 107.075744 -273.276314) (xy 106.745786 -273.276314) (xy 106.745292 -273.30088)
			(xy 106.737411 -273.349376) (xy 106.721852 -273.39598) (xy 106.699019 -273.439484) (xy 106.669503 -273.478763)
			(xy 106.634069 -273.512798) (xy 106.593634 -273.540708) (xy 106.549245 -273.561771) (xy 106.502053 -273.57544)
			(xy 106.453279 -273.581362) (xy 106.404187 -273.579384) (xy 106.356047 -273.569556) (xy 106.310108 -273.552134)
			(xy 106.267558 -273.527568) (xy 106.2295 -273.496494) (xy 106.196919 -273.459718) (xy 106.17066 -273.418192)
			(xy 106.151402 -273.372991) (xy 106.139644 -273.325287) (xy 106.13569 -273.276314) (xy 104.865932 -273.276314)
			(xy 104.865438 -273.30088) (xy 104.857557 -273.349376) (xy 104.841998 -273.39598) (xy 104.819165 -273.439484)
			(xy 104.789649 -273.478763) (xy 104.754215 -273.512798) (xy 104.71378 -273.540708) (xy 104.669391 -273.561771)
			(xy 104.622199 -273.57544) (xy 104.573425 -273.581362) (xy 104.524333 -273.579384) (xy 104.476193 -273.569556)
			(xy 104.430254 -273.552134) (xy 104.387704 -273.527568) (xy 104.349646 -273.496494) (xy 104.317065 -273.459718)
			(xy 104.290806 -273.418192) (xy 104.271548 -273.372991) (xy 104.25979 -273.325287) (xy 104.255836 -273.276314)
			(xy 103.925878 -273.276314) (xy 103.925384 -273.30088) (xy 103.917503 -273.349376) (xy 103.901944 -273.39598)
			(xy 103.879111 -273.439484) (xy 103.849595 -273.478763) (xy 103.814161 -273.512798) (xy 103.773726 -273.540708)
			(xy 103.729337 -273.561771) (xy 103.682145 -273.57544) (xy 103.633371 -273.581362) (xy 103.584279 -273.579384)
			(xy 103.536139 -273.569556) (xy 103.4902 -273.552134) (xy 103.44765 -273.527568) (xy 103.409592 -273.496494)
			(xy 103.377011 -273.459718) (xy 103.350752 -273.418192) (xy 103.331494 -273.372991) (xy 103.319736 -273.325287)
			(xy 103.315782 -273.276314) (xy 102.04577 -273.276314) (xy 102.045276 -273.30088) (xy 102.037395 -273.349376)
			(xy 102.021836 -273.39598) (xy 101.999003 -273.439484) (xy 101.969487 -273.478763) (xy 101.934053 -273.512798)
			(xy 101.893618 -273.540708) (xy 101.849229 -273.561771) (xy 101.802037 -273.57544) (xy 101.753263 -273.581362)
			(xy 101.704171 -273.579384) (xy 101.656031 -273.569556) (xy 101.610092 -273.552134) (xy 101.567542 -273.527568)
			(xy 101.529484 -273.496494) (xy 101.496903 -273.459718) (xy 101.470644 -273.418192) (xy 101.451386 -273.372991)
			(xy 101.439628 -273.325287) (xy 101.435674 -273.276314) (xy 101.105716 -273.276314) (xy 101.105222 -273.30088)
			(xy 101.097341 -273.349376) (xy 101.081782 -273.39598) (xy 101.058949 -273.439484) (xy 101.029433 -273.478763)
			(xy 100.993999 -273.512798) (xy 100.953564 -273.540708) (xy 100.909175 -273.561771) (xy 100.861983 -273.57544)
			(xy 100.813209 -273.581362) (xy 100.764117 -273.579384) (xy 100.715977 -273.569556) (xy 100.670038 -273.552134)
			(xy 100.627488 -273.527568) (xy 100.58943 -273.496494) (xy 100.556849 -273.459718) (xy 100.53059 -273.418192)
			(xy 100.511332 -273.372991) (xy 100.499574 -273.325287) (xy 100.49562 -273.276314) (xy 99.225862 -273.276314)
			(xy 99.225368 -273.30088) (xy 99.217487 -273.349376) (xy 99.201928 -273.39598) (xy 99.179095 -273.439484)
			(xy 99.149579 -273.478763) (xy 99.114145 -273.512798) (xy 99.07371 -273.540708) (xy 99.029321 -273.561771)
			(xy 98.982129 -273.57544) (xy 98.933355 -273.581362) (xy 98.884263 -273.579384) (xy 98.836123 -273.569556)
			(xy 98.790184 -273.552134) (xy 98.747634 -273.527568) (xy 98.709576 -273.496494) (xy 98.676995 -273.459718)
			(xy 98.650736 -273.418192) (xy 98.631478 -273.372991) (xy 98.61972 -273.325287) (xy 98.615766 -273.276314)
			(xy 98.285808 -273.276314) (xy 98.285314 -273.30088) (xy 98.277433 -273.349376) (xy 98.261874 -273.39598)
			(xy 98.239041 -273.439484) (xy 98.209525 -273.478763) (xy 98.174091 -273.512798) (xy 98.133656 -273.540708)
			(xy 98.089267 -273.561771) (xy 98.042075 -273.57544) (xy 97.993301 -273.581362) (xy 97.944209 -273.579384)
			(xy 97.896069 -273.569556) (xy 97.85013 -273.552134) (xy 97.80758 -273.527568) (xy 97.769522 -273.496494)
			(xy 97.736941 -273.459718) (xy 97.710682 -273.418192) (xy 97.691424 -273.372991) (xy 97.679666 -273.325287)
			(xy 97.675712 -273.276314) (xy 2.509012 -273.276314) (xy 2.509012 -274.08632) (xy 108.485698 -274.08632)
			(xy 108.489652 -274.037347) (xy 108.50141 -273.989643) (xy 108.520668 -273.944442) (xy 108.546927 -273.902916)
			(xy 108.579508 -273.86614) (xy 108.617566 -273.835066) (xy 108.660116 -273.8105) (xy 108.706055 -273.793078)
			(xy 108.754195 -273.78325) (xy 108.803287 -273.781272) (xy 108.852061 -273.787194) (xy 108.899253 -273.800863)
			(xy 108.943642 -273.821926) (xy 108.984077 -273.849836) (xy 109.019511 -273.883871) (xy 109.049027 -273.92315)
			(xy 109.07186 -273.966654) (xy 109.087419 -274.013258) (xy 109.0953 -274.061754) (xy 109.095794 -274.08632)
			(xy 109.425752 -274.08632) (xy 109.429706 -274.037347) (xy 109.441464 -273.989643) (xy 109.460722 -273.944442)
			(xy 109.486981 -273.902916) (xy 109.519562 -273.86614) (xy 109.55762 -273.835066) (xy 109.60017 -273.8105)
			(xy 109.646109 -273.793078) (xy 109.694249 -273.78325) (xy 109.743341 -273.781272) (xy 109.792115 -273.787194)
			(xy 109.839307 -273.800863) (xy 109.883696 -273.821926) (xy 109.924131 -273.849836) (xy 109.959565 -273.883871)
			(xy 109.989081 -273.92315) (xy 110.011914 -273.966654) (xy 110.027473 -274.013258) (xy 110.035354 -274.061754)
			(xy 110.035848 -274.08632) (xy 114.119418 -274.08632) (xy 114.123372 -274.037347) (xy 114.13513 -273.989643)
			(xy 114.154388 -273.944442) (xy 114.180647 -273.902916) (xy 114.213228 -273.86614) (xy 114.251286 -273.835066)
			(xy 114.293836 -273.8105) (xy 114.339775 -273.793078) (xy 114.387915 -273.78325) (xy 114.437007 -273.781272)
			(xy 114.485781 -273.787194) (xy 114.532973 -273.800863) (xy 114.577362 -273.821926) (xy 114.617797 -273.849836)
			(xy 114.653231 -273.883871) (xy 114.682747 -273.92315) (xy 114.70558 -273.966654) (xy 114.721139 -274.013258)
			(xy 114.72902 -274.061754) (xy 114.729514 -274.08632) (xy 115.059472 -274.08632) (xy 115.063426 -274.037347)
			(xy 115.075184 -273.989643) (xy 115.094442 -273.944442) (xy 115.120701 -273.902916) (xy 115.153282 -273.86614)
			(xy 115.19134 -273.835066) (xy 115.23389 -273.8105) (xy 115.279829 -273.793078) (xy 115.327969 -273.78325)
			(xy 115.377061 -273.781272) (xy 115.425835 -273.787194) (xy 115.473027 -273.800863) (xy 115.517416 -273.821926)
			(xy 115.557851 -273.849836) (xy 115.593285 -273.883871) (xy 115.622801 -273.92315) (xy 115.645634 -273.966654)
			(xy 115.661193 -274.013258) (xy 115.669074 -274.061754) (xy 115.669563 -274.086066) (xy 356.425766 -274.086066)
			(xy 356.42972 -274.037093) (xy 356.441478 -273.989389) (xy 356.460736 -273.944188) (xy 356.486995 -273.902662)
			(xy 356.519576 -273.865886) (xy 356.557634 -273.834812) (xy 356.600184 -273.810246) (xy 356.646123 -273.792824)
			(xy 356.694263 -273.782996) (xy 356.743355 -273.781018) (xy 356.792129 -273.78694) (xy 356.839321 -273.800609)
			(xy 356.88371 -273.821672) (xy 356.924145 -273.849582) (xy 356.959579 -273.883617) (xy 356.989095 -273.922896)
			(xy 357.011928 -273.9664) (xy 357.027487 -274.013004) (xy 357.035368 -274.0615) (xy 357.035862 -274.086066)
			(xy 357.36582 -274.086066) (xy 357.369774 -274.037093) (xy 357.381532 -273.989389) (xy 357.40079 -273.944188)
			(xy 357.427049 -273.902662) (xy 357.45963 -273.865886) (xy 357.497688 -273.834812) (xy 357.540238 -273.810246)
			(xy 357.586177 -273.792824) (xy 357.634317 -273.782996) (xy 357.683409 -273.781018) (xy 357.732183 -273.78694)
			(xy 357.779375 -273.800609) (xy 357.823764 -273.821672) (xy 357.864199 -273.849582) (xy 357.899633 -273.883617)
			(xy 357.929149 -273.922896) (xy 357.951982 -273.9664) (xy 357.967541 -274.013004) (xy 357.975422 -274.0615)
			(xy 357.975916 -274.086066) (xy 362.059486 -274.086066) (xy 362.06344 -274.037093) (xy 362.075198 -273.989389)
			(xy 362.094456 -273.944188) (xy 362.120715 -273.902662) (xy 362.153296 -273.865886) (xy 362.191354 -273.834812)
			(xy 362.233904 -273.810246) (xy 362.279843 -273.792824) (xy 362.327983 -273.782996) (xy 362.377075 -273.781018)
			(xy 362.425849 -273.78694) (xy 362.473041 -273.800609) (xy 362.51743 -273.821672) (xy 362.557865 -273.849582)
			(xy 362.593299 -273.883617) (xy 362.622815 -273.922896) (xy 362.645648 -273.9664) (xy 362.661207 -274.013004)
			(xy 362.669088 -274.0615) (xy 362.669582 -274.086066) (xy 362.99954 -274.086066) (xy 363.003494 -274.037093)
			(xy 363.015252 -273.989389) (xy 363.03451 -273.944188) (xy 363.060769 -273.902662) (xy 363.09335 -273.865886)
			(xy 363.131408 -273.834812) (xy 363.173958 -273.810246) (xy 363.219897 -273.792824) (xy 363.268037 -273.782996)
			(xy 363.317129 -273.781018) (xy 363.365903 -273.78694) (xy 363.413095 -273.800609) (xy 363.457484 -273.821672)
			(xy 363.497919 -273.849582) (xy 363.533353 -273.883617) (xy 363.562869 -273.922896) (xy 363.585702 -273.9664)
			(xy 363.601261 -274.013004) (xy 363.609142 -274.0615) (xy 363.609636 -274.086066) (xy 363.609142 -274.110632)
			(xy 363.601261 -274.159128) (xy 363.585702 -274.205732) (xy 363.562869 -274.249236) (xy 363.533353 -274.288515)
			(xy 363.497919 -274.32255) (xy 363.457484 -274.35046) (xy 363.413095 -274.371523) (xy 363.365903 -274.385192)
			(xy 363.317129 -274.391114) (xy 363.268037 -274.389136) (xy 363.219897 -274.379308) (xy 363.173958 -274.361886)
			(xy 363.131408 -274.33732) (xy 363.09335 -274.306246) (xy 363.060769 -274.26947) (xy 363.03451 -274.227944)
			(xy 363.015252 -274.182743) (xy 363.003494 -274.135039) (xy 362.99954 -274.086066) (xy 362.669582 -274.086066)
			(xy 362.669088 -274.110632) (xy 362.661207 -274.159128) (xy 362.645648 -274.205732) (xy 362.622815 -274.249236)
			(xy 362.593299 -274.288515) (xy 362.557865 -274.32255) (xy 362.51743 -274.35046) (xy 362.473041 -274.371523)
			(xy 362.425849 -274.385192) (xy 362.377075 -274.391114) (xy 362.327983 -274.389136) (xy 362.279843 -274.379308)
			(xy 362.233904 -274.361886) (xy 362.191354 -274.33732) (xy 362.153296 -274.306246) (xy 362.120715 -274.26947)
			(xy 362.094456 -274.227944) (xy 362.075198 -274.182743) (xy 362.06344 -274.135039) (xy 362.059486 -274.086066)
			(xy 357.975916 -274.086066) (xy 357.975422 -274.110632) (xy 357.967541 -274.159128) (xy 357.951982 -274.205732)
			(xy 357.929149 -274.249236) (xy 357.899633 -274.288515) (xy 357.864199 -274.32255) (xy 357.823764 -274.35046)
			(xy 357.779375 -274.371523) (xy 357.732183 -274.385192) (xy 357.683409 -274.391114) (xy 357.634317 -274.389136)
			(xy 357.586177 -274.379308) (xy 357.540238 -274.361886) (xy 357.497688 -274.33732) (xy 357.45963 -274.306246)
			(xy 357.427049 -274.26947) (xy 357.40079 -274.227944) (xy 357.381532 -274.182743) (xy 357.369774 -274.135039)
			(xy 357.36582 -274.086066) (xy 357.035862 -274.086066) (xy 357.035368 -274.110632) (xy 357.027487 -274.159128)
			(xy 357.011928 -274.205732) (xy 356.989095 -274.249236) (xy 356.959579 -274.288515) (xy 356.924145 -274.32255)
			(xy 356.88371 -274.35046) (xy 356.839321 -274.371523) (xy 356.792129 -274.385192) (xy 356.743355 -274.391114)
			(xy 356.694263 -274.389136) (xy 356.646123 -274.379308) (xy 356.600184 -274.361886) (xy 356.557634 -274.33732)
			(xy 356.519576 -274.306246) (xy 356.486995 -274.26947) (xy 356.460736 -274.227944) (xy 356.441478 -274.182743)
			(xy 356.42972 -274.135039) (xy 356.425766 -274.086066) (xy 115.669563 -274.086066) (xy 115.669568 -274.08632)
			(xy 115.669074 -274.110886) (xy 115.661193 -274.159382) (xy 115.645634 -274.205986) (xy 115.622801 -274.24949)
			(xy 115.593285 -274.288769) (xy 115.557851 -274.322804) (xy 115.517416 -274.350714) (xy 115.473027 -274.371777)
			(xy 115.425835 -274.385446) (xy 115.377061 -274.391368) (xy 115.327969 -274.38939) (xy 115.279829 -274.379562)
			(xy 115.23389 -274.36214) (xy 115.19134 -274.337574) (xy 115.153282 -274.3065) (xy 115.120701 -274.269724)
			(xy 115.094442 -274.228198) (xy 115.075184 -274.182997) (xy 115.063426 -274.135293) (xy 115.059472 -274.08632)
			(xy 114.729514 -274.08632) (xy 114.72902 -274.110886) (xy 114.721139 -274.159382) (xy 114.70558 -274.205986)
			(xy 114.682747 -274.24949) (xy 114.653231 -274.288769) (xy 114.617797 -274.322804) (xy 114.577362 -274.350714)
			(xy 114.532973 -274.371777) (xy 114.485781 -274.385446) (xy 114.437007 -274.391368) (xy 114.387915 -274.38939)
			(xy 114.339775 -274.379562) (xy 114.293836 -274.36214) (xy 114.251286 -274.337574) (xy 114.213228 -274.3065)
			(xy 114.180647 -274.269724) (xy 114.154388 -274.228198) (xy 114.13513 -274.182997) (xy 114.123372 -274.135293)
			(xy 114.119418 -274.08632) (xy 110.035848 -274.08632) (xy 110.035354 -274.110886) (xy 110.027473 -274.159382)
			(xy 110.011914 -274.205986) (xy 109.989081 -274.24949) (xy 109.959565 -274.288769) (xy 109.924131 -274.322804)
			(xy 109.883696 -274.350714) (xy 109.839307 -274.371777) (xy 109.792115 -274.385446) (xy 109.743341 -274.391368)
			(xy 109.694249 -274.38939) (xy 109.646109 -274.379562) (xy 109.60017 -274.36214) (xy 109.55762 -274.337574)
			(xy 109.519562 -274.3065) (xy 109.486981 -274.269724) (xy 109.460722 -274.228198) (xy 109.441464 -274.182997)
			(xy 109.429706 -274.135293) (xy 109.425752 -274.08632) (xy 109.095794 -274.08632) (xy 109.0953 -274.110886)
			(xy 109.087419 -274.159382) (xy 109.07186 -274.205986) (xy 109.049027 -274.24949) (xy 109.019511 -274.288769)
			(xy 108.984077 -274.322804) (xy 108.943642 -274.350714) (xy 108.899253 -274.371777) (xy 108.852061 -274.385446)
			(xy 108.803287 -274.391368) (xy 108.754195 -274.38939) (xy 108.706055 -274.379562) (xy 108.660116 -274.36214)
			(xy 108.617566 -274.337574) (xy 108.579508 -274.3065) (xy 108.546927 -274.269724) (xy 108.520668 -274.228198)
			(xy 108.50141 -274.182997) (xy 108.489652 -274.135293) (xy 108.485698 -274.08632) (xy 2.509012 -274.08632)
			(xy 2.509012 -300.146974) (xy 340.219284 -300.146974) (xy 340.219284 -299.130974) (xy 340.21977 -299.103723)
			(xy 340.227526 -299.049775) (xy 340.242881 -298.99748) (xy 340.265523 -298.947903) (xy 340.294989 -298.902053)
			(xy 340.33068 -298.860862) (xy 340.371871 -298.825171) (xy 340.417721 -298.795705) (xy 340.467298 -298.773063)
			(xy 340.519593 -298.757708) (xy 340.573541 -298.749952) (xy 340.628043 -298.749952) (xy 340.681991 -298.757708)
			(xy 340.734286 -298.773063) (xy 340.783863 -298.795705) (xy 340.829713 -298.825171) (xy 340.870904 -298.860862)
			(xy 340.906595 -298.902053) (xy 340.936061 -298.947903) (xy 340.958703 -298.99748) (xy 340.974058 -299.049775)
			(xy 340.981814 -299.103723) (xy 340.9823 -299.130974) (xy 340.9823 -300.146974) (xy 340.981814 -300.174225)
			(xy 340.974058 -300.228173) (xy 340.958703 -300.280468) (xy 340.936061 -300.330045) (xy 340.906595 -300.375895)
			(xy 340.870904 -300.417086) (xy 340.829713 -300.452777) (xy 340.783863 -300.482243) (xy 340.734286 -300.504885)
			(xy 340.681991 -300.52024) (xy 340.628043 -300.527996) (xy 340.573541 -300.527996) (xy 340.519593 -300.52024)
			(xy 340.467298 -300.504885) (xy 340.417721 -300.482243) (xy 340.371871 -300.452777) (xy 340.33068 -300.417086)
			(xy 340.294989 -300.375895) (xy 340.265523 -300.330045) (xy 340.242881 -300.280468) (xy 340.227526 -300.228173)
			(xy 340.21977 -300.174225) (xy 340.219284 -300.146974) (xy 2.509012 -300.146974) (xy 2.509012 -304.780442)
			(xy 78.810108 -304.780442) (xy 78.81414 -304.637992) (xy 78.826226 -304.495998) (xy 78.846325 -304.354915)
			(xy 78.874374 -304.215195) (xy 78.910283 -304.077286) (xy 78.953936 -303.94163) (xy 79.005195 -303.80866)
			(xy 79.063894 -303.678803) (xy 79.129845 -303.552476) (xy 79.202838 -303.430081) (xy 79.282639 -303.312013)
			(xy 79.368991 -303.198648) (xy 79.461619 -303.09035) (xy 79.560225 -302.987466) (xy 79.664494 -302.890325)
			(xy 79.774092 -302.799239) (xy 79.888667 -302.7145) (xy 80.007853 -302.636378) (xy 80.131268 -302.565124)
			(xy 80.258517 -302.500967) (xy 80.389191 -302.444112) (xy 80.522873 -302.39474) (xy 80.659134 -302.353011)
			(xy 80.797537 -302.319057) (xy 80.93764 -302.292988) (xy 81.078993 -302.274887) (xy 81.221143 -302.264812)
			(xy 81.363636 -302.262796) (xy 81.506015 -302.268844) (xy 81.647824 -302.282937) (xy 81.788608 -302.305031)
			(xy 81.927917 -302.335055) (xy 82.065304 -302.372911) (xy 82.200329 -302.41848) (xy 82.33256 -302.471615)
			(xy 82.461573 -302.532145) (xy 82.586955 -302.599878) (xy 82.708304 -302.674596) (xy 82.825232 -302.756059)
			(xy 82.937364 -302.844007) (xy 83.04434 -302.938158) (xy 83.145818 -303.03821) (xy 83.241474 -303.143843)
			(xy 83.330999 -303.254719) (xy 83.414109 -303.370482) (xy 83.490537 -303.490762) (xy 83.560037 -303.615173)
			(xy 83.622387 -303.743316) (xy 83.677387 -303.874782) (xy 83.724862 -304.009149) (xy 83.764659 -304.145987)
			(xy 83.796651 -304.284857) (xy 83.820735 -304.425314) (xy 83.836834 -304.566909) (xy 83.844896 -304.709188)
			(xy 83.8454 -304.780442) (xy 140.011408 -304.780442) (xy 140.015438 -304.638078) (xy 140.027516 -304.49617)
			(xy 140.047604 -304.355173) (xy 140.075636 -304.215538) (xy 140.111523 -304.077712) (xy 140.15515 -303.942138)
			(xy 140.206377 -303.809249) (xy 140.26504 -303.67947) (xy 140.330952 -303.553219) (xy 140.403901 -303.430899)
			(xy 140.483653 -303.312902) (xy 140.569953 -303.199606) (xy 140.662525 -303.091373) (xy 140.761071 -302.988551)
			(xy 140.865277 -302.89147) (xy 140.974809 -302.800439) (xy 141.089315 -302.715751) (xy 141.208429 -302.637676)
			(xy 141.331769 -302.566466) (xy 141.45894 -302.502347) (xy 141.589536 -302.445526) (xy 141.723136 -302.396185)
			(xy 141.859315 -302.35448) (xy 141.997634 -302.320547) (xy 142.137652 -302.294494) (xy 142.278919 -302.276404)
			(xy 142.420984 -302.266335) (xy 142.563391 -302.26432) (xy 142.705684 -302.270364) (xy 142.847406 -302.28445)
			(xy 142.988105 -302.30653) (xy 143.12733 -302.336535) (xy 143.264634 -302.374369) (xy 143.399577 -302.41991)
			(xy 143.531728 -302.473013) (xy 143.660663 -302.533507) (xy 143.785969 -302.601198) (xy 143.907245 -302.675871)
			(xy 144.024101 -302.757285) (xy 144.136165 -302.845179) (xy 144.243077 -302.939273) (xy 144.344494 -303.039265)
			(xy 144.440091 -303.144834) (xy 144.529563 -303.255643) (xy 144.612622 -303.371336) (xy 144.689003 -303.491543)
			(xy 144.758461 -303.615878) (xy 144.820774 -303.743944) (xy 144.875741 -303.875331) (xy 144.923187 -304.009616)
			(xy 144.96296 -304.146371) (xy 144.994932 -304.285157) (xy 145.019002 -304.425529) (xy 145.035091 -304.567039)
			(xy 145.043148 -304.709231) (xy 145.04365 -304.780188) (xy 326.750176 -304.780188) (xy 326.754208 -304.637738)
			(xy 326.766294 -304.495744) (xy 326.786393 -304.354661) (xy 326.814442 -304.214941) (xy 326.850351 -304.077032)
			(xy 326.894004 -303.941376) (xy 326.945263 -303.808406) (xy 327.003962 -303.678549) (xy 327.069913 -303.552222)
			(xy 327.142906 -303.429827) (xy 327.222707 -303.311759) (xy 327.309059 -303.198394) (xy 327.401687 -303.090096)
			(xy 327.500293 -302.987212) (xy 327.604562 -302.890071) (xy 327.71416 -302.798985) (xy 327.828735 -302.714246)
			(xy 327.947921 -302.636124) (xy 328.071336 -302.56487) (xy 328.198585 -302.500713) (xy 328.329259 -302.443858)
			(xy 328.462941 -302.394486) (xy 328.599202 -302.352757) (xy 328.737605 -302.318803) (xy 328.877708 -302.292734)
			(xy 329.019061 -302.274633) (xy 329.161211 -302.264558) (xy 329.303704 -302.262542) (xy 329.446083 -302.26859)
			(xy 329.587892 -302.282683) (xy 329.728676 -302.304777) (xy 329.867985 -302.334801) (xy 330.005372 -302.372657)
			(xy 330.140397 -302.418226) (xy 330.272628 -302.471361) (xy 330.401641 -302.531891) (xy 330.527023 -302.599624)
			(xy 330.648372 -302.674342) (xy 330.7653 -302.755805) (xy 330.877432 -302.843753) (xy 330.984408 -302.937904)
			(xy 331.085886 -303.037956) (xy 331.181542 -303.143589) (xy 331.271067 -303.254465) (xy 331.354177 -303.370228)
			(xy 331.430605 -303.490508) (xy 331.500105 -303.614919) (xy 331.562455 -303.743062) (xy 331.617455 -303.874528)
			(xy 331.66493 -304.008895) (xy 331.704727 -304.145733) (xy 331.736719 -304.284603) (xy 331.760803 -304.42506)
			(xy 331.776902 -304.566655) (xy 331.783388 -304.681128) (xy 333.795116 -304.681128) (xy 333.795116 -303.817528)
			(xy 333.795602 -303.790259) (xy 333.803364 -303.736275) (xy 333.818729 -303.683945) (xy 333.841386 -303.634335)
			(xy 333.870872 -303.588454) (xy 333.906587 -303.547237) (xy 333.947804 -303.511522) (xy 333.993685 -303.482036)
			(xy 334.043295 -303.459379) (xy 334.095625 -303.444014) (xy 334.149609 -303.436252) (xy 334.204147 -303.436252)
			(xy 334.258131 -303.444014) (xy 334.310461 -303.459379) (xy 334.360071 -303.482036) (xy 334.405952 -303.511522)
			(xy 334.447169 -303.547237) (xy 334.482884 -303.588454) (xy 334.51237 -303.634335) (xy 334.535027 -303.683945)
			(xy 334.550392 -303.736275) (xy 334.558154 -303.790259) (xy 334.55864 -303.817528) (xy 334.55864 -304.681128)
			(xy 334.558154 -304.708397) (xy 334.550392 -304.762381) (xy 334.545164 -304.780188) (xy 387.951476 -304.780188)
			(xy 387.955506 -304.637824) (xy 387.967584 -304.495916) (xy 387.987672 -304.354919) (xy 388.015704 -304.215284)
			(xy 388.051591 -304.077458) (xy 388.095218 -303.941884) (xy 388.146445 -303.808995) (xy 388.205108 -303.679216)
			(xy 388.27102 -303.552965) (xy 388.343969 -303.430645) (xy 388.423721 -303.312648) (xy 388.510021 -303.199352)
			(xy 388.602593 -303.091119) (xy 388.701139 -302.988297) (xy 388.805345 -302.891216) (xy 388.914877 -302.800185)
			(xy 389.029383 -302.715497) (xy 389.148497 -302.637422) (xy 389.271837 -302.566212) (xy 389.399008 -302.502093)
			(xy 389.529604 -302.445272) (xy 389.663204 -302.395931) (xy 389.799383 -302.354226) (xy 389.937702 -302.320293)
			(xy 390.07772 -302.29424) (xy 390.218987 -302.27615) (xy 390.361052 -302.266081) (xy 390.503459 -302.264066)
			(xy 390.645752 -302.27011) (xy 390.787474 -302.284196) (xy 390.928173 -302.306276) (xy 391.067398 -302.336281)
			(xy 391.204702 -302.374115) (xy 391.339645 -302.419656) (xy 391.471796 -302.472759) (xy 391.600731 -302.533253)
			(xy 391.726037 -302.600944) (xy 391.847313 -302.675617) (xy 391.964169 -302.757031) (xy 392.076233 -302.844925)
			(xy 392.183145 -302.939019) (xy 392.284562 -303.039011) (xy 392.380159 -303.14458) (xy 392.469631 -303.255389)
			(xy 392.55269 -303.371082) (xy 392.629071 -303.491289) (xy 392.698529 -303.615624) (xy 392.760842 -303.74369)
			(xy 392.815809 -303.875077) (xy 392.863255 -304.009362) (xy 392.903028 -304.146117) (xy 392.935 -304.284903)
			(xy 392.95907 -304.425275) (xy 392.975159 -304.566785) (xy 392.983216 -304.708977) (xy 392.98372 -304.780188)
			(xy 392.983216 -304.851399) (xy 392.975159 -304.993591) (xy 392.95907 -305.135101) (xy 392.935 -305.275473)
			(xy 392.903028 -305.414259) (xy 392.863255 -305.551014) (xy 392.815809 -305.685299) (xy 392.760842 -305.816686)
			(xy 392.698529 -305.944752) (xy 392.629071 -306.069087) (xy 392.55269 -306.189294) (xy 392.469631 -306.304987)
			(xy 392.380159 -306.415796) (xy 392.284562 -306.521365) (xy 392.183145 -306.621357) (xy 392.076233 -306.715451)
			(xy 391.964169 -306.803345) (xy 391.847313 -306.884759) (xy 391.726037 -306.959432) (xy 391.600731 -307.027123)
			(xy 391.471796 -307.087617) (xy 391.339645 -307.14072) (xy 391.204702 -307.186261) (xy 391.067398 -307.224095)
			(xy 390.928173 -307.2541) (xy 390.787474 -307.27618) (xy 390.645752 -307.290266) (xy 390.503459 -307.29631)
			(xy 390.361052 -307.294295) (xy 390.218987 -307.284226) (xy 390.07772 -307.266136) (xy 389.937702 -307.240083)
			(xy 389.799383 -307.20615) (xy 389.663204 -307.164445) (xy 389.529604 -307.115104) (xy 389.399008 -307.058283)
			(xy 389.271837 -306.994164) (xy 389.148497 -306.922954) (xy 389.029383 -306.844879) (xy 388.914877 -306.760191)
			(xy 388.805345 -306.66916) (xy 388.701139 -306.572079) (xy 388.602593 -306.469257) (xy 388.510021 -306.361024)
			(xy 388.423721 -306.247728) (xy 388.343969 -306.129731) (xy 388.27102 -306.007411) (xy 388.205108 -305.88116)
			(xy 388.146445 -305.751381) (xy 388.095218 -305.618492) (xy 388.051591 -305.482918) (xy 388.015704 -305.345092)
			(xy 387.987672 -305.205457) (xy 387.967584 -305.06446) (xy 387.955506 -304.922552) (xy 387.951476 -304.780188)
			(xy 334.545164 -304.780188) (xy 334.535027 -304.814711) (xy 334.51237 -304.864321) (xy 334.482884 -304.910202)
			(xy 334.447169 -304.951419) (xy 334.405952 -304.987134) (xy 334.360071 -305.01662) (xy 334.310461 -305.039277)
			(xy 334.258131 -305.054642) (xy 334.204147 -305.062404) (xy 334.149609 -305.062404) (xy 334.095625 -305.054642)
			(xy 334.043295 -305.039277) (xy 333.993685 -305.01662) (xy 333.947804 -304.987134) (xy 333.906587 -304.951419)
			(xy 333.870872 -304.910202) (xy 333.841386 -304.864321) (xy 333.818729 -304.814711) (xy 333.803364 -304.762381)
			(xy 333.795602 -304.708397) (xy 333.795116 -304.681128) (xy 331.783388 -304.681128) (xy 331.784964 -304.708934)
			(xy 331.785468 -304.780188) (xy 331.784964 -304.851442) (xy 331.776902 -304.993721) (xy 331.760803 -305.135316)
			(xy 331.736719 -305.275773) (xy 331.704727 -305.414643) (xy 331.66493 -305.551481) (xy 331.617455 -305.685848)
			(xy 331.562455 -305.817314) (xy 331.500105 -305.945457) (xy 331.430605 -306.069868) (xy 331.354177 -306.190148)
			(xy 331.271067 -306.305911) (xy 331.181542 -306.416787) (xy 331.166891 -306.432966) (xy 340.495636 -306.432966)
			(xy 340.495636 -305.569366) (xy 340.496122 -305.542115) (xy 340.503878 -305.488167) (xy 340.519233 -305.435872)
			(xy 340.541875 -305.386295) (xy 340.571341 -305.340445) (xy 340.607032 -305.299254) (xy 340.648223 -305.263563)
			(xy 340.694073 -305.234097) (xy 340.74365 -305.211455) (xy 340.795945 -305.1961) (xy 340.849893 -305.188344)
			(xy 340.904395 -305.188344) (xy 340.958343 -305.1961) (xy 341.010638 -305.211455) (xy 341.060215 -305.234097)
			(xy 341.106065 -305.263563) (xy 341.147256 -305.299254) (xy 341.182947 -305.340445) (xy 341.212413 -305.386295)
			(xy 341.235055 -305.435872) (xy 341.25041 -305.488167) (xy 341.258166 -305.542115) (xy 341.258652 -305.569366)
			(xy 341.258652 -306.432966) (xy 341.258166 -306.460217) (xy 341.25041 -306.514165) (xy 341.235055 -306.56646)
			(xy 341.212413 -306.616037) (xy 341.182947 -306.661887) (xy 341.147256 -306.703078) (xy 341.106065 -306.738769)
			(xy 341.060215 -306.768235) (xy 341.010638 -306.790877) (xy 340.958343 -306.806232) (xy 340.904395 -306.813988)
			(xy 340.849893 -306.813988) (xy 340.795945 -306.806232) (xy 340.74365 -306.790877) (xy 340.694073 -306.768235)
			(xy 340.648223 -306.738769) (xy 340.607032 -306.703078) (xy 340.571341 -306.661887) (xy 340.541875 -306.616037)
			(xy 340.519233 -306.56646) (xy 340.503878 -306.514165) (xy 340.496122 -306.460217) (xy 340.495636 -306.432966)
			(xy 331.166891 -306.432966) (xy 331.085886 -306.52242) (xy 330.984408 -306.622472) (xy 330.877432 -306.716623)
			(xy 330.7653 -306.804571) (xy 330.648372 -306.886034) (xy 330.527023 -306.960752) (xy 330.401641 -307.028485)
			(xy 330.272628 -307.089015) (xy 330.140397 -307.14215) (xy 330.005372 -307.187719) (xy 329.867985 -307.225575)
			(xy 329.728676 -307.255599) (xy 329.587892 -307.277693) (xy 329.446083 -307.291786) (xy 329.303704 -307.297834)
			(xy 329.161211 -307.295818) (xy 329.019061 -307.285743) (xy 328.877708 -307.267642) (xy 328.737605 -307.241573)
			(xy 328.599202 -307.207619) (xy 328.462941 -307.16589) (xy 328.329259 -307.116518) (xy 328.198585 -307.059663)
			(xy 328.071336 -306.995506) (xy 327.947921 -306.924252) (xy 327.828735 -306.84613) (xy 327.71416 -306.761391)
			(xy 327.604562 -306.670305) (xy 327.500293 -306.573164) (xy 327.401687 -306.47028) (xy 327.309059 -306.361982)
			(xy 327.222707 -306.248617) (xy 327.142906 -306.130549) (xy 327.069913 -306.008154) (xy 327.003962 -305.881827)
			(xy 326.945263 -305.75197) (xy 326.894004 -305.619) (xy 326.850351 -305.483344) (xy 326.814442 -305.345435)
			(xy 326.786393 -305.205715) (xy 326.766294 -305.064632) (xy 326.754208 -304.922638) (xy 326.750176 -304.780188)
			(xy 145.04365 -304.780188) (xy 145.043652 -304.780442) (xy 145.043148 -304.851653) (xy 145.035091 -304.993845)
			(xy 145.019002 -305.135355) (xy 144.994932 -305.275727) (xy 144.96296 -305.414513) (xy 144.923187 -305.551268)
			(xy 144.875741 -305.685553) (xy 144.820774 -305.81694) (xy 144.758461 -305.945006) (xy 144.689003 -306.069341)
			(xy 144.612622 -306.189548) (xy 144.529563 -306.305241) (xy 144.440091 -306.41605) (xy 144.344494 -306.521619)
			(xy 144.243077 -306.621611) (xy 144.136165 -306.715705) (xy 144.024101 -306.803599) (xy 143.907245 -306.885013)
			(xy 143.785969 -306.959686) (xy 143.660663 -307.027377) (xy 143.531728 -307.087871) (xy 143.399577 -307.140974)
			(xy 143.264634 -307.186515) (xy 143.12733 -307.224349) (xy 142.988105 -307.254354) (xy 142.847406 -307.276434)
			(xy 142.705684 -307.29052) (xy 142.563391 -307.296564) (xy 142.420984 -307.294549) (xy 142.278919 -307.28448)
			(xy 142.137652 -307.26639) (xy 141.997634 -307.240337) (xy 141.859315 -307.206404) (xy 141.723136 -307.164699)
			(xy 141.589536 -307.115358) (xy 141.45894 -307.058537) (xy 141.331769 -306.994418) (xy 141.208429 -306.923208)
			(xy 141.089315 -306.845133) (xy 140.974809 -306.760445) (xy 140.865277 -306.669414) (xy 140.761071 -306.572333)
			(xy 140.662525 -306.469511) (xy 140.569953 -306.361278) (xy 140.483653 -306.247982) (xy 140.403901 -306.129985)
			(xy 140.330952 -306.007665) (xy 140.26504 -305.881414) (xy 140.206377 -305.751635) (xy 140.15515 -305.618746)
			(xy 140.111523 -305.483172) (xy 140.075636 -305.345346) (xy 140.047604 -305.205711) (xy 140.027516 -305.064714)
			(xy 140.015438 -304.922806) (xy 140.011408 -304.780442) (xy 83.8454 -304.780442) (xy 83.844896 -304.851696)
			(xy 83.836834 -304.993975) (xy 83.820735 -305.13557) (xy 83.796651 -305.276027) (xy 83.764659 -305.414897)
			(xy 83.724862 -305.551735) (xy 83.677387 -305.686102) (xy 83.622387 -305.817568) (xy 83.560037 -305.945711)
			(xy 83.490537 -306.070122) (xy 83.414109 -306.190402) (xy 83.330999 -306.306165) (xy 83.241474 -306.417041)
			(xy 83.145818 -306.522674) (xy 83.04434 -306.622726) (xy 82.937364 -306.716877) (xy 82.825232 -306.804825)
			(xy 82.708304 -306.886288) (xy 82.586955 -306.961006) (xy 82.461573 -307.028739) (xy 82.33256 -307.089269)
			(xy 82.200329 -307.142404) (xy 82.065304 -307.187973) (xy 81.927917 -307.225829) (xy 81.788608 -307.255853)
			(xy 81.647824 -307.277947) (xy 81.506015 -307.29204) (xy 81.363636 -307.298088) (xy 81.221143 -307.296072)
			(xy 81.078993 -307.285997) (xy 80.93764 -307.267896) (xy 80.797537 -307.241827) (xy 80.659134 -307.207873)
			(xy 80.522873 -307.166144) (xy 80.389191 -307.116772) (xy 80.258517 -307.059917) (xy 80.131268 -306.99576)
			(xy 80.007853 -306.924506) (xy 79.888667 -306.846384) (xy 79.774092 -306.761645) (xy 79.664494 -306.670559)
			(xy 79.560225 -306.573418) (xy 79.461619 -306.470534) (xy 79.368991 -306.362236) (xy 79.282639 -306.248871)
			(xy 79.202838 -306.130803) (xy 79.129845 -306.008408) (xy 79.063894 -305.882081) (xy 79.005195 -305.752224)
			(xy 78.953936 -305.619254) (xy 78.910283 -305.483598) (xy 78.874374 -305.345689) (xy 78.846325 -305.205969)
			(xy 78.826226 -305.064886) (xy 78.81414 -304.922892) (xy 78.810108 -304.780442) (xy 2.509012 -304.780442)
			(xy 2.509012 -309.504588) (xy 79.192628 -309.504588) (xy 79.192628 -308.640988) (xy 79.193114 -308.613737)
			(xy 79.20087 -308.559789) (xy 79.216225 -308.507494) (xy 79.238867 -308.457917) (xy 79.268333 -308.412067)
			(xy 79.304024 -308.370876) (xy 79.345215 -308.335185) (xy 79.391065 -308.305719) (xy 79.440642 -308.283077)
			(xy 79.492937 -308.267722) (xy 79.546885 -308.259966) (xy 79.601387 -308.259966) (xy 79.655335 -308.267722)
			(xy 79.70763 -308.283077) (xy 79.757207 -308.305719) (xy 79.803057 -308.335185) (xy 79.844248 -308.370876)
			(xy 79.879939 -308.412067) (xy 79.909405 -308.457917) (xy 79.92811 -308.498873) (xy 93.275072 -308.498873)
			(xy 93.275072 -308.444327) (xy 93.282834 -308.390335) (xy 93.298202 -308.337998) (xy 93.320862 -308.288381)
			(xy 93.350352 -308.242493) (xy 93.386073 -308.20127) (xy 93.427297 -308.16555) (xy 93.473184 -308.13606)
			(xy 93.522802 -308.113401) (xy 93.575139 -308.098034) (xy 93.629131 -308.090271) (xy 93.656404 -308.089808)
			(xy 94.520004 -308.089808) (xy 94.547271 -308.090355) (xy 94.60125 -308.098116) (xy 94.653575 -308.113481)
			(xy 94.703181 -308.136135) (xy 94.749058 -308.165619) (xy 94.790271 -308.201331) (xy 94.825983 -308.242546)
			(xy 94.855467 -308.288423) (xy 94.878121 -308.338029) (xy 94.893485 -308.390354) (xy 94.901246 -308.444333)
			(xy 94.901246 -308.498867) (xy 94.893485 -308.552846) (xy 94.878121 -308.605171) (xy 94.855467 -308.654777)
			(xy 94.825983 -308.700654) (xy 94.790271 -308.741869) (xy 94.749058 -308.777581) (xy 94.703181 -308.807065)
			(xy 94.653575 -308.829719) (xy 94.60125 -308.845084) (xy 94.547271 -308.852845) (xy 94.520004 -308.853332)
			(xy 93.656404 -308.853332) (xy 93.629131 -308.852929) (xy 93.575139 -308.845166) (xy 93.522802 -308.829799)
			(xy 93.473184 -308.80714) (xy 93.427297 -308.77765) (xy 93.386073 -308.74193) (xy 93.350352 -308.700707)
			(xy 93.320862 -308.654819) (xy 93.298202 -308.605202) (xy 93.282834 -308.552865) (xy 93.275072 -308.498873)
			(xy 79.92811 -308.498873) (xy 79.932047 -308.507494) (xy 79.947402 -308.559789) (xy 79.955158 -308.613737)
			(xy 79.955644 -308.640988) (xy 79.955644 -309.303166) (xy 341.51824 -309.303166) (xy 341.51824 -308.439566)
			(xy 341.518726 -308.412297) (xy 341.526488 -308.358313) (xy 341.541853 -308.305983) (xy 341.56451 -308.256373)
			(xy 341.593996 -308.210492) (xy 341.629711 -308.169275) (xy 341.670928 -308.13356) (xy 341.716809 -308.104074)
			(xy 341.766419 -308.081417) (xy 341.818749 -308.066052) (xy 341.872733 -308.05829) (xy 341.927271 -308.05829)
			(xy 341.981255 -308.066052) (xy 342.033585 -308.081417) (xy 342.083195 -308.104074) (xy 342.129076 -308.13356)
			(xy 342.170293 -308.169275) (xy 342.206008 -308.210492) (xy 342.235494 -308.256373) (xy 342.258151 -308.305983)
			(xy 342.273516 -308.358313) (xy 342.281278 -308.412297) (xy 342.281764 -308.439566) (xy 342.281764 -309.303166)
			(xy 342.281278 -309.330435) (xy 342.273516 -309.384419) (xy 342.258151 -309.436749) (xy 342.235494 -309.486359)
			(xy 342.206008 -309.53224) (xy 342.170293 -309.573457) (xy 342.129076 -309.609172) (xy 342.083195 -309.638658)
			(xy 342.033585 -309.661315) (xy 341.981255 -309.67668) (xy 341.927271 -309.684442) (xy 341.872733 -309.684442)
			(xy 341.818749 -309.67668) (xy 341.766419 -309.661315) (xy 341.716809 -309.638658) (xy 341.670928 -309.609172)
			(xy 341.629711 -309.573457) (xy 341.593996 -309.53224) (xy 341.56451 -309.486359) (xy 341.541853 -309.436749)
			(xy 341.526488 -309.384419) (xy 341.518726 -309.330435) (xy 341.51824 -309.303166) (xy 79.955644 -309.303166)
			(xy 79.955644 -309.504588) (xy 79.955158 -309.531839) (xy 79.947402 -309.585787) (xy 79.932047 -309.638082)
			(xy 79.909405 -309.687659) (xy 79.879939 -309.733509) (xy 79.844248 -309.7747) (xy 79.803057 -309.810391)
			(xy 79.757207 -309.839857) (xy 79.70763 -309.862499) (xy 79.655335 -309.877854) (xy 79.601387 -309.88561)
			(xy 79.546885 -309.88561) (xy 79.492937 -309.877854) (xy 79.440642 -309.862499) (xy 79.391065 -309.839857)
			(xy 79.345215 -309.810391) (xy 79.304024 -309.7747) (xy 79.268333 -309.733509) (xy 79.238867 -309.687659)
			(xy 79.216225 -309.638082) (xy 79.20087 -309.585787) (xy 79.193114 -309.531839) (xy 79.192628 -309.504588)
			(xy 2.509012 -309.504588) (xy 2.509012 -310.603646) (xy 98.925888 -310.603646) (xy 98.925888 -309.740046)
			(xy 98.926374 -309.712795) (xy 98.93413 -309.658847) (xy 98.949485 -309.606552) (xy 98.972127 -309.556975)
			(xy 99.001593 -309.511125) (xy 99.037284 -309.469934) (xy 99.078475 -309.434243) (xy 99.124325 -309.404777)
			(xy 99.173902 -309.382135) (xy 99.226197 -309.36678) (xy 99.280145 -309.359024) (xy 99.334647 -309.359024)
			(xy 99.388595 -309.36678) (xy 99.44089 -309.382135) (xy 99.490467 -309.404777) (xy 99.536317 -309.434243)
			(xy 99.577508 -309.469934) (xy 99.613199 -309.511125) (xy 99.642665 -309.556975) (xy 99.665307 -309.606552)
			(xy 99.680662 -309.658847) (xy 99.688418 -309.712795) (xy 99.688904 -309.740046) (xy 99.688904 -310.603646)
			(xy 99.688418 -310.630897) (xy 99.680662 -310.684845) (xy 99.665307 -310.73714) (xy 99.642665 -310.786717)
			(xy 99.613199 -310.832567) (xy 99.577508 -310.873758) (xy 99.536317 -310.909449) (xy 99.490467 -310.938915)
			(xy 99.44089 -310.961557) (xy 99.388595 -310.976912) (xy 99.334647 -310.984668) (xy 99.280145 -310.984668)
			(xy 99.226197 -310.976912) (xy 99.173902 -310.961557) (xy 99.124325 -310.938915) (xy 99.078475 -310.909449)
			(xy 99.037284 -310.873758) (xy 99.001593 -310.832567) (xy 98.972127 -310.786717) (xy 98.949485 -310.73714)
			(xy 98.93413 -310.684845) (xy 98.926374 -310.630897) (xy 98.925888 -310.603646) (xy 2.509012 -310.603646)
			(xy 2.509012 -311.513728) (xy 347.772228 -311.513728) (xy 347.772228 -310.650128) (xy 347.772714 -310.622859)
			(xy 347.780476 -310.568875) (xy 347.795841 -310.516545) (xy 347.818498 -310.466935) (xy 347.847984 -310.421054)
			(xy 347.883699 -310.379837) (xy 347.924916 -310.344122) (xy 347.970797 -310.314636) (xy 348.020407 -310.291979)
			(xy 348.072737 -310.276614) (xy 348.126721 -310.268852) (xy 348.181259 -310.268852) (xy 348.235243 -310.276614)
			(xy 348.287573 -310.291979) (xy 348.337183 -310.314636) (xy 348.383064 -310.344122) (xy 348.424281 -310.379837)
			(xy 348.459996 -310.421054) (xy 348.489482 -310.466935) (xy 348.512139 -310.516545) (xy 348.527504 -310.568875)
			(xy 348.535266 -310.622859) (xy 348.535752 -310.650128) (xy 348.535752 -311.513728) (xy 348.535266 -311.540997)
			(xy 348.527504 -311.594981) (xy 348.512139 -311.647311) (xy 348.489482 -311.696921) (xy 348.459996 -311.742802)
			(xy 348.424281 -311.784019) (xy 348.383064 -311.819734) (xy 348.337183 -311.84922) (xy 348.287573 -311.871877)
			(xy 348.235243 -311.887242) (xy 348.181259 -311.895004) (xy 348.126721 -311.895004) (xy 348.072737 -311.887242)
			(xy 348.020407 -311.871877) (xy 347.970797 -311.84922) (xy 347.924916 -311.819734) (xy 347.883699 -311.784019)
			(xy 347.847984 -311.742802) (xy 347.818498 -311.696921) (xy 347.795841 -311.647311) (xy 347.780476 -311.594981)
			(xy 347.772714 -311.540997) (xy 347.772228 -311.513728) (xy 2.509012 -311.513728) (xy 2.509012 -314.997338)
			(xy 98.330512 -314.997338) (xy 98.330512 -314.133738) (xy 98.330998 -314.106487) (xy 98.338754 -314.052539)
			(xy 98.354109 -314.000244) (xy 98.376751 -313.950667) (xy 98.406217 -313.904817) (xy 98.441908 -313.863626)
			(xy 98.483099 -313.827935) (xy 98.528949 -313.798469) (xy 98.578526 -313.775827) (xy 98.630821 -313.760472)
			(xy 98.684769 -313.752716) (xy 98.739271 -313.752716) (xy 98.793219 -313.760472) (xy 98.845514 -313.775827)
			(xy 98.895091 -313.798469) (xy 98.940941 -313.827935) (xy 98.982132 -313.863626) (xy 99.017823 -313.904817)
			(xy 99.047289 -313.950667) (xy 99.069931 -314.000244) (xy 99.085286 -314.052539) (xy 99.093042 -314.106487)
			(xy 99.093528 -314.133738) (xy 99.093528 -314.997338) (xy 99.093042 -315.024589) (xy 99.085286 -315.078537)
			(xy 99.069931 -315.130832) (xy 99.047289 -315.180409) (xy 99.017823 -315.226259) (xy 98.982132 -315.26745)
			(xy 98.940941 -315.303141) (xy 98.895091 -315.332607) (xy 98.845514 -315.355249) (xy 98.793219 -315.370604)
			(xy 98.739271 -315.37836) (xy 98.684769 -315.37836) (xy 98.630821 -315.370604) (xy 98.578526 -315.355249)
			(xy 98.528949 -315.332607) (xy 98.483099 -315.303141) (xy 98.441908 -315.26745) (xy 98.406217 -315.226259)
			(xy 98.376751 -315.180409) (xy 98.354109 -315.130832) (xy 98.338754 -315.078537) (xy 98.330998 -315.024589)
			(xy 98.330512 -314.997338) (xy 2.509012 -314.997338) (xy 2.509012 -336.9884) (xy 70.218517 -336.9884)
			(xy 70.222508 -336.904617) (xy 70.234446 -336.821593) (xy 70.254221 -336.74008) (xy 70.281655 -336.660815)
			(xy 70.3165 -336.584518) (xy 70.35844 -336.511878) (xy 70.407095 -336.443554) (xy 70.462025 -336.380164)
			(xy 70.522731 -336.322283) (xy 70.588664 -336.270435) (xy 70.659228 -336.225089) (xy 70.733783 -336.186656)
			(xy 70.811653 -336.155484) (xy 70.892134 -336.131855) (xy 70.974497 -336.115984) (xy 71.057995 -336.108014)
			(xy 71.099934 -336.107532) (xy 71.137123 -336.107938) (xy 71.211236 -336.114223) (xy 71.284556 -336.126727)
			(xy 71.356562 -336.145363) (xy 71.39178 -336.157316) (xy 71.399977 -336.15983) (xy 71.417111 -336.15983)
			(xy 71.425308 -336.157316) (xy 71.460496 -336.145371) (xy 71.532436 -336.126725) (xy 71.605692 -336.114215)
			(xy 71.679742 -336.107929) (xy 71.7169 -336.107532) (xy 71.717408 -336.107532) (xy 71.748142 -336.108294)
			(xy 71.757646 -336.056715) (xy 71.787316 -335.956115) (xy 71.807324 -335.907634) (xy 71.810983 -335.897931)
			(xy 71.810971 -335.877211) (xy 71.807324 -335.867502) (xy 71.790219 -335.826242) (xy 71.763427 -335.741032)
			(xy 71.74539 -335.653549) (xy 71.736293 -335.564691) (xy 71.735696 -335.52003) (xy 71.735696 -335.519268)
			(xy 71.736195 -335.477343) (xy 71.744165 -335.393872) (xy 71.760034 -335.311537) (xy 71.783657 -335.231083)
			(xy 71.814821 -335.153239) (xy 71.853244 -335.078709) (xy 71.898577 -335.00817) (xy 71.95041 -334.942259)
			(xy 72.008273 -334.881573) (xy 72.071643 -334.826663) (xy 72.139946 -334.778025) (xy 72.212563 -334.7361)
			(xy 72.288836 -334.701267) (xy 72.368075 -334.673842) (xy 72.449561 -334.654073) (xy 72.532558 -334.64214)
			(xy 72.616314 -334.638151) (xy 72.70007 -334.64214) (xy 72.783067 -334.654073) (xy 72.864553 -334.673842)
			(xy 72.943792 -334.701267) (xy 73.020065 -334.7361) (xy 73.092682 -334.778025) (xy 73.160985 -334.826663)
			(xy 73.224355 -334.881573) (xy 73.282218 -334.942259) (xy 73.334051 -335.00817) (xy 73.379384 -335.078709)
			(xy 73.417807 -335.153239) (xy 73.448971 -335.231083) (xy 73.472594 -335.311537) (xy 73.488463 -335.393872)
			(xy 73.496433 -335.477343) (xy 73.496932 -335.519268) (xy 73.496932 -335.52003) (xy 73.496371 -335.564694)
			(xy 73.487295 -335.653559) (xy 73.46926 -335.741047) (xy 73.442452 -335.826257) (xy 73.425304 -335.867502)
			(xy 73.421681 -335.877216) (xy 73.421669 -335.897926) (xy 73.425304 -335.907634) (xy 73.441139 -335.945575)
			(xy 73.466487 -336.02379) (xy 73.484436 -336.104027) (xy 73.494829 -336.185587) (xy 73.496678 -336.226658)
			(xy 73.496932 -336.24012) (xy 73.51141 -336.263234) (xy 73.61301 -336.31759) (xy 73.639934 -336.316828)
			(xy 73.651618 -336.309462) (xy 73.686811 -336.288202) (xy 73.76042 -336.251553) (xy 73.837094 -336.221845)
			(xy 73.91618 -336.199333) (xy 73.997005 -336.184209) (xy 74.07888 -336.1766) (xy 74.119994 -336.176112)
			(xy 74.161107 -336.176619) (xy 74.242983 -336.184205) (xy 74.32381 -336.199313) (xy 74.402898 -336.221815)
			(xy 74.479573 -336.251518) (xy 74.553179 -336.288168) (xy 74.623091 -336.331454) (xy 74.68871 -336.381006)
			(xy 74.749477 -336.4364) (xy 74.804874 -336.497166) (xy 74.854428 -336.562783) (xy 74.897716 -336.632693)
			(xy 74.934369 -336.706298) (xy 74.964075 -336.782971) (xy 74.986579 -336.862059) (xy 75.001691 -336.942885)
			(xy 75.005252 -336.9813) (xy 78.574105 -336.9813) (xy 78.578096 -336.897517) (xy 78.590033 -336.814493)
			(xy 78.609809 -336.732979) (xy 78.637243 -336.653715) (xy 78.672087 -336.577417) (xy 78.714027 -336.504776)
			(xy 78.762681 -336.436452) (xy 78.81761 -336.373061) (xy 78.878316 -336.31518) (xy 78.94425 -336.26333)
			(xy 79.014813 -336.217984) (xy 79.089367 -336.179549) (xy 79.167237 -336.148376) (xy 79.247718 -336.124747)
			(xy 79.330081 -336.108874) (xy 79.413579 -336.100902) (xy 79.455518 -336.10042) (xy 79.492708 -336.100802)
			(xy 79.566821 -336.107094) (xy 79.640141 -336.119606) (xy 79.712146 -336.138248) (xy 79.747364 -336.150204)
			(xy 79.755561 -336.152718) (xy 79.772695 -336.152718) (xy 79.780892 -336.150204) (xy 79.816103 -336.138226)
			(xy 79.888108 -336.119576) (xy 79.961431 -336.107072) (xy 80.035547 -336.100804) (xy 80.072738 -336.10042)
			(xy 80.10906 -336.101182) (xy 80.115245 -336.066241) (xy 80.132513 -335.997409) (xy 80.155273 -335.930194)
			(xy 80.169004 -335.897474) (xy 80.172641 -335.887764) (xy 80.172644 -335.86705) (xy 80.169004 -335.857342)
			(xy 80.151879 -335.81609) (xy 80.125092 -335.730877) (xy 80.107061 -335.643392) (xy 80.09797 -335.554532)
			(xy 80.097376 -335.50987) (xy 80.097376 -335.509108) (xy 80.097875 -335.467183) (xy 80.105845 -335.383712)
			(xy 80.121714 -335.301377) (xy 80.145337 -335.220923) (xy 80.176501 -335.143079) (xy 80.214924 -335.068549)
			(xy 80.260257 -334.99801) (xy 80.31209 -334.932099) (xy 80.369953 -334.871413) (xy 80.433323 -334.816503)
			(xy 80.501626 -334.767865) (xy 80.574243 -334.72594) (xy 80.650516 -334.691107) (xy 80.729755 -334.663682)
			(xy 80.811241 -334.643913) (xy 80.894238 -334.63198) (xy 80.977994 -334.627991) (xy 81.06175 -334.63198)
			(xy 81.144747 -334.643913) (xy 81.226233 -334.663682) (xy 81.305472 -334.691107) (xy 81.381745 -334.72594)
			(xy 81.454362 -334.767865) (xy 81.522665 -334.816503) (xy 81.586035 -334.871413) (xy 81.643898 -334.932099)
			(xy 81.695731 -334.99801) (xy 81.741064 -335.068549) (xy 81.779487 -335.143079) (xy 81.810651 -335.220923)
			(xy 81.834274 -335.301377) (xy 81.850143 -335.383712) (xy 81.858113 -335.467183) (xy 81.858612 -335.509108)
			(xy 81.858612 -335.50987) (xy 81.858066 -335.554534) (xy 81.848986 -335.6434) (xy 81.830947 -335.730888)
			(xy 81.804134 -335.816098) (xy 81.786984 -335.857342) (xy 81.783338 -335.867049) (xy 81.783341 -335.887765)
			(xy 81.786984 -335.897474) (xy 81.802748 -335.935334) (xy 81.827987 -336.013369) (xy 81.845871 -336.093411)
			(xy 81.856247 -336.174768) (xy 81.858104 -336.215736) (xy 81.858828 -336.22455) (xy 81.865419 -336.240944)
			(xy 81.877182 -336.254128) (xy 81.884774 -336.258662) (xy 81.973928 -336.306922) (xy 82.000852 -336.30616)
			(xy 82.012536 -336.299048) (xy 82.047432 -336.278305) (xy 82.120306 -336.242523) (xy 82.19614 -336.213534)
			(xy 82.2743 -336.191579) (xy 82.354137 -336.176843) (xy 82.434985 -336.169448) (xy 82.475578 -336.169)
			(xy 82.516691 -336.169534) (xy 82.598566 -336.177119) (xy 82.679391 -336.192225) (xy 82.758479 -336.214725)
			(xy 82.835153 -336.244426) (xy 82.908759 -336.281075) (xy 82.97867 -336.324359) (xy 83.044289 -336.373909)
			(xy 83.105056 -336.429302) (xy 83.160453 -336.490065) (xy 83.210007 -336.555681) (xy 83.253296 -336.625589)
			(xy 83.28995 -336.699193) (xy 83.319656 -336.775864) (xy 83.342161 -336.85495) (xy 83.357273 -336.935775)
			(xy 83.360149 -336.9668) (xy 86.931981 -336.9668) (xy 86.935971 -336.883042) (xy 86.947905 -336.800043)
			(xy 86.967674 -336.718554) (xy 86.9951 -336.639313) (xy 87.029935 -336.563039) (xy 87.071862 -336.490421)
			(xy 87.120503 -336.422117) (xy 87.175416 -336.358746) (xy 87.236104 -336.300883) (xy 87.302018 -336.24905)
			(xy 87.37256 -336.203717) (xy 87.447092 -336.165296) (xy 87.52494 -336.134133) (xy 87.605396 -336.110512)
			(xy 87.687734 -336.094645) (xy 87.771208 -336.086677) (xy 87.813134 -336.086196) (xy 87.81415 -336.086196)
			(xy 87.851207 -336.086587) (xy 87.925057 -336.092856) (xy 87.998119 -336.105302) (xy 88.069879 -336.123838)
			(xy 88.10498 -336.135726) (xy 88.113177 -336.13824) (xy 88.130311 -336.13824) (xy 88.138508 -336.135726)
			(xy 88.173727 -336.123789) (xy 88.245736 -336.1052) (xy 88.319058 -336.092757) (xy 88.393169 -336.086549)
			(xy 88.430354 -336.086196) (xy 88.454992 -336.08645) (xy 88.464629 -336.040549) (xy 88.49238 -335.950951)
			(xy 88.510364 -335.907634) (xy 88.514021 -335.89793) (xy 88.514009 -335.877211) (xy 88.510364 -335.867502)
			(xy 88.493256 -335.826243) (xy 88.466465 -335.741033) (xy 88.448429 -335.65355) (xy 88.439333 -335.564691)
			(xy 88.438736 -335.52003) (xy 88.438736 -335.519268) (xy 88.439235 -335.477343) (xy 88.447205 -335.393872)
			(xy 88.463074 -335.311537) (xy 88.486697 -335.231083) (xy 88.517861 -335.153239) (xy 88.556284 -335.078709)
			(xy 88.601617 -335.00817) (xy 88.65345 -334.942259) (xy 88.711313 -334.881573) (xy 88.774683 -334.826663)
			(xy 88.842986 -334.778025) (xy 88.915603 -334.7361) (xy 88.991876 -334.701267) (xy 89.071115 -334.673842)
			(xy 89.152601 -334.654073) (xy 89.235598 -334.64214) (xy 89.319354 -334.638151) (xy 89.40311 -334.64214)
			(xy 89.486107 -334.654073) (xy 89.567593 -334.673842) (xy 89.646832 -334.701267) (xy 89.723105 -334.7361)
			(xy 89.795722 -334.778025) (xy 89.864025 -334.826663) (xy 89.927395 -334.881573) (xy 89.985258 -334.942259)
			(xy 90.037091 -335.00817) (xy 90.082424 -335.078709) (xy 90.120847 -335.153239) (xy 90.152011 -335.231083)
			(xy 90.175634 -335.311537) (xy 90.191503 -335.393872) (xy 90.199473 -335.477343) (xy 90.199972 -335.519268)
			(xy 90.199972 -335.52003) (xy 90.199408 -335.564694) (xy 90.190332 -335.653559) (xy 90.172298 -335.741047)
			(xy 90.145491 -335.826257) (xy 90.128344 -335.867502) (xy 90.124724 -335.877216) (xy 90.124712 -335.897925)
			(xy 90.128344 -335.907634) (xy 90.14352 -335.944017) (xy 90.168055 -336.018939) (xy 90.185802 -336.095753)
			(xy 90.196619 -336.173844) (xy 90.198956 -336.213196) (xy 90.198956 -336.21345) (xy 90.199799 -336.222253)
			(xy 90.206694 -336.238523) (xy 90.218709 -336.251482) (xy 90.226388 -336.255868) (xy 90.316812 -336.302604)
			(xy 90.343482 -336.301334) (xy 90.355166 -336.293968) (xy 90.390883 -336.271832) (xy 90.465707 -336.233583)
			(xy 90.543804 -336.20256) (xy 90.624479 -336.17904) (xy 90.707013 -336.163233) (xy 90.790669 -336.155279)
			(xy 90.832686 -336.154776) (xy 90.833194 -336.154776) (xy 90.874302 -336.155218) (xy 90.956167 -336.162803)
			(xy 91.036983 -336.177907) (xy 91.116061 -336.200402) (xy 91.192727 -336.230097) (xy 91.266326 -336.266738)
			(xy 91.336231 -336.310013) (xy 91.401845 -336.359552) (xy 91.46261 -336.414933) (xy 91.518006 -336.475684)
			(xy 91.567562 -336.541286) (xy 91.610854 -336.61118) (xy 91.647513 -336.68477) (xy 91.677227 -336.761428)
			(xy 91.699742 -336.840501) (xy 91.714867 -336.921313) (xy 91.722471 -337.003176) (xy 91.722641 -337.0176)
			(xy 95.263181 -337.0176) (xy 95.267171 -336.933842) (xy 95.279105 -336.850843) (xy 95.298874 -336.769354)
			(xy 95.3263 -336.690113) (xy 95.361135 -336.613839) (xy 95.403062 -336.541221) (xy 95.451703 -336.472917)
			(xy 95.506616 -336.409546) (xy 95.567304 -336.351683) (xy 95.633218 -336.29985) (xy 95.70376 -336.254517)
			(xy 95.778292 -336.216096) (xy 95.85614 -336.184933) (xy 95.936596 -336.161312) (xy 96.018934 -336.145445)
			(xy 96.102408 -336.137477) (xy 96.144334 -336.136996) (xy 96.14535 -336.136996) (xy 96.182407 -336.137387)
			(xy 96.256257 -336.143656) (xy 96.329319 -336.156102) (xy 96.401079 -336.174638) (xy 96.43618 -336.186526)
			(xy 96.444377 -336.18904) (xy 96.461511 -336.18904) (xy 96.469708 -336.186526) (xy 96.504897 -336.174599)
			(xy 96.576843 -336.15602) (xy 96.650101 -336.143577) (xy 96.724146 -336.137359) (xy 96.7613 -336.136996)
			(xy 96.761808 -336.136996) (xy 96.796352 -336.137504) (xy 96.805918 -336.09484) (xy 96.832381 -336.0115)
			(xy 96.849184 -335.971134) (xy 96.852845 -335.961431) (xy 96.852833 -335.940711) (xy 96.849184 -335.931002)
			(xy 96.832077 -335.889743) (xy 96.805286 -335.804532) (xy 96.78725 -335.717049) (xy 96.778153 -335.628191)
			(xy 96.777556 -335.58353) (xy 96.777556 -335.582768) (xy 96.778055 -335.540843) (xy 96.786025 -335.457372)
			(xy 96.801894 -335.375037) (xy 96.825517 -335.294583) (xy 96.856681 -335.216739) (xy 96.895104 -335.142209)
			(xy 96.940437 -335.07167) (xy 96.99227 -335.005759) (xy 97.050133 -334.945073) (xy 97.113503 -334.890163)
			(xy 97.181806 -334.841525) (xy 97.254423 -334.7996) (xy 97.330696 -334.764767) (xy 97.409935 -334.737342)
			(xy 97.491421 -334.717573) (xy 97.574418 -334.70564) (xy 97.658174 -334.701651) (xy 97.74193 -334.70564)
			(xy 97.824927 -334.717573) (xy 97.906413 -334.737342) (xy 97.985652 -334.764767) (xy 98.061925 -334.7996)
			(xy 98.134542 -334.841525) (xy 98.202845 -334.890163) (xy 98.266215 -334.945073) (xy 98.324078 -335.005759)
			(xy 98.375911 -335.07167) (xy 98.421244 -335.142209) (xy 98.459667 -335.216739) (xy 98.490831 -335.294583)
			(xy 98.514454 -335.375037) (xy 98.530323 -335.457372) (xy 98.538293 -335.540843) (xy 98.538792 -335.582768)
			(xy 98.538792 -335.58353) (xy 98.538226 -335.628194) (xy 98.529151 -335.717059) (xy 98.511117 -335.804547)
			(xy 98.484311 -335.889757) (xy 98.467164 -335.931002) (xy 98.463542 -335.940716) (xy 98.463531 -335.961426)
			(xy 98.467164 -335.971134) (xy 98.48433 -336.012473) (xy 98.511159 -336.097874) (xy 98.529194 -336.185554)
			(xy 98.538249 -336.27461) (xy 98.538792 -336.319368) (xy 98.538552 -336.350973) (xy 98.534101 -336.414026)
			(xy 98.529902 -336.445352) (xy 98.528378 -336.45602) (xy 98.53422 -336.477102) (xy 98.590608 -336.543396)
			(xy 98.597904 -336.55118) (xy 98.617064 -336.560504) (xy 98.627692 -336.56143) (xy 98.6282 -336.56143)
			(xy 98.671147 -336.563026) (xy 98.756458 -336.573467) (xy 98.840365 -336.592088) (xy 98.922084 -336.618714)
			(xy 99.000854 -336.653099) (xy 99.07594 -336.69492) (xy 99.146643 -336.743788) (xy 99.212303 -336.799248)
			(xy 99.272307 -336.860782) (xy 99.326097 -336.927817) (xy 99.362614 -336.9836) (xy 318.155561 -336.9836)
			(xy 318.15955 -336.899842) (xy 318.171484 -336.816843) (xy 318.191253 -336.735354) (xy 318.218678 -336.656114)
			(xy 318.253512 -336.579839) (xy 318.295438 -336.50722) (xy 318.344078 -336.438916) (xy 318.398989 -336.375544)
			(xy 318.459676 -336.317679) (xy 318.525589 -336.265845) (xy 318.59613 -336.220511) (xy 318.670661 -336.182087)
			(xy 318.748507 -336.150922) (xy 318.828963 -336.127298) (xy 318.911301 -336.111429) (xy 318.994774 -336.103459)
			(xy 319.0367 -336.10296) (xy 319.037716 -336.10296) (xy 319.074773 -336.103363) (xy 319.148622 -336.109628)
			(xy 319.221685 -336.122071) (xy 319.293445 -336.140604) (xy 319.328546 -336.15249) (xy 319.336743 -336.155004)
			(xy 319.353877 -336.155004) (xy 319.362074 -336.15249) (xy 319.397267 -336.140575) (xy 319.469212 -336.121992)
			(xy 319.542468 -336.109546) (xy 319.616513 -336.103324) (xy 319.653666 -336.10296) (xy 319.654174 -336.10296)
			(xy 319.681606 -336.103214) (xy 319.687655 -336.066844) (xy 319.704988 -335.995173) (xy 319.728195 -335.925184)
			(xy 319.742312 -335.891124) (xy 319.745871 -335.881532) (xy 319.745875 -335.86109) (xy 319.742312 -335.8515)
			(xy 319.725303 -335.810117) (xy 319.698681 -335.724692) (xy 319.680772 -335.637026) (xy 319.671759 -335.548004)
			(xy 319.671192 -335.503266) (xy 319.671192 -335.503012) (xy 319.671696 -335.460664) (xy 319.679747 -335.37635)
			(xy 319.695776 -335.293184) (xy 319.719637 -335.211917) (xy 319.751116 -335.133287) (xy 319.789927 -335.058006)
			(xy 319.835717 -334.986754) (xy 319.888073 -334.920178) (xy 319.946521 -334.85888) (xy 320.010531 -334.803415)
			(xy 320.079523 -334.754286) (xy 320.152873 -334.711937) (xy 320.229916 -334.676753) (xy 320.309955 -334.649051)
			(xy 320.392264 -334.629083) (xy 320.476099 -334.61703) (xy 320.5607 -334.613) (xy 320.645301 -334.61703)
			(xy 320.729136 -334.629083) (xy 320.811445 -334.649051) (xy 320.891484 -334.676753) (xy 320.968527 -334.711937)
			(xy 321.041877 -334.754286) (xy 321.110869 -334.803415) (xy 321.174879 -334.85888) (xy 321.233327 -334.920178)
			(xy 321.285683 -334.986754) (xy 321.331473 -335.058006) (xy 321.370284 -335.133287) (xy 321.401763 -335.211917)
			(xy 321.425624 -335.293184) (xy 321.441653 -335.37635) (xy 321.449704 -335.460664) (xy 321.450208 -335.503012)
			(xy 321.450208 -335.503266) (xy 321.449645 -335.548004) (xy 321.440627 -335.637026) (xy 321.422721 -335.724694)
			(xy 321.396107 -335.810121) (xy 321.379088 -335.8515) (xy 321.375596 -335.861115) (xy 321.37573 -335.881553)
			(xy 321.379342 -335.891124) (xy 321.395061 -335.929255) (xy 321.42019 -336.007817) (xy 321.437947 -336.088366)
			(xy 321.448179 -336.170212) (xy 321.449954 -336.211418) (xy 321.450208 -336.22488) (xy 321.464178 -336.24774)
			(xy 321.564762 -336.303112) (xy 321.591432 -336.302604) (xy 321.603116 -336.295746) (xy 321.637431 -336.275914)
			(xy 321.708951 -336.241747) (xy 321.783227 -336.214078) (xy 321.859671 -336.193127) (xy 321.937675 -336.179058)
			(xy 322.016621 -336.171985) (xy 322.056252 -336.17154) (xy 322.05676 -336.17154) (xy 322.097864 -336.17199)
			(xy 322.179721 -336.179572) (xy 322.26053 -336.194675) (xy 322.3396 -336.21717) (xy 322.416257 -336.246866)
			(xy 322.489847 -336.283508) (xy 322.559742 -336.326784) (xy 322.625346 -336.376325) (xy 322.686098 -336.431708)
			(xy 322.74148 -336.492461) (xy 322.791021 -336.558064) (xy 322.834296 -336.62796) (xy 322.870938 -336.70155)
			(xy 322.900632 -336.778207) (xy 322.923127 -336.857278) (xy 322.938229 -336.938087) (xy 322.941787 -336.9765)
			(xy 326.511148 -336.9765) (xy 326.515138 -336.892742) (xy 326.527072 -336.809743) (xy 326.546841 -336.728254)
			(xy 326.574266 -336.649013) (xy 326.609099 -336.572737) (xy 326.651025 -336.500118) (xy 326.699664 -336.431814)
			(xy 326.754575 -336.368441) (xy 326.815262 -336.310576) (xy 326.881174 -336.258741) (xy 326.951715 -336.213406)
			(xy 327.026246 -336.174981) (xy 327.104092 -336.143815) (xy 327.184547 -336.12019) (xy 327.266885 -336.104319)
			(xy 327.350358 -336.096347) (xy 327.392284 -336.095848) (xy 327.3933 -336.095848) (xy 327.430357 -336.096256)
			(xy 327.504206 -336.10252) (xy 327.577268 -336.114961) (xy 327.649028 -336.133493) (xy 327.68413 -336.145378)
			(xy 327.692327 -336.147892) (xy 327.709461 -336.147892) (xy 327.717658 -336.145378) (xy 327.752881 -336.133453)
			(xy 327.824889 -336.114861) (xy 327.898209 -336.102415) (xy 327.972319 -336.096203) (xy 328.009504 -336.095848)
			(xy 328.043286 -336.096356) (xy 328.05281 -336.047304) (xy 328.081456 -335.951571) (xy 328.100436 -335.905348)
			(xy 328.10398 -335.895751) (xy 328.103994 -335.875314) (xy 328.100436 -335.865724) (xy 328.083404 -335.82435)
			(xy 328.056787 -335.738922) (xy 328.038886 -335.651253) (xy 328.02988 -335.562229) (xy 328.029316 -335.51749)
			(xy 328.029316 -335.517236) (xy 328.02982 -335.474888) (xy 328.037871 -335.390574) (xy 328.0539 -335.307408)
			(xy 328.077761 -335.226141) (xy 328.10924 -335.147511) (xy 328.148051 -335.07223) (xy 328.193841 -335.000978)
			(xy 328.246197 -334.934402) (xy 328.304645 -334.873104) (xy 328.368655 -334.817639) (xy 328.437647 -334.76851)
			(xy 328.510997 -334.726161) (xy 328.58804 -334.690977) (xy 328.668079 -334.663275) (xy 328.750388 -334.643307)
			(xy 328.834223 -334.631254) (xy 328.918824 -334.627224) (xy 329.003425 -334.631254) (xy 329.08726 -334.643307)
			(xy 329.169569 -334.663275) (xy 329.249608 -334.690977) (xy 329.326651 -334.726161) (xy 329.400001 -334.76851)
			(xy 329.468993 -334.817639) (xy 329.533003 -334.873104) (xy 329.591451 -334.934402) (xy 329.643807 -335.000978)
			(xy 329.689597 -335.07223) (xy 329.728408 -335.147511) (xy 329.759887 -335.226141) (xy 329.783748 -335.307408)
			(xy 329.799777 -335.390574) (xy 329.807828 -335.474888) (xy 329.808332 -335.517236) (xy 329.808332 -335.51749)
			(xy 329.807775 -335.562229) (xy 329.798756 -335.651251) (xy 329.780848 -335.738918) (xy 329.754231 -335.824345)
			(xy 329.737212 -335.865724) (xy 329.733624 -335.875308) (xy 329.733638 -335.895757) (xy 329.737212 -335.905348)
			(xy 329.752022 -335.941175) (xy 329.776095 -336.014872) (xy 329.793653 -336.090386) (xy 329.804563 -336.167144)
			(xy 329.807062 -336.20583) (xy 329.807824 -336.219038) (xy 329.822048 -336.24139) (xy 329.91044 -336.288888)
			(xy 329.918254 -336.292745) (xy 329.93547 -336.295369) (xy 329.95256 -336.292022) (xy 329.960224 -336.287872)
			(xy 329.994483 -336.268147) (xy 330.065868 -336.23417) (xy 330.139986 -336.206662) (xy 330.216254 -336.18584)
			(xy 330.294068 -336.171868) (xy 330.372815 -336.164856) (xy 330.412344 -336.164428) (xy 330.453448 -336.164825)
			(xy 330.535306 -336.172414) (xy 330.616114 -336.187524) (xy 330.695183 -336.210025) (xy 330.771839 -336.239726)
			(xy 330.845427 -336.276373) (xy 330.91532 -336.319653) (xy 330.980922 -336.369198) (xy 331.041672 -336.424584)
			(xy 331.097053 -336.48534) (xy 331.146592 -336.550946) (xy 331.189866 -336.620843) (xy 331.226507 -336.694434)
			(xy 331.256201 -336.771093) (xy 331.278695 -336.850164) (xy 331.293797 -336.930973) (xy 331.296671 -336.962)
			(xy 334.868517 -336.962) (xy 334.872507 -336.878219) (xy 334.884444 -336.795197) (xy 334.904219 -336.713686)
			(xy 334.931652 -336.634423) (xy 334.966495 -336.558127) (xy 335.008433 -336.485488) (xy 335.057086 -336.417165)
			(xy 335.112013 -336.353776) (xy 335.172717 -336.295895) (xy 335.238647 -336.244046) (xy 335.309208 -336.198699)
			(xy 335.38376 -336.160265) (xy 335.461628 -336.129092) (xy 335.542106 -336.105461) (xy 335.624466 -336.089588)
			(xy 335.707962 -336.081615) (xy 335.7499 -336.081116) (xy 335.78709 -336.081504) (xy 335.861203 -336.087794)
			(xy 335.934522 -336.100304) (xy 336.006528 -336.118945) (xy 336.041746 -336.1309) (xy 336.049943 -336.133414)
			(xy 336.067077 -336.133414) (xy 336.075274 -336.1309) (xy 336.110487 -336.118927) (xy 336.182491 -336.100276)
			(xy 336.255813 -336.08777) (xy 336.329929 -336.0815) (xy 336.36712 -336.081116) (xy 336.407506 -336.082132)
			(xy 336.417036 -336.036786) (xy 336.444265 -335.948213) (xy 336.461862 -335.905348) (xy 336.465474 -335.895775)
			(xy 336.465619 -335.875336) (xy 336.462116 -335.865724) (xy 336.445083 -335.824351) (xy 336.418467 -335.738922)
			(xy 336.400565 -335.651253) (xy 336.39156 -335.562229) (xy 336.390996 -335.51749) (xy 336.390996 -335.517236)
			(xy 336.3915 -335.474888) (xy 336.399551 -335.390574) (xy 336.41558 -335.307408) (xy 336.439441 -335.226141)
			(xy 336.47092 -335.147511) (xy 336.509731 -335.07223) (xy 336.555521 -335.000978) (xy 336.607877 -334.934402)
			(xy 336.666325 -334.873104) (xy 336.730335 -334.817639) (xy 336.799327 -334.76851) (xy 336.872677 -334.726161)
			(xy 336.94972 -334.690977) (xy 337.029759 -334.663275) (xy 337.112068 -334.643307) (xy 337.195903 -334.631254)
			(xy 337.280504 -334.627224) (xy 337.365105 -334.631254) (xy 337.44894 -334.643307) (xy 337.531249 -334.663275)
			(xy 337.611288 -334.690977) (xy 337.688331 -334.726161) (xy 337.761681 -334.76851) (xy 337.830673 -334.817639)
			(xy 337.894683 -334.873104) (xy 337.953131 -334.934402) (xy 338.005487 -335.000978) (xy 338.051277 -335.07223)
			(xy 338.090088 -335.147511) (xy 338.121567 -335.226141) (xy 338.145428 -335.307408) (xy 338.161457 -335.390574)
			(xy 338.169508 -335.474888) (xy 338.170012 -335.517236) (xy 338.170012 -335.51749) (xy 338.169456 -335.562229)
			(xy 338.160437 -335.651251) (xy 338.142528 -335.738918) (xy 338.115912 -335.824345) (xy 338.098892 -335.865724)
			(xy 338.095386 -335.875335) (xy 338.09553 -335.895777) (xy 338.099146 -335.905348) (xy 338.117792 -335.95091)
			(xy 338.146101 -336.045203) (xy 338.163844 -336.142042) (xy 338.16798 -336.191098) (xy 338.168919 -336.199672)
			(xy 338.175759 -336.215494) (xy 338.187449 -336.228161) (xy 338.194904 -336.2325) (xy 338.283042 -336.278728)
			(xy 338.309204 -336.27822) (xy 338.320634 -336.271616) (xy 338.354723 -336.252133) (xy 338.425722 -336.218592)
			(xy 338.499399 -336.191437) (xy 338.575183 -336.170878) (xy 338.652483 -336.157075) (xy 338.730699 -336.150137)
			(xy 338.76996 -336.149696) (xy 338.811054 -336.150204) (xy 338.892893 -336.157783) (xy 338.973684 -336.172879)
			(xy 339.052737 -336.195365) (xy 339.129379 -336.225047) (xy 339.202956 -336.261673) (xy 339.27284 -336.304931)
			(xy 339.338435 -336.354452) (xy 339.399182 -336.409813) (xy 339.454563 -336.470542) (xy 339.504105 -336.536121)
			(xy 339.547386 -336.605991) (xy 339.584036 -336.679555) (xy 339.613743 -336.756188) (xy 339.636254 -336.835234)
			(xy 339.651377 -336.916019) (xy 339.658982 -336.997856) (xy 339.659159 -337.0128) (xy 343.199717 -337.0128)
			(xy 343.203707 -336.929019) (xy 343.215644 -336.845997) (xy 343.235419 -336.764486) (xy 343.262852 -336.685223)
			(xy 343.297695 -336.608927) (xy 343.339633 -336.536288) (xy 343.388286 -336.467965) (xy 343.443213 -336.404576)
			(xy 343.503917 -336.346695) (xy 343.569847 -336.294846) (xy 343.640408 -336.249499) (xy 343.71496 -336.211065)
			(xy 343.792828 -336.179892) (xy 343.873306 -336.156261) (xy 343.955666 -336.140388) (xy 344.039162 -336.132415)
			(xy 344.0811 -336.131916) (xy 344.11829 -336.132304) (xy 344.192403 -336.138594) (xy 344.265722 -336.151104)
			(xy 344.337728 -336.169745) (xy 344.372946 -336.1817) (xy 344.381143 -336.184214) (xy 344.398277 -336.184214)
			(xy 344.406474 -336.1817) (xy 344.441687 -336.169727) (xy 344.513691 -336.151076) (xy 344.587013 -336.13857)
			(xy 344.661129 -336.1323) (xy 344.69832 -336.131916) (xy 344.712798 -336.13217) (xy 344.724169 -336.131792)
			(xy 344.744841 -336.122355) (xy 344.759419 -336.104924) (xy 344.762836 -336.09407) (xy 344.771457 -336.062103)
			(xy 344.792812 -335.999426) (xy 344.805508 -335.968848) (xy 344.809054 -335.959252) (xy 344.809067 -335.938814)
			(xy 344.805508 -335.929224) (xy 344.788475 -335.887851) (xy 344.761859 -335.802423) (xy 344.743957 -335.714753)
			(xy 344.734952 -335.625729) (xy 344.734388 -335.58099) (xy 344.734388 -335.580736) (xy 344.734892 -335.538388)
			(xy 344.742943 -335.454074) (xy 344.758972 -335.370908) (xy 344.782833 -335.289641) (xy 344.814312 -335.211011)
			(xy 344.853123 -335.13573) (xy 344.898913 -335.064478) (xy 344.951269 -334.997902) (xy 345.009717 -334.936604)
			(xy 345.073727 -334.881139) (xy 345.142719 -334.83201) (xy 345.216069 -334.789661) (xy 345.293112 -334.754477)
			(xy 345.373151 -334.726775) (xy 345.45546 -334.706807) (xy 345.539295 -334.694754) (xy 345.623896 -334.690724)
			(xy 345.708497 -334.694754) (xy 345.792332 -334.706807) (xy 345.874641 -334.726775) (xy 345.95468 -334.754477)
			(xy 346.031723 -334.789661) (xy 346.105073 -334.83201) (xy 346.174065 -334.881139) (xy 346.238075 -334.936604)
			(xy 346.296523 -334.997902) (xy 346.348879 -335.064478) (xy 346.394669 -335.13573) (xy 346.43348 -335.211011)
			(xy 346.464959 -335.289641) (xy 346.48882 -335.370908) (xy 346.504849 -335.454074) (xy 346.5129 -335.538388)
			(xy 346.513404 -335.580736) (xy 346.513404 -335.58099) (xy 346.512849 -335.625729) (xy 346.50383 -335.714751)
			(xy 346.485921 -335.802418) (xy 346.459304 -335.887845) (xy 346.442284 -335.929224) (xy 346.438698 -335.938808)
			(xy 346.438711 -335.959257) (xy 346.442284 -335.968848) (xy 346.459319 -336.010255) (xy 346.48595 -336.095744)
			(xy 346.503854 -336.183477) (xy 346.51285 -336.272565) (xy 346.513404 -336.317336) (xy 346.513182 -336.348682)
			(xy 346.508857 -336.411225) (xy 346.504768 -336.442304) (xy 346.503244 -336.452972) (xy 346.508832 -336.473546)
			(xy 346.56268 -336.539586) (xy 346.569651 -336.547336) (xy 346.588142 -336.55691) (xy 346.598494 -336.558128)
			(xy 346.599002 -336.558128) (xy 346.640786 -336.561293) (xy 346.723543 -336.574476) (xy 346.804694 -336.595383)
			(xy 346.883519 -336.62383) (xy 346.959319 -336.659564) (xy 347.031422 -336.702268) (xy 347.09919 -336.751564)
			(xy 347.162022 -336.807015) (xy 347.21936 -336.868129) (xy 347.270696 -336.934365) (xy 347.315576 -337.005135)
			(xy 347.353601 -337.079812) (xy 347.384434 -337.157734) (xy 347.407802 -337.238211) (xy 347.423499 -337.320529)
			(xy 347.431384 -337.403958) (xy 347.431868 -337.445858) (xy 347.431868 -337.446874) (xy 347.431339 -337.489485)
			(xy 347.423121 -337.57431) (xy 347.406824 -337.657959) (xy 347.382599 -337.739665) (xy 347.367098 -337.77936)
			(xy 347.363634 -337.789438) (xy 347.36443 -337.810709) (xy 347.368622 -337.820508) (xy 347.385666 -337.856788)
			(xy 347.413917 -337.931808) (xy 347.435302 -338.009067) (xy 347.449648 -338.087936) (xy 347.456838 -338.167776)
			(xy 347.457268 -338.207858) (xy 347.456674 -338.254253) (xy 347.447033 -338.346541) (xy 347.42784 -338.437325)
			(xy 347.399305 -338.525619) (xy 347.381068 -338.568284) (xy 347.377284 -338.578233) (xy 347.377268 -338.599491)
			(xy 347.381068 -338.609432) (xy 347.399296 -338.652101) (xy 347.427845 -338.740391) (xy 347.447043 -338.831174)
			(xy 347.456681 -338.923462) (xy 347.457268 -338.969858) (xy 347.456674 -339.016253) (xy 347.447033 -339.108541)
			(xy 347.42784 -339.199325) (xy 347.399305 -339.287619) (xy 347.381068 -339.330284) (xy 347.377284 -339.340233)
			(xy 347.377268 -339.361491) (xy 347.381068 -339.371432) (xy 347.39928 -339.414039) (xy 347.427799 -339.502205)
			(xy 347.446995 -339.592859) (xy 347.456658 -339.685018) (xy 347.457268 -339.73135) (xy 347.457268 -339.731858)
			(xy 347.456747 -339.772964) (xy 347.449167 -339.854825) (xy 347.434067 -339.935639) (xy 347.411576 -340.014714)
			(xy 347.381885 -340.091377) (xy 347.345249 -340.164975) (xy 347.30198 -340.234878) (xy 347.252446 -340.300492)
			(xy 347.19707 -340.361256) (xy 347.136324 -340.416653) (xy 347.070727 -340.466209) (xy 347.000838 -340.509502)
			(xy 346.927254 -340.546163) (xy 346.8506 -340.575879) (xy 346.771533 -340.598397) (xy 346.690725 -340.613525)
			(xy 346.608866 -340.621133) (xy 346.56776 -340.62162) (xy 346.525159 -340.621134) (xy 346.440349 -340.612975)
			(xy 346.356708 -340.596745) (xy 346.275001 -340.572593) (xy 346.195978 -340.540739) (xy 346.120362 -340.501477)
			(xy 346.048846 -340.455165) (xy 345.982085 -340.402229) (xy 345.920691 -340.343152) (xy 345.865226 -340.278476)
			(xy 345.840304 -340.243922) (xy 345.834713 -340.236567) (xy 345.819465 -340.226159) (xy 345.810586 -340.223602)
			(xy 345.769427 -340.213207) (xy 345.689122 -340.185668) (xy 345.611806 -340.150603) (xy 345.538183 -340.108332)
			(xy 345.468921 -340.05924) (xy 345.40465 -340.003772) (xy 345.345957 -339.942434) (xy 345.293373 -339.875784)
			(xy 345.247379 -339.804427) (xy 345.208391 -339.729013) (xy 345.176765 -339.650228) (xy 345.152789 -339.568788)
			(xy 345.136679 -339.485435) (xy 345.128584 -339.400926) (xy 345.128088 -339.358478) (xy 345.128088 -339.358224)
			(xy 345.128648 -339.313485) (xy 345.137666 -339.224464) (xy 345.155574 -339.136796) (xy 345.182189 -339.051369)
			(xy 345.199208 -339.00999) (xy 345.202787 -339.000403) (xy 345.202779 -338.979957) (xy 345.199208 -338.970366)
			(xy 345.182177 -338.928958) (xy 345.155545 -338.843469) (xy 345.13764 -338.755736) (xy 345.128642 -338.666649)
			(xy 345.128088 -338.621878) (xy 345.128637 -338.577108) (xy 345.137642 -338.488021) (xy 345.15555 -338.400289)
			(xy 345.182178 -338.314799) (xy 345.199208 -338.27339) (xy 345.202787 -338.263803) (xy 345.202779 -338.243357)
			(xy 345.199208 -338.233766) (xy 345.182177 -338.192358) (xy 345.155545 -338.106869) (xy 345.13764 -338.019136)
			(xy 345.128642 -337.930049) (xy 345.128088 -337.885278) (xy 345.128088 -337.87334) (xy 345.101609 -337.867394)
			(xy 345.049374 -337.852651) (xy 345.023694 -337.843876) (xy 345.015497 -337.841362) (xy 344.998363 -337.841362)
			(xy 344.990166 -337.843876) (xy 344.95495 -337.855837) (xy 344.882946 -337.874492) (xy 344.809626 -337.887)
			(xy 344.73551 -337.893274) (xy 344.69832 -337.89366) (xy 344.661131 -337.893262) (xy 344.587018 -337.886974)
			(xy 344.513698 -337.874467) (xy 344.441692 -337.855829) (xy 344.406474 -337.843876) (xy 344.398277 -337.841362)
			(xy 344.381143 -337.841362) (xy 344.372946 -337.843876) (xy 344.337731 -337.855842) (xy 344.265728 -337.874496)
			(xy 344.192406 -337.887003) (xy 344.11829 -337.893275) (xy 344.0811 -337.89366) (xy 344.039162 -337.893185)
			(xy 343.955666 -337.885212) (xy 343.873306 -337.869339) (xy 343.792828 -337.845708) (xy 343.71496 -337.814535)
			(xy 343.640408 -337.776101) (xy 343.569847 -337.730754) (xy 343.503917 -337.678905) (xy 343.443213 -337.621024)
			(xy 343.388286 -337.557635) (xy 343.339633 -337.489312) (xy 343.297695 -337.416673) (xy 343.262852 -337.340377)
			(xy 343.235419 -337.261114) (xy 343.215644 -337.179603) (xy 343.203707 -337.096581) (xy 343.199717 -337.0128)
			(xy 339.659159 -337.0128) (xy 339.659468 -337.03895) (xy 339.659468 -337.039458) (xy 339.6589 -337.084228)
			(xy 339.649901 -337.173314) (xy 339.631999 -337.261046) (xy 339.605375 -337.346537) (xy 339.588348 -337.387946)
			(xy 339.584808 -337.397544) (xy 339.584792 -337.41798) (xy 339.588348 -337.42757) (xy 339.605388 -337.468975)
			(xy 339.632018 -337.554465) (xy 339.649921 -337.642198) (xy 339.658915 -337.731287) (xy 339.659468 -337.776058)
			(xy 339.6589 -337.820828) (xy 339.649901 -337.909914) (xy 339.631999 -337.997646) (xy 339.605375 -338.083137)
			(xy 339.588348 -338.124546) (xy 339.584808 -338.134144) (xy 339.584792 -338.15458) (xy 339.588348 -338.16417)
			(xy 339.605377 -338.205545) (xy 339.631995 -338.290972) (xy 339.649897 -338.378641) (xy 339.658904 -338.467665)
			(xy 339.659468 -338.512404) (xy 339.659468 -338.512658) (xy 339.658947 -338.553764) (xy 339.651367 -338.635625)
			(xy 339.636267 -338.716439) (xy 339.613776 -338.795514) (xy 339.584085 -338.872177) (xy 339.547449 -338.945775)
			(xy 339.50418 -339.015678) (xy 339.454646 -339.081292) (xy 339.39927 -339.142056) (xy 339.338524 -339.197453)
			(xy 339.272927 -339.247009) (xy 339.203038 -339.290302) (xy 339.129454 -339.326963) (xy 339.0528 -339.356679)
			(xy 338.973733 -339.379197) (xy 338.892925 -339.394325) (xy 338.811066 -339.401933) (xy 338.76996 -339.40242)
			(xy 338.728351 -339.40191) (xy 338.645495 -339.394139) (xy 338.563727 -339.378669) (xy 338.483759 -339.355636)
			(xy 338.40629 -339.325239) (xy 338.331996 -339.287745) (xy 338.296504 -339.266022) (xy 338.287367 -339.260856)
			(xy 338.26665 -339.257639) (xy 338.246374 -339.262975) (xy 338.23783 -339.26907) (xy 338.204174 -339.295024)
			(xy 338.132784 -339.341153) (xy 338.057318 -339.380258) (xy 337.978465 -339.411983) (xy 337.896945 -339.436039)
			(xy 337.8135 -339.452205) (xy 337.728894 -339.460335) (xy 337.686396 -339.46084) (xy 337.645302 -339.460338)
			(xy 337.563464 -339.452755) (xy 337.482675 -339.437656) (xy 337.403623 -339.415168) (xy 337.326982 -339.385484)
			(xy 337.253407 -339.348856) (xy 337.183524 -339.305597) (xy 337.11793 -339.256076) (xy 337.057184 -339.200716)
			(xy 337.001804 -339.139987) (xy 336.952262 -339.074409) (xy 336.908981 -339.00454) (xy 336.87233 -338.930976)
			(xy 336.842621 -338.854345) (xy 336.820109 -338.7753) (xy 336.804984 -338.694515) (xy 336.797375 -338.61268)
			(xy 336.796888 -338.571586) (xy 336.796888 -338.571078) (xy 336.797437 -338.526308) (xy 336.806442 -338.437221)
			(xy 336.82435 -338.349489) (xy 336.850978 -338.263999) (xy 336.868008 -338.22259) (xy 336.871587 -338.213003)
			(xy 336.871579 -338.192557) (xy 336.868008 -338.182966) (xy 336.850977 -338.141558) (xy 336.824345 -338.056069)
			(xy 336.80644 -337.968336) (xy 336.797442 -337.879249) (xy 336.796888 -337.834478) (xy 336.796888 -337.82254)
			(xy 336.770409 -337.816594) (xy 336.718174 -337.801851) (xy 336.692494 -337.793076) (xy 336.684297 -337.790562)
			(xy 336.667163 -337.790562) (xy 336.658966 -337.793076) (xy 336.62375 -337.805037) (xy 336.551746 -337.823692)
			(xy 336.478426 -337.8362) (xy 336.40431 -337.842474) (xy 336.36712 -337.84286) (xy 336.329931 -337.842462)
			(xy 336.255818 -337.836174) (xy 336.182498 -337.823667) (xy 336.110492 -337.805029) (xy 336.075274 -337.793076)
			(xy 336.067077 -337.790562) (xy 336.049943 -337.790562) (xy 336.041746 -337.793076) (xy 336.006531 -337.805042)
			(xy 335.934528 -337.823696) (xy 335.861206 -337.836203) (xy 335.78709 -337.842475) (xy 335.7499 -337.84286)
			(xy 335.707962 -337.842385) (xy 335.624466 -337.834412) (xy 335.542106 -337.818539) (xy 335.461628 -337.794908)
			(xy 335.38376 -337.763735) (xy 335.309208 -337.725301) (xy 335.238647 -337.679954) (xy 335.172717 -337.628105)
			(xy 335.112013 -337.570224) (xy 335.057086 -337.506835) (xy 335.008433 -337.438512) (xy 334.966495 -337.365873)
			(xy 334.931652 -337.289577) (xy 334.904219 -337.210314) (xy 334.884444 -337.128803) (xy 334.872507 -337.045781)
			(xy 334.868517 -336.962) (xy 331.296671 -336.962) (xy 331.301379 -337.012832) (xy 331.301852 -337.053936)
			(xy 331.301852 -337.05419) (xy 331.301293 -337.098929) (xy 331.292274 -337.18795) (xy 331.274367 -337.275618)
			(xy 331.247751 -337.361045) (xy 331.230732 -337.402424) (xy 331.227148 -337.412009) (xy 331.227161 -337.432457)
			(xy 331.230732 -337.442048) (xy 331.247764 -337.483456) (xy 331.274397 -337.568945) (xy 331.292302 -337.656677)
			(xy 331.301298 -337.745765) (xy 331.301852 -337.790536) (xy 331.301312 -337.835307) (xy 331.292305 -337.924394)
			(xy 331.274395 -338.012126) (xy 331.247763 -338.097615) (xy 331.230732 -338.139024) (xy 331.227148 -338.148609)
			(xy 331.227161 -338.169057) (xy 331.230732 -338.178648) (xy 331.247759 -338.220024) (xy 331.274376 -338.305451)
			(xy 331.292279 -338.39312) (xy 331.301287 -338.482143) (xy 331.301852 -338.526882) (xy 331.301852 -338.527136)
			(xy 331.301368 -338.568238) (xy 331.29378 -338.65009) (xy 331.278673 -338.730894) (xy 331.256175 -338.809959)
			(xy 331.226478 -338.886611) (xy 331.189836 -338.960196) (xy 331.14656 -339.030087) (xy 331.097021 -339.095686)
			(xy 331.041641 -339.156436) (xy 330.980892 -339.211816) (xy 330.915293 -339.261356) (xy 330.845403 -339.304632)
			(xy 330.771818 -339.341275) (xy 330.695167 -339.370972) (xy 330.616102 -339.393471) (xy 330.535298 -339.408579)
			(xy 330.453446 -339.416167) (xy 330.412344 -339.416644) (xy 330.411582 -339.416644) (xy 330.370042 -339.416142)
			(xy 330.287326 -339.408361) (xy 330.205695 -339.392907) (xy 330.125859 -339.369913) (xy 330.048513 -339.339581)
			(xy 329.97433 -339.302172) (xy 329.938888 -339.2805) (xy 329.929757 -339.275322) (xy 329.909036 -339.272112)
			(xy 329.888759 -339.277452) (xy 329.880214 -339.283548) (xy 329.846565 -339.30947) (xy 329.775191 -339.355528)
			(xy 329.699752 -339.394575) (xy 329.620935 -339.426254) (xy 329.539458 -339.450278) (xy 329.456062 -339.466427)
			(xy 329.371506 -339.474554) (xy 329.329034 -339.475064) (xy 329.32878 -339.475064) (xy 329.287675 -339.474667)
			(xy 329.205817 -339.46708) (xy 329.125007 -339.451972) (xy 329.045936 -339.429472) (xy 328.969279 -339.399772)
			(xy 328.895689 -339.363126) (xy 328.825795 -339.319846) (xy 328.760192 -339.270301) (xy 328.69944 -339.214915)
			(xy 328.644058 -339.154159) (xy 328.594518 -339.088553) (xy 328.551243 -339.018655) (xy 328.514602 -338.945062)
			(xy 328.484908 -338.868403) (xy 328.462414 -338.789331) (xy 328.447312 -338.70852) (xy 328.43973 -338.626661)
			(xy 328.439272 -338.585556) (xy 328.439272 -338.585302) (xy 328.43986 -338.540564) (xy 328.44887 -338.451543)
			(xy 328.466769 -338.363876) (xy 328.493377 -338.278448) (xy 328.510392 -338.237068) (xy 328.513984 -338.227485)
			(xy 328.513968 -338.207035) (xy 328.510392 -338.197444) (xy 328.493353 -338.156039) (xy 328.466723 -338.070549)
			(xy 328.44882 -337.982815) (xy 328.439825 -337.893727) (xy 328.439272 -337.848956) (xy 328.439272 -337.837018)
			(xy 328.412793 -337.831074) (xy 328.360558 -337.81633) (xy 328.334878 -337.807554) (xy 328.326681 -337.80504)
			(xy 328.309547 -337.80504) (xy 328.30135 -337.807554) (xy 328.266125 -337.819474) (xy 328.194118 -337.838068)
			(xy 328.120798 -337.850516) (xy 328.046689 -337.856728) (xy 328.009504 -337.857084) (xy 327.97232 -337.856715)
			(xy 327.898212 -337.850493) (xy 327.824892 -337.838051) (xy 327.752881 -337.819476) (xy 327.717658 -337.807554)
			(xy 327.709461 -337.80504) (xy 327.692327 -337.80504) (xy 327.68413 -337.807554) (xy 327.649029 -337.819442)
			(xy 327.577272 -337.837992) (xy 327.504209 -337.850438) (xy 327.430358 -337.856691) (xy 327.3933 -337.857084)
			(xy 327.392284 -337.857084) (xy 327.350358 -337.856653) (xy 327.266885 -337.848681) (xy 327.184547 -337.83281)
			(xy 327.104092 -337.809185) (xy 327.026246 -337.778019) (xy 326.951715 -337.739594) (xy 326.881174 -337.694259)
			(xy 326.815262 -337.642424) (xy 326.754575 -337.584559) (xy 326.699664 -337.521186) (xy 326.651025 -337.452882)
			(xy 326.609099 -337.380263) (xy 326.574266 -337.303987) (xy 326.546841 -337.224746) (xy 326.527072 -337.143257)
			(xy 326.515138 -337.060258) (xy 326.511148 -336.9765) (xy 322.941787 -336.9765) (xy 322.94581 -337.019944)
			(xy 322.946268 -337.061048) (xy 322.946268 -337.061302) (xy 322.945685 -337.10604) (xy 322.936674 -337.195061)
			(xy 322.918774 -337.282729) (xy 322.892164 -337.368156) (xy 322.875148 -337.409536) (xy 322.871556 -337.419119)
			(xy 322.871574 -337.439569) (xy 322.875148 -337.44916) (xy 322.892185 -337.490566) (xy 322.918816 -337.576056)
			(xy 322.93672 -337.663789) (xy 322.945715 -337.752877) (xy 322.946268 -337.797648) (xy 322.945697 -337.842418)
			(xy 322.936698 -337.931504) (xy 322.918797 -338.019236) (xy 322.892175 -338.104727) (xy 322.875148 -338.146136)
			(xy 322.871556 -338.155719) (xy 322.871574 -338.176169) (xy 322.875148 -338.18576) (xy 322.892174 -338.227136)
			(xy 322.918792 -338.312563) (xy 322.936696 -338.400232) (xy 322.945704 -338.489255) (xy 322.946268 -338.533994)
			(xy 322.946268 -338.534248) (xy 322.945879 -338.575352) (xy 322.938289 -338.65721) (xy 322.923179 -338.738019)
			(xy 322.900678 -338.817088) (xy 322.870976 -338.893744) (xy 322.834329 -338.967333) (xy 322.791048 -339.037226)
			(xy 322.741503 -339.102828) (xy 322.686116 -339.163578) (xy 322.62536 -339.218959) (xy 322.559753 -339.268498)
			(xy 322.489856 -339.311772) (xy 322.416264 -339.348412) (xy 322.339605 -339.378106) (xy 322.260533 -339.400599)
			(xy 322.179723 -339.415702) (xy 322.097864 -339.423283) (xy 322.05676 -339.423756) (xy 322.055998 -339.423756)
			(xy 322.014458 -339.423244) (xy 321.931742 -339.415465) (xy 321.850112 -339.400013) (xy 321.770276 -339.377021)
			(xy 321.69293 -339.34669) (xy 321.618746 -339.309284) (xy 321.583304 -339.287612) (xy 321.574167 -339.282447)
			(xy 321.55345 -339.279232) (xy 321.533175 -339.284566) (xy 321.52463 -339.29066) (xy 321.491012 -339.316622)
			(xy 321.419631 -339.362677) (xy 321.344187 -339.401718) (xy 321.265365 -339.433392) (xy 321.183883 -339.457409)
			(xy 321.100483 -339.47355) (xy 321.015924 -339.48167) (xy 320.97345 -339.482176) (xy 320.973196 -339.482176)
			(xy 320.932092 -339.481752) (xy 320.850234 -339.474166) (xy 320.769426 -339.459059) (xy 320.690356 -339.436561)
			(xy 320.613699 -339.406863) (xy 320.54011 -339.370219) (xy 320.470216 -339.326941) (xy 320.404613 -339.277398)
			(xy 320.343861 -339.222013) (xy 320.288479 -339.161259) (xy 320.238939 -339.095655) (xy 320.195664 -339.025759)
			(xy 320.159022 -338.952168) (xy 320.129327 -338.87551) (xy 320.106832 -338.796439) (xy 320.091729 -338.71563)
			(xy 320.084147 -338.633772) (xy 320.083688 -338.592668) (xy 320.083688 -338.592414) (xy 320.084245 -338.547675)
			(xy 320.093264 -338.458653) (xy 320.111172 -338.370986) (xy 320.137789 -338.285559) (xy 320.154808 -338.24418)
			(xy 320.158393 -338.234595) (xy 320.158381 -338.214147) (xy 320.154808 -338.204556) (xy 320.137774 -338.163149)
			(xy 320.111142 -338.07766) (xy 320.093238 -337.989927) (xy 320.084242 -337.900839) (xy 320.083688 -337.856068)
			(xy 320.083688 -337.84413) (xy 320.057209 -337.838184) (xy 320.004974 -337.823441) (xy 319.979294 -337.814666)
			(xy 319.971097 -337.812152) (xy 319.953963 -337.812152) (xy 319.945766 -337.814666) (xy 319.910549 -337.82661)
			(xy 319.838539 -337.845197) (xy 319.765217 -337.857638) (xy 319.691106 -337.863844) (xy 319.65392 -337.864196)
			(xy 319.616736 -337.863827) (xy 319.542628 -337.857606) (xy 319.469308 -337.845164) (xy 319.397297 -337.826589)
			(xy 319.362074 -337.814666) (xy 319.353877 -337.812152) (xy 319.336743 -337.812152) (xy 319.328546 -337.814666)
			(xy 319.293452 -337.826578) (xy 319.221693 -337.845121) (xy 319.148627 -337.85756) (xy 319.074774 -337.863807)
			(xy 319.037716 -337.864196) (xy 319.0367 -337.864196) (xy 318.994774 -337.863741) (xy 318.911301 -337.855771)
			(xy 318.828963 -337.839902) (xy 318.748507 -337.816278) (xy 318.670661 -337.785113) (xy 318.59613 -337.746689)
			(xy 318.525589 -337.701355) (xy 318.459676 -337.649521) (xy 318.398989 -337.591656) (xy 318.344078 -337.528284)
			(xy 318.295438 -337.45998) (xy 318.253512 -337.387361) (xy 318.218678 -337.311086) (xy 318.191253 -337.231846)
			(xy 318.171484 -337.150357) (xy 318.15955 -337.067358) (xy 318.155561 -336.9836) (xy 99.362614 -336.9836)
			(xy 99.373171 -336.999727) (xy 99.41309 -337.075842) (xy 99.445481 -337.155452) (xy 99.470043 -337.237815)
			(xy 99.486546 -337.322163) (xy 99.494837 -337.40771) (xy 99.495356 -337.450684) (xy 99.495356 -337.451192)
			(xy 99.494833 -337.493866) (xy 99.486634 -337.578818) (xy 99.47034 -337.662596) (xy 99.446101 -337.744429)
			(xy 99.430586 -337.784186) (xy 99.426944 -337.794219) (xy 99.427619 -337.815536) (xy 99.431856 -337.825334)
			(xy 99.448914 -337.861614) (xy 99.477225 -337.936624) (xy 99.498666 -338.013878) (xy 99.513065 -338.092749)
			(xy 99.520304 -338.172597) (xy 99.520756 -338.212684) (xy 99.520272 -338.252763) (xy 99.512982 -338.33259)
			(xy 99.498549 -338.411439) (xy 99.488244 -338.450174) (xy 99.485843 -338.460698) (xy 99.489132 -338.482012)
			(xy 99.494594 -338.491322) (xy 99.517345 -338.52734) (xy 99.556637 -338.602937) (xy 99.588514 -338.681946)
			(xy 99.612684 -338.763644) (xy 99.628925 -338.847279) (xy 99.637089 -338.932085) (xy 99.637596 -338.974684)
			(xy 99.637001 -339.021087) (xy 99.627302 -339.113385) (xy 99.608039 -339.204171) (xy 99.579422 -339.292455)
			(xy 99.561142 -339.33511) (xy 99.557344 -339.345055) (xy 99.557338 -339.366316) (xy 99.561142 -339.376258)
			(xy 99.579397 -339.418922) (xy 99.607993 -339.507209) (xy 99.627252 -339.597991) (xy 99.636966 -339.690283)
			(xy 99.637596 -339.736684) (xy 99.637118 -339.777779) (xy 99.629538 -339.859619) (xy 99.614439 -339.94041)
			(xy 99.591952 -340.019465) (xy 99.562267 -340.096107) (xy 99.525639 -340.169684) (xy 99.482378 -340.239568)
			(xy 99.432856 -340.305164) (xy 99.377493 -340.36591) (xy 99.316762 -340.421291) (xy 99.251181 -340.470833)
			(xy 99.18131 -340.514113) (xy 99.107743 -340.550763) (xy 99.031109 -340.58047) (xy 98.952062 -340.60298)
			(xy 98.871275 -340.618102) (xy 98.789437 -340.625707) (xy 98.748342 -340.626192) (xy 98.747834 -340.626192)
			(xy 98.704859 -340.625663) (xy 98.619309 -340.617375) (xy 98.534957 -340.600874) (xy 98.45259 -340.576313)
			(xy 98.372977 -340.543922) (xy 98.296859 -340.504001) (xy 98.224947 -340.456925) (xy 98.157912 -340.403131)
			(xy 98.096378 -340.343122) (xy 98.040919 -340.277458) (xy 98.01606 -340.242398) (xy 98.010455 -340.235056)
			(xy 97.995216 -340.224641) (xy 97.986342 -340.222078) (xy 97.94544 -340.211492) (xy 97.865683 -340.183605)
			(xy 97.788928 -340.148281) (xy 97.715869 -340.105839) (xy 97.647164 -340.05666) (xy 97.583432 -340.001188)
			(xy 97.525246 -339.939922) (xy 97.473132 -339.873416) (xy 97.427559 -339.802268) (xy 97.388937 -339.727119)
			(xy 97.357615 -339.648646) (xy 97.333875 -339.567557) (xy 97.317931 -339.484583) (xy 97.309927 -339.40047)
			(xy 97.309432 -339.358224) (xy 97.309829 -339.321956) (xy 97.315809 -339.249667) (xy 97.327648 -339.178103)
			(xy 97.336102 -339.142832) (xy 97.338115 -339.132729) (xy 97.334853 -339.112411) (xy 97.329752 -339.103462)
			(xy 97.30766 -339.067807) (xy 97.269551 -338.993079) (xy 97.238646 -338.915096) (xy 97.215218 -338.83455)
			(xy 97.199477 -338.752156) (xy 97.191562 -338.668646) (xy 97.191068 -338.626704) (xy 97.191648 -338.581935)
			(xy 97.200654 -338.49285) (xy 97.218554 -338.405119) (xy 97.245168 -338.319627) (xy 97.262188 -338.278216)
			(xy 97.265753 -338.268625) (xy 97.265754 -338.248182) (xy 97.262188 -338.238592) (xy 97.245172 -338.197246)
			(xy 97.218563 -338.111882) (xy 97.20066 -338.024278) (xy 97.191642 -337.935319) (xy 97.191068 -337.890612)
			(xy 97.191068 -337.889596) (xy 97.191322 -337.878166) (xy 97.164844 -337.872216) (xy 97.112609 -337.857476)
			(xy 97.086928 -337.848702) (xy 97.078731 -337.846188) (xy 97.061597 -337.846188) (xy 97.0534 -337.848702)
			(xy 97.01818 -337.860638) (xy 96.946171 -337.879227) (xy 96.87285 -337.89167) (xy 96.798739 -337.897878)
			(xy 96.761554 -337.898232) (xy 96.724369 -337.89788) (xy 96.650261 -337.891654) (xy 96.576941 -337.879206)
			(xy 96.504931 -337.860627) (xy 96.469708 -337.848702) (xy 96.461511 -337.846188) (xy 96.444377 -337.846188)
			(xy 96.43618 -337.848702) (xy 96.401082 -337.860602) (xy 96.329324 -337.879149) (xy 96.25626 -337.891592)
			(xy 96.182408 -337.897841) (xy 96.14535 -337.898232) (xy 96.144334 -337.898232) (xy 96.102408 -337.897723)
			(xy 96.018934 -337.889755) (xy 95.936596 -337.873888) (xy 95.85614 -337.850267) (xy 95.778292 -337.819104)
			(xy 95.70376 -337.780683) (xy 95.633218 -337.73535) (xy 95.567304 -337.683517) (xy 95.506616 -337.625654)
			(xy 95.451703 -337.562283) (xy 95.403062 -337.493979) (xy 95.361135 -337.421361) (xy 95.3263 -337.345087)
			(xy 95.298874 -337.265846) (xy 95.279105 -337.184357) (xy 95.267171 -337.101358) (xy 95.263181 -337.0176)
			(xy 91.722641 -337.0176) (xy 91.722956 -337.044284) (xy 91.722404 -337.089054) (xy 91.71339 -337.178139)
			(xy 91.695482 -337.26587) (xy 91.668861 -337.351361) (xy 91.651836 -337.392772) (xy 91.648282 -337.402366)
			(xy 91.648276 -337.422805) (xy 91.651836 -337.432396) (xy 91.668872 -337.473803) (xy 91.695506 -337.559291)
			(xy 91.71341 -337.647024) (xy 91.722404 -337.736113) (xy 91.722956 -337.780884) (xy 91.722404 -337.825654)
			(xy 91.71339 -337.914739) (xy 91.695482 -338.00247) (xy 91.668861 -338.087961) (xy 91.651836 -338.129372)
			(xy 91.648282 -338.138966) (xy 91.648276 -338.159405) (xy 91.651836 -338.168996) (xy 91.668872 -338.210403)
			(xy 91.695506 -338.295891) (xy 91.71341 -338.383624) (xy 91.722404 -338.472713) (xy 91.722956 -338.517484)
			(xy 91.722432 -338.558593) (xy 91.714846 -338.64046) (xy 91.699738 -338.721278) (xy 91.677236 -338.800357)
			(xy 91.647532 -338.877021) (xy 91.610881 -338.950618) (xy 91.567594 -339.020518) (xy 91.518041 -339.086125)
			(xy 91.462645 -339.146879) (xy 91.401879 -339.202262) (xy 91.336261 -339.251801) (xy 91.266352 -339.295073)
			(xy 91.192747 -339.331709) (xy 91.116076 -339.361396) (xy 91.036993 -339.383882) (xy 90.956172 -339.398973)
			(xy 90.874303 -339.406541) (xy 90.833194 -339.406992) (xy 90.791589 -339.406554) (xy 90.70874 -339.398816)
			(xy 90.626975 -339.383379) (xy 90.547007 -339.360379) (xy 90.469535 -339.330016) (xy 90.395235 -339.292555)
			(xy 90.359738 -339.270848) (xy 90.350631 -339.26562) (xy 90.329893 -339.262421) (xy 90.309608 -339.267785)
			(xy 90.301064 -339.273896) (xy 90.267427 -339.299833) (xy 90.196051 -339.345891) (xy 90.12061 -339.384937)
			(xy 90.041791 -339.416615) (xy 89.960312 -339.440636) (xy 89.876914 -339.456781) (xy 89.792357 -339.464905)
			(xy 89.749884 -339.465412) (xy 89.74963 -339.465412) (xy 89.708522 -339.464959) (xy 89.626657 -339.457377)
			(xy 89.545841 -339.442274) (xy 89.466762 -339.41978) (xy 89.390096 -339.390087) (xy 89.316497 -339.353447)
			(xy 89.246591 -339.310173) (xy 89.180976 -339.260635) (xy 89.120211 -339.205254) (xy 89.064815 -339.144504)
			(xy 89.015259 -339.078902) (xy 88.971967 -339.009008) (xy 88.935308 -338.935418) (xy 88.905594 -338.85876)
			(xy 88.883079 -338.779687) (xy 88.867956 -338.698875) (xy 88.860352 -338.617012) (xy 88.859868 -338.575904)
			(xy 88.860448 -338.531135) (xy 88.869454 -338.44205) (xy 88.887354 -338.354319) (xy 88.913968 -338.268827)
			(xy 88.930988 -338.227416) (xy 88.934553 -338.217825) (xy 88.934554 -338.197382) (xy 88.930988 -338.187792)
			(xy 88.913972 -338.146446) (xy 88.887363 -338.061082) (xy 88.86946 -337.973478) (xy 88.860442 -337.884519)
			(xy 88.859868 -337.839812) (xy 88.859868 -337.838796) (xy 88.860122 -337.827366) (xy 88.833644 -337.821416)
			(xy 88.781409 -337.806676) (xy 88.755728 -337.797902) (xy 88.747531 -337.795388) (xy 88.730397 -337.795388)
			(xy 88.7222 -337.797902) (xy 88.68698 -337.809838) (xy 88.614971 -337.828427) (xy 88.54165 -337.84087)
			(xy 88.467539 -337.847078) (xy 88.430354 -337.847432) (xy 88.393169 -337.84708) (xy 88.319061 -337.840854)
			(xy 88.245741 -337.828406) (xy 88.173731 -337.809827) (xy 88.138508 -337.797902) (xy 88.130311 -337.795388)
			(xy 88.113177 -337.795388) (xy 88.10498 -337.797902) (xy 88.069882 -337.809802) (xy 87.998124 -337.828349)
			(xy 87.92506 -337.840792) (xy 87.851208 -337.847041) (xy 87.81415 -337.847432) (xy 87.813134 -337.847432)
			(xy 87.771208 -337.846923) (xy 87.687734 -337.838955) (xy 87.605396 -337.823088) (xy 87.52494 -337.799467)
			(xy 87.447092 -337.768304) (xy 87.37256 -337.729883) (xy 87.302018 -337.68455) (xy 87.236104 -337.632717)
			(xy 87.175416 -337.574854) (xy 87.120503 -337.511483) (xy 87.071862 -337.443179) (xy 87.029935 -337.370561)
			(xy 86.9951 -337.294287) (xy 86.967674 -337.215046) (xy 86.947905 -337.133557) (xy 86.935971 -337.050558)
			(xy 86.931981 -336.9668) (xy 83.360149 -336.9668) (xy 83.364863 -337.017649) (xy 83.36534 -337.058762)
			(xy 83.364781 -337.103532) (xy 83.35577 -337.192617) (xy 83.337863 -337.280348) (xy 83.311243 -337.365839)
			(xy 83.29422 -337.40725) (xy 83.290679 -337.416847) (xy 83.290665 -337.437283) (xy 83.29422 -337.446874)
			(xy 83.311248 -337.488284) (xy 83.337884 -337.573771) (xy 83.355791 -337.661503) (xy 83.364787 -337.750591)
			(xy 83.36534 -337.795362) (xy 83.364781 -337.840132) (xy 83.35577 -337.929217) (xy 83.337863 -338.016948)
			(xy 83.311243 -338.102439) (xy 83.29422 -338.14385) (xy 83.290679 -338.153447) (xy 83.290665 -338.173883)
			(xy 83.29422 -338.183474) (xy 83.311248 -338.224884) (xy 83.337884 -338.310371) (xy 83.355791 -338.398103)
			(xy 83.364787 -338.487191) (xy 83.36534 -338.531962) (xy 83.364865 -338.573077) (xy 83.357281 -338.654956)
			(xy 83.342174 -338.735786) (xy 83.319674 -338.814878) (xy 83.289971 -338.891556) (xy 83.253319 -338.965166)
			(xy 83.210032 -339.03508) (xy 83.160479 -339.100701) (xy 83.105082 -339.16147) (xy 83.044313 -339.216869)
			(xy 82.978693 -339.266423) (xy 82.90878 -339.309712) (xy 82.83517 -339.346364) (xy 82.758493 -339.376068)
			(xy 82.679402 -339.398571) (xy 82.598572 -339.413679) (xy 82.516693 -339.421265) (xy 82.475578 -339.421724)
			(xy 82.433968 -339.421253) (xy 82.351111 -339.413475) (xy 82.269342 -339.397998) (xy 82.189374 -339.374957)
			(xy 82.111906 -339.344554) (xy 82.037613 -339.307053) (xy 82.002122 -339.285326) (xy 81.992978 -339.280175)
			(xy 81.972265 -339.276953) (xy 81.951992 -339.282282) (xy 81.943448 -339.288374) (xy 81.909821 -339.314367)
			(xy 81.838426 -339.360491) (xy 81.762954 -339.399592) (xy 81.684096 -339.431311) (xy 81.602571 -339.455361)
			(xy 81.519123 -339.471521) (xy 81.434513 -339.479643) (xy 81.392014 -339.480144) (xy 81.350899 -339.479688)
			(xy 81.269019 -339.472102) (xy 81.188189 -339.456993) (xy 81.109097 -339.434491) (xy 81.032419 -339.404786)
			(xy 80.95881 -339.368133) (xy 80.888896 -339.324845) (xy 80.823275 -339.27529) (xy 80.762506 -339.219892)
			(xy 80.707108 -339.159122) (xy 80.657553 -339.093501) (xy 80.614265 -339.023587) (xy 80.577612 -338.949977)
			(xy 80.547908 -338.873299) (xy 80.525406 -338.794207) (xy 80.510297 -338.713377) (xy 80.502712 -338.631497)
			(xy 80.502252 -338.590382) (xy 80.502826 -338.545613) (xy 80.511834 -338.456528) (xy 80.529735 -338.368797)
			(xy 80.556351 -338.283305) (xy 80.573372 -338.241894) (xy 80.576945 -338.232306) (xy 80.576939 -338.211861)
			(xy 80.573372 -338.20227) (xy 80.556348 -338.160927) (xy 80.529742 -338.075562) (xy 80.511841 -337.987957)
			(xy 80.502825 -337.898997) (xy 80.502252 -337.85429) (xy 80.502252 -337.853274) (xy 80.502506 -337.841844)
			(xy 80.476028 -337.835896) (xy 80.423793 -337.821155) (xy 80.398112 -337.81238) (xy 80.389915 -337.809866)
			(xy 80.372781 -337.809866) (xy 80.364584 -337.81238) (xy 80.329366 -337.824336) (xy 80.257364 -337.842992)
			(xy 80.184043 -337.855502) (xy 80.109928 -337.861777) (xy 80.072738 -337.862164) (xy 80.035549 -337.861761)
			(xy 79.961436 -337.855475) (xy 79.888116 -337.842969) (xy 79.81611 -337.824332) (xy 79.780892 -337.81238)
			(xy 79.772695 -337.809866) (xy 79.755561 -337.809866) (xy 79.747364 -337.81238) (xy 79.712148 -337.824342)
			(xy 79.640145 -337.842996) (xy 79.566824 -337.855505) (xy 79.492708 -337.861778) (xy 79.455518 -337.862164)
			(xy 79.413579 -337.861698) (xy 79.330081 -337.853726) (xy 79.247718 -337.837853) (xy 79.167237 -337.814224)
			(xy 79.089367 -337.783051) (xy 79.014813 -337.744616) (xy 78.94425 -337.69927) (xy 78.878316 -337.64742)
			(xy 78.81761 -337.589539) (xy 78.762681 -337.526148) (xy 78.714027 -337.457824) (xy 78.672087 -337.385183)
			(xy 78.637243 -337.308885) (xy 78.609809 -337.229621) (xy 78.590033 -337.148107) (xy 78.578096 -337.065083)
			(xy 78.574105 -336.9813) (xy 75.005252 -336.9813) (xy 75.00928 -337.024761) (xy 75.009756 -337.065874)
			(xy 75.009201 -337.110644) (xy 75.000188 -337.199729) (xy 74.982281 -337.28746) (xy 74.95566 -337.372951)
			(xy 74.938636 -337.414362) (xy 74.935088 -337.423957) (xy 74.935078 -337.444395) (xy 74.938636 -337.453986)
			(xy 74.955669 -337.495394) (xy 74.982303 -337.580882) (xy 75.000209 -337.668615) (xy 75.009203 -337.757703)
			(xy 75.009756 -337.802474) (xy 75.009201 -337.847244) (xy 75.000188 -337.936329) (xy 74.982281 -338.02406)
			(xy 74.95566 -338.109551) (xy 74.938636 -338.150962) (xy 74.935088 -338.160557) (xy 74.935078 -338.180995)
			(xy 74.938636 -338.190586) (xy 74.955669 -338.231994) (xy 74.982303 -338.317482) (xy 75.000209 -338.405215)
			(xy 75.009203 -338.494303) (xy 75.009756 -338.539074) (xy 75.009277 -338.580189) (xy 75.001692 -338.662067)
			(xy 74.986584 -338.742897) (xy 74.964083 -338.821988) (xy 74.93438 -338.898665) (xy 74.897729 -338.972274)
			(xy 74.854442 -339.042187) (xy 74.804888 -339.107809) (xy 74.749492 -339.168577) (xy 74.688724 -339.223976)
			(xy 74.623104 -339.27353) (xy 74.553192 -339.316819) (xy 74.479583 -339.353472) (xy 74.402907 -339.383177)
			(xy 74.323816 -339.40568) (xy 74.242987 -339.420789) (xy 74.161109 -339.428376) (xy 74.119994 -339.428836)
			(xy 74.078384 -339.428356) (xy 73.995528 -339.420579) (xy 73.913759 -339.405104) (xy 73.833791 -339.382065)
			(xy 73.756322 -339.351663) (xy 73.682029 -339.314164) (xy 73.646538 -339.292438) (xy 73.63743 -339.287211)
			(xy 73.616693 -339.284013) (xy 73.596408 -339.289376) (xy 73.587864 -339.295486) (xy 73.554233 -339.321473)
			(xy 73.482838 -339.367598) (xy 73.407368 -339.406699) (xy 73.32851 -339.438419) (xy 73.246986 -339.46247)
			(xy 73.163538 -339.47863) (xy 73.078929 -339.486754) (xy 73.03643 -339.487256) (xy 72.995315 -339.486773)
			(xy 72.913437 -339.479188) (xy 72.832607 -339.464081) (xy 72.753517 -339.44158) (xy 72.67684 -339.411877)
			(xy 72.60323 -339.375226) (xy 72.533317 -339.33194) (xy 72.467696 -339.282387) (xy 72.406927 -339.22699)
			(xy 72.351529 -339.166223) (xy 72.301974 -339.100603) (xy 72.258685 -339.030691) (xy 72.222032 -338.957082)
			(xy 72.192327 -338.880406) (xy 72.169824 -338.801316) (xy 72.154715 -338.720487) (xy 72.147128 -338.638609)
			(xy 72.146668 -338.597494) (xy 72.147245 -338.552725) (xy 72.156251 -338.46364) (xy 72.174152 -338.375909)
			(xy 72.200767 -338.290417) (xy 72.217788 -338.249006) (xy 72.221359 -338.239417) (xy 72.221356 -338.218972)
			(xy 72.217788 -338.209382) (xy 72.200768 -338.168037) (xy 72.174161 -338.082673) (xy 72.156259 -337.995068)
			(xy 72.147241 -337.906109) (xy 72.146668 -337.861402) (xy 72.146668 -337.860386) (xy 72.146922 -337.848956)
			(xy 72.120444 -337.843006) (xy 72.068209 -337.828266) (xy 72.042528 -337.819492) (xy 72.034331 -337.816978)
			(xy 72.017197 -337.816978) (xy 72.009 -337.819492) (xy 71.973781 -337.831444) (xy 71.901779 -337.850101)
			(xy 71.828459 -337.862612) (xy 71.754344 -337.868888) (xy 71.717154 -337.869276) (xy 71.679965 -337.868873)
			(xy 71.605852 -337.862587) (xy 71.532532 -337.850082) (xy 71.460526 -337.831445) (xy 71.425308 -337.819492)
			(xy 71.417111 -337.816978) (xy 71.399977 -337.816978) (xy 71.39178 -337.819492) (xy 71.356562 -337.83145)
			(xy 71.28456 -337.850105) (xy 71.211239 -337.862615) (xy 71.137124 -337.868889) (xy 71.099934 -337.869276)
			(xy 71.057995 -337.868786) (xy 70.974497 -337.860816) (xy 70.892134 -337.844945) (xy 70.811653 -337.821316)
			(xy 70.733783 -337.790144) (xy 70.659228 -337.751711) (xy 70.588664 -337.706365) (xy 70.522731 -337.654517)
			(xy 70.462025 -337.596636) (xy 70.407095 -337.533246) (xy 70.35844 -337.464922) (xy 70.3165 -337.392282)
			(xy 70.281655 -337.315985) (xy 70.254221 -337.23672) (xy 70.234446 -337.155207) (xy 70.222508 -337.072183)
			(xy 70.218517 -336.9884) (xy 2.509012 -336.9884) (xy 2.509012 -341.9277) (xy 103.538816 -341.9277)
			(xy 103.542807 -341.843921) (xy 103.554743 -341.760902) (xy 103.574517 -341.679392) (xy 103.601948 -341.600131)
			(xy 103.63679 -341.523837) (xy 103.678726 -341.4512) (xy 103.727376 -341.382878) (xy 103.7823 -341.319489)
			(xy 103.843001 -341.261608) (xy 103.908929 -341.20976) (xy 103.979486 -341.164412) (xy 104.054035 -341.125977)
			(xy 104.131899 -341.094802) (xy 104.212375 -341.071169) (xy 104.294732 -341.055293) (xy 104.378225 -341.047317)
			(xy 104.420162 -341.046816) (xy 104.457351 -341.047215) (xy 104.531464 -341.053502) (xy 104.604784 -341.066008)
			(xy 104.67679 -341.084646) (xy 104.712008 -341.0966) (xy 104.720205 -341.099114) (xy 104.737339 -341.099114)
			(xy 104.745536 -341.0966) (xy 104.780752 -341.084638) (xy 104.852755 -341.065983) (xy 104.926076 -341.053475)
			(xy 105.000192 -341.047202) (xy 105.037382 -341.046816) (xy 105.07218 -341.047578) (xy 105.081741 -341.004913)
			(xy 105.108207 -340.921573) (xy 105.125012 -340.881208) (xy 105.128629 -340.871492) (xy 105.128644 -340.850784)
			(xy 105.125012 -340.841076) (xy 105.107898 -340.799819) (xy 105.081109 -340.714608) (xy 105.063074 -340.627124)
			(xy 105.053979 -340.538265) (xy 105.053384 -340.493604) (xy 105.053384 -340.492842) (xy 105.053883 -340.450917)
			(xy 105.061853 -340.367446) (xy 105.077722 -340.285111) (xy 105.101345 -340.204657) (xy 105.132509 -340.126813)
			(xy 105.170932 -340.052283) (xy 105.216265 -339.981744) (xy 105.268098 -339.915833) (xy 105.325961 -339.855147)
			(xy 105.389331 -339.800237) (xy 105.457634 -339.751599) (xy 105.530251 -339.709674) (xy 105.606524 -339.674841)
			(xy 105.685763 -339.647416) (xy 105.767249 -339.627647) (xy 105.850246 -339.615714) (xy 105.934002 -339.611725)
			(xy 106.017758 -339.615714) (xy 106.100755 -339.627647) (xy 106.182241 -339.647416) (xy 106.26148 -339.674841)
			(xy 106.337753 -339.709674) (xy 106.41037 -339.751599) (xy 106.478673 -339.800237) (xy 106.542043 -339.855147)
			(xy 106.599906 -339.915833) (xy 106.651739 -339.981744) (xy 106.697072 -340.052283) (xy 106.735495 -340.126813)
			(xy 106.766659 -340.204657) (xy 106.790282 -340.285111) (xy 106.806151 -340.367446) (xy 106.814121 -340.450917)
			(xy 106.81462 -340.492842) (xy 106.81462 -340.493604) (xy 106.814051 -340.538267) (xy 106.804977 -340.627133)
			(xy 106.786945 -340.714621) (xy 106.760139 -340.799831) (xy 106.742992 -340.841076) (xy 106.739326 -340.850777)
			(xy 106.739342 -340.871499) (xy 106.742992 -340.881208) (xy 106.751628 -340.901528) (xy 106.756582 -340.912278)
			(xy 106.774248 -340.927996) (xy 106.797062 -340.934212) (xy 106.808778 -340.932516) (xy 106.8525 -340.924198)
			(xy 106.941059 -340.915292) (xy 106.985562 -340.914736) (xy 106.98607 -340.914736) (xy 107.027176 -340.915241)
			(xy 107.109038 -340.922823) (xy 107.189852 -340.937924) (xy 107.268928 -340.960416) (xy 107.345591 -340.990108)
			(xy 107.419189 -341.026745) (xy 107.489092 -341.070016) (xy 107.554706 -341.119551) (xy 107.61547 -341.174927)
			(xy 107.670867 -341.235674) (xy 107.720423 -341.301272) (xy 107.763716 -341.371161) (xy 107.800377 -341.444747)
			(xy 107.830093 -341.521401) (xy 107.85261 -341.60047) (xy 107.867738 -341.681278) (xy 107.875346 -341.763138)
			(xy 107.875832 -341.804244) (xy 107.875268 -341.849014) (xy 107.867795 -341.9229) (xy 351.475729 -341.9229)
			(xy 351.479719 -341.839138) (xy 351.491654 -341.756134) (xy 351.511424 -341.674641) (xy 351.538852 -341.595396)
			(xy 351.573688 -341.519117) (xy 351.615617 -341.446494) (xy 351.66426 -341.378187) (xy 351.719176 -341.314813)
			(xy 351.779867 -341.256945) (xy 351.845785 -341.205109) (xy 351.916331 -341.159774) (xy 351.990867 -341.12135)
			(xy 352.068718 -341.090185) (xy 352.149179 -341.066562) (xy 352.231522 -341.050694) (xy 352.314999 -341.042726)
			(xy 352.356928 -341.042244) (xy 352.357944 -341.042244) (xy 352.395001 -341.04264) (xy 352.46885 -341.048907)
			(xy 352.541913 -341.061352) (xy 352.613673 -341.079887) (xy 352.648774 -341.091774) (xy 352.656971 -341.094288)
			(xy 352.674105 -341.094288) (xy 352.682302 -341.091774) (xy 352.717522 -341.079841) (xy 352.789531 -341.06125)
			(xy 352.862852 -341.048806) (xy 352.936963 -341.042598) (xy 352.974148 -341.042244) (xy 352.988626 -341.042244)
			(xy 352.999994 -341.041829) (xy 353.020668 -341.032414) (xy 353.035248 -341.014994) (xy 353.038664 -341.004144)
			(xy 353.047281 -340.972176) (xy 353.068638 -340.909499) (xy 353.081336 -340.878922) (xy 353.084895 -340.86933)
			(xy 353.084899 -340.848889) (xy 353.081336 -340.839298) (xy 353.064328 -340.797915) (xy 353.037705 -340.71249)
			(xy 353.019796 -340.624824) (xy 353.010783 -340.535802) (xy 353.010216 -340.491064) (xy 353.010216 -340.49081)
			(xy 353.01072 -340.448462) (xy 353.018771 -340.364148) (xy 353.0348 -340.280982) (xy 353.058661 -340.199715)
			(xy 353.09014 -340.121085) (xy 353.128951 -340.045804) (xy 353.174741 -339.974552) (xy 353.227097 -339.907976)
			(xy 353.285545 -339.846678) (xy 353.349555 -339.791213) (xy 353.418547 -339.742084) (xy 353.491897 -339.699735)
			(xy 353.56894 -339.664551) (xy 353.648979 -339.636849) (xy 353.731288 -339.616881) (xy 353.815123 -339.604828)
			(xy 353.899724 -339.600798) (xy 353.984325 -339.604828) (xy 354.06816 -339.616881) (xy 354.150469 -339.636849)
			(xy 354.230508 -339.664551) (xy 354.307551 -339.699735) (xy 354.380901 -339.742084) (xy 354.449893 -339.791213)
			(xy 354.513903 -339.846678) (xy 354.572351 -339.907976) (xy 354.624707 -339.974552) (xy 354.670497 -340.045804)
			(xy 354.709308 -340.121085) (xy 354.740787 -340.199715) (xy 354.764648 -340.280982) (xy 354.780677 -340.364148)
			(xy 354.788728 -340.448462) (xy 354.789232 -340.49081) (xy 354.789232 -340.491064) (xy 354.788666 -340.535802)
			(xy 354.779649 -340.624824) (xy 354.761744 -340.712491) (xy 354.73513 -340.797919) (xy 354.718112 -340.839298)
			(xy 354.714539 -340.848887) (xy 354.714543 -340.869332) (xy 354.718112 -340.878922) (xy 354.735129 -340.920302)
			(xy 354.761749 -341.005728) (xy 354.779655 -341.093395) (xy 354.788666 -341.182417) (xy 354.789232 -341.227156)
			(xy 354.789232 -341.228172) (xy 354.789643 -341.238195) (xy 354.79731 -341.256718) (xy 354.811486 -341.270892)
			(xy 354.830009 -341.278557) (xy 354.840032 -341.278972) (xy 354.840286 -341.278972) (xy 354.84794 -341.278603)
			(xy 354.862532 -341.273956) (xy 354.868988 -341.269828) (xy 354.869242 -341.269828) (xy 354.906515 -341.244617)
			(xy 354.985224 -341.200991) (xy 355.067937 -341.165538) (xy 355.153807 -341.13862) (xy 355.241957 -341.120513)
			(xy 355.331485 -341.111402) (xy 355.37648 -341.110824) (xy 355.376988 -341.110824) (xy 355.418092 -341.111264)
			(xy 355.499949 -341.118848) (xy 355.580757 -341.133953) (xy 355.659827 -341.15645) (xy 355.736484 -341.186147)
			(xy 355.810073 -341.22279) (xy 355.879967 -341.266067) (xy 355.94557 -341.315609) (xy 356.006322 -341.370992)
			(xy 356.061704 -341.431745) (xy 356.111244 -341.497349) (xy 356.15452 -341.567245) (xy 356.191162 -341.640835)
			(xy 356.220857 -341.717492) (xy 356.243352 -341.796562) (xy 356.258455 -341.877371) (xy 356.266037 -341.959228)
			(xy 356.266496 -342.000332) (xy 356.266496 -342.000586) (xy 356.26594 -342.045325) (xy 356.256921 -342.134347)
			(xy 356.239013 -342.222014) (xy 356.212396 -342.307441) (xy 356.195376 -342.34882) (xy 356.191792 -342.358405)
			(xy 356.191804 -342.378853) (xy 356.195376 -342.388444) (xy 356.212409 -342.429852) (xy 356.239041 -342.515341)
			(xy 356.256946 -342.603073) (xy 356.265942 -342.692161) (xy 356.266496 -342.736932) (xy 356.265952 -342.781703)
			(xy 356.256945 -342.87079) (xy 356.239036 -342.958522) (xy 356.212407 -343.044011) (xy 356.195376 -343.08542)
			(xy 356.191792 -343.095005) (xy 356.191804 -343.115453) (xy 356.195376 -343.125044) (xy 356.212398 -343.166422)
			(xy 356.239017 -343.251848) (xy 356.256922 -343.339516) (xy 356.265931 -343.428539) (xy 356.266496 -343.473278)
			(xy 356.266496 -343.473532) (xy 356.266064 -343.514635) (xy 356.258476 -343.596491) (xy 356.243368 -343.677298)
			(xy 356.220868 -343.756366) (xy 356.191169 -343.83302) (xy 356.154525 -343.906608) (xy 356.111246 -343.9765)
			(xy 356.061704 -344.042101) (xy 356.00632 -344.102851) (xy 355.945567 -344.158232) (xy 355.879964 -344.207771)
			(xy 355.810069 -344.251046) (xy 355.73648 -344.287687) (xy 355.659824 -344.317382) (xy 355.580755 -344.339878)
			(xy 355.499948 -344.354982) (xy 355.418091 -344.362566) (xy 355.376988 -344.36304) (xy 355.376226 -344.36304)
			(xy 355.334685 -344.362565) (xy 355.251968 -344.35478) (xy 355.170337 -344.33932) (xy 355.090501 -344.316321)
			(xy 355.013156 -344.285984) (xy 354.938974 -344.248571) (xy 354.903532 -344.226896) (xy 354.894382 -344.221758)
			(xy 354.873674 -344.218535) (xy 354.853403 -344.223857) (xy 354.844858 -344.229944) (xy 354.811228 -344.255891)
			(xy 354.73985 -344.301947) (xy 354.664408 -344.340991) (xy 354.585588 -344.372667) (xy 354.504107 -344.396686)
			(xy 354.420709 -344.412831) (xy 354.336151 -344.420953) (xy 354.293678 -344.42146) (xy 354.293424 -344.42146)
			(xy 354.25232 -344.421025) (xy 354.170462 -344.413441) (xy 354.089653 -344.398337) (xy 354.010583 -344.375841)
			(xy 353.933926 -344.346144) (xy 353.860336 -344.309501) (xy 353.790441 -344.266224) (xy 353.724837 -344.216682)
			(xy 353.664085 -344.161298) (xy 353.608703 -344.100544) (xy 353.559163 -344.03494) (xy 353.515887 -343.965043)
			(xy 353.479246 -343.891453) (xy 353.449552 -343.814794) (xy 353.427057 -343.735723) (xy 353.411955 -343.654914)
			(xy 353.404374 -343.573056) (xy 353.403916 -343.531952) (xy 353.403916 -343.531698) (xy 353.4045 -343.48696)
			(xy 353.413511 -343.397939) (xy 353.431411 -343.310272) (xy 353.45802 -343.224844) (xy 353.475036 -343.183464)
			(xy 353.478628 -343.173881) (xy 353.47861 -343.153431) (xy 353.475036 -343.14384) (xy 353.457998 -343.102434)
			(xy 353.431368 -343.016945) (xy 353.413464 -342.929211) (xy 353.404469 -342.840123) (xy 353.403916 -342.795352)
			(xy 353.403916 -342.783414) (xy 353.377438 -342.777466) (xy 353.325203 -342.762725) (xy 353.299522 -342.75395)
			(xy 353.291325 -342.751436) (xy 353.274191 -342.751436) (xy 353.265994 -342.75395) (xy 353.230774 -342.765885)
			(xy 353.158765 -342.784475) (xy 353.085444 -342.796919) (xy 353.011333 -342.803127) (xy 352.974148 -342.80348)
			(xy 352.936964 -342.803098) (xy 352.862857 -342.79688) (xy 352.789537 -342.784441) (xy 352.717525 -342.76587)
			(xy 352.682302 -342.75395) (xy 352.674105 -342.751436) (xy 352.656971 -342.751436) (xy 352.648774 -342.75395)
			(xy 352.613678 -342.765853) (xy 352.541919 -342.784399) (xy 352.468854 -342.796841) (xy 352.395002 -342.80309)
			(xy 352.357944 -342.80348) (xy 352.356928 -342.80348) (xy 352.314999 -342.803074) (xy 352.231522 -342.795106)
			(xy 352.149179 -342.779238) (xy 352.068718 -342.755615) (xy 351.990867 -342.72445) (xy 351.916331 -342.686026)
			(xy 351.845785 -342.640691) (xy 351.779867 -342.588855) (xy 351.719176 -342.530987) (xy 351.66426 -342.467613)
			(xy 351.615617 -342.399306) (xy 351.573688 -342.326683) (xy 351.538852 -342.250404) (xy 351.511424 -342.171159)
			(xy 351.491654 -342.089666) (xy 351.479719 -342.006662) (xy 351.475729 -341.9229) (xy 107.867795 -341.9229)
			(xy 107.866258 -341.938099) (xy 107.848353 -342.02583) (xy 107.821735 -342.111321) (xy 107.804712 -342.152732)
			(xy 107.80112 -342.162315) (xy 107.801136 -342.182765) (xy 107.804712 -342.192356) (xy 107.821734 -342.233768)
			(xy 107.848372 -342.319255) (xy 107.86628 -342.406986) (xy 107.875278 -342.496074) (xy 107.875832 -342.540844)
			(xy 107.875405 -342.579435) (xy 107.868704 -342.656327) (xy 107.855365 -342.732349) (xy 107.835489 -342.806929)
			(xy 107.822746 -342.843358) (xy 107.81982 -342.852801) (xy 107.820595 -342.872535) (xy 107.82427 -342.881712)
			(xy 107.843302 -342.9251) (xy 107.873066 -343.015053) (xy 107.893096 -343.107662) (xy 107.903166 -343.201875)
			(xy 107.903772 -343.24925) (xy 107.903772 -343.249504) (xy 107.903199 -343.294273) (xy 107.894192 -343.383358)
			(xy 107.87629 -343.471089) (xy 107.849674 -343.556581) (xy 107.832652 -343.597992) (xy 107.829086 -343.607582)
			(xy 107.829087 -343.628025) (xy 107.832652 -343.637616) (xy 107.849695 -343.67902) (xy 107.876327 -343.76451)
			(xy 107.894229 -343.852244) (xy 107.903221 -343.941333) (xy 107.903772 -343.986104) (xy 107.903338 -344.0272)
			(xy 107.895755 -344.109042) (xy 107.880654 -344.189835) (xy 107.858164 -344.268891) (xy 107.828477 -344.345534)
			(xy 107.791846 -344.419112) (xy 107.748583 -344.488997) (xy 107.699057 -344.554593) (xy 107.643692 -344.61534)
			(xy 107.582958 -344.670721) (xy 107.517374 -344.720262) (xy 107.447499 -344.763541) (xy 107.37393 -344.80019)
			(xy 107.297294 -344.829896) (xy 107.218244 -344.852405) (xy 107.137454 -344.867525) (xy 107.055614 -344.875128)
			(xy 107.014518 -344.875612) (xy 107.01401 -344.875612) (xy 106.971454 -344.875048) (xy 106.886731 -344.866913)
			(xy 106.803172 -344.850725) (xy 106.72154 -344.826633) (xy 106.642582 -344.794856) (xy 106.567018 -344.755685)
			(xy 106.49554 -344.709478) (xy 106.428801 -344.656658) (xy 106.36741 -344.597706) (xy 106.311928 -344.533162)
			(xy 106.262863 -344.463615) (xy 106.220663 -344.389701) (xy 106.202734 -344.351102) (xy 106.197143 -344.340314)
			(xy 106.178175 -344.325188) (xy 106.166412 -344.322146) (xy 106.123815 -344.31302) (xy 106.04054 -344.287419)
			(xy 105.960165 -344.253801) (xy 105.883461 -344.212489) (xy 105.811162 -344.163878) (xy 105.74396 -344.108434)
			(xy 105.682498 -344.046687) (xy 105.627365 -343.979229) (xy 105.579089 -343.906705) (xy 105.538133 -343.829811)
			(xy 105.504888 -343.749281) (xy 105.479672 -343.665888) (xy 105.462727 -343.58043) (xy 105.454216 -343.493725)
			(xy 105.453688 -343.450164) (xy 105.454253 -343.405394) (xy 105.463263 -343.316309) (xy 105.481167 -343.228578)
			(xy 105.507785 -343.143087) (xy 105.524808 -343.101676) (xy 105.528395 -343.092092) (xy 105.528382 -343.071643)
			(xy 105.524808 -343.062052) (xy 105.508891 -343.02338) (xy 105.483531 -342.943684) (xy 105.46577 -342.861957)
			(xy 105.460292 -342.820498) (xy 105.458558 -342.81058) (xy 105.448632 -342.793088) (xy 105.43277 -342.780723)
			(xy 105.423208 -342.777572) (xy 105.40795 -342.773353) (xy 105.377717 -342.763951) (xy 105.362756 -342.758776)
			(xy 105.354559 -342.756262) (xy 105.337425 -342.756262) (xy 105.329228 -342.758776) (xy 105.294015 -342.770747)
			(xy 105.222011 -342.789399) (xy 105.148689 -342.801905) (xy 105.074572 -342.808175) (xy 105.037382 -342.80856)
			(xy 105.000192 -342.808173) (xy 104.926079 -342.801882) (xy 104.85276 -342.789372) (xy 104.780754 -342.770731)
			(xy 104.745536 -342.758776) (xy 104.737339 -342.756262) (xy 104.720205 -342.756262) (xy 104.712008 -342.758776)
			(xy 104.676797 -342.770753) (xy 104.604792 -342.789403) (xy 104.531469 -342.801908) (xy 104.457353 -342.808176)
			(xy 104.420162 -342.80856) (xy 104.378225 -342.808083) (xy 104.294732 -342.800107) (xy 104.212375 -342.784231)
			(xy 104.131899 -342.760598) (xy 104.054035 -342.729423) (xy 103.979486 -342.690988) (xy 103.908929 -342.64564)
			(xy 103.843001 -342.593792) (xy 103.7823 -342.535911) (xy 103.727376 -342.472522) (xy 103.678726 -342.4042)
			(xy 103.63679 -342.331563) (xy 103.601948 -342.255269) (xy 103.574517 -342.176008) (xy 103.554743 -342.094498)
			(xy 103.542807 -342.011479) (xy 103.538816 -341.9277) (xy 2.509012 -341.9277) (xy 2.509012 -345.238324)
			(xy 88.42502 -345.238324) (xy 88.42502 -345.237562) (xy 88.425476 -345.196455) (xy 88.433064 -345.114592)
			(xy 88.448171 -345.033778) (xy 88.470668 -344.954703) (xy 88.500364 -344.87804) (xy 88.537005 -344.804443)
			(xy 88.58028 -344.73454) (xy 88.629818 -344.668927) (xy 88.685198 -344.608163) (xy 88.745947 -344.552768)
			(xy 88.811546 -344.503212) (xy 88.881438 -344.459919) (xy 88.955025 -344.423259) (xy 89.031681 -344.393542)
			(xy 89.110751 -344.371024) (xy 89.19156 -344.355896) (xy 89.273421 -344.348287) (xy 89.314528 -344.3478)
			(xy 89.358923 -344.348358) (xy 89.447268 -344.357247) (xy 89.534288 -344.374894) (xy 89.619117 -344.401123)
			(xy 89.660222 -344.417904) (xy 89.668919 -344.421068) (xy 89.687398 -344.421734) (xy 89.69629 -344.419174)
			(xy 89.742575 -344.404089) (xy 89.837607 -344.382956) (xy 89.934379 -344.372329) (xy 89.983056 -344.371676)
			(xy 89.984326 -344.371676) (xy 90.022483 -344.372111) (xy 90.098512 -344.378695) (xy 90.173695 -344.391776)
			(xy 90.24748 -344.411259) (xy 90.283538 -344.423746) (xy 90.291854 -344.426332) (xy 90.309258 -344.426332)
			(xy 90.317574 -344.423746) (xy 90.353782 -344.41121) (xy 90.427885 -344.391692) (xy 90.503391 -344.378612)
			(xy 90.579741 -344.372068) (xy 90.618056 -344.371676) (xy 90.664451 -344.372276) (xy 90.756739 -344.381916)
			(xy 90.847523 -344.401107) (xy 90.935817 -344.429641) (xy 90.978482 -344.447876) (xy 90.988424 -344.451682)
			(xy 91.009688 -344.451682) (xy 91.01963 -344.447876) (xy 91.062298 -344.429645) (xy 91.150588 -344.401097)
			(xy 91.241371 -344.381901) (xy 91.33366 -344.372263) (xy 91.380056 -344.371676) (xy 91.418372 -344.372058)
			(xy 91.494725 -344.378586) (xy 91.570232 -344.391667) (xy 91.644331 -344.411203) (xy 91.680538 -344.423746)
			(xy 91.688854 -344.426332) (xy 91.706258 -344.426332) (xy 91.714574 -344.423746) (xy 91.750782 -344.41121)
			(xy 91.824885 -344.391692) (xy 91.900391 -344.378612) (xy 91.976741 -344.372068) (xy 92.015056 -344.371676)
			(xy 92.053372 -344.372058) (xy 92.129725 -344.378586) (xy 92.205232 -344.391667) (xy 92.279331 -344.411203)
			(xy 92.315538 -344.423746) (xy 92.323854 -344.426332) (xy 92.341258 -344.426332) (xy 92.349574 -344.423746)
			(xy 92.385691 -344.411238) (xy 92.459606 -344.391753) (xy 92.534918 -344.378674) (xy 92.611074 -344.372097)
			(xy 92.649294 -344.371676) (xy 92.650056 -344.371676) (xy 92.691158 -344.372194) (xy 92.773012 -344.379775)
			(xy 92.853817 -344.394876) (xy 92.932883 -344.417369) (xy 93.009537 -344.447061) (xy 93.083125 -344.4837)
			(xy 93.153018 -344.526972) (xy 93.21862 -344.576508) (xy 93.279371 -344.631887) (xy 93.334753 -344.692634)
			(xy 93.384294 -344.758233) (xy 93.427571 -344.828123) (xy 93.464215 -344.901708) (xy 93.493912 -344.97836)
			(xy 93.51641 -345.057425) (xy 93.531517 -345.138229) (xy 93.539103 -345.220082) (xy 93.539564 -345.261184)
			(xy 93.539564 -345.261692) (xy 93.539139 -345.302203) (xy 93.531771 -345.38289) (xy 93.517086 -345.462571)
			(xy 93.495207 -345.540583) (xy 93.466315 -345.616279) (xy 93.448886 -345.652852) (xy 93.444973 -345.661871)
			(xy 93.443532 -345.68146) (xy 93.446092 -345.690952) (xy 93.460285 -345.736019) (xy 93.480192 -345.828387)
			(xy 93.490186 -345.922345) (xy 93.490796 -345.96959) (xy 93.490238 -346.015229) (xy 93.480936 -346.106032)
			(xy 93.462388 -346.195406) (xy 93.44914 -346.239084) (xy 93.446696 -346.248096) (xy 93.447735 -346.266724)
			(xy 93.451172 -346.275406) (xy 93.469867 -346.318487) (xy 93.49915 -346.407722) (xy 93.518862 -346.499547)
			(xy 93.527728 -346.583) (xy 200.85558 -346.583) (xy 200.856207 -346.536598) (xy 200.865897 -346.444301)
			(xy 200.88515 -346.353515) (xy 200.913758 -346.26523) (xy 200.932034 -346.222574) (xy 200.935843 -346.212632)
			(xy 200.935843 -346.191368) (xy 200.932034 -346.181426) (xy 200.913772 -346.138765) (xy 200.885179 -346.050477)
			(xy 200.865922 -345.959694) (xy 200.856209 -345.867401) (xy 200.85558 -345.821) (xy 200.856064 -345.779859)
			(xy 200.863695 -345.69793) (xy 200.878855 -345.617056) (xy 200.901414 -345.537926) (xy 200.931179 -345.461215)
			(xy 200.967897 -345.38758) (xy 200.989184 -345.35237) (xy 200.993752 -345.344157) (xy 200.997195 -345.3257)
			(xy 200.993752 -345.307243) (xy 200.989184 -345.29903) (xy 200.967885 -345.263826) (xy 200.931155 -345.190194)
			(xy 200.901383 -345.113484) (xy 200.878824 -345.034352) (xy 200.86367 -344.953474) (xy 200.856051 -344.871542)
			(xy 200.85558 -344.8304) (xy 200.856207 -344.783998) (xy 200.865897 -344.691701) (xy 200.88515 -344.600915)
			(xy 200.913758 -344.51263) (xy 200.932034 -344.469974) (xy 200.935843 -344.460032) (xy 200.935843 -344.438768)
			(xy 200.932034 -344.428826) (xy 200.913772 -344.386165) (xy 200.885179 -344.297877) (xy 200.865922 -344.207094)
			(xy 200.856209 -344.114801) (xy 200.85558 -344.0684) (xy 200.856084 -344.026039) (xy 200.864137 -343.941702)
			(xy 200.880171 -343.858512) (xy 200.904039 -343.777222) (xy 200.935527 -343.69857) (xy 200.974349 -343.623267)
			(xy 201.020152 -343.551995) (xy 201.072523 -343.485399) (xy 201.130988 -343.424084) (xy 201.195016 -343.368603)
			(xy 201.264028 -343.31946) (xy 201.337398 -343.2771) (xy 201.414463 -343.241905) (xy 201.494525 -343.214196)
			(xy 201.576858 -343.194222) (xy 201.660717 -343.182165) (xy 201.745342 -343.178134) (xy 201.829967 -343.182165)
			(xy 201.913826 -343.194222) (xy 201.996159 -343.214196) (xy 202.076221 -343.241905) (xy 202.153286 -343.2771)
			(xy 202.226656 -343.31946) (xy 202.295668 -343.368603) (xy 202.359696 -343.424084) (xy 202.418161 -343.485399)
			(xy 202.470532 -343.551995) (xy 202.516335 -343.623267) (xy 202.555157 -343.69857) (xy 202.586645 -343.777222)
			(xy 202.610513 -343.858512) (xy 202.626547 -343.941702) (xy 202.6346 -344.026039) (xy 202.635104 -344.0684)
			(xy 202.634479 -344.114802) (xy 202.624789 -344.2071) (xy 202.605534 -344.297885) (xy 202.576926 -344.38617)
			(xy 202.55865 -344.428826) (xy 202.554842 -344.438768) (xy 202.554842 -344.460032) (xy 202.55865 -344.469974)
			(xy 202.576911 -344.512635) (xy 202.605505 -344.600923) (xy 202.624762 -344.691706) (xy 202.634475 -344.783999)
			(xy 202.635104 -344.8304) (xy 202.634622 -344.871541) (xy 202.626991 -344.95347) (xy 202.611831 -345.034344)
			(xy 202.589272 -345.113474) (xy 202.559506 -345.190185) (xy 202.522787 -345.263821) (xy 202.5015 -345.29903)
			(xy 202.496933 -345.307243) (xy 202.493491 -345.3257) (xy 202.496933 -345.344157) (xy 202.5015 -345.35237)
			(xy 202.522797 -345.387575) (xy 202.559528 -345.461207) (xy 202.5893 -345.537917) (xy 202.61186 -345.617049)
			(xy 202.627014 -345.697926) (xy 202.634633 -345.779858) (xy 202.635104 -345.821) (xy 202.634479 -345.867402)
			(xy 202.624789 -345.9597) (xy 202.605534 -346.050485) (xy 202.576926 -346.13877) (xy 202.55865 -346.181426)
			(xy 202.554842 -346.191368) (xy 202.554842 -346.212632) (xy 202.55865 -346.222574) (xy 202.576911 -346.265235)
			(xy 202.605505 -346.353523) (xy 202.624762 -346.444306) (xy 202.634475 -346.536599) (xy 202.635104 -346.583)
			(xy 202.6346 -346.625361) (xy 202.626547 -346.709698) (xy 202.610513 -346.792888) (xy 202.586645 -346.874178)
			(xy 202.555157 -346.95283) (xy 202.516335 -347.028133) (xy 202.470532 -347.099405) (xy 202.418161 -347.166001)
			(xy 202.359696 -347.227316) (xy 202.295668 -347.282797) (xy 202.226656 -347.33194) (xy 202.153286 -347.3743)
			(xy 202.076221 -347.409495) (xy 201.996159 -347.437204) (xy 201.913826 -347.457178) (xy 201.829967 -347.469235)
			(xy 201.745342 -347.473267) (xy 201.660717 -347.469235) (xy 201.576858 -347.457178) (xy 201.494525 -347.437204)
			(xy 201.414463 -347.409495) (xy 201.337398 -347.3743) (xy 201.264028 -347.33194) (xy 201.195016 -347.282797)
			(xy 201.130988 -347.227316) (xy 201.072523 -347.166001) (xy 201.020152 -347.099405) (xy 200.974349 -347.028133)
			(xy 200.935527 -346.95283) (xy 200.904039 -346.874178) (xy 200.880171 -346.792888) (xy 200.864137 -346.709698)
			(xy 200.856084 -346.625361) (xy 200.85558 -346.583) (xy 93.527728 -346.583) (xy 93.528784 -346.592938)
			(xy 93.529404 -346.639896) (xy 93.528944 -346.681007) (xy 93.521356 -346.762877) (xy 93.506246 -346.843698)
			(xy 93.483741 -346.92278) (xy 93.454034 -346.999447) (xy 93.417379 -347.073045) (xy 93.374088 -347.142947)
			(xy 93.324531 -347.208555) (xy 93.269131 -347.26931) (xy 93.20836 -347.324693) (xy 93.142737 -347.374232)
			(xy 93.072823 -347.417503) (xy 92.999214 -347.454137) (xy 92.922539 -347.483822) (xy 92.843451 -347.506304)
			(xy 92.762626 -347.521391) (xy 92.680753 -347.528955) (xy 92.639642 -347.529404) (xy 92.601326 -347.529024)
			(xy 92.524973 -347.522495) (xy 92.449466 -347.509414) (xy 92.375367 -347.489878) (xy 92.33916 -347.477334)
			(xy 92.330844 -347.474748) (xy 92.31344 -347.474748) (xy 92.305124 -347.477334) (xy 92.268906 -347.489842)
			(xy 92.194807 -347.509368) (xy 92.119304 -347.522455) (xy 92.042956 -347.529008) (xy 92.004642 -347.529404)
			(xy 91.961529 -347.52892) (xy 91.875703 -347.520642) (xy 91.791081 -347.504091) (xy 91.70846 -347.479423)
			(xy 91.668346 -347.463618) (xy 91.658977 -347.460281) (xy 91.639107 -347.460281) (xy 91.629738 -347.463618)
			(xy 91.589623 -347.479419) (xy 91.506999 -347.504075) (xy 91.422379 -347.520627) (xy 91.336554 -347.528919)
			(xy 91.293442 -347.529404) (xy 91.255126 -347.529024) (xy 91.178773 -347.522495) (xy 91.103266 -347.509414)
			(xy 91.029167 -347.489878) (xy 90.99296 -347.477334) (xy 90.984644 -347.474748) (xy 90.96724 -347.474748)
			(xy 90.958924 -347.477334) (xy 90.922706 -347.489842) (xy 90.848607 -347.509368) (xy 90.773104 -347.522455)
			(xy 90.696756 -347.529008) (xy 90.658442 -347.529404) (xy 90.620126 -347.529024) (xy 90.543773 -347.522495)
			(xy 90.468266 -347.509414) (xy 90.394167 -347.489878) (xy 90.35796 -347.477334) (xy 90.349644 -347.474748)
			(xy 90.33224 -347.474748) (xy 90.323924 -347.477334) (xy 90.287706 -347.489842) (xy 90.213607 -347.509368)
			(xy 90.138104 -347.522455) (xy 90.061756 -347.529008) (xy 90.023442 -347.529404) (xy 89.985126 -347.529024)
			(xy 89.908773 -347.522495) (xy 89.833266 -347.509414) (xy 89.759167 -347.489878) (xy 89.72296 -347.477334)
			(xy 89.714644 -347.474748) (xy 89.69724 -347.474748) (xy 89.688924 -347.477334) (xy 89.652807 -347.489842)
			(xy 89.578892 -347.509327) (xy 89.50358 -347.522407) (xy 89.427424 -347.528983) (xy 89.389204 -347.529404)
			(xy 89.388442 -347.529404) (xy 89.347337 -347.528847) (xy 89.265478 -347.521267) (xy 89.184667 -347.506168)
			(xy 89.105593 -347.483678) (xy 89.028932 -347.453989) (xy 88.955336 -347.417355) (xy 88.885433 -347.374087)
			(xy 88.81982 -347.324556) (xy 88.759057 -347.269183) (xy 88.70366 -347.20844) (xy 88.654104 -347.142846)
			(xy 88.61081 -347.07296) (xy 88.574148 -346.999378) (xy 88.54443 -346.922728) (xy 88.52191 -346.843663)
			(xy 88.506779 -346.762857) (xy 88.499168 -346.681001) (xy 88.49868 -346.639896) (xy 88.49928 -346.594251)
			(xy 88.508675 -346.503445) (xy 88.527305 -346.414075) (xy 88.54059 -346.370402) (xy 88.543039 -346.361391)
			(xy 88.541996 -346.342762) (xy 88.538558 -346.33408) (xy 88.519895 -346.290993) (xy 88.490688 -346.201748)
			(xy 88.471043 -346.109924) (xy 88.461176 -346.016541) (xy 88.46058 -345.96959) (xy 88.460997 -345.930463)
			(xy 88.467845 -345.852508) (xy 88.481506 -345.775455) (xy 88.501874 -345.699897) (xy 88.514936 -345.663012)
			(xy 88.517951 -345.653293) (xy 88.516917 -345.632991) (xy 88.512904 -345.623642) (xy 88.496039 -345.587523)
			(xy 88.46806 -345.512874) (xy 88.44687 -345.436021) (xy 88.432638 -345.357582) (xy 88.425479 -345.278184)
			(xy 88.42502 -345.238324) (xy 2.509012 -345.238324) (xy 2.509012 -348.70949) (xy 28.410141 -348.70949)
			(xy 28.414132 -348.625708) (xy 28.426069 -348.542686) (xy 28.445844 -348.461173) (xy 28.473277 -348.38191)
			(xy 28.508121 -348.305613) (xy 28.550059 -348.232974) (xy 28.598712 -348.16465) (xy 28.65364 -348.101261)
			(xy 28.714345 -348.043379) (xy 28.780276 -347.99153) (xy 28.850838 -347.946183) (xy 28.92539 -347.907749)
			(xy 29.003259 -347.876576) (xy 29.083738 -347.852945) (xy 29.166099 -347.837072) (xy 29.249596 -347.829099)
			(xy 29.291534 -347.828616) (xy 29.328723 -347.829023) (xy 29.402836 -347.835307) (xy 29.476156 -347.847812)
			(xy 29.548162 -347.866448) (xy 29.58338 -347.8784) (xy 29.591577 -347.880914) (xy 29.608711 -347.880914)
			(xy 29.616908 -347.8784) (xy 29.652035 -347.866473) (xy 29.723849 -347.847849) (xy 29.796976 -347.835339)
			(xy 29.870898 -347.829031) (xy 29.907992 -347.828616) (xy 29.909516 -347.828616) (xy 29.916374 -347.82887)
			(xy 29.922431 -347.792721) (xy 29.939716 -347.721486) (xy 29.962803 -347.651915) (xy 29.976826 -347.61805)
			(xy 29.980289 -347.608427) (xy 29.980173 -347.587996) (xy 29.976572 -347.578426) (xy 29.959544 -347.537016)
			(xy 29.932908 -347.451529) (xy 29.915001 -347.363797) (xy 29.906005 -347.274709) (xy 29.905452 -347.229938)
			(xy 29.905933 -347.189355) (xy 29.913331 -347.108527) (xy 29.928059 -347.028709) (xy 29.949995 -346.950564)
			(xy 29.978957 -346.874741) (xy 30.014703 -346.801871) (xy 30.056938 -346.732559) (xy 30.10531 -346.667382)
			(xy 30.159416 -346.606881) (xy 30.218807 -346.551559) (xy 30.28299 -346.501876) (xy 30.351431 -346.458245)
			(xy 30.38729 -346.439236) (xy 30.395816 -346.434265) (xy 30.408633 -346.419285) (xy 30.414885 -346.400588)
			(xy 30.414722 -346.390722) (xy 30.41396 -346.365322) (xy 30.414481 -346.337437) (xy 30.422793 -346.28229)
			(xy 30.439231 -346.228998) (xy 30.463429 -346.178752) (xy 30.494845 -346.132673) (xy 30.532778 -346.091791)
			(xy 30.57638 -346.057019) (xy 30.624678 -346.029134) (xy 30.676593 -346.008759) (xy 30.730964 -345.996349)
			(xy 30.786578 -345.992182) (xy 30.842192 -345.996349) (xy 30.896563 -346.008759) (xy 30.948478 -346.029134)
			(xy 30.996776 -346.057019) (xy 31.040378 -346.091791) (xy 31.078311 -346.132673) (xy 31.109727 -346.178752)
			(xy 31.133925 -346.228998) (xy 31.150363 -346.28229) (xy 31.158675 -346.337437) (xy 31.159196 -346.365322)
			(xy 31.158688 -346.383356) (xy 31.15866 -346.393249) (xy 31.165282 -346.411875) (xy 31.178455 -346.426614)
			(xy 31.187136 -346.431362) (xy 31.224041 -346.449965) (xy 31.294555 -346.49308) (xy 31.360766 -346.542551)
			(xy 31.4221 -346.597952) (xy 31.47803 -346.658805) (xy 31.528073 -346.724585) (xy 31.571797 -346.794724)
			(xy 31.608825 -346.868616) (xy 31.638837 -346.945626) (xy 31.661575 -347.025088) (xy 31.676842 -347.106317)
			(xy 31.684507 -347.188612) (xy 31.684976 -347.229938) (xy 31.684414 -347.274708) (xy 31.675404 -347.363793)
			(xy 31.657499 -347.451524) (xy 31.630879 -347.537015) (xy 31.613856 -347.578426) (xy 31.61027 -347.58801)
			(xy 31.610284 -347.608459) (xy 31.613856 -347.61805) (xy 31.630031 -347.657368) (xy 31.655701 -347.738424)
			(xy 31.673532 -347.821557) (xy 31.68336 -347.906011) (xy 31.684722 -347.948504) (xy 31.684976 -347.96222)
			(xy 31.6992 -347.985588) (xy 31.788862 -348.034102) (xy 31.796927 -348.038113) (xy 31.814734 -348.040741)
			(xy 31.832352 -348.037052) (xy 31.84017 -348.032578) (xy 31.875522 -348.010993) (xy 31.949529 -347.973778)
			(xy 32.026677 -347.943609) (xy 32.106297 -347.920748) (xy 32.187699 -347.905393) (xy 32.270176 -347.897677)
			(xy 32.311594 -347.897196) (xy 32.352707 -347.897719) (xy 32.434582 -347.905305) (xy 32.515408 -347.920413)
			(xy 32.594495 -347.942914) (xy 32.671169 -347.972616) (xy 32.744775 -348.009266) (xy 32.814686 -348.05255)
			(xy 32.880304 -348.102101) (xy 32.941071 -348.157495) (xy 32.996468 -348.218259) (xy 33.046022 -348.283875)
			(xy 33.089311 -348.353783) (xy 33.125965 -348.427387) (xy 33.155671 -348.504059) (xy 33.178176 -348.583145)
			(xy 33.193289 -348.66397) (xy 33.197509 -348.70949) (xy 36.690541 -348.70949) (xy 36.694532 -348.625708)
			(xy 36.706469 -348.542686) (xy 36.726244 -348.461173) (xy 36.753677 -348.38191) (xy 36.788521 -348.305613)
			(xy 36.830459 -348.232974) (xy 36.879112 -348.16465) (xy 36.93404 -348.101261) (xy 36.994745 -348.043379)
			(xy 37.060676 -347.99153) (xy 37.131238 -347.946183) (xy 37.20579 -347.907749) (xy 37.283659 -347.876576)
			(xy 37.364138 -347.852945) (xy 37.446499 -347.837072) (xy 37.529996 -347.829099) (xy 37.571934 -347.828616)
			(xy 37.609123 -347.829023) (xy 37.683236 -347.835307) (xy 37.756556 -347.847812) (xy 37.828562 -347.866448)
			(xy 37.86378 -347.8784) (xy 37.871977 -347.880914) (xy 37.889111 -347.880914) (xy 37.897308 -347.8784)
			(xy 37.93549 -347.865472) (xy 38.013674 -347.845816) (xy 38.093328 -347.833391) (xy 38.133528 -347.830394)
			(xy 38.144516 -347.829167) (xy 38.163935 -347.818636) (xy 38.177169 -347.800949) (xy 38.18001 -347.790262)
			(xy 38.189419 -347.748079) (xy 38.215379 -347.665637) (xy 38.231826 -347.62567) (xy 38.235335 -347.61606)
			(xy 38.235189 -347.595617) (xy 38.231572 -347.586046) (xy 38.21455 -347.544634) (xy 38.187912 -347.459147)
			(xy 38.170004 -347.371416) (xy 38.161006 -347.282328) (xy 38.160452 -347.237558) (xy 38.160956 -347.195197)
			(xy 38.169009 -347.11086) (xy 38.185043 -347.02767) (xy 38.208911 -346.94638) (xy 38.240399 -346.867728)
			(xy 38.279221 -346.792425) (xy 38.325024 -346.721153) (xy 38.377395 -346.654557) (xy 38.43586 -346.593242)
			(xy 38.499888 -346.537761) (xy 38.5689 -346.488618) (xy 38.64227 -346.446258) (xy 38.719335 -346.411063)
			(xy 38.799397 -346.383354) (xy 38.88173 -346.36338) (xy 38.965589 -346.351323) (xy 39.050214 -346.347292)
			(xy 39.134839 -346.351323) (xy 39.218698 -346.36338) (xy 39.301031 -346.383354) (xy 39.381093 -346.411063)
			(xy 39.458158 -346.446258) (xy 39.531528 -346.488618) (xy 39.60054 -346.537761) (xy 39.664568 -346.593242)
			(xy 39.723033 -346.654557) (xy 39.775404 -346.721153) (xy 39.821207 -346.792425) (xy 39.860029 -346.867728)
			(xy 39.891517 -346.94638) (xy 39.915385 -347.02767) (xy 39.931419 -347.11086) (xy 39.939472 -347.195197)
			(xy 39.939976 -347.237558) (xy 39.939421 -347.282328) (xy 39.930409 -347.371413) (xy 39.912502 -347.459144)
			(xy 39.88588 -347.544635) (xy 39.868856 -347.586046) (xy 39.865251 -347.595621) (xy 39.865104 -347.616057)
			(xy 39.868602 -347.62567) (xy 39.88516 -347.665899) (xy 39.911278 -347.748887) (xy 39.929176 -347.834027)
			(xy 39.938683 -347.920507) (xy 39.939722 -347.963998) (xy 39.939722 -347.964252) (xy 39.94031 -347.973302)
			(xy 39.94696 -347.990157) (xy 39.959055 -348.003648) (xy 39.9669 -348.008194) (xy 40.058086 -348.056454)
			(xy 40.086026 -348.05493) (xy 40.09771 -348.04731) (xy 40.134305 -348.023444) (xy 40.211348 -347.98223)
			(xy 40.292061 -347.948768) (xy 40.375665 -347.923381) (xy 40.461356 -347.906311) (xy 40.548307 -347.897725)
			(xy 40.591994 -347.897196) (xy 40.633107 -347.897719) (xy 40.714982 -347.905305) (xy 40.795808 -347.920413)
			(xy 40.874895 -347.942914) (xy 40.951569 -347.972616) (xy 41.025175 -348.009266) (xy 41.095086 -348.05255)
			(xy 41.160704 -348.102101) (xy 41.221471 -348.157495) (xy 41.276868 -348.218259) (xy 41.326422 -348.283875)
			(xy 41.369711 -348.353783) (xy 41.406365 -348.427387) (xy 41.436071 -348.504059) (xy 41.458576 -348.583145)
			(xy 41.473689 -348.66397) (xy 41.47791 -348.7095) (xy 44.996301 -348.7095) (xy 45.000292 -348.625716)
			(xy 45.01223 -348.54269) (xy 45.032006 -348.461175) (xy 45.05944 -348.381909) (xy 45.094286 -348.30561)
			(xy 45.136227 -348.232969) (xy 45.184883 -348.164644) (xy 45.239813 -348.101253) (xy 45.30052 -348.043371)
			(xy 45.366455 -347.991522) (xy 45.43702 -347.946175) (xy 45.511576 -347.907741) (xy 45.589448 -347.876568)
			(xy 45.66993 -347.852939) (xy 45.752294 -347.837068) (xy 45.835794 -347.829098) (xy 45.877734 -347.828616)
			(xy 45.914923 -347.829023) (xy 45.989036 -347.835307) (xy 46.062356 -347.847812) (xy 46.134362 -347.866448)
			(xy 46.16958 -347.8784) (xy 46.177777 -347.880914) (xy 46.194911 -347.880914) (xy 46.203108 -347.8784)
			(xy 46.238327 -347.866445) (xy 46.310329 -347.847789) (xy 46.383649 -347.835279) (xy 46.457764 -347.829003)
			(xy 46.494954 -347.828616) (xy 46.496732 -347.82887) (xy 46.506097 -347.78788) (xy 46.53154 -347.707736)
			(xy 46.547532 -347.66885) (xy 46.551076 -347.659253) (xy 46.55109 -347.638816) (xy 46.547532 -347.629226)
			(xy 46.530501 -347.587817) (xy 46.503866 -347.502329) (xy 46.485961 -347.414597) (xy 46.476965 -347.325509)
			(xy 46.476412 -347.280738) (xy 46.476916 -347.238377) (xy 46.484969 -347.15404) (xy 46.501003 -347.07085)
			(xy 46.524871 -346.98956) (xy 46.556359 -346.910908) (xy 46.595181 -346.835605) (xy 46.640984 -346.764333)
			(xy 46.693355 -346.697737) (xy 46.75182 -346.636422) (xy 46.815848 -346.580941) (xy 46.88486 -346.531798)
			(xy 46.95823 -346.489438) (xy 47.035295 -346.454243) (xy 47.115357 -346.426534) (xy 47.19769 -346.40656)
			(xy 47.281549 -346.394503) (xy 47.366174 -346.390472) (xy 47.450799 -346.394503) (xy 47.534658 -346.40656)
			(xy 47.616991 -346.426534) (xy 47.697053 -346.454243) (xy 47.774118 -346.489438) (xy 47.847488 -346.531798)
			(xy 47.9165 -346.580941) (xy 47.980528 -346.636422) (xy 48.038993 -346.697737) (xy 48.091364 -346.764333)
			(xy 48.137167 -346.835605) (xy 48.175989 -346.910908) (xy 48.207477 -346.98956) (xy 48.231345 -347.07085)
			(xy 48.247379 -347.15404) (xy 48.255432 -347.238377) (xy 48.255936 -347.280738) (xy 48.25537 -347.325508)
			(xy 48.24636 -347.414592) (xy 48.228456 -347.502324) (xy 48.201838 -347.587815) (xy 48.184816 -347.629226)
			(xy 48.181232 -347.638811) (xy 48.181246 -347.659259) (xy 48.184816 -347.66885) (xy 48.199304 -347.703977)
			(xy 48.222973 -347.776187) (xy 48.2404 -347.850153) (xy 48.251457 -347.925335) (xy 48.254158 -347.963236)
			(xy 48.255104 -347.972078) (xy 48.26215 -347.988388) (xy 48.274337 -348.001315) (xy 48.282098 -348.005654)
			(xy 48.37303 -348.051374) (xy 48.3997 -348.04985) (xy 48.41113 -348.04223) (xy 48.447343 -348.019182)
			(xy 48.523387 -347.979349) (xy 48.602912 -347.947022) (xy 48.685181 -347.922504) (xy 48.769429 -347.90602)
			(xy 48.854872 -347.897725) (xy 48.897794 -347.897196) (xy 48.938907 -347.897719) (xy 49.020782 -347.905305)
			(xy 49.101608 -347.920413) (xy 49.180695 -347.942914) (xy 49.257369 -347.972616) (xy 49.330975 -348.009266)
			(xy 49.400886 -348.05255) (xy 49.466504 -348.102101) (xy 49.527271 -348.157495) (xy 49.582668 -348.218259)
			(xy 49.632222 -348.283875) (xy 49.675511 -348.353783) (xy 49.712165 -348.427387) (xy 49.741871 -348.504059)
			(xy 49.764376 -348.583145) (xy 49.779489 -348.66397) (xy 49.78371 -348.7095) (xy 53.352901 -348.7095)
			(xy 53.356892 -348.625716) (xy 53.36883 -348.54269) (xy 53.388606 -348.461175) (xy 53.41604 -348.381909)
			(xy 53.450886 -348.30561) (xy 53.492827 -348.232969) (xy 53.541483 -348.164644) (xy 53.596413 -348.101253)
			(xy 53.65712 -348.043371) (xy 53.723055 -347.991522) (xy 53.79362 -347.946175) (xy 53.868176 -347.907741)
			(xy 53.946048 -347.876568) (xy 54.02653 -347.852939) (xy 54.108894 -347.837068) (xy 54.192394 -347.829098)
			(xy 54.234334 -347.828616) (xy 54.271523 -347.829023) (xy 54.345636 -347.835307) (xy 54.418956 -347.847812)
			(xy 54.490962 -347.866448) (xy 54.52618 -347.8784) (xy 54.534377 -347.880914) (xy 54.551511 -347.880914)
			(xy 54.559708 -347.8784) (xy 54.594654 -347.86653) (xy 54.66609 -347.847969) (xy 54.738831 -347.835458)
			(xy 54.812365 -347.829087) (xy 54.849268 -347.828616) (xy 54.85384 -347.82887) (xy 54.854348 -347.82887)
			(xy 54.863907 -347.782599) (xy 54.89152 -347.692237) (xy 54.909466 -347.64853) (xy 54.912939 -347.63891)
			(xy 54.912815 -347.618477) (xy 54.909212 -347.608906) (xy 54.892173 -347.5675) (xy 54.865541 -347.482011)
			(xy 54.847637 -347.394278) (xy 54.838644 -347.305189) (xy 54.838092 -347.260418) (xy 54.838596 -347.218057)
			(xy 54.846649 -347.13372) (xy 54.862683 -347.05053) (xy 54.886551 -346.96924) (xy 54.918039 -346.890588)
			(xy 54.956861 -346.815285) (xy 55.002664 -346.744013) (xy 55.055035 -346.677417) (xy 55.1135 -346.616102)
			(xy 55.177528 -346.560621) (xy 55.24654 -346.511478) (xy 55.31991 -346.469118) (xy 55.396975 -346.433923)
			(xy 55.477037 -346.406214) (xy 55.55937 -346.38624) (xy 55.643229 -346.374183) (xy 55.727854 -346.370152)
			(xy 55.812479 -346.374183) (xy 55.896338 -346.38624) (xy 55.978671 -346.406214) (xy 56.058733 -346.433923)
			(xy 56.135798 -346.469118) (xy 56.209168 -346.511478) (xy 56.27818 -346.560621) (xy 56.342208 -346.616102)
			(xy 56.400673 -346.677417) (xy 56.453044 -346.744013) (xy 56.498847 -346.815285) (xy 56.537669 -346.890588)
			(xy 56.569157 -346.96924) (xy 56.593025 -347.05053) (xy 56.609059 -347.13372) (xy 56.617112 -347.218057)
			(xy 56.617616 -347.260418) (xy 56.617044 -347.305187) (xy 56.608037 -347.394272) (xy 56.590134 -347.482003)
			(xy 56.563518 -347.567495) (xy 56.546496 -347.608906) (xy 56.542919 -347.618493) (xy 56.542926 -347.63894)
			(xy 56.546496 -347.64853) (xy 56.561684 -347.685398) (xy 56.586189 -347.761282) (xy 56.603812 -347.839053)
			(xy 56.614411 -347.918088) (xy 56.6166 -347.957902) (xy 56.617108 -347.971364) (xy 56.63184 -347.994224)
			(xy 56.734456 -348.047564) (xy 56.761634 -348.04604) (xy 56.773064 -348.038674) (xy 56.808981 -348.016152)
			(xy 56.88432 -347.977266) (xy 56.963017 -347.945725) (xy 57.044358 -347.921816) (xy 57.127605 -347.905754)
			(xy 57.212003 -347.897686) (xy 57.254394 -347.897196) (xy 57.295507 -347.897719) (xy 57.377382 -347.905305)
			(xy 57.458208 -347.920413) (xy 57.537295 -347.942914) (xy 57.613969 -347.972616) (xy 57.687575 -348.009266)
			(xy 57.757486 -348.05255) (xy 57.823104 -348.102101) (xy 57.883871 -348.157495) (xy 57.939268 -348.218259)
			(xy 57.988822 -348.283875) (xy 58.032111 -348.353783) (xy 58.068765 -348.427387) (xy 58.098471 -348.504059)
			(xy 58.120976 -348.583145) (xy 58.136089 -348.66397) (xy 58.14031 -348.7095) (xy 61.684101 -348.7095)
			(xy 61.688092 -348.625716) (xy 61.70003 -348.54269) (xy 61.719806 -348.461175) (xy 61.74724 -348.381909)
			(xy 61.782086 -348.30561) (xy 61.824027 -348.232969) (xy 61.872683 -348.164644) (xy 61.927613 -348.101253)
			(xy 61.98832 -348.043371) (xy 62.054255 -347.991522) (xy 62.12482 -347.946175) (xy 62.199376 -347.907741)
			(xy 62.277248 -347.876568) (xy 62.35773 -347.852939) (xy 62.440094 -347.837068) (xy 62.523594 -347.829098)
			(xy 62.565534 -347.828616) (xy 62.602723 -347.829023) (xy 62.676836 -347.835307) (xy 62.750156 -347.847812)
			(xy 62.822162 -347.866448) (xy 62.85738 -347.8784) (xy 62.865577 -347.880914) (xy 62.882711 -347.880914)
			(xy 62.890908 -347.8784) (xy 62.926096 -347.866455) (xy 62.998036 -347.847809) (xy 63.071292 -347.835299)
			(xy 63.145342 -347.829013) (xy 63.1825 -347.828616) (xy 63.183008 -347.828616) (xy 63.206122 -347.829124)
			(xy 63.215205 -347.793715) (xy 63.238479 -347.724411) (xy 63.252604 -347.690694) (xy 63.256229 -347.680981)
			(xy 63.25624 -347.66027) (xy 63.252604 -347.650562) (xy 63.235485 -347.609307) (xy 63.208697 -347.524095)
			(xy 63.190664 -347.436611) (xy 63.181571 -347.347751) (xy 63.180976 -347.30309) (xy 63.180976 -347.302328)
			(xy 63.181475 -347.260403) (xy 63.189445 -347.176932) (xy 63.205314 -347.094597) (xy 63.228937 -347.014143)
			(xy 63.260101 -346.936299) (xy 63.298524 -346.861769) (xy 63.343857 -346.79123) (xy 63.39569 -346.725319)
			(xy 63.453553 -346.664633) (xy 63.516923 -346.609723) (xy 63.585226 -346.561085) (xy 63.657843 -346.51916)
			(xy 63.734116 -346.484327) (xy 63.813355 -346.456902) (xy 63.894841 -346.437133) (xy 63.977838 -346.4252)
			(xy 64.061594 -346.421211) (xy 64.14535 -346.4252) (xy 64.228347 -346.437133) (xy 64.309833 -346.456902)
			(xy 64.389072 -346.484327) (xy 64.465345 -346.51916) (xy 64.537962 -346.561085) (xy 64.606265 -346.609723)
			(xy 64.669635 -346.664633) (xy 64.727498 -346.725319) (xy 64.779331 -346.79123) (xy 64.824664 -346.861769)
			(xy 64.863087 -346.936299) (xy 64.894251 -347.014143) (xy 64.917874 -347.094597) (xy 64.933743 -347.176932)
			(xy 64.941713 -347.260403) (xy 64.942212 -347.302328) (xy 64.942212 -347.30309) (xy 64.941639 -347.347753)
			(xy 64.932567 -347.436619) (xy 64.914535 -347.524107) (xy 64.88773 -347.609317) (xy 64.870584 -347.650562)
			(xy 64.866927 -347.660266) (xy 64.866937 -347.680985) (xy 64.870584 -347.690694) (xy 64.888862 -347.734789)
			(xy 64.91689 -347.826038) (xy 64.934892 -347.919782) (xy 64.939418 -347.9673) (xy 64.940434 -347.980508)
			(xy 64.955674 -348.00286) (xy 65.046352 -348.047056) (xy 65.054393 -348.050544) (xy 65.071798 -348.052482)
			(xy 65.088843 -348.048463) (xy 65.09639 -348.044008) (xy 65.096644 -348.043754) (xy 65.132959 -348.020439)
			(xy 65.209305 -347.980191) (xy 65.289189 -347.947525) (xy 65.371861 -347.922748) (xy 65.456544 -347.906093)
			(xy 65.542442 -347.897716) (xy 65.585594 -347.897196) (xy 65.626707 -347.897719) (xy 65.708582 -347.905305)
			(xy 65.789408 -347.920413) (xy 65.868495 -347.942914) (xy 65.945169 -347.972616) (xy 66.018775 -348.009266)
			(xy 66.088686 -348.05255) (xy 66.154304 -348.102101) (xy 66.215071 -348.157495) (xy 66.270468 -348.218259)
			(xy 66.320022 -348.283875) (xy 66.363311 -348.353783) (xy 66.399965 -348.427387) (xy 66.429671 -348.504059)
			(xy 66.452176 -348.583145) (xy 66.467289 -348.66397) (xy 66.474879 -348.745845) (xy 66.475356 -348.786958)
			(xy 66.474795 -348.831728) (xy 66.467942 -348.89948) (xy 81.294224 -348.89948) (xy 81.294687 -348.858913)
			(xy 81.30208 -348.778118) (xy 81.316804 -348.698332) (xy 81.338734 -348.620219) (xy 81.36769 -348.544429)
			(xy 81.385156 -348.507812) (xy 81.389058 -348.498717) (xy 81.390365 -348.478988) (xy 81.387696 -348.469458)
			(xy 81.373498 -348.424437) (xy 81.353605 -348.332151) (xy 81.343609 -348.238277) (xy 81.342992 -348.191074)
			(xy 81.343496 -348.148713) (xy 81.351549 -348.064376) (xy 81.367583 -347.981186) (xy 81.391451 -347.899896)
			(xy 81.422939 -347.821244) (xy 81.461761 -347.745941) (xy 81.507564 -347.674669) (xy 81.559935 -347.608073)
			(xy 81.6184 -347.546758) (xy 81.682428 -347.491277) (xy 81.75144 -347.442134) (xy 81.82481 -347.399774)
			(xy 81.901875 -347.364579) (xy 81.981937 -347.33687) (xy 82.06427 -347.316896) (xy 82.148129 -347.304839)
			(xy 82.232754 -347.300808) (xy 82.317379 -347.304839) (xy 82.401238 -347.316896) (xy 82.483571 -347.33687)
			(xy 82.563633 -347.364579) (xy 82.640698 -347.399774) (xy 82.714068 -347.442134) (xy 82.78308 -347.491277)
			(xy 82.847108 -347.546758) (xy 82.905573 -347.608073) (xy 82.957944 -347.674669) (xy 83.003747 -347.745941)
			(xy 83.042569 -347.821244) (xy 83.074057 -347.899896) (xy 83.097925 -347.981186) (xy 83.113959 -348.064376)
			(xy 83.122012 -348.148713) (xy 83.122516 -348.191074) (xy 83.12207 -348.231641) (xy 83.114672 -348.312437)
			(xy 83.099945 -348.392223) (xy 83.07801 -348.470336) (xy 83.049051 -348.546125) (xy 83.031584 -348.582742)
			(xy 83.027707 -348.591846) (xy 83.026383 -348.611567) (xy 83.029044 -348.621096) (xy 83.043232 -348.66612)
			(xy 83.063129 -348.758404) (xy 83.073129 -348.852278) (xy 83.073245 -348.861126) (xy 83.956144 -348.861126)
			(xy 83.956552 -348.820564) (xy 83.963891 -348.739773) (xy 83.978566 -348.659987) (xy 84.000454 -348.581872)
			(xy 84.029373 -348.506078) (xy 84.046822 -348.469458) (xy 84.05073 -348.460437) (xy 84.052174 -348.440849)
			(xy 84.049616 -348.431358) (xy 84.035467 -348.386455) (xy 84.015597 -348.294425) (xy 84.005567 -348.200811)
			(xy 84.004912 -348.153736) (xy 84.004912 -348.15272) (xy 84.005416 -348.110372) (xy 84.013467 -348.026058)
			(xy 84.029496 -347.942892) (xy 84.053357 -347.861625) (xy 84.084836 -347.782995) (xy 84.123647 -347.707714)
			(xy 84.169437 -347.636462) (xy 84.221793 -347.569886) (xy 84.280241 -347.508588) (xy 84.344251 -347.453123)
			(xy 84.413243 -347.403994) (xy 84.486593 -347.361645) (xy 84.563636 -347.326461) (xy 84.643675 -347.298759)
			(xy 84.725984 -347.278791) (xy 84.809819 -347.266738) (xy 84.89442 -347.262708) (xy 84.979021 -347.266738)
			(xy 85.062856 -347.278791) (xy 85.145165 -347.298759) (xy 85.225204 -347.326461) (xy 85.302247 -347.361645)
			(xy 85.375597 -347.403994) (xy 85.444589 -347.453123) (xy 85.508599 -347.508588) (xy 85.567047 -347.569886)
			(xy 85.619403 -347.636462) (xy 85.665193 -347.707714) (xy 85.704004 -347.782995) (xy 85.735483 -347.861625)
			(xy 85.759344 -347.942892) (xy 85.775373 -348.026058) (xy 85.783424 -348.110372) (xy 85.783928 -348.15272)
			(xy 85.783928 -348.153228) (xy 85.783471 -348.193738) (xy 85.77611 -348.274424) (xy 85.761432 -348.354104)
			(xy 85.73956 -348.432117) (xy 85.710675 -348.507814) (xy 85.69325 -348.544388) (xy 85.689318 -348.553401)
			(xy 85.687887 -348.572996) (xy 85.690456 -348.582488) (xy 85.70466 -348.627551) (xy 85.721282 -348.7047)
			(xy 275.231844 -348.7047) (xy 275.235834 -348.620942) (xy 275.247768 -348.537942) (xy 275.267537 -348.456452)
			(xy 275.294962 -348.377211) (xy 275.329796 -348.300935) (xy 275.371722 -348.228316) (xy 275.420361 -348.16001)
			(xy 275.475273 -348.096638) (xy 275.53596 -348.038772) (xy 275.601873 -347.986937) (xy 275.672414 -347.941602)
			(xy 275.746946 -347.903177) (xy 275.824792 -347.872011) (xy 275.905248 -347.848386) (xy 275.987586 -347.832515)
			(xy 276.071059 -347.824543) (xy 276.112986 -347.824044) (xy 276.114002 -347.824044) (xy 276.151059 -347.824452)
			(xy 276.224908 -347.830716) (xy 276.29797 -347.843157) (xy 276.36973 -347.861689) (xy 276.404832 -347.873574)
			(xy 276.413029 -347.876088) (xy 276.430163 -347.876088) (xy 276.43836 -347.873574) (xy 276.478966 -347.8599)
			(xy 276.562216 -347.839604) (xy 276.647042 -347.827484) (xy 276.68982 -347.82506) (xy 276.700434 -347.823969)
			(xy 276.719453 -347.814348) (xy 276.732947 -347.797851) (xy 276.736302 -347.787722) (xy 276.744404 -347.759433)
			(xy 276.763852 -347.703889) (xy 276.775164 -347.676724) (xy 276.778721 -347.667131) (xy 276.778725 -347.646691)
			(xy 276.775164 -347.6371) (xy 276.758127 -347.595694) (xy 276.731493 -347.510205) (xy 276.713589 -347.422472)
			(xy 276.704596 -347.333383) (xy 276.704044 -347.288612) (xy 276.704548 -347.246251) (xy 276.712601 -347.161914)
			(xy 276.728635 -347.078724) (xy 276.752503 -346.997434) (xy 276.783991 -346.918782) (xy 276.822813 -346.843479)
			(xy 276.868616 -346.772207) (xy 276.920987 -346.705611) (xy 276.979452 -346.644296) (xy 277.04348 -346.588815)
			(xy 277.112492 -346.539672) (xy 277.185862 -346.497312) (xy 277.262927 -346.462117) (xy 277.342989 -346.434408)
			(xy 277.425322 -346.414434) (xy 277.509181 -346.402377) (xy 277.593806 -346.398346) (xy 277.678431 -346.402377)
			(xy 277.76229 -346.414434) (xy 277.844623 -346.434408) (xy 277.924685 -346.462117) (xy 278.00175 -346.497312)
			(xy 278.07512 -346.539672) (xy 278.144132 -346.588815) (xy 278.20816 -346.644296) (xy 278.266625 -346.705611)
			(xy 278.318996 -346.772207) (xy 278.364799 -346.843479) (xy 278.403621 -346.918782) (xy 278.435109 -346.997434)
			(xy 278.458977 -347.078724) (xy 278.475011 -347.161914) (xy 278.483064 -347.246251) (xy 278.483568 -347.288612)
			(xy 278.482998 -347.333381) (xy 278.47399 -347.422466) (xy 278.456088 -347.510198) (xy 278.42947 -347.595689)
			(xy 278.412448 -347.6371) (xy 278.408812 -347.646665) (xy 278.408686 -347.667111) (xy 278.412194 -347.676724)
			(xy 278.426408 -347.711074) (xy 278.449728 -347.781668) (xy 278.467082 -347.85396) (xy 278.478348 -347.927447)
			(xy 278.481282 -347.964506) (xy 278.482267 -347.973327) (xy 278.489457 -347.989544) (xy 278.501708 -348.002373)
			(xy 278.509476 -348.00667) (xy 278.600662 -348.051628) (xy 278.62784 -348.049596) (xy 278.639016 -348.04223)
			(xy 278.675581 -348.018458) (xy 278.752524 -347.977387) (xy 278.833117 -347.944041) (xy 278.916586 -347.91874)
			(xy 279.00213 -347.901729) (xy 279.088929 -347.893169) (xy 279.132538 -347.892624) (xy 279.133046 -347.892624)
			(xy 279.174153 -347.893069) (xy 279.256016 -347.900657) (xy 279.336831 -347.915765) (xy 279.415907 -347.938263)
			(xy 279.49257 -347.96796) (xy 279.566167 -348.004602) (xy 279.63607 -348.047877) (xy 279.701683 -348.097416)
			(xy 279.762447 -348.152796) (xy 279.817842 -348.213546) (xy 279.867398 -348.279147) (xy 279.91069 -348.349039)
			(xy 279.947351 -348.422627) (xy 279.977067 -348.499283) (xy 279.999585 -348.578353) (xy 280.014712 -348.659164)
			(xy 280.018945 -348.7047) (xy 283.512244 -348.7047) (xy 283.516234 -348.620942) (xy 283.528168 -348.537942)
			(xy 283.547937 -348.456452) (xy 283.575362 -348.377211) (xy 283.610196 -348.300935) (xy 283.652122 -348.228316)
			(xy 283.700761 -348.16001) (xy 283.755673 -348.096638) (xy 283.81636 -348.038772) (xy 283.882273 -347.986937)
			(xy 283.952814 -347.941602) (xy 284.027346 -347.903177) (xy 284.105192 -347.872011) (xy 284.185648 -347.848386)
			(xy 284.267986 -347.832515) (xy 284.351459 -347.824543) (xy 284.393386 -347.824044) (xy 284.394402 -347.824044)
			(xy 284.431459 -347.824452) (xy 284.505308 -347.830716) (xy 284.57837 -347.843157) (xy 284.65013 -347.861689)
			(xy 284.685232 -347.873574) (xy 284.693429 -347.876088) (xy 284.710563 -347.876088) (xy 284.71876 -347.873574)
			(xy 284.756938 -347.860634) (xy 284.835124 -347.840982) (xy 284.91478 -347.828562) (xy 284.95498 -347.825568)
			(xy 284.965838 -347.82436) (xy 284.985096 -347.814096) (xy 284.99831 -347.79673) (xy 285.001208 -347.786198)
			(xy 285.010486 -347.747118) (xy 285.035162 -347.670674) (xy 285.050484 -347.633544) (xy 285.054028 -347.623948)
			(xy 285.05404 -347.603511) (xy 285.050484 -347.59392) (xy 285.033454 -347.552511) (xy 285.006819 -347.467023)
			(xy 284.988912 -347.379291) (xy 284.979917 -347.290203) (xy 284.979364 -347.245432) (xy 284.979868 -347.203071)
			(xy 284.987921 -347.118734) (xy 285.003955 -347.035544) (xy 285.027823 -346.954254) (xy 285.059311 -346.875602)
			(xy 285.098133 -346.800299) (xy 285.143936 -346.729027) (xy 285.196307 -346.662431) (xy 285.254772 -346.601116)
			(xy 285.3188 -346.545635) (xy 285.387812 -346.496492) (xy 285.461182 -346.454132) (xy 285.538247 -346.418937)
			(xy 285.618309 -346.391228) (xy 285.700642 -346.371254) (xy 285.784501 -346.359197) (xy 285.869126 -346.355166)
			(xy 285.953751 -346.359197) (xy 286.03761 -346.371254) (xy 286.119943 -346.391228) (xy 286.200005 -346.418937)
			(xy 286.27707 -346.454132) (xy 286.35044 -346.496492) (xy 286.419452 -346.545635) (xy 286.48348 -346.601116)
			(xy 286.541945 -346.662431) (xy 286.594316 -346.729027) (xy 286.640119 -346.800299) (xy 286.678941 -346.875602)
			(xy 286.710429 -346.954254) (xy 286.734297 -347.035544) (xy 286.750331 -347.118734) (xy 286.758384 -347.203071)
			(xy 286.758888 -347.245432) (xy 286.758323 -347.290202) (xy 286.749314 -347.379287) (xy 286.73141 -347.467018)
			(xy 286.704791 -347.552509) (xy 286.687768 -347.59392) (xy 286.684185 -347.603505) (xy 286.684197 -347.623953)
			(xy 286.687768 -347.633544) (xy 286.703871 -347.672618) (xy 286.72945 -347.753174) (xy 286.747275 -347.835792)
			(xy 286.757183 -347.919728) (xy 286.758634 -347.961966) (xy 286.758888 -347.975936) (xy 286.77362 -347.999558)
			(xy 286.86506 -348.047056) (xy 286.873276 -348.050887) (xy 286.891249 -348.053129) (xy 286.908879 -348.048973)
			(xy 286.916622 -348.044262) (xy 286.916876 -348.044008) (xy 286.95358 -348.019938) (xy 287.030887 -347.978361)
			(xy 287.111915 -347.944605) (xy 287.195876 -347.918998) (xy 287.281951 -347.901791) (xy 287.369303 -347.893149)
			(xy 287.413192 -347.892624) (xy 287.413446 -347.892624) (xy 287.454553 -347.893069) (xy 287.536416 -347.900657)
			(xy 287.617231 -347.915765) (xy 287.696307 -347.938263) (xy 287.77297 -347.96796) (xy 287.846567 -348.004602)
			(xy 287.91647 -348.047877) (xy 287.982083 -348.097416) (xy 288.042847 -348.152796) (xy 288.098242 -348.213546)
			(xy 288.147798 -348.279147) (xy 288.19109 -348.349039) (xy 288.227751 -348.422627) (xy 288.257467 -348.499283)
			(xy 288.279985 -348.578353) (xy 288.295112 -348.659164) (xy 288.299345 -348.7047) (xy 291.818044 -348.7047)
			(xy 291.822034 -348.620942) (xy 291.833968 -348.537942) (xy 291.853737 -348.456452) (xy 291.881162 -348.377211)
			(xy 291.915996 -348.300935) (xy 291.957922 -348.228316) (xy 292.006561 -348.16001) (xy 292.061473 -348.096638)
			(xy 292.12216 -348.038772) (xy 292.188073 -347.986937) (xy 292.258614 -347.941602) (xy 292.333146 -347.903177)
			(xy 292.410992 -347.872011) (xy 292.491448 -347.848386) (xy 292.573786 -347.832515) (xy 292.657259 -347.824543)
			(xy 292.699186 -347.824044) (xy 292.700202 -347.824044) (xy 292.737259 -347.824452) (xy 292.811108 -347.830716)
			(xy 292.88417 -347.843157) (xy 292.95593 -347.861689) (xy 292.991032 -347.873574) (xy 292.999229 -347.876088)
			(xy 293.016363 -347.876088) (xy 293.02456 -347.873574) (xy 293.057737 -347.862322) (xy 293.125493 -347.844496)
			(xy 293.194454 -347.832123) (xy 293.229284 -347.828362) (xy 293.240044 -347.82673) (xy 293.258819 -347.815766)
			(xy 293.271409 -347.798041) (xy 293.273988 -347.787468) (xy 293.28351 -347.742121) (xy 293.310744 -347.653548)
			(xy 293.328344 -347.610684) (xy 293.331924 -347.601098) (xy 293.331914 -347.580651) (xy 293.328344 -347.57106)
			(xy 293.311293 -347.529659) (xy 293.284663 -347.444168) (xy 293.266763 -347.356433) (xy 293.257774 -347.267343)
			(xy 293.257224 -347.222572) (xy 293.257728 -347.180211) (xy 293.265781 -347.095874) (xy 293.281815 -347.012684)
			(xy 293.305683 -346.931394) (xy 293.337171 -346.852742) (xy 293.375993 -346.777439) (xy 293.421796 -346.706167)
			(xy 293.474167 -346.639571) (xy 293.532632 -346.578256) (xy 293.59666 -346.522775) (xy 293.665672 -346.473632)
			(xy 293.739042 -346.431272) (xy 293.816107 -346.396077) (xy 293.896169 -346.368368) (xy 293.978502 -346.348394)
			(xy 294.062361 -346.336337) (xy 294.146986 -346.332306) (xy 294.231611 -346.336337) (xy 294.31547 -346.348394)
			(xy 294.397803 -346.368368) (xy 294.477865 -346.396077) (xy 294.55493 -346.431272) (xy 294.6283 -346.473632)
			(xy 294.697312 -346.522775) (xy 294.76134 -346.578256) (xy 294.819805 -346.639571) (xy 294.872176 -346.706167)
			(xy 294.917979 -346.777439) (xy 294.956801 -346.852742) (xy 294.988289 -346.931394) (xy 295.012157 -347.012684)
			(xy 295.028191 -347.095874) (xy 295.036244 -347.180211) (xy 295.036748 -347.222572) (xy 295.036192 -347.267342)
			(xy 295.027179 -347.356427) (xy 295.009272 -347.444158) (xy 294.982652 -347.529649) (xy 294.965628 -347.57106)
			(xy 294.962081 -347.580656) (xy 294.96207 -347.601093) (xy 294.965628 -347.610684) (xy 294.982659 -347.652092)
			(xy 295.009295 -347.73758) (xy 295.0272 -347.825313) (xy 295.036195 -347.914401) (xy 295.036748 -347.959172)
			(xy 295.036494 -347.977206) (xy 295.03624 -347.991684) (xy 295.050718 -348.016576) (xy 295.157144 -348.071948)
			(xy 295.185846 -348.069916) (xy 295.19753 -348.061534) (xy 295.230035 -348.038582) (xy 295.298406 -347.997866)
			(xy 295.370142 -347.963421) (xy 295.444669 -347.935524) (xy 295.521391 -347.914398) (xy 295.599693 -347.900211)
			(xy 295.67895 -347.893078) (xy 295.718738 -347.892624) (xy 295.719246 -347.892624) (xy 295.760353 -347.893069)
			(xy 295.842216 -347.900657) (xy 295.923031 -347.915765) (xy 296.002107 -347.938263) (xy 296.07877 -347.96796)
			(xy 296.152367 -348.004602) (xy 296.22227 -348.047877) (xy 296.287883 -348.097416) (xy 296.348647 -348.152796)
			(xy 296.404042 -348.213546) (xy 296.453598 -348.279147) (xy 296.49689 -348.349039) (xy 296.533551 -348.422627)
			(xy 296.563267 -348.499283) (xy 296.585785 -348.578353) (xy 296.600912 -348.659164) (xy 296.605145 -348.7047)
			(xy 300.174644 -348.7047) (xy 300.178634 -348.620942) (xy 300.190568 -348.537942) (xy 300.210337 -348.456452)
			(xy 300.237762 -348.377211) (xy 300.272596 -348.300935) (xy 300.314522 -348.228316) (xy 300.363161 -348.16001)
			(xy 300.418073 -348.096638) (xy 300.47876 -348.038772) (xy 300.544673 -347.986937) (xy 300.615214 -347.941602)
			(xy 300.689746 -347.903177) (xy 300.767592 -347.872011) (xy 300.848048 -347.848386) (xy 300.930386 -347.832515)
			(xy 301.013859 -347.824543) (xy 301.055786 -347.824044) (xy 301.056802 -347.824044) (xy 301.093859 -347.824452)
			(xy 301.167708 -347.830716) (xy 301.24077 -347.843157) (xy 301.31253 -347.861689) (xy 301.347632 -347.873574)
			(xy 301.355829 -347.876088) (xy 301.372963 -347.876088) (xy 301.38116 -347.873574) (xy 301.419296 -347.860641)
			(xy 301.497398 -347.840993) (xy 301.576968 -347.828568) (xy 301.617126 -347.825568) (xy 301.627844 -347.824451)
			(xy 301.646914 -347.814446) (xy 301.660249 -347.797535) (xy 301.663354 -347.787214) (xy 301.672203 -347.75314)
			(xy 301.694583 -347.686387) (xy 301.708058 -347.653864) (xy 301.711569 -347.644255) (xy 301.711421 -347.623811)
			(xy 301.707804 -347.61424) (xy 301.690776 -347.57283) (xy 301.66414 -347.487343) (xy 301.646234 -347.39961)
			(xy 301.637237 -347.310523) (xy 301.636684 -347.265752) (xy 301.637188 -347.223391) (xy 301.645241 -347.139054)
			(xy 301.661275 -347.055864) (xy 301.685143 -346.974574) (xy 301.716631 -346.895922) (xy 301.755453 -346.820619)
			(xy 301.801256 -346.749347) (xy 301.853627 -346.682751) (xy 301.912092 -346.621436) (xy 301.97612 -346.565955)
			(xy 302.045132 -346.516812) (xy 302.118502 -346.474452) (xy 302.195567 -346.439257) (xy 302.275629 -346.411548)
			(xy 302.357962 -346.391574) (xy 302.441821 -346.379517) (xy 302.526446 -346.375486) (xy 302.611071 -346.379517)
			(xy 302.69493 -346.391574) (xy 302.777263 -346.411548) (xy 302.857325 -346.439257) (xy 302.93439 -346.474452)
			(xy 303.00776 -346.516812) (xy 303.076772 -346.565955) (xy 303.1408 -346.621436) (xy 303.199265 -346.682751)
			(xy 303.251636 -346.749347) (xy 303.297439 -346.820619) (xy 303.336261 -346.895922) (xy 303.367749 -346.974574)
			(xy 303.391617 -347.055864) (xy 303.407651 -347.139054) (xy 303.415704 -347.223391) (xy 303.416208 -347.265752)
			(xy 303.415649 -347.310522) (xy 303.406637 -347.399607) (xy 303.388731 -347.487338) (xy 303.362111 -347.572829)
			(xy 303.345088 -347.61424) (xy 303.341549 -347.623838) (xy 303.341532 -347.644274) (xy 303.345088 -347.653864)
			(xy 303.36051 -347.691224) (xy 303.385289 -347.768163) (xy 303.402976 -347.847034) (xy 303.413426 -347.927187)
			(xy 303.415446 -347.967554) (xy 303.415954 -347.981524) (xy 303.430686 -348.004638) (xy 303.535334 -348.057216)
			(xy 303.562766 -348.055184) (xy 303.574196 -348.04731) (xy 303.611146 -348.022772) (xy 303.689046 -347.980345)
			(xy 303.770779 -347.945874) (xy 303.855535 -347.919702) (xy 303.942473 -347.902087) (xy 304.030732 -347.893205)
			(xy 304.075084 -347.892624) (xy 304.075846 -347.892624) (xy 304.116953 -347.893069) (xy 304.198816 -347.900657)
			(xy 304.279631 -347.915765) (xy 304.358707 -347.938263) (xy 304.43537 -347.96796) (xy 304.508967 -348.004602)
			(xy 304.57887 -348.047877) (xy 304.644483 -348.097416) (xy 304.705247 -348.152796) (xy 304.760642 -348.213546)
			(xy 304.810198 -348.279147) (xy 304.85349 -348.349039) (xy 304.890151 -348.422627) (xy 304.919867 -348.499283)
			(xy 304.942385 -348.578353) (xy 304.957512 -348.659164) (xy 304.961745 -348.7047) (xy 308.505844 -348.7047)
			(xy 308.509834 -348.620942) (xy 308.521768 -348.537942) (xy 308.541537 -348.456452) (xy 308.568962 -348.377211)
			(xy 308.603796 -348.300935) (xy 308.645722 -348.228316) (xy 308.694361 -348.16001) (xy 308.749273 -348.096638)
			(xy 308.80996 -348.038772) (xy 308.875873 -347.986937) (xy 308.946414 -347.941602) (xy 309.020946 -347.903177)
			(xy 309.098792 -347.872011) (xy 309.179248 -347.848386) (xy 309.261586 -347.832515) (xy 309.345059 -347.824543)
			(xy 309.386986 -347.824044) (xy 309.388002 -347.824044) (xy 309.425059 -347.824452) (xy 309.498908 -347.830716)
			(xy 309.57197 -347.843157) (xy 309.64373 -347.861689) (xy 309.678832 -347.873574) (xy 309.687029 -347.876088)
			(xy 309.704163 -347.876088) (xy 309.71236 -347.873574) (xy 309.752087 -347.860214) (xy 309.833476 -347.84017)
			(xy 309.916402 -347.827952) (xy 309.958232 -347.825314) (xy 309.969008 -347.824123) (xy 309.988202 -347.814097)
			(xy 310.001607 -347.79709) (xy 310.004714 -347.786706) (xy 310.013576 -347.75276) (xy 310.035956 -347.686262)
			(xy 310.049418 -347.653864) (xy 310.052931 -347.644255) (xy 310.052783 -347.623811) (xy 310.049164 -347.61424)
			(xy 310.03214 -347.572829) (xy 310.005503 -347.487342) (xy 309.987595 -347.39961) (xy 309.978598 -347.310522)
			(xy 309.978044 -347.265752) (xy 309.978548 -347.223391) (xy 309.986601 -347.139054) (xy 310.002635 -347.055864)
			(xy 310.026503 -346.974574) (xy 310.057991 -346.895922) (xy 310.096813 -346.820619) (xy 310.142616 -346.749347)
			(xy 310.194987 -346.682751) (xy 310.253452 -346.621436) (xy 310.31748 -346.565955) (xy 310.386492 -346.516812)
			(xy 310.459862 -346.474452) (xy 310.536927 -346.439257) (xy 310.616989 -346.411548) (xy 310.699322 -346.391574)
			(xy 310.783181 -346.379517) (xy 310.867806 -346.375486) (xy 310.952431 -346.379517) (xy 311.03629 -346.391574)
			(xy 311.118623 -346.411548) (xy 311.198685 -346.439257) (xy 311.27575 -346.474452) (xy 311.34912 -346.516812)
			(xy 311.418132 -346.565955) (xy 311.48216 -346.621436) (xy 311.540625 -346.682751) (xy 311.592996 -346.749347)
			(xy 311.638799 -346.820619) (xy 311.677621 -346.895922) (xy 311.709109 -346.974574) (xy 311.732977 -347.055864)
			(xy 311.749011 -347.139054) (xy 311.757064 -347.223391) (xy 311.757568 -347.265752) (xy 311.757012 -347.310522)
			(xy 311.748 -347.399607) (xy 311.730093 -347.487338) (xy 311.703472 -347.572829) (xy 311.686448 -347.61424)
			(xy 311.682911 -347.623839) (xy 311.682894 -347.644274) (xy 311.686448 -347.653864) (xy 311.701578 -347.690518)
			(xy 311.725997 -347.765967) (xy 311.743615 -347.843288) (xy 311.754293 -347.921869) (xy 311.756552 -347.961458)
			(xy 311.757251 -347.970429) (xy 311.764179 -347.987026) (xy 311.776392 -348.000229) (xy 311.784238 -348.004638)
			(xy 311.875678 -348.050866) (xy 311.902856 -348.049088) (xy 311.914286 -348.041468) (xy 311.950798 -348.017804)
			(xy 312.027605 -347.976914) (xy 312.10804 -347.943725) (xy 312.191333 -347.918554) (xy 312.276687 -347.901641)
			(xy 312.363285 -347.893148) (xy 312.406792 -347.892624) (xy 312.407046 -347.892624) (xy 312.448153 -347.893069)
			(xy 312.530016 -347.900657) (xy 312.610831 -347.915765) (xy 312.689907 -347.938263) (xy 312.76657 -347.96796)
			(xy 312.840167 -348.004602) (xy 312.91007 -348.047877) (xy 312.975683 -348.097416) (xy 313.036447 -348.152796)
			(xy 313.091842 -348.213546) (xy 313.141398 -348.279147) (xy 313.18469 -348.349039) (xy 313.221351 -348.422627)
			(xy 313.251067 -348.499283) (xy 313.273585 -348.578353) (xy 313.288712 -348.659164) (xy 313.296321 -348.741025)
			(xy 313.296808 -348.782132) (xy 313.296242 -348.826902) (xy 313.287233 -348.915987) (xy 313.269329 -349.003718)
			(xy 313.242711 -349.089209) (xy 313.225688 -349.13062) (xy 313.222104 -349.140205) (xy 313.222115 -349.160653)
			(xy 313.225688 -349.170244) (xy 313.242711 -349.211656) (xy 313.269347 -349.297143) (xy 313.287256 -349.384874)
			(xy 313.291976 -349.43161) (xy 326.552821 -349.43161) (xy 326.556826 -349.325861) (xy 326.568816 -349.220718)
			(xy 326.588725 -349.116783) (xy 326.616436 -349.014651) (xy 326.651793 -348.914907) (xy 326.694591 -348.818123)
			(xy 326.744587 -348.724853) (xy 326.801494 -348.635632) (xy 326.864985 -348.550969) (xy 326.934697 -348.471351)
			(xy 327.010231 -348.397233) (xy 327.091154 -348.32904) (xy 327.177003 -348.267162) (xy 327.267286 -348.211955)
			(xy 327.361485 -348.163733) (xy 327.459062 -348.122773) (xy 327.559457 -348.089311) (xy 327.662095 -348.063537)
			(xy 327.766388 -348.045599) (xy 327.871739 -348.0356) (xy 327.977545 -348.033597) (xy 328.083199 -348.039602)
			(xy 328.188096 -348.053581) (xy 328.291636 -348.075452) (xy 328.393225 -348.105092) (xy 328.492282 -348.14233)
			(xy 328.588239 -348.186952) (xy 328.680546 -348.238704) (xy 328.768675 -348.297289) (xy 328.852121 -348.362371)
			(xy 328.930405 -348.433577) (xy 329.00308 -348.5105) (xy 329.06973 -348.5927) (xy 329.129972 -348.679704)
			(xy 329.183461 -348.771015) (xy 329.229892 -348.86611) (xy 329.268997 -348.964444) (xy 329.300554 -349.065455)
			(xy 329.324381 -349.168562) (xy 329.340342 -349.273176) (xy 329.348346 -349.378698) (xy 329.348846 -349.43161)
			(xy 334.012801 -349.43161) (xy 334.016806 -349.325861) (xy 334.028796 -349.220718) (xy 334.048705 -349.116783)
			(xy 334.076416 -349.014651) (xy 334.111773 -348.914907) (xy 334.154571 -348.818123) (xy 334.204567 -348.724853)
			(xy 334.261474 -348.635632) (xy 334.324965 -348.550969) (xy 334.394677 -348.471351) (xy 334.470211 -348.397233)
			(xy 334.551134 -348.32904) (xy 334.636983 -348.267162) (xy 334.727266 -348.211955) (xy 334.821465 -348.163733)
			(xy 334.919042 -348.122773) (xy 335.019437 -348.089311) (xy 335.122075 -348.063537) (xy 335.226368 -348.045599)
			(xy 335.331719 -348.0356) (xy 335.437525 -348.033597) (xy 335.543179 -348.039602) (xy 335.648076 -348.053581)
			(xy 335.751616 -348.075452) (xy 335.853205 -348.105092) (xy 335.952262 -348.14233) (xy 336.048219 -348.186952)
			(xy 336.140526 -348.238704) (xy 336.228655 -348.297289) (xy 336.312101 -348.362371) (xy 336.390385 -348.433577)
			(xy 336.46306 -348.5105) (xy 336.52971 -348.5927) (xy 336.589952 -348.679704) (xy 336.643441 -348.771015)
			(xy 336.689872 -348.86611) (xy 336.728977 -348.964444) (xy 336.760534 -349.065455) (xy 336.784361 -349.168562)
			(xy 336.800322 -349.273176) (xy 336.808326 -349.378698) (xy 336.808826 -349.43161) (xy 336.808326 -349.484522)
			(xy 336.800322 -349.590044) (xy 336.784361 -349.694658) (xy 336.760534 -349.797765) (xy 336.728977 -349.898776)
			(xy 336.689872 -349.99711) (xy 336.643441 -350.092205) (xy 336.589952 -350.183516) (xy 336.52971 -350.27052)
			(xy 336.46306 -350.35272) (xy 336.390385 -350.429643) (xy 336.312101 -350.500849) (xy 336.228655 -350.565931)
			(xy 336.140526 -350.624516) (xy 336.048219 -350.676268) (xy 335.952262 -350.72089) (xy 335.853205 -350.758128)
			(xy 335.751616 -350.787768) (xy 335.648076 -350.809639) (xy 335.543179 -350.823618) (xy 335.437525 -350.829623)
			(xy 335.331719 -350.82762) (xy 335.226368 -350.817621) (xy 335.122075 -350.799683) (xy 335.019437 -350.773909)
			(xy 334.919042 -350.740447) (xy 334.821465 -350.699487) (xy 334.727266 -350.651265) (xy 334.636983 -350.596058)
			(xy 334.551134 -350.53418) (xy 334.470211 -350.465987) (xy 334.394677 -350.391869) (xy 334.324965 -350.312251)
			(xy 334.261474 -350.227588) (xy 334.204567 -350.138367) (xy 334.154571 -350.045097) (xy 334.111773 -349.948313)
			(xy 334.076416 -349.848569) (xy 334.048705 -349.746437) (xy 334.028796 -349.642502) (xy 334.016806 -349.537359)
			(xy 334.012801 -349.43161) (xy 329.348846 -349.43161) (xy 329.348346 -349.484522) (xy 329.340342 -349.590044)
			(xy 329.324381 -349.694658) (xy 329.300554 -349.797765) (xy 329.268997 -349.898776) (xy 329.229892 -349.99711)
			(xy 329.183461 -350.092205) (xy 329.129972 -350.183516) (xy 329.06973 -350.27052) (xy 329.00308 -350.35272)
			(xy 328.930405 -350.429643) (xy 328.852121 -350.500849) (xy 328.768675 -350.565931) (xy 328.680546 -350.624516)
			(xy 328.588239 -350.676268) (xy 328.492282 -350.72089) (xy 328.393225 -350.758128) (xy 328.291636 -350.787768)
			(xy 328.188096 -350.809639) (xy 328.083199 -350.823618) (xy 327.977545 -350.829623) (xy 327.871739 -350.82762)
			(xy 327.766388 -350.817621) (xy 327.662095 -350.799683) (xy 327.559457 -350.773909) (xy 327.459062 -350.740447)
			(xy 327.361485 -350.699487) (xy 327.267286 -350.651265) (xy 327.177003 -350.596058) (xy 327.091154 -350.53418)
			(xy 327.010231 -350.465987) (xy 326.934697 -350.391869) (xy 326.864985 -350.312251) (xy 326.801494 -350.227588)
			(xy 326.744587 -350.138367) (xy 326.694591 -350.045097) (xy 326.651793 -349.948313) (xy 326.616436 -349.848569)
			(xy 326.588725 -349.746437) (xy 326.568816 -349.642502) (xy 326.556826 -349.537359) (xy 326.552821 -349.43161)
			(xy 313.291976 -349.43161) (xy 313.296254 -349.473962) (xy 313.296808 -349.518732) (xy 313.296242 -349.563502)
			(xy 313.287233 -349.652587) (xy 313.269329 -349.740318) (xy 313.242711 -349.825809) (xy 313.225688 -349.86722)
			(xy 313.222104 -349.876805) (xy 313.222115 -349.897253) (xy 313.225688 -349.906844) (xy 313.242711 -349.948256)
			(xy 313.269347 -350.033743) (xy 313.287256 -350.121474) (xy 313.296254 -350.210562) (xy 313.296808 -350.255332)
			(xy 313.296378 -350.296443) (xy 313.288787 -350.378314) (xy 313.273674 -350.459136) (xy 313.251166 -350.538217)
			(xy 313.221457 -350.614885) (xy 313.184799 -350.688483) (xy 313.141506 -350.758385) (xy 313.091947 -350.823993)
			(xy 313.036545 -350.884747) (xy 312.975772 -350.94013) (xy 312.910148 -350.989668) (xy 312.840233 -351.032938)
			(xy 312.766623 -351.069572) (xy 312.689946 -351.099257) (xy 312.610857 -351.121739) (xy 312.530031 -351.136827)
			(xy 312.448157 -351.144391) (xy 312.407046 -351.14484) (xy 312.365442 -351.14437) (xy 312.282594 -351.136637)
			(xy 312.200829 -351.121206) (xy 312.120862 -351.098211) (xy 312.043389 -351.067854) (xy 311.969088 -351.0304)
			(xy 311.93359 -351.008696) (xy 311.924458 -351.003521) (xy 311.903738 -351.00031) (xy 311.883461 -351.005649)
			(xy 311.874916 -351.011744) (xy 311.841266 -351.037664) (xy 311.769892 -351.083723) (xy 311.694453 -351.12277)
			(xy 311.615637 -351.15445) (xy 311.53416 -351.178473) (xy 311.450764 -351.194623) (xy 311.366208 -351.20275)
			(xy 311.323736 -351.20326) (xy 311.323482 -351.20326) (xy 311.282375 -351.202805) (xy 311.200511 -351.195219)
			(xy 311.119697 -351.180113) (xy 311.04062 -351.157617) (xy 310.963956 -351.127921) (xy 310.890359 -351.09128)
			(xy 310.820455 -351.048006) (xy 310.754841 -350.998468) (xy 310.694077 -350.943088) (xy 310.638682 -350.882339)
			(xy 310.589126 -350.816738) (xy 310.545833 -350.746846) (xy 310.509173 -350.673258) (xy 310.479458 -350.596602)
			(xy 310.456941 -350.517531) (xy 310.441814 -350.43672) (xy 310.434206 -350.354859) (xy 310.43372 -350.313752)
			(xy 310.434279 -350.268982) (xy 310.44329 -350.179897) (xy 310.461196 -350.092166) (xy 310.487816 -350.006675)
			(xy 310.50484 -349.965264) (xy 310.508432 -349.955681) (xy 310.508415 -349.935231) (xy 310.50484 -349.92564)
			(xy 310.487836 -349.884289) (xy 310.461225 -349.798927) (xy 310.443318 -349.711324) (xy 310.434296 -349.622367)
			(xy 310.43372 -349.57766) (xy 310.43372 -349.576644) (xy 310.433974 -349.565214) (xy 310.407495 -349.559269)
			(xy 310.35526 -349.544526) (xy 310.32958 -349.53575) (xy 310.321383 -349.533236) (xy 310.304249 -349.533236)
			(xy 310.296052 -349.53575) (xy 310.260836 -349.547697) (xy 310.188826 -349.566284) (xy 310.115503 -349.578724)
			(xy 310.041392 -349.584928) (xy 310.004206 -349.58528) (xy 309.967022 -349.584911) (xy 309.892914 -349.578689)
			(xy 309.819594 -349.566246) (xy 309.747583 -349.547672) (xy 309.71236 -349.53575) (xy 309.704163 -349.533236)
			(xy 309.687029 -349.533236) (xy 309.678832 -349.53575) (xy 309.64373 -349.547637) (xy 309.571974 -349.566187)
			(xy 309.498911 -349.578634) (xy 309.42506 -349.584887) (xy 309.388002 -349.58528) (xy 309.386986 -349.58528)
			(xy 309.345059 -349.584857) (xy 309.261586 -349.576885) (xy 309.179248 -349.561014) (xy 309.098792 -349.537389)
			(xy 309.020946 -349.506223) (xy 308.946414 -349.467798) (xy 308.875873 -349.422463) (xy 308.80996 -349.370628)
			(xy 308.749273 -349.312762) (xy 308.694361 -349.24939) (xy 308.645722 -349.181084) (xy 308.603796 -349.108465)
			(xy 308.568962 -349.032189) (xy 308.541537 -348.952948) (xy 308.521768 -348.871458) (xy 308.509834 -348.788458)
			(xy 308.505844 -348.7047) (xy 304.961745 -348.7047) (xy 304.965121 -348.741025) (xy 304.965608 -348.782132)
			(xy 304.965042 -348.826902) (xy 304.956033 -348.915987) (xy 304.938129 -349.003718) (xy 304.911511 -349.089209)
			(xy 304.894488 -349.13062) (xy 304.890904 -349.140205) (xy 304.890915 -349.160653) (xy 304.894488 -349.170244)
			(xy 304.911511 -349.211656) (xy 304.938147 -349.297143) (xy 304.956056 -349.384874) (xy 304.965054 -349.473962)
			(xy 304.965608 -349.518732) (xy 304.965042 -349.563502) (xy 304.956033 -349.652587) (xy 304.938129 -349.740318)
			(xy 304.911511 -349.825809) (xy 304.894488 -349.86722) (xy 304.890904 -349.876805) (xy 304.890915 -349.897253)
			(xy 304.894488 -349.906844) (xy 304.911511 -349.948256) (xy 304.938147 -350.033743) (xy 304.956056 -350.121474)
			(xy 304.965054 -350.210562) (xy 304.965608 -350.255332) (xy 304.965178 -350.296443) (xy 304.957587 -350.378314)
			(xy 304.942474 -350.459136) (xy 304.919966 -350.538217) (xy 304.890257 -350.614885) (xy 304.853599 -350.688483)
			(xy 304.810306 -350.758385) (xy 304.760747 -350.823993) (xy 304.705345 -350.884747) (xy 304.644572 -350.94013)
			(xy 304.578948 -350.989668) (xy 304.509033 -351.032938) (xy 304.435423 -351.069572) (xy 304.358746 -351.099257)
			(xy 304.279657 -351.121739) (xy 304.198831 -351.136827) (xy 304.116957 -351.144391) (xy 304.075846 -351.14484)
			(xy 304.034242 -351.14437) (xy 303.951394 -351.136637) (xy 303.869629 -351.121206) (xy 303.789662 -351.098211)
			(xy 303.712189 -351.067854) (xy 303.637888 -351.0304) (xy 303.60239 -351.008696) (xy 303.593258 -351.003521)
			(xy 303.572538 -351.00031) (xy 303.552261 -351.005649) (xy 303.543716 -351.011744) (xy 303.510066 -351.037664)
			(xy 303.438692 -351.083723) (xy 303.363253 -351.12277) (xy 303.284437 -351.15445) (xy 303.20296 -351.178473)
			(xy 303.119564 -351.194623) (xy 303.035008 -351.20275) (xy 302.992536 -351.20326) (xy 302.992282 -351.20326)
			(xy 302.951175 -351.202805) (xy 302.869311 -351.195219) (xy 302.788497 -351.180113) (xy 302.70942 -351.157617)
			(xy 302.632756 -351.127921) (xy 302.559159 -351.09128) (xy 302.489255 -351.048006) (xy 302.423641 -350.998468)
			(xy 302.362877 -350.943088) (xy 302.307482 -350.882339) (xy 302.257926 -350.816738) (xy 302.214633 -350.746846)
			(xy 302.177973 -350.673258) (xy 302.148258 -350.596602) (xy 302.125741 -350.517531) (xy 302.110614 -350.43672)
			(xy 302.103006 -350.354859) (xy 302.10252 -350.313752) (xy 302.103079 -350.268982) (xy 302.11209 -350.179897)
			(xy 302.129996 -350.092166) (xy 302.156616 -350.006675) (xy 302.17364 -349.965264) (xy 302.177232 -349.955681)
			(xy 302.177215 -349.935231) (xy 302.17364 -349.92564) (xy 302.156636 -349.884289) (xy 302.130025 -349.798927)
			(xy 302.112118 -349.711324) (xy 302.103096 -349.622367) (xy 302.10252 -349.57766) (xy 302.10252 -349.576644)
			(xy 302.102774 -349.565214) (xy 302.076295 -349.559269) (xy 302.02406 -349.544526) (xy 301.99838 -349.53575)
			(xy 301.990183 -349.533236) (xy 301.973049 -349.533236) (xy 301.964852 -349.53575) (xy 301.929636 -349.547697)
			(xy 301.857626 -349.566284) (xy 301.784303 -349.578724) (xy 301.710192 -349.584928) (xy 301.673006 -349.58528)
			(xy 301.635822 -349.584911) (xy 301.561714 -349.578689) (xy 301.488394 -349.566246) (xy 301.416383 -349.547672)
			(xy 301.38116 -349.53575) (xy 301.372963 -349.533236) (xy 301.355829 -349.533236) (xy 301.347632 -349.53575)
			(xy 301.31253 -349.547637) (xy 301.240774 -349.566187) (xy 301.167711 -349.578634) (xy 301.09386 -349.584887)
			(xy 301.056802 -349.58528) (xy 301.055786 -349.58528) (xy 301.013859 -349.584857) (xy 300.930386 -349.576885)
			(xy 300.848048 -349.561014) (xy 300.767592 -349.537389) (xy 300.689746 -349.506223) (xy 300.615214 -349.467798)
			(xy 300.544673 -349.422463) (xy 300.47876 -349.370628) (xy 300.418073 -349.312762) (xy 300.363161 -349.24939)
			(xy 300.314522 -349.181084) (xy 300.272596 -349.108465) (xy 300.237762 -349.032189) (xy 300.210337 -348.952948)
			(xy 300.190568 -348.871458) (xy 300.178634 -348.788458) (xy 300.174644 -348.7047) (xy 296.605145 -348.7047)
			(xy 296.608521 -348.741025) (xy 296.609008 -348.782132) (xy 296.608442 -348.826902) (xy 296.599433 -348.915987)
			(xy 296.581529 -349.003718) (xy 296.554911 -349.089209) (xy 296.537888 -349.13062) (xy 296.534304 -349.140205)
			(xy 296.534315 -349.160653) (xy 296.537888 -349.170244) (xy 296.554911 -349.211656) (xy 296.581547 -349.297143)
			(xy 296.599456 -349.384874) (xy 296.608454 -349.473962) (xy 296.609008 -349.518732) (xy 296.608442 -349.563502)
			(xy 296.599433 -349.652587) (xy 296.581529 -349.740318) (xy 296.554911 -349.825809) (xy 296.537888 -349.86722)
			(xy 296.534304 -349.876805) (xy 296.534315 -349.897253) (xy 296.537888 -349.906844) (xy 296.554911 -349.948256)
			(xy 296.581547 -350.033743) (xy 296.599456 -350.121474) (xy 296.608454 -350.210562) (xy 296.609008 -350.255332)
			(xy 296.608578 -350.296443) (xy 296.600987 -350.378314) (xy 296.585874 -350.459136) (xy 296.563366 -350.538217)
			(xy 296.533657 -350.614885) (xy 296.496999 -350.688483) (xy 296.453706 -350.758385) (xy 296.404147 -350.823993)
			(xy 296.348745 -350.884747) (xy 296.287972 -350.94013) (xy 296.222348 -350.989668) (xy 296.152433 -351.032938)
			(xy 296.078823 -351.069572) (xy 296.002146 -351.099257) (xy 295.923057 -351.121739) (xy 295.842231 -351.136827)
			(xy 295.760357 -351.144391) (xy 295.719246 -351.14484) (xy 295.677642 -351.14437) (xy 295.594794 -351.136637)
			(xy 295.513029 -351.121206) (xy 295.433062 -351.098211) (xy 295.355589 -351.067854) (xy 295.281288 -351.0304)
			(xy 295.24579 -351.008696) (xy 295.236658 -351.003521) (xy 295.215938 -351.00031) (xy 295.195661 -351.005649)
			(xy 295.187116 -351.011744) (xy 295.153466 -351.037664) (xy 295.082092 -351.083723) (xy 295.006653 -351.12277)
			(xy 294.927837 -351.15445) (xy 294.84636 -351.178473) (xy 294.762964 -351.194623) (xy 294.678408 -351.20275)
			(xy 294.635936 -351.20326) (xy 294.635682 -351.20326) (xy 294.594575 -351.202805) (xy 294.512711 -351.195219)
			(xy 294.431897 -351.180113) (xy 294.35282 -351.157617) (xy 294.276156 -351.127921) (xy 294.202559 -351.09128)
			(xy 294.132655 -351.048006) (xy 294.067041 -350.998468) (xy 294.006277 -350.943088) (xy 293.950882 -350.882339)
			(xy 293.901326 -350.816738) (xy 293.858033 -350.746846) (xy 293.821373 -350.673258) (xy 293.791658 -350.596602)
			(xy 293.769141 -350.517531) (xy 293.754014 -350.43672) (xy 293.746406 -350.354859) (xy 293.74592 -350.313752)
			(xy 293.746479 -350.268982) (xy 293.75549 -350.179897) (xy 293.773396 -350.092166) (xy 293.800016 -350.006675)
			(xy 293.81704 -349.965264) (xy 293.820632 -349.955681) (xy 293.820615 -349.935231) (xy 293.81704 -349.92564)
			(xy 293.800036 -349.884289) (xy 293.773425 -349.798927) (xy 293.755518 -349.711324) (xy 293.746496 -349.622367)
			(xy 293.74592 -349.57766) (xy 293.74592 -349.576644) (xy 293.746174 -349.565214) (xy 293.719695 -349.559269)
			(xy 293.66746 -349.544526) (xy 293.64178 -349.53575) (xy 293.633583 -349.533236) (xy 293.616449 -349.533236)
			(xy 293.608252 -349.53575) (xy 293.573036 -349.547697) (xy 293.501026 -349.566284) (xy 293.427703 -349.578724)
			(xy 293.353592 -349.584928) (xy 293.316406 -349.58528) (xy 293.279222 -349.584911) (xy 293.205114 -349.578689)
			(xy 293.131794 -349.566246) (xy 293.059783 -349.547672) (xy 293.02456 -349.53575) (xy 293.016363 -349.533236)
			(xy 292.999229 -349.533236) (xy 292.991032 -349.53575) (xy 292.95593 -349.547637) (xy 292.884174 -349.566187)
			(xy 292.811111 -349.578634) (xy 292.73726 -349.584887) (xy 292.700202 -349.58528) (xy 292.699186 -349.58528)
			(xy 292.657259 -349.584857) (xy 292.573786 -349.576885) (xy 292.491448 -349.561014) (xy 292.410992 -349.537389)
			(xy 292.333146 -349.506223) (xy 292.258614 -349.467798) (xy 292.188073 -349.422463) (xy 292.12216 -349.370628)
			(xy 292.061473 -349.312762) (xy 292.006561 -349.24939) (xy 291.957922 -349.181084) (xy 291.915996 -349.108465)
			(xy 291.881162 -349.032189) (xy 291.853737 -348.952948) (xy 291.833968 -348.871458) (xy 291.822034 -348.788458)
			(xy 291.818044 -348.7047) (xy 288.299345 -348.7047) (xy 288.302721 -348.741025) (xy 288.303208 -348.782132)
			(xy 288.302642 -348.826902) (xy 288.293633 -348.915987) (xy 288.275729 -349.003718) (xy 288.249111 -349.089209)
			(xy 288.232088 -349.13062) (xy 288.228504 -349.140205) (xy 288.228515 -349.160653) (xy 288.232088 -349.170244)
			(xy 288.249111 -349.211656) (xy 288.275747 -349.297143) (xy 288.293656 -349.384874) (xy 288.302654 -349.473962)
			(xy 288.303208 -349.518732) (xy 288.302642 -349.563502) (xy 288.293633 -349.652587) (xy 288.275729 -349.740318)
			(xy 288.249111 -349.825809) (xy 288.232088 -349.86722) (xy 288.228504 -349.876805) (xy 288.228515 -349.897253)
			(xy 288.232088 -349.906844) (xy 288.249111 -349.948256) (xy 288.275747 -350.033743) (xy 288.293656 -350.121474)
			(xy 288.302654 -350.210562) (xy 288.303208 -350.255332) (xy 288.302778 -350.296443) (xy 288.295187 -350.378314)
			(xy 288.280074 -350.459136) (xy 288.257566 -350.538217) (xy 288.227857 -350.614885) (xy 288.191199 -350.688483)
			(xy 288.147906 -350.758385) (xy 288.098347 -350.823993) (xy 288.042945 -350.884747) (xy 287.982172 -350.94013)
			(xy 287.916548 -350.989668) (xy 287.846633 -351.032938) (xy 287.773023 -351.069572) (xy 287.696346 -351.099257)
			(xy 287.617257 -351.121739) (xy 287.536431 -351.136827) (xy 287.454557 -351.144391) (xy 287.413446 -351.14484)
			(xy 287.371842 -351.14437) (xy 287.288994 -351.136637) (xy 287.207229 -351.121206) (xy 287.127262 -351.098211)
			(xy 287.049789 -351.067854) (xy 286.975488 -351.0304) (xy 286.93999 -351.008696) (xy 286.930858 -351.003521)
			(xy 286.910138 -351.00031) (xy 286.889861 -351.005649) (xy 286.881316 -351.011744) (xy 286.847666 -351.037664)
			(xy 286.776292 -351.083723) (xy 286.700853 -351.12277) (xy 286.622037 -351.15445) (xy 286.54056 -351.178473)
			(xy 286.457164 -351.194623) (xy 286.372608 -351.20275) (xy 286.330136 -351.20326) (xy 286.329882 -351.20326)
			(xy 286.288775 -351.202805) (xy 286.206911 -351.195219) (xy 286.126097 -351.180113) (xy 286.04702 -351.157617)
			(xy 285.970356 -351.127921) (xy 285.896759 -351.09128) (xy 285.826855 -351.048006) (xy 285.761241 -350.998468)
			(xy 285.700477 -350.943088) (xy 285.645082 -350.882339) (xy 285.595526 -350.816738) (xy 285.552233 -350.746846)
			(xy 285.515573 -350.673258) (xy 285.485858 -350.596602) (xy 285.463341 -350.517531) (xy 285.448214 -350.43672)
			(xy 285.440606 -350.354859) (xy 285.44012 -350.313752) (xy 285.440679 -350.268982) (xy 285.44969 -350.179897)
			(xy 285.467596 -350.092166) (xy 285.494216 -350.006675) (xy 285.51124 -349.965264) (xy 285.514832 -349.955681)
			(xy 285.514815 -349.935231) (xy 285.51124 -349.92564) (xy 285.494236 -349.884289) (xy 285.467625 -349.798927)
			(xy 285.449718 -349.711324) (xy 285.440696 -349.622367) (xy 285.44012 -349.57766) (xy 285.44012 -349.576644)
			(xy 285.440374 -349.565214) (xy 285.413895 -349.559269) (xy 285.36166 -349.544526) (xy 285.33598 -349.53575)
			(xy 285.327783 -349.533236) (xy 285.310649 -349.533236) (xy 285.302452 -349.53575) (xy 285.267236 -349.547697)
			(xy 285.195226 -349.566284) (xy 285.121903 -349.578724) (xy 285.047792 -349.584928) (xy 285.010606 -349.58528)
			(xy 284.973422 -349.584911) (xy 284.899314 -349.578689) (xy 284.825994 -349.566246) (xy 284.753983 -349.547672)
			(xy 284.71876 -349.53575) (xy 284.710563 -349.533236) (xy 284.693429 -349.533236) (xy 284.685232 -349.53575)
			(xy 284.65013 -349.547637) (xy 284.578374 -349.566187) (xy 284.505311 -349.578634) (xy 284.43146 -349.584887)
			(xy 284.394402 -349.58528) (xy 284.393386 -349.58528) (xy 284.351459 -349.584857) (xy 284.267986 -349.576885)
			(xy 284.185648 -349.561014) (xy 284.105192 -349.537389) (xy 284.027346 -349.506223) (xy 283.952814 -349.467798)
			(xy 283.882273 -349.422463) (xy 283.81636 -349.370628) (xy 283.755673 -349.312762) (xy 283.700761 -349.24939)
			(xy 283.652122 -349.181084) (xy 283.610196 -349.108465) (xy 283.575362 -349.032189) (xy 283.547937 -348.952948)
			(xy 283.528168 -348.871458) (xy 283.516234 -348.788458) (xy 283.512244 -348.7047) (xy 280.018945 -348.7047)
			(xy 280.022321 -348.741025) (xy 280.022808 -348.782132) (xy 280.022242 -348.826902) (xy 280.013233 -348.915987)
			(xy 279.995329 -349.003718) (xy 279.968711 -349.089209) (xy 279.951688 -349.13062) (xy 279.948104 -349.140205)
			(xy 279.948115 -349.160653) (xy 279.951688 -349.170244) (xy 279.968711 -349.211656) (xy 279.995347 -349.297143)
			(xy 280.013256 -349.384874) (xy 280.022254 -349.473962) (xy 280.022808 -349.518732) (xy 280.022242 -349.563502)
			(xy 280.013233 -349.652587) (xy 279.995329 -349.740318) (xy 279.968711 -349.825809) (xy 279.951688 -349.86722)
			(xy 279.948104 -349.876805) (xy 279.948115 -349.897253) (xy 279.951688 -349.906844) (xy 279.968711 -349.948256)
			(xy 279.995347 -350.033743) (xy 280.013256 -350.121474) (xy 280.022254 -350.210562) (xy 280.022808 -350.255332)
			(xy 280.022378 -350.296443) (xy 280.014787 -350.378314) (xy 279.999674 -350.459136) (xy 279.977166 -350.538217)
			(xy 279.947457 -350.614885) (xy 279.910799 -350.688483) (xy 279.867506 -350.758385) (xy 279.817947 -350.823993)
			(xy 279.762545 -350.884747) (xy 279.701772 -350.94013) (xy 279.636148 -350.989668) (xy 279.566233 -351.032938)
			(xy 279.492623 -351.069572) (xy 279.415946 -351.099257) (xy 279.336857 -351.121739) (xy 279.256031 -351.136827)
			(xy 279.174157 -351.144391) (xy 279.133046 -351.14484) (xy 279.091442 -351.14437) (xy 279.008594 -351.136637)
			(xy 278.926829 -351.121206) (xy 278.846862 -351.098211) (xy 278.769389 -351.067854) (xy 278.695088 -351.0304)
			(xy 278.65959 -351.008696) (xy 278.650458 -351.003521) (xy 278.629738 -351.00031) (xy 278.609461 -351.005649)
			(xy 278.600916 -351.011744) (xy 278.567266 -351.037664) (xy 278.495892 -351.083723) (xy 278.420453 -351.12277)
			(xy 278.341637 -351.15445) (xy 278.26016 -351.178473) (xy 278.176764 -351.194623) (xy 278.092208 -351.20275)
			(xy 278.049736 -351.20326) (xy 278.049482 -351.20326) (xy 278.008375 -351.202805) (xy 277.926511 -351.195219)
			(xy 277.845697 -351.180113) (xy 277.76662 -351.157617) (xy 277.689956 -351.127921) (xy 277.616359 -351.09128)
			(xy 277.546455 -351.048006) (xy 277.480841 -350.998468) (xy 277.420077 -350.943088) (xy 277.364682 -350.882339)
			(xy 277.315126 -350.816738) (xy 277.271833 -350.746846) (xy 277.235173 -350.673258) (xy 277.205458 -350.596602)
			(xy 277.182941 -350.517531) (xy 277.167814 -350.43672) (xy 277.160206 -350.354859) (xy 277.15972 -350.313752)
			(xy 277.160279 -350.268982) (xy 277.16929 -350.179897) (xy 277.187196 -350.092166) (xy 277.213816 -350.006675)
			(xy 277.23084 -349.965264) (xy 277.234432 -349.955681) (xy 277.234415 -349.935231) (xy 277.23084 -349.92564)
			(xy 277.213836 -349.884289) (xy 277.187225 -349.798927) (xy 277.169318 -349.711324) (xy 277.160296 -349.622367)
			(xy 277.15972 -349.57766) (xy 277.15972 -349.576644) (xy 277.159974 -349.565214) (xy 277.133495 -349.559269)
			(xy 277.08126 -349.544526) (xy 277.05558 -349.53575) (xy 277.047383 -349.533236) (xy 277.030249 -349.533236)
			(xy 277.022052 -349.53575) (xy 276.986836 -349.547697) (xy 276.914826 -349.566284) (xy 276.841503 -349.578724)
			(xy 276.767392 -349.584928) (xy 276.730206 -349.58528) (xy 276.693022 -349.584911) (xy 276.618914 -349.578689)
			(xy 276.545594 -349.566246) (xy 276.473583 -349.547672) (xy 276.43836 -349.53575) (xy 276.430163 -349.533236)
			(xy 276.413029 -349.533236) (xy 276.404832 -349.53575) (xy 276.36973 -349.547637) (xy 276.297974 -349.566187)
			(xy 276.224911 -349.578634) (xy 276.15106 -349.584887) (xy 276.114002 -349.58528) (xy 276.112986 -349.58528)
			(xy 276.071059 -349.584857) (xy 275.987586 -349.576885) (xy 275.905248 -349.561014) (xy 275.824792 -349.537389)
			(xy 275.746946 -349.506223) (xy 275.672414 -349.467798) (xy 275.601873 -349.422463) (xy 275.53596 -349.370628)
			(xy 275.475273 -349.312762) (xy 275.420361 -349.24939) (xy 275.371722 -349.181084) (xy 275.329796 -349.108465)
			(xy 275.294962 -349.032189) (xy 275.267537 -348.952948) (xy 275.247768 -348.871458) (xy 275.235834 -348.788458)
			(xy 275.231844 -348.7047) (xy 85.721282 -348.7047) (xy 85.724562 -348.719921) (xy 85.734552 -348.813881)
			(xy 85.73516 -348.861126) (xy 85.734613 -348.906766) (xy 85.725307 -348.997569) (xy 85.706754 -349.086942)
			(xy 85.693504 -349.13062) (xy 85.691044 -349.139629) (xy 85.692095 -349.15826) (xy 85.695536 -349.166942)
			(xy 85.714247 -349.210016) (xy 85.743525 -349.299254) (xy 85.763232 -349.391081) (xy 85.77315 -349.484473)
			(xy 85.773768 -349.531432) (xy 85.77323 -349.574377) (xy 85.764932 -349.659867) (xy 85.748446 -349.744161)
			(xy 85.723925 -349.826477) (xy 85.708236 -349.866458) (xy 85.704966 -349.875707) (xy 85.704968 -349.895308)
			(xy 85.708236 -349.904558) (xy 85.723933 -349.944537) (xy 85.748482 -350.026848) (xy 85.764973 -350.111143)
			(xy 85.773254 -350.196637) (xy 85.773768 -350.239584) (xy 85.773768 -350.239838) (xy 85.773264 -350.282199)
			(xy 85.765211 -350.366536) (xy 85.749177 -350.449726) (xy 85.725309 -350.531016) (xy 85.693821 -350.609668)
			(xy 85.654999 -350.684971) (xy 85.609196 -350.756243) (xy 85.556825 -350.822839) (xy 85.49836 -350.884154)
			(xy 85.434332 -350.939635) (xy 85.36532 -350.988778) (xy 85.29195 -351.031138) (xy 85.214885 -351.066333)
			(xy 85.134823 -351.094042) (xy 85.05249 -351.114016) (xy 84.968631 -351.126073) (xy 84.884006 -351.130105)
			(xy 84.799381 -351.126073) (xy 84.715522 -351.114016) (xy 84.633189 -351.094042) (xy 84.553127 -351.066333)
			(xy 84.476062 -351.031138) (xy 84.402692 -350.988778) (xy 84.33368 -350.939635) (xy 84.269652 -350.884154)
			(xy 84.211187 -350.822839) (xy 84.158816 -350.756243) (xy 84.113013 -350.684971) (xy 84.074191 -350.609668)
			(xy 84.042703 -350.531016) (xy 84.018835 -350.449726) (xy 84.002801 -350.366536) (xy 83.994748 -350.282199)
			(xy 83.994244 -350.239838) (xy 83.994244 -350.239584) (xy 83.994787 -350.196639) (xy 84.003083 -350.111149)
			(xy 84.019568 -350.026855) (xy 84.044088 -349.944539) (xy 84.059776 -349.904558) (xy 84.063037 -349.895306)
			(xy 84.06304 -349.875708) (xy 84.059776 -349.866458) (xy 84.044053 -349.826489) (xy 84.019511 -349.744174)
			(xy 84.003027 -349.659876) (xy 83.994754 -349.57438) (xy 83.994244 -349.531432) (xy 83.994855 -349.485787)
			(xy 84.004246 -349.394981) (xy 84.022872 -349.305612) (xy 84.036154 -349.261938) (xy 84.038586 -349.252923)
			(xy 84.037555 -349.234298) (xy 84.034122 -349.225616) (xy 84.015469 -349.182525) (xy 83.98626 -349.093282)
			(xy 83.966612 -349.001459) (xy 83.956742 -348.908077) (xy 83.956144 -348.861126) (xy 83.073245 -348.861126)
			(xy 83.073748 -348.89948) (xy 83.073141 -348.945125) (xy 83.063748 -349.035931) (xy 83.045121 -349.1253)
			(xy 83.031838 -349.168974) (xy 83.0294 -349.177987) (xy 83.030435 -349.196614) (xy 83.03387 -349.205296)
			(xy 83.052527 -349.248385) (xy 83.081735 -349.337629) (xy 83.101382 -349.429453) (xy 83.111251 -349.522835)
			(xy 83.111848 -349.569786) (xy 83.111412 -349.610119) (xy 83.104141 -349.690457) (xy 83.08963 -349.769807)
			(xy 83.067997 -349.847519) (xy 83.039422 -349.922954) (xy 83.022186 -349.959422) (xy 83.017653 -349.970011)
			(xy 83.017661 -349.993024) (xy 83.022186 -350.003618) (xy 83.039387 -350.040045) (xy 83.067929 -350.115383)
			(xy 83.089551 -350.19299) (xy 83.104075 -350.272234) (xy 83.111383 -350.352465) (xy 83.111848 -350.392746)
			(xy 83.111848 -350.393) (xy 83.111344 -350.435361) (xy 83.103291 -350.519698) (xy 83.087257 -350.602888)
			(xy 83.063389 -350.684178) (xy 83.031901 -350.76283) (xy 82.993079 -350.838133) (xy 82.947276 -350.909405)
			(xy 82.894905 -350.976001) (xy 82.83644 -351.037316) (xy 82.772412 -351.092797) (xy 82.7034 -351.14194)
			(xy 82.63003 -351.1843) (xy 82.552965 -351.219495) (xy 82.472903 -351.247204) (xy 82.39057 -351.267178)
			(xy 82.306711 -351.279235) (xy 82.222086 -351.283267) (xy 82.137461 -351.279235) (xy 82.053602 -351.267178)
			(xy 81.971269 -351.247204) (xy 81.891207 -351.219495) (xy 81.814142 -351.1843) (xy 81.740772 -351.14194)
			(xy 81.67176 -351.092797) (xy 81.607732 -351.037316) (xy 81.549267 -350.976001) (xy 81.496896 -350.909405)
			(xy 81.451093 -350.838133) (xy 81.412271 -350.76283) (xy 81.380783 -350.684178) (xy 81.356915 -350.602888)
			(xy 81.340881 -350.519698) (xy 81.332828 -350.435361) (xy 81.332324 -350.393) (xy 81.332778 -350.35266)
			(xy 81.340081 -350.272312) (xy 81.354637 -350.192956) (xy 81.376326 -350.115246) (xy 81.404968 -350.039822)
			(xy 81.42224 -350.003364) (xy 81.426812 -349.992711) (xy 81.426828 -349.969558) (xy 81.42224 -349.958914)
			(xy 81.405059 -349.922483) (xy 81.376548 -349.847143) (xy 81.35497 -349.769534) (xy 81.340501 -349.69029)
			(xy 81.33326 -349.610063) (xy 81.332832 -349.569786) (xy 81.333382 -349.524146) (xy 81.342687 -349.433343)
			(xy 81.361239 -349.34397) (xy 81.374488 -349.300292) (xy 81.376942 -349.291282) (xy 81.375896 -349.272652)
			(xy 81.372456 -349.26397) (xy 81.353748 -349.220894) (xy 81.32447 -349.131657) (xy 81.304762 -349.039831)
			(xy 81.294843 -348.946439) (xy 81.294224 -348.89948) (xy 66.467942 -348.89948) (xy 66.465784 -348.920813)
			(xy 66.447878 -349.008544) (xy 66.421259 -349.094035) (xy 66.404236 -349.135446) (xy 66.400697 -349.145044)
			(xy 66.400681 -349.16548) (xy 66.404236 -349.17507) (xy 66.421263 -349.21648) (xy 66.4479 -349.301967)
			(xy 66.465806 -349.3897) (xy 66.474803 -349.478787) (xy 66.475356 -349.523558) (xy 66.474795 -349.568328)
			(xy 66.465784 -349.657413) (xy 66.447878 -349.745144) (xy 66.421259 -349.830635) (xy 66.404236 -349.872046)
			(xy 66.400697 -349.881644) (xy 66.400681 -349.90208) (xy 66.404236 -349.91167) (xy 66.421263 -349.95308)
			(xy 66.4479 -350.038567) (xy 66.465806 -350.1263) (xy 66.474803 -350.215387) (xy 66.475356 -350.260158)
			(xy 66.474861 -350.301272) (xy 66.467278 -350.383151) (xy 66.452172 -350.46398) (xy 66.429672 -350.54307)
			(xy 66.39997 -350.619748) (xy 66.36332 -350.693357) (xy 66.320034 -350.76327) (xy 66.270482 -350.828891)
			(xy 66.215086 -350.88966) (xy 66.154319 -350.945059) (xy 66.0887 -350.994614) (xy 66.018788 -351.037902)
			(xy 65.94518 -351.074555) (xy 65.868505 -351.10426) (xy 65.789415 -351.126764) (xy 65.708586 -351.141873)
			(xy 65.626708 -351.14946) (xy 65.585594 -351.14992) (xy 65.543984 -351.149442) (xy 65.461127 -351.141665)
			(xy 65.379358 -351.12619) (xy 65.299391 -351.10315) (xy 65.221922 -351.072748) (xy 65.147629 -351.035248)
			(xy 65.112138 -351.013522) (xy 65.10303 -351.008297) (xy 65.082293 -351.005101) (xy 65.062008 -351.010462)
			(xy 65.053464 -351.01657) (xy 65.019831 -351.042555) (xy 64.948437 -351.08868) (xy 64.872967 -351.127782)
			(xy 64.79411 -351.159503) (xy 64.712585 -351.183553) (xy 64.629138 -351.199714) (xy 64.544529 -351.207838)
			(xy 64.50203 -351.20834) (xy 64.460915 -351.207873) (xy 64.379035 -351.200288) (xy 64.298205 -351.185181)
			(xy 64.219114 -351.162679) (xy 64.142436 -351.132976) (xy 64.068826 -351.096324) (xy 63.998912 -351.053036)
			(xy 63.93329 -351.003482) (xy 63.872521 -350.948084) (xy 63.817123 -350.887316) (xy 63.767568 -350.821695)
			(xy 63.72428 -350.751781) (xy 63.687628 -350.678172) (xy 63.657923 -350.601494) (xy 63.635421 -350.522403)
			(xy 63.620313 -350.441573) (xy 63.612727 -350.359693) (xy 63.612268 -350.318578) (xy 63.61284 -350.273809)
			(xy 63.621847 -350.184724) (xy 63.63975 -350.096993) (xy 63.666366 -350.011501) (xy 63.683388 -349.97009)
			(xy 63.686968 -349.960503) (xy 63.68696 -349.940056) (xy 63.683388 -349.930466) (xy 63.666363 -349.889123)
			(xy 63.639757 -349.803758) (xy 63.621856 -349.716153) (xy 63.612841 -349.627193) (xy 63.612268 -349.582486)
			(xy 63.612268 -349.58147) (xy 63.612522 -349.57004) (xy 63.586044 -349.564091) (xy 63.533809 -349.54935)
			(xy 63.508128 -349.540576) (xy 63.499931 -349.538062) (xy 63.482797 -349.538062) (xy 63.4746 -349.540576)
			(xy 63.43938 -349.552528) (xy 63.367379 -349.571185) (xy 63.294059 -349.583696) (xy 63.219944 -349.589972)
			(xy 63.182754 -349.59036) (xy 63.145565 -349.589952) (xy 63.071452 -349.583667) (xy 62.998133 -349.571163)
			(xy 62.926126 -349.552528) (xy 62.890908 -349.540576) (xy 62.882711 -349.538062) (xy 62.865577 -349.538062)
			(xy 62.85738 -349.540576) (xy 62.822162 -349.552533) (xy 62.75016 -349.571189) (xy 62.676839 -349.583699)
			(xy 62.602724 -349.589973) (xy 62.565534 -349.59036) (xy 62.523594 -349.589902) (xy 62.440094 -349.581932)
			(xy 62.35773 -349.566061) (xy 62.277248 -349.542432) (xy 62.199376 -349.511259) (xy 62.12482 -349.472825)
			(xy 62.054255 -349.427478) (xy 61.98832 -349.375629) (xy 61.927613 -349.317747) (xy 61.872683 -349.254356)
			(xy 61.824027 -349.186031) (xy 61.782086 -349.11339) (xy 61.74724 -349.037091) (xy 61.719806 -348.957825)
			(xy 61.70003 -348.87631) (xy 61.688092 -348.793284) (xy 61.684101 -348.7095) (xy 58.14031 -348.7095)
			(xy 58.143679 -348.745845) (xy 58.144156 -348.786958) (xy 58.143595 -348.831728) (xy 58.134584 -348.920813)
			(xy 58.116678 -349.008544) (xy 58.090059 -349.094035) (xy 58.073036 -349.135446) (xy 58.069497 -349.145044)
			(xy 58.069481 -349.16548) (xy 58.073036 -349.17507) (xy 58.090063 -349.21648) (xy 58.1167 -349.301967)
			(xy 58.134606 -349.3897) (xy 58.143603 -349.478787) (xy 58.144156 -349.523558) (xy 58.143595 -349.568328)
			(xy 58.134584 -349.657413) (xy 58.116678 -349.745144) (xy 58.090059 -349.830635) (xy 58.073036 -349.872046)
			(xy 58.069497 -349.881644) (xy 58.069481 -349.90208) (xy 58.073036 -349.91167) (xy 58.090063 -349.95308)
			(xy 58.1167 -350.038567) (xy 58.134606 -350.1263) (xy 58.143603 -350.215387) (xy 58.144156 -350.260158)
			(xy 58.143661 -350.301272) (xy 58.136078 -350.383151) (xy 58.120972 -350.46398) (xy 58.098472 -350.54307)
			(xy 58.06877 -350.619748) (xy 58.03212 -350.693357) (xy 57.988834 -350.76327) (xy 57.939282 -350.828891)
			(xy 57.883886 -350.88966) (xy 57.823119 -350.945059) (xy 57.7575 -350.994614) (xy 57.687588 -351.037902)
			(xy 57.61398 -351.074555) (xy 57.537305 -351.10426) (xy 57.458215 -351.126764) (xy 57.377386 -351.141873)
			(xy 57.295508 -351.14946) (xy 57.254394 -351.14992) (xy 57.212784 -351.149442) (xy 57.129927 -351.141665)
			(xy 57.048158 -351.12619) (xy 56.968191 -351.10315) (xy 56.890722 -351.072748) (xy 56.816429 -351.035248)
			(xy 56.780938 -351.013522) (xy 56.77183 -351.008297) (xy 56.751093 -351.005101) (xy 56.730808 -351.010462)
			(xy 56.722264 -351.01657) (xy 56.688631 -351.042555) (xy 56.617237 -351.08868) (xy 56.541767 -351.127782)
			(xy 56.46291 -351.159503) (xy 56.381385 -351.183553) (xy 56.297938 -351.199714) (xy 56.213329 -351.207838)
			(xy 56.17083 -351.20834) (xy 56.129715 -351.207873) (xy 56.047835 -351.200288) (xy 55.967005 -351.185181)
			(xy 55.887914 -351.162679) (xy 55.811236 -351.132976) (xy 55.737626 -351.096324) (xy 55.667712 -351.053036)
			(xy 55.60209 -351.003482) (xy 55.541321 -350.948084) (xy 55.485923 -350.887316) (xy 55.436368 -350.821695)
			(xy 55.39308 -350.751781) (xy 55.356428 -350.678172) (xy 55.326723 -350.601494) (xy 55.304221 -350.522403)
			(xy 55.289113 -350.441573) (xy 55.281527 -350.359693) (xy 55.281068 -350.318578) (xy 55.28164 -350.273809)
			(xy 55.290647 -350.184724) (xy 55.30855 -350.096993) (xy 55.335166 -350.011501) (xy 55.352188 -349.97009)
			(xy 55.355768 -349.960503) (xy 55.35576 -349.940056) (xy 55.352188 -349.930466) (xy 55.335163 -349.889123)
			(xy 55.308557 -349.803758) (xy 55.290656 -349.716153) (xy 55.281641 -349.627193) (xy 55.281068 -349.582486)
			(xy 55.281068 -349.58147) (xy 55.281322 -349.57004) (xy 55.254844 -349.564091) (xy 55.202609 -349.54935)
			(xy 55.176928 -349.540576) (xy 55.168731 -349.538062) (xy 55.151597 -349.538062) (xy 55.1434 -349.540576)
			(xy 55.10818 -349.552528) (xy 55.036179 -349.571185) (xy 54.962859 -349.583696) (xy 54.888744 -349.589972)
			(xy 54.851554 -349.59036) (xy 54.814365 -349.589952) (xy 54.740252 -349.583667) (xy 54.666933 -349.571163)
			(xy 54.594926 -349.552528) (xy 54.559708 -349.540576) (xy 54.551511 -349.538062) (xy 54.534377 -349.538062)
			(xy 54.52618 -349.540576) (xy 54.490962 -349.552533) (xy 54.41896 -349.571189) (xy 54.345639 -349.583699)
			(xy 54.271524 -349.589973) (xy 54.234334 -349.59036) (xy 54.192394 -349.589902) (xy 54.108894 -349.581932)
			(xy 54.02653 -349.566061) (xy 53.946048 -349.542432) (xy 53.868176 -349.511259) (xy 53.79362 -349.472825)
			(xy 53.723055 -349.427478) (xy 53.65712 -349.375629) (xy 53.596413 -349.317747) (xy 53.541483 -349.254356)
			(xy 53.492827 -349.186031) (xy 53.450886 -349.11339) (xy 53.41604 -349.037091) (xy 53.388606 -348.957825)
			(xy 53.36883 -348.87631) (xy 53.356892 -348.793284) (xy 53.352901 -348.7095) (xy 49.78371 -348.7095)
			(xy 49.787079 -348.745845) (xy 49.787556 -348.786958) (xy 49.786995 -348.831728) (xy 49.777984 -348.920813)
			(xy 49.760078 -349.008544) (xy 49.733459 -349.094035) (xy 49.716436 -349.135446) (xy 49.712897 -349.145044)
			(xy 49.712881 -349.16548) (xy 49.716436 -349.17507) (xy 49.733463 -349.21648) (xy 49.7601 -349.301967)
			(xy 49.778006 -349.3897) (xy 49.787003 -349.478787) (xy 49.787556 -349.523558) (xy 49.786995 -349.568328)
			(xy 49.777984 -349.657413) (xy 49.760078 -349.745144) (xy 49.733459 -349.830635) (xy 49.716436 -349.872046)
			(xy 49.712897 -349.881644) (xy 49.712881 -349.90208) (xy 49.716436 -349.91167) (xy 49.733463 -349.95308)
			(xy 49.7601 -350.038567) (xy 49.778006 -350.1263) (xy 49.787003 -350.215387) (xy 49.787556 -350.260158)
			(xy 49.787061 -350.301272) (xy 49.779478 -350.383151) (xy 49.764372 -350.46398) (xy 49.741872 -350.54307)
			(xy 49.71217 -350.619748) (xy 49.67552 -350.693357) (xy 49.632234 -350.76327) (xy 49.582682 -350.828891)
			(xy 49.527286 -350.88966) (xy 49.466519 -350.945059) (xy 49.4009 -350.994614) (xy 49.330988 -351.037902)
			(xy 49.25738 -351.074555) (xy 49.180705 -351.10426) (xy 49.101615 -351.126764) (xy 49.020786 -351.141873)
			(xy 48.938908 -351.14946) (xy 48.897794 -351.14992) (xy 48.856184 -351.149442) (xy 48.773327 -351.141665)
			(xy 48.691558 -351.12619) (xy 48.611591 -351.10315) (xy 48.534122 -351.072748) (xy 48.459829 -351.035248)
			(xy 48.424338 -351.013522) (xy 48.41523 -351.008297) (xy 48.394493 -351.005101) (xy 48.374208 -351.010462)
			(xy 48.365664 -351.01657) (xy 48.332031 -351.042555) (xy 48.260637 -351.08868) (xy 48.185167 -351.127782)
			(xy 48.10631 -351.159503) (xy 48.024785 -351.183553) (xy 47.941338 -351.199714) (xy 47.856729 -351.207838)
			(xy 47.81423 -351.20834) (xy 47.773115 -351.207873) (xy 47.691235 -351.200288) (xy 47.610405 -351.185181)
			(xy 47.531314 -351.162679) (xy 47.454636 -351.132976) (xy 47.381026 -351.096324) (xy 47.311112 -351.053036)
			(xy 47.24549 -351.003482) (xy 47.184721 -350.948084) (xy 47.129323 -350.887316) (xy 47.079768 -350.821695)
			(xy 47.03648 -350.751781) (xy 46.999828 -350.678172) (xy 46.970123 -350.601494) (xy 46.947621 -350.522403)
			(xy 46.932513 -350.441573) (xy 46.924927 -350.359693) (xy 46.924468 -350.318578) (xy 46.92504 -350.273809)
			(xy 46.934047 -350.184724) (xy 46.95195 -350.096993) (xy 46.978566 -350.011501) (xy 46.995588 -349.97009)
			(xy 46.999168 -349.960503) (xy 46.99916 -349.940056) (xy 46.995588 -349.930466) (xy 46.978563 -349.889123)
			(xy 46.951957 -349.803758) (xy 46.934056 -349.716153) (xy 46.925041 -349.627193) (xy 46.924468 -349.582486)
			(xy 46.924468 -349.58147) (xy 46.924722 -349.57004) (xy 46.898244 -349.564091) (xy 46.846009 -349.54935)
			(xy 46.820328 -349.540576) (xy 46.812131 -349.538062) (xy 46.794997 -349.538062) (xy 46.7868 -349.540576)
			(xy 46.75158 -349.552528) (xy 46.679579 -349.571185) (xy 46.606259 -349.583696) (xy 46.532144 -349.589972)
			(xy 46.494954 -349.59036) (xy 46.457765 -349.589952) (xy 46.383652 -349.583667) (xy 46.310333 -349.571163)
			(xy 46.238326 -349.552528) (xy 46.203108 -349.540576) (xy 46.194911 -349.538062) (xy 46.177777 -349.538062)
			(xy 46.16958 -349.540576) (xy 46.134362 -349.552533) (xy 46.06236 -349.571189) (xy 45.989039 -349.583699)
			(xy 45.914924 -349.589973) (xy 45.877734 -349.59036) (xy 45.835794 -349.589902) (xy 45.752294 -349.581932)
			(xy 45.66993 -349.566061) (xy 45.589448 -349.542432) (xy 45.511576 -349.511259) (xy 45.43702 -349.472825)
			(xy 45.366455 -349.427478) (xy 45.30052 -349.375629) (xy 45.239813 -349.317747) (xy 45.184883 -349.254356)
			(xy 45.136227 -349.186031) (xy 45.094286 -349.11339) (xy 45.05944 -349.037091) (xy 45.032006 -348.957825)
			(xy 45.01223 -348.87631) (xy 45.000292 -348.793284) (xy 44.996301 -348.7095) (xy 41.47791 -348.7095)
			(xy 41.481279 -348.745845) (xy 41.481756 -348.786958) (xy 41.481195 -348.831728) (xy 41.472184 -348.920813)
			(xy 41.454278 -349.008544) (xy 41.427659 -349.094035) (xy 41.410636 -349.135446) (xy 41.407097 -349.145044)
			(xy 41.407081 -349.16548) (xy 41.410636 -349.17507) (xy 41.427663 -349.21648) (xy 41.4543 -349.301967)
			(xy 41.472206 -349.3897) (xy 41.481203 -349.478787) (xy 41.481756 -349.523558) (xy 41.481195 -349.568328)
			(xy 41.472184 -349.657413) (xy 41.454278 -349.745144) (xy 41.427659 -349.830635) (xy 41.410636 -349.872046)
			(xy 41.407097 -349.881644) (xy 41.407081 -349.90208) (xy 41.410636 -349.91167) (xy 41.427663 -349.95308)
			(xy 41.4543 -350.038567) (xy 41.472206 -350.1263) (xy 41.481203 -350.215387) (xy 41.481756 -350.260158)
			(xy 41.481261 -350.301272) (xy 41.473678 -350.383151) (xy 41.458572 -350.46398) (xy 41.436072 -350.54307)
			(xy 41.40637 -350.619748) (xy 41.36972 -350.693357) (xy 41.326434 -350.76327) (xy 41.276882 -350.828891)
			(xy 41.221486 -350.88966) (xy 41.160719 -350.945059) (xy 41.0951 -350.994614) (xy 41.025188 -351.037902)
			(xy 40.95158 -351.074555) (xy 40.874905 -351.10426) (xy 40.795815 -351.126764) (xy 40.714986 -351.141873)
			(xy 40.633108 -351.14946) (xy 40.591994 -351.14992) (xy 40.550384 -351.149442) (xy 40.467527 -351.141665)
			(xy 40.385758 -351.12619) (xy 40.305791 -351.10315) (xy 40.228322 -351.072748) (xy 40.154029 -351.035248)
			(xy 40.118538 -351.013522) (xy 40.10943 -351.008297) (xy 40.088693 -351.005101) (xy 40.068408 -351.010462)
			(xy 40.059864 -351.01657) (xy 40.026231 -351.042555) (xy 39.954837 -351.08868) (xy 39.879367 -351.127782)
			(xy 39.80051 -351.159503) (xy 39.718985 -351.183553) (xy 39.635538 -351.199714) (xy 39.550929 -351.207838)
			(xy 39.50843 -351.20834) (xy 39.467315 -351.207873) (xy 39.385435 -351.200288) (xy 39.304605 -351.185181)
			(xy 39.225514 -351.162679) (xy 39.148836 -351.132976) (xy 39.075226 -351.096324) (xy 39.005312 -351.053036)
			(xy 38.93969 -351.003482) (xy 38.878921 -350.948084) (xy 38.823523 -350.887316) (xy 38.773968 -350.821695)
			(xy 38.73068 -350.751781) (xy 38.694028 -350.678172) (xy 38.664323 -350.601494) (xy 38.641821 -350.522403)
			(xy 38.626713 -350.441573) (xy 38.619127 -350.359693) (xy 38.618668 -350.318578) (xy 38.61924 -350.273809)
			(xy 38.628247 -350.184724) (xy 38.64615 -350.096993) (xy 38.672766 -350.011501) (xy 38.689788 -349.97009)
			(xy 38.693368 -349.960503) (xy 38.69336 -349.940056) (xy 38.689788 -349.930466) (xy 38.672763 -349.889123)
			(xy 38.646157 -349.803758) (xy 38.628256 -349.716153) (xy 38.619241 -349.627193) (xy 38.618668 -349.582486)
			(xy 38.618668 -349.58147) (xy 38.618922 -349.57004) (xy 38.592444 -349.564091) (xy 38.540209 -349.54935)
			(xy 38.514528 -349.540576) (xy 38.506331 -349.538062) (xy 38.489197 -349.538062) (xy 38.481 -349.540576)
			(xy 38.44578 -349.552528) (xy 38.373779 -349.571185) (xy 38.300459 -349.583696) (xy 38.226344 -349.589972)
			(xy 38.189154 -349.59036) (xy 38.151965 -349.589952) (xy 38.077852 -349.583667) (xy 38.004533 -349.571163)
			(xy 37.932526 -349.552528) (xy 37.897308 -349.540576) (xy 37.889111 -349.538062) (xy 37.871977 -349.538062)
			(xy 37.86378 -349.540576) (xy 37.828562 -349.552533) (xy 37.75656 -349.571189) (xy 37.683239 -349.583699)
			(xy 37.609124 -349.589973) (xy 37.571934 -349.59036) (xy 37.529996 -349.589881) (xy 37.446499 -349.581908)
			(xy 37.364138 -349.566035) (xy 37.283659 -349.542404) (xy 37.20579 -349.511231) (xy 37.131238 -349.472797)
			(xy 37.060676 -349.42745) (xy 36.994745 -349.375601) (xy 36.93404 -349.317719) (xy 36.879112 -349.25433)
			(xy 36.830459 -349.186006) (xy 36.788521 -349.113367) (xy 36.753677 -349.03707) (xy 36.726244 -348.957807)
			(xy 36.706469 -348.876294) (xy 36.694532 -348.793272) (xy 36.690541 -348.70949) (xy 33.197509 -348.70949)
			(xy 33.200879 -348.745845) (xy 33.201356 -348.786958) (xy 33.200795 -348.831728) (xy 33.191784 -348.920813)
			(xy 33.173878 -349.008544) (xy 33.147259 -349.094035) (xy 33.130236 -349.135446) (xy 33.126697 -349.145044)
			(xy 33.126681 -349.16548) (xy 33.130236 -349.17507) (xy 33.147263 -349.21648) (xy 33.1739 -349.301967)
			(xy 33.191806 -349.3897) (xy 33.200803 -349.478787) (xy 33.201356 -349.523558) (xy 33.200795 -349.568328)
			(xy 33.191784 -349.657413) (xy 33.173878 -349.745144) (xy 33.147259 -349.830635) (xy 33.130236 -349.872046)
			(xy 33.126697 -349.881644) (xy 33.126681 -349.90208) (xy 33.130236 -349.91167) (xy 33.147263 -349.95308)
			(xy 33.1739 -350.038567) (xy 33.191806 -350.1263) (xy 33.200803 -350.215387) (xy 33.201356 -350.260158)
			(xy 33.200861 -350.301272) (xy 33.193278 -350.383151) (xy 33.178172 -350.46398) (xy 33.155672 -350.54307)
			(xy 33.12597 -350.619748) (xy 33.08932 -350.693357) (xy 33.046034 -350.76327) (xy 32.996482 -350.828891)
			(xy 32.941086 -350.88966) (xy 32.880319 -350.945059) (xy 32.8147 -350.994614) (xy 32.744788 -351.037902)
			(xy 32.67118 -351.074555) (xy 32.594505 -351.10426) (xy 32.515415 -351.126764) (xy 32.434586 -351.141873)
			(xy 32.352708 -351.14946) (xy 32.311594 -351.14992) (xy 32.269984 -351.149442) (xy 32.187127 -351.141665)
			(xy 32.105358 -351.12619) (xy 32.025391 -351.10315) (xy 31.947922 -351.072748) (xy 31.873629 -351.035248)
			(xy 31.838138 -351.013522) (xy 31.82903 -351.008297) (xy 31.808293 -351.005101) (xy 31.788008 -351.010462)
			(xy 31.779464 -351.01657) (xy 31.745831 -351.042555) (xy 31.674437 -351.08868) (xy 31.598967 -351.127782)
			(xy 31.52011 -351.159503) (xy 31.438585 -351.183553) (xy 31.355138 -351.199714) (xy 31.270529 -351.207838)
			(xy 31.22803 -351.20834) (xy 31.186915 -351.207873) (xy 31.105035 -351.200288) (xy 31.024205 -351.185181)
			(xy 30.945114 -351.162679) (xy 30.868436 -351.132976) (xy 30.794826 -351.096324) (xy 30.724912 -351.053036)
			(xy 30.65929 -351.003482) (xy 30.598521 -350.948084) (xy 30.543123 -350.887316) (xy 30.493568 -350.821695)
			(xy 30.45028 -350.751781) (xy 30.413628 -350.678172) (xy 30.383923 -350.601494) (xy 30.361421 -350.522403)
			(xy 30.346313 -350.441573) (xy 30.338727 -350.359693) (xy 30.338268 -350.318578) (xy 30.33884 -350.273809)
			(xy 30.347847 -350.184724) (xy 30.36575 -350.096993) (xy 30.392366 -350.011501) (xy 30.409388 -349.97009)
			(xy 30.412968 -349.960503) (xy 30.41296 -349.940056) (xy 30.409388 -349.930466) (xy 30.392363 -349.889123)
			(xy 30.365757 -349.803758) (xy 30.347856 -349.716153) (xy 30.338841 -349.627193) (xy 30.338268 -349.582486)
			(xy 30.338268 -349.58147) (xy 30.338522 -349.57004) (xy 30.312044 -349.564091) (xy 30.259809 -349.54935)
			(xy 30.234128 -349.540576) (xy 30.225931 -349.538062) (xy 30.208797 -349.538062) (xy 30.2006 -349.540576)
			(xy 30.16538 -349.552528) (xy 30.093379 -349.571185) (xy 30.020059 -349.583696) (xy 29.945944 -349.589972)
			(xy 29.908754 -349.59036) (xy 29.871565 -349.589952) (xy 29.797452 -349.583667) (xy 29.724133 -349.571163)
			(xy 29.652126 -349.552528) (xy 29.616908 -349.540576) (xy 29.608711 -349.538062) (xy 29.591577 -349.538062)
			(xy 29.58338 -349.540576) (xy 29.548162 -349.552533) (xy 29.47616 -349.571189) (xy 29.402839 -349.583699)
			(xy 29.328724 -349.589973) (xy 29.291534 -349.59036) (xy 29.249596 -349.589881) (xy 29.166099 -349.581908)
			(xy 29.083738 -349.566035) (xy 29.003259 -349.542404) (xy 28.92539 -349.511231) (xy 28.850838 -349.472797)
			(xy 28.780276 -349.42745) (xy 28.714345 -349.375601) (xy 28.65364 -349.317719) (xy 28.598712 -349.25433)
			(xy 28.550059 -349.186006) (xy 28.508121 -349.113367) (xy 28.473277 -349.03707) (xy 28.445844 -348.957807)
			(xy 28.426069 -348.876294) (xy 28.414132 -348.793272) (xy 28.410141 -348.70949) (xy 2.509012 -348.70949)
			(xy 2.509012 -351.637854) (xy 73.92162 -351.637854) (xy 73.922073 -351.597287) (xy 73.929469 -351.516491)
			(xy 73.944194 -351.436705) (xy 73.966127 -351.358593) (xy 73.995085 -351.282803) (xy 74.012552 -351.246186)
			(xy 74.016468 -351.237096) (xy 74.017766 -351.217362) (xy 74.015092 -351.207832) (xy 74.000912 -351.162806)
			(xy 73.981012 -351.070523) (xy 73.971009 -350.97665) (xy 73.970388 -350.929448) (xy 73.970892 -350.887087)
			(xy 73.978945 -350.80275) (xy 73.994979 -350.71956) (xy 74.018847 -350.63827) (xy 74.050335 -350.559618)
			(xy 74.089157 -350.484315) (xy 74.13496 -350.413043) (xy 74.187331 -350.346447) (xy 74.245796 -350.285132)
			(xy 74.309824 -350.229651) (xy 74.378836 -350.180508) (xy 74.452206 -350.138148) (xy 74.529271 -350.102953)
			(xy 74.609333 -350.075244) (xy 74.691666 -350.05527) (xy 74.775525 -350.043213) (xy 74.86015 -350.039182)
			(xy 74.944775 -350.043213) (xy 75.028634 -350.05527) (xy 75.110967 -350.075244) (xy 75.191029 -350.102953)
			(xy 75.268094 -350.138148) (xy 75.341464 -350.180508) (xy 75.410476 -350.229651) (xy 75.474504 -350.285132)
			(xy 75.532969 -350.346447) (xy 75.58534 -350.413043) (xy 75.631143 -350.484315) (xy 75.669965 -350.559618)
			(xy 75.701453 -350.63827) (xy 75.725321 -350.71956) (xy 75.741355 -350.80275) (xy 75.749408 -350.887087)
			(xy 75.749912 -350.929448) (xy 75.749456 -350.970015) (xy 75.742061 -351.05081) (xy 75.727336 -351.130596)
			(xy 75.705403 -351.208709) (xy 75.676446 -351.284499) (xy 75.65898 -351.321116) (xy 75.655063 -351.330206)
			(xy 75.653765 -351.34994) (xy 75.65644 -351.35947) (xy 75.670621 -351.404496) (xy 75.69052 -351.496779)
			(xy 75.700524 -351.590652) (xy 75.70064 -351.5995) (xy 76.58354 -351.5995) (xy 76.583977 -351.558938)
			(xy 76.59131 -351.478148) (xy 76.605978 -351.398363) (xy 76.62786 -351.320247) (xy 76.656772 -351.244452)
			(xy 76.674218 -351.207832) (xy 76.67814 -351.198816) (xy 76.679575 -351.179224) (xy 76.677012 -351.169732)
			(xy 76.662856 -351.124831) (xy 76.642989 -351.0328) (xy 76.632962 -350.939185) (xy 76.632308 -350.89211)
			(xy 76.632308 -350.891094) (xy 76.632812 -350.848746) (xy 76.640863 -350.764432) (xy 76.656892 -350.681266)
			(xy 76.680753 -350.599999) (xy 76.712232 -350.521369) (xy 76.751043 -350.446088) (xy 76.796833 -350.374836)
			(xy 76.849189 -350.30826) (xy 76.907637 -350.246962) (xy 76.971647 -350.191497) (xy 77.040639 -350.142368)
			(xy 77.113989 -350.100019) (xy 77.191032 -350.064835) (xy 77.271071 -350.037133) (xy 77.35338 -350.017165)
			(xy 77.437215 -350.005112) (xy 77.521816 -350.001082) (xy 77.606417 -350.005112) (xy 77.690252 -350.017165)
			(xy 77.772561 -350.037133) (xy 77.8526 -350.064835) (xy 77.929643 -350.100019) (xy 78.002993 -350.142368)
			(xy 78.071985 -350.191497) (xy 78.135995 -350.246962) (xy 78.194443 -350.30826) (xy 78.246799 -350.374836)
			(xy 78.292589 -350.446088) (xy 78.3314 -350.521369) (xy 78.362879 -350.599999) (xy 78.38674 -350.681266)
			(xy 78.402769 -350.764432) (xy 78.41082 -350.848746) (xy 78.411324 -350.891094) (xy 78.411324 -350.891602)
			(xy 78.410897 -350.932113) (xy 78.403528 -351.0128) (xy 78.388844 -351.09248) (xy 78.366965 -351.170492)
			(xy 78.338074 -351.246189) (xy 78.320646 -351.282762) (xy 78.316728 -351.291779) (xy 78.315288 -351.31137)
			(xy 78.317852 -351.320862) (xy 78.33205 -351.365927) (xy 78.351954 -351.458296) (xy 78.361947 -351.552255)
			(xy 78.362556 -351.5995) (xy 78.362003 -351.645139) (xy 78.352699 -351.735943) (xy 78.334149 -351.825316)
			(xy 78.3209 -351.868994) (xy 78.318454 -351.878006) (xy 78.319496 -351.896634) (xy 78.322932 -351.905316)
			(xy 78.341634 -351.948394) (xy 78.370914 -352.03763) (xy 78.390624 -352.129456) (xy 78.400545 -352.222848)
			(xy 78.401164 -352.269806) (xy 78.401164 -352.27006) (xy 78.400635 -352.313006) (xy 78.392335 -352.398495)
			(xy 78.375846 -352.482789) (xy 78.351322 -352.565106) (xy 78.335632 -352.605086) (xy 78.332346 -352.614331)
			(xy 78.332359 -352.633935) (xy 78.335632 -352.643186) (xy 78.351338 -352.683162) (xy 78.375884 -352.765474)
			(xy 78.392373 -352.84977) (xy 78.400651 -352.935265) (xy 78.401164 -352.978212) (xy 78.40066 -353.020573)
			(xy 78.392607 -353.10491) (xy 78.376573 -353.1881) (xy 78.352705 -353.26939) (xy 78.346936 -353.2838)
			(xy 182.729656 -353.2838) (xy 182.733646 -353.200045) (xy 182.745579 -353.117047) (xy 182.765347 -353.035561)
			(xy 182.792771 -352.956321) (xy 182.827603 -352.880048) (xy 182.869527 -352.807431) (xy 182.918163 -352.739127)
			(xy 182.973072 -352.675756) (xy 183.033756 -352.617891) (xy 183.099666 -352.566056) (xy 183.170204 -352.520721)
			(xy 183.244732 -352.482296) (xy 183.322575 -352.451129) (xy 183.403028 -352.427503) (xy 183.485362 -352.411631)
			(xy 183.568833 -352.403656) (xy 183.610758 -352.403156) (xy 183.611774 -352.403156) (xy 183.648831 -352.403571)
			(xy 183.72268 -352.409833) (xy 183.795742 -352.422272) (xy 183.867502 -352.440802) (xy 183.902604 -352.452686)
			(xy 183.910801 -352.4552) (xy 183.927935 -352.4552) (xy 183.936132 -352.452686) (xy 183.964337 -352.443048)
			(xy 184.021791 -352.42716) (xy 184.05094 -352.420936) (xy 184.060579 -352.41851) (xy 184.077071 -352.407448)
			(xy 184.088123 -352.390948) (xy 184.090564 -352.381312) (xy 184.100088 -352.337416) (xy 184.126813 -352.251655)
			(xy 184.143904 -352.210116) (xy 184.147468 -352.200525) (xy 184.147469 -352.180082) (xy 184.143904 -352.170492)
			(xy 184.126892 -352.12911) (xy 184.100271 -352.043685) (xy 184.082363 -351.956018) (xy 184.073351 -351.866996)
			(xy 184.072784 -351.822258) (xy 184.072784 -351.822004) (xy 184.073288 -351.779656) (xy 184.081339 -351.695342)
			(xy 184.097368 -351.612176) (xy 184.121229 -351.530909) (xy 184.152708 -351.452279) (xy 184.191519 -351.376998)
			(xy 184.237309 -351.305746) (xy 184.289665 -351.23917) (xy 184.348113 -351.177872) (xy 184.412123 -351.122407)
			(xy 184.481115 -351.073278) (xy 184.554465 -351.030929) (xy 184.631508 -350.995745) (xy 184.711547 -350.968043)
			(xy 184.793856 -350.948075) (xy 184.877691 -350.936022) (xy 184.962292 -350.931992) (xy 185.046893 -350.936022)
			(xy 185.130728 -350.948075) (xy 185.213037 -350.968043) (xy 185.293076 -350.995745) (xy 185.370119 -351.030929)
			(xy 185.443469 -351.073278) (xy 185.512461 -351.122407) (xy 185.576471 -351.177872) (xy 185.634919 -351.23917)
			(xy 185.687275 -351.305746) (xy 185.733065 -351.376998) (xy 185.771876 -351.452279) (xy 185.803355 -351.530909)
			(xy 185.827216 -351.612176) (xy 185.843245 -351.695342) (xy 185.851296 -351.779656) (xy 185.8518 -351.822004)
			(xy 185.8518 -351.822258) (xy 185.851234 -351.866996) (xy 185.842218 -351.956018) (xy 185.824312 -352.043685)
			(xy 185.797698 -352.129113) (xy 185.78068 -352.170492) (xy 185.777112 -352.180082) (xy 185.777113 -352.200525)
			(xy 185.78068 -352.210116) (xy 185.797704 -352.251527) (xy 185.824339 -352.337015) (xy 185.842246 -352.424746)
			(xy 185.851245 -352.513834) (xy 185.8518 -352.558604) (xy 185.85116 -352.609084) (xy 185.839825 -352.709404)
			(xy 185.829194 -352.758756) (xy 185.826997 -352.771225) (xy 185.833664 -352.795617) (xy 185.841894 -352.805238)
			(xy 185.882534 -352.847656) (xy 185.889646 -352.846132) (xy 185.898412 -352.843862) (xy 185.913646 -352.834103)
			(xy 185.919364 -352.827082) (xy 185.944527 -352.794419) (xy 185.999939 -352.733355) (xy 186.060764 -352.67768)
			(xy 186.126478 -352.627872) (xy 186.196519 -352.584357) (xy 186.270286 -352.547509) (xy 186.347146 -352.517645)
			(xy 186.426439 -352.49502) (xy 186.507485 -352.479828) (xy 186.589589 -352.472201) (xy 186.630818 -352.471736)
			(xy 186.671925 -352.472195) (xy 186.753788 -352.479781) (xy 186.834603 -352.494887) (xy 186.913679 -352.517383)
			(xy 186.990343 -352.547078) (xy 187.06394 -352.583719) (xy 187.133844 -352.626993) (xy 187.199457 -352.676531)
			(xy 187.260221 -352.73191) (xy 187.315617 -352.792659) (xy 187.365173 -352.85826) (xy 187.408465 -352.928152)
			(xy 187.445126 -353.001739) (xy 187.474841 -353.078395) (xy 187.497359 -353.157466) (xy 187.512486 -353.238276)
			(xy 187.519078 -353.3092) (xy 191.056256 -353.3092) (xy 191.060246 -353.225443) (xy 191.07218 -353.142444)
			(xy 191.091948 -353.060956) (xy 191.119373 -352.981715) (xy 191.154206 -352.90544) (xy 191.196132 -352.832822)
			(xy 191.244771 -352.764518) (xy 191.299682 -352.701146) (xy 191.360368 -352.643281) (xy 191.42628 -352.591447)
			(xy 191.49682 -352.546112) (xy 191.57135 -352.507688) (xy 191.649196 -352.476522) (xy 191.729651 -352.452897)
			(xy 191.811988 -352.437027) (xy 191.89546 -352.429055) (xy 191.937386 -352.428556) (xy 191.938402 -352.428556)
			(xy 191.975459 -352.428963) (xy 192.049308 -352.435227) (xy 192.12237 -352.447669) (xy 192.194131 -352.466201)
			(xy 192.229232 -352.478086) (xy 192.237429 -352.4806) (xy 192.254563 -352.4806) (xy 192.26276 -352.478086)
			(xy 192.290041 -352.468747) (xy 192.345585 -352.453243) (xy 192.373758 -352.447098) (xy 192.383527 -352.444576)
			(xy 192.400163 -352.433196) (xy 192.411142 -352.416293) (xy 192.413382 -352.406458) (xy 192.422838 -352.357349)
			(xy 192.451357 -352.261489) (xy 192.470278 -352.215196) (xy 192.473919 -352.205632) (xy 192.474045 -352.185185)
			(xy 192.470532 -352.175572) (xy 192.453515 -352.134192) (xy 192.426895 -352.048766) (xy 192.408989 -351.961099)
			(xy 192.399978 -351.872077) (xy 192.399412 -351.827338) (xy 192.399412 -351.827084) (xy 192.399916 -351.784736)
			(xy 192.407967 -351.700422) (xy 192.423996 -351.617256) (xy 192.447857 -351.535989) (xy 192.479336 -351.457359)
			(xy 192.518147 -351.382078) (xy 192.563937 -351.310826) (xy 192.616293 -351.24425) (xy 192.674741 -351.182952)
			(xy 192.738751 -351.127487) (xy 192.807743 -351.078358) (xy 192.881093 -351.036009) (xy 192.958136 -351.000825)
			(xy 193.038175 -350.973123) (xy 193.120484 -350.953155) (xy 193.204319 -350.941102) (xy 193.28892 -350.937072)
			(xy 193.373521 -350.941102) (xy 193.457356 -350.953155) (xy 193.539665 -350.973123) (xy 193.619704 -351.000825)
			(xy 193.696747 -351.036009) (xy 193.770097 -351.078358) (xy 193.839089 -351.127487) (xy 193.903099 -351.182952)
			(xy 193.961547 -351.24425) (xy 194.013903 -351.310826) (xy 194.059693 -351.382078) (xy 194.098504 -351.457359)
			(xy 194.129983 -351.535989) (xy 194.153844 -351.617256) (xy 194.169873 -351.700422) (xy 194.177924 -351.784736)
			(xy 194.178428 -351.827084) (xy 194.178428 -351.827338) (xy 194.177853 -351.872076) (xy 194.168839 -351.961098)
			(xy 194.150936 -352.048765) (xy 194.124325 -352.134193) (xy 194.107308 -352.175572) (xy 194.10375 -352.185165)
			(xy 194.103744 -352.205606) (xy 194.107308 -352.215196) (xy 194.12436 -352.256596) (xy 194.150986 -352.342088)
			(xy 194.165052 -352.41103) (xy 206.449676 -352.41103) (xy 206.449676 -351.54743) (xy 206.450162 -351.520179)
			(xy 206.457918 -351.466231) (xy 206.473273 -351.413936) (xy 206.495915 -351.364359) (xy 206.525381 -351.318509)
			(xy 206.561072 -351.277318) (xy 206.602263 -351.241627) (xy 206.648113 -351.212161) (xy 206.69769 -351.189519)
			(xy 206.749985 -351.174164) (xy 206.803933 -351.166408) (xy 206.858435 -351.166408) (xy 206.912383 -351.174164)
			(xy 206.964678 -351.189519) (xy 207.014255 -351.212161) (xy 207.060105 -351.241627) (xy 207.101296 -351.277318)
			(xy 207.136987 -351.318509) (xy 207.166453 -351.364359) (xy 207.189095 -351.413936) (xy 207.20445 -351.466231)
			(xy 207.212206 -351.520179) (xy 207.212692 -351.54743) (xy 207.212692 -352.41103) (xy 207.212206 -352.438281)
			(xy 207.20445 -352.492229) (xy 207.189095 -352.544524) (xy 207.166453 -352.594101) (xy 207.136987 -352.639951)
			(xy 207.101296 -352.681142) (xy 207.060105 -352.716833) (xy 207.014255 -352.746299) (xy 206.964678 -352.768941)
			(xy 206.912383 -352.784296) (xy 206.858435 -352.792052) (xy 206.803933 -352.792052) (xy 206.749985 -352.784296)
			(xy 206.69769 -352.768941) (xy 206.648113 -352.746299) (xy 206.602263 -352.716833) (xy 206.561072 -352.681142)
			(xy 206.525381 -352.639951) (xy 206.495915 -352.594101) (xy 206.473273 -352.544524) (xy 206.457918 -352.492229)
			(xy 206.450162 -352.438281) (xy 206.449676 -352.41103) (xy 194.165052 -352.41103) (xy 194.168886 -352.429823)
			(xy 194.177877 -352.518913) (xy 194.178428 -352.563684) (xy 194.178055 -352.600778) (xy 194.171875 -352.674709)
			(xy 194.159556 -352.747868) (xy 194.150742 -352.783902) (xy 194.149 -352.792252) (xy 194.15051 -352.809229)
			(xy 194.157543 -352.824754) (xy 194.163188 -352.831146) (xy 194.203574 -352.874326) (xy 194.216274 -352.871532)
			(xy 194.225043 -352.869274) (xy 194.240276 -352.859506) (xy 194.245992 -352.852482) (xy 194.271138 -352.819805)
			(xy 194.326552 -352.758742) (xy 194.387379 -352.703068) (xy 194.453095 -352.65326) (xy 194.523138 -352.609746)
			(xy 194.596907 -352.5729) (xy 194.673768 -352.543037) (xy 194.753063 -352.520414) (xy 194.834111 -352.505225)
			(xy 194.916217 -352.4976) (xy 194.957446 -352.497136) (xy 194.998553 -352.497569) (xy 195.080417 -352.505157)
			(xy 195.161232 -352.520265) (xy 195.240309 -352.542764) (xy 195.316973 -352.572461) (xy 195.390571 -352.609104)
			(xy 195.460474 -352.652379) (xy 195.526087 -352.701919) (xy 195.586851 -352.757301) (xy 195.642247 -352.818051)
			(xy 195.691802 -352.883653) (xy 195.735094 -352.953546) (xy 195.744851 -352.973132) (xy 338.849208 -352.973132)
			(xy 338.849825 -352.926972) (xy 338.859426 -352.835153) (xy 338.878488 -352.744823) (xy 338.906804 -352.656953)
			(xy 338.9249 -352.614484) (xy 338.928699 -352.60454) (xy 338.928703 -352.583278) (xy 338.9249 -352.573336)
			(xy 338.90688 -352.530918) (xy 338.878719 -352.443158) (xy 338.859786 -352.352956) (xy 338.850284 -352.26128)
			(xy 338.849716 -352.215196) (xy 338.850295 -352.1688) (xy 338.859941 -352.076512) (xy 338.879138 -351.985728)
			(xy 338.907678 -351.897435) (xy 338.925916 -351.85477) (xy 338.929722 -351.844828) (xy 338.929721 -351.823565)
			(xy 338.925916 -351.813622) (xy 338.907694 -351.771019) (xy 338.879176 -351.682852) (xy 338.859983 -351.592196)
			(xy 338.850324 -351.500036) (xy 338.849716 -351.453704) (xy 338.849716 -351.453196) (xy 338.850148 -351.412092)
			(xy 338.857734 -351.330235) (xy 338.87284 -351.249427) (xy 338.895338 -351.170357) (xy 338.925036 -351.093701)
			(xy 338.96168 -351.020112) (xy 339.004958 -350.950218) (xy 339.0545 -350.884616) (xy 339.109884 -350.823864)
			(xy 339.170637 -350.768482) (xy 339.236241 -350.718942) (xy 339.306137 -350.675666) (xy 339.379727 -350.639025)
			(xy 339.456384 -350.609329) (xy 339.535454 -350.586834) (xy 339.616263 -350.57173) (xy 339.69812 -350.564147)
			(xy 339.739224 -350.563688) (xy 339.739732 -350.563688) (xy 339.786063 -350.564321) (xy 339.87822 -350.573985)
			(xy 339.968874 -350.593172) (xy 340.057044 -350.621677) (xy 340.09965 -350.639888) (xy 340.109592 -350.643694)
			(xy 340.130856 -350.643694) (xy 340.140798 -350.639888) (xy 340.183427 -350.621646) (xy 340.271658 -350.593118)
			(xy 340.36238 -350.573927) (xy 340.454606 -350.564283) (xy 340.50097 -350.563688) (xy 340.501478 -350.563688)
			(xy 340.547841 -350.56431) (xy 340.640063 -350.57396) (xy 340.730782 -350.593148) (xy 340.819014 -350.621665)
			(xy 340.86165 -350.639888) (xy 340.871592 -350.643694) (xy 340.892856 -350.643694) (xy 340.902798 -350.639888)
			(xy 340.945427 -350.621646) (xy 341.033658 -350.593118) (xy 341.12438 -350.573927) (xy 341.216606 -350.564283)
			(xy 341.26297 -350.563688) (xy 341.263478 -350.563688) (xy 341.309841 -350.56431) (xy 341.402063 -350.57396)
			(xy 341.492782 -350.593148) (xy 341.581014 -350.621665) (xy 341.62365 -350.639888) (xy 341.633592 -350.643694)
			(xy 341.654856 -350.643694) (xy 341.664798 -350.639888) (xy 341.707427 -350.621646) (xy 341.795658 -350.593118)
			(xy 341.88638 -350.573927) (xy 341.978606 -350.564283) (xy 342.02497 -350.563688) (xy 342.025478 -350.563688)
			(xy 342.071841 -350.56431) (xy 342.164063 -350.57396) (xy 342.254782 -350.593148) (xy 342.343014 -350.621665)
			(xy 342.38565 -350.639888) (xy 342.395592 -350.643694) (xy 342.416856 -350.643694) (xy 342.426798 -350.639888)
			(xy 342.469427 -350.621646) (xy 342.557658 -350.593118) (xy 342.64838 -350.573927) (xy 342.740606 -350.564283)
			(xy 342.78697 -350.563688) (xy 342.787478 -350.563688) (xy 342.833911 -350.564319) (xy 342.926269 -350.574013)
			(xy 343.017117 -350.593266) (xy 343.105468 -350.621869) (xy 343.148158 -350.640142) (xy 343.156911 -350.643584)
			(xy 343.175683 -350.644482) (xy 343.184734 -350.64192) (xy 343.229904 -350.627586) (xy 343.322519 -350.607479)
			(xy 343.416748 -350.597344) (xy 343.464134 -350.596708) (xy 343.465404 -350.596708) (xy 343.506508 -350.597148)
			(xy 343.588364 -350.604734) (xy 343.669172 -350.61984) (xy 343.748241 -350.642338) (xy 343.824897 -350.672035)
			(xy 343.898486 -350.708679) (xy 343.968379 -350.751956) (xy 344.033982 -350.801498) (xy 344.094733 -350.856881)
			(xy 344.150115 -350.917634) (xy 344.199655 -350.983237) (xy 344.242931 -351.053132) (xy 344.279573 -351.126721)
			(xy 344.309269 -351.203378) (xy 344.331765 -351.282448) (xy 344.346869 -351.363255) (xy 344.354453 -351.445112)
			(xy 344.354912 -351.486216) (xy 344.354912 -351.486724) (xy 344.354311 -351.533056) (xy 344.344638 -351.625214)
			(xy 344.325441 -351.715868) (xy 344.296928 -351.804037) (xy 344.278712 -351.846642) (xy 344.274897 -351.856581)
			(xy 344.274903 -351.877848) (xy 344.278712 -351.88779) (xy 344.296962 -351.93045) (xy 344.325505 -352.018743)
			(xy 344.344696 -352.109529) (xy 344.354328 -352.20182) (xy 344.354912 -352.248216) (xy 344.354328 -352.294369)
			(xy 344.344776 -352.386179) (xy 344.325776 -352.476508) (xy 344.297531 -352.564386) (xy 344.279474 -352.606864)
			(xy 344.275648 -352.6168) (xy 344.275662 -352.638069) (xy 344.279474 -352.648012) (xy 344.29749 -352.690438)
			(xy 344.325707 -352.77819) (xy 344.344711 -352.868387) (xy 344.354297 -352.960064) (xy 344.354912 -353.006152)
			(xy 344.354402 -353.047262) (xy 344.34922 -353.1032) (xy 423.453493 -353.1032) (xy 423.457484 -353.019415)
			(xy 423.469422 -352.936388) (xy 423.489198 -352.854872) (xy 423.516634 -352.775605) (xy 423.55148 -352.699305)
			(xy 423.593421 -352.626663) (xy 423.642078 -352.558337) (xy 423.697009 -352.494945) (xy 423.757718 -352.437063)
			(xy 423.823654 -352.385213) (xy 423.89422 -352.339866) (xy 423.968777 -352.301432) (xy 424.04665 -352.270259)
			(xy 424.127133 -352.24663) (xy 424.209499 -352.230759) (xy 424.293 -352.222789) (xy 424.33494 -352.222308)
			(xy 424.372129 -352.222714) (xy 424.446242 -352.228999) (xy 424.519562 -352.241503) (xy 424.591568 -352.260139)
			(xy 424.626786 -352.272092) (xy 424.634983 -352.274606) (xy 424.652117 -352.274606) (xy 424.660314 -352.272092)
			(xy 424.687596 -352.262757) (xy 424.74314 -352.24725) (xy 424.771312 -352.241104) (xy 424.781089 -352.238609)
			(xy 424.797722 -352.227214) (xy 424.808697 -352.210302) (xy 424.810936 -352.200464) (xy 424.820391 -352.151355)
			(xy 424.84891 -352.055495) (xy 424.867832 -352.009202) (xy 424.871403 -351.999613) (xy 424.871399 -351.979169)
			(xy 424.867832 -351.969578) (xy 424.850786 -351.928175) (xy 424.824155 -351.842685) (xy 424.806254 -351.754951)
			(xy 424.797263 -351.665861) (xy 424.796712 -351.62109) (xy 424.797216 -351.578729) (xy 424.805269 -351.494392)
			(xy 424.821303 -351.411202) (xy 424.845171 -351.329912) (xy 424.876659 -351.25126) (xy 424.915481 -351.175957)
			(xy 424.961284 -351.104685) (xy 425.013655 -351.038089) (xy 425.07212 -350.976774) (xy 425.136148 -350.921293)
			(xy 425.20516 -350.87215) (xy 425.27853 -350.82979) (xy 425.355595 -350.794595) (xy 425.435657 -350.766886)
			(xy 425.51799 -350.746912) (xy 425.601849 -350.734855) (xy 425.686474 -350.730824) (xy 425.771099 -350.734855)
			(xy 425.854958 -350.746912) (xy 425.937291 -350.766886) (xy 426.017353 -350.794595) (xy 426.094418 -350.82979)
			(xy 426.167788 -350.87215) (xy 426.2368 -350.921293) (xy 426.300828 -350.976774) (xy 426.359293 -351.038089)
			(xy 426.411664 -351.104685) (xy 426.457467 -351.175957) (xy 426.496289 -351.25126) (xy 426.527777 -351.329912)
			(xy 426.551645 -351.411202) (xy 426.567679 -351.494392) (xy 426.575732 -351.578729) (xy 426.576236 -351.62109)
			(xy 426.575653 -351.665859) (xy 426.566649 -351.754944) (xy 426.548749 -351.842675) (xy 426.522136 -351.928167)
			(xy 426.505116 -351.969578) (xy 426.501559 -351.979171) (xy 426.501555 -351.999611) (xy 426.505116 -352.009202)
			(xy 426.522153 -352.050608) (xy 426.548787 -352.136097) (xy 426.566691 -352.22383) (xy 426.575684 -352.312919)
			(xy 426.576236 -352.35769) (xy 426.575843 -352.394784) (xy 426.569667 -352.468714) (xy 426.557358 -352.541873)
			(xy 426.54855 -352.577908) (xy 426.5467 -352.586267) (xy 426.54815 -352.603318) (xy 426.55512 -352.618947)
			(xy 426.560742 -352.625406) (xy 426.601128 -352.668332) (xy 426.613574 -352.665538) (xy 426.622391 -352.663274)
			(xy 426.637739 -352.653501) (xy 426.643546 -352.646488) (xy 426.66867 -352.613784) (xy 426.724067 -352.552685)
			(xy 426.784882 -352.496976) (xy 426.850593 -352.447136) (xy 426.920635 -352.403592) (xy 426.994408 -352.366719)
			(xy 427.071277 -352.336834) (xy 427.150582 -352.314192) (xy 427.231643 -352.298989) (xy 427.313763 -352.291354)
			(xy 427.355 -352.290888) (xy 427.396095 -352.291366) (xy 427.477934 -352.298948) (xy 427.558725 -352.314048)
			(xy 427.637779 -352.336536) (xy 427.71442 -352.366221) (xy 427.787997 -352.40285) (xy 427.85788 -352.44611)
			(xy 427.923475 -352.495633) (xy 427.984222 -352.550996) (xy 428.039602 -352.611726) (xy 428.089144 -352.677307)
			(xy 428.132424 -352.747178) (xy 428.169074 -352.820744) (xy 428.198782 -352.897377) (xy 428.221293 -352.976424)
			(xy 428.236416 -353.05721) (xy 428.243051 -353.1286) (xy 431.780208 -353.1286) (xy 431.784199 -353.04482)
			(xy 431.796136 -352.961799) (xy 431.815909 -352.880289) (xy 431.843342 -352.801027) (xy 431.878184 -352.724732)
			(xy 431.92012 -352.652094) (xy 431.968771 -352.583771) (xy 432.023696 -352.520381) (xy 432.084398 -352.4625)
			(xy 432.150327 -352.410651) (xy 432.220886 -352.365303) (xy 432.295436 -352.326868) (xy 432.373301 -352.295693)
			(xy 432.453778 -352.27206) (xy 432.536136 -352.256184) (xy 432.619631 -352.248208) (xy 432.661568 -352.247708)
			(xy 432.698757 -352.248106) (xy 432.77287 -352.254393) (xy 432.84619 -352.2669) (xy 432.918196 -352.285538)
			(xy 432.953414 -352.297492) (xy 432.961611 -352.300006) (xy 432.978745 -352.300006) (xy 432.986942 -352.297492)
			(xy 433.014223 -352.288155) (xy 433.069768 -352.27265) (xy 433.09794 -352.266504) (xy 433.107722 -352.264025)
			(xy 433.124353 -352.252622) (xy 433.135327 -352.235704) (xy 433.137564 -352.225864) (xy 433.147017 -352.176755)
			(xy 433.175537 -352.080895) (xy 433.19446 -352.034602) (xy 433.19803 -352.025013) (xy 433.198026 -352.004569)
			(xy 433.19446 -351.994978) (xy 433.177416 -351.953575) (xy 433.150784 -351.868085) (xy 433.132882 -351.780351)
			(xy 433.123891 -351.691261) (xy 433.12334 -351.64649) (xy 433.123844 -351.604129) (xy 433.131897 -351.519792)
			(xy 433.147931 -351.436602) (xy 433.171799 -351.355312) (xy 433.203287 -351.27666) (xy 433.242109 -351.201357)
			(xy 433.287912 -351.130085) (xy 433.340283 -351.063489) (xy 433.398748 -351.002174) (xy 433.462776 -350.946693)
			(xy 433.531788 -350.89755) (xy 433.605158 -350.85519) (xy 433.682223 -350.819995) (xy 433.762285 -350.792286)
			(xy 433.844618 -350.772312) (xy 433.928477 -350.760255) (xy 434.013102 -350.756224) (xy 434.097727 -350.760255)
			(xy 434.181586 -350.772312) (xy 434.263919 -350.792286) (xy 434.343981 -350.819995) (xy 434.421046 -350.85519)
			(xy 434.494416 -350.89755) (xy 434.563428 -350.946693) (xy 434.627456 -351.002174) (xy 434.685921 -351.063489)
			(xy 434.738292 -351.130085) (xy 434.784095 -351.201357) (xy 434.822917 -351.27666) (xy 434.854405 -351.355312)
			(xy 434.878273 -351.436602) (xy 434.894307 -351.519792) (xy 434.90236 -351.604129) (xy 434.902864 -351.64649)
			(xy 434.902279 -351.691259) (xy 434.893275 -351.780343) (xy 434.875376 -351.868074) (xy 434.848764 -351.953566)
			(xy 434.831744 -351.994978) (xy 434.828186 -352.00457) (xy 434.828182 -352.025011) (xy 434.831744 -352.034602)
			(xy 434.848782 -352.076008) (xy 434.875415 -352.161497) (xy 434.893319 -352.24923) (xy 434.902312 -352.338319)
			(xy 434.902864 -352.38309) (xy 434.90247 -352.420184) (xy 434.896295 -352.494114) (xy 434.883986 -352.567273)
			(xy 434.875178 -352.603308) (xy 434.873347 -352.611669) (xy 434.874795 -352.628716) (xy 434.881755 -352.644345)
			(xy 434.88737 -352.650806) (xy 434.927756 -352.693732) (xy 434.940202 -352.690938) (xy 434.94901 -352.688645)
			(xy 434.964363 -352.678893) (xy 434.970174 -352.671888) (xy 434.995281 -352.639171) (xy 435.05068 -352.578072)
			(xy 435.111497 -352.522364) (xy 435.17721 -352.472524) (xy 435.247255 -352.428982) (xy 435.321029 -352.39211)
			(xy 435.3979 -352.362226) (xy 435.477207 -352.339586) (xy 435.558269 -352.324385) (xy 435.64039 -352.316753)
			(xy 435.681628 -352.316288) (xy 435.722723 -352.31674) (xy 435.804563 -352.324324) (xy 435.885355 -352.339426)
			(xy 435.964409 -352.361917) (xy 436.04105 -352.391604) (xy 436.114627 -352.428235) (xy 436.18451 -352.471497)
			(xy 436.250105 -352.521022) (xy 436.310851 -352.576386) (xy 436.366231 -352.637118) (xy 436.415773 -352.7027)
			(xy 436.459053 -352.772572) (xy 436.495703 -352.846139) (xy 436.52541 -352.922773) (xy 436.547921 -353.001821)
			(xy 436.563044 -353.082609) (xy 436.57065 -353.164447) (xy 436.571136 -353.205542) (xy 436.571136 -353.20605)
			(xy 436.570568 -353.25082) (xy 436.561569 -353.339906) (xy 436.543667 -353.427639) (xy 436.517044 -353.513129)
			(xy 436.500016 -353.554538) (xy 436.496425 -353.564121) (xy 436.496444 -353.58457) (xy 436.500016 -353.594162)
			(xy 436.517052 -353.635569) (xy 436.543684 -353.721058) (xy 436.561588 -353.808791) (xy 436.570583 -353.897879)
			(xy 436.571136 -353.94265) (xy 436.570568 -353.98742) (xy 436.561569 -354.076506) (xy 436.543667 -354.164239)
			(xy 436.517044 -354.249729) (xy 436.500016 -354.291138) (xy 436.496425 -354.300721) (xy 436.496444 -354.32117)
			(xy 436.500016 -354.330762) (xy 436.517046 -354.372136) (xy 436.543663 -354.457564) (xy 436.561565 -354.545233)
			(xy 436.570572 -354.634257) (xy 436.571136 -354.678996) (xy 436.571136 -354.67925) (xy 436.57064 -354.720357)
			(xy 436.56306 -354.80222) (xy 436.547959 -354.883035) (xy 436.525468 -354.962112) (xy 436.495777 -355.038776)
			(xy 436.45914 -355.112375) (xy 436.415869 -355.18228) (xy 436.366333 -355.247894) (xy 436.310956 -355.308659)
			(xy 436.250208 -355.364056) (xy 436.184609 -355.413612) (xy 436.114718 -355.456904) (xy 436.041131 -355.493565)
			(xy 435.964475 -355.523279) (xy 435.885405 -355.545796) (xy 435.804595 -355.560921) (xy 435.722735 -355.568527)
			(xy 435.681628 -355.569012) (xy 435.640018 -355.568519) (xy 435.557162 -355.560745) (xy 435.475393 -355.545272)
			(xy 435.395426 -355.522236) (xy 435.317957 -355.491836) (xy 435.243663 -355.454339) (xy 435.208172 -355.432614)
			(xy 435.199049 -355.42742) (xy 435.178322 -355.424214) (xy 435.158043 -355.429561) (xy 435.149498 -355.435662)
			(xy 435.115852 -355.46163) (xy 435.044461 -355.507757) (xy 434.968993 -355.546861) (xy 434.890138 -355.578584)
			(xy 434.808616 -355.602638) (xy 434.72517 -355.618802) (xy 434.640562 -355.626929) (xy 434.598064 -355.627432)
			(xy 434.556969 -355.626968) (xy 434.47513 -355.619383) (xy 434.39434 -355.604281) (xy 434.315287 -355.58179)
			(xy 434.238646 -355.552103) (xy 434.16507 -355.515472) (xy 434.095187 -355.472211) (xy 434.029593 -355.422687)
			(xy 433.968847 -355.367324) (xy 433.913467 -355.306593) (xy 433.863926 -355.241013) (xy 433.820645 -355.171141)
			(xy 433.783995 -355.097576) (xy 433.754287 -355.020943) (xy 433.731775 -354.941896) (xy 433.71665 -354.86111)
			(xy 433.709043 -354.779273) (xy 433.708556 -354.738178) (xy 433.708556 -354.73767) (xy 433.709098 -354.692899)
			(xy 433.718104 -354.603812) (xy 433.736014 -354.51608) (xy 433.762645 -354.430591) (xy 433.779676 -354.389182)
			(xy 433.783256 -354.379596) (xy 433.783245 -354.359149) (xy 433.779676 -354.349558) (xy 433.762646 -354.308149)
			(xy 433.736013 -354.222661) (xy 433.718107 -354.134928) (xy 433.70911 -354.045841) (xy 433.708556 -354.00107)
			(xy 433.708556 -353.989132) (xy 433.682076 -353.983189) (xy 433.629842 -353.968444) (xy 433.604162 -353.959668)
			(xy 433.595965 -353.957154) (xy 433.578831 -353.957154) (xy 433.570634 -353.959668) (xy 433.535422 -353.971642)
			(xy 433.463417 -353.990292) (xy 433.390095 -354.002797) (xy 433.315979 -354.009067) (xy 433.278788 -354.009452)
			(xy 433.241598 -354.009064) (xy 433.167486 -354.002773) (xy 433.094166 -353.990263) (xy 433.02216 -353.971623)
			(xy 432.986942 -353.959668) (xy 432.978745 -353.957154) (xy 432.961611 -353.957154) (xy 432.953414 -353.959668)
			(xy 432.918203 -353.971647) (xy 432.846198 -353.990296) (xy 432.772875 -354.0028) (xy 432.698759 -354.009068)
			(xy 432.661568 -354.009452) (xy 432.619631 -354.008992) (xy 432.536136 -354.001016) (xy 432.453778 -353.98514)
			(xy 432.373301 -353.961507) (xy 432.295436 -353.930332) (xy 432.220886 -353.891897) (xy 432.150327 -353.846549)
			(xy 432.084398 -353.7947) (xy 432.023696 -353.736819) (xy 431.968771 -353.673429) (xy 431.92012 -353.605106)
			(xy 431.878184 -353.532468) (xy 431.843342 -353.456173) (xy 431.815909 -353.376911) (xy 431.796136 -353.295401)
			(xy 431.784199 -353.21238) (xy 431.780208 -353.1286) (xy 428.243051 -353.1286) (xy 428.244022 -353.139047)
			(xy 428.244508 -353.180142) (xy 428.244508 -353.18065) (xy 428.243935 -353.22542) (xy 428.234936 -353.314506)
			(xy 428.217036 -353.402238) (xy 428.190415 -353.487729) (xy 428.173388 -353.529138) (xy 428.169793 -353.53872)
			(xy 428.169812 -353.559171) (xy 428.173388 -353.568762) (xy 428.190428 -353.610167) (xy 428.217058 -353.695657)
			(xy 428.23496 -353.783391) (xy 428.243955 -353.872479) (xy 428.244508 -353.91725) (xy 428.243935 -353.96202)
			(xy 428.234936 -354.051106) (xy 428.217036 -354.138838) (xy 428.190415 -354.224329) (xy 428.173388 -354.265738)
			(xy 428.169793 -354.27532) (xy 428.169812 -354.295771) (xy 428.173388 -354.305362) (xy 428.190417 -354.346737)
			(xy 428.217034 -354.432165) (xy 428.234937 -354.519833) (xy 428.243944 -354.608857) (xy 428.244508 -354.653596)
			(xy 428.244508 -354.65385) (xy 428.24394 -354.694955) (xy 428.23636 -354.776814) (xy 428.221262 -354.857624)
			(xy 428.198773 -354.936698) (xy 428.169085 -355.013359) (xy 428.132451 -355.086955) (xy 428.089184 -355.156857)
			(xy 428.039654 -355.22247) (xy 427.984281 -355.283233) (xy 427.923539 -355.33863) (xy 427.857946 -355.388186)
			(xy 427.788061 -355.431481) (xy 427.714479 -355.468143) (xy 427.63783 -355.497861) (xy 427.558765 -355.520382)
			(xy 427.47796 -355.535512) (xy 427.396104 -355.543124) (xy 427.355 -355.543612) (xy 427.31339 -355.543132)
			(xy 427.230533 -355.535356) (xy 427.148764 -355.519881) (xy 427.068797 -355.496842) (xy 426.991328 -355.46644)
			(xy 426.917035 -355.42894) (xy 426.881544 -355.407214) (xy 426.872433 -355.401996) (xy 426.851698 -355.398798)
			(xy 426.831415 -355.404156) (xy 426.82287 -355.410262) (xy 426.789234 -355.436243) (xy 426.717841 -355.482369)
			(xy 426.642371 -355.521471) (xy 426.563514 -355.553192) (xy 426.481991 -355.577244) (xy 426.398543 -355.593405)
			(xy 426.313935 -355.60153) (xy 426.271436 -355.602032) (xy 426.230342 -355.601499) (xy 426.148505 -355.593921)
			(xy 426.067716 -355.578825) (xy 425.988664 -355.55634) (xy 425.912023 -355.526659) (xy 425.838448 -355.490033)
			(xy 425.768565 -355.446777) (xy 425.70297 -355.397258) (xy 425.642223 -355.341899) (xy 425.586843 -355.281172)
			(xy 425.537301 -355.215595) (xy 425.49402 -355.145727) (xy 425.457368 -355.072164) (xy 425.42766 -354.995534)
			(xy 425.405147 -354.91649) (xy 425.390023 -354.835706) (xy 425.382415 -354.753872) (xy 425.381928 -354.712778)
			(xy 425.381928 -354.71227) (xy 425.382471 -354.667499) (xy 425.391478 -354.578412) (xy 425.409387 -354.49068)
			(xy 425.436017 -354.40519) (xy 425.453048 -354.363782) (xy 425.45663 -354.354196) (xy 425.456619 -354.333749)
			(xy 425.453048 -354.324158) (xy 425.436017 -354.28275) (xy 425.409384 -354.197261) (xy 425.391479 -354.109528)
			(xy 425.382482 -354.020441) (xy 425.381928 -353.97567) (xy 425.381928 -353.963732) (xy 425.35545 -353.957782)
			(xy 425.303215 -353.943042) (xy 425.277534 -353.934268) (xy 425.269337 -353.931754) (xy 425.252203 -353.931754)
			(xy 425.244006 -353.934268) (xy 425.208787 -353.946222) (xy 425.136785 -353.964878) (xy 425.063465 -353.977388)
			(xy 424.98935 -353.983664) (xy 424.95216 -353.984052) (xy 424.914971 -353.983643) (xy 424.840858 -353.977359)
			(xy 424.767539 -353.964855) (xy 424.695532 -353.94622) (xy 424.660314 -353.934268) (xy 424.652117 -353.931754)
			(xy 424.634983 -353.931754) (xy 424.626786 -353.934268) (xy 424.591569 -353.946227) (xy 424.519566 -353.964882)
			(xy 424.446245 -353.977391) (xy 424.37213 -353.983665) (xy 424.33494 -353.984052) (xy 424.293 -353.983611)
			(xy 424.209499 -353.975641) (xy 424.127133 -353.95977) (xy 424.04665 -353.936141) (xy 423.968777 -353.904968)
			(xy 423.89422 -353.866534) (xy 423.823654 -353.821187) (xy 423.757718 -353.769337) (xy 423.697009 -353.711455)
			(xy 423.642078 -353.648063) (xy 423.593421 -353.579737) (xy 423.55148 -353.507095) (xy 423.516634 -353.430795)
			(xy 423.489198 -353.351528) (xy 423.469422 -353.270012) (xy 423.457484 -353.186985) (xy 423.453493 -353.1032)
			(xy 344.34922 -353.1032) (xy 344.346818 -353.129131) (xy 344.331712 -353.20995) (xy 344.309211 -353.289031)
			(xy 344.279508 -353.365698) (xy 344.242856 -353.439296) (xy 344.199569 -353.509197) (xy 344.150015 -353.574806)
			(xy 344.094618 -353.635561) (xy 344.03385 -353.690944) (xy 343.968231 -353.740483) (xy 343.898319 -353.783755)
			(xy 343.824713 -353.82039) (xy 343.748039 -353.850075) (xy 343.668954 -353.872558) (xy 343.58813 -353.887646)
			(xy 343.50626 -353.895211) (xy 343.46515 -353.89566) (xy 343.421566 -353.895134) (xy 343.334811 -353.886653)
			(xy 343.249302 -353.869729) (xy 343.165858 -353.844524) (xy 343.085279 -353.81128) (xy 343.046558 -353.791266)
			(xy 343.035092 -353.785848) (xy 343.009764 -353.785848) (xy 342.998298 -353.791266) (xy 342.959077 -353.812027)
			(xy 342.877306 -353.846516) (xy 342.792508 -353.872694) (xy 342.705525 -353.890299) (xy 342.617221 -353.899159)
			(xy 342.572848 -353.899724) (xy 342.571578 -353.899724) (xy 342.533421 -353.899288) (xy 342.457393 -353.892705)
			(xy 342.382209 -353.879623) (xy 342.308424 -353.86014) (xy 342.272366 -353.847654) (xy 342.26405 -353.845068)
			(xy 342.246646 -353.845068) (xy 342.23833 -353.847654) (xy 342.202121 -353.860189) (xy 342.128019 -353.879707)
			(xy 342.052513 -353.892787) (xy 341.976163 -353.899332) (xy 341.937848 -353.899724) (xy 341.899532 -353.899341)
			(xy 341.823179 -353.892813) (xy 341.747672 -353.879733) (xy 341.673573 -353.860197) (xy 341.637366 -353.847654)
			(xy 341.62905 -353.845068) (xy 341.611646 -353.845068) (xy 341.60333 -353.847654) (xy 341.567121 -353.860189)
			(xy 341.493019 -353.879707) (xy 341.417513 -353.892787) (xy 341.341163 -353.899332) (xy 341.302848 -353.899724)
			(xy 341.264532 -353.899341) (xy 341.188179 -353.892813) (xy 341.112672 -353.879733) (xy 341.038573 -353.860197)
			(xy 341.002366 -353.847654) (xy 340.99405 -353.845068) (xy 340.976646 -353.845068) (xy 340.96833 -353.847654)
			(xy 340.932121 -353.860189) (xy 340.858019 -353.879707) (xy 340.782513 -353.892787) (xy 340.706163 -353.899332)
			(xy 340.667848 -353.899724) (xy 340.626539 -353.899263) (xy 340.544274 -353.89164) (xy 340.463071 -353.876418)
			(xy 340.38363 -353.853729) (xy 340.306637 -353.823768) (xy 340.232755 -353.786793) (xy 340.19744 -353.765358)
			(xy 340.189803 -353.761082) (xy 340.172701 -353.75742) (xy 340.155358 -353.759679) (xy 340.147402 -353.763326)
			(xy 340.109501 -353.782381) (xy 340.030769 -353.813979) (xy 339.949386 -353.837938) (xy 339.866091 -353.85404)
			(xy 339.781642 -353.862138) (xy 339.739224 -353.86264) (xy 339.73897 -353.86264) (xy 339.697862 -353.862216)
			(xy 339.615997 -353.854629) (xy 339.535181 -353.839522) (xy 339.456103 -353.817024) (xy 339.379438 -353.787327)
			(xy 339.30584 -353.750684) (xy 339.235936 -353.707408) (xy 339.170322 -353.657867) (xy 339.109558 -353.602485)
			(xy 339.054162 -353.541734) (xy 339.004606 -353.476131) (xy 338.961314 -353.406237) (xy 338.924655 -353.332646)
			(xy 338.89494 -353.255988) (xy 338.872425 -353.176916) (xy 338.857299 -353.096103) (xy 338.849693 -353.01424)
			(xy 338.849208 -352.973132) (xy 195.744851 -352.973132) (xy 195.771754 -353.027135) (xy 195.80147 -353.103792)
			(xy 195.823987 -353.182863) (xy 195.839114 -353.263674) (xy 195.846722 -353.345537) (xy 195.847208 -353.386644)
			(xy 195.846646 -353.431414) (xy 195.837635 -353.520499) (xy 195.81973 -353.60823) (xy 195.793111 -353.693721)
			(xy 195.776088 -353.735132) (xy 195.772497 -353.744715) (xy 195.772513 -353.765165) (xy 195.776088 -353.774756)
			(xy 195.793114 -353.816166) (xy 195.81975 -353.901654) (xy 195.837657 -353.989386) (xy 195.846654 -354.078474)
			(xy 195.847208 -354.123244) (xy 195.846646 -354.168014) (xy 195.837635 -354.257099) (xy 195.81973 -354.34483)
			(xy 195.793111 -354.430321) (xy 195.776088 -354.471732) (xy 195.772497 -354.481315) (xy 195.772513 -354.501765)
			(xy 195.776088 -354.511356) (xy 195.793114 -354.552766) (xy 195.81975 -354.638254) (xy 195.837657 -354.725986)
			(xy 195.846654 -354.815074) (xy 195.847208 -354.859844) (xy 195.84679 -354.900955) (xy 195.839198 -354.982827)
			(xy 195.824083 -355.063648) (xy 195.801575 -355.14273) (xy 195.771864 -355.219398) (xy 195.742079 -355.279198)
			(xy 285.476188 -355.279198) (xy 285.476597 -355.238082) (xy 285.484185 -355.1562) (xy 285.499295 -355.075367)
			(xy 285.5218 -354.996274) (xy 285.551507 -354.919594) (xy 285.588163 -354.845983) (xy 285.631455 -354.776069)
			(xy 285.681013 -354.710447) (xy 285.736414 -354.649677) (xy 285.797187 -354.594279) (xy 285.862811 -354.544725)
			(xy 285.932729 -354.501438) (xy 286.006342 -354.464786) (xy 286.083023 -354.435084) (xy 286.162118 -354.412584)
			(xy 286.242951 -354.397477) (xy 286.324834 -354.389894) (xy 286.36595 -354.389436) (xy 286.404239 -354.389856)
			(xy 286.480533 -354.39646) (xy 286.555976 -354.409605) (xy 286.630007 -354.429194) (xy 286.666178 -354.44176)
			(xy 286.674615 -354.444411) (xy 286.692285 -354.444411) (xy 286.700722 -354.44176) (xy 286.736903 -354.429226)
			(xy 286.810935 -354.409651) (xy 286.886373 -354.396501) (xy 286.962662 -354.389874) (xy 287.00095 -354.389436)
			(xy 287.039239 -354.389856) (xy 287.115533 -354.39646) (xy 287.190976 -354.409605) (xy 287.265007 -354.429194)
			(xy 287.301178 -354.44176) (xy 287.309615 -354.444411) (xy 287.327285 -354.444411) (xy 287.335722 -354.44176)
			(xy 287.371903 -354.429226) (xy 287.445935 -354.409651) (xy 287.521373 -354.396501) (xy 287.597662 -354.389874)
			(xy 287.63595 -354.389436) (xy 287.674239 -354.389856) (xy 287.750533 -354.39646) (xy 287.825976 -354.409605)
			(xy 287.900007 -354.429194) (xy 287.936178 -354.44176) (xy 287.944615 -354.444411) (xy 287.962285 -354.444411)
			(xy 287.970722 -354.44176) (xy 288.006903 -354.429226) (xy 288.080935 -354.409651) (xy 288.156373 -354.396501)
			(xy 288.232662 -354.389874) (xy 288.27095 -354.389436) (xy 288.309239 -354.389856) (xy 288.385533 -354.39646)
			(xy 288.460976 -354.409605) (xy 288.535007 -354.429194) (xy 288.571178 -354.44176) (xy 288.579615 -354.444411)
			(xy 288.597285 -354.444411) (xy 288.605722 -354.44176) (xy 288.641903 -354.429226) (xy 288.715935 -354.409651)
			(xy 288.791373 -354.396501) (xy 288.867662 -354.389874) (xy 288.90595 -354.389436) (xy 288.947064 -354.389946)
			(xy 289.028942 -354.397529) (xy 289.10977 -354.412634) (xy 289.18886 -354.435133) (xy 289.265537 -354.464834)
			(xy 289.339146 -354.501483) (xy 289.409059 -354.544768) (xy 289.47468 -354.594319) (xy 289.535449 -354.649714)
			(xy 289.590847 -354.71048) (xy 289.640402 -354.776098) (xy 289.683691 -354.846009) (xy 289.720345 -354.919615)
			(xy 289.75005 -354.99629) (xy 289.772554 -355.075379) (xy 289.787664 -355.156207) (xy 289.795251 -355.238084)
			(xy 289.795712 -355.279198) (xy 289.795298 -355.318061) (xy 289.788487 -355.395488) (xy 289.77495 -355.472025)
			(xy 289.75479 -355.547092) (xy 289.741864 -355.583744) (xy 289.739034 -355.592628) (xy 289.739308 -355.611259)
			(xy 289.742372 -355.620066) (xy 289.757559 -355.659473) (xy 289.781314 -355.740522) (xy 289.797291 -355.823456)
			(xy 289.805346 -355.907529) (xy 289.805872 -355.949758) (xy 289.805454 -355.988048) (xy 289.79885 -356.064341)
			(xy 289.785704 -356.139784) (xy 289.766114 -356.213815) (xy 289.753548 -356.249986) (xy 289.750918 -356.258428)
			(xy 289.750905 -356.276094) (xy 289.753548 -356.28453) (xy 289.766084 -356.32071) (xy 289.785659 -356.394742)
			(xy 289.798808 -356.470181) (xy 289.805435 -356.54647) (xy 289.805872 -356.584758) (xy 289.805362 -356.625872)
			(xy 289.797778 -356.707749) (xy 289.782672 -356.788578) (xy 289.760173 -356.867667) (xy 289.730472 -356.944344)
			(xy 289.693822 -357.017952) (xy 289.650537 -357.087865) (xy 289.600986 -357.153486) (xy 289.545592 -357.214255)
			(xy 289.484826 -357.269653) (xy 289.419208 -357.319208) (xy 289.349298 -357.362497) (xy 289.275691 -357.399151)
			(xy 289.199017 -357.428856) (xy 289.119928 -357.45136) (xy 289.039101 -357.466471) (xy 288.957224 -357.474059)
			(xy 288.91611 -357.47452) (xy 288.87782 -357.474114) (xy 288.801526 -357.467506) (xy 288.726084 -357.454357)
			(xy 288.652053 -357.434764) (xy 288.615882 -357.422196) (xy 288.607445 -357.419545) (xy 288.589775 -357.419545)
			(xy 288.581338 -357.422196) (xy 288.54516 -357.434739) (xy 288.471127 -357.454312) (xy 288.395688 -357.46746)
			(xy 288.319398 -357.474084) (xy 288.28111 -357.47452) (xy 288.24282 -357.474114) (xy 288.166526 -357.467506)
			(xy 288.091084 -357.454357) (xy 288.017053 -357.434764) (xy 287.980882 -357.422196) (xy 287.972445 -357.419545)
			(xy 287.954775 -357.419545) (xy 287.946338 -357.422196) (xy 287.91016 -357.434739) (xy 287.836127 -357.454312)
			(xy 287.760688 -357.46746) (xy 287.684398 -357.474084) (xy 287.64611 -357.47452) (xy 287.60782 -357.474114)
			(xy 287.531526 -357.467506) (xy 287.456084 -357.454357) (xy 287.382053 -357.434764) (xy 287.345882 -357.422196)
			(xy 287.337445 -357.419545) (xy 287.319775 -357.419545) (xy 287.311338 -357.422196) (xy 287.27516 -357.434739)
			(xy 287.201127 -357.454312) (xy 287.125688 -357.46746) (xy 287.049398 -357.474084) (xy 287.01111 -357.47452)
			(xy 286.97282 -357.474114) (xy 286.896526 -357.467506) (xy 286.821084 -357.454357) (xy 286.747053 -357.434764)
			(xy 286.710882 -357.422196) (xy 286.702445 -357.419545) (xy 286.684775 -357.419545) (xy 286.676338 -357.422196)
			(xy 286.64016 -357.434739) (xy 286.566127 -357.454312) (xy 286.490688 -357.46746) (xy 286.414398 -357.474084)
			(xy 286.37611 -357.47452) (xy 286.334994 -357.474092) (xy 286.253113 -357.466505) (xy 286.172281 -357.451395)
			(xy 286.093188 -357.428892) (xy 286.016509 -357.399186) (xy 285.942899 -357.362532) (xy 285.872984 -357.319241)
			(xy 285.807362 -357.269685) (xy 285.746593 -357.214284) (xy 285.691195 -357.153513) (xy 285.641641 -357.08789)
			(xy 285.598353 -357.017973) (xy 285.561701 -356.944361) (xy 285.531998 -356.867681) (xy 285.509497 -356.788588)
			(xy 285.49439 -356.707755) (xy 285.486807 -356.625874) (xy 285.486348 -356.584758) (xy 285.48677 -356.546469)
			(xy 285.493373 -356.470175) (xy 285.506518 -356.394732) (xy 285.526107 -356.320701) (xy 285.538672 -356.28453)
			(xy 285.541343 -356.276098) (xy 285.541329 -356.258423) (xy 285.538672 -356.249986) (xy 285.526141 -356.213804)
			(xy 285.506565 -356.139773) (xy 285.493414 -356.064334) (xy 285.486786 -355.988046) (xy 285.486348 -355.949758)
			(xy 285.486781 -355.910896) (xy 285.493587 -355.833469) (xy 285.507119 -355.756932) (xy 285.527272 -355.681865)
			(xy 285.540196 -355.645212) (xy 285.542998 -355.636321) (xy 285.542744 -355.617697) (xy 285.539688 -355.60889)
			(xy 285.524486 -355.569489) (xy 285.500735 -355.488437) (xy 285.484763 -355.405502) (xy 285.476712 -355.321427)
			(xy 285.476188 -355.279198) (xy 195.742079 -355.279198) (xy 195.735206 -355.292996) (xy 195.691912 -355.362897)
			(xy 195.642352 -355.428505) (xy 195.586949 -355.48926) (xy 195.526176 -355.544642) (xy 195.460551 -355.59418)
			(xy 195.390636 -355.637451) (xy 195.317025 -355.674085) (xy 195.240348 -355.703769) (xy 195.161258 -355.726251)
			(xy 195.080432 -355.741339) (xy 194.998557 -355.748903) (xy 194.957446 -355.749352) (xy 194.915842 -355.74888)
			(xy 194.832994 -355.741147) (xy 194.75123 -355.725716) (xy 194.671262 -355.702722) (xy 194.593789 -355.672366)
			(xy 194.519488 -355.634911) (xy 194.48399 -355.613208) (xy 194.474858 -355.608031) (xy 194.454138 -355.60482)
			(xy 194.433861 -355.61016) (xy 194.425316 -355.616256) (xy 194.391667 -355.642178) (xy 194.320293 -355.688236)
			(xy 194.244854 -355.727283) (xy 194.166037 -355.758962) (xy 194.08456 -355.782986) (xy 194.001164 -355.799135)
			(xy 193.916608 -355.807262) (xy 193.874136 -355.807772) (xy 193.873882 -355.807772) (xy 193.832775 -355.807305)
			(xy 193.750912 -355.799719) (xy 193.670098 -355.784614) (xy 193.591023 -355.762118) (xy 193.514359 -355.732423)
			(xy 193.440762 -355.695782) (xy 193.370859 -355.652509) (xy 193.305245 -355.602971) (xy 193.244482 -355.547592)
			(xy 193.189086 -355.486844) (xy 193.13953 -355.421244) (xy 193.096237 -355.351353) (xy 193.059577 -355.277766)
			(xy 193.029861 -355.201111) (xy 193.007343 -355.122041) (xy 192.992215 -355.041231) (xy 192.984607 -354.959371)
			(xy 192.98412 -354.918264) (xy 192.984683 -354.873494) (xy 192.993693 -354.784409) (xy 193.011598 -354.696678)
			(xy 193.038217 -354.611187) (xy 193.05524 -354.569776) (xy 193.058825 -354.560191) (xy 193.058812 -354.539743)
			(xy 193.05524 -354.530152) (xy 193.03824 -354.4888) (xy 193.011628 -354.403438) (xy 192.99372 -354.315836)
			(xy 192.984697 -354.226879) (xy 192.98412 -354.182172) (xy 192.98412 -354.181156) (xy 192.984374 -354.169726)
			(xy 192.957895 -354.163781) (xy 192.90566 -354.149038) (xy 192.87998 -354.140262) (xy 192.871783 -354.137748)
			(xy 192.854649 -354.137748) (xy 192.846452 -354.140262) (xy 192.811236 -354.152209) (xy 192.739226 -354.170796)
			(xy 192.665903 -354.183236) (xy 192.591792 -354.18944) (xy 192.554606 -354.189792) (xy 192.517422 -354.189422)
			(xy 192.443314 -354.1832) (xy 192.369994 -354.170758) (xy 192.297983 -354.152184) (xy 192.26276 -354.140262)
			(xy 192.254563 -354.137748) (xy 192.237429 -354.137748) (xy 192.229232 -354.140262) (xy 192.19413 -354.15215)
			(xy 192.122374 -354.1707) (xy 192.049311 -354.183146) (xy 191.97546 -354.189399) (xy 191.938402 -354.189792)
			(xy 191.937386 -354.189792) (xy 191.89546 -354.189345) (xy 191.811988 -354.181373) (xy 191.729651 -354.165503)
			(xy 191.649196 -354.141878) (xy 191.57135 -354.110712) (xy 191.49682 -354.072288) (xy 191.42628 -354.026953)
			(xy 191.360368 -353.975119) (xy 191.299682 -353.917254) (xy 191.244771 -353.853882) (xy 191.196132 -353.785578)
			(xy 191.154206 -353.71296) (xy 191.119373 -353.636685) (xy 191.091948 -353.557444) (xy 191.07218 -353.475956)
			(xy 191.060246 -353.392957) (xy 191.056256 -353.3092) (xy 187.519078 -353.3092) (xy 187.520094 -353.320137)
			(xy 187.52058 -353.361244) (xy 187.52002 -353.406014) (xy 187.511009 -353.495099) (xy 187.493104 -353.58283)
			(xy 187.466484 -353.668321) (xy 187.44946 -353.709732) (xy 187.44587 -353.719315) (xy 187.445886 -353.739765)
			(xy 187.44946 -353.749356) (xy 187.466484 -353.790767) (xy 187.493121 -353.876254) (xy 187.511029 -353.963986)
			(xy 187.520026 -354.053074) (xy 187.52058 -354.097844) (xy 187.52002 -354.142614) (xy 187.511009 -354.231699)
			(xy 187.493104 -354.31943) (xy 187.466484 -354.404921) (xy 187.44946 -354.446332) (xy 187.44587 -354.455915)
			(xy 187.445886 -354.476365) (xy 187.44946 -354.485956) (xy 187.466484 -354.527367) (xy 187.493121 -354.612854)
			(xy 187.511029 -354.700586) (xy 187.520026 -354.789674) (xy 187.52058 -354.834444) (xy 187.520189 -354.875556)
			(xy 187.512597 -354.957429) (xy 187.497482 -355.038252) (xy 187.474973 -355.117336) (xy 187.445261 -355.194004)
			(xy 187.408601 -355.267604) (xy 187.365306 -355.337506) (xy 187.315744 -355.403115) (xy 187.260339 -355.46387)
			(xy 187.199564 -355.519252) (xy 187.133937 -355.56879) (xy 187.064019 -355.61206) (xy 186.990406 -355.648693)
			(xy 186.913727 -355.678376) (xy 186.834635 -355.700857) (xy 186.753806 -355.715942) (xy 186.67193 -355.723505)
			(xy 186.630818 -355.723952) (xy 186.589214 -355.723494) (xy 186.506365 -355.715758) (xy 186.424601 -355.700325)
			(xy 186.344633 -355.677328) (xy 186.267161 -355.646969) (xy 186.192859 -355.609513) (xy 186.157362 -355.587808)
			(xy 186.148243 -355.582606) (xy 186.127514 -355.579404) (xy 186.107233 -355.584754) (xy 186.098688 -355.590856)
			(xy 186.065049 -355.616791) (xy 185.993673 -355.662848) (xy 185.918232 -355.701893) (xy 185.839413 -355.73357)
			(xy 185.757935 -355.757592) (xy 185.674537 -355.773739) (xy 185.589981 -355.781864) (xy 185.547508 -355.782372)
			(xy 185.547254 -355.782372) (xy 185.506147 -355.781931) (xy 185.424283 -355.774343) (xy 185.343469 -355.759235)
			(xy 185.264393 -355.736737) (xy 185.187729 -355.70704) (xy 185.114132 -355.670398) (xy 185.044229 -355.627122)
			(xy 184.978615 -355.577583) (xy 184.917852 -355.522202) (xy 184.862456 -355.461452) (xy 184.812901 -355.395851)
			(xy 184.769609 -355.325959) (xy 184.732948 -355.252371) (xy 184.703232 -355.175714) (xy 184.680715 -355.096644)
			(xy 184.665587 -355.015833) (xy 184.657979 -354.933971) (xy 184.657492 -354.892864) (xy 184.658057 -354.848094)
			(xy 184.667066 -354.759009) (xy 184.684971 -354.671278) (xy 184.711589 -354.585787) (xy 184.728612 -354.544376)
			(xy 184.732199 -354.534792) (xy 184.732185 -354.514343) (xy 184.728612 -354.504752) (xy 184.711616 -354.463398)
			(xy 184.685002 -354.378037) (xy 184.667093 -354.290435) (xy 184.658069 -354.201478) (xy 184.657492 -354.156772)
			(xy 184.657492 -354.155756) (xy 184.657746 -354.144326) (xy 184.631266 -354.138384) (xy 184.579032 -354.123639)
			(xy 184.553352 -354.114862) (xy 184.545155 -354.112348) (xy 184.528021 -354.112348) (xy 184.519824 -354.114862)
			(xy 184.484602 -354.126789) (xy 184.412594 -354.145381) (xy 184.339273 -354.157827) (xy 184.265163 -354.164037)
			(xy 184.227978 -354.164392) (xy 184.190794 -354.16403) (xy 184.116686 -354.157806) (xy 184.043366 -354.145361)
			(xy 183.971355 -354.126785) (xy 183.936132 -354.114862) (xy 183.927935 -354.112348) (xy 183.910801 -354.112348)
			(xy 183.902604 -354.114862) (xy 183.867505 -354.126757) (xy 183.795747 -354.145305) (xy 183.722684 -354.157749)
			(xy 183.648832 -354.164001) (xy 183.611774 -354.164392) (xy 183.610758 -354.164392) (xy 183.568833 -354.163944)
			(xy 183.485362 -354.155969) (xy 183.403028 -354.140097) (xy 183.322575 -354.11647) (xy 183.244732 -354.085304)
			(xy 183.170204 -354.046879) (xy 183.099666 -354.001544) (xy 183.033756 -353.949709) (xy 182.973072 -353.891844)
			(xy 182.918163 -353.828473) (xy 182.869527 -353.760169) (xy 182.827603 -353.687552) (xy 182.792771 -353.611278)
			(xy 182.765347 -353.532039) (xy 182.745579 -353.450553) (xy 182.733646 -353.367555) (xy 182.729656 -353.2838)
			(xy 78.346936 -353.2838) (xy 78.321217 -353.348042) (xy 78.282395 -353.423345) (xy 78.236592 -353.494617)
			(xy 78.184221 -353.561213) (xy 78.125756 -353.622528) (xy 78.061728 -353.678009) (xy 77.992716 -353.727152)
			(xy 77.919346 -353.769512) (xy 77.842281 -353.804707) (xy 77.762219 -353.832416) (xy 77.679886 -353.85239)
			(xy 77.596027 -353.864447) (xy 77.511402 -353.868479) (xy 77.426777 -353.864447) (xy 77.342918 -353.85239)
			(xy 77.260585 -353.832416) (xy 77.180523 -353.804707) (xy 77.103458 -353.769512) (xy 77.030088 -353.727152)
			(xy 76.961076 -353.678009) (xy 76.897048 -353.622528) (xy 76.838583 -353.561213) (xy 76.786212 -353.494617)
			(xy 76.740409 -353.423345) (xy 76.701587 -353.348042) (xy 76.670099 -353.26939) (xy 76.646231 -353.1881)
			(xy 76.630197 -353.10491) (xy 76.622144 -353.020573) (xy 76.62164 -352.978212) (xy 76.622159 -352.935266)
			(xy 76.630462 -352.849776) (xy 76.646954 -352.765482) (xy 76.671481 -352.683166) (xy 76.687172 -352.643186)
			(xy 76.690418 -352.63393) (xy 76.690431 -352.614336) (xy 76.687172 -352.605086) (xy 76.671458 -352.565114)
			(xy 76.646914 -352.4828) (xy 76.630427 -352.398503) (xy 76.622152 -352.313007) (xy 76.62164 -352.27006)
			(xy 76.62164 -352.269806) (xy 76.622244 -352.224161) (xy 76.631638 -352.133355) (xy 76.650266 -352.043985)
			(xy 76.66355 -352.000312) (xy 76.665996 -351.9913) (xy 76.664956 -351.972672) (xy 76.661518 -351.96399)
			(xy 76.642856 -351.920903) (xy 76.61365 -351.831658) (xy 76.594004 -351.739834) (xy 76.584137 -351.646451)
			(xy 76.58354 -351.5995) (xy 75.70064 -351.5995) (xy 75.701144 -351.637854) (xy 75.70053 -351.683499)
			(xy 75.691141 -351.774304) (xy 75.672516 -351.863674) (xy 75.659234 -351.907348) (xy 75.65681 -351.916364)
			(xy 75.657836 -351.934988) (xy 75.661266 -351.94367) (xy 75.679947 -351.986749) (xy 75.709149 -352.075997)
			(xy 75.728789 -352.167824) (xy 75.738651 -352.261208) (xy 75.739244 -352.30816) (xy 75.738798 -352.348493)
			(xy 75.731529 -352.428831) (xy 75.71702 -352.508181) (xy 75.69539 -352.585893) (xy 75.666817 -352.661328)
			(xy 75.649582 -352.697796) (xy 75.645066 -352.708391) (xy 75.645063 -352.731399) (xy 75.649582 -352.741992)
			(xy 75.666809 -352.778407) (xy 75.695346 -352.853748) (xy 75.716963 -352.931359) (xy 75.731481 -353.010605)
			(xy 75.738782 -353.090838) (xy 75.739244 -353.13112) (xy 75.739244 -353.131374) (xy 75.73874 -353.173735)
			(xy 75.730687 -353.258072) (xy 75.714653 -353.341262) (xy 75.690785 -353.422552) (xy 75.659297 -353.501204)
			(xy 75.620475 -353.576507) (xy 75.574672 -353.647779) (xy 75.522301 -353.714375) (xy 75.463836 -353.77569)
			(xy 75.399808 -353.831171) (xy 75.330796 -353.880314) (xy 75.257426 -353.922674) (xy 75.180361 -353.957869)
			(xy 75.100299 -353.985578) (xy 75.017966 -354.005552) (xy 74.934107 -354.017609) (xy 74.849482 -354.021641)
			(xy 74.764857 -354.017609) (xy 74.680998 -354.005552) (xy 74.598665 -353.985578) (xy 74.518603 -353.957869)
			(xy 74.441538 -353.922674) (xy 74.368168 -353.880314) (xy 74.299156 -353.831171) (xy 74.235128 -353.77569)
			(xy 74.176663 -353.714375) (xy 74.124292 -353.647779) (xy 74.078489 -353.576507) (xy 74.039667 -353.501204)
			(xy 74.008179 -353.422552) (xy 73.984311 -353.341262) (xy 73.968277 -353.258072) (xy 73.960224 -353.173735)
			(xy 73.95972 -353.131374) (xy 73.960164 -353.091034) (xy 73.96747 -353.010685) (xy 73.982028 -352.931329)
			(xy 74.003719 -352.85362) (xy 74.032363 -352.778196) (xy 74.049636 -352.741738) (xy 74.054225 -352.731091)
			(xy 74.054231 -352.707932) (xy 74.049636 -352.697288) (xy 74.032445 -352.660861) (xy 74.003936 -352.58552)
			(xy 73.98236 -352.50791) (xy 73.967893 -352.428665) (xy 73.960655 -352.348437) (xy 73.960228 -352.30816)
			(xy 73.960797 -352.262521) (xy 73.970094 -352.171718) (xy 73.988639 -352.082344) (xy 74.001884 -352.038666)
			(xy 74.004352 -352.029659) (xy 74.003297 -352.011026) (xy 73.999852 -352.002344) (xy 73.981136 -351.959272)
			(xy 73.95186 -351.870033) (xy 73.932154 -351.778206) (xy 73.922237 -351.684813) (xy 73.92162 -351.637854)
			(xy 2.509012 -351.637854) (xy 2.509012 -358.071674) (xy 14.438884 -358.071674) (xy 14.438884 -357.208074)
			(xy 14.43937 -357.180805) (xy 14.447132 -357.126821) (xy 14.462497 -357.074491) (xy 14.485154 -357.024881)
			(xy 14.51464 -356.979) (xy 14.550355 -356.937783) (xy 14.591572 -356.902068) (xy 14.637453 -356.872582)
			(xy 14.687063 -356.849925) (xy 14.739393 -356.83456) (xy 14.793377 -356.826798) (xy 14.847915 -356.826798)
			(xy 14.901899 -356.83456) (xy 14.954229 -356.849925) (xy 15.003839 -356.872582) (xy 15.04972 -356.902068)
			(xy 15.090937 -356.937783) (xy 15.126652 -356.979) (xy 15.156138 -357.024881) (xy 15.178795 -357.074491)
			(xy 15.19416 -357.126821) (xy 15.201922 -357.180805) (xy 15.202408 -357.208074) (xy 15.202408 -358.071674)
			(xy 15.201922 -358.098943) (xy 15.19416 -358.152927) (xy 15.178795 -358.205257) (xy 15.156138 -358.254867)
			(xy 15.126652 -358.300748) (xy 15.090937 -358.341965) (xy 15.04972 -358.37768) (xy 15.003839 -358.407166)
			(xy 14.954229 -358.429823) (xy 14.901899 -358.445188) (xy 14.847915 -358.45295) (xy 14.793377 -358.45295)
			(xy 14.739393 -358.445188) (xy 14.687063 -358.429823) (xy 14.637453 -358.407166) (xy 14.591572 -358.37768)
			(xy 14.550355 -358.341965) (xy 14.51464 -358.300748) (xy 14.485154 -358.254867) (xy 14.462497 -358.205257)
			(xy 14.447132 -358.152927) (xy 14.43937 -358.098943) (xy 14.438884 -358.071674) (xy 2.509012 -358.071674)
			(xy 2.509012 -358.549194) (xy 40.47998 -358.549194) (xy 40.47998 -358.548686) (xy 40.480371 -358.510677)
			(xy 40.486871 -358.434938) (xy 40.499812 -358.36003) (xy 40.519101 -358.286501) (xy 40.544596 -358.214886)
			(xy 40.55999 -358.180132) (xy 40.563435 -358.171803) (xy 40.56487 -358.153848) (xy 40.562784 -358.14508)
			(xy 40.551663 -358.104882) (xy 40.536092 -358.022938) (xy 40.528245 -357.939897) (xy 40.527732 -357.898192)
			(xy 40.528135 -357.859902) (xy 40.534744 -357.783608) (xy 40.547894 -357.708165) (xy 40.567488 -357.634135)
			(xy 40.580056 -357.597964) (xy 40.58271 -357.589528) (xy 40.582708 -357.571857) (xy 40.580056 -357.56342)
			(xy 40.567506 -357.527245) (xy 40.547935 -357.453211) (xy 40.53479 -357.37777) (xy 40.528167 -357.30148)
			(xy 40.527732 -357.263192) (xy 40.528236 -357.220831) (xy 40.536289 -357.136494) (xy 40.552323 -357.053304)
			(xy 40.576191 -356.972014) (xy 40.607679 -356.893362) (xy 40.646501 -356.818059) (xy 40.692304 -356.746787)
			(xy 40.744675 -356.680191) (xy 40.80314 -356.618876) (xy 40.867168 -356.563395) (xy 40.93618 -356.514252)
			(xy 41.00955 -356.471892) (xy 41.086615 -356.436697) (xy 41.166677 -356.408988) (xy 41.24901 -356.389014)
			(xy 41.332869 -356.376957) (xy 41.417494 -356.372926) (xy 41.502119 -356.376957) (xy 41.585978 -356.389014)
			(xy 41.668311 -356.408988) (xy 41.748373 -356.436697) (xy 41.825438 -356.471892) (xy 41.898808 -356.514252)
			(xy 41.96782 -356.563395) (xy 42.031848 -356.618876) (xy 42.090313 -356.680191) (xy 42.142684 -356.746787)
			(xy 42.188487 -356.818059) (xy 42.227309 -356.893362) (xy 42.258797 -356.972014) (xy 42.282665 -357.053304)
			(xy 42.298699 -357.136494) (xy 42.306752 -357.220831) (xy 42.307256 -357.263192) (xy 42.306849 -357.301482)
			(xy 42.300241 -357.377776) (xy 42.287093 -357.453218) (xy 42.2675 -357.527249) (xy 42.254932 -357.56342)
			(xy 42.252286 -357.571858) (xy 42.252283 -357.589527) (xy 42.254932 -357.597964) (xy 42.267477 -357.634141)
			(xy 42.28705 -357.708174) (xy 42.300196 -357.783614) (xy 42.30682 -357.859904) (xy 42.307256 -357.898192)
			(xy 42.307256 -357.8987) (xy 42.306856 -357.936708) (xy 42.300359 -358.012447) (xy 42.287419 -358.087355)
			(xy 42.268132 -358.160885) (xy 42.242639 -358.2325) (xy 42.227246 -358.267254) (xy 42.223809 -358.275586)
			(xy 42.222368 -358.293538) (xy 42.224452 -358.302306) (xy 42.23557 -358.342505) (xy 42.251142 -358.424449)
			(xy 42.258991 -358.507489) (xy 42.259032 -358.51084) (xy 43.046396 -358.51084) (xy 43.046759 -358.47278)
			(xy 43.053225 -358.396935) (xy 43.066156 -358.321921) (xy 43.085458 -358.248289) (xy 43.110988 -358.176577)
			(xy 43.126406 -358.141778) (xy 43.129746 -358.133421) (xy 43.131033 -358.115482) (xy 43.128946 -358.106726)
			(xy 43.117873 -358.066521) (xy 43.102375 -357.984574) (xy 43.094614 -357.901538) (xy 43.094148 -357.859838)
			(xy 43.094524 -357.821522) (xy 43.101053 -357.745169) (xy 43.114136 -357.669662) (xy 43.133673 -357.595562)
			(xy 43.146218 -357.559356) (xy 43.148787 -357.551035) (xy 43.148799 -357.533636) (xy 43.146218 -357.52532)
			(xy 43.13374 -357.489193) (xy 43.114246 -357.415282) (xy 43.101158 -357.339973) (xy 43.094573 -357.263819)
			(xy 43.094148 -357.2256) (xy 43.094148 -357.224838) (xy 43.094652 -357.18249) (xy 43.102703 -357.098176)
			(xy 43.118732 -357.01501) (xy 43.142593 -356.933743) (xy 43.174072 -356.855113) (xy 43.212883 -356.779832)
			(xy 43.258673 -356.70858) (xy 43.311029 -356.642004) (xy 43.369477 -356.580706) (xy 43.433487 -356.525241)
			(xy 43.502479 -356.476112) (xy 43.575829 -356.433763) (xy 43.652872 -356.398579) (xy 43.732911 -356.370877)
			(xy 43.81522 -356.350909) (xy 43.899055 -356.338856) (xy 43.983656 -356.334826) (xy 44.068257 -356.338856)
			(xy 44.152092 -356.350909) (xy 44.234401 -356.370877) (xy 44.31444 -356.398579) (xy 44.391483 -356.433763)
			(xy 44.464833 -356.476112) (xy 44.533825 -356.525241) (xy 44.597835 -356.580706) (xy 44.656283 -356.642004)
			(xy 44.708639 -356.70858) (xy 44.754429 -356.779832) (xy 44.79324 -356.855113) (xy 44.824719 -356.933743)
			(xy 44.84858 -357.01501) (xy 44.864609 -357.098176) (xy 44.87266 -357.18249) (xy 44.873164 -357.224838)
			(xy 44.873164 -357.2256) (xy 44.87277 -357.263821) (xy 44.866201 -357.339979) (xy 44.853113 -357.415292)
			(xy 44.833602 -357.489202) (xy 44.821094 -357.52532) (xy 44.818487 -357.533631) (xy 44.818499 -357.55104)
			(xy 44.821094 -357.559356) (xy 44.833623 -357.595567) (xy 44.853143 -357.669669) (xy 44.866225 -357.745173)
			(xy 44.872771 -357.821523) (xy 44.873164 -357.859838) (xy 44.872788 -357.897898) (xy 44.866324 -357.973742)
			(xy 44.853395 -358.048756) (xy 44.837736 -358.108504) (xy 46.991016 -358.108504) (xy 46.991016 -358.107996)
			(xy 46.991417 -358.069988) (xy 46.997915 -357.994249) (xy 47.010854 -357.919341) (xy 47.030141 -357.845811)
			(xy 47.055634 -357.774197) (xy 47.071026 -357.739442) (xy 47.074466 -357.731111) (xy 47.075906 -357.713158)
			(xy 47.07382 -357.70439) (xy 47.0627 -357.664192) (xy 47.047129 -357.582247) (xy 47.039281 -357.499207)
			(xy 47.038768 -357.457502) (xy 47.039173 -357.419212) (xy 47.045781 -357.342918) (xy 47.05893 -357.267476)
			(xy 47.078524 -357.193445) (xy 47.091092 -357.157274) (xy 47.09374 -357.148837) (xy 47.093741 -357.131167)
			(xy 47.091092 -357.12273) (xy 47.078546 -357.086553) (xy 47.058974 -357.01252) (xy 47.045827 -356.93708)
			(xy 47.039204 -356.86079) (xy 47.038768 -356.822502) (xy 47.0392 -356.781386) (xy 47.046788 -356.699506)
			(xy 47.061898 -356.618674) (xy 47.084402 -356.539582) (xy 47.114108 -356.462904) (xy 47.150762 -356.389293)
			(xy 47.194052 -356.319379) (xy 47.243609 -356.253758) (xy 47.299008 -356.192989) (xy 47.359779 -356.137591)
			(xy 47.425402 -356.088036) (xy 47.495318 -356.044749) (xy 47.568929 -356.008097) (xy 47.645609 -355.978393)
			(xy 47.724702 -355.955891) (xy 47.805533 -355.940784) (xy 47.887414 -355.933199) (xy 47.92853 -355.93274)
			(xy 47.969637 -355.933252) (xy 48.051499 -355.940877) (xy 48.132307 -355.956023) (xy 48.211373 -355.97856)
			(xy 48.288023 -356.008296) (xy 48.325024 -356.026212) (xy 48.335846 -356.030917) (xy 48.359414 -356.030917)
			(xy 48.370236 -356.026212) (xy 48.407247 -356.008316) (xy 48.483894 -355.978575) (xy 48.562957 -355.956031)
			(xy 48.643763 -355.940876) (xy 48.725623 -355.93324) (xy 48.76673 -355.93274) (xy 48.80502 -355.933136)
			(xy 48.881314 -355.939747) (xy 48.956757 -355.952899) (xy 49.030787 -355.972495) (xy 49.066958 -355.985064)
			(xy 49.075395 -355.987715) (xy 49.093065 -355.987715) (xy 49.101502 -355.985064) (xy 49.137675 -355.972508)
			(xy 49.21171 -355.952938) (xy 49.287151 -355.939795) (xy 49.363442 -355.933174) (xy 49.40173 -355.93274)
			(xy 49.44002 -355.933136) (xy 49.516314 -355.939747) (xy 49.591757 -355.952899) (xy 49.665787 -355.972495)
			(xy 49.701958 -355.985064) (xy 49.710395 -355.987715) (xy 49.728065 -355.987715) (xy 49.736502 -355.985064)
			(xy 49.772675 -355.972508) (xy 49.84671 -355.952938) (xy 49.922151 -355.939795) (xy 49.998442 -355.933174)
			(xy 50.03673 -355.93274) (xy 50.07502 -355.933136) (xy 50.151314 -355.939747) (xy 50.226757 -355.952899)
			(xy 50.300787 -355.972495) (xy 50.336958 -355.985064) (xy 50.345395 -355.987715) (xy 50.363065 -355.987715)
			(xy 50.371502 -355.985064) (xy 50.407675 -355.972508) (xy 50.48171 -355.952938) (xy 50.557151 -355.939795)
			(xy 50.633442 -355.933174) (xy 50.67173 -355.93274) (xy 50.712845 -355.933184) (xy 50.794723 -355.940774)
			(xy 50.875552 -355.955886) (xy 50.954642 -355.978392) (xy 51.031318 -356.008098) (xy 51.104926 -356.044753)
			(xy 51.174838 -356.088043) (xy 51.240458 -356.137599) (xy 51.301225 -356.192997) (xy 51.356622 -356.253767)
			(xy 51.406175 -356.319388) (xy 51.449463 -356.389302) (xy 51.486115 -356.462911) (xy 51.515819 -356.539588)
			(xy 51.538321 -356.618679) (xy 51.55343 -356.699508) (xy 51.561017 -356.781387) (xy 51.561492 -356.822502)
			(xy 51.561091 -356.860792) (xy 51.554482 -356.937086) (xy 51.541332 -357.012529) (xy 51.521737 -357.086559)
			(xy 51.509168 -357.12273) (xy 51.506515 -357.131166) (xy 51.506516 -357.148837) (xy 51.509168 -357.157274)
			(xy 51.521713 -357.193451) (xy 51.541286 -357.267484) (xy 51.554433 -357.342924) (xy 51.561057 -357.419214)
			(xy 51.561492 -357.457502) (xy 51.561492 -357.45801) (xy 51.561093 -357.496018) (xy 51.554594 -357.571757)
			(xy 51.541655 -357.646665) (xy 51.522368 -357.720195) (xy 51.496874 -357.791809) (xy 51.481482 -357.826564)
			(xy 51.478039 -357.834894) (xy 51.476603 -357.852848) (xy 51.478688 -357.861616) (xy 51.48981 -357.901814)
			(xy 51.50538 -357.983758) (xy 51.513227 -358.066799) (xy 51.51374 -358.108504) (xy 51.513251 -358.149614)
			(xy 51.505664 -358.231482) (xy 51.490553 -358.312301) (xy 51.468049 -358.391381) (xy 51.438343 -358.468047)
			(xy 51.401689 -358.541644) (xy 51.3584 -358.611544) (xy 51.308844 -358.677152) (xy 51.253446 -358.737906)
			(xy 51.192678 -358.793289) (xy 51.127058 -358.842827) (xy 51.057146 -358.886099) (xy 50.98354 -358.922734)
			(xy 50.906867 -358.952421) (xy 50.827781 -358.974905) (xy 50.746958 -358.989995) (xy 50.665088 -358.997562)
			(xy 50.623978 -358.998012) (xy 50.585661 -358.99765) (xy 50.509308 -358.991116) (xy 50.433801 -358.97803)
			(xy 50.359702 -358.958488) (xy 50.323496 -358.945942) (xy 50.31518 -358.943356) (xy 50.297776 -358.943356)
			(xy 50.28946 -358.945942) (xy 50.253248 -358.958468) (xy 50.179147 -358.977989) (xy 50.103642 -358.991071)
			(xy 50.027293 -358.997619) (xy 49.988978 -358.998012) (xy 49.950661 -358.99765) (xy 49.874308 -358.991116)
			(xy 49.798801 -358.97803) (xy 49.724702 -358.958488) (xy 49.688496 -358.945942) (xy 49.68018 -358.943356)
			(xy 49.662776 -358.943356) (xy 49.65446 -358.945942) (xy 49.618248 -358.958468) (xy 49.544147 -358.977989)
			(xy 49.468642 -358.991071) (xy 49.392293 -358.997619) (xy 49.353978 -358.998012) (xy 49.315661 -358.99765)
			(xy 49.239308 -358.991116) (xy 49.163801 -358.97803) (xy 49.089702 -358.958488) (xy 49.053496 -358.945942)
			(xy 49.04518 -358.943356) (xy 49.027776 -358.943356) (xy 49.01946 -358.945942) (xy 48.983339 -358.95844)
			(xy 48.909426 -358.977928) (xy 48.834115 -358.99101) (xy 48.757959 -358.99759) (xy 48.71974 -358.998012)
			(xy 48.718978 -358.998012) (xy 48.677876 -358.99753) (xy 48.596022 -358.989953) (xy 48.515216 -358.974857)
			(xy 48.436148 -358.95237) (xy 48.359491 -358.922685) (xy 48.322484 -358.904794) (xy 48.311662 -358.900089)
			(xy 48.288094 -358.900089) (xy 48.277272 -358.904794) (xy 48.240271 -358.922698) (xy 48.163612 -358.952379)
			(xy 48.084542 -358.974864) (xy 48.003735 -358.98996) (xy 47.92188 -358.997539) (xy 47.880778 -358.998012)
			(xy 47.839669 -358.997608) (xy 47.757803 -358.990022) (xy 47.676986 -358.974915) (xy 47.597907 -358.952416)
			(xy 47.52124 -358.922719) (xy 47.447641 -358.886075) (xy 47.377735 -358.842798) (xy 47.312121 -358.793256)
			(xy 47.251356 -358.737873) (xy 47.19596 -358.677119) (xy 47.146405 -358.611515) (xy 47.103114 -358.541618)
			(xy 47.066455 -358.468026) (xy 47.036742 -358.391366) (xy 47.014227 -358.312292) (xy 46.999104 -358.231477)
			(xy 46.9915 -358.149612) (xy 46.991016 -358.108504) (xy 44.837736 -358.108504) (xy 44.834097 -358.122388)
			(xy 44.808571 -358.1941) (xy 44.793154 -358.2289) (xy 44.789778 -358.237249) (xy 44.788481 -358.255202)
			(xy 44.790614 -358.263952) (xy 44.801704 -358.304153) (xy 44.817195 -358.386101) (xy 44.82495 -358.46914)
			(xy 44.825412 -358.51084) (xy 44.824852 -358.556303) (xy 44.815599 -358.646758) (xy 44.797171 -358.735798)
			(xy 44.78401 -358.779318) (xy 44.78146 -358.788893) (xy 44.783017 -358.808626) (xy 44.787058 -358.817672)
			(xy 44.805431 -358.855048) (xy 44.835897 -358.932566) (xy 44.858991 -359.012591) (xy 44.87451 -359.094423)
			(xy 44.882318 -359.177347) (xy 44.882816 -359.218992) (xy 44.882816 -359.219246) (xy 44.882312 -359.261594)
			(xy 44.874261 -359.345908) (xy 44.858232 -359.429074) (xy 44.834371 -359.510341) (xy 44.802892 -359.588971)
			(xy 44.764081 -359.664252) (xy 44.718291 -359.735504) (xy 44.665935 -359.80208) (xy 44.607487 -359.863378)
			(xy 44.543477 -359.918843) (xy 44.474485 -359.967972) (xy 44.401135 -360.010321) (xy 44.324092 -360.045505)
			(xy 44.244053 -360.073207) (xy 44.161744 -360.093175) (xy 44.077909 -360.105228) (xy 43.993308 -360.109259)
			(xy 43.908707 -360.105228) (xy 43.824872 -360.093175) (xy 43.742563 -360.073207) (xy 43.662524 -360.045505)
			(xy 43.585481 -360.010321) (xy 43.512131 -359.967972) (xy 43.443139 -359.918843) (xy 43.379129 -359.863378)
			(xy 43.320681 -359.80208) (xy 43.268325 -359.735504) (xy 43.222535 -359.664252) (xy 43.183724 -359.588971)
			(xy 43.152245 -359.510341) (xy 43.128384 -359.429074) (xy 43.112355 -359.345908) (xy 43.104304 -359.261594)
			(xy 43.1038 -359.219246) (xy 43.1038 -359.218738) (xy 43.104382 -359.17336) (xy 43.113653 -359.083077)
			(xy 43.132063 -358.994207) (xy 43.145202 -358.950768) (xy 43.147759 -358.941194) (xy 43.146197 -358.921461)
			(xy 43.142154 -358.912414) (xy 43.123767 -358.875016) (xy 43.093286 -358.797449) (xy 43.070189 -358.717372)
			(xy 43.054676 -358.635487) (xy 43.046883 -358.552511) (xy 43.046396 -358.51084) (xy 42.259032 -358.51084)
			(xy 42.259504 -358.549194) (xy 42.258889 -358.594663) (xy 42.249552 -358.685121) (xy 42.231047 -358.774157)
			(xy 42.217848 -358.817672) (xy 42.215273 -358.827242) (xy 42.216849 -358.846979) (xy 42.220896 -358.856026)
			(xy 42.239309 -358.893418) (xy 42.269845 -358.970977) (xy 42.292996 -359.051051) (xy 42.308559 -359.132939)
			(xy 42.316398 -359.215923) (xy 42.316908 -359.2576) (xy 42.316404 -359.299961) (xy 42.308351 -359.384298)
			(xy 42.292317 -359.467488) (xy 42.268449 -359.548778) (xy 42.236961 -359.62743) (xy 42.198139 -359.702733)
			(xy 42.152336 -359.774005) (xy 42.099965 -359.840601) (xy 42.0415 -359.901916) (xy 41.977472 -359.957397)
			(xy 41.90846 -360.00654) (xy 41.83509 -360.0489) (xy 41.758025 -360.084095) (xy 41.677963 -360.111804)
			(xy 41.59563 -360.131778) (xy 41.511771 -360.143835) (xy 41.427146 -360.147867) (xy 41.342521 -360.143835)
			(xy 41.258662 -360.131778) (xy 41.176329 -360.111804) (xy 41.096267 -360.084095) (xy 41.019202 -360.0489)
			(xy 40.945832 -360.00654) (xy 40.87682 -359.957397) (xy 40.812792 -359.901916) (xy 40.754327 -359.840601)
			(xy 40.701956 -359.774005) (xy 40.656153 -359.702733) (xy 40.617331 -359.62743) (xy 40.585843 -359.548778)
			(xy 40.561975 -359.467488) (xy 40.545941 -359.384298) (xy 40.537888 -359.299961) (xy 40.537384 -359.2576)
			(xy 40.537998 -359.212131) (xy 40.547335 -359.121673) (xy 40.565841 -359.032637) (xy 40.57904 -358.989122)
			(xy 40.581619 -358.979553) (xy 40.580041 -358.959815) (xy 40.575992 -358.950768) (xy 40.557613 -358.91336)
			(xy 40.527071 -358.835806) (xy 40.503913 -358.755736) (xy 40.488342 -358.673851) (xy 40.480494 -358.59087)
			(xy 40.47998 -358.549194) (xy 2.509012 -358.549194) (xy 2.509012 -361.825848) (xy 5.986007 -361.825848)
			(xy 5.986007 -361.696708) (xy 5.993957 -361.567813) (xy 6.009827 -361.439653) (xy 6.033556 -361.312712)
			(xy 6.065055 -361.187473) (xy 6.104204 -361.06441) (xy 6.150855 -360.943991) (xy 6.20483 -360.826672)
			(xy 6.265925 -360.712898) (xy 6.333908 -360.603101) (xy 6.408522 -360.497698) (xy 6.489483 -360.397088)
			(xy 6.576483 -360.301653) (xy 6.669194 -360.211754) (xy 6.767264 -360.127733) (xy 6.870319 -360.049909)
			(xy 6.97797 -359.978577) (xy 7.089809 -359.914007) (xy 7.20541 -359.856445) (xy 7.324335 -359.806108)
			(xy 7.446134 -359.763188) (xy 7.570344 -359.727847) (xy 7.696493 -359.70022) (xy 7.824105 -359.680411)
			(xy 7.952694 -359.668495) (xy 8.081772 -359.664519) (xy 8.21085 -359.668495) (xy 8.339439 -359.680411)
			(xy 8.467051 -359.70022) (xy 8.5932 -359.727847) (xy 8.71741 -359.763188) (xy 8.839209 -359.806108)
			(xy 8.958134 -359.856445) (xy 9.073735 -359.914007) (xy 9.185574 -359.978577) (xy 9.293225 -360.049909)
			(xy 9.39628 -360.127733) (xy 9.49435 -360.211754) (xy 9.587061 -360.301653) (xy 9.674061 -360.397088)
			(xy 9.689764 -360.416602) (xy 12.542012 -360.416602) (xy 12.542012 -359.553002) (xy 12.542498 -359.525751)
			(xy 12.550254 -359.471803) (xy 12.565609 -359.419508) (xy 12.588251 -359.369931) (xy 12.617717 -359.324081)
			(xy 12.653408 -359.28289) (xy 12.694599 -359.247199) (xy 12.740449 -359.217733) (xy 12.790026 -359.195091)
			(xy 12.842321 -359.179736) (xy 12.896269 -359.17198) (xy 12.950771 -359.17198) (xy 13.004719 -359.179736)
			(xy 13.057014 -359.195091) (xy 13.106591 -359.217733) (xy 13.152441 -359.247199) (xy 13.193632 -359.28289)
			(xy 13.229323 -359.324081) (xy 13.258789 -359.369931) (xy 13.281431 -359.419508) (xy 13.296786 -359.471803)
			(xy 13.304542 -359.525751) (xy 13.305028 -359.553002) (xy 13.305028 -360.416602) (xy 13.304542 -360.443853)
			(xy 13.296786 -360.497801) (xy 13.281431 -360.550096) (xy 13.258789 -360.599673) (xy 13.229323 -360.645523)
			(xy 13.193632 -360.686714) (xy 13.152441 -360.722405) (xy 13.106591 -360.751871) (xy 13.057014 -360.774513)
			(xy 13.004719 -360.789868) (xy 12.950771 -360.797624) (xy 12.896269 -360.797624) (xy 12.842321 -360.789868)
			(xy 12.790026 -360.774513) (xy 12.740449 -360.751871) (xy 12.694599 -360.722405) (xy 12.653408 -360.686714)
			(xy 12.617717 -360.645523) (xy 12.588251 -360.599673) (xy 12.565609 -360.550096) (xy 12.550254 -360.497801)
			(xy 12.542498 -360.443853) (xy 12.542012 -360.416602) (xy 9.689764 -360.416602) (xy 9.755022 -360.497698)
			(xy 9.829636 -360.603101) (xy 9.897619 -360.712898) (xy 9.958714 -360.826672) (xy 10.012689 -360.943991)
			(xy 10.05934 -361.06441) (xy 10.098489 -361.187473) (xy 10.129988 -361.312712) (xy 10.153717 -361.439653)
			(xy 10.169587 -361.567813) (xy 10.177537 -361.696708) (xy 10.178034 -361.761278) (xy 10.177537 -361.825848)
			(xy 10.169587 -361.954743) (xy 10.153717 -362.082903) (xy 10.129988 -362.209844) (xy 10.098489 -362.335083)
			(xy 10.079022 -362.396278) (xy 165.733984 -362.396278) (xy 165.733984 -361.532678) (xy 165.73447 -361.505409)
			(xy 165.742232 -361.451425) (xy 165.757597 -361.399095) (xy 165.780254 -361.349485) (xy 165.80974 -361.303604)
			(xy 165.845455 -361.262387) (xy 165.886672 -361.226672) (xy 165.932553 -361.197186) (xy 165.982163 -361.174529)
			(xy 166.034493 -361.159164) (xy 166.088477 -361.151402) (xy 166.143015 -361.151402) (xy 166.196999 -361.159164)
			(xy 166.249329 -361.174529) (xy 166.298939 -361.197186) (xy 166.34482 -361.226672) (xy 166.386037 -361.262387)
			(xy 166.421752 -361.303604) (xy 166.451238 -361.349485) (xy 166.473895 -361.399095) (xy 166.48926 -361.451425)
			(xy 166.497022 -361.505409) (xy 166.497508 -361.532678) (xy 166.497508 -362.234988) (xy 185.144664 -362.234988)
			(xy 185.144664 -362.23448) (xy 185.145268 -362.188148) (xy 185.154941 -362.09599) (xy 185.174137 -362.005336)
			(xy 185.202649 -361.917167) (xy 185.220864 -361.874562) (xy 185.224678 -361.864622) (xy 185.224673 -361.843356)
			(xy 185.220864 -361.833414) (xy 185.202614 -361.790754) (xy 185.174071 -361.702461) (xy 185.15488 -361.611675)
			(xy 185.145248 -361.519384) (xy 185.144664 -361.472988) (xy 185.145245 -361.426592) (xy 185.154891 -361.334304)
			(xy 185.174088 -361.24352) (xy 185.202626 -361.155227) (xy 185.220864 -361.112562) (xy 185.224678 -361.102622)
			(xy 185.224673 -361.081356) (xy 185.220864 -361.071414) (xy 185.202636 -361.028813) (xy 185.17412 -360.940645)
			(xy 185.154929 -360.849989) (xy 185.145271 -360.757828) (xy 185.144664 -360.711496) (xy 185.144664 -360.710988)
			(xy 185.145155 -360.669886) (xy 185.152741 -360.588033) (xy 185.167846 -360.507229) (xy 185.190343 -360.428164)
			(xy 185.220039 -360.351511) (xy 185.25668 -360.277925) (xy 185.299955 -360.208034) (xy 185.349493 -360.142434)
			(xy 185.404873 -360.081684) (xy 185.465622 -360.026303) (xy 185.531221 -359.976764) (xy 185.601111 -359.933488)
			(xy 185.674696 -359.896845) (xy 185.751348 -359.867148) (xy 185.830414 -359.84465) (xy 185.911217 -359.829543)
			(xy 185.99307 -359.821956) (xy 186.034172 -359.82148) (xy 186.03468 -359.82148) (xy 186.081011 -359.822097)
			(xy 186.173169 -359.831765) (xy 186.263823 -359.850958) (xy 186.351992 -359.879466) (xy 186.394598 -359.89768)
			(xy 186.40454 -359.901486) (xy 186.425804 -359.901486) (xy 186.435746 -359.89768) (xy 186.478352 -359.879466)
			(xy 186.566519 -359.850947) (xy 186.657173 -359.831752) (xy 186.749332 -359.822089) (xy 186.795664 -359.82148)
			(xy 186.796172 -359.82148) (xy 186.837274 -359.821979) (xy 186.919129 -359.829561) (xy 186.999934 -359.844664)
			(xy 187.079001 -359.867158) (xy 187.155656 -359.896852) (xy 187.229243 -359.933492) (xy 187.299136 -359.976765)
			(xy 187.364738 -360.026303) (xy 187.425489 -360.081682) (xy 187.480872 -360.142431) (xy 187.530412 -360.208031)
			(xy 187.573689 -360.277922) (xy 187.610332 -360.351508) (xy 187.640029 -360.428161) (xy 187.662527 -360.507227)
			(xy 187.677633 -360.588032) (xy 187.685219 -360.669886) (xy 187.68568 -360.710988) (xy 187.68568 -360.711496)
			(xy 187.685072 -360.757828) (xy 187.684417 -360.764074) (xy 211.161635 -360.764074) (xy 211.16566 -360.621882)
			(xy 211.177723 -360.480146) (xy 211.197786 -360.33932) (xy 211.225784 -360.199854) (xy 211.261628 -360.062195)
			(xy 211.305202 -359.926785) (xy 211.356367 -359.794057) (xy 211.41496 -359.664436) (xy 211.480791 -359.538338)
			(xy 211.553652 -359.416166) (xy 211.633307 -359.298312) (xy 211.719503 -359.185153) (xy 211.811962 -359.077051)
			(xy 211.91039 -358.974354) (xy 212.014469 -358.87739) (xy 212.123868 -358.78647) (xy 212.238236 -358.701884)
			(xy 212.357205 -358.623904) (xy 212.480396 -358.55278) (xy 212.607413 -358.488739) (xy 212.73785 -358.431987)
			(xy 212.871289 -358.382705) (xy 213.007302 -358.341051) (xy 213.145454 -358.307159) (xy 213.285303 -358.281138)
			(xy 213.426399 -358.26307) (xy 213.568291 -358.253013) (xy 213.710526 -358.251) (xy 213.852646 -358.257037)
			(xy 213.994197 -358.271105) (xy 214.134726 -358.293159) (xy 214.273781 -358.323128) (xy 214.410919 -358.360916)
			(xy 214.545699 -358.406402) (xy 214.67769 -358.45944) (xy 214.806469 -358.519861) (xy 214.931623 -358.58747)
			(xy 215.052751 -358.662052) (xy 215.169467 -358.743368) (xy 215.281395 -358.831156) (xy 215.388177 -358.925136)
			(xy 215.489471 -359.025006) (xy 215.584952 -359.130448) (xy 215.674316 -359.241122) (xy 215.757274 -359.356675)
			(xy 215.833563 -359.476736) (xy 215.902937 -359.600921) (xy 215.965174 -359.728832) (xy 216.020075 -359.860059)
			(xy 216.067463 -359.994182) (xy 216.107188 -360.130771) (xy 216.139121 -360.269389) (xy 216.163162 -360.409591)
			(xy 216.179231 -360.550929) (xy 216.187279 -360.69295) (xy 216.187782 -360.764074) (xy 255.611635 -360.764074)
			(xy 255.61566 -360.621882) (xy 255.627723 -360.480146) (xy 255.647786 -360.33932) (xy 255.675784 -360.199854)
			(xy 255.711628 -360.062195) (xy 255.755202 -359.926785) (xy 255.806367 -359.794057) (xy 255.86496 -359.664436)
			(xy 255.930791 -359.538338) (xy 256.003652 -359.416166) (xy 256.083307 -359.298312) (xy 256.169503 -359.185153)
			(xy 256.261962 -359.077051) (xy 256.36039 -358.974354) (xy 256.464469 -358.87739) (xy 256.573868 -358.78647)
			(xy 256.688236 -358.701884) (xy 256.807205 -358.623904) (xy 256.930396 -358.55278) (xy 257.057413 -358.488739)
			(xy 257.18785 -358.431987) (xy 257.321289 -358.382705) (xy 257.457302 -358.341051) (xy 257.595454 -358.307159)
			(xy 257.735303 -358.281138) (xy 257.876399 -358.26307) (xy 258.018291 -358.253013) (xy 258.160526 -358.251)
			(xy 258.302646 -358.257037) (xy 258.444197 -358.271105) (xy 258.584726 -358.293159) (xy 258.723781 -358.323128)
			(xy 258.860919 -358.360916) (xy 258.995699 -358.406402) (xy 259.12769 -358.45944) (xy 259.256469 -358.519861)
			(xy 259.381623 -358.58747) (xy 259.502751 -358.662052) (xy 259.619467 -358.743368) (xy 259.652996 -358.769666)
			(xy 294.901627 -358.769666) (xy 294.905632 -358.663917) (xy 294.917622 -358.558774) (xy 294.937531 -358.454839)
			(xy 294.965242 -358.352707) (xy 295.000599 -358.252963) (xy 295.043397 -358.156179) (xy 295.093393 -358.062909)
			(xy 295.1503 -357.973688) (xy 295.213791 -357.889025) (xy 295.283503 -357.809407) (xy 295.359037 -357.735289)
			(xy 295.43996 -357.667096) (xy 295.525809 -357.605218) (xy 295.616092 -357.550011) (xy 295.710291 -357.501789)
			(xy 295.807868 -357.460829) (xy 295.908263 -357.427367) (xy 296.010901 -357.401593) (xy 296.115194 -357.383655)
			(xy 296.220545 -357.373656) (xy 296.326351 -357.371653) (xy 296.432005 -357.377658) (xy 296.536902 -357.391637)
			(xy 296.640442 -357.413508) (xy 296.742031 -357.443148) (xy 296.841088 -357.480386) (xy 296.937045 -357.525008)
			(xy 297.029352 -357.57676) (xy 297.117481 -357.635345) (xy 297.200927 -357.700427) (xy 297.279211 -357.771633)
			(xy 297.351886 -357.848556) (xy 297.418536 -357.930756) (xy 297.478778 -358.01776) (xy 297.532267 -358.109071)
			(xy 297.578698 -358.204166) (xy 297.617803 -358.3025) (xy 297.64936 -358.403511) (xy 297.673187 -358.506618)
			(xy 297.689148 -358.611232) (xy 297.697152 -358.716754) (xy 297.697652 -358.769666) (xy 297.697152 -358.822578)
			(xy 297.689148 -358.9281) (xy 297.673187 -359.032714) (xy 297.64936 -359.135821) (xy 297.617803 -359.236832)
			(xy 297.578698 -359.335166) (xy 297.532267 -359.430261) (xy 297.478778 -359.521572) (xy 297.418536 -359.608576)
			(xy 297.351886 -359.690776) (xy 297.279211 -359.767699) (xy 297.200927 -359.838905) (xy 297.117481 -359.903987)
			(xy 297.029352 -359.962572) (xy 296.937045 -360.014324) (xy 296.841088 -360.058946) (xy 296.742031 -360.096184)
			(xy 296.640442 -360.125824) (xy 296.536902 -360.147695) (xy 296.432005 -360.161674) (xy 296.326351 -360.167679)
			(xy 296.220545 -360.165676) (xy 296.115194 -360.155677) (xy 296.010901 -360.137739) (xy 295.908263 -360.111965)
			(xy 295.807868 -360.078503) (xy 295.710291 -360.037543) (xy 295.616092 -359.989321) (xy 295.525809 -359.934114)
			(xy 295.43996 -359.872236) (xy 295.359037 -359.804043) (xy 295.283503 -359.729925) (xy 295.213791 -359.650307)
			(xy 295.1503 -359.565644) (xy 295.093393 -359.476423) (xy 295.043397 -359.383153) (xy 295.000599 -359.286369)
			(xy 294.965242 -359.186625) (xy 294.937531 -359.084493) (xy 294.917622 -358.980558) (xy 294.905632 -358.875415)
			(xy 294.901627 -358.769666) (xy 259.652996 -358.769666) (xy 259.731395 -358.831156) (xy 259.838177 -358.925136)
			(xy 259.939471 -359.025006) (xy 260.034952 -359.130448) (xy 260.124316 -359.241122) (xy 260.207274 -359.356675)
			(xy 260.283563 -359.476736) (xy 260.352937 -359.600921) (xy 260.415174 -359.728832) (xy 260.470075 -359.860059)
			(xy 260.517463 -359.994182) (xy 260.557188 -360.130771) (xy 260.589121 -360.269389) (xy 260.613162 -360.409591)
			(xy 260.629231 -360.550929) (xy 260.637279 -360.69295) (xy 260.637782 -360.764074) (xy 260.637279 -360.835198)
			(xy 260.629231 -360.977219) (xy 260.613162 -361.118557) (xy 260.589121 -361.258759) (xy 260.557188 -361.397377)
			(xy 260.517463 -361.533966) (xy 260.470075 -361.668089) (xy 260.415174 -361.799316) (xy 260.401302 -361.827826)
			(xy 430.615097 -361.827826) (xy 430.619102 -361.722077) (xy 430.631092 -361.616934) (xy 430.651001 -361.512999)
			(xy 430.678712 -361.410867) (xy 430.714069 -361.311123) (xy 430.756867 -361.214339) (xy 430.806863 -361.121069)
			(xy 430.86377 -361.031848) (xy 430.927261 -360.947185) (xy 430.996973 -360.867567) (xy 431.072507 -360.793449)
			(xy 431.15343 -360.725256) (xy 431.239279 -360.663378) (xy 431.329562 -360.608171) (xy 431.423761 -360.559949)
			(xy 431.521338 -360.518989) (xy 431.621733 -360.485527) (xy 431.724371 -360.459753) (xy 431.828664 -360.441815)
			(xy 431.934015 -360.431816) (xy 432.039821 -360.429813) (xy 432.145475 -360.435818) (xy 432.250372 -360.449797)
			(xy 432.353912 -360.471668) (xy 432.455501 -360.501308) (xy 432.554558 -360.538546) (xy 432.650515 -360.583168)
			(xy 432.742822 -360.63492) (xy 432.830951 -360.693505) (xy 432.914397 -360.758587) (xy 432.992681 -360.829793)
			(xy 433.065356 -360.906716) (xy 433.132006 -360.988916) (xy 433.192248 -361.07592) (xy 433.245737 -361.167231)
			(xy 433.292168 -361.262326) (xy 433.331273 -361.36066) (xy 433.36283 -361.461671) (xy 433.370787 -361.496102)
			(xy 434.579776 -361.496102) (xy 434.580404 -361.4497) (xy 434.590093 -361.357403) (xy 434.609347 -361.266617)
			(xy 434.637954 -361.178332) (xy 434.65623 -361.135676) (xy 434.660038 -361.125734) (xy 434.660039 -361.10447)
			(xy 434.65623 -361.094528) (xy 434.637968 -361.051867) (xy 434.609375 -360.963579) (xy 434.590118 -360.872796)
			(xy 434.580405 -360.780503) (xy 434.579776 -360.734102) (xy 434.580404 -360.6877) (xy 434.590093 -360.595403)
			(xy 434.609347 -360.504617) (xy 434.637954 -360.416332) (xy 434.65623 -360.373676) (xy 434.660038 -360.363734)
			(xy 434.660039 -360.34247) (xy 434.65623 -360.332528) (xy 434.637968 -360.289867) (xy 434.609375 -360.201579)
			(xy 434.590118 -360.110796) (xy 434.580405 -360.018503) (xy 434.579776 -359.972102) (xy 434.5802 -359.930986)
			(xy 434.587788 -359.849105) (xy 434.602898 -359.768273) (xy 434.625402 -359.68918) (xy 434.655109 -359.612502)
			(xy 434.691763 -359.538891) (xy 434.735054 -359.468977) (xy 434.784611 -359.403355) (xy 434.840011 -359.342586)
			(xy 434.900783 -359.287188) (xy 434.966406 -359.237634) (xy 435.036323 -359.194346) (xy 435.109935 -359.157694)
			(xy 435.186615 -359.127991) (xy 435.265708 -359.10549) (xy 435.346541 -359.090383) (xy 435.428422 -359.082799)
			(xy 435.469538 -359.08234) (xy 435.51594 -359.082957) (xy 435.608238 -359.09265) (xy 435.699023 -359.111907)
			(xy 435.787308 -359.140517) (xy 435.829964 -359.158794) (xy 435.839906 -359.1626) (xy 435.86117 -359.1626)
			(xy 435.871112 -359.158794) (xy 435.913767 -359.140517) (xy 436.002057 -359.111928) (xy 436.092842 -359.092675)
			(xy 436.185137 -359.082967) (xy 436.231538 -359.08234) (xy 436.272653 -359.082777) (xy 436.354532 -359.090367)
			(xy 436.435361 -359.10548) (xy 436.514451 -359.127986) (xy 436.591127 -359.157693) (xy 436.664735 -359.194349)
			(xy 436.734647 -359.237639) (xy 436.800266 -359.287195) (xy 436.861034 -359.342595) (xy 436.91643 -359.403364)
			(xy 436.965984 -359.468986) (xy 437.009271 -359.5389) (xy 437.045923 -359.61251) (xy 437.075627 -359.689187)
			(xy 437.098129 -359.768278) (xy 437.113238 -359.849108) (xy 437.120825 -359.930987) (xy 437.1213 -359.972102)
			(xy 437.120676 -360.018504) (xy 437.110985 -360.110802) (xy 437.091731 -360.201587) (xy 437.063122 -360.289872)
			(xy 437.044846 -360.332528) (xy 437.041037 -360.34247) (xy 437.041038 -360.363734) (xy 437.044846 -360.373676)
			(xy 437.063108 -360.416337) (xy 437.091701 -360.504625) (xy 437.110959 -360.595408) (xy 437.120671 -360.687701)
			(xy 437.1213 -360.734102) (xy 437.120676 -360.780504) (xy 437.110985 -360.872802) (xy 437.091731 -360.963587)
			(xy 437.063122 -361.051872) (xy 437.044846 -361.094528) (xy 437.041037 -361.10447) (xy 437.041038 -361.125734)
			(xy 437.044846 -361.135676) (xy 437.063108 -361.178337) (xy 437.091701 -361.266625) (xy 437.110959 -361.357408)
			(xy 437.120671 -361.449701) (xy 437.1213 -361.496102) (xy 437.120789 -361.537215) (xy 437.113202 -361.619091)
			(xy 437.098093 -361.699917) (xy 437.075592 -361.779004) (xy 437.045889 -361.855678) (xy 437.009238 -361.929285)
			(xy 436.965952 -361.999196) (xy 436.916401 -362.064814) (xy 436.861007 -362.125581) (xy 436.800242 -362.180978)
			(xy 436.734625 -362.230532) (xy 436.664716 -362.273821) (xy 436.591111 -362.310474) (xy 436.514439 -362.34018)
			(xy 436.435352 -362.362685) (xy 436.354526 -362.377797) (xy 436.272651 -362.385387) (xy 436.231538 -362.385864)
			(xy 436.185135 -362.385256) (xy 436.092838 -362.37556) (xy 436.002052 -362.356301) (xy 435.913768 -362.327688)
			(xy 435.871112 -362.30941) (xy 435.86117 -362.305604) (xy 435.839906 -362.305604) (xy 435.829964 -362.30941)
			(xy 435.787299 -362.327662) (xy 435.699012 -362.356257) (xy 435.608231 -362.375517) (xy 435.515939 -362.385233)
			(xy 435.469538 -362.385864) (xy 435.428424 -362.385365) (xy 435.346546 -362.377782) (xy 435.265717 -362.362675)
			(xy 435.186627 -362.340175) (xy 435.10995 -362.310473) (xy 435.036341 -362.273823) (xy 434.966428 -362.230538)
			(xy 434.900807 -362.180986) (xy 434.840038 -362.12559) (xy 434.78464 -362.064824) (xy 434.735085 -361.999205)
			(xy 434.691796 -361.929294) (xy 434.655143 -361.855686) (xy 434.625438 -361.779011) (xy 434.602934 -361.699922)
			(xy 434.587824 -361.619094) (xy 434.580237 -361.537216) (xy 434.579776 -361.496102) (xy 433.370787 -361.496102)
			(xy 433.386657 -361.564778) (xy 433.402618 -361.669392) (xy 433.410622 -361.774914) (xy 433.411122 -361.827826)
			(xy 433.410622 -361.880738) (xy 433.402618 -361.98626) (xy 433.386657 -362.090874) (xy 433.36283 -362.193981)
			(xy 433.331273 -362.294992) (xy 433.292168 -362.393326) (xy 433.245737 -362.488421) (xy 433.192248 -362.579732)
			(xy 433.132006 -362.666736) (xy 433.065356 -362.748936) (xy 432.992681 -362.825859) (xy 432.914397 -362.897065)
			(xy 432.830951 -362.962147) (xy 432.742822 -363.020732) (xy 432.650515 -363.072484) (xy 432.554558 -363.117106)
			(xy 432.455501 -363.154344) (xy 432.353912 -363.183984) (xy 432.250372 -363.205855) (xy 432.145475 -363.219834)
			(xy 432.039821 -363.225839) (xy 431.934015 -363.223836) (xy 431.828664 -363.213837) (xy 431.724371 -363.195899)
			(xy 431.621733 -363.170125) (xy 431.521338 -363.136663) (xy 431.423761 -363.095703) (xy 431.329562 -363.047481)
			(xy 431.239279 -362.992274) (xy 431.15343 -362.930396) (xy 431.072507 -362.862203) (xy 430.996973 -362.788085)
			(xy 430.927261 -362.708467) (xy 430.86377 -362.623804) (xy 430.806863 -362.534583) (xy 430.756867 -362.441313)
			(xy 430.714069 -362.344529) (xy 430.678712 -362.244785) (xy 430.651001 -362.142653) (xy 430.631092 -362.038718)
			(xy 430.619102 -361.933575) (xy 430.615097 -361.827826) (xy 260.401302 -361.827826) (xy 260.352937 -361.927227)
			(xy 260.283563 -362.051412) (xy 260.207274 -362.171473) (xy 260.124316 -362.287026) (xy 260.034952 -362.3977)
			(xy 259.939471 -362.503142) (xy 259.838177 -362.603012) (xy 259.731395 -362.696992) (xy 259.619467 -362.78478)
			(xy 259.502751 -362.866096) (xy 259.381623 -362.940678) (xy 259.256469 -363.008287) (xy 259.12769 -363.068708)
			(xy 258.995699 -363.121746) (xy 258.860919 -363.167232) (xy 258.723781 -363.20502) (xy 258.584726 -363.234989)
			(xy 258.444197 -363.257043) (xy 258.302646 -363.271111) (xy 258.160526 -363.277148) (xy 258.018291 -363.275135)
			(xy 257.876399 -363.265078) (xy 257.735303 -363.24701) (xy 257.595454 -363.220989) (xy 257.457302 -363.187097)
			(xy 257.321289 -363.145443) (xy 257.18785 -363.096161) (xy 257.057413 -363.039409) (xy 256.930396 -362.975368)
			(xy 256.807205 -362.904244) (xy 256.688236 -362.826264) (xy 256.573868 -362.741678) (xy 256.464469 -362.650758)
			(xy 256.36039 -362.553794) (xy 256.261962 -362.451097) (xy 256.169503 -362.342995) (xy 256.083307 -362.229836)
			(xy 256.003652 -362.111982) (xy 255.930791 -361.98981) (xy 255.86496 -361.863712) (xy 255.806367 -361.734091)
			(xy 255.755202 -361.601363) (xy 255.711628 -361.465953) (xy 255.675784 -361.328294) (xy 255.647786 -361.188828)
			(xy 255.627723 -361.048002) (xy 255.61566 -360.906266) (xy 255.611635 -360.764074) (xy 216.187782 -360.764074)
			(xy 216.187279 -360.835198) (xy 216.179231 -360.977219) (xy 216.163162 -361.118557) (xy 216.139121 -361.258759)
			(xy 216.107188 -361.397377) (xy 216.067463 -361.533966) (xy 216.020075 -361.668089) (xy 215.965174 -361.799316)
			(xy 215.902937 -361.927227) (xy 215.833563 -362.051412) (xy 215.757274 -362.171473) (xy 215.674316 -362.287026)
			(xy 215.584952 -362.3977) (xy 215.489471 -362.503142) (xy 215.388177 -362.603012) (xy 215.281395 -362.696992)
			(xy 215.169467 -362.78478) (xy 215.052751 -362.866096) (xy 214.931623 -362.940678) (xy 214.806469 -363.008287)
			(xy 214.67769 -363.068708) (xy 214.545699 -363.121746) (xy 214.410919 -363.167232) (xy 214.273781 -363.20502)
			(xy 214.134726 -363.234989) (xy 213.994197 -363.257043) (xy 213.852646 -363.271111) (xy 213.710526 -363.277148)
			(xy 213.568291 -363.275135) (xy 213.426399 -363.265078) (xy 213.285303 -363.24701) (xy 213.145454 -363.220989)
			(xy 213.007302 -363.187097) (xy 212.871289 -363.145443) (xy 212.73785 -363.096161) (xy 212.607413 -363.039409)
			(xy 212.480396 -362.975368) (xy 212.357205 -362.904244) (xy 212.238236 -362.826264) (xy 212.123868 -362.741678)
			(xy 212.014469 -362.650758) (xy 211.91039 -362.553794) (xy 211.811962 -362.451097) (xy 211.719503 -362.342995)
			(xy 211.633307 -362.229836) (xy 211.553652 -362.111982) (xy 211.480791 -361.98981) (xy 211.41496 -361.863712)
			(xy 211.356367 -361.734091) (xy 211.305202 -361.601363) (xy 211.261628 -361.465953) (xy 211.225784 -361.328294)
			(xy 211.197786 -361.188828) (xy 211.177723 -361.048002) (xy 211.16566 -360.906266) (xy 211.161635 -360.764074)
			(xy 187.684417 -360.764074) (xy 187.675402 -360.849986) (xy 187.656207 -360.94064) (xy 187.627695 -361.028809)
			(xy 187.60948 -361.071414) (xy 187.605683 -361.081359) (xy 187.605679 -361.10262) (xy 187.60948 -361.112562)
			(xy 187.627719 -361.155227) (xy 187.656265 -361.243518) (xy 187.67546 -361.334302) (xy 187.685094 -361.426592)
			(xy 187.68568 -361.472988) (xy 187.685095 -361.519384) (xy 187.675451 -361.611672) (xy 187.656256 -361.702456)
			(xy 187.627718 -361.790749) (xy 187.60948 -361.833414) (xy 187.605683 -361.843359) (xy 187.605679 -361.86462)
			(xy 187.60948 -361.874562) (xy 187.627696 -361.917167) (xy 187.656216 -362.005334) (xy 187.67541 -362.095988)
			(xy 187.685071 -362.188148) (xy 187.68568 -362.23448) (xy 187.68568 -362.234988) (xy 187.685236 -362.276092)
			(xy 187.677652 -362.357949) (xy 187.664078 -362.430568) (xy 190.281567 -362.430568) (xy 190.285572 -362.324819)
			(xy 190.297562 -362.219676) (xy 190.317471 -362.115741) (xy 190.345182 -362.013609) (xy 190.380539 -361.913865)
			(xy 190.423337 -361.817081) (xy 190.473333 -361.723811) (xy 190.53024 -361.63459) (xy 190.593731 -361.549927)
			(xy 190.663443 -361.470309) (xy 190.738977 -361.396191) (xy 190.8199 -361.327998) (xy 190.905749 -361.26612)
			(xy 190.996032 -361.210913) (xy 191.090231 -361.162691) (xy 191.187808 -361.121731) (xy 191.288203 -361.088269)
			(xy 191.390841 -361.062495) (xy 191.495134 -361.044557) (xy 191.600485 -361.034558) (xy 191.706291 -361.032555)
			(xy 191.811945 -361.03856) (xy 191.916842 -361.052539) (xy 192.020382 -361.07441) (xy 192.121971 -361.10405)
			(xy 192.221028 -361.141288) (xy 192.316985 -361.18591) (xy 192.409292 -361.237662) (xy 192.497421 -361.296247)
			(xy 192.580867 -361.361329) (xy 192.659151 -361.432535) (xy 192.731826 -361.509458) (xy 192.798476 -361.591658)
			(xy 192.858718 -361.678662) (xy 192.912207 -361.769973) (xy 192.958638 -361.865068) (xy 192.997743 -361.963402)
			(xy 193.0293 -362.064413) (xy 193.053127 -362.16752) (xy 193.069088 -362.272134) (xy 193.077092 -362.377656)
			(xy 193.077592 -362.430568) (xy 193.077092 -362.48348) (xy 193.069088 -362.589002) (xy 193.053127 -362.693616)
			(xy 193.0293 -362.796723) (xy 192.997743 -362.897734) (xy 192.958638 -362.996068) (xy 192.912207 -363.091163)
			(xy 192.858718 -363.182474) (xy 192.798476 -363.269478) (xy 192.731826 -363.351678) (xy 192.659151 -363.428601)
			(xy 192.580867 -363.499807) (xy 192.497421 -363.564889) (xy 192.409292 -363.623474) (xy 192.316985 -363.675226)
			(xy 192.221028 -363.719848) (xy 192.121971 -363.757086) (xy 192.020382 -363.786726) (xy 191.916842 -363.808597)
			(xy 191.811945 -363.822576) (xy 191.706291 -363.828581) (xy 191.600485 -363.826578) (xy 191.495134 -363.816579)
			(xy 191.390841 -363.798641) (xy 191.288203 -363.772867) (xy 191.187808 -363.739405) (xy 191.090231 -363.698445)
			(xy 190.996032 -363.650223) (xy 190.905749 -363.595016) (xy 190.8199 -363.533138) (xy 190.738977 -363.464945)
			(xy 190.663443 -363.390827) (xy 190.593731 -363.311209) (xy 190.53024 -363.226546) (xy 190.473333 -363.137325)
			(xy 190.423337 -363.044055) (xy 190.380539 -362.947271) (xy 190.345182 -362.847527) (xy 190.317471 -362.745395)
			(xy 190.297562 -362.64146) (xy 190.285572 -362.536317) (xy 190.281567 -362.430568) (xy 187.664078 -362.430568)
			(xy 187.662547 -362.438757) (xy 187.64005 -362.517826) (xy 187.610354 -362.594483) (xy 187.573711 -362.668072)
			(xy 187.530434 -362.737966) (xy 187.480892 -362.803569) (xy 187.425509 -362.86432) (xy 187.364756 -362.919703)
			(xy 187.299153 -362.969243) (xy 187.229258 -363.012519) (xy 187.155668 -363.04916) (xy 187.079011 -363.078856)
			(xy 186.999941 -363.101351) (xy 186.919133 -363.116454) (xy 186.837276 -363.124037) (xy 186.796172 -363.124496)
			(xy 186.795664 -363.124496) (xy 186.749333 -363.123866) (xy 186.657176 -363.114202) (xy 186.566521 -363.095013)
			(xy 186.478352 -363.066508) (xy 186.435746 -363.048296) (xy 186.425804 -363.04449) (xy 186.40454 -363.04449)
			(xy 186.394598 -363.048296) (xy 186.351999 -363.066527) (xy 186.26383 -363.095042) (xy 186.173173 -363.114232)
			(xy 186.081013 -363.123889) (xy 186.03468 -363.124496) (xy 186.034172 -363.124496) (xy 185.993069 -363.12406)
			(xy 185.911213 -363.116473) (xy 185.830407 -363.101365) (xy 185.751339 -363.078866) (xy 185.674684 -363.049167)
			(xy 185.601097 -363.012522) (xy 185.531204 -362.969244) (xy 185.465603 -362.919702) (xy 185.404853 -362.864319)
			(xy 185.349472 -362.803566) (xy 185.299933 -362.737963) (xy 185.256658 -362.668068) (xy 185.220017 -362.594479)
			(xy 185.190322 -362.517823) (xy 185.167826 -362.438755) (xy 185.152722 -362.357947) (xy 185.145138 -362.276091)
			(xy 185.144664 -362.234988) (xy 166.497508 -362.234988) (xy 166.497508 -362.396278) (xy 166.497022 -362.423547)
			(xy 166.48926 -362.477531) (xy 166.473895 -362.529861) (xy 166.451238 -362.579471) (xy 166.421752 -362.625352)
			(xy 166.386037 -362.666569) (xy 166.34482 -362.702284) (xy 166.298939 -362.73177) (xy 166.249329 -362.754427)
			(xy 166.196999 -362.769792) (xy 166.143015 -362.777554) (xy 166.088477 -362.777554) (xy 166.034493 -362.769792)
			(xy 165.982163 -362.754427) (xy 165.932553 -362.73177) (xy 165.886672 -362.702284) (xy 165.845455 -362.666569)
			(xy 165.80974 -362.625352) (xy 165.780254 -362.579471) (xy 165.757597 -362.529861) (xy 165.742232 -362.477531)
			(xy 165.73447 -362.423547) (xy 165.733984 -362.396278) (xy 10.079022 -362.396278) (xy 10.05934 -362.458146)
			(xy 10.012689 -362.578565) (xy 9.958714 -362.695884) (xy 9.897619 -362.809658) (xy 9.829636 -362.919455)
			(xy 9.755022 -363.024858) (xy 9.674061 -363.125468) (xy 9.587061 -363.220903) (xy 9.49435 -363.310802)
			(xy 9.39628 -363.394823) (xy 9.293225 -363.472647) (xy 9.185574 -363.543979) (xy 9.073735 -363.608549)
			(xy 8.958134 -363.666111) (xy 8.839209 -363.716448) (xy 8.71741 -363.759368) (xy 8.5932 -363.794709)
			(xy 8.467051 -363.822336) (xy 8.339439 -363.842145) (xy 8.21085 -363.854061) (xy 8.081772 -363.858038)
			(xy 7.952694 -363.854061) (xy 7.824105 -363.842145) (xy 7.696493 -363.822336) (xy 7.570344 -363.794709)
			(xy 7.446134 -363.759368) (xy 7.324335 -363.716448) (xy 7.20541 -363.666111) (xy 7.089809 -363.608549)
			(xy 6.97797 -363.543979) (xy 6.870319 -363.472647) (xy 6.767264 -363.394823) (xy 6.669194 -363.310802)
			(xy 6.576483 -363.220903) (xy 6.489483 -363.125468) (xy 6.408522 -363.024858) (xy 6.333908 -362.919455)
			(xy 6.265925 -362.809658) (xy 6.20483 -362.695884) (xy 6.150855 -362.578565) (xy 6.104204 -362.458146)
			(xy 6.065055 -362.335083) (xy 6.033556 -362.209844) (xy 6.009827 -362.082903) (xy 5.993957 -361.954743)
			(xy 5.986007 -361.825848) (xy 2.509012 -361.825848) (xy 2.509012 -369.062565) (xy 44.335754 -369.062565)
			(xy 44.335754 -369.008035) (xy 44.343514 -368.95406) (xy 44.358876 -368.901738) (xy 44.381527 -368.852135)
			(xy 44.411006 -368.806259) (xy 44.446714 -368.765046) (xy 44.487923 -368.729334) (xy 44.533794 -368.699849)
			(xy 44.583395 -368.677192) (xy 44.635715 -368.661824) (xy 44.689689 -368.654057) (xy 44.716954 -368.653568)
			(xy 45.580554 -368.653568) (xy 45.607829 -368.653968) (xy 45.661825 -368.661726) (xy 45.714168 -368.677089)
			(xy 45.763791 -368.699746) (xy 45.809684 -368.729235) (xy 45.850912 -368.764955) (xy 45.886638 -368.80618)
			(xy 45.916132 -368.852069) (xy 45.938795 -368.901689) (xy 45.954164 -368.95403) (xy 45.961928 -369.008025)
			(xy 45.961928 -369.062565) (xy 51.142954 -369.062565) (xy 51.142954 -369.008035) (xy 51.150714 -368.95406)
			(xy 51.166076 -368.901738) (xy 51.188727 -368.852135) (xy 51.218206 -368.806259) (xy 51.253914 -368.765046)
			(xy 51.295123 -368.729334) (xy 51.340994 -368.699849) (xy 51.390595 -368.677192) (xy 51.442915 -368.661824)
			(xy 51.496889 -368.654057) (xy 51.524154 -368.653568) (xy 52.387754 -368.653568) (xy 52.415029 -368.653968)
			(xy 52.469025 -368.661726) (xy 52.521368 -368.677089) (xy 52.570991 -368.699746) (xy 52.616884 -368.729235)
			(xy 52.658112 -368.764955) (xy 52.693838 -368.80618) (xy 52.723332 -368.852069) (xy 52.745995 -368.901689)
			(xy 52.761364 -368.95403) (xy 52.769128 -369.008025) (xy 52.769128 -369.062565) (xy 57.950154 -369.062565)
			(xy 57.950154 -369.008035) (xy 57.957914 -368.95406) (xy 57.973276 -368.901738) (xy 57.995927 -368.852135)
			(xy 58.025406 -368.806259) (xy 58.061114 -368.765046) (xy 58.102323 -368.729334) (xy 58.148194 -368.699849)
			(xy 58.197795 -368.677192) (xy 58.250115 -368.661824) (xy 58.304089 -368.654057) (xy 58.331354 -368.653568)
			(xy 59.194954 -368.653568) (xy 59.222229 -368.653968) (xy 59.276225 -368.661726) (xy 59.328568 -368.677089)
			(xy 59.378191 -368.699746) (xy 59.424084 -368.729235) (xy 59.465312 -368.764955) (xy 59.501038 -368.80618)
			(xy 59.530532 -368.852069) (xy 59.553195 -368.901689) (xy 59.568564 -368.95403) (xy 59.576328 -369.008025)
			(xy 59.576328 -369.062565) (xy 64.757354 -369.062565) (xy 64.757354 -369.008035) (xy 64.765114 -368.95406)
			(xy 64.780476 -368.901738) (xy 64.803127 -368.852135) (xy 64.832606 -368.806259) (xy 64.868314 -368.765046)
			(xy 64.909523 -368.729334) (xy 64.955394 -368.699849) (xy 65.004995 -368.677192) (xy 65.057315 -368.661824)
			(xy 65.111289 -368.654057) (xy 65.138554 -368.653568) (xy 66.002154 -368.653568) (xy 66.029429 -368.653968)
			(xy 66.083425 -368.661726) (xy 66.135768 -368.677089) (xy 66.185391 -368.699746) (xy 66.231284 -368.729235)
			(xy 66.272512 -368.764955) (xy 66.308238 -368.80618) (xy 66.337732 -368.852069) (xy 66.360395 -368.901689)
			(xy 66.375764 -368.95403) (xy 66.383528 -369.008025) (xy 66.383528 -369.062565) (xy 68.160954 -369.062565)
			(xy 68.160954 -369.008035) (xy 68.168714 -368.95406) (xy 68.184076 -368.901738) (xy 68.206727 -368.852135)
			(xy 68.236206 -368.806259) (xy 68.271914 -368.765046) (xy 68.313123 -368.729334) (xy 68.358994 -368.699849)
			(xy 68.408595 -368.677192) (xy 68.460915 -368.661824) (xy 68.514889 -368.654057) (xy 68.542154 -368.653568)
			(xy 69.405754 -368.653568) (xy 69.433029 -368.653968) (xy 69.487025 -368.661726) (xy 69.539368 -368.677089)
			(xy 69.588991 -368.699746) (xy 69.634884 -368.729235) (xy 69.676112 -368.764955) (xy 69.711838 -368.80618)
			(xy 69.741332 -368.852069) (xy 69.763995 -368.901689) (xy 69.779364 -368.95403) (xy 69.787128 -369.008025)
			(xy 69.787128 -369.062569) (xy 76.863431 -369.062569) (xy 76.863431 -369.008031) (xy 76.871193 -368.954048)
			(xy 76.886558 -368.90172) (xy 76.909214 -368.85211) (xy 76.9387 -368.80623) (xy 76.974414 -368.765013)
			(xy 77.015632 -368.729298) (xy 77.061512 -368.699813) (xy 77.111121 -368.677157) (xy 77.16345 -368.661793)
			(xy 77.217433 -368.654031) (xy 77.244702 -368.653568) (xy 78.108302 -368.653568) (xy 78.135573 -368.653995)
			(xy 78.189561 -368.661757) (xy 78.241894 -368.677124) (xy 78.291508 -368.699782) (xy 78.337393 -368.72927)
			(xy 78.378613 -368.764988) (xy 78.414331 -368.806209) (xy 78.443819 -368.852093) (xy 78.466477 -368.901707)
			(xy 78.481843 -368.954041) (xy 78.489606 -369.008029) (xy 78.489606 -369.062569) (xy 83.670631 -369.062569)
			(xy 83.670631 -369.008031) (xy 83.678393 -368.954048) (xy 83.693758 -368.90172) (xy 83.716414 -368.85211)
			(xy 83.7459 -368.80623) (xy 83.781614 -368.765013) (xy 83.822832 -368.729298) (xy 83.868712 -368.699813)
			(xy 83.918321 -368.677157) (xy 83.97065 -368.661793) (xy 84.024633 -368.654031) (xy 84.051902 -368.653568)
			(xy 84.915502 -368.653568) (xy 84.942773 -368.653995) (xy 84.996761 -368.661757) (xy 85.049094 -368.677124)
			(xy 85.098708 -368.699782) (xy 85.144593 -368.72927) (xy 85.185813 -368.764988) (xy 85.221531 -368.806209)
			(xy 85.251019 -368.852093) (xy 85.273677 -368.901707) (xy 85.289043 -368.954041) (xy 85.296806 -369.008029)
			(xy 85.296806 -369.062569) (xy 90.477831 -369.062569) (xy 90.477831 -369.008031) (xy 90.485593 -368.954048)
			(xy 90.500958 -368.90172) (xy 90.523614 -368.85211) (xy 90.5531 -368.80623) (xy 90.588814 -368.765013)
			(xy 90.630032 -368.729298) (xy 90.675912 -368.699813) (xy 90.725521 -368.677157) (xy 90.77785 -368.661793)
			(xy 90.831833 -368.654031) (xy 90.859102 -368.653568) (xy 91.722702 -368.653568) (xy 91.749973 -368.653995)
			(xy 91.803961 -368.661757) (xy 91.856294 -368.677124) (xy 91.905908 -368.699782) (xy 91.951793 -368.72927)
			(xy 91.993013 -368.764988) (xy 92.028731 -368.806209) (xy 92.058219 -368.852093) (xy 92.080877 -368.901707)
			(xy 92.096243 -368.954041) (xy 92.104006 -369.008029) (xy 92.104006 -369.062569) (xy 97.285031 -369.062569)
			(xy 97.285031 -369.008031) (xy 97.292793 -368.954048) (xy 97.308158 -368.90172) (xy 97.330814 -368.85211)
			(xy 97.3603 -368.80623) (xy 97.396014 -368.765013) (xy 97.437232 -368.729298) (xy 97.483112 -368.699813)
			(xy 97.532721 -368.677157) (xy 97.58505 -368.661793) (xy 97.639033 -368.654031) (xy 97.666302 -368.653568)
			(xy 98.529902 -368.653568) (xy 98.557173 -368.653995) (xy 98.611161 -368.661757) (xy 98.663494 -368.677124)
			(xy 98.713108 -368.699782) (xy 98.758993 -368.72927) (xy 98.800213 -368.764988) (xy 98.835931 -368.806209)
			(xy 98.865419 -368.852093) (xy 98.888077 -368.901707) (xy 98.903443 -368.954041) (xy 98.911206 -369.008029)
			(xy 98.911206 -369.062569) (xy 100.688631 -369.062569) (xy 100.688631 -369.008031) (xy 100.696393 -368.954048)
			(xy 100.711758 -368.90172) (xy 100.734414 -368.85211) (xy 100.7639 -368.80623) (xy 100.799614 -368.765013)
			(xy 100.840832 -368.729298) (xy 100.886712 -368.699813) (xy 100.936321 -368.677157) (xy 100.98865 -368.661793)
			(xy 101.042633 -368.654031) (xy 101.069902 -368.653568) (xy 101.933502 -368.653568) (xy 101.960773 -368.653995)
			(xy 102.014761 -368.661757) (xy 102.067094 -368.677124) (xy 102.116708 -368.699782) (xy 102.162593 -368.72927)
			(xy 102.203813 -368.764988) (xy 102.239531 -368.806209) (xy 102.269019 -368.852093) (xy 102.291677 -368.901707)
			(xy 102.307043 -368.954041) (xy 102.314806 -369.008029) (xy 102.314806 -369.062567) (xy 111.435654 -369.062567)
			(xy 111.435654 -369.008033) (xy 111.443415 -368.954054) (xy 111.458779 -368.901729) (xy 111.481433 -368.852123)
			(xy 111.510917 -368.806246) (xy 111.546629 -368.765031) (xy 111.587842 -368.729319) (xy 111.633719 -368.699835)
			(xy 111.683325 -368.677181) (xy 111.73565 -368.661816) (xy 111.789629 -368.654055) (xy 111.816896 -368.653568)
			(xy 112.680496 -368.653568) (xy 112.707769 -368.653971) (xy 112.761761 -368.661734) (xy 112.814098 -368.677101)
			(xy 112.863716 -368.69976) (xy 112.909603 -368.72925) (xy 112.950827 -368.76497) (xy 112.986548 -368.806193)
			(xy 113.016038 -368.852081) (xy 113.038698 -368.901698) (xy 113.054066 -368.954035) (xy 113.061828 -369.008027)
			(xy 113.061828 -369.062567) (xy 118.242854 -369.062567) (xy 118.242854 -369.008033) (xy 118.250615 -368.954054)
			(xy 118.265979 -368.901729) (xy 118.288633 -368.852123) (xy 118.318117 -368.806246) (xy 118.353829 -368.765031)
			(xy 118.395042 -368.729319) (xy 118.440919 -368.699835) (xy 118.490525 -368.677181) (xy 118.54285 -368.661816)
			(xy 118.596829 -368.654055) (xy 118.624096 -368.653568) (xy 119.487696 -368.653568) (xy 119.514969 -368.653971)
			(xy 119.568961 -368.661734) (xy 119.621298 -368.677101) (xy 119.670916 -368.69976) (xy 119.716803 -368.72925)
			(xy 119.758027 -368.76497) (xy 119.793748 -368.806193) (xy 119.823238 -368.852081) (xy 119.845898 -368.901698)
			(xy 119.861266 -368.954035) (xy 119.869028 -369.008027) (xy 119.869028 -369.062567) (xy 125.050054 -369.062567)
			(xy 125.050054 -369.008033) (xy 125.057815 -368.954054) (xy 125.073179 -368.901729) (xy 125.095833 -368.852123)
			(xy 125.125317 -368.806246) (xy 125.161029 -368.765031) (xy 125.202242 -368.729319) (xy 125.248119 -368.699835)
			(xy 125.297725 -368.677181) (xy 125.35005 -368.661816) (xy 125.404029 -368.654055) (xy 125.431296 -368.653568)
			(xy 126.294896 -368.653568) (xy 126.322169 -368.653971) (xy 126.376161 -368.661734) (xy 126.428498 -368.677101)
			(xy 126.478116 -368.69976) (xy 126.524003 -368.72925) (xy 126.565227 -368.76497) (xy 126.600948 -368.806193)
			(xy 126.630438 -368.852081) (xy 126.653098 -368.901698) (xy 126.668466 -368.954035) (xy 126.676228 -369.008027)
			(xy 126.676228 -369.062567) (xy 131.857254 -369.062567) (xy 131.857254 -369.008033) (xy 131.865015 -368.954054)
			(xy 131.880379 -368.901729) (xy 131.903033 -368.852123) (xy 131.932517 -368.806246) (xy 131.968229 -368.765031)
			(xy 132.009442 -368.729319) (xy 132.055319 -368.699835) (xy 132.104925 -368.677181) (xy 132.15725 -368.661816)
			(xy 132.211229 -368.654055) (xy 132.238496 -368.653568) (xy 133.102096 -368.653568) (xy 133.129369 -368.653971)
			(xy 133.183361 -368.661734) (xy 133.235698 -368.677101) (xy 133.285316 -368.69976) (xy 133.331203 -368.72925)
			(xy 133.372427 -368.76497) (xy 133.408148 -368.806193) (xy 133.437638 -368.852081) (xy 133.460298 -368.901698)
			(xy 133.475666 -368.954035) (xy 133.483428 -369.008027) (xy 133.483428 -369.062567) (xy 135.260854 -369.062567)
			(xy 135.260854 -369.008033) (xy 135.268615 -368.954054) (xy 135.283979 -368.901729) (xy 135.306633 -368.852123)
			(xy 135.336117 -368.806246) (xy 135.371829 -368.765031) (xy 135.413042 -368.729319) (xy 135.458919 -368.699835)
			(xy 135.508525 -368.677181) (xy 135.56085 -368.661816) (xy 135.614829 -368.654055) (xy 135.642096 -368.653568)
			(xy 136.505696 -368.653568) (xy 136.532969 -368.653971) (xy 136.586961 -368.661734) (xy 136.639298 -368.677101)
			(xy 136.688916 -368.69976) (xy 136.734803 -368.72925) (xy 136.776027 -368.76497) (xy 136.811748 -368.806193)
			(xy 136.841238 -368.852081) (xy 136.863898 -368.901698) (xy 136.879266 -368.954035) (xy 136.887028 -369.008027)
			(xy 136.887028 -369.062573) (xy 136.879266 -369.116565) (xy 136.863898 -369.168902) (xy 136.841238 -369.218519)
			(xy 136.811748 -369.264407) (xy 136.776027 -369.30563) (xy 136.734803 -369.34135) (xy 136.688916 -369.37084)
			(xy 136.639298 -369.393499) (xy 136.586961 -369.408866) (xy 136.532969 -369.416629) (xy 136.505696 -369.417092)
			(xy 135.642096 -369.417092) (xy 135.614829 -369.416545) (xy 135.56085 -369.408784) (xy 135.508525 -369.393419)
			(xy 135.458919 -369.370765) (xy 135.413042 -369.341281) (xy 135.371829 -369.305569) (xy 135.336117 -369.264354)
			(xy 135.306633 -369.218477) (xy 135.283979 -369.168871) (xy 135.268615 -369.116546) (xy 135.260854 -369.062567)
			(xy 133.483428 -369.062567) (xy 133.483428 -369.062573) (xy 133.475666 -369.116565) (xy 133.460298 -369.168902)
			(xy 133.437638 -369.218519) (xy 133.408148 -369.264407) (xy 133.372427 -369.30563) (xy 133.331203 -369.34135)
			(xy 133.285316 -369.37084) (xy 133.235698 -369.393499) (xy 133.183361 -369.408866) (xy 133.129369 -369.416629)
			(xy 133.102096 -369.417092) (xy 132.238496 -369.417092) (xy 132.211229 -369.416545) (xy 132.15725 -369.408784)
			(xy 132.104925 -369.393419) (xy 132.055319 -369.370765) (xy 132.009442 -369.341281) (xy 131.968229 -369.305569)
			(xy 131.932517 -369.264354) (xy 131.903033 -369.218477) (xy 131.880379 -369.168871) (xy 131.865015 -369.116546)
			(xy 131.857254 -369.062567) (xy 126.676228 -369.062567) (xy 126.676228 -369.062573) (xy 126.668466 -369.116565)
			(xy 126.653098 -369.168902) (xy 126.630438 -369.218519) (xy 126.600948 -369.264407) (xy 126.565227 -369.30563)
			(xy 126.524003 -369.34135) (xy 126.478116 -369.37084) (xy 126.428498 -369.393499) (xy 126.376161 -369.408866)
			(xy 126.322169 -369.416629) (xy 126.294896 -369.417092) (xy 125.431296 -369.417092) (xy 125.404029 -369.416545)
			(xy 125.35005 -369.408784) (xy 125.297725 -369.393419) (xy 125.248119 -369.370765) (xy 125.202242 -369.341281)
			(xy 125.161029 -369.305569) (xy 125.125317 -369.264354) (xy 125.095833 -369.218477) (xy 125.073179 -369.168871)
			(xy 125.057815 -369.116546) (xy 125.050054 -369.062567) (xy 119.869028 -369.062567) (xy 119.869028 -369.062573)
			(xy 119.861266 -369.116565) (xy 119.845898 -369.168902) (xy 119.823238 -369.218519) (xy 119.793748 -369.264407)
			(xy 119.758027 -369.30563) (xy 119.716803 -369.34135) (xy 119.670916 -369.37084) (xy 119.621298 -369.393499)
			(xy 119.568961 -369.408866) (xy 119.514969 -369.416629) (xy 119.487696 -369.417092) (xy 118.624096 -369.417092)
			(xy 118.596829 -369.416545) (xy 118.54285 -369.408784) (xy 118.490525 -369.393419) (xy 118.440919 -369.370765)
			(xy 118.395042 -369.341281) (xy 118.353829 -369.305569) (xy 118.318117 -369.264354) (xy 118.288633 -369.218477)
			(xy 118.265979 -369.168871) (xy 118.250615 -369.116546) (xy 118.242854 -369.062567) (xy 113.061828 -369.062567)
			(xy 113.061828 -369.062573) (xy 113.054066 -369.116565) (xy 113.038698 -369.168902) (xy 113.016038 -369.218519)
			(xy 112.986548 -369.264407) (xy 112.950827 -369.30563) (xy 112.909603 -369.34135) (xy 112.863716 -369.37084)
			(xy 112.814098 -369.393499) (xy 112.761761 -369.408866) (xy 112.707769 -369.416629) (xy 112.680496 -369.417092)
			(xy 111.816896 -369.417092) (xy 111.789629 -369.416545) (xy 111.73565 -369.408784) (xy 111.683325 -369.393419)
			(xy 111.633719 -369.370765) (xy 111.587842 -369.341281) (xy 111.546629 -369.305569) (xy 111.510917 -369.264354)
			(xy 111.481433 -369.218477) (xy 111.458779 -369.168871) (xy 111.443415 -369.116546) (xy 111.435654 -369.062567)
			(xy 102.314806 -369.062567) (xy 102.314806 -369.062571) (xy 102.307043 -369.116559) (xy 102.291677 -369.168893)
			(xy 102.269019 -369.218507) (xy 102.239531 -369.264391) (xy 102.203813 -369.305612) (xy 102.162593 -369.34133)
			(xy 102.116708 -369.370818) (xy 102.067094 -369.393476) (xy 102.014761 -369.408843) (xy 101.960773 -369.416605)
			(xy 101.933502 -369.417092) (xy 101.069902 -369.417092) (xy 101.042633 -369.416569) (xy 100.98865 -369.408807)
			(xy 100.936321 -369.393443) (xy 100.886712 -369.370787) (xy 100.840832 -369.341302) (xy 100.799614 -369.305587)
			(xy 100.7639 -369.26437) (xy 100.734414 -369.21849) (xy 100.711758 -369.16888) (xy 100.696393 -369.116552)
			(xy 100.688631 -369.062569) (xy 98.911206 -369.062569) (xy 98.911206 -369.062571) (xy 98.903443 -369.116559)
			(xy 98.888077 -369.168893) (xy 98.865419 -369.218507) (xy 98.835931 -369.264391) (xy 98.800213 -369.305612)
			(xy 98.758993 -369.34133) (xy 98.713108 -369.370818) (xy 98.663494 -369.393476) (xy 98.611161 -369.408843)
			(xy 98.557173 -369.416605) (xy 98.529902 -369.417092) (xy 97.666302 -369.417092) (xy 97.639033 -369.416569)
			(xy 97.58505 -369.408807) (xy 97.532721 -369.393443) (xy 97.483112 -369.370787) (xy 97.437232 -369.341302)
			(xy 97.396014 -369.305587) (xy 97.3603 -369.26437) (xy 97.330814 -369.21849) (xy 97.308158 -369.16888)
			(xy 97.292793 -369.116552) (xy 97.285031 -369.062569) (xy 92.104006 -369.062569) (xy 92.104006 -369.062571)
			(xy 92.096243 -369.116559) (xy 92.080877 -369.168893) (xy 92.058219 -369.218507) (xy 92.028731 -369.264391)
			(xy 91.993013 -369.305612) (xy 91.951793 -369.34133) (xy 91.905908 -369.370818) (xy 91.856294 -369.393476)
			(xy 91.803961 -369.408843) (xy 91.749973 -369.416605) (xy 91.722702 -369.417092) (xy 90.859102 -369.417092)
			(xy 90.831833 -369.416569) (xy 90.77785 -369.408807) (xy 90.725521 -369.393443) (xy 90.675912 -369.370787)
			(xy 90.630032 -369.341302) (xy 90.588814 -369.305587) (xy 90.5531 -369.26437) (xy 90.523614 -369.21849)
			(xy 90.500958 -369.16888) (xy 90.485593 -369.116552) (xy 90.477831 -369.062569) (xy 85.296806 -369.062569)
			(xy 85.296806 -369.062571) (xy 85.289043 -369.116559) (xy 85.273677 -369.168893) (xy 85.251019 -369.218507)
			(xy 85.221531 -369.264391) (xy 85.185813 -369.305612) (xy 85.144593 -369.34133) (xy 85.098708 -369.370818)
			(xy 85.049094 -369.393476) (xy 84.996761 -369.408843) (xy 84.942773 -369.416605) (xy 84.915502 -369.417092)
			(xy 84.051902 -369.417092) (xy 84.024633 -369.416569) (xy 83.97065 -369.408807) (xy 83.918321 -369.393443)
			(xy 83.868712 -369.370787) (xy 83.822832 -369.341302) (xy 83.781614 -369.305587) (xy 83.7459 -369.26437)
			(xy 83.716414 -369.21849) (xy 83.693758 -369.16888) (xy 83.678393 -369.116552) (xy 83.670631 -369.062569)
			(xy 78.489606 -369.062569) (xy 78.489606 -369.062571) (xy 78.481843 -369.116559) (xy 78.466477 -369.168893)
			(xy 78.443819 -369.218507) (xy 78.414331 -369.264391) (xy 78.378613 -369.305612) (xy 78.337393 -369.34133)
			(xy 78.291508 -369.370818) (xy 78.241894 -369.393476) (xy 78.189561 -369.408843) (xy 78.135573 -369.416605)
			(xy 78.108302 -369.417092) (xy 77.244702 -369.417092) (xy 77.217433 -369.416569) (xy 77.16345 -369.408807)
			(xy 77.111121 -369.393443) (xy 77.061512 -369.370787) (xy 77.015632 -369.341302) (xy 76.974414 -369.305587)
			(xy 76.9387 -369.26437) (xy 76.909214 -369.21849) (xy 76.886558 -369.16888) (xy 76.871193 -369.116552)
			(xy 76.863431 -369.062569) (xy 69.787128 -369.062569) (xy 69.787128 -369.062575) (xy 69.779364 -369.11657)
			(xy 69.763995 -369.168911) (xy 69.741332 -369.218531) (xy 69.711838 -369.26442) (xy 69.676112 -369.305645)
			(xy 69.634884 -369.341365) (xy 69.588991 -369.370854) (xy 69.539368 -369.393511) (xy 69.487025 -369.408874)
			(xy 69.433029 -369.416632) (xy 69.405754 -369.417092) (xy 68.542154 -369.417092) (xy 68.514889 -369.416543)
			(xy 68.460915 -369.408776) (xy 68.408595 -369.393408) (xy 68.358994 -369.370751) (xy 68.313123 -369.341266)
			(xy 68.271914 -369.305554) (xy 68.236206 -369.264341) (xy 68.206727 -369.218465) (xy 68.184076 -369.168862)
			(xy 68.168714 -369.11654) (xy 68.160954 -369.062565) (xy 66.383528 -369.062565) (xy 66.383528 -369.062575)
			(xy 66.375764 -369.11657) (xy 66.360395 -369.168911) (xy 66.337732 -369.218531) (xy 66.308238 -369.26442)
			(xy 66.272512 -369.305645) (xy 66.231284 -369.341365) (xy 66.185391 -369.370854) (xy 66.135768 -369.393511)
			(xy 66.083425 -369.408874) (xy 66.029429 -369.416632) (xy 66.002154 -369.417092) (xy 65.138554 -369.417092)
			(xy 65.111289 -369.416543) (xy 65.057315 -369.408776) (xy 65.004995 -369.393408) (xy 64.955394 -369.370751)
			(xy 64.909523 -369.341266) (xy 64.868314 -369.305554) (xy 64.832606 -369.264341) (xy 64.803127 -369.218465)
			(xy 64.780476 -369.168862) (xy 64.765114 -369.11654) (xy 64.757354 -369.062565) (xy 59.576328 -369.062565)
			(xy 59.576328 -369.062575) (xy 59.568564 -369.11657) (xy 59.553195 -369.168911) (xy 59.530532 -369.218531)
			(xy 59.501038 -369.26442) (xy 59.465312 -369.305645) (xy 59.424084 -369.341365) (xy 59.378191 -369.370854)
			(xy 59.328568 -369.393511) (xy 59.276225 -369.408874) (xy 59.222229 -369.416632) (xy 59.194954 -369.417092)
			(xy 58.331354 -369.417092) (xy 58.304089 -369.416543) (xy 58.250115 -369.408776) (xy 58.197795 -369.393408)
			(xy 58.148194 -369.370751) (xy 58.102323 -369.341266) (xy 58.061114 -369.305554) (xy 58.025406 -369.264341)
			(xy 57.995927 -369.218465) (xy 57.973276 -369.168862) (xy 57.957914 -369.11654) (xy 57.950154 -369.062565)
			(xy 52.769128 -369.062565) (xy 52.769128 -369.062575) (xy 52.761364 -369.11657) (xy 52.745995 -369.168911)
			(xy 52.723332 -369.218531) (xy 52.693838 -369.26442) (xy 52.658112 -369.305645) (xy 52.616884 -369.341365)
			(xy 52.570991 -369.370854) (xy 52.521368 -369.393511) (xy 52.469025 -369.408874) (xy 52.415029 -369.416632)
			(xy 52.387754 -369.417092) (xy 51.524154 -369.417092) (xy 51.496889 -369.416543) (xy 51.442915 -369.408776)
			(xy 51.390595 -369.393408) (xy 51.340994 -369.370751) (xy 51.295123 -369.341266) (xy 51.253914 -369.305554)
			(xy 51.218206 -369.264341) (xy 51.188727 -369.218465) (xy 51.166076 -369.168862) (xy 51.150714 -369.11654)
			(xy 51.142954 -369.062565) (xy 45.961928 -369.062565) (xy 45.961928 -369.062575) (xy 45.954164 -369.11657)
			(xy 45.938795 -369.168911) (xy 45.916132 -369.218531) (xy 45.886638 -369.26442) (xy 45.850912 -369.305645)
			(xy 45.809684 -369.341365) (xy 45.763791 -369.370854) (xy 45.714168 -369.393511) (xy 45.661825 -369.408874)
			(xy 45.607829 -369.416632) (xy 45.580554 -369.417092) (xy 44.716954 -369.417092) (xy 44.689689 -369.416543)
			(xy 44.635715 -369.408776) (xy 44.583395 -369.393408) (xy 44.533794 -369.370751) (xy 44.487923 -369.341266)
			(xy 44.446714 -369.305554) (xy 44.411006 -369.264341) (xy 44.381527 -369.218465) (xy 44.358876 -369.168862)
			(xy 44.343514 -369.11654) (xy 44.335754 -369.062565) (xy 2.509012 -369.062565) (xy 2.509012 -370.206778)
			(xy 138.3665 -370.206778) (xy 138.3665 -369.343178) (xy 138.366986 -369.315909) (xy 138.374748 -369.261925)
			(xy 138.390113 -369.209595) (xy 138.41277 -369.159985) (xy 138.442256 -369.114104) (xy 138.477971 -369.072887)
			(xy 138.519188 -369.037172) (xy 138.565069 -369.007686) (xy 138.614679 -368.985029) (xy 138.667009 -368.969664)
			(xy 138.720993 -368.961902) (xy 138.775531 -368.961902) (xy 138.829515 -368.969664) (xy 138.881845 -368.985029)
			(xy 138.931455 -369.007686) (xy 138.977336 -369.037172) (xy 139.006648 -369.062571) (xy 143.963332 -369.062571)
			(xy 143.963332 -369.008029) (xy 143.971094 -368.954043) (xy 143.986461 -368.901711) (xy 144.009121 -368.852098)
			(xy 144.03861 -368.806216) (xy 144.074329 -368.764998) (xy 144.115551 -368.729284) (xy 144.161437 -368.699799)
			(xy 144.211052 -368.677146) (xy 144.263386 -368.661785) (xy 144.317373 -368.654028) (xy 144.344644 -368.653568)
			(xy 145.208244 -368.653568) (xy 145.235513 -368.653998) (xy 145.289497 -368.661765) (xy 145.341825 -368.677135)
			(xy 145.391433 -368.699796) (xy 145.437312 -368.729285) (xy 145.478528 -368.765003) (xy 145.514241 -368.806223)
			(xy 145.543725 -368.852105) (xy 145.56638 -368.901716) (xy 145.581744 -368.954047) (xy 145.589506 -369.00803)
			(xy 145.589506 -369.06257) (xy 145.589506 -369.062571) (xy 150.770532 -369.062571) (xy 150.770532 -369.008029)
			(xy 150.778294 -368.954043) (xy 150.793661 -368.901711) (xy 150.816321 -368.852098) (xy 150.84581 -368.806216)
			(xy 150.881529 -368.764998) (xy 150.922751 -368.729284) (xy 150.968637 -368.699799) (xy 151.018252 -368.677146)
			(xy 151.070586 -368.661785) (xy 151.124573 -368.654028) (xy 151.151844 -368.653568) (xy 152.015444 -368.653568)
			(xy 152.042713 -368.653998) (xy 152.096697 -368.661765) (xy 152.149025 -368.677135) (xy 152.198633 -368.699796)
			(xy 152.244512 -368.729285) (xy 152.285728 -368.765003) (xy 152.321441 -368.806223) (xy 152.350925 -368.852105)
			(xy 152.37358 -368.901716) (xy 152.388944 -368.954047) (xy 152.396706 -369.00803) (xy 152.396706 -369.06257)
			(xy 152.396706 -369.062571) (xy 157.577732 -369.062571) (xy 157.577732 -369.008029) (xy 157.585494 -368.954043)
			(xy 157.600861 -368.901711) (xy 157.623521 -368.852098) (xy 157.65301 -368.806216) (xy 157.688729 -368.764998)
			(xy 157.729951 -368.729284) (xy 157.775837 -368.699799) (xy 157.825452 -368.677146) (xy 157.877786 -368.661785)
			(xy 157.931773 -368.654028) (xy 157.959044 -368.653568) (xy 158.822644 -368.653568) (xy 158.849913 -368.653998)
			(xy 158.903897 -368.661765) (xy 158.956225 -368.677135) (xy 159.005833 -368.699796) (xy 159.051712 -368.729285)
			(xy 159.092928 -368.765003) (xy 159.128641 -368.806223) (xy 159.158125 -368.852105) (xy 159.18078 -368.901716)
			(xy 159.196144 -368.954047) (xy 159.203906 -369.00803) (xy 159.203906 -369.06257) (xy 159.203906 -369.062571)
			(xy 164.384932 -369.062571) (xy 164.384932 -369.008029) (xy 164.392694 -368.954043) (xy 164.408061 -368.901711)
			(xy 164.430721 -368.852098) (xy 164.46021 -368.806216) (xy 164.495929 -368.764998) (xy 164.537151 -368.729284)
			(xy 164.583037 -368.699799) (xy 164.632652 -368.677146) (xy 164.684986 -368.661785) (xy 164.738973 -368.654028)
			(xy 164.766244 -368.653568) (xy 165.629844 -368.653568) (xy 165.657113 -368.653998) (xy 165.711097 -368.661765)
			(xy 165.763425 -368.677135) (xy 165.813033 -368.699796) (xy 165.858912 -368.729285) (xy 165.900128 -368.765003)
			(xy 165.935841 -368.806223) (xy 165.965325 -368.852105) (xy 165.98798 -368.901716) (xy 166.003344 -368.954047)
			(xy 166.011106 -369.00803) (xy 166.011106 -369.06257) (xy 166.011106 -369.062571) (xy 167.788532 -369.062571)
			(xy 167.788532 -369.008029) (xy 167.796294 -368.954043) (xy 167.811661 -368.901711) (xy 167.834321 -368.852098)
			(xy 167.86381 -368.806216) (xy 167.899529 -368.764998) (xy 167.940751 -368.729284) (xy 167.986637 -368.699799)
			(xy 168.036252 -368.677146) (xy 168.088586 -368.661785) (xy 168.142573 -368.654028) (xy 168.169844 -368.653568)
			(xy 169.033444 -368.653568) (xy 169.060713 -368.653998) (xy 169.114697 -368.661765) (xy 169.167025 -368.677135)
			(xy 169.216633 -368.699796) (xy 169.262512 -368.729285) (xy 169.303728 -368.765003) (xy 169.339441 -368.806223)
			(xy 169.368925 -368.852105) (xy 169.39158 -368.901716) (xy 169.406944 -368.954047) (xy 169.414706 -369.00803)
			(xy 169.414706 -369.06257) (xy 169.406944 -369.116553) (xy 169.39158 -369.168884) (xy 169.368925 -369.218495)
			(xy 169.339441 -369.264377) (xy 169.303728 -369.305597) (xy 169.262512 -369.341315) (xy 169.216633 -369.370804)
			(xy 169.167025 -369.393465) (xy 169.114697 -369.408835) (xy 169.060713 -369.416602) (xy 169.033444 -369.417092)
			(xy 168.169844 -369.417092) (xy 168.142573 -369.416572) (xy 168.088586 -369.408815) (xy 168.036252 -369.393454)
			(xy 167.986637 -369.370801) (xy 167.940751 -369.341316) (xy 167.899529 -369.305602) (xy 167.86381 -369.264384)
			(xy 167.834321 -369.218502) (xy 167.811661 -369.168889) (xy 167.796294 -369.116557) (xy 167.788532 -369.062571)
			(xy 166.011106 -369.062571) (xy 166.003344 -369.116553) (xy 165.98798 -369.168884) (xy 165.965325 -369.218495)
			(xy 165.935841 -369.264377) (xy 165.900128 -369.305597) (xy 165.858912 -369.341315) (xy 165.813033 -369.370804)
			(xy 165.763425 -369.393465) (xy 165.711097 -369.408835) (xy 165.657113 -369.416602) (xy 165.629844 -369.417092)
			(xy 164.766244 -369.417092) (xy 164.738973 -369.416572) (xy 164.684986 -369.408815) (xy 164.632652 -369.393454)
			(xy 164.583037 -369.370801) (xy 164.537151 -369.341316) (xy 164.495929 -369.305602) (xy 164.46021 -369.264384)
			(xy 164.430721 -369.218502) (xy 164.408061 -369.168889) (xy 164.392694 -369.116557) (xy 164.384932 -369.062571)
			(xy 159.203906 -369.062571) (xy 159.196144 -369.116553) (xy 159.18078 -369.168884) (xy 159.158125 -369.218495)
			(xy 159.128641 -369.264377) (xy 159.092928 -369.305597) (xy 159.051712 -369.341315) (xy 159.005833 -369.370804)
			(xy 158.956225 -369.393465) (xy 158.903897 -369.408835) (xy 158.849913 -369.416602) (xy 158.822644 -369.417092)
			(xy 157.959044 -369.417092) (xy 157.931773 -369.416572) (xy 157.877786 -369.408815) (xy 157.825452 -369.393454)
			(xy 157.775837 -369.370801) (xy 157.729951 -369.341316) (xy 157.688729 -369.305602) (xy 157.65301 -369.264384)
			(xy 157.623521 -369.218502) (xy 157.600861 -369.168889) (xy 157.585494 -369.116557) (xy 157.577732 -369.062571)
			(xy 152.396706 -369.062571) (xy 152.388944 -369.116553) (xy 152.37358 -369.168884) (xy 152.350925 -369.218495)
			(xy 152.321441 -369.264377) (xy 152.285728 -369.305597) (xy 152.244512 -369.341315) (xy 152.198633 -369.370804)
			(xy 152.149025 -369.393465) (xy 152.096697 -369.408835) (xy 152.042713 -369.416602) (xy 152.015444 -369.417092)
			(xy 151.151844 -369.417092) (xy 151.124573 -369.416572) (xy 151.070586 -369.408815) (xy 151.018252 -369.393454)
			(xy 150.968637 -369.370801) (xy 150.922751 -369.341316) (xy 150.881529 -369.305602) (xy 150.84581 -369.264384)
			(xy 150.816321 -369.218502) (xy 150.793661 -369.168889) (xy 150.778294 -369.116557) (xy 150.770532 -369.062571)
			(xy 145.589506 -369.062571) (xy 145.581744 -369.116553) (xy 145.56638 -369.168884) (xy 145.543725 -369.218495)
			(xy 145.514241 -369.264377) (xy 145.478528 -369.305597) (xy 145.437312 -369.341315) (xy 145.391433 -369.370804)
			(xy 145.341825 -369.393465) (xy 145.289497 -369.408835) (xy 145.235513 -369.416602) (xy 145.208244 -369.417092)
			(xy 144.344644 -369.417092) (xy 144.317373 -369.416572) (xy 144.263386 -369.408815) (xy 144.211052 -369.393454)
			(xy 144.161437 -369.370801) (xy 144.115551 -369.341316) (xy 144.074329 -369.305602) (xy 144.03861 -369.264384)
			(xy 144.009121 -369.218502) (xy 143.986461 -369.168889) (xy 143.971094 -369.116557) (xy 143.963332 -369.062571)
			(xy 139.006648 -369.062571) (xy 139.018553 -369.072887) (xy 139.054268 -369.114104) (xy 139.083754 -369.159985)
			(xy 139.106411 -369.209595) (xy 139.121776 -369.261925) (xy 139.129538 -369.315909) (xy 139.130024 -369.343178)
			(xy 139.130024 -370.206778) (xy 139.129538 -370.234047) (xy 139.121776 -370.288031) (xy 139.106411 -370.340361)
			(xy 139.083754 -370.389971) (xy 139.071223 -370.40947) (xy 141.572996 -370.40947) (xy 141.572996 -369.54587)
			(xy 141.573482 -369.518619) (xy 141.581238 -369.464671) (xy 141.596593 -369.412376) (xy 141.619235 -369.362799)
			(xy 141.648701 -369.316949) (xy 141.684392 -369.275758) (xy 141.725583 -369.240067) (xy 141.771433 -369.210601)
			(xy 141.82101 -369.187959) (xy 141.873305 -369.172604) (xy 141.927253 -369.164848) (xy 141.981755 -369.164848)
			(xy 142.035703 -369.172604) (xy 142.087998 -369.187959) (xy 142.137575 -369.210601) (xy 142.183425 -369.240067)
			(xy 142.224616 -369.275758) (xy 142.260307 -369.316949) (xy 142.289773 -369.362799) (xy 142.312415 -369.412376)
			(xy 142.32777 -369.464671) (xy 142.335526 -369.518619) (xy 142.336012 -369.54587) (xy 142.336012 -369.62565)
			(xy 175.203103 -369.62565) (xy 175.203103 -369.57115) (xy 175.210859 -369.517206) (xy 175.226214 -369.464914)
			(xy 175.248854 -369.41534) (xy 175.278318 -369.369493) (xy 175.314008 -369.328305) (xy 175.355196 -369.292616)
			(xy 175.401044 -369.263152) (xy 175.450618 -369.240512) (xy 175.50291 -369.225158) (xy 175.556854 -369.217403)
			(xy 175.584104 -369.21694) (xy 176.447704 -369.21694) (xy 176.474958 -369.21733) (xy 176.528913 -369.225088)
			(xy 176.581213 -369.240446) (xy 176.630796 -369.26309) (xy 176.676652 -369.29256) (xy 176.717847 -369.328256)
			(xy 176.753543 -369.369451) (xy 176.783012 -369.415307) (xy 176.805656 -369.46489) (xy 176.821013 -369.517191)
			(xy 176.82877 -369.571146) (xy 176.82877 -369.625654) (xy 176.821013 -369.679609) (xy 176.805656 -369.73191)
			(xy 176.783012 -369.781493) (xy 176.753543 -369.827349) (xy 176.717847 -369.868544) (xy 176.676652 -369.90424)
			(xy 176.630796 -369.93371) (xy 176.581213 -369.956354) (xy 176.528913 -369.971712) (xy 176.474958 -369.97947)
			(xy 176.447704 -369.979956) (xy 175.584104 -369.979956) (xy 175.556854 -369.979397) (xy 175.50291 -369.971642)
			(xy 175.450618 -369.956288) (xy 175.401044 -369.933648) (xy 175.355196 -369.904184) (xy 175.314008 -369.868495)
			(xy 175.278318 -369.827307) (xy 175.248854 -369.78146) (xy 175.226214 -369.731886) (xy 175.210859 -369.679594)
			(xy 175.203103 -369.62565) (xy 142.336012 -369.62565) (xy 142.336012 -370.40947) (xy 142.335526 -370.436721)
			(xy 142.32777 -370.490669) (xy 142.312415 -370.542964) (xy 142.289773 -370.592541) (xy 142.260307 -370.638391)
			(xy 142.224616 -370.679582) (xy 142.183425 -370.715273) (xy 142.137575 -370.744739) (xy 142.087998 -370.767381)
			(xy 142.035703 -370.782736) (xy 141.981755 -370.790492) (xy 141.927253 -370.790492) (xy 141.873305 -370.782736)
			(xy 141.82101 -370.767381) (xy 141.771433 -370.744739) (xy 141.725583 -370.715273) (xy 141.684392 -370.679582)
			(xy 141.648701 -370.638391) (xy 141.619235 -370.592541) (xy 141.596593 -370.542964) (xy 141.581238 -370.490669)
			(xy 141.573482 -370.436721) (xy 141.572996 -370.40947) (xy 139.071223 -370.40947) (xy 139.054268 -370.435852)
			(xy 139.018553 -370.477069) (xy 138.977336 -370.512784) (xy 138.931455 -370.54227) (xy 138.881845 -370.564927)
			(xy 138.829515 -370.580292) (xy 138.775531 -370.588054) (xy 138.720993 -370.588054) (xy 138.667009 -370.580292)
			(xy 138.614679 -370.564927) (xy 138.565069 -370.54227) (xy 138.519188 -370.512784) (xy 138.477971 -370.477069)
			(xy 138.442256 -370.435852) (xy 138.41277 -370.389971) (xy 138.390113 -370.340361) (xy 138.374748 -370.288031)
			(xy 138.366986 -370.234047) (xy 138.3665 -370.206778) (xy 2.509012 -370.206778) (xy 2.509012 -371.526365)
			(xy 42.633954 -371.526365) (xy 42.633954 -371.471835) (xy 42.641714 -371.41786) (xy 42.657076 -371.365538)
			(xy 42.679727 -371.315935) (xy 42.709206 -371.270059) (xy 42.744914 -371.228846) (xy 42.786123 -371.193134)
			(xy 42.831994 -371.163649) (xy 42.881595 -371.140992) (xy 42.933915 -371.125624) (xy 42.987889 -371.117857)
			(xy 43.015154 -371.117368) (xy 43.878754 -371.117368) (xy 43.906029 -371.117768) (xy 43.960025 -371.125526)
			(xy 44.012368 -371.140889) (xy 44.061991 -371.163546) (xy 44.107884 -371.193035) (xy 44.149112 -371.228755)
			(xy 44.184838 -371.26998) (xy 44.214332 -371.315869) (xy 44.236995 -371.365489) (xy 44.252364 -371.41783)
			(xy 44.260128 -371.471825) (xy 44.260128 -371.526365) (xy 49.441154 -371.526365) (xy 49.441154 -371.471835)
			(xy 49.448914 -371.41786) (xy 49.464276 -371.365538) (xy 49.486927 -371.315935) (xy 49.516406 -371.270059)
			(xy 49.552114 -371.228846) (xy 49.593323 -371.193134) (xy 49.639194 -371.163649) (xy 49.688795 -371.140992)
			(xy 49.741115 -371.125624) (xy 49.795089 -371.117857) (xy 49.822354 -371.117368) (xy 50.685954 -371.117368)
			(xy 50.713229 -371.117768) (xy 50.767225 -371.125526) (xy 50.819568 -371.140889) (xy 50.869191 -371.163546)
			(xy 50.915084 -371.193035) (xy 50.956312 -371.228755) (xy 50.992038 -371.26998) (xy 51.021532 -371.315869)
			(xy 51.044195 -371.365489) (xy 51.059564 -371.41783) (xy 51.067328 -371.471825) (xy 51.067328 -371.526365)
			(xy 56.248354 -371.526365) (xy 56.248354 -371.471835) (xy 56.256114 -371.41786) (xy 56.271476 -371.365538)
			(xy 56.294127 -371.315935) (xy 56.323606 -371.270059) (xy 56.359314 -371.228846) (xy 56.400523 -371.193134)
			(xy 56.446394 -371.163649) (xy 56.495995 -371.140992) (xy 56.548315 -371.125624) (xy 56.602289 -371.117857)
			(xy 56.629554 -371.117368) (xy 57.493154 -371.117368) (xy 57.520429 -371.117768) (xy 57.574425 -371.125526)
			(xy 57.626768 -371.140889) (xy 57.676391 -371.163546) (xy 57.722284 -371.193035) (xy 57.763512 -371.228755)
			(xy 57.799238 -371.26998) (xy 57.828732 -371.315869) (xy 57.851395 -371.365489) (xy 57.866764 -371.41783)
			(xy 57.874528 -371.471825) (xy 57.874528 -371.526365) (xy 63.055554 -371.526365) (xy 63.055554 -371.471835)
			(xy 63.063314 -371.41786) (xy 63.078676 -371.365538) (xy 63.101327 -371.315935) (xy 63.130806 -371.270059)
			(xy 63.166514 -371.228846) (xy 63.207723 -371.193134) (xy 63.253594 -371.163649) (xy 63.303195 -371.140992)
			(xy 63.355515 -371.125624) (xy 63.409489 -371.117857) (xy 63.436754 -371.117368) (xy 64.300354 -371.117368)
			(xy 64.327629 -371.117768) (xy 64.381625 -371.125526) (xy 64.433968 -371.140889) (xy 64.483591 -371.163546)
			(xy 64.529484 -371.193035) (xy 64.570712 -371.228755) (xy 64.606438 -371.26998) (xy 64.635932 -371.315869)
			(xy 64.658595 -371.365489) (xy 64.673964 -371.41783) (xy 64.681728 -371.471825) (xy 64.681728 -371.526369)
			(xy 75.161631 -371.526369) (xy 75.161631 -371.471831) (xy 75.169393 -371.417848) (xy 75.184758 -371.36552)
			(xy 75.207414 -371.31591) (xy 75.2369 -371.27003) (xy 75.272614 -371.228813) (xy 75.313832 -371.193098)
			(xy 75.359712 -371.163613) (xy 75.409321 -371.140957) (xy 75.46165 -371.125593) (xy 75.515633 -371.117831)
			(xy 75.542902 -371.117368) (xy 76.406502 -371.117368) (xy 76.433773 -371.117795) (xy 76.487761 -371.125557)
			(xy 76.540094 -371.140924) (xy 76.589708 -371.163582) (xy 76.635593 -371.19307) (xy 76.676813 -371.228788)
			(xy 76.712531 -371.270009) (xy 76.742019 -371.315893) (xy 76.764677 -371.365507) (xy 76.780043 -371.417841)
			(xy 76.787806 -371.471829) (xy 76.787806 -371.526369) (xy 81.968831 -371.526369) (xy 81.968831 -371.471831)
			(xy 81.976593 -371.417848) (xy 81.991958 -371.36552) (xy 82.014614 -371.31591) (xy 82.0441 -371.27003)
			(xy 82.079814 -371.228813) (xy 82.121032 -371.193098) (xy 82.166912 -371.163613) (xy 82.216521 -371.140957)
			(xy 82.26885 -371.125593) (xy 82.322833 -371.117831) (xy 82.350102 -371.117368) (xy 83.213702 -371.117368)
			(xy 83.240973 -371.117795) (xy 83.294961 -371.125557) (xy 83.347294 -371.140924) (xy 83.396908 -371.163582)
			(xy 83.442793 -371.19307) (xy 83.484013 -371.228788) (xy 83.519731 -371.270009) (xy 83.549219 -371.315893)
			(xy 83.571877 -371.365507) (xy 83.587243 -371.417841) (xy 83.595006 -371.471829) (xy 83.595006 -371.526369)
			(xy 88.776031 -371.526369) (xy 88.776031 -371.471831) (xy 88.783793 -371.417848) (xy 88.799158 -371.36552)
			(xy 88.821814 -371.31591) (xy 88.8513 -371.27003) (xy 88.887014 -371.228813) (xy 88.928232 -371.193098)
			(xy 88.974112 -371.163613) (xy 89.023721 -371.140957) (xy 89.07605 -371.125593) (xy 89.130033 -371.117831)
			(xy 89.157302 -371.117368) (xy 90.020902 -371.117368) (xy 90.048173 -371.117795) (xy 90.102161 -371.125557)
			(xy 90.154494 -371.140924) (xy 90.204108 -371.163582) (xy 90.249993 -371.19307) (xy 90.291213 -371.228788)
			(xy 90.326931 -371.270009) (xy 90.356419 -371.315893) (xy 90.379077 -371.365507) (xy 90.394443 -371.417841)
			(xy 90.402206 -371.471829) (xy 90.402206 -371.526369) (xy 95.583231 -371.526369) (xy 95.583231 -371.471831)
			(xy 95.590993 -371.417848) (xy 95.606358 -371.36552) (xy 95.629014 -371.31591) (xy 95.6585 -371.27003)
			(xy 95.694214 -371.228813) (xy 95.735432 -371.193098) (xy 95.781312 -371.163613) (xy 95.830921 -371.140957)
			(xy 95.88325 -371.125593) (xy 95.937233 -371.117831) (xy 95.964502 -371.117368) (xy 96.828102 -371.117368)
			(xy 96.855373 -371.117795) (xy 96.909361 -371.125557) (xy 96.961694 -371.140924) (xy 97.011308 -371.163582)
			(xy 97.057193 -371.19307) (xy 97.098413 -371.228788) (xy 97.134131 -371.270009) (xy 97.163619 -371.315893)
			(xy 97.186277 -371.365507) (xy 97.201643 -371.417841) (xy 97.209406 -371.471829) (xy 97.209406 -371.526367)
			(xy 109.733854 -371.526367) (xy 109.733854 -371.471833) (xy 109.741615 -371.417854) (xy 109.756979 -371.365529)
			(xy 109.779633 -371.315923) (xy 109.809117 -371.270046) (xy 109.844829 -371.228831) (xy 109.886042 -371.193119)
			(xy 109.931919 -371.163635) (xy 109.981525 -371.140981) (xy 110.03385 -371.125616) (xy 110.087829 -371.117855)
			(xy 110.115096 -371.117368) (xy 110.978696 -371.117368) (xy 111.005969 -371.117771) (xy 111.059961 -371.125534)
			(xy 111.112298 -371.140901) (xy 111.161916 -371.16356) (xy 111.207803 -371.19305) (xy 111.249027 -371.22877)
			(xy 111.284748 -371.269993) (xy 111.314238 -371.315881) (xy 111.336898 -371.365498) (xy 111.352266 -371.417835)
			(xy 111.360028 -371.471827) (xy 111.360028 -371.526367) (xy 116.541054 -371.526367) (xy 116.541054 -371.471833)
			(xy 116.548815 -371.417854) (xy 116.564179 -371.365529) (xy 116.586833 -371.315923) (xy 116.616317 -371.270046)
			(xy 116.652029 -371.228831) (xy 116.693242 -371.193119) (xy 116.739119 -371.163635) (xy 116.788725 -371.140981)
			(xy 116.84105 -371.125616) (xy 116.895029 -371.117855) (xy 116.922296 -371.117368) (xy 117.785896 -371.117368)
			(xy 117.813169 -371.117771) (xy 117.867161 -371.125534) (xy 117.919498 -371.140901) (xy 117.969116 -371.16356)
			(xy 118.015003 -371.19305) (xy 118.056227 -371.22877) (xy 118.091948 -371.269993) (xy 118.121438 -371.315881)
			(xy 118.144098 -371.365498) (xy 118.159466 -371.417835) (xy 118.167228 -371.471827) (xy 118.167228 -371.526367)
			(xy 123.348254 -371.526367) (xy 123.348254 -371.471833) (xy 123.356015 -371.417854) (xy 123.371379 -371.365529)
			(xy 123.394033 -371.315923) (xy 123.423517 -371.270046) (xy 123.459229 -371.228831) (xy 123.500442 -371.193119)
			(xy 123.546319 -371.163635) (xy 123.595925 -371.140981) (xy 123.64825 -371.125616) (xy 123.702229 -371.117855)
			(xy 123.729496 -371.117368) (xy 124.593096 -371.117368) (xy 124.620369 -371.117771) (xy 124.674361 -371.125534)
			(xy 124.726698 -371.140901) (xy 124.776316 -371.16356) (xy 124.822203 -371.19305) (xy 124.863427 -371.22877)
			(xy 124.899148 -371.269993) (xy 124.928638 -371.315881) (xy 124.951298 -371.365498) (xy 124.966666 -371.417835)
			(xy 124.974428 -371.471827) (xy 124.974428 -371.526367) (xy 130.155454 -371.526367) (xy 130.155454 -371.471833)
			(xy 130.163215 -371.417854) (xy 130.178579 -371.365529) (xy 130.201233 -371.315923) (xy 130.230717 -371.270046)
			(xy 130.266429 -371.228831) (xy 130.307642 -371.193119) (xy 130.353519 -371.163635) (xy 130.403125 -371.140981)
			(xy 130.45545 -371.125616) (xy 130.509429 -371.117855) (xy 130.536696 -371.117368) (xy 131.400296 -371.117368)
			(xy 131.427569 -371.117771) (xy 131.481561 -371.125534) (xy 131.533898 -371.140901) (xy 131.583516 -371.16356)
			(xy 131.629403 -371.19305) (xy 131.670627 -371.22877) (xy 131.706348 -371.269993) (xy 131.735838 -371.315881)
			(xy 131.758498 -371.365498) (xy 131.773866 -371.417835) (xy 131.781628 -371.471827) (xy 131.781628 -371.526371)
			(xy 142.261532 -371.526371) (xy 142.261532 -371.471829) (xy 142.269294 -371.417843) (xy 142.284661 -371.365511)
			(xy 142.307321 -371.315898) (xy 142.33681 -371.270016) (xy 142.372529 -371.228798) (xy 142.413751 -371.193084)
			(xy 142.459637 -371.163599) (xy 142.509252 -371.140946) (xy 142.561586 -371.125585) (xy 142.615573 -371.117828)
			(xy 142.642844 -371.117368) (xy 143.506444 -371.117368) (xy 143.533713 -371.117798) (xy 143.587697 -371.125565)
			(xy 143.640025 -371.140935) (xy 143.689633 -371.163596) (xy 143.735512 -371.193085) (xy 143.776728 -371.228803)
			(xy 143.812441 -371.270023) (xy 143.841925 -371.315905) (xy 143.86458 -371.365516) (xy 143.879944 -371.417847)
			(xy 143.887706 -371.47183) (xy 143.887706 -371.52637) (xy 143.887706 -371.526371) (xy 149.068732 -371.526371)
			(xy 149.068732 -371.471829) (xy 149.076494 -371.417843) (xy 149.091861 -371.365511) (xy 149.114521 -371.315898)
			(xy 149.14401 -371.270016) (xy 149.179729 -371.228798) (xy 149.220951 -371.193084) (xy 149.266837 -371.163599)
			(xy 149.316452 -371.140946) (xy 149.368786 -371.125585) (xy 149.422773 -371.117828) (xy 149.450044 -371.117368)
			(xy 150.313644 -371.117368) (xy 150.340913 -371.117798) (xy 150.394897 -371.125565) (xy 150.447225 -371.140935)
			(xy 150.496833 -371.163596) (xy 150.542712 -371.193085) (xy 150.583928 -371.228803) (xy 150.619641 -371.270023)
			(xy 150.649125 -371.315905) (xy 150.67178 -371.365516) (xy 150.687144 -371.417847) (xy 150.694906 -371.47183)
			(xy 150.694906 -371.52637) (xy 150.694906 -371.526371) (xy 155.875932 -371.526371) (xy 155.875932 -371.471829)
			(xy 155.883694 -371.417843) (xy 155.899061 -371.365511) (xy 155.921721 -371.315898) (xy 155.95121 -371.270016)
			(xy 155.986929 -371.228798) (xy 156.028151 -371.193084) (xy 156.074037 -371.163599) (xy 156.123652 -371.140946)
			(xy 156.175986 -371.125585) (xy 156.229973 -371.117828) (xy 156.257244 -371.117368) (xy 157.120844 -371.117368)
			(xy 157.148113 -371.117798) (xy 157.202097 -371.125565) (xy 157.254425 -371.140935) (xy 157.304033 -371.163596)
			(xy 157.349912 -371.193085) (xy 157.391128 -371.228803) (xy 157.426841 -371.270023) (xy 157.456325 -371.315905)
			(xy 157.47898 -371.365516) (xy 157.494344 -371.417847) (xy 157.502106 -371.47183) (xy 157.502106 -371.52637)
			(xy 157.502106 -371.526371) (xy 162.683132 -371.526371) (xy 162.683132 -371.471829) (xy 162.690894 -371.417843)
			(xy 162.706261 -371.365511) (xy 162.728921 -371.315898) (xy 162.75841 -371.270016) (xy 162.794129 -371.228798)
			(xy 162.835351 -371.193084) (xy 162.881237 -371.163599) (xy 162.930852 -371.140946) (xy 162.983186 -371.125585)
			(xy 163.037173 -371.117828) (xy 163.064444 -371.117368) (xy 163.928044 -371.117368) (xy 163.955313 -371.117798)
			(xy 164.009297 -371.125565) (xy 164.061625 -371.140935) (xy 164.111233 -371.163596) (xy 164.157112 -371.193085)
			(xy 164.198328 -371.228803) (xy 164.234041 -371.270023) (xy 164.263525 -371.315905) (xy 164.28618 -371.365516)
			(xy 164.301544 -371.417847) (xy 164.309306 -371.47183) (xy 164.309306 -371.52637) (xy 164.301544 -371.580353)
			(xy 164.28618 -371.632684) (xy 164.263525 -371.682295) (xy 164.234041 -371.728177) (xy 164.198328 -371.769397)
			(xy 164.157112 -371.805115) (xy 164.111233 -371.834604) (xy 164.061625 -371.857265) (xy 164.009297 -371.872635)
			(xy 163.955313 -371.880402) (xy 163.928044 -371.880892) (xy 163.064444 -371.880892) (xy 163.037173 -371.880372)
			(xy 162.983186 -371.872615) (xy 162.930852 -371.857254) (xy 162.881237 -371.834601) (xy 162.835351 -371.805116)
			(xy 162.794129 -371.769402) (xy 162.75841 -371.728184) (xy 162.728921 -371.682302) (xy 162.706261 -371.632689)
			(xy 162.690894 -371.580357) (xy 162.683132 -371.526371) (xy 157.502106 -371.526371) (xy 157.494344 -371.580353)
			(xy 157.47898 -371.632684) (xy 157.456325 -371.682295) (xy 157.426841 -371.728177) (xy 157.391128 -371.769397)
			(xy 157.349912 -371.805115) (xy 157.304033 -371.834604) (xy 157.254425 -371.857265) (xy 157.202097 -371.872635)
			(xy 157.148113 -371.880402) (xy 157.120844 -371.880892) (xy 156.257244 -371.880892) (xy 156.229973 -371.880372)
			(xy 156.175986 -371.872615) (xy 156.123652 -371.857254) (xy 156.074037 -371.834601) (xy 156.028151 -371.805116)
			(xy 155.986929 -371.769402) (xy 155.95121 -371.728184) (xy 155.921721 -371.682302) (xy 155.899061 -371.632689)
			(xy 155.883694 -371.580357) (xy 155.875932 -371.526371) (xy 150.694906 -371.526371) (xy 150.687144 -371.580353)
			(xy 150.67178 -371.632684) (xy 150.649125 -371.682295) (xy 150.619641 -371.728177) (xy 150.583928 -371.769397)
			(xy 150.542712 -371.805115) (xy 150.496833 -371.834604) (xy 150.447225 -371.857265) (xy 150.394897 -371.872635)
			(xy 150.340913 -371.880402) (xy 150.313644 -371.880892) (xy 149.450044 -371.880892) (xy 149.422773 -371.880372)
			(xy 149.368786 -371.872615) (xy 149.316452 -371.857254) (xy 149.266837 -371.834601) (xy 149.220951 -371.805116)
			(xy 149.179729 -371.769402) (xy 149.14401 -371.728184) (xy 149.114521 -371.682302) (xy 149.091861 -371.632689)
			(xy 149.076494 -371.580357) (xy 149.068732 -371.526371) (xy 143.887706 -371.526371) (xy 143.879944 -371.580353)
			(xy 143.86458 -371.632684) (xy 143.841925 -371.682295) (xy 143.812441 -371.728177) (xy 143.776728 -371.769397)
			(xy 143.735512 -371.805115) (xy 143.689633 -371.834604) (xy 143.640025 -371.857265) (xy 143.587697 -371.872635)
			(xy 143.533713 -371.880402) (xy 143.506444 -371.880892) (xy 142.642844 -371.880892) (xy 142.615573 -371.880372)
			(xy 142.561586 -371.872615) (xy 142.509252 -371.857254) (xy 142.459637 -371.834601) (xy 142.413751 -371.805116)
			(xy 142.372529 -371.769402) (xy 142.33681 -371.728184) (xy 142.307321 -371.682302) (xy 142.284661 -371.632689)
			(xy 142.269294 -371.580357) (xy 142.261532 -371.526371) (xy 131.781628 -371.526371) (xy 131.781628 -371.526373)
			(xy 131.773866 -371.580365) (xy 131.758498 -371.632702) (xy 131.735838 -371.682319) (xy 131.706348 -371.728207)
			(xy 131.670627 -371.76943) (xy 131.629403 -371.80515) (xy 131.583516 -371.83464) (xy 131.533898 -371.857299)
			(xy 131.481561 -371.872666) (xy 131.427569 -371.880429) (xy 131.400296 -371.880892) (xy 130.536696 -371.880892)
			(xy 130.509429 -371.880345) (xy 130.45545 -371.872584) (xy 130.403125 -371.857219) (xy 130.353519 -371.834565)
			(xy 130.307642 -371.805081) (xy 130.266429 -371.769369) (xy 130.230717 -371.728154) (xy 130.201233 -371.682277)
			(xy 130.178579 -371.632671) (xy 130.163215 -371.580346) (xy 130.155454 -371.526367) (xy 124.974428 -371.526367)
			(xy 124.974428 -371.526373) (xy 124.966666 -371.580365) (xy 124.951298 -371.632702) (xy 124.928638 -371.682319)
			(xy 124.899148 -371.728207) (xy 124.863427 -371.76943) (xy 124.822203 -371.80515) (xy 124.776316 -371.83464)
			(xy 124.726698 -371.857299) (xy 124.674361 -371.872666) (xy 124.620369 -371.880429) (xy 124.593096 -371.880892)
			(xy 123.729496 -371.880892) (xy 123.702229 -371.880345) (xy 123.64825 -371.872584) (xy 123.595925 -371.857219)
			(xy 123.546319 -371.834565) (xy 123.500442 -371.805081) (xy 123.459229 -371.769369) (xy 123.423517 -371.728154)
			(xy 123.394033 -371.682277) (xy 123.371379 -371.632671) (xy 123.356015 -371.580346) (xy 123.348254 -371.526367)
			(xy 118.167228 -371.526367) (xy 118.167228 -371.526373) (xy 118.159466 -371.580365) (xy 118.144098 -371.632702)
			(xy 118.121438 -371.682319) (xy 118.091948 -371.728207) (xy 118.056227 -371.76943) (xy 118.015003 -371.80515)
			(xy 117.969116 -371.83464) (xy 117.919498 -371.857299) (xy 117.867161 -371.872666) (xy 117.813169 -371.880429)
			(xy 117.785896 -371.880892) (xy 116.922296 -371.880892) (xy 116.895029 -371.880345) (xy 116.84105 -371.872584)
			(xy 116.788725 -371.857219) (xy 116.739119 -371.834565) (xy 116.693242 -371.805081) (xy 116.652029 -371.769369)
			(xy 116.616317 -371.728154) (xy 116.586833 -371.682277) (xy 116.564179 -371.632671) (xy 116.548815 -371.580346)
			(xy 116.541054 -371.526367) (xy 111.360028 -371.526367) (xy 111.360028 -371.526373) (xy 111.352266 -371.580365)
			(xy 111.336898 -371.632702) (xy 111.314238 -371.682319) (xy 111.284748 -371.728207) (xy 111.249027 -371.76943)
			(xy 111.207803 -371.80515) (xy 111.161916 -371.83464) (xy 111.112298 -371.857299) (xy 111.059961 -371.872666)
			(xy 111.005969 -371.880429) (xy 110.978696 -371.880892) (xy 110.115096 -371.880892) (xy 110.087829 -371.880345)
			(xy 110.03385 -371.872584) (xy 109.981525 -371.857219) (xy 109.931919 -371.834565) (xy 109.886042 -371.805081)
			(xy 109.844829 -371.769369) (xy 109.809117 -371.728154) (xy 109.779633 -371.682277) (xy 109.756979 -371.632671)
			(xy 109.741615 -371.580346) (xy 109.733854 -371.526367) (xy 97.209406 -371.526367) (xy 97.209406 -371.526371)
			(xy 97.201643 -371.580359) (xy 97.186277 -371.632693) (xy 97.163619 -371.682307) (xy 97.134131 -371.728191)
			(xy 97.098413 -371.769412) (xy 97.057193 -371.80513) (xy 97.011308 -371.834618) (xy 96.961694 -371.857276)
			(xy 96.909361 -371.872643) (xy 96.855373 -371.880405) (xy 96.828102 -371.880892) (xy 95.964502 -371.880892)
			(xy 95.937233 -371.880369) (xy 95.88325 -371.872607) (xy 95.830921 -371.857243) (xy 95.781312 -371.834587)
			(xy 95.735432 -371.805102) (xy 95.694214 -371.769387) (xy 95.6585 -371.72817) (xy 95.629014 -371.68229)
			(xy 95.606358 -371.63268) (xy 95.590993 -371.580352) (xy 95.583231 -371.526369) (xy 90.402206 -371.526369)
			(xy 90.402206 -371.526371) (xy 90.394443 -371.580359) (xy 90.379077 -371.632693) (xy 90.356419 -371.682307)
			(xy 90.326931 -371.728191) (xy 90.291213 -371.769412) (xy 90.249993 -371.80513) (xy 90.204108 -371.834618)
			(xy 90.154494 -371.857276) (xy 90.102161 -371.872643) (xy 90.048173 -371.880405) (xy 90.020902 -371.880892)
			(xy 89.157302 -371.880892) (xy 89.130033 -371.880369) (xy 89.07605 -371.872607) (xy 89.023721 -371.857243)
			(xy 88.974112 -371.834587) (xy 88.928232 -371.805102) (xy 88.887014 -371.769387) (xy 88.8513 -371.72817)
			(xy 88.821814 -371.68229) (xy 88.799158 -371.63268) (xy 88.783793 -371.580352) (xy 88.776031 -371.526369)
			(xy 83.595006 -371.526369) (xy 83.595006 -371.526371) (xy 83.587243 -371.580359) (xy 83.571877 -371.632693)
			(xy 83.549219 -371.682307) (xy 83.519731 -371.728191) (xy 83.484013 -371.769412) (xy 83.442793 -371.80513)
			(xy 83.396908 -371.834618) (xy 83.347294 -371.857276) (xy 83.294961 -371.872643) (xy 83.240973 -371.880405)
			(xy 83.213702 -371.880892) (xy 82.350102 -371.880892) (xy 82.322833 -371.880369) (xy 82.26885 -371.872607)
			(xy 82.216521 -371.857243) (xy 82.166912 -371.834587) (xy 82.121032 -371.805102) (xy 82.079814 -371.769387)
			(xy 82.0441 -371.72817) (xy 82.014614 -371.68229) (xy 81.991958 -371.63268) (xy 81.976593 -371.580352)
			(xy 81.968831 -371.526369) (xy 76.787806 -371.526369) (xy 76.787806 -371.526371) (xy 76.780043 -371.580359)
			(xy 76.764677 -371.632693) (xy 76.742019 -371.682307) (xy 76.712531 -371.728191) (xy 76.676813 -371.769412)
			(xy 76.635593 -371.80513) (xy 76.589708 -371.834618) (xy 76.540094 -371.857276) (xy 76.487761 -371.872643)
			(xy 76.433773 -371.880405) (xy 76.406502 -371.880892) (xy 75.542902 -371.880892) (xy 75.515633 -371.880369)
			(xy 75.46165 -371.872607) (xy 75.409321 -371.857243) (xy 75.359712 -371.834587) (xy 75.313832 -371.805102)
			(xy 75.272614 -371.769387) (xy 75.2369 -371.72817) (xy 75.207414 -371.68229) (xy 75.184758 -371.63268)
			(xy 75.169393 -371.580352) (xy 75.161631 -371.526369) (xy 64.681728 -371.526369) (xy 64.681728 -371.526375)
			(xy 64.673964 -371.58037) (xy 64.658595 -371.632711) (xy 64.635932 -371.682331) (xy 64.606438 -371.72822)
			(xy 64.570712 -371.769445) (xy 64.529484 -371.805165) (xy 64.483591 -371.834654) (xy 64.433968 -371.857311)
			(xy 64.381625 -371.872674) (xy 64.327629 -371.880432) (xy 64.300354 -371.880892) (xy 63.436754 -371.880892)
			(xy 63.409489 -371.880343) (xy 63.355515 -371.872576) (xy 63.303195 -371.857208) (xy 63.253594 -371.834551)
			(xy 63.207723 -371.805066) (xy 63.166514 -371.769354) (xy 63.130806 -371.728141) (xy 63.101327 -371.682265)
			(xy 63.078676 -371.632662) (xy 63.063314 -371.58034) (xy 63.055554 -371.526365) (xy 57.874528 -371.526365)
			(xy 57.874528 -371.526375) (xy 57.866764 -371.58037) (xy 57.851395 -371.632711) (xy 57.828732 -371.682331)
			(xy 57.799238 -371.72822) (xy 57.763512 -371.769445) (xy 57.722284 -371.805165) (xy 57.676391 -371.834654)
			(xy 57.626768 -371.857311) (xy 57.574425 -371.872674) (xy 57.520429 -371.880432) (xy 57.493154 -371.880892)
			(xy 56.629554 -371.880892) (xy 56.602289 -371.880343) (xy 56.548315 -371.872576) (xy 56.495995 -371.857208)
			(xy 56.446394 -371.834551) (xy 56.400523 -371.805066) (xy 56.359314 -371.769354) (xy 56.323606 -371.728141)
			(xy 56.294127 -371.682265) (xy 56.271476 -371.632662) (xy 56.256114 -371.58034) (xy 56.248354 -371.526365)
			(xy 51.067328 -371.526365) (xy 51.067328 -371.526375) (xy 51.059564 -371.58037) (xy 51.044195 -371.632711)
			(xy 51.021532 -371.682331) (xy 50.992038 -371.72822) (xy 50.956312 -371.769445) (xy 50.915084 -371.805165)
			(xy 50.869191 -371.834654) (xy 50.819568 -371.857311) (xy 50.767225 -371.872674) (xy 50.713229 -371.880432)
			(xy 50.685954 -371.880892) (xy 49.822354 -371.880892) (xy 49.795089 -371.880343) (xy 49.741115 -371.872576)
			(xy 49.688795 -371.857208) (xy 49.639194 -371.834551) (xy 49.593323 -371.805066) (xy 49.552114 -371.769354)
			(xy 49.516406 -371.728141) (xy 49.486927 -371.682265) (xy 49.464276 -371.632662) (xy 49.448914 -371.58034)
			(xy 49.441154 -371.526365) (xy 44.260128 -371.526365) (xy 44.260128 -371.526375) (xy 44.252364 -371.58037)
			(xy 44.236995 -371.632711) (xy 44.214332 -371.682331) (xy 44.184838 -371.72822) (xy 44.149112 -371.769445)
			(xy 44.107884 -371.805165) (xy 44.061991 -371.834654) (xy 44.012368 -371.857311) (xy 43.960025 -371.872674)
			(xy 43.906029 -371.880432) (xy 43.878754 -371.880892) (xy 43.015154 -371.880892) (xy 42.987889 -371.880343)
			(xy 42.933915 -371.872576) (xy 42.881595 -371.857208) (xy 42.831994 -371.834551) (xy 42.786123 -371.805066)
			(xy 42.744914 -371.769354) (xy 42.709206 -371.728141) (xy 42.679727 -371.682265) (xy 42.657076 -371.632662)
			(xy 42.641714 -371.58034) (xy 42.633954 -371.526365) (xy 2.509012 -371.526365) (xy 2.509012 -376.489976)
			(xy 31.068784 -376.489976) (xy 31.072756 -376.311733) (xy 31.084664 -376.133844) (xy 31.104485 -375.956662)
			(xy 31.132179 -375.780538) (xy 31.167691 -375.605823) (xy 31.210951 -375.432864) (xy 31.261873 -375.262003)
			(xy 31.320356 -375.093581) (xy 31.386283 -374.927931) (xy 31.459524 -374.765382) (xy 31.539934 -374.606257)
			(xy 31.627352 -374.450872) (xy 31.721605 -374.299536) (xy 31.822506 -374.152548) (xy 31.929855 -374.010201)
			(xy 32.043438 -373.872778) (xy 32.163031 -373.740551) (xy 32.288395 -373.613782) (xy 32.419282 -373.492724)
			(xy 32.555431 -373.377617) (xy 32.696573 -373.268689) (xy 32.842428 -373.166157) (xy 32.992705 -373.070223)
			(xy 33.147106 -372.98108) (xy 33.305325 -372.898903) (xy 33.467048 -372.823855) (xy 33.631953 -372.756087)
			(xy 33.799714 -372.695731) (xy 33.969997 -372.642909) (xy 34.142464 -372.597725) (xy 34.316772 -372.560268)
			(xy 34.492576 -372.530614) (xy 34.669526 -372.508821) (xy 34.847272 -372.494931) (xy 35.025459 -372.488974)
			(xy 35.203736 -372.49096) (xy 35.381747 -372.500886) (xy 35.559139 -372.518732) (xy 35.735559 -372.544462)
			(xy 35.910659 -372.578026) (xy 36.08409 -372.619356) (xy 36.255507 -372.668372) (xy 36.42457 -372.724974)
			(xy 36.590945 -372.789052) (xy 36.754299 -372.860478) (xy 36.91431 -372.93911) (xy 37.070659 -373.024791)
			(xy 37.223036 -373.117353) (xy 37.371139 -373.21661) (xy 37.514673 -373.322367) (xy 37.653353 -373.434412)
			(xy 37.786904 -373.552524) (xy 37.915061 -373.676468) (xy 38.03757 -373.805998) (xy 38.154187 -373.940857)
			(xy 38.193125 -373.990165) (xy 47.739354 -373.990165) (xy 47.739354 -373.935635) (xy 47.747114 -373.88166)
			(xy 47.762476 -373.829338) (xy 47.785127 -373.779735) (xy 47.814606 -373.733859) (xy 47.850314 -373.692646)
			(xy 47.891523 -373.656934) (xy 47.937394 -373.627449) (xy 47.986995 -373.604792) (xy 48.039315 -373.589424)
			(xy 48.093289 -373.581657) (xy 48.120554 -373.581168) (xy 48.984154 -373.581168) (xy 49.011429 -373.581568)
			(xy 49.065425 -373.589326) (xy 49.117768 -373.604689) (xy 49.167391 -373.627346) (xy 49.213284 -373.656835)
			(xy 49.254512 -373.692555) (xy 49.290238 -373.73378) (xy 49.319732 -373.779669) (xy 49.342395 -373.829289)
			(xy 49.357764 -373.88163) (xy 49.365528 -373.935625) (xy 49.365528 -373.990165) (xy 54.546554 -373.990165)
			(xy 54.546554 -373.935635) (xy 54.554314 -373.88166) (xy 54.569676 -373.829338) (xy 54.592327 -373.779735)
			(xy 54.621806 -373.733859) (xy 54.657514 -373.692646) (xy 54.698723 -373.656934) (xy 54.744594 -373.627449)
			(xy 54.794195 -373.604792) (xy 54.846515 -373.589424) (xy 54.900489 -373.581657) (xy 54.927754 -373.581168)
			(xy 55.791354 -373.581168) (xy 55.818629 -373.581568) (xy 55.872625 -373.589326) (xy 55.924968 -373.604689)
			(xy 55.974591 -373.627346) (xy 56.020484 -373.656835) (xy 56.061712 -373.692555) (xy 56.097438 -373.73378)
			(xy 56.126932 -373.779669) (xy 56.149595 -373.829289) (xy 56.164964 -373.88163) (xy 56.172728 -373.935625)
			(xy 56.172728 -373.990165) (xy 61.353754 -373.990165) (xy 61.353754 -373.935635) (xy 61.361514 -373.88166)
			(xy 61.376876 -373.829338) (xy 61.399527 -373.779735) (xy 61.429006 -373.733859) (xy 61.464714 -373.692646)
			(xy 61.505923 -373.656934) (xy 61.551794 -373.627449) (xy 61.601395 -373.604792) (xy 61.653715 -373.589424)
			(xy 61.707689 -373.581657) (xy 61.734954 -373.581168) (xy 62.598554 -373.581168) (xy 62.625829 -373.581568)
			(xy 62.679825 -373.589326) (xy 62.732168 -373.604689) (xy 62.781791 -373.627346) (xy 62.827684 -373.656835)
			(xy 62.868912 -373.692555) (xy 62.904638 -373.73378) (xy 62.934132 -373.779669) (xy 62.956795 -373.829289)
			(xy 62.972164 -373.88163) (xy 62.979928 -373.935625) (xy 62.979928 -373.990169) (xy 80.267031 -373.990169)
			(xy 80.267031 -373.935631) (xy 80.274793 -373.881648) (xy 80.290158 -373.82932) (xy 80.312814 -373.77971)
			(xy 80.3423 -373.73383) (xy 80.378014 -373.692613) (xy 80.419232 -373.656898) (xy 80.465112 -373.627413)
			(xy 80.514721 -373.604757) (xy 80.56705 -373.589393) (xy 80.621033 -373.581631) (xy 80.648302 -373.581168)
			(xy 81.511902 -373.581168) (xy 81.539173 -373.581595) (xy 81.593161 -373.589357) (xy 81.645494 -373.604724)
			(xy 81.695108 -373.627382) (xy 81.740993 -373.65687) (xy 81.782213 -373.692588) (xy 81.817931 -373.733809)
			(xy 81.847419 -373.779693) (xy 81.870077 -373.829307) (xy 81.885443 -373.881641) (xy 81.893206 -373.935629)
			(xy 81.893206 -373.990169) (xy 87.074231 -373.990169) (xy 87.074231 -373.935631) (xy 87.081993 -373.881648)
			(xy 87.097358 -373.82932) (xy 87.120014 -373.77971) (xy 87.1495 -373.73383) (xy 87.185214 -373.692613)
			(xy 87.226432 -373.656898) (xy 87.272312 -373.627413) (xy 87.321921 -373.604757) (xy 87.37425 -373.589393)
			(xy 87.428233 -373.581631) (xy 87.455502 -373.581168) (xy 88.319102 -373.581168) (xy 88.346373 -373.581595)
			(xy 88.400361 -373.589357) (xy 88.452694 -373.604724) (xy 88.502308 -373.627382) (xy 88.548193 -373.65687)
			(xy 88.589413 -373.692588) (xy 88.625131 -373.733809) (xy 88.654619 -373.779693) (xy 88.677277 -373.829307)
			(xy 88.692643 -373.881641) (xy 88.700406 -373.935629) (xy 88.700406 -373.990169) (xy 93.881431 -373.990169)
			(xy 93.881431 -373.935631) (xy 93.889193 -373.881648) (xy 93.904558 -373.82932) (xy 93.927214 -373.77971)
			(xy 93.9567 -373.73383) (xy 93.992414 -373.692613) (xy 94.033632 -373.656898) (xy 94.079512 -373.627413)
			(xy 94.129121 -373.604757) (xy 94.18145 -373.589393) (xy 94.235433 -373.581631) (xy 94.262702 -373.581168)
			(xy 95.126302 -373.581168) (xy 95.153573 -373.581595) (xy 95.207561 -373.589357) (xy 95.259894 -373.604724)
			(xy 95.309508 -373.627382) (xy 95.355393 -373.65687) (xy 95.396613 -373.692588) (xy 95.432331 -373.733809)
			(xy 95.461819 -373.779693) (xy 95.484477 -373.829307) (xy 95.499843 -373.881641) (xy 95.507606 -373.935629)
			(xy 95.507606 -373.990167) (xy 114.839254 -373.990167) (xy 114.839254 -373.935633) (xy 114.847015 -373.881654)
			(xy 114.862379 -373.829329) (xy 114.885033 -373.779723) (xy 114.914517 -373.733846) (xy 114.950229 -373.692631)
			(xy 114.991442 -373.656919) (xy 115.037319 -373.627435) (xy 115.086925 -373.604781) (xy 115.13925 -373.589416)
			(xy 115.193229 -373.581655) (xy 115.220496 -373.581168) (xy 116.084096 -373.581168) (xy 116.111369 -373.581571)
			(xy 116.165361 -373.589334) (xy 116.217698 -373.604701) (xy 116.267316 -373.62736) (xy 116.313203 -373.65685)
			(xy 116.354427 -373.69257) (xy 116.390148 -373.733793) (xy 116.419638 -373.779681) (xy 116.442298 -373.829298)
			(xy 116.457666 -373.881635) (xy 116.465428 -373.935627) (xy 116.465428 -373.990167) (xy 121.646454 -373.990167)
			(xy 121.646454 -373.935633) (xy 121.654215 -373.881654) (xy 121.669579 -373.829329) (xy 121.692233 -373.779723)
			(xy 121.721717 -373.733846) (xy 121.757429 -373.692631) (xy 121.798642 -373.656919) (xy 121.844519 -373.627435)
			(xy 121.894125 -373.604781) (xy 121.94645 -373.589416) (xy 122.000429 -373.581655) (xy 122.027696 -373.581168)
			(xy 122.891296 -373.581168) (xy 122.918569 -373.581571) (xy 122.972561 -373.589334) (xy 123.024898 -373.604701)
			(xy 123.074516 -373.62736) (xy 123.120403 -373.65685) (xy 123.161627 -373.69257) (xy 123.197348 -373.733793)
			(xy 123.226838 -373.779681) (xy 123.249498 -373.829298) (xy 123.264866 -373.881635) (xy 123.272628 -373.935627)
			(xy 123.272628 -373.990167) (xy 128.453654 -373.990167) (xy 128.453654 -373.935633) (xy 128.461415 -373.881654)
			(xy 128.476779 -373.829329) (xy 128.499433 -373.779723) (xy 128.528917 -373.733846) (xy 128.564629 -373.692631)
			(xy 128.605842 -373.656919) (xy 128.651719 -373.627435) (xy 128.701325 -373.604781) (xy 128.75365 -373.589416)
			(xy 128.807629 -373.581655) (xy 128.834896 -373.581168) (xy 129.698496 -373.581168) (xy 129.725769 -373.581571)
			(xy 129.779761 -373.589334) (xy 129.832098 -373.604701) (xy 129.881716 -373.62736) (xy 129.927603 -373.65685)
			(xy 129.968827 -373.69257) (xy 130.004548 -373.733793) (xy 130.034038 -373.779681) (xy 130.056698 -373.829298)
			(xy 130.072066 -373.881635) (xy 130.079828 -373.935627) (xy 130.079828 -373.990171) (xy 147.366932 -373.990171)
			(xy 147.366932 -373.935629) (xy 147.374694 -373.881643) (xy 147.390061 -373.829311) (xy 147.412721 -373.779698)
			(xy 147.44221 -373.733816) (xy 147.477929 -373.692598) (xy 147.519151 -373.656884) (xy 147.565037 -373.627399)
			(xy 147.614652 -373.604746) (xy 147.666986 -373.589385) (xy 147.720973 -373.581628) (xy 147.748244 -373.581168)
			(xy 148.611844 -373.581168) (xy 148.639113 -373.581598) (xy 148.693097 -373.589365) (xy 148.745425 -373.604735)
			(xy 148.795033 -373.627396) (xy 148.840912 -373.656885) (xy 148.882128 -373.692603) (xy 148.917841 -373.733823)
			(xy 148.947325 -373.779705) (xy 148.96998 -373.829316) (xy 148.985344 -373.881647) (xy 148.993106 -373.93563)
			(xy 148.993106 -373.99017) (xy 148.993106 -373.990171) (xy 154.174132 -373.990171) (xy 154.174132 -373.935629)
			(xy 154.181894 -373.881643) (xy 154.197261 -373.829311) (xy 154.219921 -373.779698) (xy 154.24941 -373.733816)
			(xy 154.285129 -373.692598) (xy 154.326351 -373.656884) (xy 154.372237 -373.627399) (xy 154.421852 -373.604746)
			(xy 154.474186 -373.589385) (xy 154.528173 -373.581628) (xy 154.555444 -373.581168) (xy 155.419044 -373.581168)
			(xy 155.446313 -373.581598) (xy 155.500297 -373.589365) (xy 155.552625 -373.604735) (xy 155.602233 -373.627396)
			(xy 155.648112 -373.656885) (xy 155.689328 -373.692603) (xy 155.725041 -373.733823) (xy 155.754525 -373.779705)
			(xy 155.77718 -373.829316) (xy 155.792544 -373.881647) (xy 155.800306 -373.93563) (xy 155.800306 -373.99017)
			(xy 155.800306 -373.990171) (xy 160.981332 -373.990171) (xy 160.981332 -373.935629) (xy 160.989094 -373.881643)
			(xy 161.004461 -373.829311) (xy 161.027121 -373.779698) (xy 161.05661 -373.733816) (xy 161.092329 -373.692598)
			(xy 161.133551 -373.656884) (xy 161.179437 -373.627399) (xy 161.229052 -373.604746) (xy 161.281386 -373.589385)
			(xy 161.335373 -373.581628) (xy 161.362644 -373.581168) (xy 162.226244 -373.581168) (xy 162.253513 -373.581598)
			(xy 162.307497 -373.589365) (xy 162.359825 -373.604735) (xy 162.409433 -373.627396) (xy 162.455312 -373.656885)
			(xy 162.496528 -373.692603) (xy 162.532241 -373.733823) (xy 162.561725 -373.779705) (xy 162.58438 -373.829316)
			(xy 162.599744 -373.881647) (xy 162.607506 -373.93563) (xy 162.607506 -373.99017) (xy 162.599744 -374.044153)
			(xy 162.58438 -374.096484) (xy 162.561725 -374.146095) (xy 162.532241 -374.191977) (xy 162.496528 -374.233197)
			(xy 162.455312 -374.268915) (xy 162.409433 -374.298404) (xy 162.359825 -374.321065) (xy 162.307497 -374.336435)
			(xy 162.253513 -374.344202) (xy 162.226244 -374.344692) (xy 161.362644 -374.344692) (xy 161.335373 -374.344172)
			(xy 161.281386 -374.336415) (xy 161.229052 -374.321054) (xy 161.179437 -374.298401) (xy 161.133551 -374.268916)
			(xy 161.092329 -374.233202) (xy 161.05661 -374.191984) (xy 161.027121 -374.146102) (xy 161.004461 -374.096489)
			(xy 160.989094 -374.044157) (xy 160.981332 -373.990171) (xy 155.800306 -373.990171) (xy 155.792544 -374.044153)
			(xy 155.77718 -374.096484) (xy 155.754525 -374.146095) (xy 155.725041 -374.191977) (xy 155.689328 -374.233197)
			(xy 155.648112 -374.268915) (xy 155.602233 -374.298404) (xy 155.552625 -374.321065) (xy 155.500297 -374.336435)
			(xy 155.446313 -374.344202) (xy 155.419044 -374.344692) (xy 154.555444 -374.344692) (xy 154.528173 -374.344172)
			(xy 154.474186 -374.336415) (xy 154.421852 -374.321054) (xy 154.372237 -374.298401) (xy 154.326351 -374.268916)
			(xy 154.285129 -374.233202) (xy 154.24941 -374.191984) (xy 154.219921 -374.146102) (xy 154.197261 -374.096489)
			(xy 154.181894 -374.044157) (xy 154.174132 -373.990171) (xy 148.993106 -373.990171) (xy 148.985344 -374.044153)
			(xy 148.96998 -374.096484) (xy 148.947325 -374.146095) (xy 148.917841 -374.191977) (xy 148.882128 -374.233197)
			(xy 148.840912 -374.268915) (xy 148.795033 -374.298404) (xy 148.745425 -374.321065) (xy 148.693097 -374.336435)
			(xy 148.639113 -374.344202) (xy 148.611844 -374.344692) (xy 147.748244 -374.344692) (xy 147.720973 -374.344172)
			(xy 147.666986 -374.336415) (xy 147.614652 -374.321054) (xy 147.565037 -374.298401) (xy 147.519151 -374.268916)
			(xy 147.477929 -374.233202) (xy 147.44221 -374.191984) (xy 147.412721 -374.146102) (xy 147.390061 -374.096489)
			(xy 147.374694 -374.044157) (xy 147.366932 -373.990171) (xy 130.079828 -373.990171) (xy 130.079828 -373.990173)
			(xy 130.072066 -374.044165) (xy 130.056698 -374.096502) (xy 130.034038 -374.146119) (xy 130.004548 -374.192007)
			(xy 129.968827 -374.23323) (xy 129.927603 -374.26895) (xy 129.881716 -374.29844) (xy 129.832098 -374.321099)
			(xy 129.779761 -374.336466) (xy 129.725769 -374.344229) (xy 129.698496 -374.344692) (xy 128.834896 -374.344692)
			(xy 128.807629 -374.344145) (xy 128.75365 -374.336384) (xy 128.701325 -374.321019) (xy 128.651719 -374.298365)
			(xy 128.605842 -374.268881) (xy 128.564629 -374.233169) (xy 128.528917 -374.191954) (xy 128.499433 -374.146077)
			(xy 128.476779 -374.096471) (xy 128.461415 -374.044146) (xy 128.453654 -373.990167) (xy 123.272628 -373.990167)
			(xy 123.272628 -373.990173) (xy 123.264866 -374.044165) (xy 123.249498 -374.096502) (xy 123.226838 -374.146119)
			(xy 123.197348 -374.192007) (xy 123.161627 -374.23323) (xy 123.120403 -374.26895) (xy 123.074516 -374.29844)
			(xy 123.024898 -374.321099) (xy 122.972561 -374.336466) (xy 122.918569 -374.344229) (xy 122.891296 -374.344692)
			(xy 122.027696 -374.344692) (xy 122.000429 -374.344145) (xy 121.94645 -374.336384) (xy 121.894125 -374.321019)
			(xy 121.844519 -374.298365) (xy 121.798642 -374.268881) (xy 121.757429 -374.233169) (xy 121.721717 -374.191954)
			(xy 121.692233 -374.146077) (xy 121.669579 -374.096471) (xy 121.654215 -374.044146) (xy 121.646454 -373.990167)
			(xy 116.465428 -373.990167) (xy 116.465428 -373.990173) (xy 116.457666 -374.044165) (xy 116.442298 -374.096502)
			(xy 116.419638 -374.146119) (xy 116.390148 -374.192007) (xy 116.354427 -374.23323) (xy 116.313203 -374.26895)
			(xy 116.267316 -374.29844) (xy 116.217698 -374.321099) (xy 116.165361 -374.336466) (xy 116.111369 -374.344229)
			(xy 116.084096 -374.344692) (xy 115.220496 -374.344692) (xy 115.193229 -374.344145) (xy 115.13925 -374.336384)
			(xy 115.086925 -374.321019) (xy 115.037319 -374.298365) (xy 114.991442 -374.268881) (xy 114.950229 -374.233169)
			(xy 114.914517 -374.191954) (xy 114.885033 -374.146077) (xy 114.862379 -374.096471) (xy 114.847015 -374.044146)
			(xy 114.839254 -373.990167) (xy 95.507606 -373.990167) (xy 95.507606 -373.990171) (xy 95.499843 -374.044159)
			(xy 95.484477 -374.096493) (xy 95.461819 -374.146107) (xy 95.432331 -374.191991) (xy 95.396613 -374.233212)
			(xy 95.355393 -374.26893) (xy 95.309508 -374.298418) (xy 95.259894 -374.321076) (xy 95.207561 -374.336443)
			(xy 95.153573 -374.344205) (xy 95.126302 -374.344692) (xy 94.262702 -374.344692) (xy 94.235433 -374.344169)
			(xy 94.18145 -374.336407) (xy 94.129121 -374.321043) (xy 94.079512 -374.298387) (xy 94.033632 -374.268902)
			(xy 93.992414 -374.233187) (xy 93.9567 -374.19197) (xy 93.927214 -374.14609) (xy 93.904558 -374.09648)
			(xy 93.889193 -374.044152) (xy 93.881431 -373.990169) (xy 88.700406 -373.990169) (xy 88.700406 -373.990171)
			(xy 88.692643 -374.044159) (xy 88.677277 -374.096493) (xy 88.654619 -374.146107) (xy 88.625131 -374.191991)
			(xy 88.589413 -374.233212) (xy 88.548193 -374.26893) (xy 88.502308 -374.298418) (xy 88.452694 -374.321076)
			(xy 88.400361 -374.336443) (xy 88.346373 -374.344205) (xy 88.319102 -374.344692) (xy 87.455502 -374.344692)
			(xy 87.428233 -374.344169) (xy 87.37425 -374.336407) (xy 87.321921 -374.321043) (xy 87.272312 -374.298387)
			(xy 87.226432 -374.268902) (xy 87.185214 -374.233187) (xy 87.1495 -374.19197) (xy 87.120014 -374.14609)
			(xy 87.097358 -374.09648) (xy 87.081993 -374.044152) (xy 87.074231 -373.990169) (xy 81.893206 -373.990169)
			(xy 81.893206 -373.990171) (xy 81.885443 -374.044159) (xy 81.870077 -374.096493) (xy 81.847419 -374.146107)
			(xy 81.817931 -374.191991) (xy 81.782213 -374.233212) (xy 81.740993 -374.26893) (xy 81.695108 -374.298418)
			(xy 81.645494 -374.321076) (xy 81.593161 -374.336443) (xy 81.539173 -374.344205) (xy 81.511902 -374.344692)
			(xy 80.648302 -374.344692) (xy 80.621033 -374.344169) (xy 80.56705 -374.336407) (xy 80.514721 -374.321043)
			(xy 80.465112 -374.298387) (xy 80.419232 -374.268902) (xy 80.378014 -374.233187) (xy 80.3423 -374.19197)
			(xy 80.312814 -374.14609) (xy 80.290158 -374.09648) (xy 80.274793 -374.044152) (xy 80.267031 -373.990169)
			(xy 62.979928 -373.990169) (xy 62.979928 -373.990175) (xy 62.972164 -374.04417) (xy 62.956795 -374.096511)
			(xy 62.934132 -374.146131) (xy 62.904638 -374.19202) (xy 62.868912 -374.233245) (xy 62.827684 -374.268965)
			(xy 62.781791 -374.298454) (xy 62.732168 -374.321111) (xy 62.679825 -374.336474) (xy 62.625829 -374.344232)
			(xy 62.598554 -374.344692) (xy 61.734954 -374.344692) (xy 61.707689 -374.344143) (xy 61.653715 -374.336376)
			(xy 61.601395 -374.321008) (xy 61.551794 -374.298351) (xy 61.505923 -374.268866) (xy 61.464714 -374.233154)
			(xy 61.429006 -374.191941) (xy 61.399527 -374.146065) (xy 61.376876 -374.096462) (xy 61.361514 -374.04414)
			(xy 61.353754 -373.990165) (xy 56.172728 -373.990165) (xy 56.172728 -373.990175) (xy 56.164964 -374.04417)
			(xy 56.149595 -374.096511) (xy 56.126932 -374.146131) (xy 56.097438 -374.19202) (xy 56.061712 -374.233245)
			(xy 56.020484 -374.268965) (xy 55.974591 -374.298454) (xy 55.924968 -374.321111) (xy 55.872625 -374.336474)
			(xy 55.818629 -374.344232) (xy 55.791354 -374.344692) (xy 54.927754 -374.344692) (xy 54.900489 -374.344143)
			(xy 54.846515 -374.336376) (xy 54.794195 -374.321008) (xy 54.744594 -374.298351) (xy 54.698723 -374.268866)
			(xy 54.657514 -374.233154) (xy 54.621806 -374.191941) (xy 54.592327 -374.146065) (xy 54.569676 -374.096462)
			(xy 54.554314 -374.04414) (xy 54.546554 -373.990165) (xy 49.365528 -373.990165) (xy 49.365528 -373.990175)
			(xy 49.357764 -374.04417) (xy 49.342395 -374.096511) (xy 49.319732 -374.146131) (xy 49.290238 -374.19202)
			(xy 49.254512 -374.233245) (xy 49.213284 -374.268965) (xy 49.167391 -374.298454) (xy 49.117768 -374.321111)
			(xy 49.065425 -374.336474) (xy 49.011429 -374.344232) (xy 48.984154 -374.344692) (xy 48.120554 -374.344692)
			(xy 48.093289 -374.344143) (xy 48.039315 -374.336376) (xy 47.986995 -374.321008) (xy 47.937394 -374.298351)
			(xy 47.891523 -374.268866) (xy 47.850314 -374.233154) (xy 47.814606 -374.191941) (xy 47.785127 -374.146065)
			(xy 47.762476 -374.096462) (xy 47.747114 -374.04414) (xy 47.739354 -373.990165) (xy 38.193125 -373.990165)
			(xy 38.26468 -374.080777) (xy 38.368831 -374.22548) (xy 38.466433 -374.374679) (xy 38.557291 -374.528078)
			(xy 38.641225 -374.685372) (xy 38.71807 -374.846248) (xy 38.787671 -375.010389) (xy 38.849892 -375.177466)
			(xy 38.904608 -375.34715) (xy 38.95171 -375.519103) (xy 38.991106 -375.692983) (xy 39.022717 -375.868446)
			(xy 39.046481 -376.045142) (xy 39.062349 -376.222722) (xy 39.070291 -376.400832) (xy 39.070788 -376.489976)
			(xy 39.070291 -376.57912) (xy 39.062349 -376.75723) (xy 39.05568 -376.83186) (xy 41.04894 -376.83186)
			(xy 41.04894 -375.96826) (xy 41.049426 -375.940991) (xy 41.057188 -375.887007) (xy 41.072553 -375.834677)
			(xy 41.09521 -375.785067) (xy 41.124696 -375.739186) (xy 41.160411 -375.697969) (xy 41.201628 -375.662254)
			(xy 41.247509 -375.632768) (xy 41.297119 -375.610111) (xy 41.349449 -375.594746) (xy 41.403433 -375.586984)
			(xy 41.457971 -375.586984) (xy 41.511955 -375.594746) (xy 41.564285 -375.610111) (xy 41.613895 -375.632768)
			(xy 41.659776 -375.662254) (xy 41.700993 -375.697969) (xy 41.736708 -375.739186) (xy 41.766194 -375.785067)
			(xy 41.788851 -375.834677) (xy 41.804216 -375.887007) (xy 41.811978 -375.940991) (xy 41.812464 -375.96826)
			(xy 41.812464 -376.83186) (xy 41.811978 -376.859129) (xy 41.804216 -376.913113) (xy 41.791381 -376.956828)
			(xy 70.895972 -376.956828) (xy 70.895972 -376.093228) (xy 70.896458 -376.065959) (xy 70.90422 -376.011975)
			(xy 70.919585 -375.959645) (xy 70.942242 -375.910035) (xy 70.971728 -375.864154) (xy 71.007443 -375.822937)
			(xy 71.04866 -375.787222) (xy 71.094541 -375.757736) (xy 71.144151 -375.735079) (xy 71.196481 -375.719714)
			(xy 71.250465 -375.711952) (xy 71.305003 -375.711952) (xy 71.358987 -375.719714) (xy 71.411317 -375.735079)
			(xy 71.460927 -375.757736) (xy 71.506808 -375.787222) (xy 71.548025 -375.822937) (xy 71.58374 -375.864154)
			(xy 71.613226 -375.910035) (xy 71.635883 -375.959645) (xy 71.651248 -376.011975) (xy 71.65901 -376.065959)
			(xy 71.659496 -376.093228) (xy 71.659496 -376.83186) (xy 73.576688 -376.83186) (xy 73.576688 -375.96826)
			(xy 73.577174 -375.940991) (xy 73.584936 -375.887007) (xy 73.600301 -375.834677) (xy 73.622958 -375.785067)
			(xy 73.652444 -375.739186) (xy 73.688159 -375.697969) (xy 73.729376 -375.662254) (xy 73.775257 -375.632768)
			(xy 73.824867 -375.610111) (xy 73.877197 -375.594746) (xy 73.931181 -375.586984) (xy 73.985719 -375.586984)
			(xy 74.039703 -375.594746) (xy 74.092033 -375.610111) (xy 74.141643 -375.632768) (xy 74.187524 -375.662254)
			(xy 74.228741 -375.697969) (xy 74.264456 -375.739186) (xy 74.293942 -375.785067) (xy 74.316599 -375.834677)
			(xy 74.331964 -375.887007) (xy 74.339726 -375.940991) (xy 74.340212 -375.96826) (xy 74.340212 -376.83186)
			(xy 74.339726 -376.859129) (xy 74.331964 -376.913113) (xy 74.319129 -376.956828) (xy 103.42372 -376.956828)
			(xy 103.42372 -376.093228) (xy 103.424206 -376.065959) (xy 103.431968 -376.011975) (xy 103.447333 -375.959645)
			(xy 103.46999 -375.910035) (xy 103.499476 -375.864154) (xy 103.535191 -375.822937) (xy 103.576408 -375.787222)
			(xy 103.622289 -375.757736) (xy 103.671899 -375.735079) (xy 103.724229 -375.719714) (xy 103.778213 -375.711952)
			(xy 103.832751 -375.711952) (xy 103.886735 -375.719714) (xy 103.939065 -375.735079) (xy 103.988675 -375.757736)
			(xy 104.034556 -375.787222) (xy 104.075773 -375.822937) (xy 104.111488 -375.864154) (xy 104.140974 -375.910035)
			(xy 104.163631 -375.959645) (xy 104.178996 -376.011975) (xy 104.186758 -376.065959) (xy 104.187244 -376.093228)
			(xy 104.187244 -376.83186) (xy 108.149136 -376.83186) (xy 108.149136 -375.96826) (xy 108.149622 -375.941009)
			(xy 108.157378 -375.887061) (xy 108.172733 -375.834766) (xy 108.195375 -375.785189) (xy 108.224841 -375.739339)
			(xy 108.260532 -375.698148) (xy 108.301723 -375.662457) (xy 108.347573 -375.632991) (xy 108.39715 -375.610349)
			(xy 108.449445 -375.594994) (xy 108.503393 -375.587238) (xy 108.557895 -375.587238) (xy 108.611843 -375.594994)
			(xy 108.664138 -375.610349) (xy 108.713715 -375.632991) (xy 108.759565 -375.662457) (xy 108.800756 -375.698148)
			(xy 108.836447 -375.739339) (xy 108.865913 -375.785189) (xy 108.888555 -375.834766) (xy 108.90391 -375.887061)
			(xy 108.911666 -375.941009) (xy 108.912152 -375.96826) (xy 108.912152 -376.83186) (xy 108.911666 -376.859111)
			(xy 108.90391 -376.913059) (xy 108.891058 -376.956828) (xy 137.996168 -376.956828) (xy 137.996168 -376.093228)
			(xy 137.996654 -376.065977) (xy 138.00441 -376.012029) (xy 138.019765 -375.959734) (xy 138.042407 -375.910157)
			(xy 138.071873 -375.864307) (xy 138.107564 -375.823116) (xy 138.148755 -375.787425) (xy 138.194605 -375.757959)
			(xy 138.244182 -375.735317) (xy 138.296477 -375.719962) (xy 138.350425 -375.712206) (xy 138.404927 -375.712206)
			(xy 138.458875 -375.719962) (xy 138.51117 -375.735317) (xy 138.560747 -375.757959) (xy 138.606597 -375.787425)
			(xy 138.647788 -375.823116) (xy 138.683479 -375.864307) (xy 138.712945 -375.910157) (xy 138.735587 -375.959734)
			(xy 138.750942 -376.012029) (xy 138.758698 -376.065977) (xy 138.759184 -376.093228) (xy 138.759184 -376.83186)
			(xy 140.676884 -376.83186) (xy 140.676884 -375.96826) (xy 140.67737 -375.941009) (xy 140.685126 -375.887061)
			(xy 140.700481 -375.834766) (xy 140.723123 -375.785189) (xy 140.752589 -375.739339) (xy 140.78828 -375.698148)
			(xy 140.829471 -375.662457) (xy 140.875321 -375.632991) (xy 140.924898 -375.610349) (xy 140.977193 -375.594994)
			(xy 141.031141 -375.587238) (xy 141.085643 -375.587238) (xy 141.139591 -375.594994) (xy 141.191886 -375.610349)
			(xy 141.241463 -375.632991) (xy 141.287313 -375.662457) (xy 141.328504 -375.698148) (xy 141.364195 -375.739339)
			(xy 141.393661 -375.785189) (xy 141.416303 -375.834766) (xy 141.431658 -375.887061) (xy 141.439414 -375.941009)
			(xy 141.4399 -375.96826) (xy 141.4399 -376.83186) (xy 141.439414 -376.859111) (xy 141.431658 -376.913059)
			(xy 141.418806 -376.956828) (xy 170.523916 -376.956828) (xy 170.523916 -376.093228) (xy 170.524402 -376.065977)
			(xy 170.532158 -376.012029) (xy 170.547513 -375.959734) (xy 170.570155 -375.910157) (xy 170.599621 -375.864307)
			(xy 170.635312 -375.823116) (xy 170.676503 -375.787425) (xy 170.722353 -375.757959) (xy 170.77193 -375.735317)
			(xy 170.824225 -375.719962) (xy 170.878173 -375.712206) (xy 170.932675 -375.712206) (xy 170.986623 -375.719962)
			(xy 171.038918 -375.735317) (xy 171.088495 -375.757959) (xy 171.134345 -375.787425) (xy 171.175536 -375.823116)
			(xy 171.211227 -375.864307) (xy 171.240693 -375.910157) (xy 171.263335 -375.959734) (xy 171.27869 -376.012029)
			(xy 171.286446 -376.065977) (xy 171.286932 -376.093228) (xy 171.286932 -376.489976) (xy 173.498776 -376.489976)
			(xy 173.502748 -376.311733) (xy 173.514656 -376.133844) (xy 173.534477 -375.956662) (xy 173.562171 -375.780538)
			(xy 173.597683 -375.605823) (xy 173.640943 -375.432864) (xy 173.691865 -375.262003) (xy 173.750348 -375.093581)
			(xy 173.816275 -374.927931) (xy 173.889516 -374.765382) (xy 173.969926 -374.606257) (xy 174.057344 -374.450872)
			(xy 174.151597 -374.299536) (xy 174.252498 -374.152548) (xy 174.359847 -374.010201) (xy 174.47343 -373.872778)
			(xy 174.593023 -373.740551) (xy 174.718387 -373.613782) (xy 174.849274 -373.492724) (xy 174.985423 -373.377617)
			(xy 175.126565 -373.268689) (xy 175.27242 -373.166157) (xy 175.422697 -373.070223) (xy 175.577098 -372.98108)
			(xy 175.735317 -372.898903) (xy 175.89704 -372.823855) (xy 176.061945 -372.756087) (xy 176.229706 -372.695731)
			(xy 176.399989 -372.642909) (xy 176.572456 -372.597725) (xy 176.746764 -372.560268) (xy 176.922568 -372.530614)
			(xy 177.099518 -372.508821) (xy 177.277264 -372.494931) (xy 177.455451 -372.488974) (xy 177.633728 -372.49096)
			(xy 177.811739 -372.500886) (xy 177.989131 -372.518732) (xy 178.165551 -372.544462) (xy 178.340651 -372.578026)
			(xy 178.514082 -372.619356) (xy 178.685499 -372.668372) (xy 178.854562 -372.724974) (xy 179.020937 -372.789052)
			(xy 179.184291 -372.860478) (xy 179.344302 -372.93911) (xy 179.500651 -373.024791) (xy 179.653028 -373.117353)
			(xy 179.801131 -373.21661) (xy 179.944665 -373.322367) (xy 180.083345 -373.434412) (xy 180.216896 -373.552524)
			(xy 180.345053 -373.676468) (xy 180.467562 -373.805998) (xy 180.584179 -373.940857) (xy 180.596796 -373.956834)
			(xy 282.853384 -373.956834) (xy 282.853384 -373.093234) (xy 282.85387 -373.065983) (xy 282.861626 -373.012035)
			(xy 282.876981 -372.95974) (xy 282.899623 -372.910163) (xy 282.929089 -372.864313) (xy 282.96478 -372.823122)
			(xy 283.005971 -372.787431) (xy 283.051821 -372.757965) (xy 283.101398 -372.735323) (xy 283.153693 -372.719968)
			(xy 283.207641 -372.712212) (xy 283.262143 -372.712212) (xy 283.316091 -372.719968) (xy 283.368386 -372.735323)
			(xy 283.417963 -372.757965) (xy 283.463813 -372.787431) (xy 283.505004 -372.823122) (xy 283.540695 -372.864313)
			(xy 283.570161 -372.910163) (xy 283.592803 -372.95974) (xy 283.608158 -373.012035) (xy 283.615914 -373.065983)
			(xy 283.6164 -373.093234) (xy 283.6164 -373.956834) (xy 283.615914 -373.984085) (xy 283.608158 -374.038033)
			(xy 283.592803 -374.090328) (xy 283.570161 -374.139905) (xy 283.540695 -374.185755) (xy 283.505004 -374.226946)
			(xy 283.463813 -374.262637) (xy 283.417963 -374.292103) (xy 283.368386 -374.314745) (xy 283.316091 -374.3301)
			(xy 283.262143 -374.337856) (xy 283.207641 -374.337856) (xy 283.153693 -374.3301) (xy 283.101398 -374.314745)
			(xy 283.051821 -374.292103) (xy 283.005971 -374.262637) (xy 282.96478 -374.226946) (xy 282.929089 -374.185755)
			(xy 282.899623 -374.139905) (xy 282.876981 -374.090328) (xy 282.861626 -374.038033) (xy 282.85387 -373.984085)
			(xy 282.853384 -373.956834) (xy 180.596796 -373.956834) (xy 180.694672 -374.080777) (xy 180.798823 -374.22548)
			(xy 180.896425 -374.374679) (xy 180.987283 -374.528078) (xy 181.071217 -374.685372) (xy 181.148062 -374.846248)
			(xy 181.217663 -375.010389) (xy 181.279884 -375.177466) (xy 181.3346 -375.34715) (xy 181.381702 -375.519103)
			(xy 181.421098 -375.692983) (xy 181.452709 -375.868446) (xy 181.476473 -376.045142) (xy 181.492341 -376.222722)
			(xy 181.500283 -376.400832) (xy 181.50078 -376.489976) (xy 181.500283 -376.57912) (xy 181.492341 -376.75723)
			(xy 181.476473 -376.93481) (xy 181.452709 -377.111506) (xy 181.421098 -377.286969) (xy 181.381702 -377.460849)
			(xy 181.3346 -377.632802) (xy 181.319901 -377.678385) (xy 193.900548 -377.678385) (xy 193.900548 -377.593663)
			(xy 193.908601 -377.509326) (xy 193.924635 -377.426136) (xy 193.948503 -377.344846) (xy 193.979991 -377.266194)
			(xy 194.018813 -377.190891) (xy 194.064616 -377.119619) (xy 194.116987 -377.053023) (xy 194.175452 -376.991708)
			(xy 194.23948 -376.936227) (xy 194.308492 -376.887084) (xy 194.381862 -376.844724) (xy 194.458927 -376.809529)
			(xy 194.538989 -376.78182) (xy 194.621322 -376.761846) (xy 194.705181 -376.749789) (xy 194.789806 -376.745758)
			(xy 194.874431 -376.749789) (xy 194.95829 -376.761846) (xy 195.040623 -376.78182) (xy 195.120685 -376.809529)
			(xy 195.19775 -376.844724) (xy 195.27112 -376.887084) (xy 195.340132 -376.936227) (xy 195.40416 -376.991708)
			(xy 195.462625 -377.053023) (xy 195.514996 -377.119619) (xy 195.560799 -377.190891) (xy 195.599621 -377.266194)
			(xy 195.631109 -377.344846) (xy 195.654977 -377.426136) (xy 195.671011 -377.509326) (xy 195.679064 -377.593663)
			(xy 195.679568 -377.636024) (xy 195.679064 -377.678385) (xy 195.671011 -377.762722) (xy 195.654977 -377.845912)
			(xy 195.631109 -377.927202) (xy 195.599621 -378.005854) (xy 195.560799 -378.081157) (xy 195.514996 -378.152429)
			(xy 195.47531 -378.202895) (xy 199.443082 -378.202895) (xy 199.443082 -378.118173) (xy 199.451135 -378.033836)
			(xy 199.467169 -377.950646) (xy 199.491037 -377.869356) (xy 199.522525 -377.790704) (xy 199.561347 -377.715401)
			(xy 199.60715 -377.644129) (xy 199.659521 -377.577533) (xy 199.717986 -377.516218) (xy 199.782014 -377.460737)
			(xy 199.851026 -377.411594) (xy 199.924396 -377.369234) (xy 200.001461 -377.334039) (xy 200.081523 -377.30633)
			(xy 200.163856 -377.286356) (xy 200.247715 -377.274299) (xy 200.33234 -377.270268) (xy 200.416965 -377.274299)
			(xy 200.500824 -377.286356) (xy 200.583157 -377.30633) (xy 200.663219 -377.334039) (xy 200.740284 -377.369234)
			(xy 200.813654 -377.411594) (xy 200.859958 -377.444567) (xy 300.335454 -377.444567) (xy 300.335454 -377.390033)
			(xy 300.343215 -377.336054) (xy 300.358579 -377.283729) (xy 300.381233 -377.234123) (xy 300.410717 -377.188246)
			(xy 300.446429 -377.147031) (xy 300.487642 -377.111319) (xy 300.533519 -377.081835) (xy 300.583125 -377.059181)
			(xy 300.63545 -377.043816) (xy 300.689429 -377.036055) (xy 300.716696 -377.035568) (xy 301.580296 -377.035568)
			(xy 301.607569 -377.035971) (xy 301.661561 -377.043734) (xy 301.713898 -377.059101) (xy 301.763516 -377.08176)
			(xy 301.809403 -377.11125) (xy 301.850627 -377.14697) (xy 301.886348 -377.188193) (xy 301.915838 -377.234081)
			(xy 301.938498 -377.283698) (xy 301.953866 -377.336035) (xy 301.961628 -377.390027) (xy 301.961628 -377.444567)
			(xy 307.142654 -377.444567) (xy 307.142654 -377.390033) (xy 307.150415 -377.336054) (xy 307.165779 -377.283729)
			(xy 307.188433 -377.234123) (xy 307.217917 -377.188246) (xy 307.253629 -377.147031) (xy 307.294842 -377.111319)
			(xy 307.340719 -377.081835) (xy 307.390325 -377.059181) (xy 307.44265 -377.043816) (xy 307.496629 -377.036055)
			(xy 307.523896 -377.035568) (xy 308.387496 -377.035568) (xy 308.414769 -377.035971) (xy 308.468761 -377.043734)
			(xy 308.521098 -377.059101) (xy 308.570716 -377.08176) (xy 308.616603 -377.11125) (xy 308.657827 -377.14697)
			(xy 308.693548 -377.188193) (xy 308.723038 -377.234081) (xy 308.745698 -377.283698) (xy 308.761066 -377.336035)
			(xy 308.768828 -377.390027) (xy 308.768828 -377.444567) (xy 313.949854 -377.444567) (xy 313.949854 -377.390033)
			(xy 313.957615 -377.336054) (xy 313.972979 -377.283729) (xy 313.995633 -377.234123) (xy 314.025117 -377.188246)
			(xy 314.060829 -377.147031) (xy 314.102042 -377.111319) (xy 314.147919 -377.081835) (xy 314.197525 -377.059181)
			(xy 314.24985 -377.043816) (xy 314.303829 -377.036055) (xy 314.331096 -377.035568) (xy 315.194696 -377.035568)
			(xy 315.221969 -377.035971) (xy 315.275961 -377.043734) (xy 315.328298 -377.059101) (xy 315.377916 -377.08176)
			(xy 315.423803 -377.11125) (xy 315.465027 -377.14697) (xy 315.500748 -377.188193) (xy 315.530238 -377.234081)
			(xy 315.552898 -377.283698) (xy 315.568266 -377.336035) (xy 315.576028 -377.390027) (xy 315.576028 -377.444567)
			(xy 320.757054 -377.444567) (xy 320.757054 -377.390033) (xy 320.764815 -377.336054) (xy 320.780179 -377.283729)
			(xy 320.802833 -377.234123) (xy 320.832317 -377.188246) (xy 320.868029 -377.147031) (xy 320.909242 -377.111319)
			(xy 320.955119 -377.081835) (xy 321.004725 -377.059181) (xy 321.05705 -377.043816) (xy 321.111029 -377.036055)
			(xy 321.138296 -377.035568) (xy 322.001896 -377.035568) (xy 322.029169 -377.035971) (xy 322.083161 -377.043734)
			(xy 322.135498 -377.059101) (xy 322.185116 -377.08176) (xy 322.231003 -377.11125) (xy 322.272227 -377.14697)
			(xy 322.307948 -377.188193) (xy 322.337438 -377.234081) (xy 322.360098 -377.283698) (xy 322.375466 -377.336035)
			(xy 322.383228 -377.390027) (xy 322.383228 -377.444567) (xy 324.160654 -377.444567) (xy 324.160654 -377.390033)
			(xy 324.168415 -377.336054) (xy 324.183779 -377.283729) (xy 324.206433 -377.234123) (xy 324.235917 -377.188246)
			(xy 324.271629 -377.147031) (xy 324.312842 -377.111319) (xy 324.358719 -377.081835) (xy 324.408325 -377.059181)
			(xy 324.46065 -377.043816) (xy 324.514629 -377.036055) (xy 324.541896 -377.035568) (xy 325.405496 -377.035568)
			(xy 325.432769 -377.035971) (xy 325.486761 -377.043734) (xy 325.539098 -377.059101) (xy 325.588716 -377.08176)
			(xy 325.634603 -377.11125) (xy 325.675827 -377.14697) (xy 325.711548 -377.188193) (xy 325.741038 -377.234081)
			(xy 325.763698 -377.283698) (xy 325.779066 -377.336035) (xy 325.786828 -377.390027) (xy 325.786828 -377.444571)
			(xy 332.863132 -377.444571) (xy 332.863132 -377.390029) (xy 332.870894 -377.336043) (xy 332.886261 -377.283711)
			(xy 332.908921 -377.234098) (xy 332.93841 -377.188216) (xy 332.974129 -377.146998) (xy 333.015351 -377.111284)
			(xy 333.061237 -377.081799) (xy 333.110852 -377.059146) (xy 333.163186 -377.043785) (xy 333.217173 -377.036028)
			(xy 333.244444 -377.035568) (xy 334.108044 -377.035568) (xy 334.135313 -377.035998) (xy 334.189297 -377.043765)
			(xy 334.241625 -377.059135) (xy 334.291233 -377.081796) (xy 334.337112 -377.111285) (xy 334.378328 -377.147003)
			(xy 334.414041 -377.188223) (xy 334.443525 -377.234105) (xy 334.46618 -377.283716) (xy 334.481544 -377.336047)
			(xy 334.489306 -377.39003) (xy 334.489306 -377.44457) (xy 334.489306 -377.444571) (xy 339.670332 -377.444571)
			(xy 339.670332 -377.390029) (xy 339.678094 -377.336043) (xy 339.693461 -377.283711) (xy 339.716121 -377.234098)
			(xy 339.74561 -377.188216) (xy 339.781329 -377.146998) (xy 339.822551 -377.111284) (xy 339.868437 -377.081799)
			(xy 339.918052 -377.059146) (xy 339.970386 -377.043785) (xy 340.024373 -377.036028) (xy 340.051644 -377.035568)
			(xy 340.915244 -377.035568) (xy 340.942513 -377.035998) (xy 340.996497 -377.043765) (xy 341.048825 -377.059135)
			(xy 341.098433 -377.081796) (xy 341.144312 -377.111285) (xy 341.185528 -377.147003) (xy 341.221241 -377.188223)
			(xy 341.250725 -377.234105) (xy 341.27338 -377.283716) (xy 341.288744 -377.336047) (xy 341.296506 -377.39003)
			(xy 341.296506 -377.44457) (xy 341.296506 -377.444571) (xy 346.477532 -377.444571) (xy 346.477532 -377.390029)
			(xy 346.485294 -377.336043) (xy 346.500661 -377.283711) (xy 346.523321 -377.234098) (xy 346.55281 -377.188216)
			(xy 346.588529 -377.146998) (xy 346.629751 -377.111284) (xy 346.675637 -377.081799) (xy 346.725252 -377.059146)
			(xy 346.777586 -377.043785) (xy 346.831573 -377.036028) (xy 346.858844 -377.035568) (xy 347.722444 -377.035568)
			(xy 347.749713 -377.035998) (xy 347.803697 -377.043765) (xy 347.856025 -377.059135) (xy 347.905633 -377.081796)
			(xy 347.951512 -377.111285) (xy 347.992728 -377.147003) (xy 348.028441 -377.188223) (xy 348.057925 -377.234105)
			(xy 348.08058 -377.283716) (xy 348.095944 -377.336047) (xy 348.103706 -377.39003) (xy 348.103706 -377.44457)
			(xy 348.103706 -377.444571) (xy 353.284732 -377.444571) (xy 353.284732 -377.390029) (xy 353.292494 -377.336043)
			(xy 353.307861 -377.283711) (xy 353.330521 -377.234098) (xy 353.36001 -377.188216) (xy 353.395729 -377.146998)
			(xy 353.436951 -377.111284) (xy 353.482837 -377.081799) (xy 353.532452 -377.059146) (xy 353.584786 -377.043785)
			(xy 353.638773 -377.036028) (xy 353.666044 -377.035568) (xy 354.529644 -377.035568) (xy 354.556913 -377.035998)
			(xy 354.610897 -377.043765) (xy 354.663225 -377.059135) (xy 354.712833 -377.081796) (xy 354.758712 -377.111285)
			(xy 354.799928 -377.147003) (xy 354.835641 -377.188223) (xy 354.865125 -377.234105) (xy 354.88778 -377.283716)
			(xy 354.903144 -377.336047) (xy 354.910906 -377.39003) (xy 354.910906 -377.44457) (xy 354.910906 -377.444571)
			(xy 356.688332 -377.444571) (xy 356.688332 -377.390029) (xy 356.696094 -377.336043) (xy 356.711461 -377.283711)
			(xy 356.734121 -377.234098) (xy 356.76361 -377.188216) (xy 356.799329 -377.146998) (xy 356.840551 -377.111284)
			(xy 356.886437 -377.081799) (xy 356.936052 -377.059146) (xy 356.988386 -377.043785) (xy 357.042373 -377.036028)
			(xy 357.069644 -377.035568) (xy 357.933244 -377.035568) (xy 357.960513 -377.035998) (xy 358.014497 -377.043765)
			(xy 358.066825 -377.059135) (xy 358.116433 -377.081796) (xy 358.162312 -377.111285) (xy 358.203528 -377.147003)
			(xy 358.239241 -377.188223) (xy 358.268725 -377.234105) (xy 358.29138 -377.283716) (xy 358.306744 -377.336047)
			(xy 358.314506 -377.39003) (xy 358.314506 -377.444567) (xy 367.435654 -377.444567) (xy 367.435654 -377.390033)
			(xy 367.443415 -377.336054) (xy 367.458779 -377.28373) (xy 367.481433 -377.234124) (xy 367.510916 -377.188247)
			(xy 367.546627 -377.147033) (xy 367.587841 -377.11132) (xy 367.633717 -377.081837) (xy 367.683322 -377.059182)
			(xy 367.735647 -377.043817) (xy 367.789625 -377.036055) (xy 367.816892 -377.035568) (xy 368.680492 -377.035568)
			(xy 368.707766 -377.035971) (xy 368.761757 -377.043733) (xy 368.814095 -377.0591) (xy 368.863713 -377.081759)
			(xy 368.909602 -377.111248) (xy 368.950826 -377.146968) (xy 368.986547 -377.188192) (xy 369.016038 -377.23408)
			(xy 369.038698 -377.283697) (xy 369.054065 -377.336035) (xy 369.061828 -377.390026) (xy 369.061828 -377.444567)
			(xy 374.242854 -377.444567) (xy 374.242854 -377.390033) (xy 374.250615 -377.336054) (xy 374.265979 -377.28373)
			(xy 374.288633 -377.234124) (xy 374.318116 -377.188247) (xy 374.353827 -377.147033) (xy 374.395041 -377.11132)
			(xy 374.440917 -377.081837) (xy 374.490522 -377.059182) (xy 374.542847 -377.043817) (xy 374.596825 -377.036055)
			(xy 374.624092 -377.035568) (xy 375.487692 -377.035568) (xy 375.514966 -377.035971) (xy 375.568957 -377.043733)
			(xy 375.621295 -377.0591) (xy 375.670913 -377.081759) (xy 375.716802 -377.111248) (xy 375.758026 -377.146968)
			(xy 375.793747 -377.188192) (xy 375.823238 -377.23408) (xy 375.845898 -377.283697) (xy 375.861265 -377.336035)
			(xy 375.869028 -377.390026) (xy 375.869028 -377.444567) (xy 381.050054 -377.444567) (xy 381.050054 -377.390033)
			(xy 381.057815 -377.336054) (xy 381.073179 -377.28373) (xy 381.095833 -377.234124) (xy 381.125316 -377.188247)
			(xy 381.161027 -377.147033) (xy 381.202241 -377.11132) (xy 381.248117 -377.081837) (xy 381.297722 -377.059182)
			(xy 381.350047 -377.043817) (xy 381.404025 -377.036055) (xy 381.431292 -377.035568) (xy 382.294892 -377.035568)
			(xy 382.322166 -377.035971) (xy 382.376157 -377.043733) (xy 382.428495 -377.0591) (xy 382.478113 -377.081759)
			(xy 382.524002 -377.111248) (xy 382.565226 -377.146968) (xy 382.600947 -377.188192) (xy 382.630438 -377.23408)
			(xy 382.653098 -377.283697) (xy 382.668465 -377.336035) (xy 382.676228 -377.390026) (xy 382.676228 -377.444567)
			(xy 387.857254 -377.444567) (xy 387.857254 -377.390033) (xy 387.865015 -377.336054) (xy 387.880379 -377.28373)
			(xy 387.903033 -377.234124) (xy 387.932516 -377.188247) (xy 387.968227 -377.147033) (xy 388.009441 -377.11132)
			(xy 388.055317 -377.081837) (xy 388.104922 -377.059182) (xy 388.157247 -377.043817) (xy 388.211225 -377.036055)
			(xy 388.238492 -377.035568) (xy 389.102092 -377.035568) (xy 389.129366 -377.035971) (xy 389.183357 -377.043733)
			(xy 389.235695 -377.0591) (xy 389.285313 -377.081759) (xy 389.331202 -377.111248) (xy 389.372426 -377.146968)
			(xy 389.408147 -377.188192) (xy 389.437638 -377.23408) (xy 389.460298 -377.283697) (xy 389.475665 -377.336035)
			(xy 389.483428 -377.390026) (xy 389.483428 -377.444567) (xy 391.260854 -377.444567) (xy 391.260854 -377.390033)
			(xy 391.268615 -377.336054) (xy 391.283979 -377.28373) (xy 391.306633 -377.234124) (xy 391.336116 -377.188247)
			(xy 391.371827 -377.147033) (xy 391.413041 -377.11132) (xy 391.458917 -377.081837) (xy 391.508522 -377.059182)
			(xy 391.560847 -377.043817) (xy 391.614825 -377.036055) (xy 391.642092 -377.035568) (xy 392.505692 -377.035568)
			(xy 392.532966 -377.035971) (xy 392.586957 -377.043733) (xy 392.639295 -377.0591) (xy 392.688913 -377.081759)
			(xy 392.734802 -377.111248) (xy 392.776026 -377.146968) (xy 392.811747 -377.188192) (xy 392.841238 -377.23408)
			(xy 392.863898 -377.283697) (xy 392.879265 -377.336035) (xy 392.887028 -377.390026) (xy 392.887028 -377.444571)
			(xy 399.963332 -377.444571) (xy 399.963332 -377.390029) (xy 399.971094 -377.336043) (xy 399.986461 -377.283711)
			(xy 400.00912 -377.234099) (xy 400.038609 -377.188217) (xy 400.074328 -377.147) (xy 400.11555 -377.111285)
			(xy 400.161435 -377.081801) (xy 400.211049 -377.059147) (xy 400.263382 -377.043786) (xy 400.317369 -377.036029)
			(xy 400.34464 -377.035568) (xy 401.20824 -377.035568) (xy 401.23551 -377.035997) (xy 401.289493 -377.043764)
			(xy 401.341822 -377.059134) (xy 401.391431 -377.081794) (xy 401.437311 -377.111284) (xy 401.478527 -377.147002)
			(xy 401.51424 -377.188222) (xy 401.543725 -377.234104) (xy 401.56638 -377.283716) (xy 401.581744 -377.336046)
			(xy 401.589506 -377.39003) (xy 401.589506 -377.44457) (xy 401.589506 -377.444571) (xy 406.770532 -377.444571)
			(xy 406.770532 -377.390029) (xy 406.778294 -377.336043) (xy 406.793661 -377.283711) (xy 406.81632 -377.234099)
			(xy 406.845809 -377.188217) (xy 406.881528 -377.147) (xy 406.92275 -377.111285) (xy 406.968635 -377.081801)
			(xy 407.018249 -377.059147) (xy 407.070582 -377.043786) (xy 407.124569 -377.036029) (xy 407.15184 -377.035568)
			(xy 408.01544 -377.035568) (xy 408.04271 -377.035997) (xy 408.096693 -377.043764) (xy 408.149022 -377.059134)
			(xy 408.198631 -377.081794) (xy 408.244511 -377.111284) (xy 408.285727 -377.147002) (xy 408.32144 -377.188222)
			(xy 408.350925 -377.234104) (xy 408.37358 -377.283716) (xy 408.388944 -377.336046) (xy 408.396706 -377.39003)
			(xy 408.396706 -377.44457) (xy 408.396706 -377.444571) (xy 413.577732 -377.444571) (xy 413.577732 -377.390029)
			(xy 413.585494 -377.336043) (xy 413.600861 -377.283711) (xy 413.62352 -377.234099) (xy 413.653009 -377.188217)
			(xy 413.688728 -377.147) (xy 413.72995 -377.111285) (xy 413.775835 -377.081801) (xy 413.825449 -377.059147)
			(xy 413.877782 -377.043786) (xy 413.931769 -377.036029) (xy 413.95904 -377.035568) (xy 414.82264 -377.035568)
			(xy 414.84991 -377.035997) (xy 414.903893 -377.043764) (xy 414.956222 -377.059134) (xy 415.005831 -377.081794)
			(xy 415.051711 -377.111284) (xy 415.092927 -377.147002) (xy 415.12864 -377.188222) (xy 415.158125 -377.234104)
			(xy 415.18078 -377.283716) (xy 415.196144 -377.336046) (xy 415.203906 -377.39003) (xy 415.203906 -377.44457)
			(xy 415.203906 -377.444571) (xy 420.384932 -377.444571) (xy 420.384932 -377.390029) (xy 420.392694 -377.336043)
			(xy 420.408061 -377.283711) (xy 420.43072 -377.234099) (xy 420.460209 -377.188217) (xy 420.495928 -377.147)
			(xy 420.53715 -377.111285) (xy 420.583035 -377.081801) (xy 420.632649 -377.059147) (xy 420.684982 -377.043786)
			(xy 420.738969 -377.036029) (xy 420.76624 -377.035568) (xy 421.62984 -377.035568) (xy 421.65711 -377.035997)
			(xy 421.711093 -377.043764) (xy 421.763422 -377.059134) (xy 421.813031 -377.081794) (xy 421.858911 -377.111284)
			(xy 421.900127 -377.147002) (xy 421.93584 -377.188222) (xy 421.965325 -377.234104) (xy 421.98798 -377.283716)
			(xy 422.003344 -377.336046) (xy 422.011106 -377.39003) (xy 422.011106 -377.44457) (xy 422.011106 -377.444571)
			(xy 423.788532 -377.444571) (xy 423.788532 -377.390029) (xy 423.796294 -377.336043) (xy 423.811661 -377.283711)
			(xy 423.83432 -377.234099) (xy 423.863809 -377.188217) (xy 423.899528 -377.147) (xy 423.94075 -377.111285)
			(xy 423.986635 -377.081801) (xy 424.036249 -377.059147) (xy 424.088582 -377.043786) (xy 424.142569 -377.036029)
			(xy 424.16984 -377.035568) (xy 425.03344 -377.035568) (xy 425.06071 -377.035997) (xy 425.114693 -377.043764)
			(xy 425.167022 -377.059134) (xy 425.216631 -377.081794) (xy 425.262511 -377.111284) (xy 425.303727 -377.147002)
			(xy 425.33944 -377.188222) (xy 425.368925 -377.234104) (xy 425.39158 -377.283716) (xy 425.406944 -377.336046)
			(xy 425.414706 -377.39003) (xy 425.414706 -377.44457) (xy 425.406944 -377.498554) (xy 425.39158 -377.550884)
			(xy 425.368925 -377.600496) (xy 425.33944 -377.646378) (xy 425.303727 -377.687598) (xy 425.262511 -377.723316)
			(xy 425.216631 -377.752806) (xy 425.167022 -377.775466) (xy 425.114693 -377.790836) (xy 425.06071 -377.798603)
			(xy 425.03344 -377.799092) (xy 424.16984 -377.799092) (xy 424.142569 -377.798571) (xy 424.088582 -377.790814)
			(xy 424.036249 -377.775453) (xy 423.986635 -377.752799) (xy 423.94075 -377.723315) (xy 423.899528 -377.6876)
			(xy 423.863809 -377.646383) (xy 423.83432 -377.600501) (xy 423.811661 -377.550889) (xy 423.796294 -377.498557)
			(xy 423.788532 -377.444571) (xy 422.011106 -377.444571) (xy 422.003344 -377.498554) (xy 421.98798 -377.550884)
			(xy 421.965325 -377.600496) (xy 421.93584 -377.646378) (xy 421.900127 -377.687598) (xy 421.858911 -377.723316)
			(xy 421.813031 -377.752806) (xy 421.763422 -377.775466) (xy 421.711093 -377.790836) (xy 421.65711 -377.798603)
			(xy 421.62984 -377.799092) (xy 420.76624 -377.799092) (xy 420.738969 -377.798571) (xy 420.684982 -377.790814)
			(xy 420.632649 -377.775453) (xy 420.583035 -377.752799) (xy 420.53715 -377.723315) (xy 420.495928 -377.6876)
			(xy 420.460209 -377.646383) (xy 420.43072 -377.600501) (xy 420.408061 -377.550889) (xy 420.392694 -377.498557)
			(xy 420.384932 -377.444571) (xy 415.203906 -377.444571) (xy 415.196144 -377.498554) (xy 415.18078 -377.550884)
			(xy 415.158125 -377.600496) (xy 415.12864 -377.646378) (xy 415.092927 -377.687598) (xy 415.051711 -377.723316)
			(xy 415.005831 -377.752806) (xy 414.956222 -377.775466) (xy 414.903893 -377.790836) (xy 414.84991 -377.798603)
			(xy 414.82264 -377.799092) (xy 413.95904 -377.799092) (xy 413.931769 -377.798571) (xy 413.877782 -377.790814)
			(xy 413.825449 -377.775453) (xy 413.775835 -377.752799) (xy 413.72995 -377.723315) (xy 413.688728 -377.6876)
			(xy 413.653009 -377.646383) (xy 413.62352 -377.600501) (xy 413.600861 -377.550889) (xy 413.585494 -377.498557)
			(xy 413.577732 -377.444571) (xy 408.396706 -377.444571) (xy 408.388944 -377.498554) (xy 408.37358 -377.550884)
			(xy 408.350925 -377.600496) (xy 408.32144 -377.646378) (xy 408.285727 -377.687598) (xy 408.244511 -377.723316)
			(xy 408.198631 -377.752806) (xy 408.149022 -377.775466) (xy 408.096693 -377.790836) (xy 408.04271 -377.798603)
			(xy 408.01544 -377.799092) (xy 407.15184 -377.799092) (xy 407.124569 -377.798571) (xy 407.070582 -377.790814)
			(xy 407.018249 -377.775453) (xy 406.968635 -377.752799) (xy 406.92275 -377.723315) (xy 406.881528 -377.6876)
			(xy 406.845809 -377.646383) (xy 406.81632 -377.600501) (xy 406.793661 -377.550889) (xy 406.778294 -377.498557)
			(xy 406.770532 -377.444571) (xy 401.589506 -377.444571) (xy 401.581744 -377.498554) (xy 401.56638 -377.550884)
			(xy 401.543725 -377.600496) (xy 401.51424 -377.646378) (xy 401.478527 -377.687598) (xy 401.437311 -377.723316)
			(xy 401.391431 -377.752806) (xy 401.341822 -377.775466) (xy 401.289493 -377.790836) (xy 401.23551 -377.798603)
			(xy 401.20824 -377.799092) (xy 400.34464 -377.799092) (xy 400.317369 -377.798571) (xy 400.263382 -377.790814)
			(xy 400.211049 -377.775453) (xy 400.161435 -377.752799) (xy 400.11555 -377.723315) (xy 400.074328 -377.6876)
			(xy 400.038609 -377.646383) (xy 400.00912 -377.600501) (xy 399.986461 -377.550889) (xy 399.971094 -377.498557)
			(xy 399.963332 -377.444571) (xy 392.887028 -377.444571) (xy 392.887028 -377.444574) (xy 392.879265 -377.498565)
			(xy 392.863898 -377.550903) (xy 392.841238 -377.60052) (xy 392.811747 -377.646408) (xy 392.776026 -377.687632)
			(xy 392.734802 -377.723352) (xy 392.688913 -377.752841) (xy 392.639295 -377.7755) (xy 392.586957 -377.790867)
			(xy 392.532966 -377.798629) (xy 392.505692 -377.799092) (xy 391.642092 -377.799092) (xy 391.614825 -377.798545)
			(xy 391.560847 -377.790783) (xy 391.508522 -377.775418) (xy 391.458917 -377.752763) (xy 391.413041 -377.72328)
			(xy 391.371827 -377.687567) (xy 391.336116 -377.646353) (xy 391.306633 -377.600476) (xy 391.283979 -377.55087)
			(xy 391.268615 -377.498546) (xy 391.260854 -377.444567) (xy 389.483428 -377.444567) (xy 389.483428 -377.444574)
			(xy 389.475665 -377.498565) (xy 389.460298 -377.550903) (xy 389.437638 -377.60052) (xy 389.408147 -377.646408)
			(xy 389.372426 -377.687632) (xy 389.331202 -377.723352) (xy 389.285313 -377.752841) (xy 389.235695 -377.7755)
			(xy 389.183357 -377.790867) (xy 389.129366 -377.798629) (xy 389.102092 -377.799092) (xy 388.238492 -377.799092)
			(xy 388.211225 -377.798545) (xy 388.157247 -377.790783) (xy 388.104922 -377.775418) (xy 388.055317 -377.752763)
			(xy 388.009441 -377.72328) (xy 387.968227 -377.687567) (xy 387.932516 -377.646353) (xy 387.903033 -377.600476)
			(xy 387.880379 -377.55087) (xy 387.865015 -377.498546) (xy 387.857254 -377.444567) (xy 382.676228 -377.444567)
			(xy 382.676228 -377.444574) (xy 382.668465 -377.498565) (xy 382.653098 -377.550903) (xy 382.630438 -377.60052)
			(xy 382.600947 -377.646408) (xy 382.565226 -377.687632) (xy 382.524002 -377.723352) (xy 382.478113 -377.752841)
			(xy 382.428495 -377.7755) (xy 382.376157 -377.790867) (xy 382.322166 -377.798629) (xy 382.294892 -377.799092)
			(xy 381.431292 -377.799092) (xy 381.404025 -377.798545) (xy 381.350047 -377.790783) (xy 381.297722 -377.775418)
			(xy 381.248117 -377.752763) (xy 381.202241 -377.72328) (xy 381.161027 -377.687567) (xy 381.125316 -377.646353)
			(xy 381.095833 -377.600476) (xy 381.073179 -377.55087) (xy 381.057815 -377.498546) (xy 381.050054 -377.444567)
			(xy 375.869028 -377.444567) (xy 375.869028 -377.444574) (xy 375.861265 -377.498565) (xy 375.845898 -377.550903)
			(xy 375.823238 -377.60052) (xy 375.793747 -377.646408) (xy 375.758026 -377.687632) (xy 375.716802 -377.723352)
			(xy 375.670913 -377.752841) (xy 375.621295 -377.7755) (xy 375.568957 -377.790867) (xy 375.514966 -377.798629)
			(xy 375.487692 -377.799092) (xy 374.624092 -377.799092) (xy 374.596825 -377.798545) (xy 374.542847 -377.790783)
			(xy 374.490522 -377.775418) (xy 374.440917 -377.752763) (xy 374.395041 -377.72328) (xy 374.353827 -377.687567)
			(xy 374.318116 -377.646353) (xy 374.288633 -377.600476) (xy 374.265979 -377.55087) (xy 374.250615 -377.498546)
			(xy 374.242854 -377.444567) (xy 369.061828 -377.444567) (xy 369.061828 -377.444574) (xy 369.054065 -377.498565)
			(xy 369.038698 -377.550903) (xy 369.016038 -377.60052) (xy 368.986547 -377.646408) (xy 368.950826 -377.687632)
			(xy 368.909602 -377.723352) (xy 368.863713 -377.752841) (xy 368.814095 -377.7755) (xy 368.761757 -377.790867)
			(xy 368.707766 -377.798629) (xy 368.680492 -377.799092) (xy 367.816892 -377.799092) (xy 367.789625 -377.798545)
			(xy 367.735647 -377.790783) (xy 367.683322 -377.775418) (xy 367.633717 -377.752763) (xy 367.587841 -377.72328)
			(xy 367.546627 -377.687567) (xy 367.510916 -377.646353) (xy 367.481433 -377.600476) (xy 367.458779 -377.55087)
			(xy 367.443415 -377.498546) (xy 367.435654 -377.444567) (xy 358.314506 -377.444567) (xy 358.314506 -377.44457)
			(xy 358.306744 -377.498553) (xy 358.29138 -377.550884) (xy 358.268725 -377.600495) (xy 358.239241 -377.646377)
			(xy 358.203528 -377.687597) (xy 358.162312 -377.723315) (xy 358.116433 -377.752804) (xy 358.066825 -377.775465)
			(xy 358.014497 -377.790835) (xy 357.960513 -377.798602) (xy 357.933244 -377.799092) (xy 357.069644 -377.799092)
			(xy 357.042373 -377.798572) (xy 356.988386 -377.790815) (xy 356.936052 -377.775454) (xy 356.886437 -377.752801)
			(xy 356.840551 -377.723316) (xy 356.799329 -377.687602) (xy 356.76361 -377.646384) (xy 356.734121 -377.600502)
			(xy 356.711461 -377.550889) (xy 356.696094 -377.498557) (xy 356.688332 -377.444571) (xy 354.910906 -377.444571)
			(xy 354.903144 -377.498553) (xy 354.88778 -377.550884) (xy 354.865125 -377.600495) (xy 354.835641 -377.646377)
			(xy 354.799928 -377.687597) (xy 354.758712 -377.723315) (xy 354.712833 -377.752804) (xy 354.663225 -377.775465)
			(xy 354.610897 -377.790835) (xy 354.556913 -377.798602) (xy 354.529644 -377.799092) (xy 353.666044 -377.799092)
			(xy 353.638773 -377.798572) (xy 353.584786 -377.790815) (xy 353.532452 -377.775454) (xy 353.482837 -377.752801)
			(xy 353.436951 -377.723316) (xy 353.395729 -377.687602) (xy 353.36001 -377.646384) (xy 353.330521 -377.600502)
			(xy 353.307861 -377.550889) (xy 353.292494 -377.498557) (xy 353.284732 -377.444571) (xy 348.103706 -377.444571)
			(xy 348.095944 -377.498553) (xy 348.08058 -377.550884) (xy 348.057925 -377.600495) (xy 348.028441 -377.646377)
			(xy 347.992728 -377.687597) (xy 347.951512 -377.723315) (xy 347.905633 -377.752804) (xy 347.856025 -377.775465)
			(xy 347.803697 -377.790835) (xy 347.749713 -377.798602) (xy 347.722444 -377.799092) (xy 346.858844 -377.799092)
			(xy 346.831573 -377.798572) (xy 346.777586 -377.790815) (xy 346.725252 -377.775454) (xy 346.675637 -377.752801)
			(xy 346.629751 -377.723316) (xy 346.588529 -377.687602) (xy 346.55281 -377.646384) (xy 346.523321 -377.600502)
			(xy 346.500661 -377.550889) (xy 346.485294 -377.498557) (xy 346.477532 -377.444571) (xy 341.296506 -377.444571)
			(xy 341.288744 -377.498553) (xy 341.27338 -377.550884) (xy 341.250725 -377.600495) (xy 341.221241 -377.646377)
			(xy 341.185528 -377.687597) (xy 341.144312 -377.723315) (xy 341.098433 -377.752804) (xy 341.048825 -377.775465)
			(xy 340.996497 -377.790835) (xy 340.942513 -377.798602) (xy 340.915244 -377.799092) (xy 340.051644 -377.799092)
			(xy 340.024373 -377.798572) (xy 339.970386 -377.790815) (xy 339.918052 -377.775454) (xy 339.868437 -377.752801)
			(xy 339.822551 -377.723316) (xy 339.781329 -377.687602) (xy 339.74561 -377.646384) (xy 339.716121 -377.600502)
			(xy 339.693461 -377.550889) (xy 339.678094 -377.498557) (xy 339.670332 -377.444571) (xy 334.489306 -377.444571)
			(xy 334.481544 -377.498553) (xy 334.46618 -377.550884) (xy 334.443525 -377.600495) (xy 334.414041 -377.646377)
			(xy 334.378328 -377.687597) (xy 334.337112 -377.723315) (xy 334.291233 -377.752804) (xy 334.241625 -377.775465)
			(xy 334.189297 -377.790835) (xy 334.135313 -377.798602) (xy 334.108044 -377.799092) (xy 333.244444 -377.799092)
			(xy 333.217173 -377.798572) (xy 333.163186 -377.790815) (xy 333.110852 -377.775454) (xy 333.061237 -377.752801)
			(xy 333.015351 -377.723316) (xy 332.974129 -377.687602) (xy 332.93841 -377.646384) (xy 332.908921 -377.600502)
			(xy 332.886261 -377.550889) (xy 332.870894 -377.498557) (xy 332.863132 -377.444571) (xy 325.786828 -377.444571)
			(xy 325.786828 -377.444573) (xy 325.779066 -377.498565) (xy 325.763698 -377.550902) (xy 325.741038 -377.600519)
			(xy 325.711548 -377.646407) (xy 325.675827 -377.68763) (xy 325.634603 -377.72335) (xy 325.588716 -377.75284)
			(xy 325.539098 -377.775499) (xy 325.486761 -377.790866) (xy 325.432769 -377.798629) (xy 325.405496 -377.799092)
			(xy 324.541896 -377.799092) (xy 324.514629 -377.798545) (xy 324.46065 -377.790784) (xy 324.408325 -377.775419)
			(xy 324.358719 -377.752765) (xy 324.312842 -377.723281) (xy 324.271629 -377.687569) (xy 324.235917 -377.646354)
			(xy 324.206433 -377.600477) (xy 324.183779 -377.550871) (xy 324.168415 -377.498546) (xy 324.160654 -377.444567)
			(xy 322.383228 -377.444567) (xy 322.383228 -377.444573) (xy 322.375466 -377.498565) (xy 322.360098 -377.550902)
			(xy 322.337438 -377.600519) (xy 322.307948 -377.646407) (xy 322.272227 -377.68763) (xy 322.231003 -377.72335)
			(xy 322.185116 -377.75284) (xy 322.135498 -377.775499) (xy 322.083161 -377.790866) (xy 322.029169 -377.798629)
			(xy 322.001896 -377.799092) (xy 321.138296 -377.799092) (xy 321.111029 -377.798545) (xy 321.05705 -377.790784)
			(xy 321.004725 -377.775419) (xy 320.955119 -377.752765) (xy 320.909242 -377.723281) (xy 320.868029 -377.687569)
			(xy 320.832317 -377.646354) (xy 320.802833 -377.600477) (xy 320.780179 -377.550871) (xy 320.764815 -377.498546)
			(xy 320.757054 -377.444567) (xy 315.576028 -377.444567) (xy 315.576028 -377.444573) (xy 315.568266 -377.498565)
			(xy 315.552898 -377.550902) (xy 315.530238 -377.600519) (xy 315.500748 -377.646407) (xy 315.465027 -377.68763)
			(xy 315.423803 -377.72335) (xy 315.377916 -377.75284) (xy 315.328298 -377.775499) (xy 315.275961 -377.790866)
			(xy 315.221969 -377.798629) (xy 315.194696 -377.799092) (xy 314.331096 -377.799092) (xy 314.303829 -377.798545)
			(xy 314.24985 -377.790784) (xy 314.197525 -377.775419) (xy 314.147919 -377.752765) (xy 314.102042 -377.723281)
			(xy 314.060829 -377.687569) (xy 314.025117 -377.646354) (xy 313.995633 -377.600477) (xy 313.972979 -377.550871)
			(xy 313.957615 -377.498546) (xy 313.949854 -377.444567) (xy 308.768828 -377.444567) (xy 308.768828 -377.444573)
			(xy 308.761066 -377.498565) (xy 308.745698 -377.550902) (xy 308.723038 -377.600519) (xy 308.693548 -377.646407)
			(xy 308.657827 -377.68763) (xy 308.616603 -377.72335) (xy 308.570716 -377.75284) (xy 308.521098 -377.775499)
			(xy 308.468761 -377.790866) (xy 308.414769 -377.798629) (xy 308.387496 -377.799092) (xy 307.523896 -377.799092)
			(xy 307.496629 -377.798545) (xy 307.44265 -377.790784) (xy 307.390325 -377.775419) (xy 307.340719 -377.752765)
			(xy 307.294842 -377.723281) (xy 307.253629 -377.687569) (xy 307.217917 -377.646354) (xy 307.188433 -377.600477)
			(xy 307.165779 -377.550871) (xy 307.150415 -377.498546) (xy 307.142654 -377.444567) (xy 301.961628 -377.444567)
			(xy 301.961628 -377.444573) (xy 301.953866 -377.498565) (xy 301.938498 -377.550902) (xy 301.915838 -377.600519)
			(xy 301.886348 -377.646407) (xy 301.850627 -377.68763) (xy 301.809403 -377.72335) (xy 301.763516 -377.75284)
			(xy 301.713898 -377.775499) (xy 301.661561 -377.790866) (xy 301.607569 -377.798629) (xy 301.580296 -377.799092)
			(xy 300.716696 -377.799092) (xy 300.689429 -377.798545) (xy 300.63545 -377.790784) (xy 300.583125 -377.775419)
			(xy 300.533519 -377.752765) (xy 300.487642 -377.723281) (xy 300.446429 -377.687569) (xy 300.410717 -377.646354)
			(xy 300.381233 -377.600477) (xy 300.358579 -377.550871) (xy 300.343215 -377.498546) (xy 300.335454 -377.444567)
			(xy 200.859958 -377.444567) (xy 200.882666 -377.460737) (xy 200.946694 -377.516218) (xy 201.005159 -377.577533)
			(xy 201.05753 -377.644129) (xy 201.103333 -377.715401) (xy 201.142155 -377.790704) (xy 201.173643 -377.869356)
			(xy 201.197511 -377.950646) (xy 201.213545 -378.033836) (xy 201.221598 -378.118173) (xy 201.222102 -378.160534)
			(xy 201.221598 -378.202895) (xy 201.213545 -378.287232) (xy 201.197511 -378.370422) (xy 201.173643 -378.451712)
			(xy 201.142155 -378.530364) (xy 201.103333 -378.605667) (xy 201.05753 -378.676939) (xy 201.005159 -378.743535)
			(xy 200.946694 -378.80485) (xy 200.882666 -378.860331) (xy 200.813654 -378.909474) (xy 200.740284 -378.951834)
			(xy 200.663219 -378.987029) (xy 200.583157 -379.014738) (xy 200.500824 -379.034712) (xy 200.416965 -379.046769)
			(xy 200.33234 -379.050801) (xy 200.247715 -379.046769) (xy 200.163856 -379.034712) (xy 200.081523 -379.014738)
			(xy 200.001461 -378.987029) (xy 199.924396 -378.951834) (xy 199.851026 -378.909474) (xy 199.782014 -378.860331)
			(xy 199.717986 -378.80485) (xy 199.659521 -378.743535) (xy 199.60715 -378.676939) (xy 199.561347 -378.605667)
			(xy 199.522525 -378.530364) (xy 199.491037 -378.451712) (xy 199.467169 -378.370422) (xy 199.451135 -378.287232)
			(xy 199.443082 -378.202895) (xy 195.47531 -378.202895) (xy 195.462625 -378.219025) (xy 195.40416 -378.28034)
			(xy 195.340132 -378.335821) (xy 195.27112 -378.384964) (xy 195.19775 -378.427324) (xy 195.120685 -378.462519)
			(xy 195.040623 -378.490228) (xy 194.95829 -378.510202) (xy 194.874431 -378.522259) (xy 194.789806 -378.526291)
			(xy 194.705181 -378.522259) (xy 194.621322 -378.510202) (xy 194.538989 -378.490228) (xy 194.458927 -378.462519)
			(xy 194.381862 -378.427324) (xy 194.308492 -378.384964) (xy 194.23948 -378.335821) (xy 194.175452 -378.28034)
			(xy 194.116987 -378.219025) (xy 194.064616 -378.152429) (xy 194.018813 -378.081157) (xy 193.979991 -378.005854)
			(xy 193.948503 -377.927202) (xy 193.924635 -377.845912) (xy 193.908601 -377.762722) (xy 193.900548 -377.678385)
			(xy 181.319901 -377.678385) (xy 181.279884 -377.802486) (xy 181.217663 -377.969563) (xy 181.148062 -378.133704)
			(xy 181.071217 -378.29458) (xy 180.987283 -378.451874) (xy 180.896425 -378.605273) (xy 180.798823 -378.754472)
			(xy 180.694672 -378.899175) (xy 180.584179 -379.039095) (xy 180.467562 -379.173954) (xy 180.345053 -379.303484)
			(xy 180.216896 -379.427428) (xy 180.083345 -379.54554) (xy 179.944665 -379.657585) (xy 179.801131 -379.763342)
			(xy 179.653028 -379.862599) (xy 179.577684 -379.908367) (xy 298.633654 -379.908367) (xy 298.633654 -379.853833)
			(xy 298.641415 -379.799854) (xy 298.656779 -379.747529) (xy 298.679433 -379.697923) (xy 298.708917 -379.652046)
			(xy 298.744629 -379.610831) (xy 298.785842 -379.575119) (xy 298.831719 -379.545635) (xy 298.881325 -379.522981)
			(xy 298.93365 -379.507616) (xy 298.987629 -379.499855) (xy 299.014896 -379.499368) (xy 299.878496 -379.499368)
			(xy 299.905769 -379.499771) (xy 299.959761 -379.507534) (xy 300.012098 -379.522901) (xy 300.061716 -379.54556)
			(xy 300.107603 -379.57505) (xy 300.148827 -379.61077) (xy 300.184548 -379.651993) (xy 300.214038 -379.697881)
			(xy 300.236698 -379.747498) (xy 300.252066 -379.799835) (xy 300.259828 -379.853827) (xy 300.259828 -379.908367)
			(xy 305.440854 -379.908367) (xy 305.440854 -379.853833) (xy 305.448615 -379.799854) (xy 305.463979 -379.747529)
			(xy 305.486633 -379.697923) (xy 305.516117 -379.652046) (xy 305.551829 -379.610831) (xy 305.593042 -379.575119)
			(xy 305.638919 -379.545635) (xy 305.688525 -379.522981) (xy 305.74085 -379.507616) (xy 305.794829 -379.499855)
			(xy 305.822096 -379.499368) (xy 306.685696 -379.499368) (xy 306.712969 -379.499771) (xy 306.766961 -379.507534)
			(xy 306.819298 -379.522901) (xy 306.868916 -379.54556) (xy 306.914803 -379.57505) (xy 306.956027 -379.61077)
			(xy 306.991748 -379.651993) (xy 307.021238 -379.697881) (xy 307.043898 -379.747498) (xy 307.059266 -379.799835)
			(xy 307.067028 -379.853827) (xy 307.067028 -379.908367) (xy 312.248054 -379.908367) (xy 312.248054 -379.853833)
			(xy 312.255815 -379.799854) (xy 312.271179 -379.747529) (xy 312.293833 -379.697923) (xy 312.323317 -379.652046)
			(xy 312.359029 -379.610831) (xy 312.400242 -379.575119) (xy 312.446119 -379.545635) (xy 312.495725 -379.522981)
			(xy 312.54805 -379.507616) (xy 312.602029 -379.499855) (xy 312.629296 -379.499368) (xy 313.492896 -379.499368)
			(xy 313.520169 -379.499771) (xy 313.574161 -379.507534) (xy 313.626498 -379.522901) (xy 313.676116 -379.54556)
			(xy 313.722003 -379.57505) (xy 313.763227 -379.61077) (xy 313.798948 -379.651993) (xy 313.828438 -379.697881)
			(xy 313.851098 -379.747498) (xy 313.866466 -379.799835) (xy 313.874228 -379.853827) (xy 313.874228 -379.908367)
			(xy 319.055254 -379.908367) (xy 319.055254 -379.853833) (xy 319.063015 -379.799854) (xy 319.078379 -379.747529)
			(xy 319.101033 -379.697923) (xy 319.130517 -379.652046) (xy 319.166229 -379.610831) (xy 319.207442 -379.575119)
			(xy 319.253319 -379.545635) (xy 319.302925 -379.522981) (xy 319.35525 -379.507616) (xy 319.409229 -379.499855)
			(xy 319.436496 -379.499368) (xy 320.300096 -379.499368) (xy 320.327369 -379.499771) (xy 320.381361 -379.507534)
			(xy 320.433698 -379.522901) (xy 320.483316 -379.54556) (xy 320.529203 -379.57505) (xy 320.570427 -379.61077)
			(xy 320.606148 -379.651993) (xy 320.635638 -379.697881) (xy 320.658298 -379.747498) (xy 320.673666 -379.799835)
			(xy 320.681428 -379.853827) (xy 320.681428 -379.908371) (xy 331.161332 -379.908371) (xy 331.161332 -379.853829)
			(xy 331.169094 -379.799843) (xy 331.184461 -379.747511) (xy 331.207121 -379.697898) (xy 331.23661 -379.652016)
			(xy 331.272329 -379.610798) (xy 331.313551 -379.575084) (xy 331.359437 -379.545599) (xy 331.409052 -379.522946)
			(xy 331.461386 -379.507585) (xy 331.515373 -379.499828) (xy 331.542644 -379.499368) (xy 332.406244 -379.499368)
			(xy 332.433513 -379.499798) (xy 332.487497 -379.507565) (xy 332.539825 -379.522935) (xy 332.589433 -379.545596)
			(xy 332.635312 -379.575085) (xy 332.676528 -379.610803) (xy 332.712241 -379.652023) (xy 332.741725 -379.697905)
			(xy 332.76438 -379.747516) (xy 332.779744 -379.799847) (xy 332.787506 -379.85383) (xy 332.787506 -379.90837)
			(xy 332.787506 -379.908371) (xy 337.968532 -379.908371) (xy 337.968532 -379.853829) (xy 337.976294 -379.799843)
			(xy 337.991661 -379.747511) (xy 338.014321 -379.697898) (xy 338.04381 -379.652016) (xy 338.079529 -379.610798)
			(xy 338.120751 -379.575084) (xy 338.166637 -379.545599) (xy 338.216252 -379.522946) (xy 338.268586 -379.507585)
			(xy 338.322573 -379.499828) (xy 338.349844 -379.499368) (xy 339.213444 -379.499368) (xy 339.240713 -379.499798)
			(xy 339.294697 -379.507565) (xy 339.347025 -379.522935) (xy 339.396633 -379.545596) (xy 339.442512 -379.575085)
			(xy 339.483728 -379.610803) (xy 339.519441 -379.652023) (xy 339.548925 -379.697905) (xy 339.57158 -379.747516)
			(xy 339.586944 -379.799847) (xy 339.594706 -379.85383) (xy 339.594706 -379.90837) (xy 339.594706 -379.908371)
			(xy 344.775732 -379.908371) (xy 344.775732 -379.853829) (xy 344.783494 -379.799843) (xy 344.798861 -379.747511)
			(xy 344.821521 -379.697898) (xy 344.85101 -379.652016) (xy 344.886729 -379.610798) (xy 344.927951 -379.575084)
			(xy 344.973837 -379.545599) (xy 345.023452 -379.522946) (xy 345.075786 -379.507585) (xy 345.129773 -379.499828)
			(xy 345.157044 -379.499368) (xy 346.020644 -379.499368) (xy 346.047913 -379.499798) (xy 346.101897 -379.507565)
			(xy 346.154225 -379.522935) (xy 346.203833 -379.545596) (xy 346.249712 -379.575085) (xy 346.290928 -379.610803)
			(xy 346.326641 -379.652023) (xy 346.356125 -379.697905) (xy 346.37878 -379.747516) (xy 346.394144 -379.799847)
			(xy 346.401906 -379.85383) (xy 346.401906 -379.90837) (xy 346.401906 -379.908371) (xy 351.582932 -379.908371)
			(xy 351.582932 -379.853829) (xy 351.590694 -379.799843) (xy 351.606061 -379.747511) (xy 351.628721 -379.697898)
			(xy 351.65821 -379.652016) (xy 351.693929 -379.610798) (xy 351.735151 -379.575084) (xy 351.781037 -379.545599)
			(xy 351.830652 -379.522946) (xy 351.882986 -379.507585) (xy 351.936973 -379.499828) (xy 351.964244 -379.499368)
			(xy 352.827844 -379.499368) (xy 352.855113 -379.499798) (xy 352.909097 -379.507565) (xy 352.961425 -379.522935)
			(xy 353.011033 -379.545596) (xy 353.056912 -379.575085) (xy 353.098128 -379.610803) (xy 353.133841 -379.652023)
			(xy 353.163325 -379.697905) (xy 353.18598 -379.747516) (xy 353.201344 -379.799847) (xy 353.209106 -379.85383)
			(xy 353.209106 -379.908367) (xy 365.733854 -379.908367) (xy 365.733854 -379.853833) (xy 365.741615 -379.799854)
			(xy 365.756979 -379.74753) (xy 365.779633 -379.697924) (xy 365.809116 -379.652047) (xy 365.844827 -379.610833)
			(xy 365.886041 -379.57512) (xy 365.931917 -379.545637) (xy 365.981522 -379.522982) (xy 366.033847 -379.507617)
			(xy 366.087825 -379.499855) (xy 366.115092 -379.499368) (xy 366.978692 -379.499368) (xy 367.005966 -379.499771)
			(xy 367.059957 -379.507533) (xy 367.112295 -379.5229) (xy 367.161913 -379.545559) (xy 367.207802 -379.575048)
			(xy 367.249026 -379.610768) (xy 367.284747 -379.651992) (xy 367.314238 -379.69788) (xy 367.336898 -379.747497)
			(xy 367.352265 -379.799835) (xy 367.360028 -379.853826) (xy 367.360028 -379.908367) (xy 372.541054 -379.908367)
			(xy 372.541054 -379.853833) (xy 372.548815 -379.799854) (xy 372.564179 -379.74753) (xy 372.586833 -379.697924)
			(xy 372.616316 -379.652047) (xy 372.652027 -379.610833) (xy 372.693241 -379.57512) (xy 372.739117 -379.545637)
			(xy 372.788722 -379.522982) (xy 372.841047 -379.507617) (xy 372.895025 -379.499855) (xy 372.922292 -379.499368)
			(xy 373.785892 -379.499368) (xy 373.813166 -379.499771) (xy 373.867157 -379.507533) (xy 373.919495 -379.5229)
			(xy 373.969113 -379.545559) (xy 374.015002 -379.575048) (xy 374.056226 -379.610768) (xy 374.091947 -379.651992)
			(xy 374.121438 -379.69788) (xy 374.144098 -379.747497) (xy 374.159465 -379.799835) (xy 374.167228 -379.853826)
			(xy 374.167228 -379.908367) (xy 379.348254 -379.908367) (xy 379.348254 -379.853833) (xy 379.356015 -379.799854)
			(xy 379.371379 -379.74753) (xy 379.394033 -379.697924) (xy 379.423516 -379.652047) (xy 379.459227 -379.610833)
			(xy 379.500441 -379.57512) (xy 379.546317 -379.545637) (xy 379.595922 -379.522982) (xy 379.648247 -379.507617)
			(xy 379.702225 -379.499855) (xy 379.729492 -379.499368) (xy 380.593092 -379.499368) (xy 380.620366 -379.499771)
			(xy 380.674357 -379.507533) (xy 380.726695 -379.5229) (xy 380.776313 -379.545559) (xy 380.822202 -379.575048)
			(xy 380.863426 -379.610768) (xy 380.899147 -379.651992) (xy 380.928638 -379.69788) (xy 380.951298 -379.747497)
			(xy 380.966665 -379.799835) (xy 380.974428 -379.853826) (xy 380.974428 -379.908367) (xy 386.155454 -379.908367)
			(xy 386.155454 -379.853833) (xy 386.163215 -379.799854) (xy 386.178579 -379.74753) (xy 386.201233 -379.697924)
			(xy 386.230716 -379.652047) (xy 386.266427 -379.610833) (xy 386.307641 -379.57512) (xy 386.353517 -379.545637)
			(xy 386.403122 -379.522982) (xy 386.455447 -379.507617) (xy 386.509425 -379.499855) (xy 386.536692 -379.499368)
			(xy 387.400292 -379.499368) (xy 387.427566 -379.499771) (xy 387.481557 -379.507533) (xy 387.533895 -379.5229)
			(xy 387.583513 -379.545559) (xy 387.629402 -379.575048) (xy 387.670626 -379.610768) (xy 387.706347 -379.651992)
			(xy 387.735838 -379.69788) (xy 387.758498 -379.747497) (xy 387.773865 -379.799835) (xy 387.781628 -379.853826)
			(xy 387.781628 -379.908371) (xy 398.261532 -379.908371) (xy 398.261532 -379.853829) (xy 398.269294 -379.799843)
			(xy 398.284661 -379.747511) (xy 398.30732 -379.697899) (xy 398.336809 -379.652017) (xy 398.372528 -379.6108)
			(xy 398.41375 -379.575085) (xy 398.459635 -379.545601) (xy 398.509249 -379.522947) (xy 398.561582 -379.507586)
			(xy 398.615569 -379.499829) (xy 398.64284 -379.499368) (xy 399.50644 -379.499368) (xy 399.53371 -379.499797)
			(xy 399.587693 -379.507564) (xy 399.640022 -379.522934) (xy 399.689631 -379.545594) (xy 399.735511 -379.575084)
			(xy 399.776727 -379.610802) (xy 399.81244 -379.652022) (xy 399.841925 -379.697904) (xy 399.86458 -379.747516)
			(xy 399.879944 -379.799846) (xy 399.887706 -379.85383) (xy 399.887706 -379.90837) (xy 399.887706 -379.908371)
			(xy 405.068732 -379.908371) (xy 405.068732 -379.853829) (xy 405.076494 -379.799843) (xy 405.091861 -379.747511)
			(xy 405.11452 -379.697899) (xy 405.144009 -379.652017) (xy 405.179728 -379.6108) (xy 405.22095 -379.575085)
			(xy 405.266835 -379.545601) (xy 405.316449 -379.522947) (xy 405.368782 -379.507586) (xy 405.422769 -379.499829)
			(xy 405.45004 -379.499368) (xy 406.31364 -379.499368) (xy 406.34091 -379.499797) (xy 406.394893 -379.507564)
			(xy 406.447222 -379.522934) (xy 406.496831 -379.545594) (xy 406.542711 -379.575084) (xy 406.583927 -379.610802)
			(xy 406.61964 -379.652022) (xy 406.649125 -379.697904) (xy 406.67178 -379.747516) (xy 406.687144 -379.799846)
			(xy 406.694906 -379.85383) (xy 406.694906 -379.90837) (xy 406.694906 -379.908371) (xy 411.875932 -379.908371)
			(xy 411.875932 -379.853829) (xy 411.883694 -379.799843) (xy 411.899061 -379.747511) (xy 411.92172 -379.697899)
			(xy 411.951209 -379.652017) (xy 411.986928 -379.6108) (xy 412.02815 -379.575085) (xy 412.074035 -379.545601)
			(xy 412.123649 -379.522947) (xy 412.175982 -379.507586) (xy 412.229969 -379.499829) (xy 412.25724 -379.499368)
			(xy 413.12084 -379.499368) (xy 413.14811 -379.499797) (xy 413.202093 -379.507564) (xy 413.254422 -379.522934)
			(xy 413.304031 -379.545594) (xy 413.349911 -379.575084) (xy 413.391127 -379.610802) (xy 413.42684 -379.652022)
			(xy 413.456325 -379.697904) (xy 413.47898 -379.747516) (xy 413.494344 -379.799846) (xy 413.502106 -379.85383)
			(xy 413.502106 -379.90837) (xy 413.502106 -379.908371) (xy 418.683132 -379.908371) (xy 418.683132 -379.853829)
			(xy 418.690894 -379.799843) (xy 418.706261 -379.747511) (xy 418.72892 -379.697899) (xy 418.758409 -379.652017)
			(xy 418.794128 -379.6108) (xy 418.83535 -379.575085) (xy 418.881235 -379.545601) (xy 418.930849 -379.522947)
			(xy 418.983182 -379.507586) (xy 419.037169 -379.499829) (xy 419.06444 -379.499368) (xy 419.92804 -379.499368)
			(xy 419.95531 -379.499797) (xy 420.009293 -379.507564) (xy 420.061622 -379.522934) (xy 420.111231 -379.545594)
			(xy 420.157111 -379.575084) (xy 420.198327 -379.610802) (xy 420.23404 -379.652022) (xy 420.263525 -379.697904)
			(xy 420.28618 -379.747516) (xy 420.301544 -379.799846) (xy 420.309306 -379.85383) (xy 420.309306 -379.90837)
			(xy 420.301544 -379.962354) (xy 420.28618 -380.014684) (xy 420.263525 -380.064296) (xy 420.23404 -380.110178)
			(xy 420.198327 -380.151398) (xy 420.157111 -380.187116) (xy 420.111231 -380.216606) (xy 420.061622 -380.239266)
			(xy 420.009293 -380.254636) (xy 419.95531 -380.262403) (xy 419.92804 -380.262892) (xy 419.06444 -380.262892)
			(xy 419.037169 -380.262371) (xy 418.983182 -380.254614) (xy 418.930849 -380.239253) (xy 418.881235 -380.216599)
			(xy 418.83535 -380.187115) (xy 418.794128 -380.1514) (xy 418.758409 -380.110183) (xy 418.72892 -380.064301)
			(xy 418.706261 -380.014689) (xy 418.690894 -379.962357) (xy 418.683132 -379.908371) (xy 413.502106 -379.908371)
			(xy 413.494344 -379.962354) (xy 413.47898 -380.014684) (xy 413.456325 -380.064296) (xy 413.42684 -380.110178)
			(xy 413.391127 -380.151398) (xy 413.349911 -380.187116) (xy 413.304031 -380.216606) (xy 413.254422 -380.239266)
			(xy 413.202093 -380.254636) (xy 413.14811 -380.262403) (xy 413.12084 -380.262892) (xy 412.25724 -380.262892)
			(xy 412.229969 -380.262371) (xy 412.175982 -380.254614) (xy 412.123649 -380.239253) (xy 412.074035 -380.216599)
			(xy 412.02815 -380.187115) (xy 411.986928 -380.1514) (xy 411.951209 -380.110183) (xy 411.92172 -380.064301)
			(xy 411.899061 -380.014689) (xy 411.883694 -379.962357) (xy 411.875932 -379.908371) (xy 406.694906 -379.908371)
			(xy 406.687144 -379.962354) (xy 406.67178 -380.014684) (xy 406.649125 -380.064296) (xy 406.61964 -380.110178)
			(xy 406.583927 -380.151398) (xy 406.542711 -380.187116) (xy 406.496831 -380.216606) (xy 406.447222 -380.239266)
			(xy 406.394893 -380.254636) (xy 406.34091 -380.262403) (xy 406.31364 -380.262892) (xy 405.45004 -380.262892)
			(xy 405.422769 -380.262371) (xy 405.368782 -380.254614) (xy 405.316449 -380.239253) (xy 405.266835 -380.216599)
			(xy 405.22095 -380.187115) (xy 405.179728 -380.1514) (xy 405.144009 -380.110183) (xy 405.11452 -380.064301)
			(xy 405.091861 -380.014689) (xy 405.076494 -379.962357) (xy 405.068732 -379.908371) (xy 399.887706 -379.908371)
			(xy 399.879944 -379.962354) (xy 399.86458 -380.014684) (xy 399.841925 -380.064296) (xy 399.81244 -380.110178)
			(xy 399.776727 -380.151398) (xy 399.735511 -380.187116) (xy 399.689631 -380.216606) (xy 399.640022 -380.239266)
			(xy 399.587693 -380.254636) (xy 399.53371 -380.262403) (xy 399.50644 -380.262892) (xy 398.64284 -380.262892)
			(xy 398.615569 -380.262371) (xy 398.561582 -380.254614) (xy 398.509249 -380.239253) (xy 398.459635 -380.216599)
			(xy 398.41375 -380.187115) (xy 398.372528 -380.1514) (xy 398.336809 -380.110183) (xy 398.30732 -380.064301)
			(xy 398.284661 -380.014689) (xy 398.269294 -379.962357) (xy 398.261532 -379.908371) (xy 387.781628 -379.908371)
			(xy 387.781628 -379.908374) (xy 387.773865 -379.962365) (xy 387.758498 -380.014703) (xy 387.735838 -380.06432)
			(xy 387.706347 -380.110208) (xy 387.670626 -380.151432) (xy 387.629402 -380.187152) (xy 387.583513 -380.216641)
			(xy 387.533895 -380.2393) (xy 387.481557 -380.254667) (xy 387.427566 -380.262429) (xy 387.400292 -380.262892)
			(xy 386.536692 -380.262892) (xy 386.509425 -380.262345) (xy 386.455447 -380.254583) (xy 386.403122 -380.239218)
			(xy 386.353517 -380.216563) (xy 386.307641 -380.18708) (xy 386.266427 -380.151367) (xy 386.230716 -380.110153)
			(xy 386.201233 -380.064276) (xy 386.178579 -380.01467) (xy 386.163215 -379.962346) (xy 386.155454 -379.908367)
			(xy 380.974428 -379.908367) (xy 380.974428 -379.908374) (xy 380.966665 -379.962365) (xy 380.951298 -380.014703)
			(xy 380.928638 -380.06432) (xy 380.899147 -380.110208) (xy 380.863426 -380.151432) (xy 380.822202 -380.187152)
			(xy 380.776313 -380.216641) (xy 380.726695 -380.2393) (xy 380.674357 -380.254667) (xy 380.620366 -380.262429)
			(xy 380.593092 -380.262892) (xy 379.729492 -380.262892) (xy 379.702225 -380.262345) (xy 379.648247 -380.254583)
			(xy 379.595922 -380.239218) (xy 379.546317 -380.216563) (xy 379.500441 -380.18708) (xy 379.459227 -380.151367)
			(xy 379.423516 -380.110153) (xy 379.394033 -380.064276) (xy 379.371379 -380.01467) (xy 379.356015 -379.962346)
			(xy 379.348254 -379.908367) (xy 374.167228 -379.908367) (xy 374.167228 -379.908374) (xy 374.159465 -379.962365)
			(xy 374.144098 -380.014703) (xy 374.121438 -380.06432) (xy 374.091947 -380.110208) (xy 374.056226 -380.151432)
			(xy 374.015002 -380.187152) (xy 373.969113 -380.216641) (xy 373.919495 -380.2393) (xy 373.867157 -380.254667)
			(xy 373.813166 -380.262429) (xy 373.785892 -380.262892) (xy 372.922292 -380.262892) (xy 372.895025 -380.262345)
			(xy 372.841047 -380.254583) (xy 372.788722 -380.239218) (xy 372.739117 -380.216563) (xy 372.693241 -380.18708)
			(xy 372.652027 -380.151367) (xy 372.616316 -380.110153) (xy 372.586833 -380.064276) (xy 372.564179 -380.01467)
			(xy 372.548815 -379.962346) (xy 372.541054 -379.908367) (xy 367.360028 -379.908367) (xy 367.360028 -379.908374)
			(xy 367.352265 -379.962365) (xy 367.336898 -380.014703) (xy 367.314238 -380.06432) (xy 367.284747 -380.110208)
			(xy 367.249026 -380.151432) (xy 367.207802 -380.187152) (xy 367.161913 -380.216641) (xy 367.112295 -380.2393)
			(xy 367.059957 -380.254667) (xy 367.005966 -380.262429) (xy 366.978692 -380.262892) (xy 366.115092 -380.262892)
			(xy 366.087825 -380.262345) (xy 366.033847 -380.254583) (xy 365.981522 -380.239218) (xy 365.931917 -380.216563)
			(xy 365.886041 -380.18708) (xy 365.844827 -380.151367) (xy 365.809116 -380.110153) (xy 365.779633 -380.064276)
			(xy 365.756979 -380.01467) (xy 365.741615 -379.962346) (xy 365.733854 -379.908367) (xy 353.209106 -379.908367)
			(xy 353.209106 -379.90837) (xy 353.201344 -379.962353) (xy 353.18598 -380.014684) (xy 353.163325 -380.064295)
			(xy 353.133841 -380.110177) (xy 353.098128 -380.151397) (xy 353.056912 -380.187115) (xy 353.011033 -380.216604)
			(xy 352.961425 -380.239265) (xy 352.909097 -380.254635) (xy 352.855113 -380.262402) (xy 352.827844 -380.262892)
			(xy 351.964244 -380.262892) (xy 351.936973 -380.262372) (xy 351.882986 -380.254615) (xy 351.830652 -380.239254)
			(xy 351.781037 -380.216601) (xy 351.735151 -380.187116) (xy 351.693929 -380.151402) (xy 351.65821 -380.110184)
			(xy 351.628721 -380.064302) (xy 351.606061 -380.014689) (xy 351.590694 -379.962357) (xy 351.582932 -379.908371)
			(xy 346.401906 -379.908371) (xy 346.394144 -379.962353) (xy 346.37878 -380.014684) (xy 346.356125 -380.064295)
			(xy 346.326641 -380.110177) (xy 346.290928 -380.151397) (xy 346.249712 -380.187115) (xy 346.203833 -380.216604)
			(xy 346.154225 -380.239265) (xy 346.101897 -380.254635) (xy 346.047913 -380.262402) (xy 346.020644 -380.262892)
			(xy 345.157044 -380.262892) (xy 345.129773 -380.262372) (xy 345.075786 -380.254615) (xy 345.023452 -380.239254)
			(xy 344.973837 -380.216601) (xy 344.927951 -380.187116) (xy 344.886729 -380.151402) (xy 344.85101 -380.110184)
			(xy 344.821521 -380.064302) (xy 344.798861 -380.014689) (xy 344.783494 -379.962357) (xy 344.775732 -379.908371)
			(xy 339.594706 -379.908371) (xy 339.586944 -379.962353) (xy 339.57158 -380.014684) (xy 339.548925 -380.064295)
			(xy 339.519441 -380.110177) (xy 339.483728 -380.151397) (xy 339.442512 -380.187115) (xy 339.396633 -380.216604)
			(xy 339.347025 -380.239265) (xy 339.294697 -380.254635) (xy 339.240713 -380.262402) (xy 339.213444 -380.262892)
			(xy 338.349844 -380.262892) (xy 338.322573 -380.262372) (xy 338.268586 -380.254615) (xy 338.216252 -380.239254)
			(xy 338.166637 -380.216601) (xy 338.120751 -380.187116) (xy 338.079529 -380.151402) (xy 338.04381 -380.110184)
			(xy 338.014321 -380.064302) (xy 337.991661 -380.014689) (xy 337.976294 -379.962357) (xy 337.968532 -379.908371)
			(xy 332.787506 -379.908371) (xy 332.779744 -379.962353) (xy 332.76438 -380.014684) (xy 332.741725 -380.064295)
			(xy 332.712241 -380.110177) (xy 332.676528 -380.151397) (xy 332.635312 -380.187115) (xy 332.589433 -380.216604)
			(xy 332.539825 -380.239265) (xy 332.487497 -380.254635) (xy 332.433513 -380.262402) (xy 332.406244 -380.262892)
			(xy 331.542644 -380.262892) (xy 331.515373 -380.262372) (xy 331.461386 -380.254615) (xy 331.409052 -380.239254)
			(xy 331.359437 -380.216601) (xy 331.313551 -380.187116) (xy 331.272329 -380.151402) (xy 331.23661 -380.110184)
			(xy 331.207121 -380.064302) (xy 331.184461 -380.014689) (xy 331.169094 -379.962357) (xy 331.161332 -379.908371)
			(xy 320.681428 -379.908371) (xy 320.681428 -379.908373) (xy 320.673666 -379.962365) (xy 320.658298 -380.014702)
			(xy 320.635638 -380.064319) (xy 320.606148 -380.110207) (xy 320.570427 -380.15143) (xy 320.529203 -380.18715)
			(xy 320.483316 -380.21664) (xy 320.433698 -380.239299) (xy 320.381361 -380.254666) (xy 320.327369 -380.262429)
			(xy 320.300096 -380.262892) (xy 319.436496 -380.262892) (xy 319.409229 -380.262345) (xy 319.35525 -380.254584)
			(xy 319.302925 -380.239219) (xy 319.253319 -380.216565) (xy 319.207442 -380.187081) (xy 319.166229 -380.151369)
			(xy 319.130517 -380.110154) (xy 319.101033 -380.064277) (xy 319.078379 -380.014671) (xy 319.063015 -379.962346)
			(xy 319.055254 -379.908367) (xy 313.874228 -379.908367) (xy 313.874228 -379.908373) (xy 313.866466 -379.962365)
			(xy 313.851098 -380.014702) (xy 313.828438 -380.064319) (xy 313.798948 -380.110207) (xy 313.763227 -380.15143)
			(xy 313.722003 -380.18715) (xy 313.676116 -380.21664) (xy 313.626498 -380.239299) (xy 313.574161 -380.254666)
			(xy 313.520169 -380.262429) (xy 313.492896 -380.262892) (xy 312.629296 -380.262892) (xy 312.602029 -380.262345)
			(xy 312.54805 -380.254584) (xy 312.495725 -380.239219) (xy 312.446119 -380.216565) (xy 312.400242 -380.187081)
			(xy 312.359029 -380.151369) (xy 312.323317 -380.110154) (xy 312.293833 -380.064277) (xy 312.271179 -380.014671)
			(xy 312.255815 -379.962346) (xy 312.248054 -379.908367) (xy 307.067028 -379.908367) (xy 307.067028 -379.908373)
			(xy 307.059266 -379.962365) (xy 307.043898 -380.014702) (xy 307.021238 -380.064319) (xy 306.991748 -380.110207)
			(xy 306.956027 -380.15143) (xy 306.914803 -380.18715) (xy 306.868916 -380.21664) (xy 306.819298 -380.239299)
			(xy 306.766961 -380.254666) (xy 306.712969 -380.262429) (xy 306.685696 -380.262892) (xy 305.822096 -380.262892)
			(xy 305.794829 -380.262345) (xy 305.74085 -380.254584) (xy 305.688525 -380.239219) (xy 305.638919 -380.216565)
			(xy 305.593042 -380.187081) (xy 305.551829 -380.151369) (xy 305.516117 -380.110154) (xy 305.486633 -380.064277)
			(xy 305.463979 -380.014671) (xy 305.448615 -379.962346) (xy 305.440854 -379.908367) (xy 300.259828 -379.908367)
			(xy 300.259828 -379.908373) (xy 300.252066 -379.962365) (xy 300.236698 -380.014702) (xy 300.214038 -380.064319)
			(xy 300.184548 -380.110207) (xy 300.148827 -380.15143) (xy 300.107603 -380.18715) (xy 300.061716 -380.21664)
			(xy 300.012098 -380.239299) (xy 299.959761 -380.254666) (xy 299.905769 -380.262429) (xy 299.878496 -380.262892)
			(xy 299.014896 -380.262892) (xy 298.987629 -380.262345) (xy 298.93365 -380.254584) (xy 298.881325 -380.239219)
			(xy 298.831719 -380.216565) (xy 298.785842 -380.187081) (xy 298.744629 -380.151369) (xy 298.708917 -380.110154)
			(xy 298.679433 -380.064277) (xy 298.656779 -380.014671) (xy 298.641415 -379.962346) (xy 298.633654 -379.908367)
			(xy 179.577684 -379.908367) (xy 179.500651 -379.955161) (xy 179.344302 -380.040842) (xy 179.184291 -380.119474)
			(xy 179.020937 -380.1909) (xy 178.854562 -380.254978) (xy 178.685499 -380.31158) (xy 178.514082 -380.360596)
			(xy 178.340651 -380.401926) (xy 178.165551 -380.43549) (xy 177.989131 -380.46122) (xy 177.811739 -380.479066)
			(xy 177.633728 -380.488992) (xy 177.455451 -380.490978) (xy 177.277264 -380.485021) (xy 177.099518 -380.471131)
			(xy 176.922568 -380.449338) (xy 176.746764 -380.419684) (xy 176.572456 -380.382227) (xy 176.399989 -380.337043)
			(xy 176.229706 -380.284221) (xy 176.061945 -380.223865) (xy 175.89704 -380.156097) (xy 175.735317 -380.081049)
			(xy 175.577098 -379.998872) (xy 175.422697 -379.909729) (xy 175.27242 -379.813795) (xy 175.126565 -379.711263)
			(xy 174.985423 -379.602335) (xy 174.849274 -379.487228) (xy 174.718387 -379.36617) (xy 174.593023 -379.239401)
			(xy 174.47343 -379.107174) (xy 174.359847 -378.969751) (xy 174.252498 -378.827404) (xy 174.151597 -378.680416)
			(xy 174.057344 -378.52908) (xy 173.969926 -378.373695) (xy 173.889516 -378.21457) (xy 173.816275 -378.052021)
			(xy 173.750348 -377.886371) (xy 173.691865 -377.717949) (xy 173.640943 -377.547088) (xy 173.597683 -377.374129)
			(xy 173.562171 -377.199414) (xy 173.534477 -377.02329) (xy 173.514656 -376.846108) (xy 173.502748 -376.668219)
			(xy 173.498776 -376.489976) (xy 171.286932 -376.489976) (xy 171.286932 -376.956828) (xy 171.286446 -376.984079)
			(xy 171.27869 -377.038027) (xy 171.263335 -377.090322) (xy 171.240693 -377.139899) (xy 171.211227 -377.185749)
			(xy 171.175536 -377.22694) (xy 171.134345 -377.262631) (xy 171.088495 -377.292097) (xy 171.038918 -377.314739)
			(xy 170.986623 -377.330094) (xy 170.932675 -377.33785) (xy 170.878173 -377.33785) (xy 170.824225 -377.330094)
			(xy 170.77193 -377.314739) (xy 170.722353 -377.292097) (xy 170.676503 -377.262631) (xy 170.635312 -377.22694)
			(xy 170.599621 -377.185749) (xy 170.570155 -377.139899) (xy 170.547513 -377.090322) (xy 170.532158 -377.038027)
			(xy 170.524402 -376.984079) (xy 170.523916 -376.956828) (xy 141.418806 -376.956828) (xy 141.416303 -376.965354)
			(xy 141.393661 -377.014931) (xy 141.364195 -377.060781) (xy 141.328504 -377.101972) (xy 141.287313 -377.137663)
			(xy 141.241463 -377.167129) (xy 141.191886 -377.189771) (xy 141.139591 -377.205126) (xy 141.085643 -377.212882)
			(xy 141.031141 -377.212882) (xy 140.977193 -377.205126) (xy 140.924898 -377.189771) (xy 140.875321 -377.167129)
			(xy 140.829471 -377.137663) (xy 140.78828 -377.101972) (xy 140.752589 -377.060781) (xy 140.723123 -377.014931)
			(xy 140.700481 -376.965354) (xy 140.685126 -376.913059) (xy 140.67737 -376.859111) (xy 140.676884 -376.83186)
			(xy 138.759184 -376.83186) (xy 138.759184 -376.956828) (xy 138.758698 -376.984079) (xy 138.750942 -377.038027)
			(xy 138.735587 -377.090322) (xy 138.712945 -377.139899) (xy 138.683479 -377.185749) (xy 138.647788 -377.22694)
			(xy 138.606597 -377.262631) (xy 138.560747 -377.292097) (xy 138.51117 -377.314739) (xy 138.458875 -377.330094)
			(xy 138.404927 -377.33785) (xy 138.350425 -377.33785) (xy 138.296477 -377.330094) (xy 138.244182 -377.314739)
			(xy 138.194605 -377.292097) (xy 138.148755 -377.262631) (xy 138.107564 -377.22694) (xy 138.071873 -377.185749)
			(xy 138.042407 -377.139899) (xy 138.019765 -377.090322) (xy 138.00441 -377.038027) (xy 137.996654 -376.984079)
			(xy 137.996168 -376.956828) (xy 108.891058 -376.956828) (xy 108.888555 -376.965354) (xy 108.865913 -377.014931)
			(xy 108.836447 -377.060781) (xy 108.800756 -377.101972) (xy 108.759565 -377.137663) (xy 108.713715 -377.167129)
			(xy 108.664138 -377.189771) (xy 108.611843 -377.205126) (xy 108.557895 -377.212882) (xy 108.503393 -377.212882)
			(xy 108.449445 -377.205126) (xy 108.39715 -377.189771) (xy 108.347573 -377.167129) (xy 108.301723 -377.137663)
			(xy 108.260532 -377.101972) (xy 108.224841 -377.060781) (xy 108.195375 -377.014931) (xy 108.172733 -376.965354)
			(xy 108.157378 -376.913059) (xy 108.149622 -376.859111) (xy 108.149136 -376.83186) (xy 104.187244 -376.83186)
			(xy 104.187244 -376.956828) (xy 104.186758 -376.984097) (xy 104.178996 -377.038081) (xy 104.163631 -377.090411)
			(xy 104.140974 -377.140021) (xy 104.111488 -377.185902) (xy 104.075773 -377.227119) (xy 104.034556 -377.262834)
			(xy 103.988675 -377.29232) (xy 103.939065 -377.314977) (xy 103.886735 -377.330342) (xy 103.832751 -377.338104)
			(xy 103.778213 -377.338104) (xy 103.724229 -377.330342) (xy 103.671899 -377.314977) (xy 103.622289 -377.29232)
			(xy 103.576408 -377.262834) (xy 103.535191 -377.227119) (xy 103.499476 -377.185902) (xy 103.46999 -377.140021)
			(xy 103.447333 -377.090411) (xy 103.431968 -377.038081) (xy 103.424206 -376.984097) (xy 103.42372 -376.956828)
			(xy 74.319129 -376.956828) (xy 74.316599 -376.965443) (xy 74.293942 -377.015053) (xy 74.264456 -377.060934)
			(xy 74.228741 -377.102151) (xy 74.187524 -377.137866) (xy 74.141643 -377.167352) (xy 74.092033 -377.190009)
			(xy 74.039703 -377.205374) (xy 73.985719 -377.213136) (xy 73.931181 -377.213136) (xy 73.877197 -377.205374)
			(xy 73.824867 -377.190009) (xy 73.775257 -377.167352) (xy 73.729376 -377.137866) (xy 73.688159 -377.102151)
			(xy 73.652444 -377.060934) (xy 73.622958 -377.015053) (xy 73.600301 -376.965443) (xy 73.584936 -376.913113)
			(xy 73.577174 -376.859129) (xy 73.576688 -376.83186) (xy 71.659496 -376.83186) (xy 71.659496 -376.956828)
			(xy 71.65901 -376.984097) (xy 71.651248 -377.038081) (xy 71.635883 -377.090411) (xy 71.613226 -377.140021)
			(xy 71.58374 -377.185902) (xy 71.548025 -377.227119) (xy 71.506808 -377.262834) (xy 71.460927 -377.29232)
			(xy 71.411317 -377.314977) (xy 71.358987 -377.330342) (xy 71.305003 -377.338104) (xy 71.250465 -377.338104)
			(xy 71.196481 -377.330342) (xy 71.144151 -377.314977) (xy 71.094541 -377.29232) (xy 71.04866 -377.262834)
			(xy 71.007443 -377.227119) (xy 70.971728 -377.185902) (xy 70.942242 -377.140021) (xy 70.919585 -377.090411)
			(xy 70.90422 -377.038081) (xy 70.896458 -376.984097) (xy 70.895972 -376.956828) (xy 41.791381 -376.956828)
			(xy 41.788851 -376.965443) (xy 41.766194 -377.015053) (xy 41.736708 -377.060934) (xy 41.700993 -377.102151)
			(xy 41.659776 -377.137866) (xy 41.613895 -377.167352) (xy 41.564285 -377.190009) (xy 41.511955 -377.205374)
			(xy 41.457971 -377.213136) (xy 41.403433 -377.213136) (xy 41.349449 -377.205374) (xy 41.297119 -377.190009)
			(xy 41.247509 -377.167352) (xy 41.201628 -377.137866) (xy 41.160411 -377.102151) (xy 41.124696 -377.060934)
			(xy 41.09521 -377.015053) (xy 41.072553 -376.965443) (xy 41.057188 -376.913113) (xy 41.049426 -376.859129)
			(xy 41.04894 -376.83186) (xy 39.05568 -376.83186) (xy 39.046481 -376.93481) (xy 39.022717 -377.111506)
			(xy 38.991106 -377.286969) (xy 38.95171 -377.460849) (xy 38.904608 -377.632802) (xy 38.849892 -377.802486)
			(xy 38.787671 -377.969563) (xy 38.71807 -378.133704) (xy 38.641225 -378.29458) (xy 38.557291 -378.451874)
			(xy 38.466433 -378.605273) (xy 38.368831 -378.754472) (xy 38.26468 -378.899175) (xy 38.154187 -379.039095)
			(xy 38.03757 -379.173954) (xy 37.915061 -379.303484) (xy 37.786904 -379.427428) (xy 37.653353 -379.54554)
			(xy 37.514673 -379.657585) (xy 37.371139 -379.763342) (xy 37.223036 -379.862599) (xy 37.070659 -379.955161)
			(xy 36.91431 -380.040842) (xy 36.754299 -380.119474) (xy 36.590945 -380.1909) (xy 36.42457 -380.254978)
			(xy 36.255507 -380.31158) (xy 36.084678 -380.360428) (xy 70.895972 -380.360428) (xy 70.895972 -379.496828)
			(xy 70.896458 -379.469559) (xy 70.90422 -379.415575) (xy 70.919585 -379.363245) (xy 70.942242 -379.313635)
			(xy 70.971728 -379.267754) (xy 71.007443 -379.226537) (xy 71.04866 -379.190822) (xy 71.094541 -379.161336)
			(xy 71.144151 -379.138679) (xy 71.196481 -379.123314) (xy 71.250465 -379.115552) (xy 71.305003 -379.115552)
			(xy 71.358987 -379.123314) (xy 71.411317 -379.138679) (xy 71.460927 -379.161336) (xy 71.506808 -379.190822)
			(xy 71.548025 -379.226537) (xy 71.58374 -379.267754) (xy 71.613226 -379.313635) (xy 71.635883 -379.363245)
			(xy 71.651248 -379.415575) (xy 71.65901 -379.469559) (xy 71.659496 -379.496828) (xy 71.659496 -380.360428)
			(xy 103.42372 -380.360428) (xy 103.42372 -379.496828) (xy 103.424206 -379.469559) (xy 103.431968 -379.415575)
			(xy 103.447333 -379.363245) (xy 103.46999 -379.313635) (xy 103.499476 -379.267754) (xy 103.535191 -379.226537)
			(xy 103.576408 -379.190822) (xy 103.622289 -379.161336) (xy 103.671899 -379.138679) (xy 103.724229 -379.123314)
			(xy 103.778213 -379.115552) (xy 103.832751 -379.115552) (xy 103.886735 -379.123314) (xy 103.939065 -379.138679)
			(xy 103.988675 -379.161336) (xy 104.034556 -379.190822) (xy 104.075773 -379.226537) (xy 104.111488 -379.267754)
			(xy 104.140974 -379.313635) (xy 104.163631 -379.363245) (xy 104.178996 -379.415575) (xy 104.186758 -379.469559)
			(xy 104.187244 -379.496828) (xy 104.187244 -380.360428) (xy 137.996168 -380.360428) (xy 137.996168 -379.496828)
			(xy 137.996654 -379.469577) (xy 138.00441 -379.415629) (xy 138.019765 -379.363334) (xy 138.042407 -379.313757)
			(xy 138.071873 -379.267907) (xy 138.107564 -379.226716) (xy 138.148755 -379.191025) (xy 138.194605 -379.161559)
			(xy 138.244182 -379.138917) (xy 138.296477 -379.123562) (xy 138.350425 -379.115806) (xy 138.404927 -379.115806)
			(xy 138.458875 -379.123562) (xy 138.51117 -379.138917) (xy 138.560747 -379.161559) (xy 138.606597 -379.191025)
			(xy 138.647788 -379.226716) (xy 138.683479 -379.267907) (xy 138.712945 -379.313757) (xy 138.735587 -379.363334)
			(xy 138.750942 -379.415629) (xy 138.758698 -379.469577) (xy 138.759184 -379.496828) (xy 138.759184 -380.360428)
			(xy 170.523916 -380.360428) (xy 170.523916 -379.496828) (xy 170.524402 -379.469577) (xy 170.532158 -379.415629)
			(xy 170.547513 -379.363334) (xy 170.570155 -379.313757) (xy 170.599621 -379.267907) (xy 170.635312 -379.226716)
			(xy 170.676503 -379.191025) (xy 170.722353 -379.161559) (xy 170.77193 -379.138917) (xy 170.824225 -379.123562)
			(xy 170.878173 -379.115806) (xy 170.932675 -379.115806) (xy 170.986623 -379.123562) (xy 171.038918 -379.138917)
			(xy 171.088495 -379.161559) (xy 171.134345 -379.191025) (xy 171.175536 -379.226716) (xy 171.211227 -379.267907)
			(xy 171.240693 -379.313757) (xy 171.263335 -379.363334) (xy 171.27869 -379.415629) (xy 171.286446 -379.469577)
			(xy 171.286932 -379.496828) (xy 171.286932 -380.360428) (xy 171.286446 -380.387679) (xy 171.27869 -380.441627)
			(xy 171.263335 -380.493922) (xy 171.240693 -380.543499) (xy 171.211227 -380.589349) (xy 171.175536 -380.63054)
			(xy 171.134345 -380.666231) (xy 171.088495 -380.695697) (xy 171.038918 -380.718339) (xy 170.986623 -380.733694)
			(xy 170.932675 -380.74145) (xy 170.878173 -380.74145) (xy 170.824225 -380.733694) (xy 170.77193 -380.718339)
			(xy 170.722353 -380.695697) (xy 170.676503 -380.666231) (xy 170.635312 -380.63054) (xy 170.599621 -380.589349)
			(xy 170.570155 -380.543499) (xy 170.547513 -380.493922) (xy 170.532158 -380.441627) (xy 170.524402 -380.387679)
			(xy 170.523916 -380.360428) (xy 138.759184 -380.360428) (xy 138.758698 -380.387679) (xy 138.750942 -380.441627)
			(xy 138.735587 -380.493922) (xy 138.712945 -380.543499) (xy 138.683479 -380.589349) (xy 138.647788 -380.63054)
			(xy 138.606597 -380.666231) (xy 138.560747 -380.695697) (xy 138.51117 -380.718339) (xy 138.458875 -380.733694)
			(xy 138.404927 -380.74145) (xy 138.350425 -380.74145) (xy 138.296477 -380.733694) (xy 138.244182 -380.718339)
			(xy 138.194605 -380.695697) (xy 138.148755 -380.666231) (xy 138.107564 -380.63054) (xy 138.071873 -380.589349)
			(xy 138.042407 -380.543499) (xy 138.019765 -380.493922) (xy 138.00441 -380.441627) (xy 137.996654 -380.387679)
			(xy 137.996168 -380.360428) (xy 104.187244 -380.360428) (xy 104.186758 -380.387697) (xy 104.178996 -380.441681)
			(xy 104.163631 -380.494011) (xy 104.140974 -380.543621) (xy 104.111488 -380.589502) (xy 104.075773 -380.630719)
			(xy 104.034556 -380.666434) (xy 103.988675 -380.69592) (xy 103.939065 -380.718577) (xy 103.886735 -380.733942)
			(xy 103.832751 -380.741704) (xy 103.778213 -380.741704) (xy 103.724229 -380.733942) (xy 103.671899 -380.718577)
			(xy 103.622289 -380.69592) (xy 103.576408 -380.666434) (xy 103.535191 -380.630719) (xy 103.499476 -380.589502)
			(xy 103.46999 -380.543621) (xy 103.447333 -380.494011) (xy 103.431968 -380.441681) (xy 103.424206 -380.387697)
			(xy 103.42372 -380.360428) (xy 71.659496 -380.360428) (xy 71.65901 -380.387697) (xy 71.651248 -380.441681)
			(xy 71.635883 -380.494011) (xy 71.613226 -380.543621) (xy 71.58374 -380.589502) (xy 71.548025 -380.630719)
			(xy 71.506808 -380.666434) (xy 71.460927 -380.69592) (xy 71.411317 -380.718577) (xy 71.358987 -380.733942)
			(xy 71.305003 -380.741704) (xy 71.250465 -380.741704) (xy 71.196481 -380.733942) (xy 71.144151 -380.718577)
			(xy 71.094541 -380.69592) (xy 71.04866 -380.666434) (xy 71.007443 -380.630719) (xy 70.971728 -380.589502)
			(xy 70.942242 -380.543621) (xy 70.919585 -380.494011) (xy 70.90422 -380.441681) (xy 70.896458 -380.387697)
			(xy 70.895972 -380.360428) (xy 36.084678 -380.360428) (xy 36.08409 -380.360596) (xy 35.910659 -380.401926)
			(xy 35.735559 -380.43549) (xy 35.559139 -380.46122) (xy 35.381747 -380.479066) (xy 35.203736 -380.488992)
			(xy 35.025459 -380.490978) (xy 34.847272 -380.485021) (xy 34.669526 -380.471131) (xy 34.492576 -380.449338)
			(xy 34.316772 -380.419684) (xy 34.142464 -380.382227) (xy 33.969997 -380.337043) (xy 33.799714 -380.284221)
			(xy 33.631953 -380.223865) (xy 33.467048 -380.156097) (xy 33.305325 -380.081049) (xy 33.147106 -379.998872)
			(xy 32.992705 -379.909729) (xy 32.842428 -379.813795) (xy 32.696573 -379.711263) (xy 32.555431 -379.602335)
			(xy 32.419282 -379.487228) (xy 32.288395 -379.36617) (xy 32.163031 -379.239401) (xy 32.043438 -379.107174)
			(xy 31.929855 -378.969751) (xy 31.822506 -378.827404) (xy 31.721605 -378.680416) (xy 31.627352 -378.52908)
			(xy 31.539934 -378.373695) (xy 31.459524 -378.21457) (xy 31.386283 -378.052021) (xy 31.320356 -377.886371)
			(xy 31.261873 -377.717949) (xy 31.210951 -377.547088) (xy 31.167691 -377.374129) (xy 31.132179 -377.199414)
			(xy 31.104485 -377.02329) (xy 31.084664 -376.846108) (xy 31.072756 -376.668219) (xy 31.068784 -376.489976)
			(xy 2.509012 -376.489976) (xy 2.509012 -382.36906) (xy 41.04894 -382.36906) (xy 41.04894 -381.50546)
			(xy 41.049426 -381.478191) (xy 41.057188 -381.424207) (xy 41.072553 -381.371877) (xy 41.09521 -381.322267)
			(xy 41.124696 -381.276386) (xy 41.160411 -381.235169) (xy 41.201628 -381.199454) (xy 41.247509 -381.169968)
			(xy 41.297119 -381.147311) (xy 41.349449 -381.131946) (xy 41.403433 -381.124184) (xy 41.457971 -381.124184)
			(xy 41.511955 -381.131946) (xy 41.564285 -381.147311) (xy 41.613895 -381.169968) (xy 41.659776 -381.199454)
			(xy 41.700993 -381.235169) (xy 41.736708 -381.276386) (xy 41.766194 -381.322267) (xy 41.788851 -381.371877)
			(xy 41.804216 -381.424207) (xy 41.811978 -381.478191) (xy 41.812464 -381.50546) (xy 41.812464 -382.36906)
			(xy 73.576688 -382.36906) (xy 73.576688 -381.50546) (xy 73.577174 -381.478191) (xy 73.584936 -381.424207)
			(xy 73.600301 -381.371877) (xy 73.622958 -381.322267) (xy 73.652444 -381.276386) (xy 73.688159 -381.235169)
			(xy 73.729376 -381.199454) (xy 73.775257 -381.169968) (xy 73.824867 -381.147311) (xy 73.877197 -381.131946)
			(xy 73.931181 -381.124184) (xy 73.985719 -381.124184) (xy 74.039703 -381.131946) (xy 74.092033 -381.147311)
			(xy 74.141643 -381.169968) (xy 74.187524 -381.199454) (xy 74.228741 -381.235169) (xy 74.264456 -381.276386)
			(xy 74.293942 -381.322267) (xy 74.316599 -381.371877) (xy 74.331964 -381.424207) (xy 74.339726 -381.478191)
			(xy 74.340212 -381.50546) (xy 74.340212 -382.36906) (xy 108.149136 -382.36906) (xy 108.149136 -381.50546)
			(xy 108.149622 -381.478209) (xy 108.157378 -381.424261) (xy 108.172733 -381.371966) (xy 108.195375 -381.322389)
			(xy 108.224841 -381.276539) (xy 108.260532 -381.235348) (xy 108.301723 -381.199657) (xy 108.347573 -381.170191)
			(xy 108.39715 -381.147549) (xy 108.449445 -381.132194) (xy 108.503393 -381.124438) (xy 108.557895 -381.124438)
			(xy 108.611843 -381.132194) (xy 108.664138 -381.147549) (xy 108.713715 -381.170191) (xy 108.759565 -381.199657)
			(xy 108.800756 -381.235348) (xy 108.836447 -381.276539) (xy 108.865913 -381.322389) (xy 108.888555 -381.371966)
			(xy 108.90391 -381.424261) (xy 108.911666 -381.478209) (xy 108.912152 -381.50546) (xy 108.912152 -382.36906)
			(xy 140.676884 -382.36906) (xy 140.676884 -381.50546) (xy 140.67737 -381.478209) (xy 140.685126 -381.424261)
			(xy 140.700481 -381.371966) (xy 140.723123 -381.322389) (xy 140.752589 -381.276539) (xy 140.78828 -381.235348)
			(xy 140.829471 -381.199657) (xy 140.875321 -381.170191) (xy 140.924898 -381.147549) (xy 140.977193 -381.132194)
			(xy 141.031141 -381.124438) (xy 141.085643 -381.124438) (xy 141.139591 -381.132194) (xy 141.191886 -381.147549)
			(xy 141.241463 -381.170191) (xy 141.287313 -381.199657) (xy 141.328504 -381.235348) (xy 141.364195 -381.276539)
			(xy 141.393661 -381.322389) (xy 141.416303 -381.371966) (xy 141.431658 -381.424261) (xy 141.439414 -381.478209)
			(xy 141.4399 -381.50546) (xy 141.4399 -382.36906) (xy 141.439414 -382.396311) (xy 141.431658 -382.450259)
			(xy 141.416303 -382.502554) (xy 141.393661 -382.552131) (xy 141.364195 -382.597981) (xy 141.328504 -382.639172)
			(xy 141.287313 -382.674863) (xy 141.241463 -382.704329) (xy 141.191886 -382.726971) (xy 141.139591 -382.742326)
			(xy 141.085643 -382.750082) (xy 141.031141 -382.750082) (xy 140.977193 -382.742326) (xy 140.924898 -382.726971)
			(xy 140.875321 -382.704329) (xy 140.829471 -382.674863) (xy 140.78828 -382.639172) (xy 140.752589 -382.597981)
			(xy 140.723123 -382.552131) (xy 140.700481 -382.502554) (xy 140.685126 -382.450259) (xy 140.67737 -382.396311)
			(xy 140.676884 -382.36906) (xy 108.912152 -382.36906) (xy 108.911666 -382.396311) (xy 108.90391 -382.450259)
			(xy 108.888555 -382.502554) (xy 108.865913 -382.552131) (xy 108.836447 -382.597981) (xy 108.800756 -382.639172)
			(xy 108.759565 -382.674863) (xy 108.713715 -382.704329) (xy 108.664138 -382.726971) (xy 108.611843 -382.742326)
			(xy 108.557895 -382.750082) (xy 108.503393 -382.750082) (xy 108.449445 -382.742326) (xy 108.39715 -382.726971)
			(xy 108.347573 -382.704329) (xy 108.301723 -382.674863) (xy 108.260532 -382.639172) (xy 108.224841 -382.597981)
			(xy 108.195375 -382.552131) (xy 108.172733 -382.502554) (xy 108.157378 -382.450259) (xy 108.149622 -382.396311)
			(xy 108.149136 -382.36906) (xy 74.340212 -382.36906) (xy 74.339726 -382.396329) (xy 74.331964 -382.450313)
			(xy 74.316599 -382.502643) (xy 74.293942 -382.552253) (xy 74.264456 -382.598134) (xy 74.228741 -382.639351)
			(xy 74.187524 -382.675066) (xy 74.141643 -382.704552) (xy 74.092033 -382.727209) (xy 74.039703 -382.742574)
			(xy 73.985719 -382.750336) (xy 73.931181 -382.750336) (xy 73.877197 -382.742574) (xy 73.824867 -382.727209)
			(xy 73.775257 -382.704552) (xy 73.729376 -382.675066) (xy 73.688159 -382.639351) (xy 73.652444 -382.598134)
			(xy 73.622958 -382.552253) (xy 73.600301 -382.502643) (xy 73.584936 -382.450313) (xy 73.577174 -382.396329)
			(xy 73.576688 -382.36906) (xy 41.812464 -382.36906) (xy 41.811978 -382.396329) (xy 41.804216 -382.450313)
			(xy 41.788851 -382.502643) (xy 41.766194 -382.552253) (xy 41.736708 -382.598134) (xy 41.700993 -382.639351)
			(xy 41.659776 -382.675066) (xy 41.613895 -382.704552) (xy 41.564285 -382.727209) (xy 41.511955 -382.742574)
			(xy 41.457971 -382.750336) (xy 41.403433 -382.750336) (xy 41.349449 -382.742574) (xy 41.297119 -382.727209)
			(xy 41.247509 -382.704552) (xy 41.201628 -382.675066) (xy 41.160411 -382.639351) (xy 41.124696 -382.598134)
			(xy 41.09521 -382.552253) (xy 41.072553 -382.502643) (xy 41.057188 -382.450313) (xy 41.049426 -382.396329)
			(xy 41.04894 -382.36906) (xy 2.509012 -382.36906) (xy 2.509012 -385.310888) (xy 47.485808 -385.310888)
			(xy 47.485808 -385.31038) (xy 47.486243 -385.2864) (xy 47.493745 -385.239031) (xy 47.508561 -385.193417)
			(xy 47.530326 -385.15068) (xy 47.558505 -385.111872) (xy 47.592406 -385.077947) (xy 47.631194 -385.04974)
			(xy 47.673915 -385.027944) (xy 47.719518 -385.013096) (xy 47.766882 -385.00556) (xy 47.790862 -385.005072)
			(xy 47.79137 -385.005072) (xy 47.815305 -385.005523) (xy 47.862591 -385.012984) (xy 47.908134 -385.027728)
			(xy 47.950821 -385.049394) (xy 47.989606 -385.077452) (xy 48.023541 -385.111216) (xy 48.051795 -385.149858)
			(xy 48.06315 -385.170934) (xy 48.063658 -385.17195) (xy 48.143964 -385.310888) (xy 48.685704 -385.310888)
			(xy 48.685704 -385.31038) (xy 48.686143 -385.2864) (xy 48.693645 -385.239031) (xy 48.70846 -385.193417)
			(xy 48.730225 -385.150681) (xy 48.758404 -385.111873) (xy 48.792304 -385.077949) (xy 48.831092 -385.049741)
			(xy 48.873812 -385.027945) (xy 48.919415 -385.013097) (xy 48.966779 -385.005561) (xy 48.990758 -385.005072)
			(xy 48.991266 -385.005072) (xy 49.015201 -385.005526) (xy 49.062486 -385.012986) (xy 49.10803 -385.02773)
			(xy 49.150716 -385.049395) (xy 49.189502 -385.077453) (xy 49.223437 -385.111216) (xy 49.251691 -385.149859)
			(xy 49.263046 -385.170934) (xy 49.263554 -385.17195) (xy 49.34386 -385.310888) (xy 49.8856 -385.310888)
			(xy 49.8856 -385.31038) (xy 49.886043 -385.286401) (xy 49.893545 -385.239032) (xy 49.90836 -385.193418)
			(xy 49.930124 -385.150682) (xy 49.958303 -385.111875) (xy 49.992203 -385.07795) (xy 50.030989 -385.049743)
			(xy 50.073709 -385.027946) (xy 50.119312 -385.013097) (xy 50.166675 -385.005561) (xy 50.190654 -385.005072)
			(xy 50.191162 -385.005072) (xy 50.215097 -385.005529) (xy 50.262382 -385.012989) (xy 50.307925 -385.027732)
			(xy 50.350612 -385.049397) (xy 50.389397 -385.077454) (xy 50.423333 -385.111217) (xy 50.451587 -385.149859)
			(xy 50.462942 -385.170934) (xy 50.46345 -385.17195) (xy 50.543756 -385.310888) (xy 51.086004 -385.310888)
			(xy 51.086004 -385.31038) (xy 51.086444 -385.286388) (xy 51.093954 -385.238994) (xy 51.108785 -385.193359)
			(xy 51.130572 -385.150605) (xy 51.158779 -385.111786) (xy 51.192711 -385.077858) (xy 51.231533 -385.049655)
			(xy 51.274288 -385.027872) (xy 51.319925 -385.013046) (xy 51.36732 -385.005542) (xy 51.391312 -385.005072)
			(xy 51.415246 -385.00557) (xy 51.462529 -385.013022) (xy 51.508071 -385.027757) (xy 51.550758 -385.049416)
			(xy 51.589544 -385.077467) (xy 51.62348 -385.111224) (xy 51.651736 -385.149861) (xy 51.663092 -385.170934)
			(xy 51.6636 -385.17195) (xy 51.743906 -385.310888) (xy 52.2859 -385.310888) (xy 52.2859 -385.31038)
			(xy 52.286344 -385.286388) (xy 52.293854 -385.238995) (xy 52.308684 -385.19336) (xy 52.330471 -385.150606)
			(xy 52.358677 -385.111788) (xy 52.392609 -385.077859) (xy 52.43143 -385.049656) (xy 52.474186 -385.027873)
			(xy 52.519822 -385.013047) (xy 52.567216 -385.005542) (xy 52.591208 -385.005072) (xy 52.615141 -385.005573)
			(xy 52.662424 -385.013024) (xy 52.707967 -385.027759) (xy 52.750653 -385.049417) (xy 52.789439 -385.077468)
			(xy 52.823376 -385.111224) (xy 52.851632 -385.149861) (xy 52.862988 -385.170934) (xy 52.863496 -385.17195)
			(xy 52.943802 -385.310888) (xy 53.485796 -385.310888) (xy 53.485796 -385.31038) (xy 53.486243 -385.286401)
			(xy 53.493744 -385.239032) (xy 53.508559 -385.193419) (xy 53.530324 -385.150684) (xy 53.558502 -385.111876)
			(xy 53.592401 -385.077951) (xy 53.631187 -385.049744) (xy 53.673907 -385.027948) (xy 53.719508 -385.013098)
			(xy 53.766871 -385.005561) (xy 53.79085 -385.005072) (xy 53.791358 -385.005072) (xy 53.815293 -385.005532)
			(xy 53.862578 -385.012992) (xy 53.908121 -385.027734) (xy 53.950807 -385.049398) (xy 53.989593 -385.077455)
			(xy 54.023528 -385.111217) (xy 54.051783 -385.149859) (xy 54.063138 -385.170934) (xy 54.063646 -385.17195)
			(xy 54.143952 -385.310888) (xy 54.685692 -385.310888) (xy 54.685692 -385.31038) (xy 54.686143 -385.286401)
			(xy 54.693644 -385.239033) (xy 54.708459 -385.19342) (xy 54.730223 -385.150685) (xy 54.758401 -385.111877)
			(xy 54.792299 -385.077953) (xy 54.831085 -385.049745) (xy 54.873804 -385.027949) (xy 54.919405 -385.013099)
			(xy 54.966767 -385.005562) (xy 54.990746 -385.005072) (xy 54.991254 -385.005072) (xy 55.015189 -385.005536)
			(xy 55.062474 -385.012994) (xy 55.108017 -385.027736) (xy 55.150703 -385.0494) (xy 55.189489 -385.077456)
			(xy 55.223424 -385.111218) (xy 55.251679 -385.149859) (xy 55.263034 -385.170934) (xy 55.263542 -385.17195)
			(xy 55.343848 -385.310888) (xy 55.885588 -385.310888) (xy 55.885588 -385.31038) (xy 55.886043 -385.286401)
			(xy 55.893544 -385.239034) (xy 55.908359 -385.193421) (xy 55.930122 -385.150686) (xy 55.958299 -385.111879)
			(xy 55.992198 -385.077954) (xy 56.030983 -385.049747) (xy 56.073701 -385.02795) (xy 56.119302 -385.0131)
			(xy 56.166663 -385.005562) (xy 56.190642 -385.005072) (xy 56.19115 -385.005072) (xy 56.215085 -385.005539)
			(xy 56.262369 -385.012997) (xy 56.307912 -385.027738) (xy 56.350599 -385.049401) (xy 56.389384 -385.077457)
			(xy 56.42332 -385.111218) (xy 56.451575 -385.149859) (xy 56.46293 -385.170934) (xy 56.463438 -385.17195)
			(xy 56.543744 -385.310888) (xy 57.085992 -385.310888) (xy 57.085992 -385.31038) (xy 57.086444 -385.286388)
			(xy 57.093953 -385.238996) (xy 57.108783 -385.193362) (xy 57.130569 -385.150609) (xy 57.158775 -385.11179)
			(xy 57.192706 -385.077862) (xy 57.231526 -385.049659) (xy 57.27428 -385.027876) (xy 57.319915 -385.013049)
			(xy 57.367308 -385.005543) (xy 57.3913 -385.005072) (xy 57.391554 -385.005072) (xy 57.415489 -385.005536)
			(xy 57.462774 -385.012994) (xy 57.508317 -385.027736) (xy 57.551003 -385.0494) (xy 57.589789 -385.077456)
			(xy 57.623724 -385.111218) (xy 57.651979 -385.149859) (xy 57.663334 -385.170934) (xy 57.663842 -385.17195)
			(xy 57.744148 -385.310888) (xy 58.285888 -385.310888) (xy 58.285888 -385.31038) (xy 58.286344 -385.286388)
			(xy 58.293853 -385.238996) (xy 58.308683 -385.193362) (xy 58.330469 -385.15061) (xy 58.358674 -385.111792)
			(xy 58.392604 -385.077863) (xy 58.431424 -385.04966) (xy 58.474177 -385.027877) (xy 58.519812 -385.013049)
			(xy 58.567204 -385.005543) (xy 58.591196 -385.005072) (xy 58.59145 -385.005072) (xy 58.615385 -385.005539)
			(xy 58.662669 -385.012997) (xy 58.708212 -385.027738) (xy 58.750899 -385.049401) (xy 58.789684 -385.077457)
			(xy 58.82362 -385.111218) (xy 58.851875 -385.149859) (xy 58.86323 -385.170934) (xy 58.863738 -385.17195)
			(xy 58.944044 -385.310888) (xy 59.485784 -385.310888) (xy 59.485784 -385.31038) (xy 59.486243 -385.286401)
			(xy 59.493744 -385.239034) (xy 59.508558 -385.193422) (xy 59.530321 -385.150687) (xy 59.558498 -385.11188)
			(xy 59.592396 -385.077956) (xy 59.63118 -385.049748) (xy 59.673898 -385.027951) (xy 59.719498 -385.013101)
			(xy 59.76686 -385.005562) (xy 59.790838 -385.005072) (xy 59.791346 -385.005072) (xy 59.815281 -385.005542)
			(xy 59.862565 -385.012999) (xy 59.908108 -385.02774) (xy 59.950794 -385.049403) (xy 59.98958 -385.077458)
			(xy 60.023516 -385.111219) (xy 60.051771 -385.149859) (xy 60.063126 -385.170934) (xy 60.063634 -385.17195)
			(xy 60.14394 -385.310888) (xy 60.68568 -385.310888) (xy 60.68568 -385.31038) (xy 60.686121 -385.286374)
			(xy 60.693638 -385.238955) (xy 60.708484 -385.193296) (xy 60.730293 -385.150524) (xy 60.758527 -385.111692)
			(xy 60.792491 -385.077757) (xy 60.831347 -385.049556) (xy 60.874139 -385.027783) (xy 60.91981 -385.012977)
			(xy 60.967236 -385.0055) (xy 60.991242 -385.005072) (xy 60.991496 -385.005072) (xy 61.015432 -385.005502)
			(xy 61.062718 -385.012966) (xy 61.108262 -385.027714) (xy 61.150949 -385.049384) (xy 61.189734 -385.077445)
			(xy 61.223668 -385.111212) (xy 61.251922 -385.149857) (xy 61.263276 -385.170934) (xy 61.263784 -385.17195)
			(xy 61.34409 -385.310888) (xy 61.885576 -385.310888) (xy 61.885576 -385.31038) (xy 61.886021 -385.286374)
			(xy 61.893538 -385.238955) (xy 61.908383 -385.193297) (xy 61.930192 -385.150525) (xy 61.958426 -385.111693)
			(xy 61.992389 -385.077758) (xy 62.031245 -385.049557) (xy 62.074036 -385.027785) (xy 62.119707 -385.012977)
			(xy 62.167132 -385.0055) (xy 62.191138 -385.005072) (xy 62.191392 -385.005072) (xy 62.215328 -385.005505)
			(xy 62.262614 -385.012969) (xy 62.308158 -385.027716) (xy 62.350844 -385.049385) (xy 62.38963 -385.077446)
			(xy 62.423564 -385.111212) (xy 62.451818 -385.149857) (xy 62.463172 -385.170934) (xy 62.46368 -385.17195)
			(xy 62.543986 -385.310888) (xy 63.08598 -385.310888) (xy 63.08598 -385.31038) (xy 63.086444 -385.286389)
			(xy 63.093953 -385.238998) (xy 63.108782 -385.193364) (xy 63.130567 -385.150612) (xy 63.158771 -385.111795)
			(xy 63.192701 -385.077866) (xy 63.231519 -385.049663) (xy 63.274272 -385.027879) (xy 63.319905 -385.013051)
			(xy 63.367297 -385.005543) (xy 63.391288 -385.005072) (xy 63.391542 -385.005072) (xy 63.415476 -385.005545)
			(xy 63.462761 -385.013002) (xy 63.508303 -385.027742) (xy 63.55099 -385.049404) (xy 63.589776 -385.077459)
			(xy 63.623712 -385.11122) (xy 63.651967 -385.14986) (xy 63.663322 -385.170934) (xy 63.66383 -385.17195)
			(xy 63.744136 -385.310888) (xy 64.285876 -385.310888) (xy 64.285876 -385.31038) (xy 64.286344 -385.286389)
			(xy 64.293853 -385.238998) (xy 64.308682 -385.193365) (xy 64.330467 -385.150614) (xy 64.35867 -385.111796)
			(xy 64.392599 -385.077868) (xy 64.431417 -385.049664) (xy 64.474169 -385.02788) (xy 64.519802 -385.013052)
			(xy 64.567193 -385.005544) (xy 64.591184 -385.005072) (xy 64.591438 -385.005072) (xy 64.615372 -385.005549)
			(xy 64.662656 -385.013005) (xy 64.708199 -385.027744) (xy 64.750886 -385.049406) (xy 64.789672 -385.07746)
			(xy 64.823607 -385.11122) (xy 64.851863 -385.14986) (xy 64.863218 -385.170934) (xy 64.863726 -385.17195)
			(xy 64.944032 -385.310888) (xy 65.485772 -385.310888) (xy 65.485772 -385.31038) (xy 65.486243 -385.286402)
			(xy 65.493744 -385.239036) (xy 65.508557 -385.193425) (xy 65.530319 -385.150691) (xy 65.558495 -385.111884)
			(xy 65.592391 -385.07796) (xy 65.631174 -385.049752) (xy 65.67389 -385.027954) (xy 65.719489 -385.013103)
			(xy 65.766848 -385.005563) (xy 65.790826 -385.005072) (xy 65.791334 -385.005072) (xy 65.815268 -385.005552)
			(xy 65.862552 -385.013007) (xy 65.908095 -385.027746) (xy 65.950781 -385.049407) (xy 65.989567 -385.077461)
			(xy 66.023503 -385.111221) (xy 66.051759 -385.14986) (xy 66.063114 -385.170934) (xy 66.063622 -385.17195)
			(xy 66.143928 -385.310888) (xy 80.013556 -385.310888) (xy 80.013556 -385.31038) (xy 80.014043 -385.286403)
			(xy 80.021543 -385.239038) (xy 80.036355 -385.193429) (xy 80.058116 -385.150695) (xy 80.08629 -385.11189)
			(xy 80.120184 -385.077966) (xy 80.158965 -385.049758) (xy 80.201679 -385.027959) (xy 80.247275 -385.013106)
			(xy 80.294633 -385.005564) (xy 80.31861 -385.005072) (xy 80.319118 -385.005072) (xy 80.343052 -385.005565)
			(xy 80.390335 -385.013018) (xy 80.435877 -385.027754) (xy 80.478564 -385.049413) (xy 80.51735 -385.077465)
			(xy 80.551287 -385.111223) (xy 80.579542 -385.149861) (xy 80.590898 -385.170934) (xy 80.591406 -385.17195)
			(xy 80.671712 -385.310888) (xy 81.213452 -385.310888) (xy 81.213452 -385.31038) (xy 81.213943 -385.286403)
			(xy 81.221443 -385.239039) (xy 81.236255 -385.193429) (xy 81.258015 -385.150697) (xy 81.286189 -385.111891)
			(xy 81.320082 -385.077967) (xy 81.358863 -385.049759) (xy 81.401576 -385.02796) (xy 81.447172 -385.013107)
			(xy 81.494529 -385.005565) (xy 81.518506 -385.005072) (xy 81.519014 -385.005072) (xy 81.542948 -385.005568)
			(xy 81.590231 -385.013021) (xy 81.635773 -385.027756) (xy 81.67846 -385.049415) (xy 81.717246 -385.077466)
			(xy 81.751182 -385.111224) (xy 81.779438 -385.149861) (xy 81.790794 -385.170934) (xy 81.791302 -385.17195)
			(xy 81.871608 -385.310888) (xy 82.413348 -385.310888) (xy 82.413348 -385.31038) (xy 82.413843 -385.286403)
			(xy 82.421343 -385.239039) (xy 82.436155 -385.19343) (xy 82.457915 -385.150698) (xy 82.486088 -385.111892)
			(xy 82.519981 -385.077969) (xy 82.55876 -385.04976) (xy 82.601473 -385.027961) (xy 82.647069 -385.013108)
			(xy 82.694426 -385.005565) (xy 82.718402 -385.005072) (xy 82.71891 -385.005072) (xy 82.742843 -385.005571)
			(xy 82.790127 -385.013023) (xy 82.835669 -385.027758) (xy 82.878355 -385.049416) (xy 82.917142 -385.077467)
			(xy 82.951078 -385.111224) (xy 82.979334 -385.149861) (xy 82.99069 -385.170934) (xy 82.991198 -385.17195)
			(xy 83.071504 -385.310888) (xy 83.613752 -385.310888) (xy 83.613752 -385.31038) (xy 83.614244 -385.28639)
			(xy 83.621752 -385.239002) (xy 83.63658 -385.193371) (xy 83.658362 -385.150621) (xy 83.686563 -385.111804)
			(xy 83.720489 -385.077876) (xy 83.759304 -385.049673) (xy 83.802052 -385.027887) (xy 83.847682 -385.013057)
			(xy 83.89507 -385.005546) (xy 83.91906 -385.005072) (xy 83.942995 -385.005531) (xy 83.99028 -385.01299)
			(xy 84.035823 -385.027733) (xy 84.07851 -385.049398) (xy 84.117295 -385.077455) (xy 84.151231 -385.111217)
			(xy 84.179485 -385.149859) (xy 84.19084 -385.170934) (xy 84.191348 -385.17195) (xy 84.271654 -385.310888)
			(xy 84.813648 -385.310888) (xy 84.813648 -385.31038) (xy 84.814144 -385.28639) (xy 84.821652 -385.239002)
			(xy 84.836479 -385.193372) (xy 84.858261 -385.150622) (xy 84.886462 -385.111805) (xy 84.920387 -385.077878)
			(xy 84.959201 -385.049674) (xy 85.001949 -385.027888) (xy 85.047579 -385.013057) (xy 85.094966 -385.005546)
			(xy 85.118956 -385.005072) (xy 85.142891 -385.005534) (xy 85.190176 -385.012993) (xy 85.235719 -385.027735)
			(xy 85.278405 -385.049399) (xy 85.317191 -385.077456) (xy 85.351126 -385.111218) (xy 85.379381 -385.149859)
			(xy 85.390736 -385.170934) (xy 85.391244 -385.17195) (xy 85.47155 -385.310888) (xy 86.013544 -385.310888)
			(xy 86.013544 -385.31038) (xy 86.014043 -385.286403) (xy 86.021543 -385.23904) (xy 86.036354 -385.193431)
			(xy 86.058114 -385.150699) (xy 86.086287 -385.111894) (xy 86.120179 -385.07797) (xy 86.158958 -385.049762)
			(xy 86.20167 -385.027962) (xy 86.247265 -385.013109) (xy 86.294622 -385.005565) (xy 86.318598 -385.005072)
			(xy 86.319106 -385.005072) (xy 86.343039 -385.005575) (xy 86.390322 -385.013026) (xy 86.435864 -385.02776)
			(xy 86.478551 -385.049418) (xy 86.517337 -385.077468) (xy 86.551274 -385.111225) (xy 86.57953 -385.149861)
			(xy 86.590886 -385.170934) (xy 86.591394 -385.17195) (xy 86.6717 -385.310888) (xy 87.21344 -385.310888)
			(xy 87.21344 -385.31038) (xy 87.213843 -385.286399) (xy 87.221346 -385.239026) (xy 87.236164 -385.193409)
			(xy 87.257932 -385.15067) (xy 87.286115 -385.111861) (xy 87.320019 -385.077936) (xy 87.358812 -385.049729)
			(xy 87.401537 -385.027935) (xy 87.447145 -385.013089) (xy 87.494513 -385.005558) (xy 87.518494 -385.005072)
			(xy 87.519002 -385.005072) (xy 87.542935 -385.005578) (xy 87.590218 -385.013028) (xy 87.63576 -385.027763)
			(xy 87.678447 -385.04942) (xy 87.717233 -385.077469) (xy 87.75117 -385.111225) (xy 87.779426 -385.149861)
			(xy 87.790782 -385.170934) (xy 87.79129 -385.17195) (xy 87.871596 -385.310888) (xy 88.413336 -385.310888)
			(xy 88.413336 -385.31038) (xy 88.413743 -385.286399) (xy 88.421246 -385.239027) (xy 88.436063 -385.19341)
			(xy 88.457831 -385.150672) (xy 88.486013 -385.111862) (xy 88.519918 -385.077937) (xy 88.558709 -385.04973)
			(xy 88.601434 -385.027936) (xy 88.647041 -385.01309) (xy 88.694409 -385.005558) (xy 88.71839 -385.005072)
			(xy 88.718898 -385.005072) (xy 88.742834 -385.0055) (xy 88.790121 -385.012965) (xy 88.835664 -385.027713)
			(xy 88.878351 -385.049383) (xy 88.917136 -385.077445) (xy 88.95107 -385.111212) (xy 88.979324 -385.149857)
			(xy 88.990678 -385.170934) (xy 88.991186 -385.17195) (xy 89.071492 -385.310888) (xy 89.61374 -385.310888)
			(xy 89.61374 -385.31038) (xy 89.61412 -385.286384) (xy 89.621631 -385.238983) (xy 89.636465 -385.193341)
			(xy 89.658257 -385.150582) (xy 89.68647 -385.111758) (xy 89.72041 -385.077826) (xy 89.75924 -385.049622)
			(xy 89.802004 -385.027839) (xy 89.847649 -385.013015) (xy 89.895052 -385.005515) (xy 89.919048 -385.005072)
			(xy 89.942983 -385.005541) (xy 89.990267 -385.012998) (xy 90.03581 -385.027739) (xy 90.078497 -385.049402)
			(xy 90.117282 -385.077458) (xy 90.151218 -385.111219) (xy 90.179473 -385.149859) (xy 90.190828 -385.170934)
			(xy 90.191336 -385.17195) (xy 90.271642 -385.310888) (xy 90.813636 -385.310888) (xy 90.813636 -385.31038)
			(xy 90.81402 -385.286384) (xy 90.821531 -385.238984) (xy 90.836365 -385.193342) (xy 90.858157 -385.150583)
			(xy 90.886369 -385.111759) (xy 90.920308 -385.077828) (xy 90.959138 -385.049623) (xy 91.001901 -385.02784)
			(xy 91.047546 -385.013016) (xy 91.094948 -385.005515) (xy 91.118944 -385.005072) (xy 91.142878 -385.005544)
			(xy 91.190163 -385.013001) (xy 91.235706 -385.027741) (xy 91.278392 -385.049404) (xy 91.317178 -385.077459)
			(xy 91.351114 -385.111219) (xy 91.379369 -385.14986) (xy 91.390724 -385.170934) (xy 91.391232 -385.17195)
			(xy 91.471538 -385.310888) (xy 92.013532 -385.310888) (xy 92.013532 -385.31038) (xy 92.013943 -385.286399)
			(xy 92.021446 -385.239027) (xy 92.036263 -385.193411) (xy 92.05803 -385.150673) (xy 92.086212 -385.111864)
			(xy 92.120116 -385.077939) (xy 92.158907 -385.049732) (xy 92.201632 -385.027937) (xy 92.247238 -385.013091)
			(xy 92.294605 -385.005559) (xy 92.318586 -385.005072) (xy 92.319094 -385.005072) (xy 92.34303 -385.005503)
			(xy 92.390316 -385.012968) (xy 92.43586 -385.027715) (xy 92.478547 -385.049385) (xy 92.517332 -385.077446)
			(xy 92.551266 -385.111212) (xy 92.57952 -385.149857) (xy 92.590874 -385.170934) (xy 92.591382 -385.17195)
			(xy 92.671688 -385.310888) (xy 93.213428 -385.310888) (xy 93.213428 -385.31038) (xy 93.213843 -385.286399)
			(xy 93.221346 -385.239028) (xy 93.236162 -385.193412) (xy 93.257929 -385.150674) (xy 93.286111 -385.111865)
			(xy 93.320014 -385.07794) (xy 93.358805 -385.049733) (xy 93.401529 -385.027938) (xy 93.447135 -385.013092)
			(xy 93.494501 -385.005559) (xy 93.518482 -385.005072) (xy 93.51899 -385.005072) (xy 93.542926 -385.005506)
			(xy 93.590212 -385.01297) (xy 93.635756 -385.027717) (xy 93.678442 -385.049386) (xy 93.717227 -385.077447)
			(xy 93.751162 -385.111213) (xy 93.779416 -385.149857) (xy 93.79077 -385.170934) (xy 93.791278 -385.17195)
			(xy 93.871584 -385.310888) (xy 94.413324 -385.310888) (xy 94.413324 -385.31038) (xy 94.413743 -385.286399)
			(xy 94.421245 -385.239028) (xy 94.436062 -385.193413) (xy 94.457829 -385.150675) (xy 94.48601 -385.111866)
			(xy 94.519913 -385.077941) (xy 94.558703 -385.049734) (xy 94.601426 -385.02794) (xy 94.647032 -385.013093)
			(xy 94.694398 -385.005559) (xy 94.718378 -385.005072) (xy 94.718886 -385.005072) (xy 94.742822 -385.00551)
			(xy 94.790108 -385.012973) (xy 94.835651 -385.027719) (xy 94.878338 -385.049388) (xy 94.917123 -385.077448)
			(xy 94.951058 -385.111213) (xy 94.979312 -385.149858) (xy 94.990666 -385.170934) (xy 94.991174 -385.17195)
			(xy 95.07148 -385.310888) (xy 95.613728 -385.310888) (xy 95.613728 -385.31038) (xy 95.61412 -385.286385)
			(xy 95.621631 -385.238985) (xy 95.636464 -385.193344) (xy 95.658255 -385.150585) (xy 95.686467 -385.111762)
			(xy 95.720405 -385.07783) (xy 95.759233 -385.049626) (xy 95.801996 -385.027843) (xy 95.847639 -385.013018)
			(xy 95.89504 -385.005515) (xy 95.919036 -385.005072) (xy 95.94297 -385.00555) (xy 95.990254 -385.013006)
			(xy 96.035797 -385.027745) (xy 96.078484 -385.049407) (xy 96.117269 -385.077461) (xy 96.151205 -385.11122)
			(xy 96.179461 -385.14986) (xy 96.190816 -385.170934) (xy 96.191324 -385.17195) (xy 96.27163 -385.310888)
			(xy 96.813624 -385.310888) (xy 96.813624 -385.31038) (xy 96.81402 -385.286385) (xy 96.821531 -385.238985)
			(xy 96.836364 -385.193345) (xy 96.858154 -385.150586) (xy 96.886366 -385.111764) (xy 96.920303 -385.077832)
			(xy 96.959131 -385.049627) (xy 97.001893 -385.027844) (xy 97.047536 -385.013018) (xy 97.094937 -385.005516)
			(xy 97.118932 -385.005072) (xy 97.142866 -385.005554) (xy 97.19015 -385.013009) (xy 97.235693 -385.027747)
			(xy 97.278379 -385.049408) (xy 97.317165 -385.077462) (xy 97.351101 -385.111221) (xy 97.379357 -385.14986)
			(xy 97.390712 -385.170934) (xy 97.39122 -385.17195) (xy 97.471526 -385.310888) (xy 98.01352 -385.310888)
			(xy 98.01352 -385.31038) (xy 98.013943 -385.2864) (xy 98.021445 -385.239029) (xy 98.036262 -385.193414)
			(xy 98.058028 -385.150676) (xy 98.086209 -385.111868) (xy 98.120111 -385.077943) (xy 98.1589 -385.049736)
			(xy 98.201623 -385.027941) (xy 98.247228 -385.013093) (xy 98.294594 -385.005559) (xy 98.318574 -385.005072)
			(xy 98.319082 -385.005072) (xy 98.343018 -385.005513) (xy 98.390303 -385.012976) (xy 98.435847 -385.027721)
			(xy 98.478534 -385.049389) (xy 98.517319 -385.077449) (xy 98.551254 -385.111214) (xy 98.579508 -385.149858)
			(xy 98.590862 -385.170934) (xy 98.59137 -385.17195) (xy 98.671676 -385.310888) (xy 114.586004 -385.310888)
			(xy 114.586004 -385.31038) (xy 114.586444 -385.286388) (xy 114.593954 -385.238994) (xy 114.608785 -385.193359)
			(xy 114.630572 -385.150605) (xy 114.658779 -385.111786) (xy 114.692711 -385.077858) (xy 114.731533 -385.049655)
			(xy 114.774288 -385.027872) (xy 114.819925 -385.013046) (xy 114.86732 -385.005542) (xy 114.891312 -385.005072)
			(xy 114.915246 -385.00557) (xy 114.962529 -385.013022) (xy 115.008071 -385.027757) (xy 115.050758 -385.049416)
			(xy 115.089544 -385.077467) (xy 115.12348 -385.111224) (xy 115.151736 -385.149861) (xy 115.163092 -385.170934)
			(xy 115.1636 -385.17195) (xy 115.243906 -385.310888) (xy 115.7859 -385.310888) (xy 115.7859 -385.31038)
			(xy 115.786344 -385.286388) (xy 115.793854 -385.238995) (xy 115.808684 -385.19336) (xy 115.830471 -385.150606)
			(xy 115.858677 -385.111788) (xy 115.892609 -385.077859) (xy 115.93143 -385.049656) (xy 115.974186 -385.027873)
			(xy 116.019822 -385.013047) (xy 116.067216 -385.005542) (xy 116.091208 -385.005072) (xy 116.115141 -385.005573)
			(xy 116.162424 -385.013024) (xy 116.207967 -385.027759) (xy 116.250653 -385.049417) (xy 116.289439 -385.077468)
			(xy 116.323376 -385.111224) (xy 116.351632 -385.149861) (xy 116.362988 -385.170934) (xy 116.363496 -385.17195)
			(xy 116.443802 -385.310888) (xy 116.985796 -385.310888) (xy 116.985796 -385.31038) (xy 116.986244 -385.286388)
			(xy 116.993753 -385.238995) (xy 117.008584 -385.193361) (xy 117.03037 -385.150608) (xy 117.058576 -385.111789)
			(xy 117.092507 -385.077861) (xy 117.131328 -385.049658) (xy 117.174083 -385.027875) (xy 117.219719 -385.013048)
			(xy 117.267112 -385.005542) (xy 117.291104 -385.005072) (xy 117.315037 -385.005576) (xy 117.36232 -385.013027)
			(xy 117.407862 -385.027762) (xy 117.450549 -385.049419) (xy 117.489335 -385.077469) (xy 117.523272 -385.111225)
			(xy 117.551528 -385.149861) (xy 117.562884 -385.170934) (xy 117.563392 -385.17195) (xy 117.643698 -385.310888)
			(xy 118.185692 -385.310888) (xy 118.185692 -385.31038) (xy 118.186143 -385.286401) (xy 118.193644 -385.239033)
			(xy 118.208459 -385.19342) (xy 118.230223 -385.150685) (xy 118.258401 -385.111877) (xy 118.292299 -385.077953)
			(xy 118.331085 -385.049745) (xy 118.373804 -385.027949) (xy 118.419405 -385.013099) (xy 118.466767 -385.005562)
			(xy 118.490746 -385.005072) (xy 118.491254 -385.005072) (xy 118.515189 -385.005536) (xy 118.562474 -385.012994)
			(xy 118.608017 -385.027736) (xy 118.650703 -385.0494) (xy 118.689489 -385.077456) (xy 118.723424 -385.111218)
			(xy 118.751679 -385.149859) (xy 118.763034 -385.170934) (xy 118.763542 -385.17195) (xy 118.843848 -385.310888)
			(xy 119.385588 -385.310888) (xy 119.385588 -385.31038) (xy 119.386043 -385.286401) (xy 119.393544 -385.239034)
			(xy 119.408359 -385.193421) (xy 119.430122 -385.150686) (xy 119.458299 -385.111879) (xy 119.492198 -385.077954)
			(xy 119.530983 -385.049747) (xy 119.573701 -385.02795) (xy 119.619302 -385.0131) (xy 119.666663 -385.005562)
			(xy 119.690642 -385.005072) (xy 119.69115 -385.005072) (xy 119.715085 -385.005539) (xy 119.762369 -385.012997)
			(xy 119.807912 -385.027738) (xy 119.850599 -385.049401) (xy 119.889384 -385.077457) (xy 119.92332 -385.111218)
			(xy 119.951575 -385.149859) (xy 119.96293 -385.170934) (xy 119.963438 -385.17195) (xy 120.043744 -385.310888)
			(xy 120.585992 -385.310888) (xy 120.585992 -385.31038) (xy 120.586444 -385.286388) (xy 120.593953 -385.238996)
			(xy 120.608783 -385.193362) (xy 120.630569 -385.150609) (xy 120.658775 -385.11179) (xy 120.692706 -385.077862)
			(xy 120.731526 -385.049659) (xy 120.77428 -385.027876) (xy 120.819915 -385.013049) (xy 120.867308 -385.005543)
			(xy 120.8913 -385.005072) (xy 120.915233 -385.00558) (xy 120.962516 -385.01303) (xy 121.008058 -385.027764)
			(xy 121.050744 -385.04942) (xy 121.089531 -385.07747) (xy 121.123468 -385.111226) (xy 121.151724 -385.149862)
			(xy 121.16308 -385.170934) (xy 121.163588 -385.17195) (xy 121.243894 -385.310888) (xy 121.785888 -385.310888)
			(xy 121.785888 -385.31038) (xy 121.786344 -385.286388) (xy 121.793853 -385.238996) (xy 121.808683 -385.193362)
			(xy 121.830469 -385.15061) (xy 121.858674 -385.111792) (xy 121.892604 -385.077863) (xy 121.931424 -385.04966)
			(xy 121.974177 -385.027877) (xy 122.019812 -385.013049) (xy 122.067204 -385.005543) (xy 122.091196 -385.005072)
			(xy 122.115132 -385.005502) (xy 122.162418 -385.012966) (xy 122.207962 -385.027714) (xy 122.250649 -385.049384)
			(xy 122.289434 -385.077445) (xy 122.323368 -385.111212) (xy 122.351622 -385.149857) (xy 122.362976 -385.170934)
			(xy 122.363484 -385.17195) (xy 122.44379 -385.310888) (xy 122.985784 -385.310888) (xy 122.985784 -385.31038)
			(xy 122.986244 -385.286389) (xy 122.993753 -385.238997) (xy 123.008583 -385.193363) (xy 123.030368 -385.150611)
			(xy 123.058573 -385.111793) (xy 123.092502 -385.077865) (xy 123.131321 -385.049662) (xy 123.174074 -385.027878)
			(xy 123.219709 -385.01305) (xy 123.267101 -385.005543) (xy 123.291092 -385.005072) (xy 123.315028 -385.005505)
			(xy 123.362314 -385.012969) (xy 123.407858 -385.027716) (xy 123.450544 -385.049385) (xy 123.48933 -385.077446)
			(xy 123.523264 -385.111212) (xy 123.551518 -385.149857) (xy 123.562872 -385.170934) (xy 123.56338 -385.17195)
			(xy 123.643686 -385.310888) (xy 124.18568 -385.310888) (xy 124.18568 -385.31038) (xy 124.186143 -385.286402)
			(xy 124.193644 -385.239035) (xy 124.208458 -385.193423) (xy 124.230221 -385.150688) (xy 124.258397 -385.111882)
			(xy 124.292294 -385.077957) (xy 124.331078 -385.049749) (xy 124.373795 -385.027952) (xy 124.419395 -385.013101)
			(xy 124.466756 -385.005562) (xy 124.490734 -385.005072) (xy 124.491242 -385.005072) (xy 124.515176 -385.005545)
			(xy 124.562461 -385.013002) (xy 124.608003 -385.027742) (xy 124.65069 -385.049404) (xy 124.689476 -385.077459)
			(xy 124.723412 -385.11122) (xy 124.751667 -385.14986) (xy 124.763022 -385.170934) (xy 124.76353 -385.17195)
			(xy 124.843836 -385.310888) (xy 125.385576 -385.310888) (xy 125.385576 -385.31038) (xy 125.386043 -385.286402)
			(xy 125.393544 -385.239035) (xy 125.408357 -385.193424) (xy 125.43012 -385.150689) (xy 125.458296 -385.111883)
			(xy 125.492192 -385.077959) (xy 125.530976 -385.049751) (xy 125.573693 -385.027953) (xy 125.619292 -385.013102)
			(xy 125.666652 -385.005563) (xy 125.69063 -385.005072) (xy 125.691138 -385.005072) (xy 125.715072 -385.005549)
			(xy 125.762356 -385.013005) (xy 125.807899 -385.027744) (xy 125.850586 -385.049406) (xy 125.889372 -385.07746)
			(xy 125.923307 -385.11122) (xy 125.951563 -385.14986) (xy 125.962918 -385.170934) (xy 125.963426 -385.17195)
			(xy 126.043732 -385.310888) (xy 126.58598 -385.310888) (xy 126.58598 -385.31038) (xy 126.586444 -385.286389)
			(xy 126.593953 -385.238998) (xy 126.608782 -385.193364) (xy 126.630567 -385.150612) (xy 126.658771 -385.111795)
			(xy 126.692701 -385.077866) (xy 126.731519 -385.049663) (xy 126.774272 -385.027879) (xy 126.819905 -385.013051)
			(xy 126.867297 -385.005543) (xy 126.891288 -385.005072) (xy 126.915224 -385.005508) (xy 126.96251 -385.012972)
			(xy 127.008053 -385.027718) (xy 127.05074 -385.049387) (xy 127.089525 -385.077447) (xy 127.12346 -385.111213)
			(xy 127.151714 -385.149858) (xy 127.163068 -385.170934) (xy 127.163576 -385.17195) (xy 127.243882 -385.310888)
			(xy 127.785876 -385.310888) (xy 127.785876 -385.31038) (xy 127.786344 -385.286389) (xy 127.793853 -385.238998)
			(xy 127.808682 -385.193365) (xy 127.830467 -385.150614) (xy 127.85867 -385.111796) (xy 127.892599 -385.077868)
			(xy 127.931417 -385.049664) (xy 127.974169 -385.02788) (xy 128.019802 -385.013052) (xy 128.067193 -385.005544)
			(xy 128.091184 -385.005072) (xy 128.11512 -385.005511) (xy 128.162406 -385.012974) (xy 128.207949 -385.02772)
			(xy 128.250636 -385.049388) (xy 128.289421 -385.077448) (xy 128.323356 -385.111214) (xy 128.35161 -385.149858)
			(xy 128.362964 -385.170934) (xy 128.363472 -385.17195) (xy 128.443778 -385.310888) (xy 128.985772 -385.310888)
			(xy 128.985772 -385.31038) (xy 128.986244 -385.286389) (xy 128.993753 -385.238999) (xy 129.008581 -385.193366)
			(xy 129.030366 -385.150615) (xy 129.058569 -385.111797) (xy 129.092497 -385.077869) (xy 129.131315 -385.049666)
			(xy 129.174066 -385.027881) (xy 129.219699 -385.013053) (xy 129.267089 -385.005544) (xy 129.29108 -385.005072)
			(xy 129.315016 -385.005515) (xy 129.362301 -385.012977) (xy 129.407845 -385.027722) (xy 129.450531 -385.04939)
			(xy 129.489317 -385.077449) (xy 129.523252 -385.111214) (xy 129.551506 -385.149858) (xy 129.56286 -385.170934)
			(xy 129.563368 -385.17195) (xy 129.643674 -385.310888) (xy 130.185668 -385.310888) (xy 130.185668 -385.31038)
			(xy 130.186143 -385.286402) (xy 130.193643 -385.239036) (xy 130.208457 -385.193426) (xy 130.230218 -385.150692)
			(xy 130.258394 -385.111886) (xy 130.292289 -385.077961) (xy 130.331072 -385.049753) (xy 130.373787 -385.027956)
			(xy 130.419385 -385.013104) (xy 130.466745 -385.005563) (xy 130.490722 -385.005072) (xy 130.49123 -385.005072)
			(xy 130.515164 -385.005555) (xy 130.562448 -385.01301) (xy 130.60799 -385.027748) (xy 130.650677 -385.049409)
			(xy 130.689463 -385.077462) (xy 130.723399 -385.111221) (xy 130.751655 -385.14986) (xy 130.76301 -385.170934)
			(xy 130.763518 -385.17195) (xy 130.843824 -385.310888) (xy 131.385564 -385.310888) (xy 131.385564 -385.31038)
			(xy 131.386043 -385.286402) (xy 131.393543 -385.239037) (xy 131.408356 -385.193427) (xy 131.430118 -385.150693)
			(xy 131.458292 -385.111887) (xy 131.492187 -385.077963) (xy 131.530969 -385.049755) (xy 131.573684 -385.027957)
			(xy 131.619282 -385.013105) (xy 131.666641 -385.005564) (xy 131.690618 -385.005072) (xy 131.691126 -385.005072)
			(xy 131.71506 -385.005558) (xy 131.762344 -385.013013) (xy 131.807886 -385.02775) (xy 131.850573 -385.04941)
			(xy 131.889359 -385.077463) (xy 131.923295 -385.111222) (xy 131.951551 -385.14986) (xy 131.962906 -385.170934)
			(xy 131.963414 -385.17195) (xy 132.04372 -385.310888) (xy 132.585968 -385.310888) (xy 132.585968 -385.31038)
			(xy 132.586444 -385.286389) (xy 132.593952 -385.238999) (xy 132.608781 -385.193367) (xy 132.630565 -385.150616)
			(xy 132.658768 -385.111799) (xy 132.692696 -385.077871) (xy 132.731513 -385.049667) (xy 132.774263 -385.027883)
			(xy 132.819895 -385.013053) (xy 132.867285 -385.005544) (xy 132.891276 -385.005072) (xy 132.915211 -385.005518)
			(xy 132.962497 -385.01298) (xy 133.00804 -385.027724) (xy 133.050727 -385.049391) (xy 133.089512 -385.07745)
			(xy 133.123447 -385.111215) (xy 133.151701 -385.149858) (xy 133.163056 -385.170934) (xy 133.163564 -385.17195)
			(xy 133.24387 -385.310888) (xy 147.113752 -385.310888) (xy 147.113752 -385.31038) (xy 147.114244 -385.28639)
			(xy 147.121752 -385.239002) (xy 147.13658 -385.193371) (xy 147.158362 -385.150621) (xy 147.186563 -385.111804)
			(xy 147.220489 -385.077876) (xy 147.259304 -385.049673) (xy 147.302052 -385.027887) (xy 147.347682 -385.013057)
			(xy 147.39507 -385.005546) (xy 147.41906 -385.005072) (xy 147.442995 -385.005531) (xy 147.49028 -385.01299)
			(xy 147.535823 -385.027733) (xy 147.57851 -385.049398) (xy 147.617295 -385.077455) (xy 147.651231 -385.111217)
			(xy 147.679485 -385.149859) (xy 147.69084 -385.170934) (xy 147.691348 -385.17195) (xy 147.771654 -385.310888)
			(xy 148.313648 -385.310888) (xy 148.313648 -385.31038) (xy 148.314144 -385.28639) (xy 148.321652 -385.239002)
			(xy 148.336479 -385.193372) (xy 148.358261 -385.150622) (xy 148.386462 -385.111805) (xy 148.420387 -385.077878)
			(xy 148.459201 -385.049674) (xy 148.501949 -385.027888) (xy 148.547579 -385.013057) (xy 148.594966 -385.005546)
			(xy 148.618956 -385.005072) (xy 148.642891 -385.005534) (xy 148.690176 -385.012993) (xy 148.735719 -385.027735)
			(xy 148.778405 -385.049399) (xy 148.817191 -385.077456) (xy 148.851126 -385.111218) (xy 148.879381 -385.149859)
			(xy 148.890736 -385.170934) (xy 148.891244 -385.17195) (xy 148.97155 -385.310888) (xy 149.513544 -385.310888)
			(xy 149.513544 -385.31038) (xy 149.514044 -385.286391) (xy 149.521552 -385.239003) (xy 149.536379 -385.193373)
			(xy 149.558161 -385.150623) (xy 149.586361 -385.111807) (xy 149.620286 -385.077879) (xy 149.659099 -385.049675)
			(xy 149.701847 -385.02789) (xy 149.747476 -385.013058) (xy 149.794863 -385.005546) (xy 149.818852 -385.005072)
			(xy 149.842787 -385.005537) (xy 149.890071 -385.012995) (xy 149.935614 -385.027737) (xy 149.978301 -385.049401)
			(xy 150.017087 -385.077457) (xy 150.051022 -385.111218) (xy 150.079277 -385.149859) (xy 150.090632 -385.170934)
			(xy 150.09114 -385.17195) (xy 150.171446 -385.310888) (xy 150.71344 -385.310888) (xy 150.71344 -385.31038)
			(xy 150.713843 -385.286399) (xy 150.721346 -385.239026) (xy 150.736164 -385.193409) (xy 150.757932 -385.15067)
			(xy 150.786115 -385.111861) (xy 150.820019 -385.077936) (xy 150.858812 -385.049729) (xy 150.901537 -385.027935)
			(xy 150.947145 -385.013089) (xy 150.994513 -385.005558) (xy 151.018494 -385.005072) (xy 151.019002 -385.005072)
			(xy 151.042935 -385.005578) (xy 151.090218 -385.013028) (xy 151.13576 -385.027763) (xy 151.178447 -385.04942)
			(xy 151.217233 -385.077469) (xy 151.25117 -385.111225) (xy 151.279426 -385.149861) (xy 151.290782 -385.170934)
			(xy 151.29129 -385.17195) (xy 151.371596 -385.310888) (xy 151.913336 -385.310888) (xy 151.913336 -385.31038)
			(xy 151.913743 -385.286399) (xy 151.921246 -385.239027) (xy 151.936063 -385.19341) (xy 151.957831 -385.150672)
			(xy 151.986013 -385.111862) (xy 152.019918 -385.077937) (xy 152.058709 -385.04973) (xy 152.101434 -385.027936)
			(xy 152.147041 -385.01309) (xy 152.194409 -385.005558) (xy 152.21839 -385.005072) (xy 152.218898 -385.005072)
			(xy 152.242834 -385.0055) (xy 152.290121 -385.012965) (xy 152.335664 -385.027713) (xy 152.378351 -385.049383)
			(xy 152.417136 -385.077445) (xy 152.45107 -385.111212) (xy 152.479324 -385.149857) (xy 152.490678 -385.170934)
			(xy 152.491186 -385.17195) (xy 152.571492 -385.310888) (xy 153.11374 -385.310888) (xy 153.11374 -385.31038)
			(xy 153.11412 -385.286384) (xy 153.121631 -385.238983) (xy 153.136465 -385.193341) (xy 153.158257 -385.150582)
			(xy 153.18647 -385.111758) (xy 153.22041 -385.077826) (xy 153.25924 -385.049622) (xy 153.302004 -385.027839)
			(xy 153.347649 -385.013015) (xy 153.395052 -385.005515) (xy 153.419048 -385.005072) (xy 153.442983 -385.005541)
			(xy 153.490267 -385.012998) (xy 153.53581 -385.027739) (xy 153.578497 -385.049402) (xy 153.617282 -385.077458)
			(xy 153.651218 -385.111219) (xy 153.679473 -385.149859) (xy 153.690828 -385.170934) (xy 153.691336 -385.17195)
			(xy 153.771642 -385.310888) (xy 154.313636 -385.310888) (xy 154.313636 -385.31038) (xy 154.31402 -385.286384)
			(xy 154.321531 -385.238984) (xy 154.336365 -385.193342) (xy 154.358157 -385.150583) (xy 154.386369 -385.111759)
			(xy 154.420308 -385.077828) (xy 154.459138 -385.049623) (xy 154.501901 -385.02784) (xy 154.547546 -385.013016)
			(xy 154.594948 -385.005515) (xy 154.618944 -385.005072) (xy 154.642878 -385.005544) (xy 154.690163 -385.013001)
			(xy 154.735706 -385.027741) (xy 154.778392 -385.049404) (xy 154.817178 -385.077459) (xy 154.851114 -385.111219)
			(xy 154.879369 -385.14986) (xy 154.890724 -385.170934) (xy 154.891232 -385.17195) (xy 154.971538 -385.310888)
			(xy 155.513532 -385.310888) (xy 155.513532 -385.31038) (xy 155.51392 -385.286384) (xy 155.521431 -385.238984)
			(xy 155.536265 -385.193343) (xy 155.558056 -385.150584) (xy 155.586268 -385.111761) (xy 155.620206 -385.077829)
			(xy 155.659035 -385.049624) (xy 155.701798 -385.027842) (xy 155.747443 -385.013017) (xy 155.794844 -385.005515)
			(xy 155.81884 -385.005072) (xy 155.842774 -385.005547) (xy 155.890059 -385.013003) (xy 155.935601 -385.027743)
			(xy 155.978288 -385.049405) (xy 156.017074 -385.07746) (xy 156.05101 -385.11122) (xy 156.079265 -385.14986)
			(xy 156.09062 -385.170934) (xy 156.091128 -385.17195) (xy 156.171434 -385.310888) (xy 156.713428 -385.310888)
			(xy 156.713428 -385.31038) (xy 156.713843 -385.286399) (xy 156.721346 -385.239028) (xy 156.736162 -385.193412)
			(xy 156.757929 -385.150674) (xy 156.786111 -385.111865) (xy 156.820014 -385.07794) (xy 156.858805 -385.049733)
			(xy 156.901529 -385.027938) (xy 156.947135 -385.013092) (xy 156.994501 -385.005559) (xy 157.018482 -385.005072)
			(xy 157.01899 -385.005072) (xy 157.042926 -385.005506) (xy 157.090212 -385.01297) (xy 157.135756 -385.027717)
			(xy 157.178442 -385.049386) (xy 157.217227 -385.077447) (xy 157.251162 -385.111213) (xy 157.279416 -385.149857)
			(xy 157.29077 -385.170934) (xy 157.291278 -385.17195) (xy 157.371584 -385.310888) (xy 157.913324 -385.310888)
			(xy 157.913324 -385.31038) (xy 157.913743 -385.286399) (xy 157.921245 -385.239028) (xy 157.936062 -385.193413)
			(xy 157.957829 -385.150675) (xy 157.98601 -385.111866) (xy 158.019913 -385.077941) (xy 158.058703 -385.049734)
			(xy 158.101426 -385.02794) (xy 158.147032 -385.013093) (xy 158.194398 -385.005559) (xy 158.218378 -385.005072)
			(xy 158.218886 -385.005072) (xy 158.242822 -385.00551) (xy 158.290108 -385.012973) (xy 158.335651 -385.027719)
			(xy 158.378338 -385.049388) (xy 158.417123 -385.077448) (xy 158.451058 -385.111213) (xy 158.479312 -385.149858)
			(xy 158.490666 -385.170934) (xy 158.491174 -385.17195) (xy 158.57148 -385.310888) (xy 159.113728 -385.310888)
			(xy 159.113728 -385.31038) (xy 159.11412 -385.286385) (xy 159.121631 -385.238985) (xy 159.136464 -385.193344)
			(xy 159.158255 -385.150585) (xy 159.186467 -385.111762) (xy 159.220405 -385.07783) (xy 159.259233 -385.049626)
			(xy 159.301996 -385.027843) (xy 159.347639 -385.013018) (xy 159.39504 -385.005515) (xy 159.419036 -385.005072)
			(xy 159.44297 -385.00555) (xy 159.490254 -385.013006) (xy 159.535797 -385.027745) (xy 159.578484 -385.049407)
			(xy 159.617269 -385.077461) (xy 159.651205 -385.11122) (xy 159.679461 -385.14986) (xy 159.690816 -385.170934)
			(xy 159.691324 -385.17195) (xy 159.77163 -385.310888) (xy 160.313624 -385.310888) (xy 160.313624 -385.31038)
			(xy 160.31402 -385.286385) (xy 160.321531 -385.238985) (xy 160.336364 -385.193345) (xy 160.358154 -385.150586)
			(xy 160.386366 -385.111764) (xy 160.420303 -385.077832) (xy 160.459131 -385.049627) (xy 160.501893 -385.027844)
			(xy 160.547536 -385.013018) (xy 160.594937 -385.005516) (xy 160.618932 -385.005072) (xy 160.642866 -385.005554)
			(xy 160.69015 -385.013009) (xy 160.735693 -385.027747) (xy 160.778379 -385.049408) (xy 160.817165 -385.077462)
			(xy 160.851101 -385.111221) (xy 160.879357 -385.14986) (xy 160.890712 -385.170934) (xy 160.89122 -385.17195)
			(xy 160.971526 -385.310888) (xy 161.51352 -385.310888) (xy 161.51352 -385.31038) (xy 161.51392 -385.286385)
			(xy 161.52143 -385.238986) (xy 161.536263 -385.193346) (xy 161.558054 -385.150588) (xy 161.586265 -385.111765)
			(xy 161.620201 -385.077833) (xy 161.659029 -385.049629) (xy 161.70179 -385.027845) (xy 161.747433 -385.013019)
			(xy 161.794833 -385.005516) (xy 161.818828 -385.005072) (xy 161.842762 -385.005557) (xy 161.890046 -385.013011)
			(xy 161.935588 -385.027749) (xy 161.978275 -385.04941) (xy 162.017061 -385.077463) (xy 162.050997 -385.111222)
			(xy 162.079253 -385.14986) (xy 162.090608 -385.170934) (xy 162.091116 -385.17195) (xy 162.171422 -385.310888)
			(xy 162.713416 -385.310888) (xy 162.713416 -385.31038) (xy 162.713843 -385.2864) (xy 162.721345 -385.239029)
			(xy 162.736161 -385.193415) (xy 162.757927 -385.150678) (xy 162.786108 -385.111869) (xy 162.820009 -385.077944)
			(xy 162.858798 -385.049737) (xy 162.90152 -385.027942) (xy 162.947125 -385.013094) (xy 162.99449 -385.00556)
			(xy 163.01847 -385.005072) (xy 163.018978 -385.005072) (xy 163.042913 -385.005516) (xy 163.090199 -385.012978)
			(xy 163.135743 -385.027723) (xy 163.178429 -385.049391) (xy 163.217215 -385.07745) (xy 163.251149 -385.111214)
			(xy 163.279404 -385.149858) (xy 163.290758 -385.170934) (xy 163.291266 -385.17195) (xy 163.371572 -385.310888)
			(xy 163.913312 -385.310888) (xy 163.913312 -385.31038) (xy 163.913743 -385.2864) (xy 163.921245 -385.23903)
			(xy 163.936061 -385.193416) (xy 163.957827 -385.150679) (xy 163.986006 -385.111871) (xy 164.019908 -385.077946)
			(xy 164.058696 -385.049739) (xy 164.101418 -385.027943) (xy 164.147022 -385.013095) (xy 164.194386 -385.00556)
			(xy 164.218366 -385.005072) (xy 164.218874 -385.005072) (xy 164.242809 -385.005519) (xy 164.290095 -385.012981)
			(xy 164.335638 -385.027726) (xy 164.378325 -385.049392) (xy 164.41711 -385.077451) (xy 164.451045 -385.111215)
			(xy 164.479299 -385.149858) (xy 164.490654 -385.170934) (xy 164.491162 -385.17195) (xy 164.571468 -385.310888)
			(xy 165.113716 -385.310888) (xy 165.113716 -385.31038) (xy 165.11412 -385.286385) (xy 165.12163 -385.238987)
			(xy 165.136463 -385.193347) (xy 165.158253 -385.150589) (xy 165.186463 -385.111766) (xy 165.2204 -385.077835)
			(xy 165.259226 -385.04963) (xy 165.301987 -385.027846) (xy 165.347629 -385.01302) (xy 165.395029 -385.005516)
			(xy 165.419024 -385.005072) (xy 165.442958 -385.00556) (xy 165.490242 -385.013014) (xy 165.535784 -385.027751)
			(xy 165.578471 -385.049411) (xy 165.617257 -385.077464) (xy 165.651193 -385.111222) (xy 165.679449 -385.14986)
			(xy 165.690804 -385.170934) (xy 165.691312 -385.17195) (xy 166.083742 -385.850892) (xy 166.096567 -385.874224)
			(xy 166.114787 -385.924247) (xy 166.124047 -385.976673) (xy 166.124636 -386.003292) (xy 166.124131 -386.027269)
			(xy 166.116635 -386.074633) (xy 166.101826 -386.120243) (xy 166.080068 -386.162977) (xy 166.051896 -386.201783)
			(xy 166.018004 -386.235708) (xy 165.979224 -386.263916) (xy 165.936511 -386.285715) (xy 165.890916 -386.300567)
			(xy 165.843558 -386.308108) (xy 165.819582 -386.3086) (xy 165.819074 -386.3086) (xy 165.795499 -386.308227)
			(xy 165.74891 -386.300982) (xy 165.703991 -386.286652) (xy 165.661813 -386.26558) (xy 165.62338 -386.238267)
			(xy 165.589609 -386.205365) (xy 165.561304 -386.167657) (xy 165.549834 -386.147056) (xy 165.549326 -386.146294)
			(xy 165.151562 -385.457954) (xy 165.139704 -385.435268) (xy 165.122846 -385.38694) (xy 165.114266 -385.33648)
			(xy 165.113716 -385.310888) (xy 164.571468 -385.310888) (xy 164.883592 -385.850892) (xy 164.896324 -385.87421)
			(xy 164.914419 -385.924158) (xy 164.923635 -385.976477) (xy 164.924232 -386.003038) (xy 164.924232 -386.003292)
			(xy 164.92373 -386.027282) (xy 164.916226 -386.074671) (xy 164.901401 -386.120303) (xy 164.879621 -386.163054)
			(xy 164.851421 -386.201871) (xy 164.817496 -386.2358) (xy 164.778681 -386.264004) (xy 164.735932 -386.285789)
			(xy 164.690302 -386.300618) (xy 164.642914 -386.308128) (xy 164.618924 -386.3086) (xy 164.595351 -386.308187)
			(xy 164.548763 -386.300949) (xy 164.503845 -386.286627) (xy 164.461667 -386.265561) (xy 164.423233 -386.238255)
			(xy 164.389461 -386.205358) (xy 164.361155 -386.167655) (xy 164.349684 -386.147056) (xy 164.349176 -386.146294)
			(xy 163.951412 -385.457954) (xy 163.939479 -385.435295) (xy 163.922547 -385.386965) (xy 163.913895 -385.336491)
			(xy 163.913312 -385.310888) (xy 163.371572 -385.310888) (xy 163.683696 -385.850892) (xy 163.696428 -385.87421)
			(xy 163.714523 -385.924158) (xy 163.723739 -385.976477) (xy 163.724336 -386.003038) (xy 163.724336 -386.003292)
			(xy 163.72383 -386.027282) (xy 163.716326 -386.07467) (xy 163.701501 -386.120302) (xy 163.679721 -386.163053)
			(xy 163.651522 -386.20187) (xy 163.617597 -386.235798) (xy 163.578783 -386.264002) (xy 163.536035 -386.285788)
			(xy 163.490405 -386.300618) (xy 163.443018 -386.308127) (xy 163.419028 -386.3086) (xy 163.395455 -386.308184)
			(xy 163.348868 -386.300946) (xy 163.30395 -386.286625) (xy 163.261771 -386.26556) (xy 163.223338 -386.238254)
			(xy 163.189565 -386.205357) (xy 163.161259 -386.167654) (xy 163.149788 -386.147056) (xy 163.14928 -386.146294)
			(xy 162.751516 -385.457954) (xy 162.739583 -385.435294) (xy 162.722652 -385.386965) (xy 162.713999 -385.336491)
			(xy 162.713416 -385.310888) (xy 162.171422 -385.310888) (xy 162.483546 -385.850892) (xy 162.496371 -385.874224)
			(xy 162.514591 -385.924247) (xy 162.523851 -385.976673) (xy 162.52444 -386.003292) (xy 162.523931 -386.027269)
			(xy 162.516435 -386.074633) (xy 162.501626 -386.120242) (xy 162.479869 -386.162976) (xy 162.451698 -386.201782)
			(xy 162.417806 -386.235706) (xy 162.379027 -386.263915) (xy 162.336314 -386.285714) (xy 162.290719 -386.300566)
			(xy 162.243362 -386.308108) (xy 162.219386 -386.3086) (xy 162.218878 -386.3086) (xy 162.195303 -386.308224)
			(xy 162.148714 -386.300979) (xy 162.103795 -386.28665) (xy 162.061617 -386.265579) (xy 162.023184 -386.238266)
			(xy 161.989413 -386.205364) (xy 161.961108 -386.167657) (xy 161.949638 -386.147056) (xy 161.94913 -386.146294)
			(xy 161.551366 -385.457954) (xy 161.539508 -385.435268) (xy 161.52265 -385.38694) (xy 161.51407 -385.33648)
			(xy 161.51352 -385.310888) (xy 160.971526 -385.310888) (xy 161.28365 -385.850892) (xy 161.296476 -385.874224)
			(xy 161.314695 -385.924247) (xy 161.323955 -385.976673) (xy 161.324544 -386.003292) (xy 161.324031 -386.027269)
			(xy 161.316535 -386.074632) (xy 161.301727 -386.120241) (xy 161.279969 -386.162974) (xy 161.251799 -386.20178)
			(xy 161.217907 -386.235705) (xy 161.179129 -386.263913) (xy 161.136417 -386.285712) (xy 161.090822 -386.300566)
			(xy 161.043466 -386.308108) (xy 161.01949 -386.3086) (xy 161.018982 -386.3086) (xy 160.995407 -386.308221)
			(xy 160.948819 -386.300977) (xy 160.9039 -386.286648) (xy 160.861721 -386.265577) (xy 160.823288 -386.238265)
			(xy 160.789517 -386.205364) (xy 160.761212 -386.167657) (xy 160.749742 -386.147056) (xy 160.749234 -386.146294)
			(xy 160.35147 -385.457954) (xy 160.339612 -385.435268) (xy 160.322755 -385.386939) (xy 160.314174 -385.33648)
			(xy 160.313624 -385.310888) (xy 159.77163 -385.310888) (xy 160.083754 -385.850892) (xy 160.09658 -385.874224)
			(xy 160.114799 -385.924247) (xy 160.124059 -385.976673) (xy 160.124648 -386.003292) (xy 160.124131 -386.027268)
			(xy 160.116636 -386.074632) (xy 160.101827 -386.12024) (xy 160.08007 -386.162973) (xy 160.0519 -386.201779)
			(xy 160.018009 -386.235703) (xy 159.979231 -386.263912) (xy 159.93652 -386.285711) (xy 159.890926 -386.300565)
			(xy 159.84357 -386.308107) (xy 159.819594 -386.3086) (xy 159.819086 -386.3086) (xy 159.795512 -386.308217)
			(xy 159.748923 -386.300974) (xy 159.704004 -386.286646) (xy 159.661826 -386.265576) (xy 159.623393 -386.238264)
			(xy 159.589621 -386.205363) (xy 159.561316 -386.167656) (xy 159.549846 -386.147056) (xy 159.549338 -386.146294)
			(xy 159.151574 -385.457954) (xy 159.139717 -385.435268) (xy 159.122859 -385.386939) (xy 159.114278 -385.336479)
			(xy 159.113728 -385.310888) (xy 158.57148 -385.310888) (xy 158.883604 -385.850892) (xy 158.896337 -385.87421)
			(xy 158.914431 -385.924158) (xy 158.923647 -385.976477) (xy 158.924244 -386.003038) (xy 158.924244 -386.003292)
			(xy 158.92373 -386.027281) (xy 158.916226 -386.074669) (xy 158.901402 -386.1203) (xy 158.879623 -386.16305)
			(xy 158.851424 -386.201867) (xy 158.817501 -386.235796) (xy 158.778688 -386.264) (xy 158.735941 -386.285785)
			(xy 158.690312 -386.300616) (xy 158.642925 -386.308127) (xy 158.618936 -386.3086) (xy 158.595363 -386.308177)
			(xy 158.548776 -386.300941) (xy 158.503858 -386.286621) (xy 158.46168 -386.265557) (xy 158.423246 -386.238252)
			(xy 158.389474 -386.205356) (xy 158.361167 -386.167654) (xy 158.349696 -386.147056) (xy 158.349188 -386.146294)
			(xy 157.951424 -385.457954) (xy 157.939492 -385.435294) (xy 157.92256 -385.386965) (xy 157.913907 -385.336491)
			(xy 157.913324 -385.310888) (xy 157.371584 -385.310888) (xy 157.683708 -385.850892) (xy 157.696441 -385.87421)
			(xy 157.714535 -385.924158) (xy 157.723751 -385.976477) (xy 157.724348 -386.003038) (xy 157.724348 -386.003292)
			(xy 157.72383 -386.027281) (xy 157.716326 -386.074669) (xy 157.701503 -386.120299) (xy 157.679724 -386.163049)
			(xy 157.651525 -386.201866) (xy 157.617603 -386.235794) (xy 157.57879 -386.263998) (xy 157.536043 -386.285784)
			(xy 157.490415 -386.300615) (xy 157.443029 -386.308126) (xy 157.41904 -386.3086) (xy 157.395467 -386.308174)
			(xy 157.34888 -386.300939) (xy 157.303963 -386.286618) (xy 157.261784 -386.265555) (xy 157.223351 -386.238251)
			(xy 157.189578 -386.205355) (xy 157.161271 -386.167654) (xy 157.1498 -386.147056) (xy 157.149292 -386.146294)
			(xy 156.751528 -385.457954) (xy 156.739596 -385.435294) (xy 156.722664 -385.386965) (xy 156.714011 -385.336491)
			(xy 156.713428 -385.310888) (xy 156.171434 -385.310888) (xy 156.483558 -385.850892) (xy 156.496384 -385.874224)
			(xy 156.514604 -385.924247) (xy 156.523863 -385.976673) (xy 156.524452 -386.003292) (xy 156.523931 -386.027268)
			(xy 156.516436 -386.074631) (xy 156.501627 -386.120239) (xy 156.479871 -386.162972) (xy 156.451701 -386.201778)
			(xy 156.417811 -386.235702) (xy 156.379033 -386.263911) (xy 156.336323 -386.28571) (xy 156.290729 -386.300564)
			(xy 156.243374 -386.308107) (xy 156.219398 -386.3086) (xy 156.21889 -386.3086) (xy 156.195316 -386.308214)
			(xy 156.148727 -386.300971) (xy 156.103808 -386.286644) (xy 156.06163 -386.265574) (xy 156.023197 -386.238263)
			(xy 155.989426 -386.205363) (xy 155.96112 -386.167656) (xy 155.94965 -386.147056) (xy 155.949142 -386.146294)
			(xy 155.551378 -385.457954) (xy 155.539521 -385.435268) (xy 155.522663 -385.386939) (xy 155.514082 -385.336479)
			(xy 155.513532 -385.310888) (xy 154.971538 -385.310888) (xy 155.283662 -385.850892) (xy 155.296489 -385.874224)
			(xy 155.314708 -385.924247) (xy 155.323967 -385.976673) (xy 155.324556 -386.003292) (xy 155.324031 -386.027268)
			(xy 155.316536 -386.07463) (xy 155.301728 -386.120239) (xy 155.279972 -386.162971) (xy 155.251802 -386.201776)
			(xy 155.217912 -386.235701) (xy 155.179135 -386.263909) (xy 155.136425 -386.285709) (xy 155.090832 -386.300563)
			(xy 155.043477 -386.308107) (xy 155.019502 -386.3086) (xy 155.018994 -386.3086) (xy 154.99542 -386.308211)
			(xy 154.948831 -386.300969) (xy 154.903913 -386.286642) (xy 154.861734 -386.265573) (xy 154.823301 -386.238262)
			(xy 154.78953 -386.205362) (xy 154.761224 -386.167656) (xy 154.749754 -386.147056) (xy 154.749246 -386.146294)
			(xy 154.351482 -385.457954) (xy 154.339625 -385.435268) (xy 154.322767 -385.386939) (xy 154.314186 -385.336479)
			(xy 154.313636 -385.310888) (xy 153.771642 -385.310888) (xy 154.083766 -385.850892) (xy 154.096593 -385.874223)
			(xy 154.114812 -385.924247) (xy 154.124071 -385.976673) (xy 154.12466 -386.003292) (xy 154.124231 -386.027273)
			(xy 154.116732 -386.074644) (xy 154.101919 -386.120261) (xy 154.080154 -386.162999) (xy 154.051974 -386.201809)
			(xy 154.018072 -386.235735) (xy 153.979282 -386.263942) (xy 153.936559 -386.285737) (xy 153.890953 -386.300582)
			(xy 153.843586 -386.308114) (xy 153.819606 -386.3086) (xy 153.819098 -386.3086) (xy 153.795524 -386.308208)
			(xy 153.748936 -386.300966) (xy 153.704017 -386.28664) (xy 153.661839 -386.265571) (xy 153.623406 -386.238261)
			(xy 153.589634 -386.205361) (xy 153.561328 -386.167656) (xy 153.549858 -386.147056) (xy 153.54935 -386.146294)
			(xy 153.151586 -385.457954) (xy 153.13973 -385.435267) (xy 153.122871 -385.386939) (xy 153.11429 -385.336479)
			(xy 153.11374 -385.310888) (xy 152.571492 -385.310888) (xy 152.883616 -385.850892) (xy 152.89635 -385.874209)
			(xy 152.914443 -385.924158) (xy 152.923659 -385.976477) (xy 152.924256 -386.003038) (xy 152.924256 -386.003292)
			(xy 152.92373 -386.027281) (xy 152.916227 -386.074667) (xy 152.901403 -386.120297) (xy 152.879625 -386.163047)
			(xy 152.851428 -386.201863) (xy 152.817506 -386.235791) (xy 152.778694 -386.263996) (xy 152.735949 -386.285782)
			(xy 152.690322 -386.300614) (xy 152.642937 -386.308126) (xy 152.618948 -386.3086) (xy 152.595375 -386.308168)
			(xy 152.548789 -386.300933) (xy 152.503871 -386.286614) (xy 152.461693 -386.265552) (xy 152.423259 -386.238248)
			(xy 152.389486 -386.205354) (xy 152.361179 -386.167654) (xy 152.349708 -386.147056) (xy 152.3492 -386.146294)
			(xy 151.951436 -385.457954) (xy 151.939505 -385.435294) (xy 151.922572 -385.386964) (xy 151.913919 -385.336491)
			(xy 151.913336 -385.310888) (xy 151.371596 -385.310888) (xy 151.68372 -385.850892) (xy 151.696454 -385.874209)
			(xy 151.714548 -385.924158) (xy 151.723763 -385.976476) (xy 151.72436 -386.003038) (xy 151.72436 -386.003292)
			(xy 151.723954 -386.027287) (xy 151.716447 -386.074687) (xy 151.701617 -386.120329) (xy 151.679828 -386.163088)
			(xy 151.651618 -386.201912) (xy 151.617682 -386.235844) (xy 151.578854 -386.264049) (xy 151.536092 -386.285832)
			(xy 151.490448 -386.300657) (xy 151.443047 -386.308157) (xy 151.419052 -386.3086) (xy 151.395479 -386.308164)
			(xy 151.348893 -386.300931) (xy 151.303976 -386.286612) (xy 151.261797 -386.265551) (xy 151.223364 -386.238247)
			(xy 151.189591 -386.205354) (xy 151.161283 -386.167653) (xy 151.149812 -386.147056) (xy 151.149304 -386.146294)
			(xy 150.75154 -385.457954) (xy 150.739609 -385.435293) (xy 150.722676 -385.386964) (xy 150.714023 -385.336491)
			(xy 150.71344 -385.310888) (xy 150.171446 -385.310888) (xy 150.48357 -385.850892) (xy 150.496397 -385.874223)
			(xy 150.514616 -385.924247) (xy 150.523875 -385.976673) (xy 150.524464 -386.003292) (xy 150.524031 -386.027273)
			(xy 150.516533 -386.074644) (xy 150.501719 -386.12026) (xy 150.479955 -386.162998) (xy 150.451775 -386.201808)
			(xy 150.417874 -386.235733) (xy 150.379084 -386.263941) (xy 150.336361 -386.285735) (xy 150.290756 -386.300581)
			(xy 150.24339 -386.308114) (xy 150.21941 -386.3086) (xy 150.218902 -386.3086) (xy 150.195328 -386.308205)
			(xy 150.14874 -386.300963) (xy 150.103821 -386.286638) (xy 150.061643 -386.26557) (xy 150.02321 -386.23826)
			(xy 149.989438 -386.205361) (xy 149.961133 -386.167656) (xy 149.949662 -386.147056) (xy 149.949154 -386.146294)
			(xy 149.55139 -385.457954) (xy 149.539534 -385.435267) (xy 149.522675 -385.386939) (xy 149.514094 -385.336479)
			(xy 149.513544 -385.310888) (xy 148.97155 -385.310888) (xy 149.283674 -385.850892) (xy 149.296501 -385.874223)
			(xy 149.31472 -385.924247) (xy 149.323979 -385.976673) (xy 149.324568 -386.003292) (xy 149.324131 -386.027272)
			(xy 149.316633 -386.074643) (xy 149.301819 -386.120259) (xy 149.280055 -386.162997) (xy 149.251876 -386.201806)
			(xy 149.217975 -386.235732) (xy 149.179187 -386.263939) (xy 149.136464 -386.285734) (xy 149.090859 -386.300581)
			(xy 149.043494 -386.308113) (xy 149.019514 -386.3086) (xy 149.019006 -386.3086) (xy 148.995432 -386.308201)
			(xy 148.948844 -386.300961) (xy 148.903926 -386.286636) (xy 148.861747 -386.265568) (xy 148.823314 -386.238259)
			(xy 148.789542 -386.20536) (xy 148.761237 -386.167655) (xy 148.749766 -386.147056) (xy 148.749258 -386.146294)
			(xy 148.351494 -385.457954) (xy 148.339638 -385.435267) (xy 148.322779 -385.386939) (xy 148.314198 -385.336479)
			(xy 148.313648 -385.310888) (xy 147.771654 -385.310888) (xy 148.083778 -385.850892) (xy 148.096606 -385.874223)
			(xy 148.114824 -385.924247) (xy 148.124083 -385.976673) (xy 148.124672 -386.003292) (xy 148.124231 -386.027272)
			(xy 148.116733 -386.074643) (xy 148.10192 -386.120258) (xy 148.080156 -386.162996) (xy 148.051978 -386.201805)
			(xy 148.018077 -386.235731) (xy 147.979289 -386.263938) (xy 147.936567 -386.285733) (xy 147.890963 -386.30058)
			(xy 147.843598 -386.308113) (xy 147.819618 -386.3086) (xy 147.81911 -386.3086) (xy 147.795536 -386.308198)
			(xy 147.748948 -386.300958) (xy 147.70403 -386.286634) (xy 147.661852 -386.265566) (xy 147.623418 -386.238258)
			(xy 147.589647 -386.20536) (xy 147.561341 -386.167655) (xy 147.54987 -386.147056) (xy 147.549362 -386.146294)
			(xy 147.151598 -385.457954) (xy 147.139742 -385.435267) (xy 147.122883 -385.386939) (xy 147.114302 -385.336479)
			(xy 147.113752 -385.310888) (xy 133.24387 -385.310888) (xy 133.555994 -385.850892) (xy 133.568823 -385.874222)
			(xy 133.587041 -385.924246) (xy 133.596299 -385.976673) (xy 133.596888 -386.003292) (xy 133.596431 -386.027271)
			(xy 133.588933 -386.07464) (xy 133.574121 -386.120254) (xy 133.552359 -386.162991) (xy 133.524182 -386.2018)
			(xy 133.490284 -386.235725) (xy 133.451498 -386.263932) (xy 133.408778 -386.285728) (xy 133.363176 -386.300577)
			(xy 133.315813 -386.308112) (xy 133.291834 -386.3086) (xy 133.291326 -386.3086) (xy 133.267753 -386.308185)
			(xy 133.221165 -386.300948) (xy 133.176247 -386.286626) (xy 133.134069 -386.26556) (xy 133.095636 -386.238254)
			(xy 133.061863 -386.205357) (xy 133.033557 -386.167655) (xy 133.022086 -386.147056) (xy 133.021578 -386.146294)
			(xy 132.623814 -385.457954) (xy 132.611952 -385.43527) (xy 132.595097 -385.38694) (xy 132.586517 -385.33648)
			(xy 132.585968 -385.310888) (xy 132.04372 -385.310888) (xy 132.355844 -385.850892) (xy 132.36858 -385.874208)
			(xy 132.386672 -385.924157) (xy 132.395888 -385.976476) (xy 132.396484 -386.003038) (xy 132.396484 -386.003292)
			(xy 132.396054 -386.027286) (xy 132.388548 -386.074684) (xy 132.373719 -386.120323) (xy 132.351933 -386.163081)
			(xy 132.323725 -386.201904) (xy 132.289792 -386.235836) (xy 132.250967 -386.264041) (xy 132.208208 -386.285825)
			(xy 132.162568 -386.300652) (xy 132.11517 -386.308156) (xy 132.091176 -386.3086) (xy 132.067601 -386.308226)
			(xy 132.021012 -386.30098) (xy 131.976093 -386.286651) (xy 131.933915 -386.265579) (xy 131.895482 -386.238267)
			(xy 131.861711 -386.205365) (xy 131.833406 -386.167657) (xy 131.821936 -386.147056) (xy 131.821428 -386.146294)
			(xy 131.423664 -385.457954) (xy 131.411735 -385.435292) (xy 131.394801 -385.386964) (xy 131.386148 -385.336491)
			(xy 131.385564 -385.310888) (xy 130.843824 -385.310888) (xy 131.155948 -385.850892) (xy 131.168685 -385.874208)
			(xy 131.186776 -385.924157) (xy 131.195992 -385.976476) (xy 131.196588 -386.003038) (xy 131.196588 -386.003292)
			(xy 131.196154 -386.027286) (xy 131.188648 -386.074683) (xy 131.17382 -386.120322) (xy 131.152033 -386.16308)
			(xy 131.123826 -386.201902) (xy 131.089893 -386.235834) (xy 131.05107 -386.26404) (xy 131.008311 -386.285824)
			(xy 130.962671 -386.300651) (xy 130.915274 -386.308155) (xy 130.89128 -386.3086) (xy 130.867705 -386.308222)
			(xy 130.821116 -386.300978) (xy 130.776197 -386.286649) (xy 130.734019 -386.265578) (xy 130.695586 -386.238266)
			(xy 130.661815 -386.205364) (xy 130.63351 -386.167657) (xy 130.62204 -386.147056) (xy 130.621532 -386.146294)
			(xy 130.223768 -385.457954) (xy 130.211839 -385.435292) (xy 130.194906 -385.386964) (xy 130.186252 -385.336491)
			(xy 130.185668 -385.310888) (xy 129.643674 -385.310888) (xy 129.955798 -385.850892) (xy 129.968619 -385.874226)
			(xy 129.986842 -385.924248) (xy 129.996103 -385.976674) (xy 129.996692 -386.003292) (xy 129.996231 -386.027271)
			(xy 129.988734 -386.07464) (xy 129.973922 -386.120253) (xy 129.95216 -386.16299) (xy 129.923983 -386.201798)
			(xy 129.890086 -386.235723) (xy 129.8513 -386.263931) (xy 129.808581 -386.285727) (xy 129.762979 -386.300576)
			(xy 129.715617 -386.308112) (xy 129.691638 -386.3086) (xy 129.69113 -386.3086) (xy 129.667557 -386.308182)
			(xy 129.62097 -386.300945) (xy 129.576052 -386.286624) (xy 129.533873 -386.265559) (xy 129.49544 -386.238253)
			(xy 129.461668 -386.205357) (xy 129.433361 -386.167654) (xy 129.42189 -386.147056) (xy 129.421382 -386.146294)
			(xy 129.023618 -385.457954) (xy 129.011756 -385.43527) (xy 128.994901 -385.38694) (xy 128.986321 -385.33648)
			(xy 128.985772 -385.310888) (xy 128.443778 -385.310888) (xy 128.755902 -385.850892) (xy 128.768724 -385.874226)
			(xy 128.786946 -385.924248) (xy 128.796207 -385.976674) (xy 128.796796 -386.003292) (xy 128.796331 -386.027271)
			(xy 128.788834 -386.074639) (xy 128.774022 -386.120252) (xy 128.752261 -386.162989) (xy 128.724085 -386.201797)
			(xy 128.690187 -386.235722) (xy 128.651402 -386.26393) (xy 128.608684 -386.285726) (xy 128.563083 -386.300575)
			(xy 128.515721 -386.308111) (xy 128.491742 -386.3086) (xy 128.491234 -386.3086) (xy 128.467661 -386.308179)
			(xy 128.421074 -386.300942) (xy 128.376156 -386.286622) (xy 128.333978 -386.265557) (xy 128.295544 -386.238252)
			(xy 128.261772 -386.205356) (xy 128.233465 -386.167654) (xy 128.221994 -386.147056) (xy 128.221486 -386.146294)
			(xy 127.823722 -385.457954) (xy 127.811861 -385.43527) (xy 127.795005 -385.38694) (xy 127.786426 -385.33648)
			(xy 127.785876 -385.310888) (xy 127.243882 -385.310888) (xy 127.556006 -385.850892) (xy 127.568828 -385.874226)
			(xy 127.58705 -385.924248) (xy 127.596311 -385.976674) (xy 127.5969 -386.003292) (xy 127.596431 -386.027271)
			(xy 127.588934 -386.074639) (xy 127.574122 -386.120251) (xy 127.552361 -386.162988) (xy 127.524186 -386.201795)
			(xy 127.490289 -386.235721) (xy 127.451504 -386.263928) (xy 127.408786 -386.285725) (xy 127.363186 -386.300574)
			(xy 127.315824 -386.308111) (xy 127.291846 -386.3086) (xy 127.291338 -386.3086) (xy 127.267765 -386.308176)
			(xy 127.221178 -386.30094) (xy 127.17626 -386.28662) (xy 127.134082 -386.265556) (xy 127.095648 -386.238251)
			(xy 127.061876 -386.205356) (xy 127.033569 -386.167654) (xy 127.022098 -386.147056) (xy 127.02159 -386.146294)
			(xy 126.623826 -385.457954) (xy 126.611965 -385.43527) (xy 126.595109 -385.38694) (xy 126.58653 -385.33648)
			(xy 126.58598 -385.310888) (xy 126.043732 -385.310888) (xy 126.355856 -385.850892) (xy 126.368593 -385.874208)
			(xy 126.386685 -385.924157) (xy 126.3959 -385.976476) (xy 126.396496 -386.003038) (xy 126.396496 -386.003292)
			(xy 126.396054 -386.027286) (xy 126.388548 -386.074682) (xy 126.37372 -386.12032) (xy 126.351935 -386.163077)
			(xy 126.323729 -386.2019) (xy 126.289797 -386.235831) (xy 126.250974 -386.264037) (xy 126.208217 -386.285822)
			(xy 126.162578 -386.300649) (xy 126.115182 -386.308155) (xy 126.091188 -386.3086) (xy 126.067614 -386.308216)
			(xy 126.021025 -386.300973) (xy 125.976106 -386.286645) (xy 125.933928 -386.265575) (xy 125.895495 -386.238264)
			(xy 125.861723 -386.205363) (xy 125.833418 -386.167656) (xy 125.821948 -386.147056) (xy 125.82144 -386.146294)
			(xy 125.423676 -385.457954) (xy 125.41174 -385.435296) (xy 125.39481 -385.386965) (xy 125.386159 -385.336492)
			(xy 125.385576 -385.310888) (xy 124.843836 -385.310888) (xy 125.15596 -385.850892) (xy 125.168698 -385.874207)
			(xy 125.186789 -385.924157) (xy 125.196004 -385.976476) (xy 125.1966 -386.003038) (xy 125.1966 -386.003292)
			(xy 125.196154 -386.027285) (xy 125.188649 -386.074681) (xy 125.173821 -386.12032) (xy 125.152036 -386.163076)
			(xy 125.12383 -386.201898) (xy 125.089898 -386.23583) (xy 125.051076 -386.264036) (xy 125.00832 -386.285821)
			(xy 124.962681 -386.300649) (xy 124.915285 -386.308154) (xy 124.891292 -386.3086) (xy 124.867718 -386.308213)
			(xy 124.821129 -386.30097) (xy 124.77621 -386.286643) (xy 124.734032 -386.265573) (xy 124.695599 -386.238263)
			(xy 124.661828 -386.205362) (xy 124.633522 -386.167656) (xy 124.622052 -386.147056) (xy 124.621544 -386.146294)
			(xy 124.22378 -385.457954) (xy 124.211844 -385.435296) (xy 124.194915 -385.386965) (xy 124.186263 -385.336492)
			(xy 124.18568 -385.310888) (xy 123.643686 -385.310888) (xy 123.95581 -385.850892) (xy 123.968632 -385.874226)
			(xy 123.986854 -385.924248) (xy 123.996115 -385.976673) (xy 123.996704 -386.003292) (xy 123.996231 -386.027271)
			(xy 123.988734 -386.074638) (xy 123.973923 -386.120251) (xy 123.952162 -386.162986) (xy 123.923987 -386.201794)
			(xy 123.890091 -386.235719) (xy 123.851307 -386.263927) (xy 123.808589 -386.285724) (xy 123.762989 -386.300574)
			(xy 123.715628 -386.308111) (xy 123.69165 -386.3086) (xy 123.691142 -386.3086) (xy 123.667569 -386.308172)
			(xy 123.620983 -386.300937) (xy 123.576065 -386.286617) (xy 123.533886 -386.265554) (xy 123.495453 -386.23825)
			(xy 123.46168 -386.205355) (xy 123.433373 -386.167654) (xy 123.421902 -386.147056) (xy 123.421394 -386.146294)
			(xy 123.02363 -385.457954) (xy 123.011769 -385.43527) (xy 122.994913 -385.38694) (xy 122.986334 -385.33648)
			(xy 122.985784 -385.310888) (xy 122.44379 -385.310888) (xy 122.755914 -385.850892) (xy 122.768737 -385.874226)
			(xy 122.786958 -385.924248) (xy 122.796219 -385.976673) (xy 122.796808 -386.003292) (xy 122.796331 -386.02727)
			(xy 122.788834 -386.074637) (xy 122.774023 -386.12025) (xy 122.752263 -386.162985) (xy 122.724088 -386.201793)
			(xy 122.690192 -386.235718) (xy 122.651409 -386.263926) (xy 122.608692 -386.285723) (xy 122.563092 -386.300573)
			(xy 122.515732 -386.30811) (xy 122.491754 -386.3086) (xy 122.491246 -386.3086) (xy 122.467673 -386.308169)
			(xy 122.421087 -386.300935) (xy 122.376169 -386.286615) (xy 122.333991 -386.265553) (xy 122.295557 -386.238249)
			(xy 122.261784 -386.205355) (xy 122.233477 -386.167654) (xy 122.222006 -386.147056) (xy 122.221498 -386.146294)
			(xy 121.823734 -385.457954) (xy 121.811874 -385.43527) (xy 121.795018 -385.38694) (xy 121.786438 -385.33648)
			(xy 121.785888 -385.310888) (xy 121.243894 -385.310888) (xy 121.556018 -385.850892) (xy 121.568841 -385.874226)
			(xy 121.587062 -385.924248) (xy 121.596323 -385.976673) (xy 121.596912 -386.003292) (xy 121.596431 -386.02727)
			(xy 121.588934 -386.074637) (xy 121.574124 -386.120249) (xy 121.552364 -386.162984) (xy 121.524189 -386.201791)
			(xy 121.490294 -386.235716) (xy 121.451511 -386.263924) (xy 121.408795 -386.285722) (xy 121.363196 -386.300572)
			(xy 121.315836 -386.30811) (xy 121.291858 -386.3086) (xy 121.29135 -386.3086) (xy 121.267777 -386.308166)
			(xy 121.221191 -386.300932) (xy 121.176273 -386.286613) (xy 121.134095 -386.265551) (xy 121.095661 -386.238248)
			(xy 121.061888 -386.205354) (xy 121.033581 -386.167653) (xy 121.02211 -386.147056) (xy 121.021602 -386.146294)
			(xy 120.623838 -385.457954) (xy 120.611978 -385.435269) (xy 120.595122 -385.38694) (xy 120.586542 -385.33648)
			(xy 120.585992 -385.310888) (xy 120.043744 -385.310888) (xy 120.355868 -385.850892) (xy 120.368606 -385.874207)
			(xy 120.386697 -385.924157) (xy 120.395912 -385.976476) (xy 120.396508 -386.003038) (xy 120.396508 -386.003292)
			(xy 120.396054 -386.027285) (xy 120.388549 -386.07468) (xy 120.373721 -386.120318) (xy 120.351937 -386.163074)
			(xy 120.323732 -386.201896) (xy 120.289802 -386.235827) (xy 120.250981 -386.264033) (xy 120.208225 -386.285818)
			(xy 120.162588 -386.300647) (xy 120.115193 -386.308154) (xy 120.0912 -386.3086) (xy 120.067626 -386.308206)
			(xy 120.021038 -386.300965) (xy 119.976119 -386.286639) (xy 119.933941 -386.26557) (xy 119.895508 -386.238261)
			(xy 119.861736 -386.205361) (xy 119.83343 -386.167656) (xy 119.82196 -386.147056) (xy 119.821452 -386.146294)
			(xy 119.423688 -385.457954) (xy 119.411753 -385.435296) (xy 119.394823 -385.386965) (xy 119.386171 -385.336491)
			(xy 119.385588 -385.310888) (xy 118.843848 -385.310888) (xy 119.155972 -385.850892) (xy 119.168711 -385.874207)
			(xy 119.186801 -385.924157) (xy 119.196016 -385.976476) (xy 119.196612 -386.003038) (xy 119.196612 -386.003292)
			(xy 119.196154 -386.027285) (xy 119.188649 -386.07468) (xy 119.173822 -386.120317) (xy 119.152038 -386.163073)
			(xy 119.123834 -386.201894) (xy 119.089903 -386.235826) (xy 119.051083 -386.264032) (xy 119.008328 -386.285817)
			(xy 118.962691 -386.300646) (xy 118.915297 -386.308154) (xy 118.891304 -386.3086) (xy 118.86773 -386.308203)
			(xy 118.821142 -386.300962) (xy 118.776223 -386.286637) (xy 118.734045 -386.265569) (xy 118.695612 -386.23826)
			(xy 118.66184 -386.205361) (xy 118.633535 -386.167656) (xy 118.622064 -386.147056) (xy 118.621556 -386.146294)
			(xy 118.223792 -385.457954) (xy 118.211857 -385.435295) (xy 118.194927 -385.386965) (xy 118.186275 -385.336491)
			(xy 118.185692 -385.310888) (xy 117.643698 -385.310888) (xy 117.955822 -385.850892) (xy 117.968645 -385.874225)
			(xy 117.986866 -385.924248) (xy 117.996127 -385.976673) (xy 117.996716 -386.003292) (xy 117.996231 -386.02727)
			(xy 117.988734 -386.074636) (xy 117.973924 -386.120248) (xy 117.952164 -386.162983) (xy 117.92399 -386.20179)
			(xy 117.890096 -386.235715) (xy 117.851313 -386.263923) (xy 117.808598 -386.28572) (xy 117.762999 -386.300571)
			(xy 117.71564 -386.30811) (xy 117.691662 -386.3086) (xy 117.691154 -386.3086) (xy 117.667582 -386.308163)
			(xy 117.620995 -386.300929) (xy 117.576078 -386.286611) (xy 117.533899 -386.26555) (xy 117.495466 -386.238247)
			(xy 117.461693 -386.205353) (xy 117.433385 -386.167653) (xy 117.421914 -386.147056) (xy 117.421406 -386.146294)
			(xy 117.023642 -385.457954) (xy 117.011782 -385.435269) (xy 116.994926 -385.38694) (xy 116.986346 -385.33648)
			(xy 116.985796 -385.310888) (xy 116.443802 -385.310888) (xy 116.755926 -385.850892) (xy 116.76875 -385.874225)
			(xy 116.786971 -385.924247) (xy 116.796231 -385.976673) (xy 116.79682 -386.003292) (xy 116.796331 -386.02727)
			(xy 116.788835 -386.074636) (xy 116.774024 -386.120247) (xy 116.752265 -386.162982) (xy 116.724092 -386.201789)
			(xy 116.690197 -386.235713) (xy 116.651416 -386.263922) (xy 116.6087 -386.285719) (xy 116.563102 -386.30057)
			(xy 116.515743 -386.30811) (xy 116.491766 -386.3086) (xy 116.491258 -386.3086) (xy 116.467686 -386.308159)
			(xy 116.4211 -386.300927) (xy 116.376182 -386.286609) (xy 116.334004 -386.265548) (xy 116.29557 -386.238246)
			(xy 116.261797 -386.205353) (xy 116.23349 -386.167653) (xy 116.222018 -386.147056) (xy 116.22151 -386.146294)
			(xy 115.823746 -385.457954) (xy 115.811886 -385.435269) (xy 115.79503 -385.38694) (xy 115.78645 -385.33648)
			(xy 115.7859 -385.310888) (xy 115.243906 -385.310888) (xy 115.55603 -385.850892) (xy 115.568854 -385.874225)
			(xy 115.587075 -385.924247) (xy 115.596335 -385.976673) (xy 115.596924 -386.003292) (xy 115.596431 -386.02727)
			(xy 115.588935 -386.074635) (xy 115.574125 -386.120246) (xy 115.552366 -386.16298) (xy 115.524193 -386.201787)
			(xy 115.490299 -386.235712) (xy 115.451518 -386.26392) (xy 115.408803 -386.285718) (xy 115.363206 -386.30057)
			(xy 115.315847 -386.308109) (xy 115.29187 -386.3086) (xy 115.291362 -386.3086) (xy 115.26779 -386.308156)
			(xy 115.221204 -386.300924) (xy 115.176286 -386.286607) (xy 115.134108 -386.265547) (xy 115.095674 -386.238245)
			(xy 115.061901 -386.205352) (xy 115.033594 -386.167653) (xy 115.022122 -386.147056) (xy 115.021614 -386.146294)
			(xy 114.62385 -385.457954) (xy 114.611991 -385.435269) (xy 114.595134 -385.38694) (xy 114.586554 -385.33648)
			(xy 114.586004 -385.310888) (xy 98.671676 -385.310888) (xy 98.9838 -385.850892) (xy 98.996533 -385.87421)
			(xy 99.014627 -385.924158) (xy 99.023843 -385.976477) (xy 99.02444 -386.003038) (xy 99.02444 -386.003292)
			(xy 99.02393 -386.027281) (xy 99.016426 -386.07467) (xy 99.001602 -386.120301) (xy 98.979822 -386.163051)
			(xy 98.951623 -386.201869) (xy 98.917699 -386.235797) (xy 98.878886 -386.264001) (xy 98.836138 -386.285787)
			(xy 98.790509 -386.300617) (xy 98.743121 -386.308127) (xy 98.719132 -386.3086) (xy 98.695559 -386.30818)
			(xy 98.648972 -386.300944) (xy 98.604054 -386.286623) (xy 98.561875 -386.265558) (xy 98.523442 -386.238253)
			(xy 98.48967 -386.205357) (xy 98.461363 -386.167654) (xy 98.449892 -386.147056) (xy 98.449384 -386.146294)
			(xy 98.05162 -385.457954) (xy 98.039687 -385.435294) (xy 98.022756 -385.386965) (xy 98.014103 -385.336491)
			(xy 98.01352 -385.310888) (xy 97.471526 -385.310888) (xy 97.78365 -385.850892) (xy 97.796476 -385.874224)
			(xy 97.814695 -385.924247) (xy 97.823955 -385.976673) (xy 97.824544 -386.003292) (xy 97.824031 -386.027269)
			(xy 97.816535 -386.074632) (xy 97.801727 -386.120241) (xy 97.779969 -386.162974) (xy 97.751799 -386.20178)
			(xy 97.717907 -386.235705) (xy 97.679129 -386.263913) (xy 97.636417 -386.285712) (xy 97.590822 -386.300566)
			(xy 97.543466 -386.308108) (xy 97.51949 -386.3086) (xy 97.518982 -386.3086) (xy 97.495407 -386.308221)
			(xy 97.448819 -386.300977) (xy 97.4039 -386.286648) (xy 97.361721 -386.265577) (xy 97.323288 -386.238265)
			(xy 97.289517 -386.205364) (xy 97.261212 -386.167657) (xy 97.249742 -386.147056) (xy 97.249234 -386.146294)
			(xy 96.85147 -385.457954) (xy 96.839612 -385.435268) (xy 96.822755 -385.386939) (xy 96.814174 -385.33648)
			(xy 96.813624 -385.310888) (xy 96.27163 -385.310888) (xy 96.583754 -385.850892) (xy 96.59658 -385.874224)
			(xy 96.614799 -385.924247) (xy 96.624059 -385.976673) (xy 96.624648 -386.003292) (xy 96.624131 -386.027268)
			(xy 96.616636 -386.074632) (xy 96.601827 -386.12024) (xy 96.58007 -386.162973) (xy 96.5519 -386.201779)
			(xy 96.518009 -386.235703) (xy 96.479231 -386.263912) (xy 96.43652 -386.285711) (xy 96.390926 -386.300565)
			(xy 96.34357 -386.308107) (xy 96.319594 -386.3086) (xy 96.319086 -386.3086) (xy 96.295512 -386.308217)
			(xy 96.248923 -386.300974) (xy 96.204004 -386.286646) (xy 96.161826 -386.265576) (xy 96.123393 -386.238264)
			(xy 96.089621 -386.205363) (xy 96.061316 -386.167656) (xy 96.049846 -386.147056) (xy 96.049338 -386.146294)
			(xy 95.651574 -385.457954) (xy 95.639717 -385.435268) (xy 95.622859 -385.386939) (xy 95.614278 -385.336479)
			(xy 95.613728 -385.310888) (xy 95.07148 -385.310888) (xy 95.383604 -385.850892) (xy 95.396337 -385.87421)
			(xy 95.414431 -385.924158) (xy 95.423647 -385.976477) (xy 95.424244 -386.003038) (xy 95.424244 -386.003292)
			(xy 95.42373 -386.027281) (xy 95.416226 -386.074669) (xy 95.401402 -386.1203) (xy 95.379623 -386.16305)
			(xy 95.351424 -386.201867) (xy 95.317501 -386.235796) (xy 95.278688 -386.264) (xy 95.235941 -386.285785)
			(xy 95.190312 -386.300616) (xy 95.142925 -386.308127) (xy 95.118936 -386.3086) (xy 95.095363 -386.308177)
			(xy 95.048776 -386.300941) (xy 95.003858 -386.286621) (xy 94.96168 -386.265557) (xy 94.923246 -386.238252)
			(xy 94.889474 -386.205356) (xy 94.861167 -386.167654) (xy 94.849696 -386.147056) (xy 94.849188 -386.146294)
			(xy 94.451424 -385.457954) (xy 94.439492 -385.435294) (xy 94.42256 -385.386965) (xy 94.413907 -385.336491)
			(xy 94.413324 -385.310888) (xy 93.871584 -385.310888) (xy 94.183708 -385.850892) (xy 94.196441 -385.87421)
			(xy 94.214535 -385.924158) (xy 94.223751 -385.976477) (xy 94.224348 -386.003038) (xy 94.224348 -386.003292)
			(xy 94.22383 -386.027281) (xy 94.216326 -386.074669) (xy 94.201503 -386.120299) (xy 94.179724 -386.163049)
			(xy 94.151525 -386.201866) (xy 94.117603 -386.235794) (xy 94.07879 -386.263998) (xy 94.036043 -386.285784)
			(xy 93.990415 -386.300615) (xy 93.943029 -386.308126) (xy 93.91904 -386.3086) (xy 93.895467 -386.308174)
			(xy 93.84888 -386.300939) (xy 93.803963 -386.286618) (xy 93.761784 -386.265555) (xy 93.723351 -386.238251)
			(xy 93.689578 -386.205355) (xy 93.661271 -386.167654) (xy 93.6498 -386.147056) (xy 93.649292 -386.146294)
			(xy 93.251528 -385.457954) (xy 93.239596 -385.435294) (xy 93.222664 -385.386965) (xy 93.214011 -385.336491)
			(xy 93.213428 -385.310888) (xy 92.671688 -385.310888) (xy 92.983812 -385.850892) (xy 92.996546 -385.87421)
			(xy 93.014639 -385.924158) (xy 93.023855 -385.976477) (xy 93.024452 -386.003038) (xy 93.024452 -386.003292)
			(xy 93.02393 -386.027281) (xy 93.016427 -386.074668) (xy 93.001603 -386.120298) (xy 92.979824 -386.163048)
			(xy 92.951627 -386.201865) (xy 92.917704 -386.235793) (xy 92.878892 -386.263997) (xy 92.836146 -386.285783)
			(xy 92.790519 -386.300614) (xy 92.743133 -386.308126) (xy 92.719144 -386.3086) (xy 92.695571 -386.308171)
			(xy 92.648985 -386.300936) (xy 92.604067 -386.286616) (xy 92.561889 -386.265554) (xy 92.523455 -386.238249)
			(xy 92.489682 -386.205355) (xy 92.461375 -386.167654) (xy 92.449904 -386.147056) (xy 92.449396 -386.146294)
			(xy 92.051632 -385.457954) (xy 92.0397 -385.435294) (xy 92.022768 -385.386965) (xy 92.014115 -385.336491)
			(xy 92.013532 -385.310888) (xy 91.471538 -385.310888) (xy 91.783662 -385.850892) (xy 91.796489 -385.874224)
			(xy 91.814708 -385.924247) (xy 91.823967 -385.976673) (xy 91.824556 -386.003292) (xy 91.824031 -386.027268)
			(xy 91.816536 -386.07463) (xy 91.801728 -386.120239) (xy 91.779972 -386.162971) (xy 91.751802 -386.201776)
			(xy 91.717912 -386.235701) (xy 91.679135 -386.263909) (xy 91.636425 -386.285709) (xy 91.590832 -386.300563)
			(xy 91.543477 -386.308107) (xy 91.519502 -386.3086) (xy 91.518994 -386.3086) (xy 91.49542 -386.308211)
			(xy 91.448831 -386.300969) (xy 91.403913 -386.286642) (xy 91.361734 -386.265573) (xy 91.323301 -386.238262)
			(xy 91.28953 -386.205362) (xy 91.261224 -386.167656) (xy 91.249754 -386.147056) (xy 91.249246 -386.146294)
			(xy 90.851482 -385.457954) (xy 90.839625 -385.435268) (xy 90.822767 -385.386939) (xy 90.814186 -385.336479)
			(xy 90.813636 -385.310888) (xy 90.271642 -385.310888) (xy 90.583766 -385.850892) (xy 90.596593 -385.874223)
			(xy 90.614812 -385.924247) (xy 90.624071 -385.976673) (xy 90.62466 -386.003292) (xy 90.624231 -386.027273)
			(xy 90.616732 -386.074644) (xy 90.601919 -386.120261) (xy 90.580154 -386.162999) (xy 90.551974 -386.201809)
			(xy 90.518072 -386.235735) (xy 90.479282 -386.263942) (xy 90.436559 -386.285737) (xy 90.390953 -386.300582)
			(xy 90.343586 -386.308114) (xy 90.319606 -386.3086) (xy 90.319098 -386.3086) (xy 90.295524 -386.308208)
			(xy 90.248936 -386.300966) (xy 90.204017 -386.28664) (xy 90.161839 -386.265571) (xy 90.123406 -386.238261)
			(xy 90.089634 -386.205361) (xy 90.061328 -386.167656) (xy 90.049858 -386.147056) (xy 90.04935 -386.146294)
			(xy 89.651586 -385.457954) (xy 89.63973 -385.435267) (xy 89.622871 -385.386939) (xy 89.61429 -385.336479)
			(xy 89.61374 -385.310888) (xy 89.071492 -385.310888) (xy 89.383616 -385.850892) (xy 89.39635 -385.874209)
			(xy 89.414443 -385.924158) (xy 89.423659 -385.976477) (xy 89.424256 -386.003038) (xy 89.424256 -386.003292)
			(xy 89.42373 -386.027281) (xy 89.416227 -386.074667) (xy 89.401403 -386.120297) (xy 89.379625 -386.163047)
			(xy 89.351428 -386.201863) (xy 89.317506 -386.235791) (xy 89.278694 -386.263996) (xy 89.235949 -386.285782)
			(xy 89.190322 -386.300614) (xy 89.142937 -386.308126) (xy 89.118948 -386.3086) (xy 89.095375 -386.308168)
			(xy 89.048789 -386.300933) (xy 89.003871 -386.286614) (xy 88.961693 -386.265552) (xy 88.923259 -386.238248)
			(xy 88.889486 -386.205354) (xy 88.861179 -386.167654) (xy 88.849708 -386.147056) (xy 88.8492 -386.146294)
			(xy 88.451436 -385.457954) (xy 88.439505 -385.435294) (xy 88.422572 -385.386964) (xy 88.413919 -385.336491)
			(xy 88.413336 -385.310888) (xy 87.871596 -385.310888) (xy 88.18372 -385.850892) (xy 88.196454 -385.874209)
			(xy 88.214548 -385.924158) (xy 88.223763 -385.976476) (xy 88.22436 -386.003038) (xy 88.22436 -386.003292)
			(xy 88.223954 -386.027287) (xy 88.216447 -386.074687) (xy 88.201617 -386.120329) (xy 88.179828 -386.163088)
			(xy 88.151618 -386.201912) (xy 88.117682 -386.235844) (xy 88.078854 -386.264049) (xy 88.036092 -386.285832)
			(xy 87.990448 -386.300657) (xy 87.943047 -386.308157) (xy 87.919052 -386.3086) (xy 87.895479 -386.308164)
			(xy 87.848893 -386.300931) (xy 87.803976 -386.286612) (xy 87.761797 -386.265551) (xy 87.723364 -386.238247)
			(xy 87.689591 -386.205354) (xy 87.661283 -386.167653) (xy 87.649812 -386.147056) (xy 87.649304 -386.146294)
			(xy 87.25154 -385.457954) (xy 87.239609 -385.435293) (xy 87.222676 -385.386964) (xy 87.214023 -385.336491)
			(xy 87.21344 -385.310888) (xy 86.6717 -385.310888) (xy 86.983824 -385.850892) (xy 86.996559 -385.874209)
			(xy 87.014652 -385.924158) (xy 87.023867 -385.976476) (xy 87.024464 -386.003038) (xy 87.024464 -386.003292)
			(xy 87.024054 -386.027287) (xy 87.016547 -386.074687) (xy 87.001717 -386.120328) (xy 86.979929 -386.163087)
			(xy 86.951719 -386.201911) (xy 86.917783 -386.235843) (xy 86.878956 -386.264048) (xy 86.836195 -386.285831)
			(xy 86.790552 -386.300656) (xy 86.743151 -386.308157) (xy 86.719156 -386.3086) (xy 86.695584 -386.308161)
			(xy 86.648997 -386.300928) (xy 86.60408 -386.28661) (xy 86.561902 -386.265549) (xy 86.523468 -386.238246)
			(xy 86.489695 -386.205353) (xy 86.461387 -386.167653) (xy 86.449916 -386.147056) (xy 86.449408 -386.146294)
			(xy 86.051644 -385.457954) (xy 86.039713 -385.435293) (xy 86.02278 -385.386964) (xy 86.014127 -385.336491)
			(xy 86.013544 -385.310888) (xy 85.47155 -385.310888) (xy 85.783674 -385.850892) (xy 85.796501 -385.874223)
			(xy 85.81472 -385.924247) (xy 85.823979 -385.976673) (xy 85.824568 -386.003292) (xy 85.824131 -386.027272)
			(xy 85.816633 -386.074643) (xy 85.801819 -386.120259) (xy 85.780055 -386.162997) (xy 85.751876 -386.201806)
			(xy 85.717975 -386.235732) (xy 85.679187 -386.263939) (xy 85.636464 -386.285734) (xy 85.590859 -386.300581)
			(xy 85.543494 -386.308113) (xy 85.519514 -386.3086) (xy 85.519006 -386.3086) (xy 85.495432 -386.308201)
			(xy 85.448844 -386.300961) (xy 85.403926 -386.286636) (xy 85.361747 -386.265568) (xy 85.323314 -386.238259)
			(xy 85.289542 -386.20536) (xy 85.261237 -386.167655) (xy 85.249766 -386.147056) (xy 85.249258 -386.146294)
			(xy 84.851494 -385.457954) (xy 84.839638 -385.435267) (xy 84.822779 -385.386939) (xy 84.814198 -385.336479)
			(xy 84.813648 -385.310888) (xy 84.271654 -385.310888) (xy 84.583778 -385.850892) (xy 84.596606 -385.874223)
			(xy 84.614824 -385.924247) (xy 84.624083 -385.976673) (xy 84.624672 -386.003292) (xy 84.624231 -386.027272)
			(xy 84.616733 -386.074643) (xy 84.60192 -386.120258) (xy 84.580156 -386.162996) (xy 84.551978 -386.201805)
			(xy 84.518077 -386.235731) (xy 84.479289 -386.263938) (xy 84.436567 -386.285733) (xy 84.390963 -386.30058)
			(xy 84.343598 -386.308113) (xy 84.319618 -386.3086) (xy 84.31911 -386.3086) (xy 84.295536 -386.308198)
			(xy 84.248948 -386.300958) (xy 84.20403 -386.286634) (xy 84.161852 -386.265566) (xy 84.123418 -386.238258)
			(xy 84.089647 -386.20536) (xy 84.061341 -386.167655) (xy 84.04987 -386.147056) (xy 84.049362 -386.146294)
			(xy 83.651598 -385.457954) (xy 83.639742 -385.435267) (xy 83.622883 -385.386939) (xy 83.614302 -385.336479)
			(xy 83.613752 -385.310888) (xy 83.071504 -385.310888) (xy 83.383628 -385.850892) (xy 83.396363 -385.874209)
			(xy 83.414456 -385.924157) (xy 83.423671 -385.976476) (xy 83.424268 -386.003038) (xy 83.424268 -386.003292)
			(xy 83.423854 -386.027287) (xy 83.416348 -386.074686) (xy 83.401518 -386.120327) (xy 83.37973 -386.163086)
			(xy 83.351521 -386.201909) (xy 83.317585 -386.235841) (xy 83.278758 -386.264047) (xy 83.235997 -386.28583)
			(xy 83.190355 -386.300655) (xy 83.142955 -386.308157) (xy 83.11896 -386.3086) (xy 83.095388 -386.308158)
			(xy 83.048802 -386.300925) (xy 83.003884 -386.286608) (xy 82.961706 -386.265548) (xy 82.923272 -386.238245)
			(xy 82.889499 -386.205353) (xy 82.861192 -386.167653) (xy 82.84972 -386.147056) (xy 82.849212 -386.146294)
			(xy 82.451448 -385.457954) (xy 82.439517 -385.435293) (xy 82.422585 -385.386964) (xy 82.413931 -385.336491)
			(xy 82.413348 -385.310888) (xy 81.871608 -385.310888) (xy 82.183732 -385.850892) (xy 82.196467 -385.874209)
			(xy 82.21456 -385.924157) (xy 82.223775 -385.976476) (xy 82.224372 -386.003038) (xy 82.224372 -386.003292)
			(xy 82.223954 -386.027287) (xy 82.216448 -386.074685) (xy 82.201618 -386.120326) (xy 82.179831 -386.163085)
			(xy 82.151622 -386.201908) (xy 82.117687 -386.23584) (xy 82.078861 -386.264045) (xy 82.0361 -386.285829)
			(xy 81.990458 -386.300654) (xy 81.943059 -386.308156) (xy 81.919064 -386.3086) (xy 81.895492 -386.308155)
			(xy 81.848906 -386.300923) (xy 81.803989 -386.286606) (xy 81.76181 -386.265546) (xy 81.723376 -386.238244)
			(xy 81.689603 -386.205352) (xy 81.661296 -386.167653) (xy 81.649824 -386.147056) (xy 81.649316 -386.146294)
			(xy 81.251552 -385.457954) (xy 81.239622 -385.435293) (xy 81.222689 -385.386964) (xy 81.214035 -385.336491)
			(xy 81.213452 -385.310888) (xy 80.671712 -385.310888) (xy 80.983836 -385.850892) (xy 80.996572 -385.874209)
			(xy 81.014664 -385.924157) (xy 81.023879 -385.976476) (xy 81.024476 -386.003038) (xy 81.024476 -386.003292)
			(xy 81.024054 -386.027287) (xy 81.016548 -386.074685) (xy 81.001718 -386.120325) (xy 80.979931 -386.163083)
			(xy 80.951723 -386.201907) (xy 80.917788 -386.235839) (xy 80.878963 -386.264044) (xy 80.836203 -386.285828)
			(xy 80.790561 -386.300653) (xy 80.743163 -386.308156) (xy 80.719168 -386.3086) (xy 80.695596 -386.308151)
			(xy 80.64901 -386.30092) (xy 80.604093 -386.286604) (xy 80.561915 -386.265545) (xy 80.523481 -386.238243)
			(xy 80.489707 -386.205351) (xy 80.4614 -386.167653) (xy 80.449928 -386.147056) (xy 80.44942 -386.146294)
			(xy 80.051656 -385.457954) (xy 80.039726 -385.435293) (xy 80.022793 -385.386964) (xy 80.014139 -385.336491)
			(xy 80.013556 -385.310888) (xy 66.143928 -385.310888) (xy 66.456052 -385.850892) (xy 66.468789 -385.874208)
			(xy 66.486881 -385.924157) (xy 66.496096 -385.976476) (xy 66.496692 -386.003038) (xy 66.496692 -386.003292)
			(xy 66.496254 -386.027286) (xy 66.488748 -386.074682) (xy 66.47392 -386.120321) (xy 66.452134 -386.163079)
			(xy 66.423928 -386.201901) (xy 66.389995 -386.235833) (xy 66.351172 -386.264038) (xy 66.308414 -386.285823)
			(xy 66.262775 -386.30065) (xy 66.215378 -386.308155) (xy 66.191384 -386.3086) (xy 66.16781 -386.308219)
			(xy 66.121221 -386.300975) (xy 66.076302 -386.286647) (xy 66.034123 -386.265576) (xy 65.995691 -386.238265)
			(xy 65.961919 -386.205363) (xy 65.933614 -386.167656) (xy 65.922144 -386.147056) (xy 65.921636 -386.146294)
			(xy 65.523872 -385.457954) (xy 65.511936 -385.435296) (xy 65.495006 -385.386965) (xy 65.486355 -385.336492)
			(xy 65.485772 -385.310888) (xy 64.944032 -385.310888) (xy 65.256156 -385.850892) (xy 65.268893 -385.874208)
			(xy 65.286985 -385.924157) (xy 65.2962 -385.976476) (xy 65.296796 -386.003038) (xy 65.296796 -386.003292)
			(xy 65.296354 -386.027286) (xy 65.288848 -386.074682) (xy 65.27402 -386.12032) (xy 65.252235 -386.163077)
			(xy 65.224029 -386.2019) (xy 65.190097 -386.235831) (xy 65.151274 -386.264037) (xy 65.108517 -386.285822)
			(xy 65.062878 -386.300649) (xy 65.015482 -386.308155) (xy 64.991488 -386.3086) (xy 64.991234 -386.3086)
			(xy 64.967661 -386.308179) (xy 64.921074 -386.300942) (xy 64.876156 -386.286622) (xy 64.833978 -386.265557)
			(xy 64.795544 -386.238252) (xy 64.761772 -386.205356) (xy 64.733465 -386.167654) (xy 64.721994 -386.147056)
			(xy 64.721486 -386.146294) (xy 64.323722 -385.457954) (xy 64.311861 -385.43527) (xy 64.295005 -385.38694)
			(xy 64.286426 -385.33648) (xy 64.285876 -385.310888) (xy 63.744136 -385.310888) (xy 64.05626 -385.850892)
			(xy 64.068998 -385.874207) (xy 64.087089 -385.924157) (xy 64.096304 -385.976476) (xy 64.0969 -386.003038)
			(xy 64.0969 -386.003292) (xy 64.096454 -386.027285) (xy 64.088949 -386.074681) (xy 64.074121 -386.12032)
			(xy 64.052336 -386.163076) (xy 64.02413 -386.201898) (xy 63.990198 -386.23583) (xy 63.951376 -386.264036)
			(xy 63.90862 -386.285821) (xy 63.862981 -386.300649) (xy 63.815585 -386.308154) (xy 63.791592 -386.3086)
			(xy 63.791338 -386.3086) (xy 63.767765 -386.308176) (xy 63.721178 -386.30094) (xy 63.67626 -386.28662)
			(xy 63.634082 -386.265556) (xy 63.595648 -386.238251) (xy 63.561876 -386.205356) (xy 63.533569 -386.167654)
			(xy 63.522098 -386.147056) (xy 63.52159 -386.146294) (xy 63.123826 -385.457954) (xy 63.111965 -385.43527)
			(xy 63.095109 -385.38694) (xy 63.08653 -385.33648) (xy 63.08598 -385.310888) (xy 62.543986 -385.310888)
			(xy 62.85611 -385.850892) (xy 62.868932 -385.874226) (xy 62.887154 -385.924248) (xy 62.896415 -385.976673)
			(xy 62.897004 -386.003292) (xy 62.896554 -386.027298) (xy 62.88904 -386.074718) (xy 62.874197 -386.120377)
			(xy 62.85239 -386.163151) (xy 62.824157 -386.201984) (xy 62.790194 -386.23592) (xy 62.751337 -386.264121)
			(xy 62.708546 -386.285893) (xy 62.662874 -386.300698) (xy 62.615448 -386.308173) (xy 62.591442 -386.3086)
			(xy 62.591188 -386.3086) (xy 62.567614 -386.308216) (xy 62.521025 -386.300973) (xy 62.476106 -386.286645)
			(xy 62.433928 -386.265575) (xy 62.395495 -386.238264) (xy 62.361723 -386.205363) (xy 62.333418 -386.167656)
			(xy 62.321948 -386.147056) (xy 62.32144 -386.146294) (xy 61.923676 -385.457954) (xy 61.91174 -385.435296)
			(xy 61.89481 -385.386965) (xy 61.886159 -385.336492) (xy 61.885576 -385.310888) (xy 61.34409 -385.310888)
			(xy 61.656214 -385.850892) (xy 61.669037 -385.874226) (xy 61.687258 -385.924248) (xy 61.696519 -385.976673)
			(xy 61.697108 -386.003292) (xy 61.696654 -386.027298) (xy 61.68914 -386.074717) (xy 61.674297 -386.120377)
			(xy 61.652491 -386.16315) (xy 61.624258 -386.201983) (xy 61.590295 -386.235918) (xy 61.55144 -386.264119)
			(xy 61.508649 -386.285891) (xy 61.462978 -386.300698) (xy 61.415552 -386.308173) (xy 61.391546 -386.3086)
			(xy 61.391292 -386.3086) (xy 61.367718 -386.308213) (xy 61.321129 -386.30097) (xy 61.27621 -386.286643)
			(xy 61.234032 -386.265573) (xy 61.195599 -386.238263) (xy 61.161828 -386.205362) (xy 61.133522 -386.167656)
			(xy 61.122052 -386.147056) (xy 61.121544 -386.146294) (xy 60.72378 -385.457954) (xy 60.711844 -385.435296)
			(xy 60.694915 -385.386965) (xy 60.686263 -385.336492) (xy 60.68568 -385.310888) (xy 60.14394 -385.310888)
			(xy 60.456064 -385.850892) (xy 60.468802 -385.874207) (xy 60.486893 -385.924157) (xy 60.496108 -385.976476)
			(xy 60.496704 -386.003038) (xy 60.496704 -386.003292) (xy 60.496254 -386.027285) (xy 60.488749 -386.074681)
			(xy 60.473921 -386.120319) (xy 60.452136 -386.163075) (xy 60.423931 -386.201897) (xy 60.39 -386.235829)
			(xy 60.351178 -386.264034) (xy 60.308422 -386.28582) (xy 60.262785 -386.300648) (xy 60.215389 -386.308154)
			(xy 60.191396 -386.3086) (xy 60.167822 -386.308209) (xy 60.121233 -386.300967) (xy 60.076315 -386.286641)
			(xy 60.034136 -386.265572) (xy 59.995703 -386.238262) (xy 59.961932 -386.205362) (xy 59.933626 -386.167656)
			(xy 59.922156 -386.147056) (xy 59.921648 -386.146294) (xy 59.523884 -385.457954) (xy 59.511948 -385.435296)
			(xy 59.495019 -385.386965) (xy 59.486367 -385.336492) (xy 59.485784 -385.310888) (xy 58.944044 -385.310888)
			(xy 59.256168 -385.850892) (xy 59.268906 -385.874207) (xy 59.286997 -385.924157) (xy 59.296212 -385.976476)
			(xy 59.296808 -386.003038) (xy 59.296808 -386.003292) (xy 59.296354 -386.027285) (xy 59.288849 -386.07468)
			(xy 59.274021 -386.120318) (xy 59.252237 -386.163074) (xy 59.224032 -386.201896) (xy 59.190102 -386.235827)
			(xy 59.151281 -386.264033) (xy 59.108525 -386.285818) (xy 59.062888 -386.300647) (xy 59.015493 -386.308154)
			(xy 58.9915 -386.3086) (xy 58.991246 -386.3086) (xy 58.967673 -386.308169) (xy 58.921087 -386.300935)
			(xy 58.876169 -386.286615) (xy 58.833991 -386.265553) (xy 58.795557 -386.238249) (xy 58.761784 -386.205355)
			(xy 58.733477 -386.167654) (xy 58.722006 -386.147056) (xy 58.721498 -386.146294) (xy 58.323734 -385.457954)
			(xy 58.311874 -385.43527) (xy 58.295018 -385.38694) (xy 58.286438 -385.33648) (xy 58.285888 -385.310888)
			(xy 57.744148 -385.310888) (xy 58.056272 -385.850892) (xy 58.069011 -385.874207) (xy 58.087101 -385.924157)
			(xy 58.096316 -385.976476) (xy 58.096912 -386.003038) (xy 58.096912 -386.003292) (xy 58.096454 -386.027285)
			(xy 58.088949 -386.07468) (xy 58.074122 -386.120317) (xy 58.052338 -386.163073) (xy 58.024134 -386.201894)
			(xy 57.990203 -386.235826) (xy 57.951383 -386.264032) (xy 57.908628 -386.285817) (xy 57.862991 -386.300646)
			(xy 57.815597 -386.308154) (xy 57.791604 -386.3086) (xy 57.79135 -386.3086) (xy 57.767777 -386.308166)
			(xy 57.721191 -386.300932) (xy 57.676273 -386.286613) (xy 57.634095 -386.265551) (xy 57.595661 -386.238248)
			(xy 57.561888 -386.205354) (xy 57.533581 -386.167653) (xy 57.52211 -386.147056) (xy 57.521602 -386.146294)
			(xy 57.123838 -385.457954) (xy 57.111978 -385.435269) (xy 57.095122 -385.38694) (xy 57.086542 -385.33648)
			(xy 57.085992 -385.310888) (xy 56.543744 -385.310888) (xy 56.855868 -385.850892) (xy 56.868606 -385.874207)
			(xy 56.886697 -385.924157) (xy 56.895912 -385.976476) (xy 56.896508 -386.003038) (xy 56.896508 -386.003292)
			(xy 56.896054 -386.027285) (xy 56.888549 -386.07468) (xy 56.873721 -386.120318) (xy 56.851937 -386.163074)
			(xy 56.823732 -386.201896) (xy 56.789802 -386.235827) (xy 56.750981 -386.264033) (xy 56.708225 -386.285818)
			(xy 56.662588 -386.300647) (xy 56.615193 -386.308154) (xy 56.5912 -386.3086) (xy 56.567626 -386.308206)
			(xy 56.521038 -386.300965) (xy 56.476119 -386.286639) (xy 56.433941 -386.26557) (xy 56.395508 -386.238261)
			(xy 56.361736 -386.205361) (xy 56.33343 -386.167656) (xy 56.32196 -386.147056) (xy 56.321452 -386.146294)
			(xy 55.923688 -385.457954) (xy 55.911753 -385.435296) (xy 55.894823 -385.386965) (xy 55.886171 -385.336491)
			(xy 55.885588 -385.310888) (xy 55.343848 -385.310888) (xy 55.655972 -385.850892) (xy 55.668711 -385.874207)
			(xy 55.686801 -385.924157) (xy 55.696016 -385.976476) (xy 55.696612 -386.003038) (xy 55.696612 -386.003292)
			(xy 55.696154 -386.027285) (xy 55.688649 -386.07468) (xy 55.673822 -386.120317) (xy 55.652038 -386.163073)
			(xy 55.623834 -386.201894) (xy 55.589903 -386.235826) (xy 55.551083 -386.264032) (xy 55.508328 -386.285817)
			(xy 55.462691 -386.300646) (xy 55.415297 -386.308154) (xy 55.391304 -386.3086) (xy 55.36773 -386.308203)
			(xy 55.321142 -386.300962) (xy 55.276223 -386.286637) (xy 55.234045 -386.265569) (xy 55.195612 -386.23826)
			(xy 55.16184 -386.205361) (xy 55.133535 -386.167656) (xy 55.122064 -386.147056) (xy 55.121556 -386.146294)
			(xy 54.723792 -385.457954) (xy 54.711857 -385.435295) (xy 54.694927 -385.386965) (xy 54.686275 -385.336491)
			(xy 54.685692 -385.310888) (xy 54.143952 -385.310888) (xy 54.456076 -385.850892) (xy 54.468815 -385.874207)
			(xy 54.486905 -385.924157) (xy 54.49612 -385.976476) (xy 54.496716 -386.003038) (xy 54.496716 -386.003292)
			(xy 54.49623 -386.027283) (xy 54.488725 -386.074673) (xy 54.4739 -386.120306) (xy 54.452118 -386.163059)
			(xy 54.423916 -386.201877) (xy 54.389989 -386.235806) (xy 54.351172 -386.264009) (xy 54.308421 -386.285793)
			(xy 54.262789 -386.300622) (xy 54.215399 -386.308129) (xy 54.191408 -386.3086) (xy 54.167834 -386.3082)
			(xy 54.121246 -386.30096) (xy 54.076328 -386.286635) (xy 54.034149 -386.265567) (xy 53.995716 -386.238259)
			(xy 53.961944 -386.20536) (xy 53.933639 -386.167655) (xy 53.922168 -386.147056) (xy 53.92166 -386.146294)
			(xy 53.523896 -385.457954) (xy 53.511961 -385.435295) (xy 53.495031 -385.386965) (xy 53.486379 -385.336491)
			(xy 53.485796 -385.310888) (xy 52.943802 -385.310888) (xy 53.255926 -385.850892) (xy 53.26875 -385.874225)
			(xy 53.286971 -385.924247) (xy 53.296231 -385.976673) (xy 53.29682 -386.003292) (xy 53.296331 -386.02727)
			(xy 53.288835 -386.074636) (xy 53.274024 -386.120247) (xy 53.252265 -386.162982) (xy 53.224092 -386.201789)
			(xy 53.190197 -386.235713) (xy 53.151416 -386.263922) (xy 53.1087 -386.285719) (xy 53.063102 -386.30057)
			(xy 53.015743 -386.30811) (xy 52.991766 -386.3086) (xy 52.991258 -386.3086) (xy 52.967686 -386.308159)
			(xy 52.9211 -386.300927) (xy 52.876182 -386.286609) (xy 52.834004 -386.265548) (xy 52.79557 -386.238246)
			(xy 52.761797 -386.205353) (xy 52.73349 -386.167653) (xy 52.722018 -386.147056) (xy 52.72151 -386.146294)
			(xy 52.323746 -385.457954) (xy 52.311886 -385.435269) (xy 52.29503 -385.38694) (xy 52.28645 -385.33648)
			(xy 52.2859 -385.310888) (xy 51.743906 -385.310888) (xy 52.05603 -385.850892) (xy 52.068854 -385.874225)
			(xy 52.087075 -385.924247) (xy 52.096335 -385.976673) (xy 52.096924 -386.003292) (xy 52.096431 -386.02727)
			(xy 52.088935 -386.074635) (xy 52.074125 -386.120246) (xy 52.052366 -386.16298) (xy 52.024193 -386.201787)
			(xy 51.990299 -386.235712) (xy 51.951518 -386.26392) (xy 51.908803 -386.285718) (xy 51.863206 -386.30057)
			(xy 51.815847 -386.308109) (xy 51.79187 -386.3086) (xy 51.791362 -386.3086) (xy 51.76779 -386.308156)
			(xy 51.721204 -386.300924) (xy 51.676286 -386.286607) (xy 51.634108 -386.265547) (xy 51.595674 -386.238245)
			(xy 51.561901 -386.205352) (xy 51.533594 -386.167653) (xy 51.522122 -386.147056) (xy 51.521614 -386.146294)
			(xy 51.12385 -385.457954) (xy 51.111991 -385.435269) (xy 51.095134 -385.38694) (xy 51.086554 -385.33648)
			(xy 51.086004 -385.310888) (xy 50.543756 -385.310888) (xy 50.85588 -385.850892) (xy 50.868619 -385.874207)
			(xy 50.886709 -385.924157) (xy 50.895924 -385.976476) (xy 50.89652 -386.003038) (xy 50.89652 -386.003292)
			(xy 50.89603 -386.027282) (xy 50.888526 -386.074673) (xy 50.8737 -386.120306) (xy 50.851918 -386.163057)
			(xy 50.823717 -386.201876) (xy 50.789791 -386.235804) (xy 50.750974 -386.264008) (xy 50.708224 -386.285792)
			(xy 50.662592 -386.300621) (xy 50.615202 -386.308128) (xy 50.591212 -386.3086) (xy 50.567638 -386.308197)
			(xy 50.521051 -386.300957) (xy 50.476132 -386.286633) (xy 50.433954 -386.265566) (xy 50.395521 -386.238258)
			(xy 50.361749 -386.205359) (xy 50.333443 -386.167655) (xy 50.321972 -386.147056) (xy 50.321464 -386.146294)
			(xy 49.9237 -385.457954) (xy 49.911766 -385.435295) (xy 49.894835 -385.386965) (xy 49.886183 -385.336491)
			(xy 49.8856 -385.310888) (xy 49.34386 -385.310888) (xy 49.655984 -385.850892) (xy 49.668715 -385.874211)
			(xy 49.68681 -385.924158) (xy 49.696027 -385.976477) (xy 49.696624 -386.003038) (xy 49.696624 -386.003292)
			(xy 49.69613 -386.027282) (xy 49.688626 -386.074672) (xy 49.6738 -386.120305) (xy 49.652019 -386.163056)
			(xy 49.623818 -386.201874) (xy 49.589892 -386.235803) (xy 49.551077 -386.264007) (xy 49.508327 -386.285791)
			(xy 49.462695 -386.30062) (xy 49.415306 -386.308128) (xy 49.391316 -386.3086) (xy 49.367742 -386.308193)
			(xy 49.321155 -386.300954) (xy 49.276236 -386.286631) (xy 49.234058 -386.265564) (xy 49.195625 -386.238257)
			(xy 49.161853 -386.205359) (xy 49.133547 -386.167655) (xy 49.122076 -386.147056) (xy 49.121568 -386.146294)
			(xy 48.723804 -385.457954) (xy 48.71187 -385.435295) (xy 48.694939 -385.386965) (xy 48.686287 -385.336491)
			(xy 48.685704 -385.310888) (xy 48.143964 -385.310888) (xy 48.456088 -385.850892) (xy 48.46882 -385.874211)
			(xy 48.486915 -385.924158) (xy 48.496131 -385.976477) (xy 48.496728 -386.003038) (xy 48.496728 -386.003292)
			(xy 48.49623 -386.027282) (xy 48.488726 -386.074672) (xy 48.473901 -386.120304) (xy 48.45212 -386.163055)
			(xy 48.42392 -386.201873) (xy 48.389994 -386.235801) (xy 48.351179 -386.264005) (xy 48.30843 -386.28579)
			(xy 48.262799 -386.300619) (xy 48.21541 -386.308128) (xy 48.19142 -386.3086) (xy 48.167847 -386.30819)
			(xy 48.121259 -386.300952) (xy 48.076341 -386.286629) (xy 48.034162 -386.265563) (xy 47.995729 -386.238256)
			(xy 47.961957 -386.205358) (xy 47.933651 -386.167655) (xy 47.92218 -386.147056) (xy 47.921672 -386.146294)
			(xy 47.523908 -385.457954) (xy 47.511974 -385.435295) (xy 47.495043 -385.386965) (xy 47.486391 -385.336491)
			(xy 47.485808 -385.310888) (xy 2.509012 -385.310888) (xy 2.509012 -387.789674) (xy 40.901112 -387.789674)
			(xy 40.901112 -386.926074) (xy 40.901598 -386.898805) (xy 40.90936 -386.844821) (xy 40.924725 -386.792491)
			(xy 40.947382 -386.742881) (xy 40.976868 -386.697) (xy 41.012583 -386.655783) (xy 41.0538 -386.620068)
			(xy 41.099681 -386.590582) (xy 41.149291 -386.567925) (xy 41.201621 -386.55256) (xy 41.255605 -386.544798)
			(xy 41.310143 -386.544798) (xy 41.364127 -386.55256) (xy 41.416457 -386.567925) (xy 41.466067 -386.590582)
			(xy 41.511948 -386.620068) (xy 41.553165 -386.655783) (xy 41.58888 -386.697) (xy 41.618366 -386.742881)
			(xy 41.641023 -386.792491) (xy 41.656388 -386.844821) (xy 41.66415 -386.898805) (xy 41.664636 -386.926074)
			(xy 41.664636 -387.789674) (xy 73.42886 -387.789674) (xy 73.42886 -386.926074) (xy 73.429346 -386.898805)
			(xy 73.437108 -386.844821) (xy 73.452473 -386.792491) (xy 73.47513 -386.742881) (xy 73.504616 -386.697)
			(xy 73.540331 -386.655783) (xy 73.581548 -386.620068) (xy 73.627429 -386.590582) (xy 73.677039 -386.567925)
			(xy 73.729369 -386.55256) (xy 73.783353 -386.544798) (xy 73.837891 -386.544798) (xy 73.891875 -386.55256)
			(xy 73.944205 -386.567925) (xy 73.993815 -386.590582) (xy 74.039696 -386.620068) (xy 74.080913 -386.655783)
			(xy 74.116628 -386.697) (xy 74.146114 -386.742881) (xy 74.168771 -386.792491) (xy 74.184136 -386.844821)
			(xy 74.191898 -386.898805) (xy 74.192384 -386.926074) (xy 74.192384 -387.789674) (xy 108.001308 -387.789674)
			(xy 108.001308 -386.926074) (xy 108.001794 -386.898823) (xy 108.00955 -386.844875) (xy 108.024905 -386.79258)
			(xy 108.047547 -386.743003) (xy 108.077013 -386.697153) (xy 108.112704 -386.655962) (xy 108.153895 -386.620271)
			(xy 108.199745 -386.590805) (xy 108.249322 -386.568163) (xy 108.301617 -386.552808) (xy 108.355565 -386.545052)
			(xy 108.410067 -386.545052) (xy 108.464015 -386.552808) (xy 108.51631 -386.568163) (xy 108.565887 -386.590805)
			(xy 108.611737 -386.620271) (xy 108.652928 -386.655962) (xy 108.688619 -386.697153) (xy 108.718085 -386.743003)
			(xy 108.740727 -386.79258) (xy 108.756082 -386.844875) (xy 108.763838 -386.898823) (xy 108.764324 -386.926074)
			(xy 108.764324 -387.789674) (xy 140.529056 -387.789674) (xy 140.529056 -386.926074) (xy 140.529542 -386.898823)
			(xy 140.537298 -386.844875) (xy 140.552653 -386.79258) (xy 140.575295 -386.743003) (xy 140.604761 -386.697153)
			(xy 140.640452 -386.655962) (xy 140.681643 -386.620271) (xy 140.727493 -386.590805) (xy 140.77707 -386.568163)
			(xy 140.829365 -386.552808) (xy 140.883313 -386.545052) (xy 140.937815 -386.545052) (xy 140.991763 -386.552808)
			(xy 141.044058 -386.568163) (xy 141.093635 -386.590805) (xy 141.139485 -386.620271) (xy 141.180676 -386.655962)
			(xy 141.216367 -386.697153) (xy 141.245833 -386.743003) (xy 141.268475 -386.79258) (xy 141.28383 -386.844875)
			(xy 141.291586 -386.898823) (xy 141.292072 -386.926074) (xy 141.292072 -387.789674) (xy 141.291586 -387.816925)
			(xy 141.28383 -387.870873) (xy 141.268475 -387.923168) (xy 141.245833 -387.972745) (xy 141.216367 -388.018595)
			(xy 141.180676 -388.059786) (xy 141.139485 -388.095477) (xy 141.093635 -388.124943) (xy 141.044058 -388.147585)
			(xy 140.991763 -388.16294) (xy 140.937815 -388.170696) (xy 140.883313 -388.170696) (xy 140.829365 -388.16294)
			(xy 140.77707 -388.147585) (xy 140.727493 -388.124943) (xy 140.681643 -388.095477) (xy 140.640452 -388.059786)
			(xy 140.604761 -388.018595) (xy 140.575295 -387.972745) (xy 140.552653 -387.923168) (xy 140.537298 -387.870873)
			(xy 140.529542 -387.816925) (xy 140.529056 -387.789674) (xy 108.764324 -387.789674) (xy 108.763838 -387.816925)
			(xy 108.756082 -387.870873) (xy 108.740727 -387.923168) (xy 108.718085 -387.972745) (xy 108.688619 -388.018595)
			(xy 108.652928 -388.059786) (xy 108.611737 -388.095477) (xy 108.565887 -388.124943) (xy 108.51631 -388.147585)
			(xy 108.464015 -388.16294) (xy 108.410067 -388.170696) (xy 108.355565 -388.170696) (xy 108.301617 -388.16294)
			(xy 108.249322 -388.147585) (xy 108.199745 -388.124943) (xy 108.153895 -388.095477) (xy 108.112704 -388.059786)
			(xy 108.077013 -388.018595) (xy 108.047547 -387.972745) (xy 108.024905 -387.923168) (xy 108.00955 -387.870873)
			(xy 108.001794 -387.816925) (xy 108.001308 -387.789674) (xy 74.192384 -387.789674) (xy 74.191898 -387.816943)
			(xy 74.184136 -387.870927) (xy 74.168771 -387.923257) (xy 74.146114 -387.972867) (xy 74.116628 -388.018748)
			(xy 74.080913 -388.059965) (xy 74.039696 -388.09568) (xy 73.993815 -388.125166) (xy 73.944205 -388.147823)
			(xy 73.891875 -388.163188) (xy 73.837891 -388.17095) (xy 73.783353 -388.17095) (xy 73.729369 -388.163188)
			(xy 73.677039 -388.147823) (xy 73.627429 -388.125166) (xy 73.581548 -388.09568) (xy 73.540331 -388.059965)
			(xy 73.504616 -388.018748) (xy 73.47513 -387.972867) (xy 73.452473 -387.923257) (xy 73.437108 -387.870927)
			(xy 73.429346 -387.816943) (xy 73.42886 -387.789674) (xy 41.664636 -387.789674) (xy 41.66415 -387.816943)
			(xy 41.656388 -387.870927) (xy 41.641023 -387.923257) (xy 41.618366 -387.972867) (xy 41.58888 -388.018748)
			(xy 41.553165 -388.059965) (xy 41.511948 -388.09568) (xy 41.466067 -388.125166) (xy 41.416457 -388.147823)
			(xy 41.364127 -388.163188) (xy 41.310143 -388.17095) (xy 41.255605 -388.17095) (xy 41.201621 -388.163188)
			(xy 41.149291 -388.147823) (xy 41.099681 -388.125166) (xy 41.0538 -388.09568) (xy 41.012583 -388.059965)
			(xy 40.976868 -388.018748) (xy 40.947382 -387.972867) (xy 40.924725 -387.923257) (xy 40.90936 -387.870927)
			(xy 40.901598 -387.816943) (xy 40.901112 -387.789674) (xy 2.509012 -387.789674) (xy 2.509012 -388.77494)
			(xy 47.485808 -388.77494) (xy 47.485808 -388.774432) (xy 47.486291 -388.750454) (xy 47.493785 -388.703086)
			(xy 47.508594 -388.657473) (xy 47.530352 -388.614736) (xy 47.558526 -388.575927) (xy 47.592422 -388.542002)
			(xy 47.631205 -388.513794) (xy 47.673923 -388.491997) (xy 47.719523 -388.477148) (xy 47.766884 -388.469612)
			(xy 47.790862 -388.469124) (xy 47.79137 -388.469124) (xy 47.815307 -388.469547) (xy 47.862595 -388.477009)
			(xy 47.90814 -388.491756) (xy 47.950828 -388.513426) (xy 47.989613 -388.541489) (xy 48.023547 -388.575259)
			(xy 48.051798 -388.613907) (xy 48.06315 -388.634986) (xy 48.063658 -388.636002) (xy 48.143964 -388.77494)
			(xy 48.685704 -388.77494) (xy 48.685704 -388.774432) (xy 48.686191 -388.750454) (xy 48.693685 -388.703086)
			(xy 48.708493 -388.657473) (xy 48.730252 -388.614737) (xy 48.758425 -388.575929) (xy 48.79232 -388.542003)
			(xy 48.831103 -388.513795) (xy 48.87382 -388.491998) (xy 48.91942 -388.477149) (xy 48.96678 -388.469613)
			(xy 48.990758 -388.469124) (xy 48.991266 -388.469124) (xy 49.015203 -388.46955) (xy 49.06249 -388.477012)
			(xy 49.108036 -388.491758) (xy 49.150724 -388.513428) (xy 49.189509 -388.54149) (xy 49.223443 -388.575259)
			(xy 49.251694 -388.613908) (xy 49.263046 -388.634986) (xy 49.263554 -388.636002) (xy 49.34386 -388.77494)
			(xy 49.8856 -388.77494) (xy 49.8856 -388.774432) (xy 49.886091 -388.750454) (xy 49.893585 -388.703087)
			(xy 49.908393 -388.657474) (xy 49.930151 -388.614738) (xy 49.958324 -388.57593) (xy 49.992219 -388.542005)
			(xy 50.031001 -388.513796) (xy 50.073717 -388.491999) (xy 50.119316 -388.47715) (xy 50.166676 -388.469613)
			(xy 50.190654 -388.469124) (xy 50.191162 -388.469124) (xy 50.215098 -388.469553) (xy 50.262386 -388.477014)
			(xy 50.307931 -388.49176) (xy 50.350619 -388.513429) (xy 50.389405 -388.541491) (xy 50.423338 -388.57526)
			(xy 50.45159 -388.613908) (xy 50.462942 -388.634986) (xy 50.46345 -388.636002) (xy 50.543756 -388.77494)
			(xy 51.086004 -388.77494) (xy 51.086004 -388.774432) (xy 51.086468 -388.750439) (xy 51.09397 -388.703044)
			(xy 51.108795 -388.657405) (xy 51.130577 -388.614648) (xy 51.158781 -388.575826) (xy 51.192711 -388.541894)
			(xy 51.231531 -388.513688) (xy 51.274287 -388.491903) (xy 51.319924 -388.477075) (xy 51.367319 -388.469569)
			(xy 51.391312 -388.469124) (xy 51.415247 -388.469594) (xy 51.462533 -388.477047) (xy 51.508077 -388.491786)
			(xy 51.550765 -388.513448) (xy 51.589551 -388.541504) (xy 51.623486 -388.575267) (xy 51.651739 -388.61391)
			(xy 51.663092 -388.634986) (xy 51.6636 -388.636002) (xy 51.743906 -388.77494) (xy 52.2859 -388.77494)
			(xy 52.2859 -388.774432) (xy 52.286368 -388.750439) (xy 52.29387 -388.703044) (xy 52.308695 -388.657406)
			(xy 52.330477 -388.61465) (xy 52.35868 -388.575827) (xy 52.392609 -388.541895) (xy 52.431429 -388.513689)
			(xy 52.474184 -388.491904) (xy 52.519821 -388.477076) (xy 52.567215 -388.46957) (xy 52.591208 -388.469124)
			(xy 52.615143 -388.469597) (xy 52.662429 -388.47705) (xy 52.707973 -388.491788) (xy 52.750661 -388.51345)
			(xy 52.789447 -388.541505) (xy 52.823382 -388.575268) (xy 52.851635 -388.61391) (xy 52.862988 -388.634986)
			(xy 52.863496 -388.636002) (xy 52.943802 -388.77494) (xy 53.485796 -388.77494) (xy 53.485796 -388.774432)
			(xy 53.486291 -388.750454) (xy 53.493785 -388.703088) (xy 53.508592 -388.657475) (xy 53.53035 -388.61474)
			(xy 53.558523 -388.575932) (xy 53.592417 -388.542006) (xy 53.631199 -388.513798) (xy 53.673914 -388.492001)
			(xy 53.719513 -388.477151) (xy 53.766873 -388.469613) (xy 53.79085 -388.469124) (xy 53.791358 -388.469124)
			(xy 53.815294 -388.469556) (xy 53.862582 -388.477017) (xy 53.908127 -388.491762) (xy 53.950815 -388.513431)
			(xy 53.9896 -388.541492) (xy 54.023534 -388.57526) (xy 54.051786 -388.613908) (xy 54.063138 -388.634986)
			(xy 54.063646 -388.636002) (xy 54.143952 -388.77494) (xy 54.685692 -388.77494) (xy 54.685692 -388.774432)
			(xy 54.686191 -388.750454) (xy 54.693684 -388.703088) (xy 54.708492 -388.657476) (xy 54.730249 -388.614741)
			(xy 54.758422 -388.575933) (xy 54.792315 -388.542008) (xy 54.831097 -388.513799) (xy 54.873812 -388.492002)
			(xy 54.91941 -388.477151) (xy 54.966769 -388.469614) (xy 54.990746 -388.469124) (xy 54.991254 -388.469124)
			(xy 55.01519 -388.46956) (xy 55.062478 -388.47702) (xy 55.108023 -388.491764) (xy 55.150711 -388.513432)
			(xy 55.189496 -388.541493) (xy 55.22343 -388.575261) (xy 55.251681 -388.613908) (xy 55.263034 -388.634986)
			(xy 55.263542 -388.636002) (xy 55.343848 -388.77494) (xy 55.885588 -388.77494) (xy 55.885588 -388.774432)
			(xy 55.886091 -388.750455) (xy 55.893584 -388.703089) (xy 55.908392 -388.657477) (xy 55.930149 -388.614742)
			(xy 55.95832 -388.575934) (xy 55.992213 -388.542009) (xy 56.030994 -388.513801) (xy 56.073709 -388.492003)
			(xy 56.119306 -388.477152) (xy 56.166665 -388.469614) (xy 56.190642 -388.469124) (xy 56.19115 -388.469124)
			(xy 56.215086 -388.469563) (xy 56.262373 -388.477022) (xy 56.307918 -388.491766) (xy 56.350606 -388.513434)
			(xy 56.389392 -388.541494) (xy 56.423326 -388.575262) (xy 56.451577 -388.613908) (xy 56.46293 -388.634986)
			(xy 56.463438 -388.636002) (xy 56.543744 -388.77494) (xy 57.085992 -388.77494) (xy 57.085992 -388.774432)
			(xy 57.086468 -388.75044) (xy 57.09397 -388.703045) (xy 57.108794 -388.657408) (xy 57.130575 -388.614652)
			(xy 57.158777 -388.57583) (xy 57.192706 -388.541898) (xy 57.231525 -388.513692) (xy 57.274279 -388.491906)
			(xy 57.319914 -388.477077) (xy 57.367308 -388.46957) (xy 57.3913 -388.469124) (xy 57.415235 -388.469603)
			(xy 57.46252 -388.477055) (xy 57.508064 -388.491792) (xy 57.550752 -388.513453) (xy 57.589538 -388.541507)
			(xy 57.623473 -388.575269) (xy 57.651726 -388.613911) (xy 57.66308 -388.634986) (xy 57.663588 -388.636002)
			(xy 57.743894 -388.77494) (xy 58.285888 -388.77494) (xy 58.285888 -388.774432) (xy 58.286368 -388.75044)
			(xy 58.29387 -388.703046) (xy 58.308693 -388.657409) (xy 58.330474 -388.614653) (xy 58.358676 -388.575831)
			(xy 58.392604 -388.5419) (xy 58.431423 -388.513693) (xy 58.474176 -388.491907) (xy 58.519811 -388.477078)
			(xy 58.567204 -388.469571) (xy 58.591196 -388.469124) (xy 58.615133 -388.469526) (xy 58.662423 -388.476992)
			(xy 58.707968 -388.491742) (xy 58.750656 -388.513416) (xy 58.789441 -388.541483) (xy 58.823374 -388.575255)
			(xy 58.851624 -388.613906) (xy 58.862976 -388.634986) (xy 58.863484 -388.636002) (xy 58.94379 -388.77494)
			(xy 59.485784 -388.77494) (xy 59.485784 -388.774432) (xy 59.486291 -388.750455) (xy 59.493784 -388.703089)
			(xy 59.508591 -388.657478) (xy 59.530348 -388.614743) (xy 59.558519 -388.575936) (xy 59.592412 -388.54201)
			(xy 59.631192 -388.513802) (xy 59.673906 -388.492004) (xy 59.719503 -388.477153) (xy 59.766861 -388.469614)
			(xy 59.790838 -388.469124) (xy 59.791346 -388.469124) (xy 59.815282 -388.469566) (xy 59.862569 -388.477025)
			(xy 59.908114 -388.491768) (xy 59.950802 -388.513435) (xy 59.989587 -388.541495) (xy 60.023522 -388.575262)
			(xy 60.051773 -388.613909) (xy 60.063126 -388.634986) (xy 60.063634 -388.636002) (xy 60.14394 -388.77494)
			(xy 60.68568 -388.77494) (xy 60.68568 -388.774432) (xy 60.686191 -388.750455) (xy 60.693684 -388.70309)
			(xy 60.708491 -388.657479) (xy 60.730247 -388.614744) (xy 60.758418 -388.575937) (xy 60.79231 -388.542012)
			(xy 60.83109 -388.513803) (xy 60.873803 -388.492005) (xy 60.9194 -388.477154) (xy 60.966757 -388.469614)
			(xy 60.990734 -388.469124) (xy 60.991242 -388.469124) (xy 61.015178 -388.469569) (xy 61.062465 -388.477028)
			(xy 61.10801 -388.49177) (xy 61.150697 -388.513437) (xy 61.189483 -388.541496) (xy 61.223417 -388.575263)
			(xy 61.251669 -388.613909) (xy 61.263022 -388.634986) (xy 61.26353 -388.636002) (xy 61.343836 -388.77494)
			(xy 61.885576 -388.77494) (xy 61.885576 -388.774432) (xy 61.886091 -388.750455) (xy 61.893584 -388.70309)
			(xy 61.908391 -388.65748) (xy 61.930147 -388.614746) (xy 61.958317 -388.575938) (xy 61.992208 -388.542013)
			(xy 62.030988 -388.513805) (xy 62.073701 -388.492006) (xy 62.119296 -388.477155) (xy 62.166654 -388.469615)
			(xy 62.19063 -388.469124) (xy 62.191138 -388.469124) (xy 62.215074 -388.469573) (xy 62.262361 -388.47703)
			(xy 62.307905 -388.491772) (xy 62.350593 -388.513438) (xy 62.389379 -388.541498) (xy 62.423313 -388.575263)
			(xy 62.451565 -388.613909) (xy 62.462918 -388.634986) (xy 62.463426 -388.636002) (xy 62.543732 -388.77494)
			(xy 63.08598 -388.77494) (xy 63.08598 -388.774432) (xy 63.086468 -388.75044) (xy 63.093969 -388.703047)
			(xy 63.108793 -388.657411) (xy 63.130573 -388.614656) (xy 63.158774 -388.575834) (xy 63.192701 -388.541902)
			(xy 63.231518 -388.513696) (xy 63.27427 -388.49191) (xy 63.319904 -388.47708) (xy 63.367296 -388.469571)
			(xy 63.391288 -388.469124) (xy 63.415225 -388.469532) (xy 63.462514 -388.476997) (xy 63.50806 -388.491747)
			(xy 63.550747 -388.513419) (xy 63.589533 -388.541485) (xy 63.623466 -388.575256) (xy 63.651716 -388.613907)
			(xy 63.663068 -388.634986) (xy 63.663576 -388.636002) (xy 63.743882 -388.77494) (xy 64.285876 -388.77494)
			(xy 64.285876 -388.774432) (xy 64.286368 -388.750441) (xy 64.293869 -388.703048) (xy 64.308692 -388.657412)
			(xy 64.330472 -388.614657) (xy 64.358673 -388.575836) (xy 64.392599 -388.541904) (xy 64.431416 -388.513697)
			(xy 64.474167 -388.491911) (xy 64.519801 -388.47708) (xy 64.567193 -388.469571) (xy 64.591184 -388.469124)
			(xy 64.615121 -388.469535) (xy 64.66241 -388.477) (xy 64.707955 -388.491749) (xy 64.750643 -388.513421)
			(xy 64.789428 -388.541486) (xy 64.823361 -388.575257) (xy 64.851612 -388.613907) (xy 64.862964 -388.634986)
			(xy 64.863472 -388.636002) (xy 64.943778 -388.77494) (xy 65.485772 -388.77494) (xy 65.485772 -388.774432)
			(xy 65.486291 -388.750455) (xy 65.493784 -388.703091) (xy 65.50859 -388.657481) (xy 65.530346 -388.614747)
			(xy 65.558516 -388.57594) (xy 65.592407 -388.542015) (xy 65.631185 -388.513806) (xy 65.673898 -388.492007)
			(xy 65.719493 -388.477155) (xy 65.76685 -388.469615) (xy 65.790826 -388.469124) (xy 65.791334 -388.469124)
			(xy 65.81527 -388.469576) (xy 65.862556 -388.477033) (xy 65.908101 -388.491774) (xy 65.950789 -388.51344)
			(xy 65.989575 -388.541499) (xy 66.023509 -388.575264) (xy 66.051761 -388.613909) (xy 66.063114 -388.634986)
			(xy 66.063622 -388.636002) (xy 66.143928 -388.77494) (xy 80.013556 -388.77494) (xy 80.013556 -388.774432)
			(xy 80.014091 -388.750456) (xy 80.021583 -388.703093) (xy 80.036389 -388.657485) (xy 80.058143 -388.614751)
			(xy 80.086311 -388.575945) (xy 80.1202 -388.54202) (xy 80.158977 -388.513811) (xy 80.201687 -388.492012)
			(xy 80.24728 -388.477159) (xy 80.294635 -388.469616) (xy 80.31861 -388.469124) (xy 80.319118 -388.469124)
			(xy 80.343053 -388.469589) (xy 80.390339 -388.477043) (xy 80.435884 -388.491783) (xy 80.478571 -388.513446)
			(xy 80.517357 -388.541503) (xy 80.551292 -388.575266) (xy 80.579545 -388.61391) (xy 80.590898 -388.634986)
			(xy 80.591406 -388.636002) (xy 80.671712 -388.77494) (xy 81.213452 -388.77494) (xy 81.213452 -388.774432)
			(xy 81.213991 -388.750456) (xy 81.221483 -388.703094) (xy 81.236288 -388.657485) (xy 81.258042 -388.614753)
			(xy 81.28621 -388.575947) (xy 81.320098 -388.542022) (xy 81.358874 -388.513813) (xy 81.401584 -388.492013)
			(xy 81.447176 -388.477159) (xy 81.494531 -388.469617) (xy 81.518506 -388.469124) (xy 81.519014 -388.469124)
			(xy 81.542949 -388.469592) (xy 81.590235 -388.477046) (xy 81.635779 -388.491785) (xy 81.678467 -388.513447)
			(xy 81.717253 -388.541504) (xy 81.751188 -388.575267) (xy 81.779441 -388.61391) (xy 81.790794 -388.634986)
			(xy 81.791302 -388.636002) (xy 81.871608 -388.77494) (xy 82.413348 -388.77494) (xy 82.413348 -388.774432)
			(xy 82.413891 -388.750456) (xy 82.421383 -388.703095) (xy 82.436188 -388.657486) (xy 82.457941 -388.614754)
			(xy 82.486109 -388.575948) (xy 82.519997 -388.542023) (xy 82.558772 -388.513814) (xy 82.601481 -388.492014)
			(xy 82.647073 -388.47716) (xy 82.694427 -388.469617) (xy 82.718402 -388.469124) (xy 82.71891 -388.469124)
			(xy 82.742845 -388.469595) (xy 82.790131 -388.477049) (xy 82.835675 -388.491787) (xy 82.878363 -388.513449)
			(xy 82.917149 -388.541505) (xy 82.951084 -388.575267) (xy 82.979337 -388.61391) (xy 82.99069 -388.634986)
			(xy 82.991198 -388.636002) (xy 83.071504 -388.77494) (xy 83.613752 -388.77494) (xy 83.613752 -388.774432)
			(xy 83.614292 -388.750444) (xy 83.621792 -388.703057) (xy 83.636613 -388.657427) (xy 83.658389 -388.614677)
			(xy 83.686584 -388.57586) (xy 83.720505 -388.541931) (xy 83.759315 -388.513726) (xy 83.80206 -388.49194)
			(xy 83.847687 -388.477109) (xy 83.895072 -388.469598) (xy 83.91906 -388.469124) (xy 83.942996 -388.469555)
			(xy 83.990284 -388.477016) (xy 84.035829 -388.491761) (xy 84.078517 -388.51343) (xy 84.117303 -388.541492)
			(xy 84.151236 -388.57526) (xy 84.179488 -388.613908) (xy 84.19084 -388.634986) (xy 84.191348 -388.636002)
			(xy 84.271654 -388.77494) (xy 84.813648 -388.77494) (xy 84.813648 -388.774432) (xy 84.814192 -388.750444)
			(xy 84.821692 -388.703057) (xy 84.836512 -388.657428) (xy 84.858288 -388.614678) (xy 84.886483 -388.575861)
			(xy 84.920403 -388.541933) (xy 84.959213 -388.513728) (xy 85.001957 -388.491941) (xy 85.047583 -388.47711)
			(xy 85.094968 -388.469598) (xy 85.118956 -388.469124) (xy 85.142892 -388.469558) (xy 85.19018 -388.477018)
			(xy 85.235725 -388.491763) (xy 85.278413 -388.513431) (xy 85.317198 -388.541493) (xy 85.351132 -388.575261)
			(xy 85.379383 -388.613908) (xy 85.390736 -388.634986) (xy 85.391244 -388.636002) (xy 85.47155 -388.77494)
			(xy 86.013544 -388.77494) (xy 86.013544 -388.774432) (xy 86.014091 -388.750457) (xy 86.021583 -388.703095)
			(xy 86.036387 -388.657487) (xy 86.058141 -388.614755) (xy 86.086307 -388.575949) (xy 86.120195 -388.542025)
			(xy 86.15897 -388.513815) (xy 86.201678 -388.492016) (xy 86.24727 -388.477161) (xy 86.294623 -388.469617)
			(xy 86.318598 -388.469124) (xy 86.319106 -388.469124) (xy 86.343041 -388.469599) (xy 86.390326 -388.477051)
			(xy 86.435871 -388.491789) (xy 86.478558 -388.51345) (xy 86.517345 -388.541506) (xy 86.55128 -388.575268)
			(xy 86.579533 -388.61391) (xy 86.590886 -388.634986) (xy 86.591394 -388.636002) (xy 86.6717 -388.77494)
			(xy 87.21344 -388.77494) (xy 87.21344 -388.774432) (xy 87.213891 -388.750452) (xy 87.221386 -388.703081)
			(xy 87.236197 -388.657465) (xy 87.257958 -388.614726) (xy 87.286136 -388.575917) (xy 87.320035 -388.54199)
			(xy 87.358823 -388.513783) (xy 87.401545 -388.491988) (xy 87.447149 -388.477142) (xy 87.494514 -388.46961)
			(xy 87.518494 -388.469124) (xy 87.519002 -388.469124) (xy 87.542937 -388.469602) (xy 87.590222 -388.477054)
			(xy 87.635766 -388.491791) (xy 87.678454 -388.513452) (xy 87.71724 -388.541507) (xy 87.751175 -388.575268)
			(xy 87.779429 -388.61391) (xy 87.790782 -388.634986) (xy 87.79129 -388.636002) (xy 87.871596 -388.77494)
			(xy 88.413336 -388.77494) (xy 88.413336 -388.774432) (xy 88.413791 -388.750452) (xy 88.421286 -388.703082)
			(xy 88.436096 -388.657466) (xy 88.457858 -388.614728) (xy 88.486034 -388.575918) (xy 88.519934 -388.541992)
			(xy 88.558721 -388.513784) (xy 88.601442 -388.491989) (xy 88.647046 -388.477143) (xy 88.69441 -388.46961)
			(xy 88.71839 -388.469124) (xy 88.718898 -388.469124) (xy 88.742835 -388.469524) (xy 88.790125 -388.476991)
			(xy 88.835671 -388.491741) (xy 88.878358 -388.513415) (xy 88.917143 -388.541482) (xy 88.951076 -388.575255)
			(xy 88.979326 -388.613906) (xy 88.990678 -388.634986) (xy 88.991186 -388.636002) (xy 89.071492 -388.77494)
			(xy 89.61374 -388.77494) (xy 89.61374 -388.774432) (xy 89.614168 -388.750437) (xy 89.621671 -388.703038)
			(xy 89.636498 -388.657397) (xy 89.658284 -388.614638) (xy 89.686491 -388.575814) (xy 89.720426 -388.541881)
			(xy 89.759251 -388.513676) (xy 89.802012 -388.491892) (xy 89.847654 -388.477068) (xy 89.895053 -388.469567)
			(xy 89.919048 -388.469124) (xy 89.942984 -388.469565) (xy 89.990271 -388.477024) (xy 90.035816 -388.491767)
			(xy 90.078504 -388.513434) (xy 90.11729 -388.541495) (xy 90.151224 -388.575262) (xy 90.179475 -388.613908)
			(xy 90.190828 -388.634986) (xy 90.191336 -388.636002) (xy 90.271642 -388.77494) (xy 90.813636 -388.77494)
			(xy 90.813636 -388.774432) (xy 90.814068 -388.750438) (xy 90.821571 -388.703039) (xy 90.836398 -388.657398)
			(xy 90.858183 -388.614639) (xy 90.88639 -388.575815) (xy 90.920324 -388.541882) (xy 90.959149 -388.513677)
			(xy 91.001909 -388.491893) (xy 91.047551 -388.477068) (xy 91.09495 -388.469567) (xy 91.118944 -388.469124)
			(xy 91.14288 -388.469568) (xy 91.190167 -388.477026) (xy 91.235712 -388.491769) (xy 91.2784 -388.513436)
			(xy 91.317185 -388.541496) (xy 91.351119 -388.575262) (xy 91.379371 -388.613909) (xy 91.390724 -388.634986)
			(xy 91.391232 -388.636002) (xy 91.471538 -388.77494) (xy 92.013532 -388.77494) (xy 92.013532 -388.774432)
			(xy 92.013991 -388.750452) (xy 92.021486 -388.703082) (xy 92.036296 -388.657467) (xy 92.058057 -388.614729)
			(xy 92.086233 -388.575919) (xy 92.120132 -388.541993) (xy 92.158919 -388.513786) (xy 92.201639 -388.49199)
			(xy 92.247243 -388.477143) (xy 92.294607 -388.469611) (xy 92.318586 -388.469124) (xy 92.319094 -388.469124)
			(xy 92.343031 -388.469527) (xy 92.39032 -388.476993) (xy 92.435866 -388.491744) (xy 92.478554 -388.513417)
			(xy 92.517339 -388.541483) (xy 92.551272 -388.575255) (xy 92.579522 -388.613906) (xy 92.590874 -388.634986)
			(xy 92.591382 -388.636002) (xy 92.671688 -388.77494) (xy 93.213428 -388.77494) (xy 93.213428 -388.774432)
			(xy 93.213891 -388.750453) (xy 93.221386 -388.703083) (xy 93.236196 -388.657468) (xy 93.257956 -388.61473)
			(xy 93.286132 -388.575921) (xy 93.32003 -388.541995) (xy 93.358817 -388.513787) (xy 93.401537 -388.491991)
			(xy 93.447139 -388.477144) (xy 93.494503 -388.469611) (xy 93.518482 -388.469124) (xy 93.51899 -388.469124)
			(xy 93.542927 -388.46953) (xy 93.590216 -388.476996) (xy 93.635762 -388.491746) (xy 93.67845 -388.513419)
			(xy 93.717235 -388.541484) (xy 93.751168 -388.575256) (xy 93.779418 -388.613907) (xy 93.79077 -388.634986)
			(xy 93.791278 -388.636002) (xy 93.871584 -388.77494) (xy 94.413324 -388.77494) (xy 94.413324 -388.774432)
			(xy 94.413791 -388.750453) (xy 94.421286 -388.703083) (xy 94.436095 -388.657469) (xy 94.457855 -388.614731)
			(xy 94.486031 -388.575922) (xy 94.519929 -388.541996) (xy 94.558714 -388.513788) (xy 94.601434 -388.491993)
			(xy 94.647036 -388.477145) (xy 94.694399 -388.469611) (xy 94.718378 -388.469124) (xy 94.718886 -388.469124)
			(xy 94.742823 -388.469534) (xy 94.790112 -388.476998) (xy 94.835657 -388.491748) (xy 94.878345 -388.51342)
			(xy 94.91713 -388.541485) (xy 94.951064 -388.575256) (xy 94.979314 -388.613907) (xy 94.990666 -388.634986)
			(xy 94.991174 -388.636002) (xy 95.07148 -388.77494) (xy 95.613728 -388.77494) (xy 95.613728 -388.774432)
			(xy 95.614168 -388.750438) (xy 95.621671 -388.70304) (xy 95.636497 -388.6574) (xy 95.658282 -388.614641)
			(xy 95.686488 -388.575818) (xy 95.720421 -388.541885) (xy 95.759245 -388.51368) (xy 95.802004 -388.491896)
			(xy 95.847644 -388.47707) (xy 95.895042 -388.469568) (xy 95.919036 -388.469124) (xy 95.942972 -388.469574)
			(xy 95.990258 -388.477031) (xy 96.035803 -388.491773) (xy 96.078491 -388.513439) (xy 96.117277 -388.541498)
			(xy 96.151211 -388.575264) (xy 96.179463 -388.613909) (xy 96.190816 -388.634986) (xy 96.191324 -388.636002)
			(xy 96.27163 -388.77494) (xy 96.813624 -388.77494) (xy 96.813624 -388.774432) (xy 96.814068 -388.750438)
			(xy 96.821571 -388.703041) (xy 96.836397 -388.657401) (xy 96.858181 -388.614643) (xy 96.886387 -388.575819)
			(xy 96.920319 -388.541887) (xy 96.959143 -388.513681) (xy 97.001901 -388.491897) (xy 97.047541 -388.477071)
			(xy 97.094938 -388.469568) (xy 97.118932 -388.469124) (xy 97.142868 -388.469578) (xy 97.190154 -388.477034)
			(xy 97.235699 -388.491775) (xy 97.278387 -388.51344) (xy 97.317172 -388.541499) (xy 97.351107 -388.575264)
			(xy 97.379359 -388.613909) (xy 97.390712 -388.634986) (xy 97.39122 -388.636002) (xy 97.471526 -388.77494)
			(xy 98.01352 -388.77494) (xy 98.01352 -388.774432) (xy 98.013991 -388.750453) (xy 98.021485 -388.703084)
			(xy 98.036295 -388.65747) (xy 98.058055 -388.614732) (xy 98.08623 -388.575923) (xy 98.120127 -388.541998)
			(xy 98.158912 -388.51379) (xy 98.201631 -388.491994) (xy 98.247233 -388.477146) (xy 98.294595 -388.469612)
			(xy 98.318574 -388.469124) (xy 98.319082 -388.469124) (xy 98.343019 -388.469537) (xy 98.390308 -388.477001)
			(xy 98.435853 -388.49175) (xy 98.478541 -388.513422) (xy 98.517326 -388.541486) (xy 98.551259 -388.575257)
			(xy 98.57951 -388.613907) (xy 98.590862 -388.634986) (xy 98.59137 -388.636002) (xy 98.671676 -388.77494)
			(xy 114.586004 -388.77494) (xy 114.586004 -388.774432) (xy 114.586468 -388.750439) (xy 114.59397 -388.703044)
			(xy 114.608795 -388.657405) (xy 114.630577 -388.614648) (xy 114.658781 -388.575826) (xy 114.692711 -388.541894)
			(xy 114.731531 -388.513688) (xy 114.774287 -388.491903) (xy 114.819924 -388.477075) (xy 114.867319 -388.469569)
			(xy 114.891312 -388.469124) (xy 114.915247 -388.469594) (xy 114.962533 -388.477047) (xy 115.008077 -388.491786)
			(xy 115.050765 -388.513448) (xy 115.089551 -388.541504) (xy 115.123486 -388.575267) (xy 115.151739 -388.61391)
			(xy 115.163092 -388.634986) (xy 115.1636 -388.636002) (xy 115.243906 -388.77494) (xy 115.7859 -388.77494)
			(xy 115.7859 -388.774432) (xy 115.786368 -388.750439) (xy 115.79387 -388.703044) (xy 115.808695 -388.657406)
			(xy 115.830477 -388.61465) (xy 115.85868 -388.575827) (xy 115.892609 -388.541895) (xy 115.931429 -388.513689)
			(xy 115.974184 -388.491904) (xy 116.019821 -388.477076) (xy 116.067215 -388.46957) (xy 116.091208 -388.469124)
			(xy 116.115143 -388.469597) (xy 116.162429 -388.47705) (xy 116.207973 -388.491788) (xy 116.250661 -388.51345)
			(xy 116.289447 -388.541505) (xy 116.323382 -388.575268) (xy 116.351635 -388.61391) (xy 116.362988 -388.634986)
			(xy 116.363496 -388.636002) (xy 116.443802 -388.77494) (xy 116.985796 -388.77494) (xy 116.985796 -388.774432)
			(xy 116.986268 -388.75044) (xy 116.99377 -388.703045) (xy 117.008594 -388.657407) (xy 117.030376 -388.614651)
			(xy 117.058578 -388.575829) (xy 117.092507 -388.541897) (xy 117.131327 -388.513691) (xy 117.174081 -388.491905)
			(xy 117.219717 -388.477076) (xy 117.267112 -388.46957) (xy 117.291104 -388.469124) (xy 117.315039 -388.4696)
			(xy 117.362324 -388.477053) (xy 117.407868 -388.49179) (xy 117.450556 -388.513451) (xy 117.489342 -388.541506)
			(xy 117.523277 -388.575268) (xy 117.551531 -388.61391) (xy 117.562884 -388.634986) (xy 117.563392 -388.636002)
			(xy 117.643698 -388.77494) (xy 118.185692 -388.77494) (xy 118.185692 -388.774432) (xy 118.186191 -388.750454)
			(xy 118.193684 -388.703088) (xy 118.208492 -388.657476) (xy 118.230249 -388.614741) (xy 118.258422 -388.575933)
			(xy 118.292315 -388.542008) (xy 118.331097 -388.513799) (xy 118.373812 -388.492002) (xy 118.41941 -388.477151)
			(xy 118.466769 -388.469614) (xy 118.490746 -388.469124) (xy 118.491254 -388.469124) (xy 118.51519 -388.46956)
			(xy 118.562478 -388.47702) (xy 118.608023 -388.491764) (xy 118.650711 -388.513432) (xy 118.689496 -388.541493)
			(xy 118.72343 -388.575261) (xy 118.751681 -388.613908) (xy 118.763034 -388.634986) (xy 118.763542 -388.636002)
			(xy 118.843848 -388.77494) (xy 119.385588 -388.77494) (xy 119.385588 -388.774432) (xy 119.386091 -388.750455)
			(xy 119.393584 -388.703089) (xy 119.408392 -388.657477) (xy 119.430149 -388.614742) (xy 119.45832 -388.575934)
			(xy 119.492213 -388.542009) (xy 119.530994 -388.513801) (xy 119.573709 -388.492003) (xy 119.619306 -388.477152)
			(xy 119.666665 -388.469614) (xy 119.690642 -388.469124) (xy 119.69115 -388.469124) (xy 119.715086 -388.469563)
			(xy 119.762373 -388.477022) (xy 119.807918 -388.491766) (xy 119.850606 -388.513434) (xy 119.889392 -388.541494)
			(xy 119.923326 -388.575262) (xy 119.951577 -388.613908) (xy 119.96293 -388.634986) (xy 119.963438 -388.636002)
			(xy 120.043744 -388.77494) (xy 120.585992 -388.77494) (xy 120.585992 -388.774432) (xy 120.586468 -388.75044)
			(xy 120.59397 -388.703045) (xy 120.608794 -388.657408) (xy 120.630575 -388.614652) (xy 120.658777 -388.57583)
			(xy 120.692706 -388.541898) (xy 120.731525 -388.513692) (xy 120.774279 -388.491906) (xy 120.819914 -388.477077)
			(xy 120.867308 -388.46957) (xy 120.8913 -388.469124) (xy 120.915235 -388.469603) (xy 120.96252 -388.477055)
			(xy 121.008064 -388.491792) (xy 121.050752 -388.513453) (xy 121.089538 -388.541507) (xy 121.123473 -388.575269)
			(xy 121.151726 -388.613911) (xy 121.16308 -388.634986) (xy 121.163588 -388.636002) (xy 121.243894 -388.77494)
			(xy 121.785888 -388.77494) (xy 121.785888 -388.774432) (xy 121.786368 -388.75044) (xy 121.79387 -388.703046)
			(xy 121.808693 -388.657409) (xy 121.830474 -388.614653) (xy 121.858676 -388.575831) (xy 121.892604 -388.5419)
			(xy 121.931423 -388.513693) (xy 121.974176 -388.491907) (xy 122.019811 -388.477078) (xy 122.067204 -388.469571)
			(xy 122.091196 -388.469124) (xy 122.115133 -388.469526) (xy 122.162423 -388.476992) (xy 122.207968 -388.491742)
			(xy 122.250656 -388.513416) (xy 122.289441 -388.541483) (xy 122.323374 -388.575255) (xy 122.351624 -388.613906)
			(xy 122.362976 -388.634986) (xy 122.363484 -388.636002) (xy 122.44379 -388.77494) (xy 122.985784 -388.77494)
			(xy 122.985784 -388.774432) (xy 122.986268 -388.75044) (xy 122.993769 -388.703046) (xy 123.008593 -388.65741)
			(xy 123.030374 -388.614654) (xy 123.058575 -388.575833) (xy 123.092502 -388.541901) (xy 123.13132 -388.513695)
			(xy 123.174073 -388.491908) (xy 123.219708 -388.477079) (xy 123.2671 -388.469571) (xy 123.291092 -388.469124)
			(xy 123.315029 -388.469529) (xy 123.362318 -388.476995) (xy 123.407864 -388.491745) (xy 123.450552 -388.513418)
			(xy 123.489337 -388.541484) (xy 123.52327 -388.575256) (xy 123.55152 -388.613906) (xy 123.562872 -388.634986)
			(xy 123.56338 -388.636002) (xy 123.643686 -388.77494) (xy 124.18568 -388.77494) (xy 124.18568 -388.774432)
			(xy 124.186191 -388.750455) (xy 124.193684 -388.70309) (xy 124.208491 -388.657479) (xy 124.230247 -388.614744)
			(xy 124.258418 -388.575937) (xy 124.29231 -388.542012) (xy 124.33109 -388.513803) (xy 124.373803 -388.492005)
			(xy 124.4194 -388.477154) (xy 124.466757 -388.469614) (xy 124.490734 -388.469124) (xy 124.491242 -388.469124)
			(xy 124.515178 -388.469569) (xy 124.562465 -388.477028) (xy 124.60801 -388.49177) (xy 124.650697 -388.513437)
			(xy 124.689483 -388.541496) (xy 124.723417 -388.575263) (xy 124.751669 -388.613909) (xy 124.763022 -388.634986)
			(xy 124.76353 -388.636002) (xy 124.843836 -388.77494) (xy 125.385576 -388.77494) (xy 125.385576 -388.774432)
			(xy 125.386091 -388.750455) (xy 125.393584 -388.70309) (xy 125.408391 -388.65748) (xy 125.430147 -388.614746)
			(xy 125.458317 -388.575938) (xy 125.492208 -388.542013) (xy 125.530988 -388.513805) (xy 125.573701 -388.492006)
			(xy 125.619296 -388.477155) (xy 125.666654 -388.469615) (xy 125.69063 -388.469124) (xy 125.691138 -388.469124)
			(xy 125.715074 -388.469573) (xy 125.762361 -388.47703) (xy 125.807905 -388.491772) (xy 125.850593 -388.513438)
			(xy 125.889379 -388.541498) (xy 125.923313 -388.575263) (xy 125.951565 -388.613909) (xy 125.962918 -388.634986)
			(xy 125.963426 -388.636002) (xy 126.043732 -388.77494) (xy 126.58598 -388.77494) (xy 126.58598 -388.774432)
			(xy 126.586468 -388.75044) (xy 126.593969 -388.703047) (xy 126.608793 -388.657411) (xy 126.630573 -388.614656)
			(xy 126.658774 -388.575834) (xy 126.692701 -388.541902) (xy 126.731518 -388.513696) (xy 126.77427 -388.49191)
			(xy 126.819904 -388.47708) (xy 126.867296 -388.469571) (xy 126.891288 -388.469124) (xy 126.915225 -388.469532)
			(xy 126.962514 -388.476997) (xy 127.00806 -388.491747) (xy 127.050747 -388.513419) (xy 127.089533 -388.541485)
			(xy 127.123466 -388.575256) (xy 127.151716 -388.613907) (xy 127.163068 -388.634986) (xy 127.163576 -388.636002)
			(xy 127.243882 -388.77494) (xy 127.785876 -388.77494) (xy 127.785876 -388.774432) (xy 127.786368 -388.750441)
			(xy 127.793869 -388.703048) (xy 127.808692 -388.657412) (xy 127.830472 -388.614657) (xy 127.858673 -388.575836)
			(xy 127.892599 -388.541904) (xy 127.931416 -388.513697) (xy 127.974167 -388.491911) (xy 128.019801 -388.47708)
			(xy 128.067193 -388.469571) (xy 128.091184 -388.469124) (xy 128.115121 -388.469535) (xy 128.16241 -388.477)
			(xy 128.207955 -388.491749) (xy 128.250643 -388.513421) (xy 128.289428 -388.541486) (xy 128.323361 -388.575257)
			(xy 128.351612 -388.613907) (xy 128.362964 -388.634986) (xy 128.363472 -388.636002) (xy 128.443778 -388.77494)
			(xy 128.985772 -388.77494) (xy 128.985772 -388.774432) (xy 128.986268 -388.750441) (xy 128.993769 -388.703048)
			(xy 129.008592 -388.657413) (xy 129.030372 -388.614658) (xy 129.058571 -388.575837) (xy 129.092497 -388.541905)
			(xy 129.131314 -388.513699) (xy 129.174065 -388.491912) (xy 129.219698 -388.477081) (xy 129.267089 -388.469572)
			(xy 129.29108 -388.469124) (xy 129.315017 -388.469539) (xy 129.362305 -388.477002) (xy 129.407851 -388.491751)
			(xy 129.450539 -388.513422) (xy 129.489324 -388.541487) (xy 129.523257 -388.575257) (xy 129.551508 -388.613907)
			(xy 129.56286 -388.634986) (xy 129.563368 -388.636002) (xy 129.643674 -388.77494) (xy 130.185668 -388.77494)
			(xy 130.185668 -388.774432) (xy 130.186191 -388.750456) (xy 130.193684 -388.703092) (xy 130.20849 -388.657482)
			(xy 130.230245 -388.614748) (xy 130.258415 -388.575941) (xy 130.292305 -388.542016) (xy 130.331083 -388.513807)
			(xy 130.373795 -388.492009) (xy 130.41939 -388.477156) (xy 130.466746 -388.469615) (xy 130.490722 -388.469124)
			(xy 130.49123 -388.469124) (xy 130.515165 -388.469579) (xy 130.562452 -388.477035) (xy 130.607997 -388.491776)
			(xy 130.650684 -388.513441) (xy 130.68947 -388.5415) (xy 130.723405 -388.575264) (xy 130.751657 -388.613909)
			(xy 130.76301 -388.634986) (xy 130.763518 -388.636002) (xy 130.843824 -388.77494) (xy 131.385564 -388.77494)
			(xy 131.385564 -388.774432) (xy 131.386091 -388.750456) (xy 131.393583 -388.703092) (xy 131.408389 -388.657483)
			(xy 131.430144 -388.614749) (xy 131.458313 -388.575943) (xy 131.492203 -388.542018) (xy 131.530981 -388.513809)
			(xy 131.573692 -388.49201) (xy 131.619286 -388.477157) (xy 131.666642 -388.469616) (xy 131.690618 -388.469124)
			(xy 131.691126 -388.469124) (xy 131.715061 -388.469582) (xy 131.762348 -388.477038) (xy 131.807892 -388.491778)
			(xy 131.85058 -388.513443) (xy 131.889366 -388.541501) (xy 131.923301 -388.575265) (xy 131.951553 -388.613909)
			(xy 131.962906 -388.634986) (xy 131.963414 -388.636002) (xy 132.04372 -388.77494) (xy 132.585968 -388.77494)
			(xy 132.585968 -388.774432) (xy 132.586468 -388.750441) (xy 132.593969 -388.703049) (xy 132.608792 -388.657414)
			(xy 132.630571 -388.614659) (xy 132.65877 -388.575838) (xy 132.692696 -388.541907) (xy 132.731511 -388.5137)
			(xy 132.774262 -388.491913) (xy 132.819894 -388.477082) (xy 132.867285 -388.469572) (xy 132.891276 -388.469124)
			(xy 132.915213 -388.469542) (xy 132.962501 -388.477005) (xy 133.008047 -388.491753) (xy 133.050734 -388.513424)
			(xy 133.08952 -388.541488) (xy 133.123453 -388.575258) (xy 133.151704 -388.613907) (xy 133.163056 -388.634986)
			(xy 133.163564 -388.636002) (xy 133.24387 -388.77494) (xy 147.113752 -388.77494) (xy 147.113752 -388.774432)
			(xy 147.114292 -388.750444) (xy 147.121792 -388.703057) (xy 147.136613 -388.657427) (xy 147.158389 -388.614677)
			(xy 147.186584 -388.57586) (xy 147.220505 -388.541931) (xy 147.259315 -388.513726) (xy 147.30206 -388.49194)
			(xy 147.347687 -388.477109) (xy 147.395072 -388.469598) (xy 147.41906 -388.469124) (xy 147.442996 -388.469555)
			(xy 147.490284 -388.477016) (xy 147.535829 -388.491761) (xy 147.578517 -388.51343) (xy 147.617303 -388.541492)
			(xy 147.651236 -388.57526) (xy 147.679488 -388.613908) (xy 147.69084 -388.634986) (xy 147.691348 -388.636002)
			(xy 147.771654 -388.77494) (xy 148.313648 -388.77494) (xy 148.313648 -388.774432) (xy 148.314192 -388.750444)
			(xy 148.321692 -388.703057) (xy 148.336512 -388.657428) (xy 148.358288 -388.614678) (xy 148.386483 -388.575861)
			(xy 148.420403 -388.541933) (xy 148.459213 -388.513728) (xy 148.501957 -388.491941) (xy 148.547583 -388.47711)
			(xy 148.594968 -388.469598) (xy 148.618956 -388.469124) (xy 148.642892 -388.469558) (xy 148.69018 -388.477018)
			(xy 148.735725 -388.491763) (xy 148.778413 -388.513431) (xy 148.817198 -388.541493) (xy 148.851132 -388.575261)
			(xy 148.879383 -388.613908) (xy 148.890736 -388.634986) (xy 148.891244 -388.636002) (xy 148.97155 -388.77494)
			(xy 149.513544 -388.77494) (xy 149.513544 -388.774432) (xy 149.514092 -388.750444) (xy 149.521592 -388.703058)
			(xy 149.536412 -388.657429) (xy 149.558187 -388.614679) (xy 149.586382 -388.575862) (xy 149.620301 -388.541934)
			(xy 149.659111 -388.513729) (xy 149.701855 -388.491943) (xy 149.74748 -388.477111) (xy 149.794864 -388.469598)
			(xy 149.818852 -388.469124) (xy 149.842788 -388.469561) (xy 149.890076 -388.477021) (xy 149.935621 -388.491765)
			(xy 149.978308 -388.513433) (xy 150.017094 -388.541494) (xy 150.051028 -388.575261) (xy 150.079279 -388.613908)
			(xy 150.090632 -388.634986) (xy 150.09114 -388.636002) (xy 150.171446 -388.77494) (xy 150.71344 -388.77494)
			(xy 150.71344 -388.774432) (xy 150.713891 -388.750452) (xy 150.721386 -388.703081) (xy 150.736197 -388.657465)
			(xy 150.757958 -388.614726) (xy 150.786136 -388.575917) (xy 150.820035 -388.54199) (xy 150.858823 -388.513783)
			(xy 150.901545 -388.491988) (xy 150.947149 -388.477142) (xy 150.994514 -388.46961) (xy 151.018494 -388.469124)
			(xy 151.019002 -388.469124) (xy 151.042937 -388.469602) (xy 151.090222 -388.477054) (xy 151.135766 -388.491791)
			(xy 151.178454 -388.513452) (xy 151.21724 -388.541507) (xy 151.251175 -388.575268) (xy 151.279429 -388.61391)
			(xy 151.290782 -388.634986) (xy 151.29129 -388.636002) (xy 151.371596 -388.77494) (xy 151.913336 -388.77494)
			(xy 151.913336 -388.774432) (xy 151.913791 -388.750452) (xy 151.921286 -388.703082) (xy 151.936096 -388.657466)
			(xy 151.957858 -388.614728) (xy 151.986034 -388.575918) (xy 152.019934 -388.541992) (xy 152.058721 -388.513784)
			(xy 152.101442 -388.491989) (xy 152.147046 -388.477143) (xy 152.19441 -388.46961) (xy 152.21839 -388.469124)
			(xy 152.218898 -388.469124) (xy 152.242835 -388.469524) (xy 152.290125 -388.476991) (xy 152.335671 -388.491741)
			(xy 152.378358 -388.513415) (xy 152.417143 -388.541482) (xy 152.451076 -388.575255) (xy 152.479326 -388.613906)
			(xy 152.490678 -388.634986) (xy 152.491186 -388.636002) (xy 152.571492 -388.77494) (xy 153.11374 -388.77494)
			(xy 153.11374 -388.774432) (xy 153.114168 -388.750437) (xy 153.121671 -388.703038) (xy 153.136498 -388.657397)
			(xy 153.158284 -388.614638) (xy 153.186491 -388.575814) (xy 153.220426 -388.541881) (xy 153.259251 -388.513676)
			(xy 153.302012 -388.491892) (xy 153.347654 -388.477068) (xy 153.395053 -388.469567) (xy 153.419048 -388.469124)
			(xy 153.442984 -388.469565) (xy 153.490271 -388.477024) (xy 153.535816 -388.491767) (xy 153.578504 -388.513434)
			(xy 153.61729 -388.541495) (xy 153.651224 -388.575262) (xy 153.679475 -388.613908) (xy 153.690828 -388.634986)
			(xy 153.691336 -388.636002) (xy 153.771642 -388.77494) (xy 154.313636 -388.77494) (xy 154.313636 -388.774432)
			(xy 154.314068 -388.750438) (xy 154.321571 -388.703039) (xy 154.336398 -388.657398) (xy 154.358183 -388.614639)
			(xy 154.38639 -388.575815) (xy 154.420324 -388.541882) (xy 154.459149 -388.513677) (xy 154.501909 -388.491893)
			(xy 154.547551 -388.477068) (xy 154.59495 -388.469567) (xy 154.618944 -388.469124) (xy 154.64288 -388.469568)
			(xy 154.690167 -388.477026) (xy 154.735712 -388.491769) (xy 154.7784 -388.513436) (xy 154.817185 -388.541496)
			(xy 154.851119 -388.575262) (xy 154.879371 -388.613909) (xy 154.890724 -388.634986) (xy 154.891232 -388.636002)
			(xy 154.971538 -388.77494) (xy 155.513532 -388.77494) (xy 155.513532 -388.774432) (xy 155.513968 -388.750438)
			(xy 155.521471 -388.703039) (xy 155.536298 -388.657399) (xy 155.558083 -388.61464) (xy 155.586289 -388.575816)
			(xy 155.620222 -388.541884) (xy 155.659047 -388.513678) (xy 155.701806 -388.491895) (xy 155.747447 -388.477069)
			(xy 155.794846 -388.469567) (xy 155.81884 -388.469124) (xy 155.842776 -388.469571) (xy 155.890063 -388.477029)
			(xy 155.935608 -388.491771) (xy 155.978295 -388.513437) (xy 156.017081 -388.541497) (xy 156.051015 -388.575263)
			(xy 156.079267 -388.613909) (xy 156.09062 -388.634986) (xy 156.091128 -388.636002) (xy 156.171434 -388.77494)
			(xy 156.713428 -388.77494) (xy 156.713428 -388.774432) (xy 156.713891 -388.750453) (xy 156.721386 -388.703083)
			(xy 156.736196 -388.657468) (xy 156.757956 -388.61473) (xy 156.786132 -388.575921) (xy 156.82003 -388.541995)
			(xy 156.858817 -388.513787) (xy 156.901537 -388.491991) (xy 156.947139 -388.477144) (xy 156.994503 -388.469611)
			(xy 157.018482 -388.469124) (xy 157.01899 -388.469124) (xy 157.042927 -388.46953) (xy 157.090216 -388.476996)
			(xy 157.135762 -388.491746) (xy 157.17845 -388.513419) (xy 157.217235 -388.541484) (xy 157.251168 -388.575256)
			(xy 157.279418 -388.613907) (xy 157.29077 -388.634986) (xy 157.291278 -388.636002) (xy 157.371584 -388.77494)
			(xy 157.913324 -388.77494) (xy 157.913324 -388.774432) (xy 157.913791 -388.750453) (xy 157.921286 -388.703083)
			(xy 157.936095 -388.657469) (xy 157.957855 -388.614731) (xy 157.986031 -388.575922) (xy 158.019929 -388.541996)
			(xy 158.058714 -388.513788) (xy 158.101434 -388.491993) (xy 158.147036 -388.477145) (xy 158.194399 -388.469611)
			(xy 158.218378 -388.469124) (xy 158.218886 -388.469124) (xy 158.242823 -388.469534) (xy 158.290112 -388.476998)
			(xy 158.335657 -388.491748) (xy 158.378345 -388.51342) (xy 158.41713 -388.541485) (xy 158.451064 -388.575256)
			(xy 158.479314 -388.613907) (xy 158.490666 -388.634986) (xy 158.491174 -388.636002) (xy 158.57148 -388.77494)
			(xy 159.113728 -388.77494) (xy 159.113728 -388.774432) (xy 159.114168 -388.750438) (xy 159.121671 -388.70304)
			(xy 159.136497 -388.6574) (xy 159.158282 -388.614641) (xy 159.186488 -388.575818) (xy 159.220421 -388.541885)
			(xy 159.259245 -388.51368) (xy 159.302004 -388.491896) (xy 159.347644 -388.47707) (xy 159.395042 -388.469568)
			(xy 159.419036 -388.469124) (xy 159.442972 -388.469574) (xy 159.490258 -388.477031) (xy 159.535803 -388.491773)
			(xy 159.578491 -388.513439) (xy 159.617277 -388.541498) (xy 159.651211 -388.575264) (xy 159.679463 -388.613909)
			(xy 159.690816 -388.634986) (xy 159.691324 -388.636002) (xy 159.77163 -388.77494) (xy 160.313624 -388.77494)
			(xy 160.313624 -388.774432) (xy 160.314068 -388.750438) (xy 160.321571 -388.703041) (xy 160.336397 -388.657401)
			(xy 160.358181 -388.614643) (xy 160.386387 -388.575819) (xy 160.420319 -388.541887) (xy 160.459143 -388.513681)
			(xy 160.501901 -388.491897) (xy 160.547541 -388.477071) (xy 160.594938 -388.469568) (xy 160.618932 -388.469124)
			(xy 160.642868 -388.469578) (xy 160.690154 -388.477034) (xy 160.735699 -388.491775) (xy 160.778387 -388.51344)
			(xy 160.817172 -388.541499) (xy 160.851107 -388.575264) (xy 160.879359 -388.613909) (xy 160.890712 -388.634986)
			(xy 160.89122 -388.636002) (xy 160.971526 -388.77494) (xy 161.51352 -388.77494) (xy 161.51352 -388.774432)
			(xy 161.513968 -388.750438) (xy 161.521471 -388.703041) (xy 161.536297 -388.657402) (xy 161.55808 -388.614644)
			(xy 161.586286 -388.57582) (xy 161.620217 -388.541888) (xy 161.65904 -388.513682) (xy 161.701798 -388.491898)
			(xy 161.747437 -388.477072) (xy 161.794834 -388.469568) (xy 161.818828 -388.469124) (xy 161.842763 -388.469581)
			(xy 161.89005 -388.477037) (xy 161.935595 -388.491777) (xy 161.978282 -388.513442) (xy 162.017068 -388.5415)
			(xy 162.051003 -388.575265) (xy 162.079255 -388.613909) (xy 162.090608 -388.634986) (xy 162.091116 -388.636002)
			(xy 162.171422 -388.77494) (xy 162.713416 -388.77494) (xy 162.713416 -388.774432) (xy 162.713891 -388.750453)
			(xy 162.721385 -388.703085) (xy 162.736194 -388.657471) (xy 162.757954 -388.614734) (xy 162.786129 -388.575925)
			(xy 162.820025 -388.541999) (xy 162.85881 -388.513791) (xy 162.901528 -388.491995) (xy 162.947129 -388.477147)
			(xy 162.994492 -388.469612) (xy 163.01847 -388.469124) (xy 163.018978 -388.469124) (xy 163.042915 -388.46954)
			(xy 163.090203 -388.477004) (xy 163.135749 -388.491752) (xy 163.178437 -388.513423) (xy 163.217222 -388.541487)
			(xy 163.251155 -388.575258) (xy 163.279406 -388.613907) (xy 163.290758 -388.634986) (xy 163.291266 -388.636002)
			(xy 163.371572 -388.77494) (xy 163.913312 -388.77494) (xy 163.913312 -388.774432) (xy 163.913791 -388.750453)
			(xy 163.921285 -388.703085) (xy 163.936094 -388.657472) (xy 163.957853 -388.614735) (xy 163.986027 -388.575926)
			(xy 164.019924 -388.542) (xy 164.058708 -388.513792) (xy 164.101425 -388.491996) (xy 164.147026 -388.477147)
			(xy 164.194388 -388.469612) (xy 164.218366 -388.469124) (xy 164.218874 -388.469124) (xy 164.242811 -388.469543)
			(xy 164.290099 -388.477006) (xy 164.335644 -388.491754) (xy 164.378332 -388.513425) (xy 164.417118 -388.541488)
			(xy 164.451051 -388.575258) (xy 164.479302 -388.613907) (xy 164.490654 -388.634986) (xy 164.491162 -388.636002)
			(xy 164.571468 -388.77494) (xy 165.113716 -388.77494) (xy 165.113716 -388.774432) (xy 165.114168 -388.750439)
			(xy 165.121671 -388.703042) (xy 165.136496 -388.657403) (xy 165.15828 -388.614645) (xy 165.186484 -388.575822)
			(xy 165.220416 -388.54189) (xy 165.259238 -388.513684) (xy 165.301995 -388.491899) (xy 165.347634 -388.477072)
			(xy 165.395031 -388.469568) (xy 165.419024 -388.469124) (xy 165.442959 -388.469584) (xy 165.490246 -388.477039)
			(xy 165.53579 -388.491779) (xy 165.578478 -388.513444) (xy 165.617264 -388.541501) (xy 165.651198 -388.575265)
			(xy 165.679451 -388.61391) (xy 165.690804 -388.634986) (xy 165.691312 -388.636002) (xy 165.744132 -388.727385)
			(xy 193.900548 -388.727385) (xy 193.900548 -388.642663) (xy 193.908601 -388.558326) (xy 193.924635 -388.475136)
			(xy 193.948503 -388.393846) (xy 193.979991 -388.315194) (xy 194.018813 -388.239891) (xy 194.064616 -388.168619)
			(xy 194.116987 -388.102023) (xy 194.175452 -388.040708) (xy 194.23948 -387.985227) (xy 194.308492 -387.936084)
			(xy 194.381862 -387.893724) (xy 194.458927 -387.858529) (xy 194.538989 -387.83082) (xy 194.621322 -387.810846)
			(xy 194.705181 -387.798789) (xy 194.789806 -387.794758) (xy 194.874431 -387.798789) (xy 194.95829 -387.810846)
			(xy 195.040623 -387.83082) (xy 195.120685 -387.858529) (xy 195.19775 -387.893724) (xy 195.27112 -387.936084)
			(xy 195.340132 -387.985227) (xy 195.40416 -388.040708) (xy 195.462625 -388.102023) (xy 195.514996 -388.168619)
			(xy 195.560799 -388.239891) (xy 195.599621 -388.315194) (xy 195.631109 -388.393846) (xy 195.654977 -388.475136)
			(xy 195.671011 -388.558326) (xy 195.679064 -388.642663) (xy 195.679568 -388.685024) (xy 195.679064 -388.727385)
			(xy 195.671011 -388.811722) (xy 195.654977 -388.894912) (xy 195.631109 -388.976202) (xy 195.599621 -389.054854)
			(xy 195.560799 -389.130157) (xy 195.514996 -389.201429) (xy 195.462625 -389.268025) (xy 195.40416 -389.32934)
			(xy 195.340132 -389.384821) (xy 195.27112 -389.433964) (xy 195.19775 -389.476324) (xy 195.120685 -389.511519)
			(xy 195.040623 -389.539228) (xy 194.95829 -389.559202) (xy 194.874431 -389.571259) (xy 194.789806 -389.575291)
			(xy 194.705181 -389.571259) (xy 194.621322 -389.559202) (xy 194.538989 -389.539228) (xy 194.458927 -389.511519)
			(xy 194.381862 -389.476324) (xy 194.308492 -389.433964) (xy 194.23948 -389.384821) (xy 194.175452 -389.32934)
			(xy 194.116987 -389.268025) (xy 194.064616 -389.201429) (xy 194.018813 -389.130157) (xy 193.979991 -389.054854)
			(xy 193.948503 -388.976202) (xy 193.924635 -388.894912) (xy 193.908601 -388.811722) (xy 193.900548 -388.727385)
			(xy 165.744132 -388.727385) (xy 166.083742 -389.314944) (xy 166.096549 -389.338286) (xy 166.114776 -389.388304)
			(xy 166.124043 -389.440727) (xy 166.124636 -389.467344) (xy 166.124179 -389.491322) (xy 166.116675 -389.538688)
			(xy 166.101859 -389.584299) (xy 166.080095 -389.627033) (xy 166.051917 -389.665839) (xy 166.01802 -389.699762)
			(xy 165.979236 -389.72797) (xy 165.936519 -389.749768) (xy 165.89092 -389.76462) (xy 165.84356 -389.77216)
			(xy 165.819582 -389.772652) (xy 165.819074 -389.772652) (xy 165.795501 -389.772252) (xy 165.748914 -389.765008)
			(xy 165.703997 -389.750681) (xy 165.66182 -389.729613) (xy 165.623387 -389.702305) (xy 165.589614 -389.669408)
			(xy 165.561306 -389.631706) (xy 165.549834 -389.611108) (xy 165.549326 -389.610346) (xy 165.151562 -388.922006)
			(xy 165.139686 -388.899329) (xy 165.122835 -388.850996) (xy 165.114262 -388.800533) (xy 165.113716 -388.77494)
			(xy 164.571468 -388.77494) (xy 164.883592 -389.314944) (xy 164.896306 -389.338272) (xy 164.914407 -389.388215)
			(xy 164.923631 -389.44053) (xy 164.924232 -389.46709) (xy 164.924232 -389.467344) (xy 164.923778 -389.491335)
			(xy 164.916266 -389.538726) (xy 164.901434 -389.584359) (xy 164.879647 -389.62711) (xy 164.851442 -389.665927)
			(xy 164.817512 -389.699855) (xy 164.778693 -389.728058) (xy 164.73594 -389.749842) (xy 164.690307 -389.764671)
			(xy 164.642915 -389.77218) (xy 164.618924 -389.772652) (xy 164.595352 -389.772211) (xy 164.548767 -389.764975)
			(xy 164.503851 -389.750656) (xy 164.461674 -389.729594) (xy 164.423241 -389.702292) (xy 164.389467 -389.669401)
			(xy 164.361157 -389.631704) (xy 164.349684 -389.611108) (xy 164.349176 -389.610346) (xy 163.951412 -388.922006)
			(xy 163.939498 -388.899337) (xy 163.92256 -388.851012) (xy 163.9139 -388.800542) (xy 163.913312 -388.77494)
			(xy 163.371572 -388.77494) (xy 163.683696 -389.314944) (xy 163.69641 -389.338271) (xy 163.714511 -389.388215)
			(xy 163.723735 -389.44053) (xy 163.724336 -389.46709) (xy 163.724336 -389.467344) (xy 163.723878 -389.491335)
			(xy 163.716366 -389.538726) (xy 163.701535 -389.584358) (xy 163.679748 -389.627109) (xy 163.651543 -389.665926)
			(xy 163.617613 -389.699853) (xy 163.578795 -389.728056) (xy 163.536043 -389.749841) (xy 163.49041 -389.76467)
			(xy 163.443019 -389.772179) (xy 163.419028 -389.772652) (xy 163.395456 -389.772208) (xy 163.348872 -389.764972)
			(xy 163.303956 -389.750653) (xy 163.261778 -389.729592) (xy 163.223345 -389.702291) (xy 163.189571 -389.6694)
			(xy 163.161261 -389.631704) (xy 163.149788 -389.611108) (xy 163.14928 -389.610346) (xy 162.751516 -388.922006)
			(xy 162.739602 -388.899337) (xy 162.722664 -388.851012) (xy 162.714004 -388.800542) (xy 162.713416 -388.77494)
			(xy 162.171422 -388.77494) (xy 162.483546 -389.314944) (xy 162.496353 -389.338286) (xy 162.51458 -389.388304)
			(xy 162.523847 -389.440727) (xy 162.52444 -389.467344) (xy 162.523979 -389.491322) (xy 162.516475 -389.538688)
			(xy 162.501659 -389.584298) (xy 162.479895 -389.627032) (xy 162.451718 -389.665837) (xy 162.417822 -389.699761)
			(xy 162.379038 -389.727969) (xy 162.336322 -389.749767) (xy 162.290724 -389.764619) (xy 162.243364 -389.77216)
			(xy 162.219386 -389.772652) (xy 162.218878 -389.772652) (xy 162.195305 -389.772249) (xy 162.148718 -389.765005)
			(xy 162.103801 -389.750679) (xy 162.061624 -389.729611) (xy 162.023191 -389.702304) (xy 161.989418 -389.669408)
			(xy 161.96111 -389.631706) (xy 161.949638 -389.611108) (xy 161.94913 -389.610346) (xy 161.551366 -388.922006)
			(xy 161.539491 -388.899329) (xy 161.522639 -388.850996) (xy 161.514066 -388.800533) (xy 161.51352 -388.77494)
			(xy 160.971526 -388.77494) (xy 161.28365 -389.314944) (xy 161.296457 -389.338285) (xy 161.314684 -389.388304)
			(xy 161.323951 -389.440726) (xy 161.324544 -389.467344) (xy 161.324079 -389.491322) (xy 161.316576 -389.538687)
			(xy 161.30176 -389.584297) (xy 161.279996 -389.62703) (xy 161.25182 -389.665836) (xy 161.217923 -389.69976)
			(xy 161.17914 -389.727967) (xy 161.136425 -389.749765) (xy 161.090827 -389.764618) (xy 161.043468 -389.77216)
			(xy 161.01949 -389.772652) (xy 161.018982 -389.772652) (xy 160.995409 -389.772245) (xy 160.948822 -389.765003)
			(xy 160.903906 -389.750677) (xy 160.861728 -389.72961) (xy 160.823295 -389.702303) (xy 160.789523 -389.669407)
			(xy 160.761214 -389.631706) (xy 160.749742 -389.611108) (xy 160.749234 -389.610346) (xy 160.35147 -388.922006)
			(xy 160.339595 -388.899329) (xy 160.322743 -388.850996) (xy 160.31417 -388.800533) (xy 160.313624 -388.77494)
			(xy 159.77163 -388.77494) (xy 160.083754 -389.314944) (xy 160.096562 -389.338285) (xy 160.114788 -389.388304)
			(xy 160.124055 -389.440726) (xy 160.124648 -389.467344) (xy 160.124179 -389.491322) (xy 160.116676 -389.538687)
			(xy 160.10186 -389.584296) (xy 160.080097 -389.627029) (xy 160.051921 -389.665835) (xy 160.018025 -389.699758)
			(xy 159.979243 -389.727966) (xy 159.936528 -389.749764) (xy 159.89093 -389.764617) (xy 159.843571 -389.772159)
			(xy 159.819594 -389.772652) (xy 159.819086 -389.772652) (xy 159.795513 -389.772242) (xy 159.748927 -389.765)
			(xy 159.70401 -389.750675) (xy 159.661833 -389.729608) (xy 159.6234 -389.702302) (xy 159.589627 -389.669406)
			(xy 159.561319 -389.631705) (xy 159.549846 -389.611108) (xy 159.549338 -389.610346) (xy 159.151574 -388.922006)
			(xy 159.139699 -388.899329) (xy 159.122848 -388.850996) (xy 159.114274 -388.800533) (xy 159.113728 -388.77494)
			(xy 158.57148 -388.77494) (xy 158.883604 -389.314944) (xy 158.896319 -389.338271) (xy 158.91442 -389.388214)
			(xy 158.923643 -389.44053) (xy 158.924244 -389.46709) (xy 158.924244 -389.467344) (xy 158.923778 -389.491335)
			(xy 158.916267 -389.538724) (xy 158.901435 -389.584356) (xy 158.879649 -389.627106) (xy 158.851445 -389.665923)
			(xy 158.817517 -389.69985) (xy 158.778699 -389.728054) (xy 158.735949 -389.749838) (xy 158.690317 -389.764668)
			(xy 158.642927 -389.772179) (xy 158.618936 -389.772652) (xy 158.595364 -389.772202) (xy 158.54878 -389.764967)
			(xy 158.503864 -389.750649) (xy 158.461687 -389.729589) (xy 158.423253 -389.702289) (xy 158.389479 -389.669399)
			(xy 158.361169 -389.631703) (xy 158.349696 -389.611108) (xy 158.349188 -389.610346) (xy 157.951424 -388.922006)
			(xy 157.939511 -388.899337) (xy 157.922572 -388.851012) (xy 157.913912 -388.800542) (xy 157.913324 -388.77494)
			(xy 157.371584 -388.77494) (xy 157.683708 -389.314944) (xy 157.696423 -389.338271) (xy 157.714524 -389.388214)
			(xy 157.723747 -389.44053) (xy 157.724348 -389.46709) (xy 157.724348 -389.467344) (xy 157.723878 -389.491334)
			(xy 157.716367 -389.538724) (xy 157.701536 -389.584355) (xy 157.67975 -389.627105) (xy 157.651546 -389.665922)
			(xy 157.617618 -389.699849) (xy 157.578802 -389.728052) (xy 157.536051 -389.749837) (xy 157.49042 -389.764668)
			(xy 157.44303 -389.772178) (xy 157.41904 -389.772652) (xy 157.395469 -389.772199) (xy 157.348884 -389.764965)
			(xy 157.303969 -389.750647) (xy 157.261791 -389.729588) (xy 157.223358 -389.702288) (xy 157.189583 -389.669399)
			(xy 157.161273 -389.631703) (xy 157.1498 -389.611108) (xy 157.149292 -389.610346) (xy 156.751528 -388.922006)
			(xy 156.739615 -388.899337) (xy 156.722676 -388.851012) (xy 156.714016 -388.800542) (xy 156.713428 -388.77494)
			(xy 156.171434 -388.77494) (xy 156.483558 -389.314944) (xy 156.496366 -389.338285) (xy 156.514592 -389.388304)
			(xy 156.523859 -389.440726) (xy 156.524452 -389.467344) (xy 156.523979 -389.491322) (xy 156.516476 -389.538686)
			(xy 156.501661 -389.584295) (xy 156.479898 -389.627028) (xy 156.451722 -389.665833) (xy 156.417827 -389.699757)
			(xy 156.379045 -389.727965) (xy 156.33633 -389.749763) (xy 156.290733 -389.764616) (xy 156.243375 -389.772159)
			(xy 156.219398 -389.772652) (xy 156.21889 -389.772652) (xy 156.195317 -389.772239) (xy 156.148731 -389.764997)
			(xy 156.103814 -389.750673) (xy 156.061637 -389.729607) (xy 156.023204 -389.702301) (xy 155.989431 -389.669406)
			(xy 155.961123 -389.631705) (xy 155.94965 -389.611108) (xy 155.949142 -389.610346) (xy 155.551378 -388.922006)
			(xy 155.539503 -388.899328) (xy 155.522652 -388.850996) (xy 155.514078 -388.800533) (xy 155.513532 -388.77494)
			(xy 154.971538 -388.77494) (xy 155.283662 -389.314944) (xy 155.29647 -389.338285) (xy 155.314696 -389.388304)
			(xy 155.323963 -389.440726) (xy 155.324556 -389.467344) (xy 155.324079 -389.491321) (xy 155.316576 -389.538686)
			(xy 155.301761 -389.584295) (xy 155.279998 -389.627027) (xy 155.251823 -389.665832) (xy 155.217928 -389.699755)
			(xy 155.179147 -389.727963) (xy 155.136433 -389.749762) (xy 155.090837 -389.764616) (xy 155.043479 -389.772159)
			(xy 155.019502 -389.772652) (xy 155.018994 -389.772652) (xy 154.995421 -389.772236) (xy 154.948835 -389.764995)
			(xy 154.903919 -389.750671) (xy 154.861741 -389.729605) (xy 154.823308 -389.7023) (xy 154.789535 -389.669405)
			(xy 154.761227 -389.631705) (xy 154.749754 -389.611108) (xy 154.749246 -389.610346) (xy 154.351482 -388.922006)
			(xy 154.339608 -388.899328) (xy 154.322756 -388.850996) (xy 154.314182 -388.800533) (xy 154.313636 -388.77494)
			(xy 153.771642 -388.77494) (xy 154.083766 -389.314944) (xy 154.096575 -389.338285) (xy 154.1148 -389.388303)
			(xy 154.124067 -389.440726) (xy 154.12466 -389.467344) (xy 154.124279 -389.491326) (xy 154.116773 -389.5387)
			(xy 154.101952 -389.584317) (xy 154.080181 -389.627055) (xy 154.051995 -389.665865) (xy 154.018088 -389.69979)
			(xy 153.979294 -389.727996) (xy 153.936567 -389.74979) (xy 153.890957 -389.764635) (xy 153.843588 -389.772166)
			(xy 153.819606 -389.772652) (xy 153.819098 -389.772652) (xy 153.795525 -389.772232) (xy 153.74894 -389.764992)
			(xy 153.704023 -389.750669) (xy 153.661846 -389.729604) (xy 153.623413 -389.702299) (xy 153.589639 -389.669405)
			(xy 153.561331 -389.631705) (xy 153.549858 -389.611108) (xy 153.54935 -389.610346) (xy 153.151586 -388.922006)
			(xy 153.139712 -388.899328) (xy 153.12286 -388.850996) (xy 153.114286 -388.800533) (xy 153.11374 -388.77494)
			(xy 152.571492 -388.77494) (xy 152.883616 -389.314944) (xy 152.896332 -389.338271) (xy 152.914432 -389.388214)
			(xy 152.923655 -389.44053) (xy 152.924256 -389.46709) (xy 152.924256 -389.467344) (xy 152.923778 -389.491334)
			(xy 152.916267 -389.538723) (xy 152.901436 -389.584353) (xy 152.879652 -389.627103) (xy 152.851449 -389.665919)
			(xy 152.817522 -389.699846) (xy 152.778706 -389.72805) (xy 152.735957 -389.749835) (xy 152.690327 -389.764666)
			(xy 152.642938 -389.772178) (xy 152.618948 -389.772652) (xy 152.595377 -389.772192) (xy 152.548793 -389.764959)
			(xy 152.503877 -389.750643) (xy 152.4617 -389.729585) (xy 152.423266 -389.702286) (xy 152.389492 -389.669398)
			(xy 152.361182 -389.631703) (xy 152.349708 -389.611108) (xy 152.3492 -389.610346) (xy 151.951436 -388.922006)
			(xy 151.939523 -388.899336) (xy 151.922584 -388.851012) (xy 151.913924 -388.800542) (xy 151.913336 -388.77494)
			(xy 151.371596 -388.77494) (xy 151.68372 -389.314944) (xy 151.696436 -389.33827) (xy 151.714536 -389.388214)
			(xy 151.723759 -389.44053) (xy 151.72436 -389.46709) (xy 151.72436 -389.467344) (xy 151.724002 -389.491341)
			(xy 151.716487 -389.538742) (xy 151.70165 -389.584385) (xy 151.679855 -389.627144) (xy 151.651639 -389.665968)
			(xy 151.617698 -389.699899) (xy 151.578866 -389.728103) (xy 151.5361 -389.749885) (xy 151.490453 -389.764709)
			(xy 151.443049 -389.772209) (xy 151.419052 -389.772652) (xy 151.395481 -389.772189) (xy 151.348897 -389.764957)
			(xy 151.303982 -389.750641) (xy 151.261804 -389.729583) (xy 151.223371 -389.702285) (xy 151.189596 -389.669397)
			(xy 151.161286 -389.631703) (xy 151.149812 -389.611108) (xy 151.149304 -389.610346) (xy 150.75154 -388.922006)
			(xy 150.739628 -388.899336) (xy 150.722688 -388.851012) (xy 150.714028 -388.800542) (xy 150.71344 -388.77494)
			(xy 150.171446 -388.77494) (xy 150.48357 -389.314944) (xy 150.496379 -389.338285) (xy 150.514604 -389.388303)
			(xy 150.523871 -389.440726) (xy 150.524464 -389.467344) (xy 150.524079 -389.491326) (xy 150.516573 -389.538699)
			(xy 150.501752 -389.584316) (xy 150.479981 -389.627054) (xy 150.451796 -389.665863) (xy 150.41789 -389.699788)
			(xy 150.379096 -389.727994) (xy 150.336369 -389.749788) (xy 150.290761 -389.764634) (xy 150.243392 -389.772166)
			(xy 150.21941 -389.772652) (xy 150.218902 -389.772652) (xy 150.195329 -389.772229) (xy 150.148744 -389.76499)
			(xy 150.103827 -389.750667) (xy 150.06165 -389.729602) (xy 150.023217 -389.702298) (xy 149.989444 -389.669404)
			(xy 149.961135 -389.631705) (xy 149.949662 -389.611108) (xy 149.949154 -389.610346) (xy 149.55139 -388.922006)
			(xy 149.539516 -388.899328) (xy 149.522664 -388.850995) (xy 149.51409 -388.800533) (xy 149.513544 -388.77494)
			(xy 148.97155 -388.77494) (xy 149.283674 -389.314944) (xy 149.296483 -389.338284) (xy 149.314708 -389.388303)
			(xy 149.323975 -389.440726) (xy 149.324568 -389.467344) (xy 149.324179 -389.491326) (xy 149.316673 -389.538698)
			(xy 149.301852 -389.584315) (xy 149.280082 -389.627053) (xy 149.251897 -389.665862) (xy 149.217991 -389.699787)
			(xy 149.179198 -389.727993) (xy 149.136472 -389.749787) (xy 149.090864 -389.764633) (xy 149.043495 -389.772165)
			(xy 149.019514 -389.772652) (xy 149.019006 -389.772652) (xy 148.995434 -389.772226) (xy 148.948848 -389.764987)
			(xy 148.903932 -389.750665) (xy 148.861754 -389.729601) (xy 148.823321 -389.702297) (xy 148.789548 -389.669404)
			(xy 148.761239 -389.631705) (xy 148.749766 -389.611108) (xy 148.749258 -389.610346) (xy 148.351494 -388.922006)
			(xy 148.339621 -388.899328) (xy 148.322768 -388.850995) (xy 148.314194 -388.800532) (xy 148.313648 -388.77494)
			(xy 147.771654 -388.77494) (xy 148.083778 -389.314944) (xy 148.096588 -389.338284) (xy 148.114813 -389.388303)
			(xy 148.124079 -389.440726) (xy 148.124672 -389.467344) (xy 148.124279 -389.491326) (xy 148.116773 -389.538698)
			(xy 148.101953 -389.584314) (xy 148.080183 -389.627052) (xy 148.051999 -389.665861) (xy 148.018093 -389.699785)
			(xy 147.9793 -389.727992) (xy 147.936575 -389.749786) (xy 147.890967 -389.764632) (xy 147.843599 -389.772165)
			(xy 147.819618 -389.772652) (xy 147.81911 -389.772652) (xy 147.795538 -389.772223) (xy 147.748952 -389.764984)
			(xy 147.704036 -389.750663) (xy 147.661859 -389.729599) (xy 147.623425 -389.702296) (xy 147.589652 -389.669403)
			(xy 147.561343 -389.631704) (xy 147.54987 -389.611108) (xy 147.549362 -389.610346) (xy 147.151598 -388.922006)
			(xy 147.139725 -388.899328) (xy 147.122872 -388.850995) (xy 147.114298 -388.800532) (xy 147.113752 -388.77494)
			(xy 133.24387 -388.77494) (xy 133.555994 -389.314944) (xy 133.568805 -389.338283) (xy 133.587029 -389.388303)
			(xy 133.596295 -389.440726) (xy 133.596888 -389.467344) (xy 133.596479 -389.491325) (xy 133.588974 -389.538695)
			(xy 133.574154 -389.58431) (xy 133.552386 -389.627047) (xy 133.524203 -389.665855) (xy 133.4903 -389.69978)
			(xy 133.451509 -389.727986) (xy 133.408786 -389.749782) (xy 133.36318 -389.764629) (xy 133.315814 -389.772164)
			(xy 133.291834 -389.772652) (xy 133.291326 -389.772652) (xy 133.267754 -389.77221) (xy 133.221169 -389.764974)
			(xy 133.176253 -389.750654) (xy 133.134076 -389.729593) (xy 133.095643 -389.702292) (xy 133.061869 -389.669401)
			(xy 133.033559 -389.631704) (xy 133.022086 -389.611108) (xy 133.021578 -389.610346) (xy 132.623814 -388.922006)
			(xy 132.611935 -388.899331) (xy 132.595086 -388.850997) (xy 132.586514 -388.800533) (xy 132.585968 -388.77494)
			(xy 132.04372 -388.77494) (xy 132.355844 -389.314944) (xy 132.368562 -389.338269) (xy 132.386661 -389.388214)
			(xy 132.395883 -389.44053) (xy 132.396484 -389.46709) (xy 132.396484 -389.467344) (xy 132.396078 -389.491338)
			(xy 132.388564 -389.538733) (xy 132.37373 -389.58437) (xy 132.351938 -389.627124) (xy 132.323728 -389.665943)
			(xy 132.289792 -389.699872) (xy 132.250966 -389.728074) (xy 132.208207 -389.749856) (xy 132.162567 -389.76468)
			(xy 132.11517 -389.772183) (xy 132.091176 -389.772652) (xy 132.067603 -389.77225) (xy 132.021016 -389.765007)
			(xy 131.976099 -389.75068) (xy 131.933922 -389.729612) (xy 131.895489 -389.702305) (xy 131.861716 -389.669408)
			(xy 131.833408 -389.631706) (xy 131.821936 -389.611108) (xy 131.821428 -389.610346) (xy 131.423664 -388.922006)
			(xy 131.411754 -388.899335) (xy 131.394814 -388.851011) (xy 131.386152 -388.800542) (xy 131.385564 -388.77494)
			(xy 130.843824 -388.77494) (xy 131.155948 -389.314944) (xy 131.168667 -389.338269) (xy 131.186765 -389.388214)
			(xy 131.195987 -389.44053) (xy 131.196588 -389.46709) (xy 131.196588 -389.467344) (xy 131.196178 -389.491337)
			(xy 131.188665 -389.538733) (xy 131.17383 -389.584369) (xy 131.152039 -389.627123) (xy 131.123829 -389.665942)
			(xy 131.089893 -389.69987) (xy 131.051068 -389.728073) (xy 131.00831 -389.749854) (xy 130.96267 -389.76468)
			(xy 130.915274 -389.772183) (xy 130.89128 -389.772652) (xy 130.867707 -389.772247) (xy 130.82112 -389.765004)
			(xy 130.776203 -389.750678) (xy 130.734026 -389.729611) (xy 130.695593 -389.702304) (xy 130.661821 -389.669407)
			(xy 130.633512 -389.631706) (xy 130.62204 -389.611108) (xy 130.621532 -389.610346) (xy 130.223768 -388.922006)
			(xy 130.211858 -388.899335) (xy 130.194918 -388.851011) (xy 130.186256 -388.800542) (xy 130.185668 -388.77494)
			(xy 129.643674 -388.77494) (xy 129.955798 -389.314944) (xy 129.968601 -389.338288) (xy 129.98683 -389.388305)
			(xy 129.996099 -389.440727) (xy 129.996692 -389.467344) (xy 129.996279 -389.491325) (xy 129.988774 -389.538695)
			(xy 129.973955 -389.584309) (xy 129.952187 -389.627046) (xy 129.924004 -389.665854) (xy 129.890101 -389.699778)
			(xy 129.851312 -389.727985) (xy 129.808589 -389.74978) (xy 129.762984 -389.764628) (xy 129.715618 -389.772164)
			(xy 129.691638 -389.772652) (xy 129.69113 -389.772652) (xy 129.667558 -389.772207) (xy 129.620974 -389.764971)
			(xy 129.576058 -389.750652) (xy 129.53388 -389.729592) (xy 129.495447 -389.702291) (xy 129.461673 -389.6694)
			(xy 129.433363 -389.631704) (xy 129.42189 -389.611108) (xy 129.421382 -389.610346) (xy 129.023618 -388.922006)
			(xy 129.011739 -388.899331) (xy 128.99489 -388.850997) (xy 128.986318 -388.800533) (xy 128.985772 -388.77494)
			(xy 128.443778 -388.77494) (xy 128.755902 -389.314944) (xy 128.768705 -389.338288) (xy 128.786934 -389.388305)
			(xy 128.796203 -389.440727) (xy 128.796796 -389.467344) (xy 128.796379 -389.491324) (xy 128.788874 -389.538694)
			(xy 128.774055 -389.584308) (xy 128.752287 -389.627045) (xy 128.724106 -389.665852) (xy 128.690203 -389.699777)
			(xy 128.651414 -389.727984) (xy 128.608692 -389.749779) (xy 128.563087 -389.764628) (xy 128.515722 -389.772163)
			(xy 128.491742 -389.772652) (xy 128.491234 -389.772652) (xy 128.467662 -389.772203) (xy 128.421078 -389.764969)
			(xy 128.376162 -389.75065) (xy 128.333985 -389.72959) (xy 128.295551 -389.70229) (xy 128.261777 -389.6694)
			(xy 128.233467 -389.631703) (xy 128.221994 -389.611108) (xy 128.221486 -389.610346) (xy 127.823722 -388.922006)
			(xy 127.811843 -388.899331) (xy 127.794994 -388.850996) (xy 127.786422 -388.800533) (xy 127.785876 -388.77494)
			(xy 127.243882 -388.77494) (xy 127.556006 -389.314944) (xy 127.56881 -389.338287) (xy 127.587038 -389.388304)
			(xy 127.596307 -389.440727) (xy 127.5969 -389.467344) (xy 127.596479 -389.491324) (xy 127.588974 -389.538694)
			(xy 127.574156 -389.584307) (xy 127.552388 -389.627044) (xy 127.524207 -389.665851) (xy 127.490305 -389.699775)
			(xy 127.451516 -389.727982) (xy 127.408794 -389.749778) (xy 127.36319 -389.764627) (xy 127.315826 -389.772163)
			(xy 127.291846 -389.772652) (xy 127.291338 -389.772652) (xy 127.267766 -389.7722) (xy 127.221182 -389.764966)
			(xy 127.176266 -389.750648) (xy 127.134089 -389.729589) (xy 127.095656 -389.702289) (xy 127.061881 -389.669399)
			(xy 127.033571 -389.631703) (xy 127.022098 -389.611108) (xy 127.02159 -389.610346) (xy 126.623826 -388.922006)
			(xy 126.611947 -388.89933) (xy 126.595098 -388.850996) (xy 126.586526 -388.800533) (xy 126.58598 -388.77494)
			(xy 126.043732 -388.77494) (xy 126.355856 -389.314944) (xy 126.368575 -389.338269) (xy 126.386673 -389.388214)
			(xy 126.395895 -389.440529) (xy 126.396496 -389.46709) (xy 126.396496 -389.467344) (xy 126.396078 -389.491337)
			(xy 126.388565 -389.538731) (xy 126.373731 -389.584367) (xy 126.351941 -389.627121) (xy 126.323731 -389.665939)
			(xy 126.289797 -389.699868) (xy 126.250973 -389.72807) (xy 126.208215 -389.749852) (xy 126.162577 -389.764678)
			(xy 126.115181 -389.772182) (xy 126.091188 -389.772652) (xy 126.067615 -389.772241) (xy 126.021029 -389.764999)
			(xy 125.976112 -389.750674) (xy 125.933935 -389.729608) (xy 125.895502 -389.702301) (xy 125.861729 -389.669406)
			(xy 125.833421 -389.631705) (xy 125.821948 -389.611108) (xy 125.82144 -389.610346) (xy 125.423676 -388.922006)
			(xy 125.411759 -388.899339) (xy 125.394823 -388.851013) (xy 125.386163 -388.800542) (xy 125.385576 -388.77494)
			(xy 124.843836 -388.77494) (xy 125.15596 -389.314944) (xy 125.16868 -389.338269) (xy 125.186777 -389.388214)
			(xy 125.195999 -389.440529) (xy 125.1966 -389.46709) (xy 125.1966 -389.467344) (xy 125.196178 -389.491337)
			(xy 125.188665 -389.538731) (xy 125.173831 -389.584366) (xy 125.152041 -389.627119) (xy 125.123832 -389.665938)
			(xy 125.089898 -389.699866) (xy 125.051075 -389.728069) (xy 125.008318 -389.749851) (xy 124.96268 -389.764677)
			(xy 124.915285 -389.772182) (xy 124.891292 -389.772652) (xy 124.867719 -389.772237) (xy 124.821133 -389.764996)
			(xy 124.776216 -389.750672) (xy 124.734039 -389.729606) (xy 124.695606 -389.7023) (xy 124.661833 -389.669406)
			(xy 124.633525 -389.631705) (xy 124.622052 -389.611108) (xy 124.621544 -389.610346) (xy 124.22378 -388.922006)
			(xy 124.211863 -388.899339) (xy 124.194927 -388.851013) (xy 124.186267 -388.800542) (xy 124.18568 -388.77494)
			(xy 123.643686 -388.77494) (xy 123.95581 -389.314944) (xy 123.968614 -389.338287) (xy 123.986843 -389.388304)
			(xy 123.996111 -389.440727) (xy 123.996704 -389.467344) (xy 123.996279 -389.491324) (xy 123.988774 -389.538693)
			(xy 123.973956 -389.584307) (xy 123.952189 -389.627042) (xy 123.924008 -389.66585) (xy 123.890106 -389.699774)
			(xy 123.851318 -389.727981) (xy 123.808597 -389.749777) (xy 123.762994 -389.764626) (xy 123.71563 -389.772163)
			(xy 123.69165 -389.772652) (xy 123.691142 -389.772652) (xy 123.667571 -389.772197) (xy 123.620986 -389.764963)
			(xy 123.576071 -389.750646) (xy 123.533893 -389.729587) (xy 123.49546 -389.702288) (xy 123.461686 -389.669398)
			(xy 123.433376 -389.631703) (xy 123.421902 -389.611108) (xy 123.421394 -389.610346) (xy 123.02363 -388.922006)
			(xy 123.011752 -388.89933) (xy 122.994902 -388.850996) (xy 122.98633 -388.800533) (xy 122.985784 -388.77494)
			(xy 122.44379 -388.77494) (xy 122.755914 -389.314944) (xy 122.768718 -389.338287) (xy 122.786947 -389.388304)
			(xy 122.796215 -389.440727) (xy 122.796808 -389.467344) (xy 122.796379 -389.491324) (xy 122.788874 -389.538693)
			(xy 122.774056 -389.584306) (xy 122.752289 -389.627041) (xy 122.724109 -389.665848) (xy 122.690208 -389.699772)
			(xy 122.65142 -389.72798) (xy 122.6087 -389.749776) (xy 122.563097 -389.764625) (xy 122.515733 -389.772162)
			(xy 122.491754 -389.772652) (xy 122.491246 -389.772652) (xy 122.467675 -389.772194) (xy 122.421091 -389.764961)
			(xy 122.376175 -389.750644) (xy 122.333998 -389.729586) (xy 122.295564 -389.702287) (xy 122.26179 -389.669398)
			(xy 122.23348 -389.631703) (xy 122.222006 -389.611108) (xy 122.221498 -389.610346) (xy 121.823734 -388.922006)
			(xy 121.811856 -388.89933) (xy 121.795006 -388.850996) (xy 121.786434 -388.800533) (xy 121.785888 -388.77494)
			(xy 121.243894 -388.77494) (xy 121.556018 -389.314944) (xy 121.568823 -389.338287) (xy 121.587051 -389.388304)
			(xy 121.596319 -389.440727) (xy 121.596912 -389.467344) (xy 121.596479 -389.491324) (xy 121.588974 -389.538692)
			(xy 121.574157 -389.584305) (xy 121.55239 -389.62704) (xy 121.52421 -389.665847) (xy 121.49031 -389.699771)
			(xy 121.451523 -389.727978) (xy 121.408803 -389.749775) (xy 121.3632 -389.764624) (xy 121.315837 -389.772162)
			(xy 121.291858 -389.772652) (xy 121.29135 -389.772652) (xy 121.267779 -389.772191) (xy 121.221195 -389.764958)
			(xy 121.176279 -389.750642) (xy 121.134102 -389.729584) (xy 121.095668 -389.702286) (xy 121.061894 -389.669397)
			(xy 121.033584 -389.631703) (xy 121.02211 -389.611108) (xy 121.021602 -389.610346) (xy 120.623838 -388.922006)
			(xy 120.61196 -388.89933) (xy 120.595111 -388.850996) (xy 120.586538 -388.800533) (xy 120.585992 -388.77494)
			(xy 120.043744 -388.77494) (xy 120.355868 -389.314944) (xy 120.368588 -389.338268) (xy 120.386686 -389.388213)
			(xy 120.395908 -389.440529) (xy 120.396508 -389.46709) (xy 120.396508 -389.467344) (xy 120.396078 -389.491336)
			(xy 120.388565 -389.53873) (xy 120.373732 -389.584364) (xy 120.351943 -389.627117) (xy 120.323735 -389.665935)
			(xy 120.289802 -389.699863) (xy 120.250979 -389.728066) (xy 120.208224 -389.749849) (xy 120.162587 -389.764676)
			(xy 120.115192 -389.772181) (xy 120.0912 -389.772652) (xy 120.067627 -389.772231) (xy 120.021042 -389.764991)
			(xy 119.976125 -389.750668) (xy 119.933948 -389.729603) (xy 119.895515 -389.702298) (xy 119.861742 -389.669404)
			(xy 119.833433 -389.631705) (xy 119.82196 -389.611108) (xy 119.821452 -389.610346) (xy 119.423688 -388.922006)
			(xy 119.411772 -388.899338) (xy 119.394835 -388.851013) (xy 119.386175 -388.800542) (xy 119.385588 -388.77494)
			(xy 118.843848 -388.77494) (xy 119.155972 -389.314944) (xy 119.168693 -389.338268) (xy 119.18679 -389.388213)
			(xy 119.196012 -389.440529) (xy 119.196612 -389.46709) (xy 119.196612 -389.467344) (xy 119.196178 -389.491336)
			(xy 119.188665 -389.538729) (xy 119.173832 -389.584363) (xy 119.152044 -389.627116) (xy 119.123836 -389.665934)
			(xy 119.089903 -389.699862) (xy 119.051082 -389.728065) (xy 119.008326 -389.749848) (xy 118.96269 -389.764675)
			(xy 118.915296 -389.772181) (xy 118.891304 -389.772652) (xy 118.867732 -389.772228) (xy 118.821146 -389.764988)
			(xy 118.776229 -389.750666) (xy 118.734052 -389.729602) (xy 118.695619 -389.702297) (xy 118.661846 -389.669404)
			(xy 118.633537 -389.631705) (xy 118.622064 -389.611108) (xy 118.621556 -389.610346) (xy 118.223792 -388.922006)
			(xy 118.211876 -388.899338) (xy 118.194939 -388.851012) (xy 118.186279 -388.800542) (xy 118.185692 -388.77494)
			(xy 117.643698 -388.77494) (xy 117.955822 -389.314944) (xy 117.968627 -389.338287) (xy 117.986855 -389.388304)
			(xy 117.996123 -389.440727) (xy 117.996716 -389.467344) (xy 117.996279 -389.491323) (xy 117.988775 -389.538691)
			(xy 117.973957 -389.584304) (xy 117.952191 -389.627039) (xy 117.924011 -389.665846) (xy 117.890112 -389.69977)
			(xy 117.851325 -389.727977) (xy 117.808605 -389.749773) (xy 117.763004 -389.764624) (xy 117.715641 -389.772162)
			(xy 117.691662 -389.772652) (xy 117.691154 -389.772652) (xy 117.667583 -389.772187) (xy 117.620999 -389.764955)
			(xy 117.576084 -389.75064) (xy 117.533906 -389.729583) (xy 117.495473 -389.702285) (xy 117.461698 -389.669397)
			(xy 117.433388 -389.631702) (xy 117.421914 -389.611108) (xy 117.421406 -389.610346) (xy 117.023642 -388.922006)
			(xy 117.011765 -388.89933) (xy 116.994915 -388.850996) (xy 116.986342 -388.800533) (xy 116.985796 -388.77494)
			(xy 116.443802 -388.77494) (xy 116.755926 -389.314944) (xy 116.768731 -389.338286) (xy 116.786959 -389.388304)
			(xy 116.796227 -389.440727) (xy 116.79682 -389.467344) (xy 116.796379 -389.491323) (xy 116.788875 -389.538691)
			(xy 116.774057 -389.584303) (xy 116.752292 -389.627038) (xy 116.724113 -389.665844) (xy 116.690213 -389.699768)
			(xy 116.651427 -389.727975) (xy 116.608708 -389.749772) (xy 116.563107 -389.764623) (xy 116.515745 -389.772162)
			(xy 116.491766 -389.772652) (xy 116.491258 -389.772652) (xy 116.467687 -389.772184) (xy 116.421104 -389.764953)
			(xy 116.376188 -389.750638) (xy 116.334011 -389.729581) (xy 116.295577 -389.702284) (xy 116.261802 -389.669396)
			(xy 116.233492 -389.631702) (xy 116.222018 -389.611108) (xy 116.22151 -389.610346) (xy 115.823746 -388.922006)
			(xy 115.811869 -388.89933) (xy 115.795019 -388.850996) (xy 115.786446 -388.800533) (xy 115.7859 -388.77494)
			(xy 115.243906 -388.77494) (xy 115.55603 -389.314944) (xy 115.568836 -389.338286) (xy 115.587063 -389.388304)
			(xy 115.596331 -389.440727) (xy 115.596924 -389.467344) (xy 115.596479 -389.491323) (xy 115.588975 -389.53869)
			(xy 115.574158 -389.584302) (xy 115.552392 -389.627036) (xy 115.524214 -389.665843) (xy 115.490315 -389.699767)
			(xy 115.451529 -389.727974) (xy 115.408811 -389.749771) (xy 115.36321 -389.764622) (xy 115.315849 -389.772161)
			(xy 115.29187 -389.772652) (xy 115.291362 -389.772652) (xy 115.267791 -389.772181) (xy 115.221208 -389.76495)
			(xy 115.176292 -389.750636) (xy 115.134115 -389.72958) (xy 115.095681 -389.702283) (xy 115.061907 -389.669396)
			(xy 115.033596 -389.631702) (xy 115.022122 -389.611108) (xy 115.021614 -389.610346) (xy 114.62385 -388.922006)
			(xy 114.611973 -388.899329) (xy 114.595123 -388.850996) (xy 114.58655 -388.800533) (xy 114.586004 -388.77494)
			(xy 98.671676 -388.77494) (xy 98.9838 -389.314944) (xy 98.996515 -389.338271) (xy 99.014615 -389.388215)
			(xy 99.023839 -389.44053) (xy 99.02444 -389.46709) (xy 99.02444 -389.467344) (xy 99.023978 -389.491335)
			(xy 99.016466 -389.538725) (xy 99.001635 -389.584357) (xy 98.979849 -389.627107) (xy 98.951644 -389.665924)
			(xy 98.917715 -389.699852) (xy 98.878897 -389.728055) (xy 98.836146 -389.74984) (xy 98.790513 -389.764669)
			(xy 98.743123 -389.772179) (xy 98.719132 -389.772652) (xy 98.69556 -389.772205) (xy 98.648976 -389.76497)
			(xy 98.60406 -389.750651) (xy 98.561883 -389.729591) (xy 98.523449 -389.70229) (xy 98.489675 -389.6694)
			(xy 98.461365 -389.631703) (xy 98.449892 -389.611108) (xy 98.449384 -389.610346) (xy 98.05162 -388.922006)
			(xy 98.039706 -388.899337) (xy 98.022768 -388.851012) (xy 98.014108 -388.800542) (xy 98.01352 -388.77494)
			(xy 97.471526 -388.77494) (xy 97.78365 -389.314944) (xy 97.796457 -389.338285) (xy 97.814684 -389.388304)
			(xy 97.823951 -389.440726) (xy 97.824544 -389.467344) (xy 97.824079 -389.491322) (xy 97.816576 -389.538687)
			(xy 97.80176 -389.584297) (xy 97.779996 -389.62703) (xy 97.75182 -389.665836) (xy 97.717923 -389.69976)
			(xy 97.67914 -389.727967) (xy 97.636425 -389.749765) (xy 97.590827 -389.764618) (xy 97.543468 -389.77216)
			(xy 97.51949 -389.772652) (xy 97.518982 -389.772652) (xy 97.495409 -389.772245) (xy 97.448822 -389.765003)
			(xy 97.403906 -389.750677) (xy 97.361728 -389.72961) (xy 97.323295 -389.702303) (xy 97.289523 -389.669407)
			(xy 97.261214 -389.631706) (xy 97.249742 -389.611108) (xy 97.249234 -389.610346) (xy 96.85147 -388.922006)
			(xy 96.839595 -388.899329) (xy 96.822743 -388.850996) (xy 96.81417 -388.800533) (xy 96.813624 -388.77494)
			(xy 96.27163 -388.77494) (xy 96.583754 -389.314944) (xy 96.596562 -389.338285) (xy 96.614788 -389.388304)
			(xy 96.624055 -389.440726) (xy 96.624648 -389.467344) (xy 96.624179 -389.491322) (xy 96.616676 -389.538687)
			(xy 96.60186 -389.584296) (xy 96.580097 -389.627029) (xy 96.551921 -389.665835) (xy 96.518025 -389.699758)
			(xy 96.479243 -389.727966) (xy 96.436528 -389.749764) (xy 96.39093 -389.764617) (xy 96.343571 -389.772159)
			(xy 96.319594 -389.772652) (xy 96.319086 -389.772652) (xy 96.295513 -389.772242) (xy 96.248927 -389.765)
			(xy 96.20401 -389.750675) (xy 96.161833 -389.729608) (xy 96.1234 -389.702302) (xy 96.089627 -389.669406)
			(xy 96.061319 -389.631705) (xy 96.049846 -389.611108) (xy 96.049338 -389.610346) (xy 95.651574 -388.922006)
			(xy 95.639699 -388.899329) (xy 95.622848 -388.850996) (xy 95.614274 -388.800533) (xy 95.613728 -388.77494)
			(xy 95.07148 -388.77494) (xy 95.383604 -389.314944) (xy 95.396319 -389.338271) (xy 95.41442 -389.388214)
			(xy 95.423643 -389.44053) (xy 95.424244 -389.46709) (xy 95.424244 -389.467344) (xy 95.423778 -389.491335)
			(xy 95.416267 -389.538724) (xy 95.401435 -389.584356) (xy 95.379649 -389.627106) (xy 95.351445 -389.665923)
			(xy 95.317517 -389.69985) (xy 95.278699 -389.728054) (xy 95.235949 -389.749838) (xy 95.190317 -389.764668)
			(xy 95.142927 -389.772179) (xy 95.118936 -389.772652) (xy 95.095364 -389.772202) (xy 95.04878 -389.764967)
			(xy 95.003864 -389.750649) (xy 94.961687 -389.729589) (xy 94.923253 -389.702289) (xy 94.889479 -389.669399)
			(xy 94.861169 -389.631703) (xy 94.849696 -389.611108) (xy 94.849188 -389.610346) (xy 94.451424 -388.922006)
			(xy 94.439511 -388.899337) (xy 94.422572 -388.851012) (xy 94.413912 -388.800542) (xy 94.413324 -388.77494)
			(xy 93.871584 -388.77494) (xy 94.183708 -389.314944) (xy 94.196423 -389.338271) (xy 94.214524 -389.388214)
			(xy 94.223747 -389.44053) (xy 94.224348 -389.46709) (xy 94.224348 -389.467344) (xy 94.223878 -389.491334)
			(xy 94.216367 -389.538724) (xy 94.201536 -389.584355) (xy 94.17975 -389.627105) (xy 94.151546 -389.665922)
			(xy 94.117618 -389.699849) (xy 94.078802 -389.728052) (xy 94.036051 -389.749837) (xy 93.99042 -389.764668)
			(xy 93.94303 -389.772178) (xy 93.91904 -389.772652) (xy 93.895469 -389.772199) (xy 93.848884 -389.764965)
			(xy 93.803969 -389.750647) (xy 93.761791 -389.729588) (xy 93.723358 -389.702288) (xy 93.689583 -389.669399)
			(xy 93.661273 -389.631703) (xy 93.6498 -389.611108) (xy 93.649292 -389.610346) (xy 93.251528 -388.922006)
			(xy 93.239615 -388.899337) (xy 93.222676 -388.851012) (xy 93.214016 -388.800542) (xy 93.213428 -388.77494)
			(xy 92.671688 -388.77494) (xy 92.983812 -389.314944) (xy 92.996528 -389.338271) (xy 93.014628 -389.388214)
			(xy 93.023851 -389.44053) (xy 93.024452 -389.46709) (xy 93.024452 -389.467344) (xy 93.023978 -389.491334)
			(xy 93.016467 -389.538723) (xy 93.001636 -389.584354) (xy 92.979851 -389.627104) (xy 92.951648 -389.66592)
			(xy 92.91772 -389.699848) (xy 92.878904 -389.728051) (xy 92.836154 -389.749836) (xy 92.790523 -389.764667)
			(xy 92.743134 -389.772178) (xy 92.719144 -389.772652) (xy 92.695573 -389.772195) (xy 92.648989 -389.764962)
			(xy 92.604073 -389.750645) (xy 92.561896 -389.729586) (xy 92.523462 -389.702287) (xy 92.489688 -389.669398)
			(xy 92.461378 -389.631703) (xy 92.449904 -389.611108) (xy 92.449396 -389.610346) (xy 92.051632 -388.922006)
			(xy 92.039719 -388.899336) (xy 92.02278 -388.851012) (xy 92.01412 -388.800542) (xy 92.013532 -388.77494)
			(xy 91.471538 -388.77494) (xy 91.783662 -389.314944) (xy 91.79647 -389.338285) (xy 91.814696 -389.388304)
			(xy 91.823963 -389.440726) (xy 91.824556 -389.467344) (xy 91.824079 -389.491321) (xy 91.816576 -389.538686)
			(xy 91.801761 -389.584295) (xy 91.779998 -389.627027) (xy 91.751823 -389.665832) (xy 91.717928 -389.699755)
			(xy 91.679147 -389.727963) (xy 91.636433 -389.749762) (xy 91.590837 -389.764616) (xy 91.543479 -389.772159)
			(xy 91.519502 -389.772652) (xy 91.518994 -389.772652) (xy 91.495421 -389.772236) (xy 91.448835 -389.764995)
			(xy 91.403919 -389.750671) (xy 91.361741 -389.729605) (xy 91.323308 -389.7023) (xy 91.289535 -389.669405)
			(xy 91.261227 -389.631705) (xy 91.249754 -389.611108) (xy 91.249246 -389.610346) (xy 90.851482 -388.922006)
			(xy 90.839608 -388.899328) (xy 90.822756 -388.850996) (xy 90.814182 -388.800533) (xy 90.813636 -388.77494)
			(xy 90.271642 -388.77494) (xy 90.583766 -389.314944) (xy 90.596575 -389.338285) (xy 90.6148 -389.388303)
			(xy 90.624067 -389.440726) (xy 90.62466 -389.467344) (xy 90.624279 -389.491326) (xy 90.616773 -389.5387)
			(xy 90.601952 -389.584317) (xy 90.580181 -389.627055) (xy 90.551995 -389.665865) (xy 90.518088 -389.69979)
			(xy 90.479294 -389.727996) (xy 90.436567 -389.74979) (xy 90.390957 -389.764635) (xy 90.343588 -389.772166)
			(xy 90.319606 -389.772652) (xy 90.319098 -389.772652) (xy 90.295525 -389.772232) (xy 90.24894 -389.764992)
			(xy 90.204023 -389.750669) (xy 90.161846 -389.729604) (xy 90.123413 -389.702299) (xy 90.089639 -389.669405)
			(xy 90.061331 -389.631705) (xy 90.049858 -389.611108) (xy 90.04935 -389.610346) (xy 89.651586 -388.922006)
			(xy 89.639712 -388.899328) (xy 89.62286 -388.850996) (xy 89.614286 -388.800533) (xy 89.61374 -388.77494)
			(xy 89.071492 -388.77494) (xy 89.383616 -389.314944) (xy 89.396332 -389.338271) (xy 89.414432 -389.388214)
			(xy 89.423655 -389.44053) (xy 89.424256 -389.46709) (xy 89.424256 -389.467344) (xy 89.423778 -389.491334)
			(xy 89.416267 -389.538723) (xy 89.401436 -389.584353) (xy 89.379652 -389.627103) (xy 89.351449 -389.665919)
			(xy 89.317522 -389.699846) (xy 89.278706 -389.72805) (xy 89.235957 -389.749835) (xy 89.190327 -389.764666)
			(xy 89.142938 -389.772178) (xy 89.118948 -389.772652) (xy 89.095377 -389.772192) (xy 89.048793 -389.764959)
			(xy 89.003877 -389.750643) (xy 88.9617 -389.729585) (xy 88.923266 -389.702286) (xy 88.889492 -389.669398)
			(xy 88.861182 -389.631703) (xy 88.849708 -389.611108) (xy 88.8492 -389.610346) (xy 88.451436 -388.922006)
			(xy 88.439523 -388.899336) (xy 88.422584 -388.851012) (xy 88.413924 -388.800542) (xy 88.413336 -388.77494)
			(xy 87.871596 -388.77494) (xy 88.18372 -389.314944) (xy 88.196436 -389.33827) (xy 88.214536 -389.388214)
			(xy 88.223759 -389.44053) (xy 88.22436 -389.46709) (xy 88.22436 -389.467344) (xy 88.224002 -389.491341)
			(xy 88.216487 -389.538742) (xy 88.20165 -389.584385) (xy 88.179855 -389.627144) (xy 88.151639 -389.665968)
			(xy 88.117698 -389.699899) (xy 88.078866 -389.728103) (xy 88.0361 -389.749885) (xy 87.990453 -389.764709)
			(xy 87.943049 -389.772209) (xy 87.919052 -389.772652) (xy 87.895481 -389.772189) (xy 87.848897 -389.764957)
			(xy 87.803982 -389.750641) (xy 87.761804 -389.729583) (xy 87.723371 -389.702285) (xy 87.689596 -389.669397)
			(xy 87.661286 -389.631703) (xy 87.649812 -389.611108) (xy 87.649304 -389.610346) (xy 87.25154 -388.922006)
			(xy 87.239628 -388.899336) (xy 87.222688 -388.851012) (xy 87.214028 -388.800542) (xy 87.21344 -388.77494)
			(xy 86.6717 -388.77494) (xy 86.983824 -389.314944) (xy 86.996541 -389.33827) (xy 87.01464 -389.388214)
			(xy 87.023863 -389.44053) (xy 87.024464 -389.46709) (xy 87.024464 -389.467344) (xy 87.024078 -389.491339)
			(xy 87.016564 -389.538736) (xy 87.001728 -389.584375) (xy 86.979935 -389.62713) (xy 86.951722 -389.66595)
			(xy 86.917783 -389.699879) (xy 86.878955 -389.728081) (xy 86.836193 -389.749861) (xy 86.79055 -389.764684)
			(xy 86.743151 -389.772185) (xy 86.719156 -389.772652) (xy 86.695585 -389.772186) (xy 86.649001 -389.764954)
			(xy 86.604086 -389.750639) (xy 86.561909 -389.729582) (xy 86.523475 -389.702284) (xy 86.4897 -389.669396)
			(xy 86.46139 -389.631702) (xy 86.449916 -389.611108) (xy 86.449408 -389.610346) (xy 86.051644 -388.922006)
			(xy 86.039732 -388.899336) (xy 86.022793 -388.851012) (xy 86.014132 -388.800542) (xy 86.013544 -388.77494)
			(xy 85.47155 -388.77494) (xy 85.783674 -389.314944) (xy 85.796483 -389.338284) (xy 85.814708 -389.388303)
			(xy 85.823975 -389.440726) (xy 85.824568 -389.467344) (xy 85.824179 -389.491326) (xy 85.816673 -389.538698)
			(xy 85.801852 -389.584315) (xy 85.780082 -389.627053) (xy 85.751897 -389.665862) (xy 85.717991 -389.699787)
			(xy 85.679198 -389.727993) (xy 85.636472 -389.749787) (xy 85.590864 -389.764633) (xy 85.543495 -389.772165)
			(xy 85.519514 -389.772652) (xy 85.519006 -389.772652) (xy 85.495434 -389.772226) (xy 85.448848 -389.764987)
			(xy 85.403932 -389.750665) (xy 85.361754 -389.729601) (xy 85.323321 -389.702297) (xy 85.289548 -389.669404)
			(xy 85.261239 -389.631705) (xy 85.249766 -389.611108) (xy 85.249258 -389.610346) (xy 84.851494 -388.922006)
			(xy 84.839621 -388.899328) (xy 84.822768 -388.850995) (xy 84.814194 -388.800532) (xy 84.813648 -388.77494)
			(xy 84.271654 -388.77494) (xy 84.583778 -389.314944) (xy 84.596588 -389.338284) (xy 84.614813 -389.388303)
			(xy 84.624079 -389.440726) (xy 84.624672 -389.467344) (xy 84.624279 -389.491326) (xy 84.616773 -389.538698)
			(xy 84.601953 -389.584314) (xy 84.580183 -389.627052) (xy 84.551999 -389.665861) (xy 84.518093 -389.699785)
			(xy 84.4793 -389.727992) (xy 84.436575 -389.749786) (xy 84.390967 -389.764632) (xy 84.343599 -389.772165)
			(xy 84.319618 -389.772652) (xy 84.31911 -389.772652) (xy 84.295538 -389.772223) (xy 84.248952 -389.764984)
			(xy 84.204036 -389.750663) (xy 84.161859 -389.729599) (xy 84.123425 -389.702296) (xy 84.089652 -389.669403)
			(xy 84.061343 -389.631704) (xy 84.04987 -389.611108) (xy 84.049362 -389.610346) (xy 83.651598 -388.922006)
			(xy 83.639725 -388.899328) (xy 83.622872 -388.850995) (xy 83.614298 -388.800532) (xy 83.613752 -388.77494)
			(xy 83.071504 -388.77494) (xy 83.383628 -389.314944) (xy 83.396345 -389.33827) (xy 83.414444 -389.388214)
			(xy 83.423667 -389.44053) (xy 83.424268 -389.46709) (xy 83.424268 -389.467344) (xy 83.423878 -389.491338)
			(xy 83.416364 -389.538735) (xy 83.401528 -389.584374) (xy 83.379736 -389.627129) (xy 83.351523 -389.665949)
			(xy 83.317585 -389.699878) (xy 83.278757 -389.728079) (xy 83.235996 -389.74986) (xy 83.190354 -389.764684)
			(xy 83.142955 -389.772184) (xy 83.11896 -389.772652) (xy 83.095389 -389.772182) (xy 83.048806 -389.764951)
			(xy 83.00389 -389.750637) (xy 82.961713 -389.72958) (xy 82.923279 -389.702283) (xy 82.889504 -389.669396)
			(xy 82.861194 -389.631702) (xy 82.84972 -389.611108) (xy 82.849212 -389.610346) (xy 82.451448 -388.922006)
			(xy 82.439536 -388.899336) (xy 82.422597 -388.851012) (xy 82.413936 -388.800542) (xy 82.413348 -388.77494)
			(xy 81.871608 -388.77494) (xy 82.183732 -389.314944) (xy 82.196449 -389.33827) (xy 82.214548 -389.388214)
			(xy 82.223771 -389.44053) (xy 82.224372 -389.46709) (xy 82.224372 -389.467344) (xy 82.223978 -389.491338)
			(xy 82.216464 -389.538735) (xy 82.201628 -389.584373) (xy 82.179836 -389.627128) (xy 82.151624 -389.665948)
			(xy 82.117687 -389.699876) (xy 82.078859 -389.728078) (xy 82.036099 -389.749859) (xy 81.990457 -389.764683)
			(xy 81.943058 -389.772184) (xy 81.919064 -389.772652) (xy 81.895493 -389.772179) (xy 81.84891 -389.764949)
			(xy 81.803995 -389.750635) (xy 81.761817 -389.729579) (xy 81.723383 -389.702282) (xy 81.689609 -389.669395)
			(xy 81.661298 -389.631702) (xy 81.649824 -389.611108) (xy 81.649316 -389.610346) (xy 81.251552 -388.922006)
			(xy 81.239641 -388.899336) (xy 81.222701 -388.851012) (xy 81.21404 -388.800542) (xy 81.213452 -388.77494)
			(xy 80.671712 -388.77494) (xy 80.983836 -389.314944) (xy 80.996554 -389.33827) (xy 81.014653 -389.388214)
			(xy 81.023875 -389.44053) (xy 81.024476 -389.46709) (xy 81.024476 -389.467344) (xy 81.024078 -389.491338)
			(xy 81.016564 -389.538734) (xy 81.001729 -389.584372) (xy 80.979937 -389.627127) (xy 80.951725 -389.665946)
			(xy 80.917788 -389.699875) (xy 80.878962 -389.728077) (xy 80.836201 -389.749858) (xy 80.79056 -389.764682)
			(xy 80.743162 -389.772184) (xy 80.719168 -389.772652) (xy 80.695597 -389.772176) (xy 80.649014 -389.764946)
			(xy 80.604099 -389.750633) (xy 80.561922 -389.729577) (xy 80.523488 -389.702281) (xy 80.489713 -389.669395)
			(xy 80.461402 -389.631702) (xy 80.449928 -389.611108) (xy 80.44942 -389.610346) (xy 80.051656 -388.922006)
			(xy 80.039745 -388.899335) (xy 80.022805 -388.851011) (xy 80.014144 -388.800542) (xy 80.013556 -388.77494)
			(xy 66.143928 -388.77494) (xy 66.456052 -389.314944) (xy 66.468771 -389.338269) (xy 66.486869 -389.388214)
			(xy 66.496091 -389.44053) (xy 66.496692 -389.46709) (xy 66.496692 -389.467344) (xy 66.496278 -389.491337)
			(xy 66.488765 -389.538732) (xy 66.47393 -389.584368) (xy 66.45214 -389.627122) (xy 66.42393 -389.665941)
			(xy 66.389995 -389.699869) (xy 66.351171 -389.728071) (xy 66.308412 -389.749853) (xy 66.262774 -389.764679)
			(xy 66.215377 -389.772183) (xy 66.191384 -389.772652) (xy 66.167811 -389.772244) (xy 66.121225 -389.765001)
			(xy 66.076308 -389.750676) (xy 66.034131 -389.729609) (xy 65.995698 -389.702302) (xy 65.961925 -389.669407)
			(xy 65.933616 -389.631706) (xy 65.922144 -389.611108) (xy 65.921636 -389.610346) (xy 65.523872 -388.922006)
			(xy 65.511954 -388.899339) (xy 65.495018 -388.851013) (xy 65.486359 -388.800542) (xy 65.485772 -388.77494)
			(xy 64.943778 -388.77494) (xy 65.255902 -389.314944) (xy 65.268705 -389.338288) (xy 65.286934 -389.388305)
			(xy 65.296203 -389.440727) (xy 65.296796 -389.467344) (xy 65.296379 -389.491324) (xy 65.288874 -389.538694)
			(xy 65.274055 -389.584308) (xy 65.252287 -389.627045) (xy 65.224106 -389.665852) (xy 65.190203 -389.699777)
			(xy 65.151414 -389.727984) (xy 65.108692 -389.749779) (xy 65.063087 -389.764628) (xy 65.015722 -389.772163)
			(xy 64.991742 -389.772652) (xy 64.991234 -389.772652) (xy 64.967662 -389.772203) (xy 64.921078 -389.764969)
			(xy 64.876162 -389.75065) (xy 64.833985 -389.72959) (xy 64.795551 -389.70229) (xy 64.761777 -389.6694)
			(xy 64.733467 -389.631703) (xy 64.721994 -389.611108) (xy 64.721486 -389.610346) (xy 64.323722 -388.922006)
			(xy 64.311843 -388.899331) (xy 64.294994 -388.850996) (xy 64.286422 -388.800533) (xy 64.285876 -388.77494)
			(xy 63.743882 -388.77494) (xy 64.056006 -389.314944) (xy 64.06881 -389.338287) (xy 64.087038 -389.388304)
			(xy 64.096307 -389.440727) (xy 64.0969 -389.467344) (xy 64.096479 -389.491324) (xy 64.088974 -389.538694)
			(xy 64.074156 -389.584307) (xy 64.052388 -389.627044) (xy 64.024207 -389.665851) (xy 63.990305 -389.699775)
			(xy 63.951516 -389.727982) (xy 63.908794 -389.749778) (xy 63.86319 -389.764627) (xy 63.815826 -389.772163)
			(xy 63.791846 -389.772652) (xy 63.791338 -389.772652) (xy 63.767766 -389.7722) (xy 63.721182 -389.764966)
			(xy 63.676266 -389.750648) (xy 63.634089 -389.729589) (xy 63.595656 -389.702289) (xy 63.561881 -389.669399)
			(xy 63.533571 -389.631703) (xy 63.522098 -389.611108) (xy 63.52159 -389.610346) (xy 63.123826 -388.922006)
			(xy 63.111947 -388.89933) (xy 63.095098 -388.850996) (xy 63.086526 -388.800533) (xy 63.08598 -388.77494)
			(xy 62.543732 -388.77494) (xy 62.855856 -389.314944) (xy 62.868575 -389.338269) (xy 62.886673 -389.388214)
			(xy 62.895895 -389.440529) (xy 62.896496 -389.46709) (xy 62.896496 -389.467344) (xy 62.896078 -389.491337)
			(xy 62.888565 -389.538731) (xy 62.873731 -389.584367) (xy 62.851941 -389.627121) (xy 62.823731 -389.665939)
			(xy 62.789797 -389.699868) (xy 62.750973 -389.72807) (xy 62.708215 -389.749852) (xy 62.662577 -389.764678)
			(xy 62.615181 -389.772182) (xy 62.591188 -389.772652) (xy 62.567615 -389.772241) (xy 62.521029 -389.764999)
			(xy 62.476112 -389.750674) (xy 62.433935 -389.729608) (xy 62.395502 -389.702301) (xy 62.361729 -389.669406)
			(xy 62.333421 -389.631705) (xy 62.321948 -389.611108) (xy 62.32144 -389.610346) (xy 61.923676 -388.922006)
			(xy 61.911759 -388.899339) (xy 61.894823 -388.851013) (xy 61.886163 -388.800542) (xy 61.885576 -388.77494)
			(xy 61.343836 -388.77494) (xy 61.65596 -389.314944) (xy 61.66868 -389.338269) (xy 61.686777 -389.388214)
			(xy 61.695999 -389.440529) (xy 61.6966 -389.46709) (xy 61.6966 -389.467344) (xy 61.696178 -389.491337)
			(xy 61.688665 -389.538731) (xy 61.673831 -389.584366) (xy 61.652041 -389.627119) (xy 61.623832 -389.665938)
			(xy 61.589898 -389.699866) (xy 61.551075 -389.728069) (xy 61.508318 -389.749851) (xy 61.46268 -389.764677)
			(xy 61.415285 -389.772182) (xy 61.391292 -389.772652) (xy 61.367719 -389.772237) (xy 61.321133 -389.764996)
			(xy 61.276216 -389.750672) (xy 61.234039 -389.729606) (xy 61.195606 -389.7023) (xy 61.161833 -389.669406)
			(xy 61.133525 -389.631705) (xy 61.122052 -389.611108) (xy 61.121544 -389.610346) (xy 60.72378 -388.922006)
			(xy 60.711863 -388.899339) (xy 60.694927 -388.851013) (xy 60.686267 -388.800542) (xy 60.68568 -388.77494)
			(xy 60.14394 -388.77494) (xy 60.456064 -389.314944) (xy 60.468784 -389.338268) (xy 60.486881 -389.388213)
			(xy 60.496104 -389.440529) (xy 60.496704 -389.46709) (xy 60.496704 -389.467344) (xy 60.496278 -389.491337)
			(xy 60.488765 -389.53873) (xy 60.473931 -389.584365) (xy 60.452142 -389.627118) (xy 60.423933 -389.665937)
			(xy 60.39 -389.699865) (xy 60.351177 -389.728067) (xy 60.308421 -389.74985) (xy 60.262783 -389.764676)
			(xy 60.215389 -389.772182) (xy 60.191396 -389.772652) (xy 60.167823 -389.772234) (xy 60.121237 -389.764993)
			(xy 60.076321 -389.75067) (xy 60.034144 -389.729605) (xy 59.99571 -389.702299) (xy 59.961937 -389.669405)
			(xy 59.933629 -389.631705) (xy 59.922156 -389.611108) (xy 59.921648 -389.610346) (xy 59.523884 -388.922006)
			(xy 59.511967 -388.899338) (xy 59.495031 -388.851013) (xy 59.486371 -388.800542) (xy 59.485784 -388.77494)
			(xy 58.94379 -388.77494) (xy 59.255914 -389.314944) (xy 59.268718 -389.338287) (xy 59.286947 -389.388304)
			(xy 59.296215 -389.440727) (xy 59.296808 -389.467344) (xy 59.296379 -389.491324) (xy 59.288874 -389.538693)
			(xy 59.274056 -389.584306) (xy 59.252289 -389.627041) (xy 59.224109 -389.665848) (xy 59.190208 -389.699772)
			(xy 59.15142 -389.72798) (xy 59.1087 -389.749776) (xy 59.063097 -389.764625) (xy 59.015733 -389.772162)
			(xy 58.991754 -389.772652) (xy 58.991246 -389.772652) (xy 58.967675 -389.772194) (xy 58.921091 -389.764961)
			(xy 58.876175 -389.750644) (xy 58.833998 -389.729586) (xy 58.795564 -389.702287) (xy 58.76179 -389.669398)
			(xy 58.73348 -389.631703) (xy 58.722006 -389.611108) (xy 58.721498 -389.610346) (xy 58.323734 -388.922006)
			(xy 58.311856 -388.89933) (xy 58.295006 -388.850996) (xy 58.286434 -388.800533) (xy 58.285888 -388.77494)
			(xy 57.743894 -388.77494) (xy 58.056018 -389.314944) (xy 58.068823 -389.338287) (xy 58.087051 -389.388304)
			(xy 58.096319 -389.440727) (xy 58.096912 -389.467344) (xy 58.096479 -389.491324) (xy 58.088974 -389.538692)
			(xy 58.074157 -389.584305) (xy 58.05239 -389.62704) (xy 58.02421 -389.665847) (xy 57.99031 -389.699771)
			(xy 57.951523 -389.727978) (xy 57.908803 -389.749775) (xy 57.8632 -389.764624) (xy 57.815837 -389.772162)
			(xy 57.791858 -389.772652) (xy 57.79135 -389.772652) (xy 57.767779 -389.772191) (xy 57.721195 -389.764958)
			(xy 57.676279 -389.750642) (xy 57.634102 -389.729584) (xy 57.595668 -389.702286) (xy 57.561894 -389.669397)
			(xy 57.533584 -389.631703) (xy 57.52211 -389.611108) (xy 57.521602 -389.610346) (xy 57.123838 -388.922006)
			(xy 57.11196 -388.89933) (xy 57.095111 -388.850996) (xy 57.086538 -388.800533) (xy 57.085992 -388.77494)
			(xy 56.543744 -388.77494) (xy 56.855868 -389.314944) (xy 56.868588 -389.338268) (xy 56.886686 -389.388213)
			(xy 56.895908 -389.440529) (xy 56.896508 -389.46709) (xy 56.896508 -389.467344) (xy 56.896078 -389.491336)
			(xy 56.888565 -389.53873) (xy 56.873732 -389.584364) (xy 56.851943 -389.627117) (xy 56.823735 -389.665935)
			(xy 56.789802 -389.699863) (xy 56.750979 -389.728066) (xy 56.708224 -389.749849) (xy 56.662587 -389.764676)
			(xy 56.615192 -389.772181) (xy 56.5912 -389.772652) (xy 56.567627 -389.772231) (xy 56.521042 -389.764991)
			(xy 56.476125 -389.750668) (xy 56.433948 -389.729603) (xy 56.395515 -389.702298) (xy 56.361742 -389.669404)
			(xy 56.333433 -389.631705) (xy 56.32196 -389.611108) (xy 56.321452 -389.610346) (xy 55.923688 -388.922006)
			(xy 55.911772 -388.899338) (xy 55.894835 -388.851013) (xy 55.886175 -388.800542) (xy 55.885588 -388.77494)
			(xy 55.343848 -388.77494) (xy 55.655972 -389.314944) (xy 55.668693 -389.338268) (xy 55.68679 -389.388213)
			(xy 55.696012 -389.440529) (xy 55.696612 -389.46709) (xy 55.696612 -389.467344) (xy 55.696178 -389.491336)
			(xy 55.688665 -389.538729) (xy 55.673832 -389.584363) (xy 55.652044 -389.627116) (xy 55.623836 -389.665934)
			(xy 55.589903 -389.699862) (xy 55.551082 -389.728065) (xy 55.508326 -389.749848) (xy 55.46269 -389.764675)
			(xy 55.415296 -389.772181) (xy 55.391304 -389.772652) (xy 55.367732 -389.772228) (xy 55.321146 -389.764988)
			(xy 55.276229 -389.750666) (xy 55.234052 -389.729602) (xy 55.195619 -389.702297) (xy 55.161846 -389.669404)
			(xy 55.133537 -389.631705) (xy 55.122064 -389.611108) (xy 55.121556 -389.610346) (xy 54.723792 -388.922006)
			(xy 54.711876 -388.899338) (xy 54.694939 -388.851012) (xy 54.686279 -388.800542) (xy 54.685692 -388.77494)
			(xy 54.143952 -388.77494) (xy 54.456076 -389.314944) (xy 54.468797 -389.338268) (xy 54.486894 -389.388213)
			(xy 54.496116 -389.440529) (xy 54.496716 -389.46709) (xy 54.496716 -389.467344) (xy 54.496278 -389.491336)
			(xy 54.488766 -389.538728) (xy 54.473933 -389.584362) (xy 54.452144 -389.627115) (xy 54.423937 -389.665932)
			(xy 54.390005 -389.69986) (xy 54.351184 -389.728063) (xy 54.308429 -389.749846) (xy 54.262793 -389.764674)
			(xy 54.2154 -389.772181) (xy 54.191408 -389.772652) (xy 54.167836 -389.772224) (xy 54.12125 -389.764986)
			(xy 54.076334 -389.750664) (xy 54.034157 -389.7296) (xy 53.995723 -389.702296) (xy 53.96195 -389.669403)
			(xy 53.933641 -389.631704) (xy 53.922168 -389.611108) (xy 53.92166 -389.610346) (xy 53.523896 -388.922006)
			(xy 53.51198 -388.899338) (xy 53.495043 -388.851012) (xy 53.486383 -388.800542) (xy 53.485796 -388.77494)
			(xy 52.943802 -388.77494) (xy 53.255926 -389.314944) (xy 53.268731 -389.338286) (xy 53.286959 -389.388304)
			(xy 53.296227 -389.440727) (xy 53.29682 -389.467344) (xy 53.296379 -389.491323) (xy 53.288875 -389.538691)
			(xy 53.274057 -389.584303) (xy 53.252292 -389.627038) (xy 53.224113 -389.665844) (xy 53.190213 -389.699768)
			(xy 53.151427 -389.727975) (xy 53.108708 -389.749772) (xy 53.063107 -389.764623) (xy 53.015745 -389.772162)
			(xy 52.991766 -389.772652) (xy 52.991258 -389.772652) (xy 52.967687 -389.772184) (xy 52.921104 -389.764953)
			(xy 52.876188 -389.750638) (xy 52.834011 -389.729581) (xy 52.795577 -389.702284) (xy 52.761802 -389.669396)
			(xy 52.733492 -389.631702) (xy 52.722018 -389.611108) (xy 52.72151 -389.610346) (xy 52.323746 -388.922006)
			(xy 52.311869 -388.89933) (xy 52.295019 -388.850996) (xy 52.286446 -388.800533) (xy 52.2859 -388.77494)
			(xy 51.743906 -388.77494) (xy 52.05603 -389.314944) (xy 52.068836 -389.338286) (xy 52.087063 -389.388304)
			(xy 52.096331 -389.440727) (xy 52.096924 -389.467344) (xy 52.096479 -389.491323) (xy 52.088975 -389.53869)
			(xy 52.074158 -389.584302) (xy 52.052392 -389.627036) (xy 52.024214 -389.665843) (xy 51.990315 -389.699767)
			(xy 51.951529 -389.727974) (xy 51.908811 -389.749771) (xy 51.86321 -389.764622) (xy 51.815849 -389.772161)
			(xy 51.79187 -389.772652) (xy 51.791362 -389.772652) (xy 51.767791 -389.772181) (xy 51.721208 -389.76495)
			(xy 51.676292 -389.750636) (xy 51.634115 -389.72958) (xy 51.595681 -389.702283) (xy 51.561907 -389.669396)
			(xy 51.533596 -389.631702) (xy 51.522122 -389.611108) (xy 51.521614 -389.610346) (xy 51.12385 -388.922006)
			(xy 51.111973 -388.899329) (xy 51.095123 -388.850996) (xy 51.08655 -388.800533) (xy 51.086004 -388.77494)
			(xy 50.543756 -388.77494) (xy 50.85588 -389.314944) (xy 50.868601 -389.338268) (xy 50.886698 -389.388213)
			(xy 50.89592 -389.440529) (xy 50.89652 -389.46709) (xy 50.89652 -389.467344) (xy 50.896078 -389.491336)
			(xy 50.888566 -389.538728) (xy 50.873733 -389.584362) (xy 50.851945 -389.627113) (xy 50.823738 -389.665931)
			(xy 50.789807 -389.699859) (xy 50.750986 -389.728062) (xy 50.708232 -389.749845) (xy 50.662597 -389.764673)
			(xy 50.615204 -389.772181) (xy 50.591212 -389.772652) (xy 50.56764 -389.772221) (xy 50.521054 -389.764983)
			(xy 50.476138 -389.750662) (xy 50.433961 -389.729599) (xy 50.395528 -389.702295) (xy 50.361754 -389.669403)
			(xy 50.333445 -389.631704) (xy 50.321972 -389.611108) (xy 50.321464 -389.610346) (xy 49.9237 -388.922006)
			(xy 49.911785 -388.899338) (xy 49.894847 -388.851012) (xy 49.886188 -388.800542) (xy 49.8856 -388.77494)
			(xy 49.34386 -388.77494) (xy 49.655984 -389.314944) (xy 49.668697 -389.338272) (xy 49.686799 -389.388215)
			(xy 49.696023 -389.44053) (xy 49.696624 -389.46709) (xy 49.696624 -389.467344) (xy 49.696178 -389.491336)
			(xy 49.688666 -389.538727) (xy 49.673833 -389.584361) (xy 49.652046 -389.627112) (xy 49.623839 -389.66593)
			(xy 49.589908 -389.699858) (xy 49.551088 -389.72806) (xy 49.508335 -389.749844) (xy 49.4627 -389.764672)
			(xy 49.415308 -389.77218) (xy 49.391316 -389.772652) (xy 49.367744 -389.772218) (xy 49.321159 -389.76498)
			(xy 49.276242 -389.75066) (xy 49.234065 -389.729597) (xy 49.195632 -389.702294) (xy 49.161858 -389.669402)
			(xy 49.133549 -389.631704) (xy 49.122076 -389.611108) (xy 49.121568 -389.610346) (xy 48.723804 -388.922006)
			(xy 48.711889 -388.899338) (xy 48.694951 -388.851012) (xy 48.686292 -388.800542) (xy 48.685704 -388.77494)
			(xy 48.143964 -388.77494) (xy 48.456088 -389.314944) (xy 48.468802 -389.338272) (xy 48.486903 -389.388215)
			(xy 48.496127 -389.44053) (xy 48.496728 -389.46709) (xy 48.496728 -389.467344) (xy 48.496278 -389.491335)
			(xy 48.488766 -389.538727) (xy 48.473934 -389.58436) (xy 48.452147 -389.627111) (xy 48.423941 -389.665928)
			(xy 48.39001 -389.699856) (xy 48.351191 -389.728059) (xy 48.308437 -389.749843) (xy 48.262803 -389.764672)
			(xy 48.215411 -389.77218) (xy 48.19142 -389.772652) (xy 48.167848 -389.772215) (xy 48.121263 -389.764978)
			(xy 48.076347 -389.750658) (xy 48.03417 -389.729595) (xy 47.995736 -389.702293) (xy 47.961962 -389.669402)
			(xy 47.933653 -389.631704) (xy 47.92218 -389.611108) (xy 47.921672 -389.610346) (xy 47.523908 -388.922006)
			(xy 47.511993 -388.899337) (xy 47.495055 -388.851012) (xy 47.486396 -388.800542) (xy 47.485808 -388.77494)
			(xy 2.509012 -388.77494) (xy 2.509012 -393.292838) (xy 47.435008 -393.292838) (xy 47.435008 -392.429238)
			(xy 47.435494 -392.401987) (xy 47.44325 -392.348039) (xy 47.458605 -392.295744) (xy 47.481247 -392.246167)
			(xy 47.510713 -392.200317) (xy 47.546404 -392.159126) (xy 47.587595 -392.123435) (xy 47.633445 -392.093969)
			(xy 47.683022 -392.071327) (xy 47.735317 -392.055972) (xy 47.789265 -392.048216) (xy 47.843767 -392.048216)
			(xy 47.897715 -392.055972) (xy 47.95001 -392.071327) (xy 47.999587 -392.093969) (xy 48.045437 -392.123435)
			(xy 48.086628 -392.159126) (xy 48.122319 -392.200317) (xy 48.151785 -392.246167) (xy 48.174427 -392.295744)
			(xy 48.189782 -392.348039) (xy 48.197538 -392.401987) (xy 48.198024 -392.429238) (xy 48.198024 -393.292838)
			(xy 48.634904 -393.292838) (xy 48.634904 -392.429238) (xy 48.63539 -392.401987) (xy 48.643146 -392.348039)
			(xy 48.658501 -392.295744) (xy 48.681143 -392.246167) (xy 48.710609 -392.200317) (xy 48.7463 -392.159126)
			(xy 48.787491 -392.123435) (xy 48.833341 -392.093969) (xy 48.882918 -392.071327) (xy 48.935213 -392.055972)
			(xy 48.989161 -392.048216) (xy 49.043663 -392.048216) (xy 49.097611 -392.055972) (xy 49.149906 -392.071327)
			(xy 49.199483 -392.093969) (xy 49.245333 -392.123435) (xy 49.286524 -392.159126) (xy 49.322215 -392.200317)
			(xy 49.351681 -392.246167) (xy 49.374323 -392.295744) (xy 49.389678 -392.348039) (xy 49.397434 -392.401987)
			(xy 49.39792 -392.429238) (xy 49.39792 -393.292838) (xy 49.8348 -393.292838) (xy 49.8348 -392.429238)
			(xy 49.835286 -392.401969) (xy 49.843048 -392.347985) (xy 49.858413 -392.295655) (xy 49.88107 -392.246045)
			(xy 49.910556 -392.200164) (xy 49.946271 -392.158947) (xy 49.987488 -392.123232) (xy 50.033369 -392.093746)
			(xy 50.082979 -392.071089) (xy 50.135309 -392.055724) (xy 50.189293 -392.047962) (xy 50.243831 -392.047962)
			(xy 50.297815 -392.055724) (xy 50.350145 -392.071089) (xy 50.399755 -392.093746) (xy 50.445636 -392.123232)
			(xy 50.486853 -392.158947) (xy 50.522568 -392.200164) (xy 50.552054 -392.246045) (xy 50.574711 -392.295655)
			(xy 50.590076 -392.347985) (xy 50.597838 -392.401969) (xy 50.598324 -392.429238) (xy 50.598324 -393.292838)
			(xy 51.034696 -393.292838) (xy 51.034696 -392.429238) (xy 51.035182 -392.401969) (xy 51.042944 -392.347985)
			(xy 51.058309 -392.295655) (xy 51.080966 -392.246045) (xy 51.110452 -392.200164) (xy 51.146167 -392.158947)
			(xy 51.187384 -392.123232) (xy 51.233265 -392.093746) (xy 51.282875 -392.071089) (xy 51.335205 -392.055724)
			(xy 51.389189 -392.047962) (xy 51.443727 -392.047962) (xy 51.497711 -392.055724) (xy 51.550041 -392.071089)
			(xy 51.599651 -392.093746) (xy 51.645532 -392.123232) (xy 51.686749 -392.158947) (xy 51.722464 -392.200164)
			(xy 51.75195 -392.246045) (xy 51.774607 -392.295655) (xy 51.789972 -392.347985) (xy 51.797734 -392.401969)
			(xy 51.79822 -392.429238) (xy 51.79822 -393.292838) (xy 52.2351 -393.292838) (xy 52.2351 -392.429238)
			(xy 52.235586 -392.401987) (xy 52.243342 -392.348039) (xy 52.258697 -392.295744) (xy 52.281339 -392.246167)
			(xy 52.310805 -392.200317) (xy 52.346496 -392.159126) (xy 52.387687 -392.123435) (xy 52.433537 -392.093969)
			(xy 52.483114 -392.071327) (xy 52.535409 -392.055972) (xy 52.589357 -392.048216) (xy 52.643859 -392.048216)
			(xy 52.697807 -392.055972) (xy 52.750102 -392.071327) (xy 52.799679 -392.093969) (xy 52.845529 -392.123435)
			(xy 52.88672 -392.159126) (xy 52.922411 -392.200317) (xy 52.951877 -392.246167) (xy 52.974519 -392.295744)
			(xy 52.989874 -392.348039) (xy 52.99763 -392.401987) (xy 52.998116 -392.429238) (xy 52.998116 -393.292838)
			(xy 53.434996 -393.292838) (xy 53.434996 -392.429238) (xy 53.435482 -392.401987) (xy 53.443238 -392.348039)
			(xy 53.458593 -392.295744) (xy 53.481235 -392.246167) (xy 53.510701 -392.200317) (xy 53.546392 -392.159126)
			(xy 53.587583 -392.123435) (xy 53.633433 -392.093969) (xy 53.68301 -392.071327) (xy 53.735305 -392.055972)
			(xy 53.789253 -392.048216) (xy 53.843755 -392.048216) (xy 53.897703 -392.055972) (xy 53.949998 -392.071327)
			(xy 53.999575 -392.093969) (xy 54.045425 -392.123435) (xy 54.086616 -392.159126) (xy 54.122307 -392.200317)
			(xy 54.151773 -392.246167) (xy 54.174415 -392.295744) (xy 54.18977 -392.348039) (xy 54.197526 -392.401987)
			(xy 54.198012 -392.429238) (xy 54.198012 -393.292838) (xy 54.634892 -393.292838) (xy 54.634892 -392.429238)
			(xy 54.635378 -392.401969) (xy 54.64314 -392.347985) (xy 54.658505 -392.295655) (xy 54.681162 -392.246045)
			(xy 54.710648 -392.200164) (xy 54.746363 -392.158947) (xy 54.78758 -392.123232) (xy 54.833461 -392.093746)
			(xy 54.883071 -392.071089) (xy 54.935401 -392.055724) (xy 54.989385 -392.047962) (xy 55.043923 -392.047962)
			(xy 55.097907 -392.055724) (xy 55.150237 -392.071089) (xy 55.199847 -392.093746) (xy 55.245728 -392.123232)
			(xy 55.286945 -392.158947) (xy 55.32266 -392.200164) (xy 55.352146 -392.246045) (xy 55.374803 -392.295655)
			(xy 55.390168 -392.347985) (xy 55.39793 -392.401969) (xy 55.398416 -392.429238) (xy 55.398416 -393.292838)
			(xy 55.834788 -393.292838) (xy 55.834788 -392.429238) (xy 55.835274 -392.401969) (xy 55.843036 -392.347985)
			(xy 55.858401 -392.295655) (xy 55.881058 -392.246045) (xy 55.910544 -392.200164) (xy 55.946259 -392.158947)
			(xy 55.987476 -392.123232) (xy 56.033357 -392.093746) (xy 56.082967 -392.071089) (xy 56.135297 -392.055724)
			(xy 56.189281 -392.047962) (xy 56.243819 -392.047962) (xy 56.297803 -392.055724) (xy 56.350133 -392.071089)
			(xy 56.399743 -392.093746) (xy 56.445624 -392.123232) (xy 56.486841 -392.158947) (xy 56.522556 -392.200164)
			(xy 56.552042 -392.246045) (xy 56.574699 -392.295655) (xy 56.590064 -392.347985) (xy 56.597826 -392.401969)
			(xy 56.598312 -392.429238) (xy 56.598312 -393.292838) (xy 57.035192 -393.292838) (xy 57.035192 -392.429238)
			(xy 57.035678 -392.401987) (xy 57.043434 -392.348039) (xy 57.058789 -392.295744) (xy 57.081431 -392.246167)
			(xy 57.110897 -392.200317) (xy 57.146588 -392.159126) (xy 57.187779 -392.123435) (xy 57.233629 -392.093969)
			(xy 57.283206 -392.071327) (xy 57.335501 -392.055972) (xy 57.389449 -392.048216) (xy 57.443951 -392.048216)
			(xy 57.497899 -392.055972) (xy 57.550194 -392.071327) (xy 57.599771 -392.093969) (xy 57.645621 -392.123435)
			(xy 57.686812 -392.159126) (xy 57.722503 -392.200317) (xy 57.751969 -392.246167) (xy 57.774611 -392.295744)
			(xy 57.789966 -392.348039) (xy 57.797722 -392.401987) (xy 57.798208 -392.429238) (xy 57.798208 -393.292838)
			(xy 58.235088 -393.292838) (xy 58.235088 -392.429238) (xy 58.235574 -392.401987) (xy 58.24333 -392.348039)
			(xy 58.258685 -392.295744) (xy 58.281327 -392.246167) (xy 58.310793 -392.200317) (xy 58.346484 -392.159126)
			(xy 58.387675 -392.123435) (xy 58.433525 -392.093969) (xy 58.483102 -392.071327) (xy 58.535397 -392.055972)
			(xy 58.589345 -392.048216) (xy 58.643847 -392.048216) (xy 58.697795 -392.055972) (xy 58.75009 -392.071327)
			(xy 58.799667 -392.093969) (xy 58.845517 -392.123435) (xy 58.886708 -392.159126) (xy 58.922399 -392.200317)
			(xy 58.951865 -392.246167) (xy 58.974507 -392.295744) (xy 58.989862 -392.348039) (xy 58.997618 -392.401987)
			(xy 58.998104 -392.429238) (xy 58.998104 -393.292838) (xy 59.434984 -393.292838) (xy 59.434984 -392.429238)
			(xy 59.43547 -392.401969) (xy 59.443232 -392.347985) (xy 59.458597 -392.295655) (xy 59.481254 -392.246045)
			(xy 59.51074 -392.200164) (xy 59.546455 -392.158947) (xy 59.587672 -392.123232) (xy 59.633553 -392.093746)
			(xy 59.683163 -392.071089) (xy 59.735493 -392.055724) (xy 59.789477 -392.047962) (xy 59.844015 -392.047962)
			(xy 59.897999 -392.055724) (xy 59.950329 -392.071089) (xy 59.999939 -392.093746) (xy 60.04582 -392.123232)
			(xy 60.087037 -392.158947) (xy 60.122752 -392.200164) (xy 60.152238 -392.246045) (xy 60.174895 -392.295655)
			(xy 60.19026 -392.347985) (xy 60.198022 -392.401969) (xy 60.198508 -392.429238) (xy 60.198508 -393.292838)
			(xy 60.63488 -393.292838) (xy 60.63488 -392.429238) (xy 60.635366 -392.401969) (xy 60.643128 -392.347985)
			(xy 60.658493 -392.295655) (xy 60.68115 -392.246045) (xy 60.710636 -392.200164) (xy 60.746351 -392.158947)
			(xy 60.787568 -392.123232) (xy 60.833449 -392.093746) (xy 60.883059 -392.071089) (xy 60.935389 -392.055724)
			(xy 60.989373 -392.047962) (xy 61.043911 -392.047962) (xy 61.097895 -392.055724) (xy 61.150225 -392.071089)
			(xy 61.199835 -392.093746) (xy 61.245716 -392.123232) (xy 61.286933 -392.158947) (xy 61.322648 -392.200164)
			(xy 61.352134 -392.246045) (xy 61.374791 -392.295655) (xy 61.390156 -392.347985) (xy 61.397918 -392.401969)
			(xy 61.398404 -392.429238) (xy 61.398404 -393.292838) (xy 61.834776 -393.292838) (xy 61.834776 -392.429238)
			(xy 61.835262 -392.401969) (xy 61.843024 -392.347985) (xy 61.858389 -392.295655) (xy 61.881046 -392.246045)
			(xy 61.910532 -392.200164) (xy 61.946247 -392.158947) (xy 61.987464 -392.123232) (xy 62.033345 -392.093746)
			(xy 62.082955 -392.071089) (xy 62.135285 -392.055724) (xy 62.189269 -392.047962) (xy 62.243807 -392.047962)
			(xy 62.297791 -392.055724) (xy 62.350121 -392.071089) (xy 62.399731 -392.093746) (xy 62.445612 -392.123232)
			(xy 62.486829 -392.158947) (xy 62.522544 -392.200164) (xy 62.55203 -392.246045) (xy 62.574687 -392.295655)
			(xy 62.590052 -392.347985) (xy 62.597814 -392.401969) (xy 62.5983 -392.429238) (xy 62.5983 -393.292838)
			(xy 63.034672 -393.292838) (xy 63.034672 -392.429238) (xy 63.035158 -392.401969) (xy 63.04292 -392.347985)
			(xy 63.058285 -392.295655) (xy 63.080942 -392.246045) (xy 63.110428 -392.200164) (xy 63.146143 -392.158947)
			(xy 63.18736 -392.123232) (xy 63.233241 -392.093746) (xy 63.282851 -392.071089) (xy 63.335181 -392.055724)
			(xy 63.389165 -392.047962) (xy 63.443703 -392.047962) (xy 63.497687 -392.055724) (xy 63.550017 -392.071089)
			(xy 63.599627 -392.093746) (xy 63.645508 -392.123232) (xy 63.686725 -392.158947) (xy 63.72244 -392.200164)
			(xy 63.751926 -392.246045) (xy 63.774583 -392.295655) (xy 63.789948 -392.347985) (xy 63.79771 -392.401969)
			(xy 63.798196 -392.429238) (xy 63.798196 -393.292838) (xy 64.235076 -393.292838) (xy 64.235076 -392.429238)
			(xy 64.235562 -392.401987) (xy 64.243318 -392.348039) (xy 64.258673 -392.295744) (xy 64.281315 -392.246167)
			(xy 64.310781 -392.200317) (xy 64.346472 -392.159126) (xy 64.387663 -392.123435) (xy 64.433513 -392.093969)
			(xy 64.48309 -392.071327) (xy 64.535385 -392.055972) (xy 64.589333 -392.048216) (xy 64.643835 -392.048216)
			(xy 64.697783 -392.055972) (xy 64.750078 -392.071327) (xy 64.799655 -392.093969) (xy 64.845505 -392.123435)
			(xy 64.886696 -392.159126) (xy 64.922387 -392.200317) (xy 64.951853 -392.246167) (xy 64.974495 -392.295744)
			(xy 64.98985 -392.348039) (xy 64.997606 -392.401987) (xy 64.998092 -392.429238) (xy 64.998092 -393.292838)
			(xy 65.434972 -393.292838) (xy 65.434972 -392.429238) (xy 65.435458 -392.401987) (xy 65.443214 -392.348039)
			(xy 65.458569 -392.295744) (xy 65.481211 -392.246167) (xy 65.510677 -392.200317) (xy 65.546368 -392.159126)
			(xy 65.587559 -392.123435) (xy 65.633409 -392.093969) (xy 65.682986 -392.071327) (xy 65.735281 -392.055972)
			(xy 65.789229 -392.048216) (xy 65.843731 -392.048216) (xy 65.897679 -392.055972) (xy 65.949974 -392.071327)
			(xy 65.999551 -392.093969) (xy 66.045401 -392.123435) (xy 66.086592 -392.159126) (xy 66.122283 -392.200317)
			(xy 66.151749 -392.246167) (xy 66.174391 -392.295744) (xy 66.189746 -392.348039) (xy 66.197502 -392.401987)
			(xy 66.197988 -392.429238) (xy 66.197988 -393.292838) (xy 79.962756 -393.292838) (xy 79.962756 -392.429238)
			(xy 79.963242 -392.401987) (xy 79.970998 -392.348039) (xy 79.986353 -392.295744) (xy 80.008995 -392.246167)
			(xy 80.038461 -392.200317) (xy 80.074152 -392.159126) (xy 80.115343 -392.123435) (xy 80.161193 -392.093969)
			(xy 80.21077 -392.071327) (xy 80.263065 -392.055972) (xy 80.317013 -392.048216) (xy 80.371515 -392.048216)
			(xy 80.425463 -392.055972) (xy 80.477758 -392.071327) (xy 80.527335 -392.093969) (xy 80.573185 -392.123435)
			(xy 80.614376 -392.159126) (xy 80.650067 -392.200317) (xy 80.679533 -392.246167) (xy 80.702175 -392.295744)
			(xy 80.71753 -392.348039) (xy 80.725286 -392.401987) (xy 80.725772 -392.429238) (xy 80.725772 -393.292838)
			(xy 81.162652 -393.292838) (xy 81.162652 -392.429238) (xy 81.163138 -392.401987) (xy 81.170894 -392.348039)
			(xy 81.186249 -392.295744) (xy 81.208891 -392.246167) (xy 81.238357 -392.200317) (xy 81.274048 -392.159126)
			(xy 81.315239 -392.123435) (xy 81.361089 -392.093969) (xy 81.410666 -392.071327) (xy 81.462961 -392.055972)
			(xy 81.516909 -392.048216) (xy 81.571411 -392.048216) (xy 81.625359 -392.055972) (xy 81.677654 -392.071327)
			(xy 81.727231 -392.093969) (xy 81.773081 -392.123435) (xy 81.814272 -392.159126) (xy 81.849963 -392.200317)
			(xy 81.879429 -392.246167) (xy 81.902071 -392.295744) (xy 81.917426 -392.348039) (xy 81.925182 -392.401987)
			(xy 81.925668 -392.429238) (xy 81.925668 -393.292838) (xy 82.362548 -393.292838) (xy 82.362548 -392.429238)
			(xy 82.363034 -392.401969) (xy 82.370796 -392.347985) (xy 82.386161 -392.295655) (xy 82.408818 -392.246045)
			(xy 82.438304 -392.200164) (xy 82.474019 -392.158947) (xy 82.515236 -392.123232) (xy 82.561117 -392.093746)
			(xy 82.610727 -392.071089) (xy 82.663057 -392.055724) (xy 82.717041 -392.047962) (xy 82.771579 -392.047962)
			(xy 82.825563 -392.055724) (xy 82.877893 -392.071089) (xy 82.927503 -392.093746) (xy 82.973384 -392.123232)
			(xy 83.014601 -392.158947) (xy 83.050316 -392.200164) (xy 83.079802 -392.246045) (xy 83.102459 -392.295655)
			(xy 83.117824 -392.347985) (xy 83.125586 -392.401969) (xy 83.126072 -392.429238) (xy 83.126072 -393.292838)
			(xy 83.562444 -393.292838) (xy 83.562444 -392.429238) (xy 83.56293 -392.401969) (xy 83.570692 -392.347985)
			(xy 83.586057 -392.295655) (xy 83.608714 -392.246045) (xy 83.6382 -392.200164) (xy 83.673915 -392.158947)
			(xy 83.715132 -392.123232) (xy 83.761013 -392.093746) (xy 83.810623 -392.071089) (xy 83.862953 -392.055724)
			(xy 83.916937 -392.047962) (xy 83.971475 -392.047962) (xy 84.025459 -392.055724) (xy 84.077789 -392.071089)
			(xy 84.127399 -392.093746) (xy 84.17328 -392.123232) (xy 84.214497 -392.158947) (xy 84.250212 -392.200164)
			(xy 84.279698 -392.246045) (xy 84.302355 -392.295655) (xy 84.31772 -392.347985) (xy 84.325482 -392.401969)
			(xy 84.325968 -392.429238) (xy 84.325968 -393.292838) (xy 84.762848 -393.292838) (xy 84.762848 -392.429238)
			(xy 84.763334 -392.401987) (xy 84.77109 -392.348039) (xy 84.786445 -392.295744) (xy 84.809087 -392.246167)
			(xy 84.838553 -392.200317) (xy 84.874244 -392.159126) (xy 84.915435 -392.123435) (xy 84.961285 -392.093969)
			(xy 85.010862 -392.071327) (xy 85.063157 -392.055972) (xy 85.117105 -392.048216) (xy 85.171607 -392.048216)
			(xy 85.225555 -392.055972) (xy 85.27785 -392.071327) (xy 85.327427 -392.093969) (xy 85.373277 -392.123435)
			(xy 85.414468 -392.159126) (xy 85.450159 -392.200317) (xy 85.479625 -392.246167) (xy 85.502267 -392.295744)
			(xy 85.517622 -392.348039) (xy 85.525378 -392.401987) (xy 85.525864 -392.429238) (xy 85.525864 -393.292838)
			(xy 85.962744 -393.292838) (xy 85.962744 -392.429238) (xy 85.96323 -392.401987) (xy 85.970986 -392.348039)
			(xy 85.986341 -392.295744) (xy 86.008983 -392.246167) (xy 86.038449 -392.200317) (xy 86.07414 -392.159126)
			(xy 86.115331 -392.123435) (xy 86.161181 -392.093969) (xy 86.210758 -392.071327) (xy 86.263053 -392.055972)
			(xy 86.317001 -392.048216) (xy 86.371503 -392.048216) (xy 86.425451 -392.055972) (xy 86.477746 -392.071327)
			(xy 86.527323 -392.093969) (xy 86.573173 -392.123435) (xy 86.614364 -392.159126) (xy 86.650055 -392.200317)
			(xy 86.679521 -392.246167) (xy 86.702163 -392.295744) (xy 86.717518 -392.348039) (xy 86.725274 -392.401987)
			(xy 86.72576 -392.429238) (xy 86.72576 -393.292838) (xy 87.16264 -393.292838) (xy 87.16264 -392.429238)
			(xy 87.163126 -392.401969) (xy 87.170888 -392.347985) (xy 87.186253 -392.295655) (xy 87.20891 -392.246045)
			(xy 87.238396 -392.200164) (xy 87.274111 -392.158947) (xy 87.315328 -392.123232) (xy 87.361209 -392.093746)
			(xy 87.410819 -392.071089) (xy 87.463149 -392.055724) (xy 87.517133 -392.047962) (xy 87.571671 -392.047962)
			(xy 87.625655 -392.055724) (xy 87.677985 -392.071089) (xy 87.727595 -392.093746) (xy 87.773476 -392.123232)
			(xy 87.814693 -392.158947) (xy 87.850408 -392.200164) (xy 87.879894 -392.246045) (xy 87.902551 -392.295655)
			(xy 87.917916 -392.347985) (xy 87.925678 -392.401969) (xy 87.926164 -392.429238) (xy 87.926164 -393.292838)
			(xy 88.362536 -393.292838) (xy 88.362536 -392.429238) (xy 88.363022 -392.401969) (xy 88.370784 -392.347985)
			(xy 88.386149 -392.295655) (xy 88.408806 -392.246045) (xy 88.438292 -392.200164) (xy 88.474007 -392.158947)
			(xy 88.515224 -392.123232) (xy 88.561105 -392.093746) (xy 88.610715 -392.071089) (xy 88.663045 -392.055724)
			(xy 88.717029 -392.047962) (xy 88.771567 -392.047962) (xy 88.825551 -392.055724) (xy 88.877881 -392.071089)
			(xy 88.927491 -392.093746) (xy 88.973372 -392.123232) (xy 89.014589 -392.158947) (xy 89.050304 -392.200164)
			(xy 89.07979 -392.246045) (xy 89.102447 -392.295655) (xy 89.117812 -392.347985) (xy 89.125574 -392.401969)
			(xy 89.12606 -392.429238) (xy 89.12606 -393.292838) (xy 89.56294 -393.292838) (xy 89.56294 -392.429238)
			(xy 89.563426 -392.401987) (xy 89.571182 -392.348039) (xy 89.586537 -392.295744) (xy 89.609179 -392.246167)
			(xy 89.638645 -392.200317) (xy 89.674336 -392.159126) (xy 89.715527 -392.123435) (xy 89.761377 -392.093969)
			(xy 89.810954 -392.071327) (xy 89.863249 -392.055972) (xy 89.917197 -392.048216) (xy 89.971699 -392.048216)
			(xy 90.025647 -392.055972) (xy 90.077942 -392.071327) (xy 90.127519 -392.093969) (xy 90.173369 -392.123435)
			(xy 90.21456 -392.159126) (xy 90.250251 -392.200317) (xy 90.279717 -392.246167) (xy 90.302359 -392.295744)
			(xy 90.317714 -392.348039) (xy 90.32547 -392.401987) (xy 90.325956 -392.429238) (xy 90.325956 -393.292838)
			(xy 90.762836 -393.292838) (xy 90.762836 -392.429238) (xy 90.763322 -392.401987) (xy 90.771078 -392.348039)
			(xy 90.786433 -392.295744) (xy 90.809075 -392.246167) (xy 90.838541 -392.200317) (xy 90.874232 -392.159126)
			(xy 90.915423 -392.123435) (xy 90.961273 -392.093969) (xy 91.01085 -392.071327) (xy 91.063145 -392.055972)
			(xy 91.117093 -392.048216) (xy 91.171595 -392.048216) (xy 91.225543 -392.055972) (xy 91.277838 -392.071327)
			(xy 91.327415 -392.093969) (xy 91.373265 -392.123435) (xy 91.414456 -392.159126) (xy 91.450147 -392.200317)
			(xy 91.479613 -392.246167) (xy 91.502255 -392.295744) (xy 91.51761 -392.348039) (xy 91.525366 -392.401987)
			(xy 91.525852 -392.429238) (xy 91.525852 -393.292838) (xy 91.962732 -393.292838) (xy 91.962732 -392.429238)
			(xy 91.963218 -392.401969) (xy 91.97098 -392.347985) (xy 91.986345 -392.295655) (xy 92.009002 -392.246045)
			(xy 92.038488 -392.200164) (xy 92.074203 -392.158947) (xy 92.11542 -392.123232) (xy 92.161301 -392.093746)
			(xy 92.210911 -392.071089) (xy 92.263241 -392.055724) (xy 92.317225 -392.047962) (xy 92.371763 -392.047962)
			(xy 92.425747 -392.055724) (xy 92.478077 -392.071089) (xy 92.527687 -392.093746) (xy 92.573568 -392.123232)
			(xy 92.614785 -392.158947) (xy 92.6505 -392.200164) (xy 92.679986 -392.246045) (xy 92.702643 -392.295655)
			(xy 92.718008 -392.347985) (xy 92.72577 -392.401969) (xy 92.726256 -392.429238) (xy 92.726256 -393.292838)
			(xy 93.162628 -393.292838) (xy 93.162628 -392.429238) (xy 93.163114 -392.401969) (xy 93.170876 -392.347985)
			(xy 93.186241 -392.295655) (xy 93.208898 -392.246045) (xy 93.238384 -392.200164) (xy 93.274099 -392.158947)
			(xy 93.315316 -392.123232) (xy 93.361197 -392.093746) (xy 93.410807 -392.071089) (xy 93.463137 -392.055724)
			(xy 93.517121 -392.047962) (xy 93.571659 -392.047962) (xy 93.625643 -392.055724) (xy 93.677973 -392.071089)
			(xy 93.727583 -392.093746) (xy 93.773464 -392.123232) (xy 93.814681 -392.158947) (xy 93.850396 -392.200164)
			(xy 93.879882 -392.246045) (xy 93.902539 -392.295655) (xy 93.917904 -392.347985) (xy 93.925666 -392.401969)
			(xy 93.926152 -392.429238) (xy 93.926152 -393.292838) (xy 94.362524 -393.292838) (xy 94.362524 -392.429238)
			(xy 94.36301 -392.401969) (xy 94.370772 -392.347985) (xy 94.386137 -392.295655) (xy 94.408794 -392.246045)
			(xy 94.43828 -392.200164) (xy 94.473995 -392.158947) (xy 94.515212 -392.123232) (xy 94.561093 -392.093746)
			(xy 94.610703 -392.071089) (xy 94.663033 -392.055724) (xy 94.717017 -392.047962) (xy 94.771555 -392.047962)
			(xy 94.825539 -392.055724) (xy 94.877869 -392.071089) (xy 94.927479 -392.093746) (xy 94.97336 -392.123232)
			(xy 95.014577 -392.158947) (xy 95.050292 -392.200164) (xy 95.079778 -392.246045) (xy 95.102435 -392.295655)
			(xy 95.1178 -392.347985) (xy 95.125562 -392.401969) (xy 95.126048 -392.429238) (xy 95.126048 -393.292838)
			(xy 95.56242 -393.292838) (xy 95.56242 -392.429238) (xy 95.562906 -392.401969) (xy 95.570668 -392.347985)
			(xy 95.586033 -392.295655) (xy 95.60869 -392.246045) (xy 95.638176 -392.200164) (xy 95.673891 -392.158947)
			(xy 95.715108 -392.123232) (xy 95.760989 -392.093746) (xy 95.810599 -392.071089) (xy 95.862929 -392.055724)
			(xy 95.916913 -392.047962) (xy 95.971451 -392.047962) (xy 96.025435 -392.055724) (xy 96.077765 -392.071089)
			(xy 96.127375 -392.093746) (xy 96.173256 -392.123232) (xy 96.214473 -392.158947) (xy 96.250188 -392.200164)
			(xy 96.279674 -392.246045) (xy 96.302331 -392.295655) (xy 96.317696 -392.347985) (xy 96.325458 -392.401969)
			(xy 96.325944 -392.429238) (xy 96.325944 -393.292838) (xy 96.762824 -393.292838) (xy 96.762824 -392.429238)
			(xy 96.76331 -392.401987) (xy 96.771066 -392.348039) (xy 96.786421 -392.295744) (xy 96.809063 -392.246167)
			(xy 96.838529 -392.200317) (xy 96.87422 -392.159126) (xy 96.915411 -392.123435) (xy 96.961261 -392.093969)
			(xy 97.010838 -392.071327) (xy 97.063133 -392.055972) (xy 97.117081 -392.048216) (xy 97.171583 -392.048216)
			(xy 97.225531 -392.055972) (xy 97.277826 -392.071327) (xy 97.327403 -392.093969) (xy 97.373253 -392.123435)
			(xy 97.414444 -392.159126) (xy 97.450135 -392.200317) (xy 97.479601 -392.246167) (xy 97.502243 -392.295744)
			(xy 97.517598 -392.348039) (xy 97.525354 -392.401987) (xy 97.52584 -392.429238) (xy 97.52584 -393.292838)
			(xy 97.96272 -393.292838) (xy 97.96272 -392.429238) (xy 97.963206 -392.401987) (xy 97.970962 -392.348039)
			(xy 97.986317 -392.295744) (xy 98.008959 -392.246167) (xy 98.038425 -392.200317) (xy 98.074116 -392.159126)
			(xy 98.115307 -392.123435) (xy 98.161157 -392.093969) (xy 98.210734 -392.071327) (xy 98.263029 -392.055972)
			(xy 98.316977 -392.048216) (xy 98.371479 -392.048216) (xy 98.425427 -392.055972) (xy 98.477722 -392.071327)
			(xy 98.527299 -392.093969) (xy 98.573149 -392.123435) (xy 98.61434 -392.159126) (xy 98.650031 -392.200317)
			(xy 98.679497 -392.246167) (xy 98.702139 -392.295744) (xy 98.717494 -392.348039) (xy 98.72525 -392.401987)
			(xy 98.725736 -392.429238) (xy 98.725736 -393.292838) (xy 114.534696 -393.292838) (xy 114.534696 -392.429238)
			(xy 114.535182 -392.401969) (xy 114.542944 -392.347985) (xy 114.558309 -392.295655) (xy 114.580966 -392.246045)
			(xy 114.610452 -392.200164) (xy 114.646167 -392.158947) (xy 114.687384 -392.123232) (xy 114.733265 -392.093746)
			(xy 114.782875 -392.071089) (xy 114.835205 -392.055724) (xy 114.889189 -392.047962) (xy 114.943727 -392.047962)
			(xy 114.997711 -392.055724) (xy 115.050041 -392.071089) (xy 115.099651 -392.093746) (xy 115.145532 -392.123232)
			(xy 115.186749 -392.158947) (xy 115.222464 -392.200164) (xy 115.25195 -392.246045) (xy 115.274607 -392.295655)
			(xy 115.289972 -392.347985) (xy 115.297734 -392.401969) (xy 115.29822 -392.429238) (xy 115.29822 -393.292838)
			(xy 115.734592 -393.292838) (xy 115.734592 -392.429238) (xy 115.735078 -392.401969) (xy 115.74284 -392.347985)
			(xy 115.758205 -392.295655) (xy 115.780862 -392.246045) (xy 115.810348 -392.200164) (xy 115.846063 -392.158947)
			(xy 115.88728 -392.123232) (xy 115.933161 -392.093746) (xy 115.982771 -392.071089) (xy 116.035101 -392.055724)
			(xy 116.089085 -392.047962) (xy 116.143623 -392.047962) (xy 116.197607 -392.055724) (xy 116.249937 -392.071089)
			(xy 116.299547 -392.093746) (xy 116.345428 -392.123232) (xy 116.386645 -392.158947) (xy 116.42236 -392.200164)
			(xy 116.451846 -392.246045) (xy 116.474503 -392.295655) (xy 116.489868 -392.347985) (xy 116.49763 -392.401969)
			(xy 116.498116 -392.429238) (xy 116.498116 -393.292838) (xy 116.934996 -393.292838) (xy 116.934996 -392.429238)
			(xy 116.935482 -392.401987) (xy 116.943238 -392.348039) (xy 116.958593 -392.295744) (xy 116.981235 -392.246167)
			(xy 117.010701 -392.200317) (xy 117.046392 -392.159126) (xy 117.087583 -392.123435) (xy 117.133433 -392.093969)
			(xy 117.18301 -392.071327) (xy 117.235305 -392.055972) (xy 117.289253 -392.048216) (xy 117.343755 -392.048216)
			(xy 117.397703 -392.055972) (xy 117.449998 -392.071327) (xy 117.499575 -392.093969) (xy 117.545425 -392.123435)
			(xy 117.586616 -392.159126) (xy 117.622307 -392.200317) (xy 117.651773 -392.246167) (xy 117.674415 -392.295744)
			(xy 117.68977 -392.348039) (xy 117.697526 -392.401987) (xy 117.698012 -392.429238) (xy 117.698012 -393.292838)
			(xy 118.134892 -393.292838) (xy 118.134892 -392.429238) (xy 118.135378 -392.401987) (xy 118.143134 -392.348039)
			(xy 118.158489 -392.295744) (xy 118.181131 -392.246167) (xy 118.210597 -392.200317) (xy 118.246288 -392.159126)
			(xy 118.287479 -392.123435) (xy 118.333329 -392.093969) (xy 118.382906 -392.071327) (xy 118.435201 -392.055972)
			(xy 118.489149 -392.048216) (xy 118.543651 -392.048216) (xy 118.597599 -392.055972) (xy 118.649894 -392.071327)
			(xy 118.699471 -392.093969) (xy 118.745321 -392.123435) (xy 118.786512 -392.159126) (xy 118.822203 -392.200317)
			(xy 118.851669 -392.246167) (xy 118.874311 -392.295744) (xy 118.889666 -392.348039) (xy 118.897422 -392.401987)
			(xy 118.897908 -392.429238) (xy 118.897908 -393.292838) (xy 119.334788 -393.292838) (xy 119.334788 -392.429238)
			(xy 119.335274 -392.401969) (xy 119.343036 -392.347985) (xy 119.358401 -392.295655) (xy 119.381058 -392.246045)
			(xy 119.410544 -392.200164) (xy 119.446259 -392.158947) (xy 119.487476 -392.123232) (xy 119.533357 -392.093746)
			(xy 119.582967 -392.071089) (xy 119.635297 -392.055724) (xy 119.689281 -392.047962) (xy 119.743819 -392.047962)
			(xy 119.797803 -392.055724) (xy 119.850133 -392.071089) (xy 119.899743 -392.093746) (xy 119.945624 -392.123232)
			(xy 119.986841 -392.158947) (xy 120.022556 -392.200164) (xy 120.052042 -392.246045) (xy 120.074699 -392.295655)
			(xy 120.090064 -392.347985) (xy 120.097826 -392.401969) (xy 120.098312 -392.429238) (xy 120.098312 -393.292838)
			(xy 120.534684 -393.292838) (xy 120.534684 -392.429238) (xy 120.53517 -392.401969) (xy 120.542932 -392.347985)
			(xy 120.558297 -392.295655) (xy 120.580954 -392.246045) (xy 120.61044 -392.200164) (xy 120.646155 -392.158947)
			(xy 120.687372 -392.123232) (xy 120.733253 -392.093746) (xy 120.782863 -392.071089) (xy 120.835193 -392.055724)
			(xy 120.889177 -392.047962) (xy 120.943715 -392.047962) (xy 120.997699 -392.055724) (xy 121.050029 -392.071089)
			(xy 121.099639 -392.093746) (xy 121.14552 -392.123232) (xy 121.186737 -392.158947) (xy 121.222452 -392.200164)
			(xy 121.251938 -392.246045) (xy 121.274595 -392.295655) (xy 121.28996 -392.347985) (xy 121.297722 -392.401969)
			(xy 121.298208 -392.429238) (xy 121.298208 -393.292838) (xy 121.735088 -393.292838) (xy 121.735088 -392.429238)
			(xy 121.735574 -392.401987) (xy 121.74333 -392.348039) (xy 121.758685 -392.295744) (xy 121.781327 -392.246167)
			(xy 121.810793 -392.200317) (xy 121.846484 -392.159126) (xy 121.887675 -392.123435) (xy 121.933525 -392.093969)
			(xy 121.983102 -392.071327) (xy 122.035397 -392.055972) (xy 122.089345 -392.048216) (xy 122.143847 -392.048216)
			(xy 122.197795 -392.055972) (xy 122.25009 -392.071327) (xy 122.299667 -392.093969) (xy 122.345517 -392.123435)
			(xy 122.386708 -392.159126) (xy 122.422399 -392.200317) (xy 122.451865 -392.246167) (xy 122.474507 -392.295744)
			(xy 122.489862 -392.348039) (xy 122.497618 -392.401987) (xy 122.498104 -392.429238) (xy 122.498104 -393.292838)
			(xy 122.934984 -393.292838) (xy 122.934984 -392.429238) (xy 122.93547 -392.401987) (xy 122.943226 -392.348039)
			(xy 122.958581 -392.295744) (xy 122.981223 -392.246167) (xy 123.010689 -392.200317) (xy 123.04638 -392.159126)
			(xy 123.087571 -392.123435) (xy 123.133421 -392.093969) (xy 123.182998 -392.071327) (xy 123.235293 -392.055972)
			(xy 123.289241 -392.048216) (xy 123.343743 -392.048216) (xy 123.397691 -392.055972) (xy 123.449986 -392.071327)
			(xy 123.499563 -392.093969) (xy 123.545413 -392.123435) (xy 123.586604 -392.159126) (xy 123.622295 -392.200317)
			(xy 123.651761 -392.246167) (xy 123.674403 -392.295744) (xy 123.689758 -392.348039) (xy 123.697514 -392.401987)
			(xy 123.698 -392.429238) (xy 123.698 -393.292838) (xy 124.13488 -393.292838) (xy 124.13488 -392.429238)
			(xy 124.135366 -392.401969) (xy 124.143128 -392.347985) (xy 124.158493 -392.295655) (xy 124.18115 -392.246045)
			(xy 124.210636 -392.200164) (xy 124.246351 -392.158947) (xy 124.287568 -392.123232) (xy 124.333449 -392.093746)
			(xy 124.383059 -392.071089) (xy 124.435389 -392.055724) (xy 124.489373 -392.047962) (xy 124.543911 -392.047962)
			(xy 124.597895 -392.055724) (xy 124.650225 -392.071089) (xy 124.699835 -392.093746) (xy 124.745716 -392.123232)
			(xy 124.786933 -392.158947) (xy 124.822648 -392.200164) (xy 124.852134 -392.246045) (xy 124.874791 -392.295655)
			(xy 124.890156 -392.347985) (xy 124.897918 -392.401969) (xy 124.898404 -392.429238) (xy 124.898404 -393.292838)
			(xy 125.334776 -393.292838) (xy 125.334776 -392.429238) (xy 125.335262 -392.401969) (xy 125.343024 -392.347985)
			(xy 125.358389 -392.295655) (xy 125.381046 -392.246045) (xy 125.410532 -392.200164) (xy 125.446247 -392.158947)
			(xy 125.487464 -392.123232) (xy 125.533345 -392.093746) (xy 125.582955 -392.071089) (xy 125.635285 -392.055724)
			(xy 125.689269 -392.047962) (xy 125.743807 -392.047962) (xy 125.797791 -392.055724) (xy 125.850121 -392.071089)
			(xy 125.899731 -392.093746) (xy 125.945612 -392.123232) (xy 125.986829 -392.158947) (xy 126.022544 -392.200164)
			(xy 126.05203 -392.246045) (xy 126.074687 -392.295655) (xy 126.090052 -392.347985) (xy 126.097814 -392.401969)
			(xy 126.0983 -392.429238) (xy 126.0983 -393.292838) (xy 126.53518 -393.292838) (xy 126.53518 -392.429238)
			(xy 126.535666 -392.401987) (xy 126.543422 -392.348039) (xy 126.558777 -392.295744) (xy 126.581419 -392.246167)
			(xy 126.610885 -392.200317) (xy 126.646576 -392.159126) (xy 126.687767 -392.123435) (xy 126.733617 -392.093969)
			(xy 126.783194 -392.071327) (xy 126.835489 -392.055972) (xy 126.889437 -392.048216) (xy 126.943939 -392.048216)
			(xy 126.997887 -392.055972) (xy 127.050182 -392.071327) (xy 127.099759 -392.093969) (xy 127.145609 -392.123435)
			(xy 127.1868 -392.159126) (xy 127.222491 -392.200317) (xy 127.251957 -392.246167) (xy 127.274599 -392.295744)
			(xy 127.289954 -392.348039) (xy 127.29771 -392.401987) (xy 127.298196 -392.429238) (xy 127.298196 -393.292838)
			(xy 127.735076 -393.292838) (xy 127.735076 -392.429238) (xy 127.735562 -392.401987) (xy 127.743318 -392.348039)
			(xy 127.758673 -392.295744) (xy 127.781315 -392.246167) (xy 127.810781 -392.200317) (xy 127.846472 -392.159126)
			(xy 127.887663 -392.123435) (xy 127.933513 -392.093969) (xy 127.98309 -392.071327) (xy 128.035385 -392.055972)
			(xy 128.089333 -392.048216) (xy 128.143835 -392.048216) (xy 128.197783 -392.055972) (xy 128.250078 -392.071327)
			(xy 128.299655 -392.093969) (xy 128.345505 -392.123435) (xy 128.386696 -392.159126) (xy 128.422387 -392.200317)
			(xy 128.451853 -392.246167) (xy 128.474495 -392.295744) (xy 128.48985 -392.348039) (xy 128.497606 -392.401987)
			(xy 128.498092 -392.429238) (xy 128.498092 -393.292838) (xy 128.934972 -393.292838) (xy 128.934972 -392.429238)
			(xy 128.935458 -392.401987) (xy 128.943214 -392.348039) (xy 128.958569 -392.295744) (xy 128.981211 -392.246167)
			(xy 129.010677 -392.200317) (xy 129.046368 -392.159126) (xy 129.087559 -392.123435) (xy 129.133409 -392.093969)
			(xy 129.182986 -392.071327) (xy 129.235281 -392.055972) (xy 129.289229 -392.048216) (xy 129.343731 -392.048216)
			(xy 129.397679 -392.055972) (xy 129.449974 -392.071327) (xy 129.499551 -392.093969) (xy 129.545401 -392.123435)
			(xy 129.586592 -392.159126) (xy 129.622283 -392.200317) (xy 129.651749 -392.246167) (xy 129.674391 -392.295744)
			(xy 129.689746 -392.348039) (xy 129.697502 -392.401987) (xy 129.697988 -392.429238) (xy 129.697988 -393.292838)
			(xy 130.134868 -393.292838) (xy 130.134868 -392.429238) (xy 130.135354 -392.401987) (xy 130.14311 -392.348039)
			(xy 130.158465 -392.295744) (xy 130.181107 -392.246167) (xy 130.210573 -392.200317) (xy 130.246264 -392.159126)
			(xy 130.287455 -392.123435) (xy 130.333305 -392.093969) (xy 130.382882 -392.071327) (xy 130.435177 -392.055972)
			(xy 130.489125 -392.048216) (xy 130.543627 -392.048216) (xy 130.597575 -392.055972) (xy 130.64987 -392.071327)
			(xy 130.699447 -392.093969) (xy 130.745297 -392.123435) (xy 130.786488 -392.159126) (xy 130.822179 -392.200317)
			(xy 130.851645 -392.246167) (xy 130.874287 -392.295744) (xy 130.889642 -392.348039) (xy 130.897398 -392.401987)
			(xy 130.897884 -392.429238) (xy 130.897884 -393.292838) (xy 131.334764 -393.292838) (xy 131.334764 -392.429238)
			(xy 131.33525 -392.401969) (xy 131.343012 -392.347985) (xy 131.358377 -392.295655) (xy 131.381034 -392.246045)
			(xy 131.41052 -392.200164) (xy 131.446235 -392.158947) (xy 131.487452 -392.123232) (xy 131.533333 -392.093746)
			(xy 131.582943 -392.071089) (xy 131.635273 -392.055724) (xy 131.689257 -392.047962) (xy 131.743795 -392.047962)
			(xy 131.797779 -392.055724) (xy 131.850109 -392.071089) (xy 131.899719 -392.093746) (xy 131.9456 -392.123232)
			(xy 131.986817 -392.158947) (xy 132.022532 -392.200164) (xy 132.052018 -392.246045) (xy 132.074675 -392.295655)
			(xy 132.09004 -392.347985) (xy 132.097802 -392.401969) (xy 132.098288 -392.429238) (xy 132.098288 -393.292838)
			(xy 132.53466 -393.292838) (xy 132.53466 -392.429238) (xy 132.535146 -392.401969) (xy 132.542908 -392.347985)
			(xy 132.558273 -392.295655) (xy 132.58093 -392.246045) (xy 132.610416 -392.200164) (xy 132.646131 -392.158947)
			(xy 132.687348 -392.123232) (xy 132.733229 -392.093746) (xy 132.782839 -392.071089) (xy 132.835169 -392.055724)
			(xy 132.889153 -392.047962) (xy 132.943691 -392.047962) (xy 132.997675 -392.055724) (xy 133.050005 -392.071089)
			(xy 133.099615 -392.093746) (xy 133.145496 -392.123232) (xy 133.186713 -392.158947) (xy 133.222428 -392.200164)
			(xy 133.251914 -392.246045) (xy 133.274571 -392.295655) (xy 133.289936 -392.347985) (xy 133.297698 -392.401969)
			(xy 133.298184 -392.429238) (xy 133.298184 -393.292838) (xy 147.062444 -393.292838) (xy 147.062444 -392.429238)
			(xy 147.06293 -392.401969) (xy 147.070692 -392.347985) (xy 147.086057 -392.295655) (xy 147.108714 -392.246045)
			(xy 147.1382 -392.200164) (xy 147.173915 -392.158947) (xy 147.215132 -392.123232) (xy 147.261013 -392.093746)
			(xy 147.310623 -392.071089) (xy 147.362953 -392.055724) (xy 147.416937 -392.047962) (xy 147.471475 -392.047962)
			(xy 147.525459 -392.055724) (xy 147.577789 -392.071089) (xy 147.627399 -392.093746) (xy 147.67328 -392.123232)
			(xy 147.714497 -392.158947) (xy 147.750212 -392.200164) (xy 147.779698 -392.246045) (xy 147.802355 -392.295655)
			(xy 147.81772 -392.347985) (xy 147.825482 -392.401969) (xy 147.825968 -392.429238) (xy 147.825968 -393.292838)
			(xy 148.26234 -393.292838) (xy 148.26234 -392.429238) (xy 148.262826 -392.401969) (xy 148.270588 -392.347985)
			(xy 148.285953 -392.295655) (xy 148.30861 -392.246045) (xy 148.338096 -392.200164) (xy 148.373811 -392.158947)
			(xy 148.415028 -392.123232) (xy 148.460909 -392.093746) (xy 148.510519 -392.071089) (xy 148.562849 -392.055724)
			(xy 148.616833 -392.047962) (xy 148.671371 -392.047962) (xy 148.725355 -392.055724) (xy 148.777685 -392.071089)
			(xy 148.827295 -392.093746) (xy 148.873176 -392.123232) (xy 148.914393 -392.158947) (xy 148.950108 -392.200164)
			(xy 148.979594 -392.246045) (xy 149.002251 -392.295655) (xy 149.017616 -392.347985) (xy 149.025378 -392.401969)
			(xy 149.025864 -392.429238) (xy 149.025864 -393.292838) (xy 149.462744 -393.292838) (xy 149.462744 -392.429238)
			(xy 149.46323 -392.401987) (xy 149.470986 -392.348039) (xy 149.486341 -392.295744) (xy 149.508983 -392.246167)
			(xy 149.538449 -392.200317) (xy 149.57414 -392.159126) (xy 149.615331 -392.123435) (xy 149.661181 -392.093969)
			(xy 149.710758 -392.071327) (xy 149.763053 -392.055972) (xy 149.817001 -392.048216) (xy 149.871503 -392.048216)
			(xy 149.925451 -392.055972) (xy 149.977746 -392.071327) (xy 150.027323 -392.093969) (xy 150.073173 -392.123435)
			(xy 150.114364 -392.159126) (xy 150.150055 -392.200317) (xy 150.179521 -392.246167) (xy 150.202163 -392.295744)
			(xy 150.217518 -392.348039) (xy 150.225274 -392.401987) (xy 150.22576 -392.429238) (xy 150.22576 -393.292838)
			(xy 150.66264 -393.292838) (xy 150.66264 -392.429238) (xy 150.663126 -392.401987) (xy 150.670882 -392.348039)
			(xy 150.686237 -392.295744) (xy 150.708879 -392.246167) (xy 150.738345 -392.200317) (xy 150.774036 -392.159126)
			(xy 150.815227 -392.123435) (xy 150.861077 -392.093969) (xy 150.910654 -392.071327) (xy 150.962949 -392.055972)
			(xy 151.016897 -392.048216) (xy 151.071399 -392.048216) (xy 151.125347 -392.055972) (xy 151.177642 -392.071327)
			(xy 151.227219 -392.093969) (xy 151.273069 -392.123435) (xy 151.31426 -392.159126) (xy 151.349951 -392.200317)
			(xy 151.379417 -392.246167) (xy 151.402059 -392.295744) (xy 151.417414 -392.348039) (xy 151.42517 -392.401987)
			(xy 151.425656 -392.429238) (xy 151.425656 -393.292838) (xy 151.862536 -393.292838) (xy 151.862536 -392.429238)
			(xy 151.863022 -392.401969) (xy 151.870784 -392.347985) (xy 151.886149 -392.295655) (xy 151.908806 -392.246045)
			(xy 151.938292 -392.200164) (xy 151.974007 -392.158947) (xy 152.015224 -392.123232) (xy 152.061105 -392.093746)
			(xy 152.110715 -392.071089) (xy 152.163045 -392.055724) (xy 152.217029 -392.047962) (xy 152.271567 -392.047962)
			(xy 152.325551 -392.055724) (xy 152.377881 -392.071089) (xy 152.427491 -392.093746) (xy 152.473372 -392.123232)
			(xy 152.514589 -392.158947) (xy 152.550304 -392.200164) (xy 152.57979 -392.246045) (xy 152.602447 -392.295655)
			(xy 152.617812 -392.347985) (xy 152.625574 -392.401969) (xy 152.62606 -392.429238) (xy 152.62606 -393.292838)
			(xy 153.062432 -393.292838) (xy 153.062432 -392.429238) (xy 153.062918 -392.401969) (xy 153.07068 -392.347985)
			(xy 153.086045 -392.295655) (xy 153.108702 -392.246045) (xy 153.138188 -392.200164) (xy 153.173903 -392.158947)
			(xy 153.21512 -392.123232) (xy 153.261001 -392.093746) (xy 153.310611 -392.071089) (xy 153.362941 -392.055724)
			(xy 153.416925 -392.047962) (xy 153.471463 -392.047962) (xy 153.525447 -392.055724) (xy 153.577777 -392.071089)
			(xy 153.627387 -392.093746) (xy 153.673268 -392.123232) (xy 153.714485 -392.158947) (xy 153.7502 -392.200164)
			(xy 153.779686 -392.246045) (xy 153.802343 -392.295655) (xy 153.817708 -392.347985) (xy 153.82547 -392.401969)
			(xy 153.825956 -392.429238) (xy 153.825956 -393.292838) (xy 154.262836 -393.292838) (xy 154.262836 -392.429238)
			(xy 154.263322 -392.401987) (xy 154.271078 -392.348039) (xy 154.286433 -392.295744) (xy 154.309075 -392.246167)
			(xy 154.338541 -392.200317) (xy 154.374232 -392.159126) (xy 154.415423 -392.123435) (xy 154.461273 -392.093969)
			(xy 154.51085 -392.071327) (xy 154.563145 -392.055972) (xy 154.617093 -392.048216) (xy 154.671595 -392.048216)
			(xy 154.725543 -392.055972) (xy 154.777838 -392.071327) (xy 154.827415 -392.093969) (xy 154.873265 -392.123435)
			(xy 154.914456 -392.159126) (xy 154.950147 -392.200317) (xy 154.979613 -392.246167) (xy 155.002255 -392.295744)
			(xy 155.01761 -392.348039) (xy 155.025366 -392.401987) (xy 155.025852 -392.429238) (xy 155.025852 -393.292838)
			(xy 155.462732 -393.292838) (xy 155.462732 -392.429238) (xy 155.463218 -392.401987) (xy 155.470974 -392.348039)
			(xy 155.486329 -392.295744) (xy 155.508971 -392.246167) (xy 155.538437 -392.200317) (xy 155.574128 -392.159126)
			(xy 155.615319 -392.123435) (xy 155.661169 -392.093969) (xy 155.710746 -392.071327) (xy 155.763041 -392.055972)
			(xy 155.816989 -392.048216) (xy 155.871491 -392.048216) (xy 155.925439 -392.055972) (xy 155.977734 -392.071327)
			(xy 156.027311 -392.093969) (xy 156.073161 -392.123435) (xy 156.114352 -392.159126) (xy 156.150043 -392.200317)
			(xy 156.179509 -392.246167) (xy 156.202151 -392.295744) (xy 156.217506 -392.348039) (xy 156.225262 -392.401987)
			(xy 156.225748 -392.429238) (xy 156.225748 -393.292838) (xy 156.662628 -393.292838) (xy 156.662628 -392.429238)
			(xy 156.663114 -392.401969) (xy 156.670876 -392.347985) (xy 156.686241 -392.295655) (xy 156.708898 -392.246045)
			(xy 156.738384 -392.200164) (xy 156.774099 -392.158947) (xy 156.815316 -392.123232) (xy 156.861197 -392.093746)
			(xy 156.910807 -392.071089) (xy 156.963137 -392.055724) (xy 157.017121 -392.047962) (xy 157.071659 -392.047962)
			(xy 157.125643 -392.055724) (xy 157.177973 -392.071089) (xy 157.227583 -392.093746) (xy 157.273464 -392.123232)
			(xy 157.314681 -392.158947) (xy 157.350396 -392.200164) (xy 157.379882 -392.246045) (xy 157.402539 -392.295655)
			(xy 157.417904 -392.347985) (xy 157.425666 -392.401969) (xy 157.426152 -392.429238) (xy 157.426152 -393.292838)
			(xy 157.862524 -393.292838) (xy 157.862524 -392.429238) (xy 157.86301 -392.401969) (xy 157.870772 -392.347985)
			(xy 157.886137 -392.295655) (xy 157.908794 -392.246045) (xy 157.93828 -392.200164) (xy 157.973995 -392.158947)
			(xy 158.015212 -392.123232) (xy 158.061093 -392.093746) (xy 158.110703 -392.071089) (xy 158.163033 -392.055724)
			(xy 158.217017 -392.047962) (xy 158.271555 -392.047962) (xy 158.325539 -392.055724) (xy 158.377869 -392.071089)
			(xy 158.427479 -392.093746) (xy 158.47336 -392.123232) (xy 158.514577 -392.158947) (xy 158.550292 -392.200164)
			(xy 158.579778 -392.246045) (xy 158.602435 -392.295655) (xy 158.6178 -392.347985) (xy 158.625562 -392.401969)
			(xy 158.626048 -392.429238) (xy 158.626048 -393.292838) (xy 159.062928 -393.292838) (xy 159.062928 -392.429238)
			(xy 159.063414 -392.401987) (xy 159.07117 -392.348039) (xy 159.086525 -392.295744) (xy 159.109167 -392.246167)
			(xy 159.138633 -392.200317) (xy 159.174324 -392.159126) (xy 159.215515 -392.123435) (xy 159.261365 -392.093969)
			(xy 159.310942 -392.071327) (xy 159.363237 -392.055972) (xy 159.417185 -392.048216) (xy 159.471687 -392.048216)
			(xy 159.525635 -392.055972) (xy 159.57793 -392.071327) (xy 159.627507 -392.093969) (xy 159.673357 -392.123435)
			(xy 159.714548 -392.159126) (xy 159.750239 -392.200317) (xy 159.779705 -392.246167) (xy 159.802347 -392.295744)
			(xy 159.817702 -392.348039) (xy 159.825458 -392.401987) (xy 159.825944 -392.429238) (xy 159.825944 -393.292838)
			(xy 160.262824 -393.292838) (xy 160.262824 -392.429238) (xy 160.26331 -392.401987) (xy 160.271066 -392.348039)
			(xy 160.286421 -392.295744) (xy 160.309063 -392.246167) (xy 160.338529 -392.200317) (xy 160.37422 -392.159126)
			(xy 160.415411 -392.123435) (xy 160.461261 -392.093969) (xy 160.510838 -392.071327) (xy 160.563133 -392.055972)
			(xy 160.617081 -392.048216) (xy 160.671583 -392.048216) (xy 160.725531 -392.055972) (xy 160.777826 -392.071327)
			(xy 160.827403 -392.093969) (xy 160.873253 -392.123435) (xy 160.914444 -392.159126) (xy 160.950135 -392.200317)
			(xy 160.979601 -392.246167) (xy 161.002243 -392.295744) (xy 161.017598 -392.348039) (xy 161.025354 -392.401987)
			(xy 161.02584 -392.429238) (xy 161.02584 -393.292838) (xy 161.46272 -393.292838) (xy 161.46272 -392.429238)
			(xy 161.463206 -392.401987) (xy 161.470962 -392.348039) (xy 161.486317 -392.295744) (xy 161.508959 -392.246167)
			(xy 161.538425 -392.200317) (xy 161.574116 -392.159126) (xy 161.615307 -392.123435) (xy 161.661157 -392.093969)
			(xy 161.710734 -392.071327) (xy 161.763029 -392.055972) (xy 161.816977 -392.048216) (xy 161.871479 -392.048216)
			(xy 161.925427 -392.055972) (xy 161.977722 -392.071327) (xy 162.027299 -392.093969) (xy 162.073149 -392.123435)
			(xy 162.11434 -392.159126) (xy 162.150031 -392.200317) (xy 162.179497 -392.246167) (xy 162.202139 -392.295744)
			(xy 162.217494 -392.348039) (xy 162.22525 -392.401987) (xy 162.225736 -392.429238) (xy 162.225736 -393.292838)
			(xy 162.662616 -393.292838) (xy 162.662616 -392.429238) (xy 162.663102 -392.401987) (xy 162.670858 -392.348039)
			(xy 162.686213 -392.295744) (xy 162.708855 -392.246167) (xy 162.738321 -392.200317) (xy 162.774012 -392.159126)
			(xy 162.815203 -392.123435) (xy 162.861053 -392.093969) (xy 162.91063 -392.071327) (xy 162.962925 -392.055972)
			(xy 163.016873 -392.048216) (xy 163.071375 -392.048216) (xy 163.125323 -392.055972) (xy 163.177618 -392.071327)
			(xy 163.227195 -392.093969) (xy 163.273045 -392.123435) (xy 163.314236 -392.159126) (xy 163.349927 -392.200317)
			(xy 163.379393 -392.246167) (xy 163.402035 -392.295744) (xy 163.41739 -392.348039) (xy 163.425146 -392.401987)
			(xy 163.425632 -392.429238) (xy 163.425632 -393.292838) (xy 163.862512 -393.292838) (xy 163.862512 -392.429238)
			(xy 163.862998 -392.401969) (xy 163.87076 -392.347985) (xy 163.886125 -392.295655) (xy 163.908782 -392.246045)
			(xy 163.938268 -392.200164) (xy 163.973983 -392.158947) (xy 164.0152 -392.123232) (xy 164.061081 -392.093746)
			(xy 164.110691 -392.071089) (xy 164.163021 -392.055724) (xy 164.217005 -392.047962) (xy 164.271543 -392.047962)
			(xy 164.325527 -392.055724) (xy 164.377857 -392.071089) (xy 164.427467 -392.093746) (xy 164.473348 -392.123232)
			(xy 164.514565 -392.158947) (xy 164.55028 -392.200164) (xy 164.579766 -392.246045) (xy 164.602423 -392.295655)
			(xy 164.617788 -392.347985) (xy 164.62555 -392.401969) (xy 164.626036 -392.429238) (xy 164.626036 -393.292838)
			(xy 165.062408 -393.292838) (xy 165.062408 -392.429238) (xy 165.062894 -392.401969) (xy 165.070656 -392.347985)
			(xy 165.086021 -392.295655) (xy 165.108678 -392.246045) (xy 165.138164 -392.200164) (xy 165.173879 -392.158947)
			(xy 165.215096 -392.123232) (xy 165.260977 -392.093746) (xy 165.310587 -392.071089) (xy 165.362917 -392.055724)
			(xy 165.416901 -392.047962) (xy 165.471439 -392.047962) (xy 165.525423 -392.055724) (xy 165.577753 -392.071089)
			(xy 165.627363 -392.093746) (xy 165.673244 -392.123232) (xy 165.714461 -392.158947) (xy 165.750176 -392.200164)
			(xy 165.779662 -392.246045) (xy 165.802319 -392.295655) (xy 165.817684 -392.347985) (xy 165.825446 -392.401969)
			(xy 165.825932 -392.429238) (xy 165.825932 -393.292838) (xy 165.825446 -393.320107) (xy 165.817684 -393.374091)
			(xy 165.802319 -393.426421) (xy 165.779662 -393.476031) (xy 165.750176 -393.521912) (xy 165.714461 -393.563129)
			(xy 165.673244 -393.598844) (xy 165.627363 -393.62833) (xy 165.577753 -393.650987) (xy 165.525423 -393.666352)
			(xy 165.471439 -393.674114) (xy 165.416901 -393.674114) (xy 165.362917 -393.666352) (xy 165.310587 -393.650987)
			(xy 165.260977 -393.62833) (xy 165.215096 -393.598844) (xy 165.173879 -393.563129) (xy 165.138164 -393.521912)
			(xy 165.108678 -393.476031) (xy 165.086021 -393.426421) (xy 165.070656 -393.374091) (xy 165.062894 -393.320107)
			(xy 165.062408 -393.292838) (xy 164.626036 -393.292838) (xy 164.62555 -393.320107) (xy 164.617788 -393.374091)
			(xy 164.602423 -393.426421) (xy 164.579766 -393.476031) (xy 164.55028 -393.521912) (xy 164.514565 -393.563129)
			(xy 164.473348 -393.598844) (xy 164.427467 -393.62833) (xy 164.377857 -393.650987) (xy 164.325527 -393.666352)
			(xy 164.271543 -393.674114) (xy 164.217005 -393.674114) (xy 164.163021 -393.666352) (xy 164.110691 -393.650987)
			(xy 164.061081 -393.62833) (xy 164.0152 -393.598844) (xy 163.973983 -393.563129) (xy 163.938268 -393.521912)
			(xy 163.908782 -393.476031) (xy 163.886125 -393.426421) (xy 163.87076 -393.374091) (xy 163.862998 -393.320107)
			(xy 163.862512 -393.292838) (xy 163.425632 -393.292838) (xy 163.425146 -393.320089) (xy 163.41739 -393.374037)
			(xy 163.402035 -393.426332) (xy 163.379393 -393.475909) (xy 163.349927 -393.521759) (xy 163.314236 -393.56295)
			(xy 163.273045 -393.598641) (xy 163.227195 -393.628107) (xy 163.177618 -393.650749) (xy 163.125323 -393.666104)
			(xy 163.071375 -393.67386) (xy 163.016873 -393.67386) (xy 162.962925 -393.666104) (xy 162.91063 -393.650749)
			(xy 162.861053 -393.628107) (xy 162.815203 -393.598641) (xy 162.774012 -393.56295) (xy 162.738321 -393.521759)
			(xy 162.708855 -393.475909) (xy 162.686213 -393.426332) (xy 162.670858 -393.374037) (xy 162.663102 -393.320089)
			(xy 162.662616 -393.292838) (xy 162.225736 -393.292838) (xy 162.22525 -393.320089) (xy 162.217494 -393.374037)
			(xy 162.202139 -393.426332) (xy 162.179497 -393.475909) (xy 162.150031 -393.521759) (xy 162.11434 -393.56295)
			(xy 162.073149 -393.598641) (xy 162.027299 -393.628107) (xy 161.977722 -393.650749) (xy 161.925427 -393.666104)
			(xy 161.871479 -393.67386) (xy 161.816977 -393.67386) (xy 161.763029 -393.666104) (xy 161.710734 -393.650749)
			(xy 161.661157 -393.628107) (xy 161.615307 -393.598641) (xy 161.574116 -393.56295) (xy 161.538425 -393.521759)
			(xy 161.508959 -393.475909) (xy 161.486317 -393.426332) (xy 161.470962 -393.374037) (xy 161.463206 -393.320089)
			(xy 161.46272 -393.292838) (xy 161.02584 -393.292838) (xy 161.025354 -393.320089) (xy 161.017598 -393.374037)
			(xy 161.002243 -393.426332) (xy 160.979601 -393.475909) (xy 160.950135 -393.521759) (xy 160.914444 -393.56295)
			(xy 160.873253 -393.598641) (xy 160.827403 -393.628107) (xy 160.777826 -393.650749) (xy 160.725531 -393.666104)
			(xy 160.671583 -393.67386) (xy 160.617081 -393.67386) (xy 160.563133 -393.666104) (xy 160.510838 -393.650749)
			(xy 160.461261 -393.628107) (xy 160.415411 -393.598641) (xy 160.37422 -393.56295) (xy 160.338529 -393.521759)
			(xy 160.309063 -393.475909) (xy 160.286421 -393.426332) (xy 160.271066 -393.374037) (xy 160.26331 -393.320089)
			(xy 160.262824 -393.292838) (xy 159.825944 -393.292838) (xy 159.825458 -393.320089) (xy 159.817702 -393.374037)
			(xy 159.802347 -393.426332) (xy 159.779705 -393.475909) (xy 159.750239 -393.521759) (xy 159.714548 -393.56295)
			(xy 159.673357 -393.598641) (xy 159.627507 -393.628107) (xy 159.57793 -393.650749) (xy 159.525635 -393.666104)
			(xy 159.471687 -393.67386) (xy 159.417185 -393.67386) (xy 159.363237 -393.666104) (xy 159.310942 -393.650749)
			(xy 159.261365 -393.628107) (xy 159.215515 -393.598641) (xy 159.174324 -393.56295) (xy 159.138633 -393.521759)
			(xy 159.109167 -393.475909) (xy 159.086525 -393.426332) (xy 159.07117 -393.374037) (xy 159.063414 -393.320089)
			(xy 159.062928 -393.292838) (xy 158.626048 -393.292838) (xy 158.625562 -393.320107) (xy 158.6178 -393.374091)
			(xy 158.602435 -393.426421) (xy 158.579778 -393.476031) (xy 158.550292 -393.521912) (xy 158.514577 -393.563129)
			(xy 158.47336 -393.598844) (xy 158.427479 -393.62833) (xy 158.377869 -393.650987) (xy 158.325539 -393.666352)
			(xy 158.271555 -393.674114) (xy 158.217017 -393.674114) (xy 158.163033 -393.666352) (xy 158.110703 -393.650987)
			(xy 158.061093 -393.62833) (xy 158.015212 -393.598844) (xy 157.973995 -393.563129) (xy 157.93828 -393.521912)
			(xy 157.908794 -393.476031) (xy 157.886137 -393.426421) (xy 157.870772 -393.374091) (xy 157.86301 -393.320107)
			(xy 157.862524 -393.292838) (xy 157.426152 -393.292838) (xy 157.425666 -393.320107) (xy 157.417904 -393.374091)
			(xy 157.402539 -393.426421) (xy 157.379882 -393.476031) (xy 157.350396 -393.521912) (xy 157.314681 -393.563129)
			(xy 157.273464 -393.598844) (xy 157.227583 -393.62833) (xy 157.177973 -393.650987) (xy 157.125643 -393.666352)
			(xy 157.071659 -393.674114) (xy 157.017121 -393.674114) (xy 156.963137 -393.666352) (xy 156.910807 -393.650987)
			(xy 156.861197 -393.62833) (xy 156.815316 -393.598844) (xy 156.774099 -393.563129) (xy 156.738384 -393.521912)
			(xy 156.708898 -393.476031) (xy 156.686241 -393.426421) (xy 156.670876 -393.374091) (xy 156.663114 -393.320107)
			(xy 156.662628 -393.292838) (xy 156.225748 -393.292838) (xy 156.225262 -393.320089) (xy 156.217506 -393.374037)
			(xy 156.202151 -393.426332) (xy 156.179509 -393.475909) (xy 156.150043 -393.521759) (xy 156.114352 -393.56295)
			(xy 156.073161 -393.598641) (xy 156.027311 -393.628107) (xy 155.977734 -393.650749) (xy 155.925439 -393.666104)
			(xy 155.871491 -393.67386) (xy 155.816989 -393.67386) (xy 155.763041 -393.666104) (xy 155.710746 -393.650749)
			(xy 155.661169 -393.628107) (xy 155.615319 -393.598641) (xy 155.574128 -393.56295) (xy 155.538437 -393.521759)
			(xy 155.508971 -393.475909) (xy 155.486329 -393.426332) (xy 155.470974 -393.374037) (xy 155.463218 -393.320089)
			(xy 155.462732 -393.292838) (xy 155.025852 -393.292838) (xy 155.025366 -393.320089) (xy 155.01761 -393.374037)
			(xy 155.002255 -393.426332) (xy 154.979613 -393.475909) (xy 154.950147 -393.521759) (xy 154.914456 -393.56295)
			(xy 154.873265 -393.598641) (xy 154.827415 -393.628107) (xy 154.777838 -393.650749) (xy 154.725543 -393.666104)
			(xy 154.671595 -393.67386) (xy 154.617093 -393.67386) (xy 154.563145 -393.666104) (xy 154.51085 -393.650749)
			(xy 154.461273 -393.628107) (xy 154.415423 -393.598641) (xy 154.374232 -393.56295) (xy 154.338541 -393.521759)
			(xy 154.309075 -393.475909) (xy 154.286433 -393.426332) (xy 154.271078 -393.374037) (xy 154.263322 -393.320089)
			(xy 154.262836 -393.292838) (xy 153.825956 -393.292838) (xy 153.82547 -393.320107) (xy 153.817708 -393.374091)
			(xy 153.802343 -393.426421) (xy 153.779686 -393.476031) (xy 153.7502 -393.521912) (xy 153.714485 -393.563129)
			(xy 153.673268 -393.598844) (xy 153.627387 -393.62833) (xy 153.577777 -393.650987) (xy 153.525447 -393.666352)
			(xy 153.471463 -393.674114) (xy 153.416925 -393.674114) (xy 153.362941 -393.666352) (xy 153.310611 -393.650987)
			(xy 153.261001 -393.62833) (xy 153.21512 -393.598844) (xy 153.173903 -393.563129) (xy 153.138188 -393.521912)
			(xy 153.108702 -393.476031) (xy 153.086045 -393.426421) (xy 153.07068 -393.374091) (xy 153.062918 -393.320107)
			(xy 153.062432 -393.292838) (xy 152.62606 -393.292838) (xy 152.625574 -393.320107) (xy 152.617812 -393.374091)
			(xy 152.602447 -393.426421) (xy 152.57979 -393.476031) (xy 152.550304 -393.521912) (xy 152.514589 -393.563129)
			(xy 152.473372 -393.598844) (xy 152.427491 -393.62833) (xy 152.377881 -393.650987) (xy 152.325551 -393.666352)
			(xy 152.271567 -393.674114) (xy 152.217029 -393.674114) (xy 152.163045 -393.666352) (xy 152.110715 -393.650987)
			(xy 152.061105 -393.62833) (xy 152.015224 -393.598844) (xy 151.974007 -393.563129) (xy 151.938292 -393.521912)
			(xy 151.908806 -393.476031) (xy 151.886149 -393.426421) (xy 151.870784 -393.374091) (xy 151.863022 -393.320107)
			(xy 151.862536 -393.292838) (xy 151.425656 -393.292838) (xy 151.42517 -393.320089) (xy 151.417414 -393.374037)
			(xy 151.402059 -393.426332) (xy 151.379417 -393.475909) (xy 151.349951 -393.521759) (xy 151.31426 -393.56295)
			(xy 151.273069 -393.598641) (xy 151.227219 -393.628107) (xy 151.177642 -393.650749) (xy 151.125347 -393.666104)
			(xy 151.071399 -393.67386) (xy 151.016897 -393.67386) (xy 150.962949 -393.666104) (xy 150.910654 -393.650749)
			(xy 150.861077 -393.628107) (xy 150.815227 -393.598641) (xy 150.774036 -393.56295) (xy 150.738345 -393.521759)
			(xy 150.708879 -393.475909) (xy 150.686237 -393.426332) (xy 150.670882 -393.374037) (xy 150.663126 -393.320089)
			(xy 150.66264 -393.292838) (xy 150.22576 -393.292838) (xy 150.225274 -393.320089) (xy 150.217518 -393.374037)
			(xy 150.202163 -393.426332) (xy 150.179521 -393.475909) (xy 150.150055 -393.521759) (xy 150.114364 -393.56295)
			(xy 150.073173 -393.598641) (xy 150.027323 -393.628107) (xy 149.977746 -393.650749) (xy 149.925451 -393.666104)
			(xy 149.871503 -393.67386) (xy 149.817001 -393.67386) (xy 149.763053 -393.666104) (xy 149.710758 -393.650749)
			(xy 149.661181 -393.628107) (xy 149.615331 -393.598641) (xy 149.57414 -393.56295) (xy 149.538449 -393.521759)
			(xy 149.508983 -393.475909) (xy 149.486341 -393.426332) (xy 149.470986 -393.374037) (xy 149.46323 -393.320089)
			(xy 149.462744 -393.292838) (xy 149.025864 -393.292838) (xy 149.025378 -393.320107) (xy 149.017616 -393.374091)
			(xy 149.002251 -393.426421) (xy 148.979594 -393.476031) (xy 148.950108 -393.521912) (xy 148.914393 -393.563129)
			(xy 148.873176 -393.598844) (xy 148.827295 -393.62833) (xy 148.777685 -393.650987) (xy 148.725355 -393.666352)
			(xy 148.671371 -393.674114) (xy 148.616833 -393.674114) (xy 148.562849 -393.666352) (xy 148.510519 -393.650987)
			(xy 148.460909 -393.62833) (xy 148.415028 -393.598844) (xy 148.373811 -393.563129) (xy 148.338096 -393.521912)
			(xy 148.30861 -393.476031) (xy 148.285953 -393.426421) (xy 148.270588 -393.374091) (xy 148.262826 -393.320107)
			(xy 148.26234 -393.292838) (xy 147.825968 -393.292838) (xy 147.825482 -393.320107) (xy 147.81772 -393.374091)
			(xy 147.802355 -393.426421) (xy 147.779698 -393.476031) (xy 147.750212 -393.521912) (xy 147.714497 -393.563129)
			(xy 147.67328 -393.598844) (xy 147.627399 -393.62833) (xy 147.577789 -393.650987) (xy 147.525459 -393.666352)
			(xy 147.471475 -393.674114) (xy 147.416937 -393.674114) (xy 147.362953 -393.666352) (xy 147.310623 -393.650987)
			(xy 147.261013 -393.62833) (xy 147.215132 -393.598844) (xy 147.173915 -393.563129) (xy 147.1382 -393.521912)
			(xy 147.108714 -393.476031) (xy 147.086057 -393.426421) (xy 147.070692 -393.374091) (xy 147.06293 -393.320107)
			(xy 147.062444 -393.292838) (xy 133.298184 -393.292838) (xy 133.297698 -393.320107) (xy 133.289936 -393.374091)
			(xy 133.274571 -393.426421) (xy 133.251914 -393.476031) (xy 133.222428 -393.521912) (xy 133.186713 -393.563129)
			(xy 133.145496 -393.598844) (xy 133.099615 -393.62833) (xy 133.050005 -393.650987) (xy 132.997675 -393.666352)
			(xy 132.943691 -393.674114) (xy 132.889153 -393.674114) (xy 132.835169 -393.666352) (xy 132.782839 -393.650987)
			(xy 132.733229 -393.62833) (xy 132.687348 -393.598844) (xy 132.646131 -393.563129) (xy 132.610416 -393.521912)
			(xy 132.58093 -393.476031) (xy 132.558273 -393.426421) (xy 132.542908 -393.374091) (xy 132.535146 -393.320107)
			(xy 132.53466 -393.292838) (xy 132.098288 -393.292838) (xy 132.097802 -393.320107) (xy 132.09004 -393.374091)
			(xy 132.074675 -393.426421) (xy 132.052018 -393.476031) (xy 132.022532 -393.521912) (xy 131.986817 -393.563129)
			(xy 131.9456 -393.598844) (xy 131.899719 -393.62833) (xy 131.850109 -393.650987) (xy 131.797779 -393.666352)
			(xy 131.743795 -393.674114) (xy 131.689257 -393.674114) (xy 131.635273 -393.666352) (xy 131.582943 -393.650987)
			(xy 131.533333 -393.62833) (xy 131.487452 -393.598844) (xy 131.446235 -393.563129) (xy 131.41052 -393.521912)
			(xy 131.381034 -393.476031) (xy 131.358377 -393.426421) (xy 131.343012 -393.374091) (xy 131.33525 -393.320107)
			(xy 131.334764 -393.292838) (xy 130.897884 -393.292838) (xy 130.897398 -393.320089) (xy 130.889642 -393.374037)
			(xy 130.874287 -393.426332) (xy 130.851645 -393.475909) (xy 130.822179 -393.521759) (xy 130.786488 -393.56295)
			(xy 130.745297 -393.598641) (xy 130.699447 -393.628107) (xy 130.64987 -393.650749) (xy 130.597575 -393.666104)
			(xy 130.543627 -393.67386) (xy 130.489125 -393.67386) (xy 130.435177 -393.666104) (xy 130.382882 -393.650749)
			(xy 130.333305 -393.628107) (xy 130.287455 -393.598641) (xy 130.246264 -393.56295) (xy 130.210573 -393.521759)
			(xy 130.181107 -393.475909) (xy 130.158465 -393.426332) (xy 130.14311 -393.374037) (xy 130.135354 -393.320089)
			(xy 130.134868 -393.292838) (xy 129.697988 -393.292838) (xy 129.697502 -393.320089) (xy 129.689746 -393.374037)
			(xy 129.674391 -393.426332) (xy 129.651749 -393.475909) (xy 129.622283 -393.521759) (xy 129.586592 -393.56295)
			(xy 129.545401 -393.598641) (xy 129.499551 -393.628107) (xy 129.449974 -393.650749) (xy 129.397679 -393.666104)
			(xy 129.343731 -393.67386) (xy 129.289229 -393.67386) (xy 129.235281 -393.666104) (xy 129.182986 -393.650749)
			(xy 129.133409 -393.628107) (xy 129.087559 -393.598641) (xy 129.046368 -393.56295) (xy 129.010677 -393.521759)
			(xy 128.981211 -393.475909) (xy 128.958569 -393.426332) (xy 128.943214 -393.374037) (xy 128.935458 -393.320089)
			(xy 128.934972 -393.292838) (xy 128.498092 -393.292838) (xy 128.497606 -393.320089) (xy 128.48985 -393.374037)
			(xy 128.474495 -393.426332) (xy 128.451853 -393.475909) (xy 128.422387 -393.521759) (xy 128.386696 -393.56295)
			(xy 128.345505 -393.598641) (xy 128.299655 -393.628107) (xy 128.250078 -393.650749) (xy 128.197783 -393.666104)
			(xy 128.143835 -393.67386) (xy 128.089333 -393.67386) (xy 128.035385 -393.666104) (xy 127.98309 -393.650749)
			(xy 127.933513 -393.628107) (xy 127.887663 -393.598641) (xy 127.846472 -393.56295) (xy 127.810781 -393.521759)
			(xy 127.781315 -393.475909) (xy 127.758673 -393.426332) (xy 127.743318 -393.374037) (xy 127.735562 -393.320089)
			(xy 127.735076 -393.292838) (xy 127.298196 -393.292838) (xy 127.29771 -393.320089) (xy 127.289954 -393.374037)
			(xy 127.274599 -393.426332) (xy 127.251957 -393.475909) (xy 127.222491 -393.521759) (xy 127.1868 -393.56295)
			(xy 127.145609 -393.598641) (xy 127.099759 -393.628107) (xy 127.050182 -393.650749) (xy 126.997887 -393.666104)
			(xy 126.943939 -393.67386) (xy 126.889437 -393.67386) (xy 126.835489 -393.666104) (xy 126.783194 -393.650749)
			(xy 126.733617 -393.628107) (xy 126.687767 -393.598641) (xy 126.646576 -393.56295) (xy 126.610885 -393.521759)
			(xy 126.581419 -393.475909) (xy 126.558777 -393.426332) (xy 126.543422 -393.374037) (xy 126.535666 -393.320089)
			(xy 126.53518 -393.292838) (xy 126.0983 -393.292838) (xy 126.097814 -393.320107) (xy 126.090052 -393.374091)
			(xy 126.074687 -393.426421) (xy 126.05203 -393.476031) (xy 126.022544 -393.521912) (xy 125.986829 -393.563129)
			(xy 125.945612 -393.598844) (xy 125.899731 -393.62833) (xy 125.850121 -393.650987) (xy 125.797791 -393.666352)
			(xy 125.743807 -393.674114) (xy 125.689269 -393.674114) (xy 125.635285 -393.666352) (xy 125.582955 -393.650987)
			(xy 125.533345 -393.62833) (xy 125.487464 -393.598844) (xy 125.446247 -393.563129) (xy 125.410532 -393.521912)
			(xy 125.381046 -393.476031) (xy 125.358389 -393.426421) (xy 125.343024 -393.374091) (xy 125.335262 -393.320107)
			(xy 125.334776 -393.292838) (xy 124.898404 -393.292838) (xy 124.897918 -393.320107) (xy 124.890156 -393.374091)
			(xy 124.874791 -393.426421) (xy 124.852134 -393.476031) (xy 124.822648 -393.521912) (xy 124.786933 -393.563129)
			(xy 124.745716 -393.598844) (xy 124.699835 -393.62833) (xy 124.650225 -393.650987) (xy 124.597895 -393.666352)
			(xy 124.543911 -393.674114) (xy 124.489373 -393.674114) (xy 124.435389 -393.666352) (xy 124.383059 -393.650987)
			(xy 124.333449 -393.62833) (xy 124.287568 -393.598844) (xy 124.246351 -393.563129) (xy 124.210636 -393.521912)
			(xy 124.18115 -393.476031) (xy 124.158493 -393.426421) (xy 124.143128 -393.374091) (xy 124.135366 -393.320107)
			(xy 124.13488 -393.292838) (xy 123.698 -393.292838) (xy 123.697514 -393.320089) (xy 123.689758 -393.374037)
			(xy 123.674403 -393.426332) (xy 123.651761 -393.475909) (xy 123.622295 -393.521759) (xy 123.586604 -393.56295)
			(xy 123.545413 -393.598641) (xy 123.499563 -393.628107) (xy 123.449986 -393.650749) (xy 123.397691 -393.666104)
			(xy 123.343743 -393.67386) (xy 123.289241 -393.67386) (xy 123.235293 -393.666104) (xy 123.182998 -393.650749)
			(xy 123.133421 -393.628107) (xy 123.087571 -393.598641) (xy 123.04638 -393.56295) (xy 123.010689 -393.521759)
			(xy 122.981223 -393.475909) (xy 122.958581 -393.426332) (xy 122.943226 -393.374037) (xy 122.93547 -393.320089)
			(xy 122.934984 -393.292838) (xy 122.498104 -393.292838) (xy 122.497618 -393.320089) (xy 122.489862 -393.374037)
			(xy 122.474507 -393.426332) (xy 122.451865 -393.475909) (xy 122.422399 -393.521759) (xy 122.386708 -393.56295)
			(xy 122.345517 -393.598641) (xy 122.299667 -393.628107) (xy 122.25009 -393.650749) (xy 122.197795 -393.666104)
			(xy 122.143847 -393.67386) (xy 122.089345 -393.67386) (xy 122.035397 -393.666104) (xy 121.983102 -393.650749)
			(xy 121.933525 -393.628107) (xy 121.887675 -393.598641) (xy 121.846484 -393.56295) (xy 121.810793 -393.521759)
			(xy 121.781327 -393.475909) (xy 121.758685 -393.426332) (xy 121.74333 -393.374037) (xy 121.735574 -393.320089)
			(xy 121.735088 -393.292838) (xy 121.298208 -393.292838) (xy 121.297722 -393.320107) (xy 121.28996 -393.374091)
			(xy 121.274595 -393.426421) (xy 121.251938 -393.476031) (xy 121.222452 -393.521912) (xy 121.186737 -393.563129)
			(xy 121.14552 -393.598844) (xy 121.099639 -393.62833) (xy 121.050029 -393.650987) (xy 120.997699 -393.666352)
			(xy 120.943715 -393.674114) (xy 120.889177 -393.674114) (xy 120.835193 -393.666352) (xy 120.782863 -393.650987)
			(xy 120.733253 -393.62833) (xy 120.687372 -393.598844) (xy 120.646155 -393.563129) (xy 120.61044 -393.521912)
			(xy 120.580954 -393.476031) (xy 120.558297 -393.426421) (xy 120.542932 -393.374091) (xy 120.53517 -393.320107)
			(xy 120.534684 -393.292838) (xy 120.098312 -393.292838) (xy 120.097826 -393.320107) (xy 120.090064 -393.374091)
			(xy 120.074699 -393.426421) (xy 120.052042 -393.476031) (xy 120.022556 -393.521912) (xy 119.986841 -393.563129)
			(xy 119.945624 -393.598844) (xy 119.899743 -393.62833) (xy 119.850133 -393.650987) (xy 119.797803 -393.666352)
			(xy 119.743819 -393.674114) (xy 119.689281 -393.674114) (xy 119.635297 -393.666352) (xy 119.582967 -393.650987)
			(xy 119.533357 -393.62833) (xy 119.487476 -393.598844) (xy 119.446259 -393.563129) (xy 119.410544 -393.521912)
			(xy 119.381058 -393.476031) (xy 119.358401 -393.426421) (xy 119.343036 -393.374091) (xy 119.335274 -393.320107)
			(xy 119.334788 -393.292838) (xy 118.897908 -393.292838) (xy 118.897422 -393.320089) (xy 118.889666 -393.374037)
			(xy 118.874311 -393.426332) (xy 118.851669 -393.475909) (xy 118.822203 -393.521759) (xy 118.786512 -393.56295)
			(xy 118.745321 -393.598641) (xy 118.699471 -393.628107) (xy 118.649894 -393.650749) (xy 118.597599 -393.666104)
			(xy 118.543651 -393.67386) (xy 118.489149 -393.67386) (xy 118.435201 -393.666104) (xy 118.382906 -393.650749)
			(xy 118.333329 -393.628107) (xy 118.287479 -393.598641) (xy 118.246288 -393.56295) (xy 118.210597 -393.521759)
			(xy 118.181131 -393.475909) (xy 118.158489 -393.426332) (xy 118.143134 -393.374037) (xy 118.135378 -393.320089)
			(xy 118.134892 -393.292838) (xy 117.698012 -393.292838) (xy 117.697526 -393.320089) (xy 117.68977 -393.374037)
			(xy 117.674415 -393.426332) (xy 117.651773 -393.475909) (xy 117.622307 -393.521759) (xy 117.586616 -393.56295)
			(xy 117.545425 -393.598641) (xy 117.499575 -393.628107) (xy 117.449998 -393.650749) (xy 117.397703 -393.666104)
			(xy 117.343755 -393.67386) (xy 117.289253 -393.67386) (xy 117.235305 -393.666104) (xy 117.18301 -393.650749)
			(xy 117.133433 -393.628107) (xy 117.087583 -393.598641) (xy 117.046392 -393.56295) (xy 117.010701 -393.521759)
			(xy 116.981235 -393.475909) (xy 116.958593 -393.426332) (xy 116.943238 -393.374037) (xy 116.935482 -393.320089)
			(xy 116.934996 -393.292838) (xy 116.498116 -393.292838) (xy 116.49763 -393.320107) (xy 116.489868 -393.374091)
			(xy 116.474503 -393.426421) (xy 116.451846 -393.476031) (xy 116.42236 -393.521912) (xy 116.386645 -393.563129)
			(xy 116.345428 -393.598844) (xy 116.299547 -393.62833) (xy 116.249937 -393.650987) (xy 116.197607 -393.666352)
			(xy 116.143623 -393.674114) (xy 116.089085 -393.674114) (xy 116.035101 -393.666352) (xy 115.982771 -393.650987)
			(xy 115.933161 -393.62833) (xy 115.88728 -393.598844) (xy 115.846063 -393.563129) (xy 115.810348 -393.521912)
			(xy 115.780862 -393.476031) (xy 115.758205 -393.426421) (xy 115.74284 -393.374091) (xy 115.735078 -393.320107)
			(xy 115.734592 -393.292838) (xy 115.29822 -393.292838) (xy 115.297734 -393.320107) (xy 115.289972 -393.374091)
			(xy 115.274607 -393.426421) (xy 115.25195 -393.476031) (xy 115.222464 -393.521912) (xy 115.186749 -393.563129)
			(xy 115.145532 -393.598844) (xy 115.099651 -393.62833) (xy 115.050041 -393.650987) (xy 114.997711 -393.666352)
			(xy 114.943727 -393.674114) (xy 114.889189 -393.674114) (xy 114.835205 -393.666352) (xy 114.782875 -393.650987)
			(xy 114.733265 -393.62833) (xy 114.687384 -393.598844) (xy 114.646167 -393.563129) (xy 114.610452 -393.521912)
			(xy 114.580966 -393.476031) (xy 114.558309 -393.426421) (xy 114.542944 -393.374091) (xy 114.535182 -393.320107)
			(xy 114.534696 -393.292838) (xy 98.725736 -393.292838) (xy 98.72525 -393.320089) (xy 98.717494 -393.374037)
			(xy 98.702139 -393.426332) (xy 98.679497 -393.475909) (xy 98.650031 -393.521759) (xy 98.61434 -393.56295)
			(xy 98.573149 -393.598641) (xy 98.527299 -393.628107) (xy 98.477722 -393.650749) (xy 98.425427 -393.666104)
			(xy 98.371479 -393.67386) (xy 98.316977 -393.67386) (xy 98.263029 -393.666104) (xy 98.210734 -393.650749)
			(xy 98.161157 -393.628107) (xy 98.115307 -393.598641) (xy 98.074116 -393.56295) (xy 98.038425 -393.521759)
			(xy 98.008959 -393.475909) (xy 97.986317 -393.426332) (xy 97.970962 -393.374037) (xy 97.963206 -393.320089)
			(xy 97.96272 -393.292838) (xy 97.52584 -393.292838) (xy 97.525354 -393.320089) (xy 97.517598 -393.374037)
			(xy 97.502243 -393.426332) (xy 97.479601 -393.475909) (xy 97.450135 -393.521759) (xy 97.414444 -393.56295)
			(xy 97.373253 -393.598641) (xy 97.327403 -393.628107) (xy 97.277826 -393.650749) (xy 97.225531 -393.666104)
			(xy 97.171583 -393.67386) (xy 97.117081 -393.67386) (xy 97.063133 -393.666104) (xy 97.010838 -393.650749)
			(xy 96.961261 -393.628107) (xy 96.915411 -393.598641) (xy 96.87422 -393.56295) (xy 96.838529 -393.521759)
			(xy 96.809063 -393.475909) (xy 96.786421 -393.426332) (xy 96.771066 -393.374037) (xy 96.76331 -393.320089)
			(xy 96.762824 -393.292838) (xy 96.325944 -393.292838) (xy 96.325458 -393.320107) (xy 96.317696 -393.374091)
			(xy 96.302331 -393.426421) (xy 96.279674 -393.476031) (xy 96.250188 -393.521912) (xy 96.214473 -393.563129)
			(xy 96.173256 -393.598844) (xy 96.127375 -393.62833) (xy 96.077765 -393.650987) (xy 96.025435 -393.666352)
			(xy 95.971451 -393.674114) (xy 95.916913 -393.674114) (xy 95.862929 -393.666352) (xy 95.810599 -393.650987)
			(xy 95.760989 -393.62833) (xy 95.715108 -393.598844) (xy 95.673891 -393.563129) (xy 95.638176 -393.521912)
			(xy 95.60869 -393.476031) (xy 95.586033 -393.426421) (xy 95.570668 -393.374091) (xy 95.562906 -393.320107)
			(xy 95.56242 -393.292838) (xy 95.126048 -393.292838) (xy 95.125562 -393.320107) (xy 95.1178 -393.374091)
			(xy 95.102435 -393.426421) (xy 95.079778 -393.476031) (xy 95.050292 -393.521912) (xy 95.014577 -393.563129)
			(xy 94.97336 -393.598844) (xy 94.927479 -393.62833) (xy 94.877869 -393.650987) (xy 94.825539 -393.666352)
			(xy 94.771555 -393.674114) (xy 94.717017 -393.674114) (xy 94.663033 -393.666352) (xy 94.610703 -393.650987)
			(xy 94.561093 -393.62833) (xy 94.515212 -393.598844) (xy 94.473995 -393.563129) (xy 94.43828 -393.521912)
			(xy 94.408794 -393.476031) (xy 94.386137 -393.426421) (xy 94.370772 -393.374091) (xy 94.36301 -393.320107)
			(xy 94.362524 -393.292838) (xy 93.926152 -393.292838) (xy 93.925666 -393.320107) (xy 93.917904 -393.374091)
			(xy 93.902539 -393.426421) (xy 93.879882 -393.476031) (xy 93.850396 -393.521912) (xy 93.814681 -393.563129)
			(xy 93.773464 -393.598844) (xy 93.727583 -393.62833) (xy 93.677973 -393.650987) (xy 93.625643 -393.666352)
			(xy 93.571659 -393.674114) (xy 93.517121 -393.674114) (xy 93.463137 -393.666352) (xy 93.410807 -393.650987)
			(xy 93.361197 -393.62833) (xy 93.315316 -393.598844) (xy 93.274099 -393.563129) (xy 93.238384 -393.521912)
			(xy 93.208898 -393.476031) (xy 93.186241 -393.426421) (xy 93.170876 -393.374091) (xy 93.163114 -393.320107)
			(xy 93.162628 -393.292838) (xy 92.726256 -393.292838) (xy 92.72577 -393.320107) (xy 92.718008 -393.374091)
			(xy 92.702643 -393.426421) (xy 92.679986 -393.476031) (xy 92.6505 -393.521912) (xy 92.614785 -393.563129)
			(xy 92.573568 -393.598844) (xy 92.527687 -393.62833) (xy 92.478077 -393.650987) (xy 92.425747 -393.666352)
			(xy 92.371763 -393.674114) (xy 92.317225 -393.674114) (xy 92.263241 -393.666352) (xy 92.210911 -393.650987)
			(xy 92.161301 -393.62833) (xy 92.11542 -393.598844) (xy 92.074203 -393.563129) (xy 92.038488 -393.521912)
			(xy 92.009002 -393.476031) (xy 91.986345 -393.426421) (xy 91.97098 -393.374091) (xy 91.963218 -393.320107)
			(xy 91.962732 -393.292838) (xy 91.525852 -393.292838) (xy 91.525366 -393.320089) (xy 91.51761 -393.374037)
			(xy 91.502255 -393.426332) (xy 91.479613 -393.475909) (xy 91.450147 -393.521759) (xy 91.414456 -393.56295)
			(xy 91.373265 -393.598641) (xy 91.327415 -393.628107) (xy 91.277838 -393.650749) (xy 91.225543 -393.666104)
			(xy 91.171595 -393.67386) (xy 91.117093 -393.67386) (xy 91.063145 -393.666104) (xy 91.01085 -393.650749)
			(xy 90.961273 -393.628107) (xy 90.915423 -393.598641) (xy 90.874232 -393.56295) (xy 90.838541 -393.521759)
			(xy 90.809075 -393.475909) (xy 90.786433 -393.426332) (xy 90.771078 -393.374037) (xy 90.763322 -393.320089)
			(xy 90.762836 -393.292838) (xy 90.325956 -393.292838) (xy 90.32547 -393.320089) (xy 90.317714 -393.374037)
			(xy 90.302359 -393.426332) (xy 90.279717 -393.475909) (xy 90.250251 -393.521759) (xy 90.21456 -393.56295)
			(xy 90.173369 -393.598641) (xy 90.127519 -393.628107) (xy 90.077942 -393.650749) (xy 90.025647 -393.666104)
			(xy 89.971699 -393.67386) (xy 89.917197 -393.67386) (xy 89.863249 -393.666104) (xy 89.810954 -393.650749)
			(xy 89.761377 -393.628107) (xy 89.715527 -393.598641) (xy 89.674336 -393.56295) (xy 89.638645 -393.521759)
			(xy 89.609179 -393.475909) (xy 89.586537 -393.426332) (xy 89.571182 -393.374037) (xy 89.563426 -393.320089)
			(xy 89.56294 -393.292838) (xy 89.12606 -393.292838) (xy 89.125574 -393.320107) (xy 89.117812 -393.374091)
			(xy 89.102447 -393.426421) (xy 89.07979 -393.476031) (xy 89.050304 -393.521912) (xy 89.014589 -393.563129)
			(xy 88.973372 -393.598844) (xy 88.927491 -393.62833) (xy 88.877881 -393.650987) (xy 88.825551 -393.666352)
			(xy 88.771567 -393.674114) (xy 88.717029 -393.674114) (xy 88.663045 -393.666352) (xy 88.610715 -393.650987)
			(xy 88.561105 -393.62833) (xy 88.515224 -393.598844) (xy 88.474007 -393.563129) (xy 88.438292 -393.521912)
			(xy 88.408806 -393.476031) (xy 88.386149 -393.426421) (xy 88.370784 -393.374091) (xy 88.363022 -393.320107)
			(xy 88.362536 -393.292838) (xy 87.926164 -393.292838) (xy 87.925678 -393.320107) (xy 87.917916 -393.374091)
			(xy 87.902551 -393.426421) (xy 87.879894 -393.476031) (xy 87.850408 -393.521912) (xy 87.814693 -393.563129)
			(xy 87.773476 -393.598844) (xy 87.727595 -393.62833) (xy 87.677985 -393.650987) (xy 87.625655 -393.666352)
			(xy 87.571671 -393.674114) (xy 87.517133 -393.674114) (xy 87.463149 -393.666352) (xy 87.410819 -393.650987)
			(xy 87.361209 -393.62833) (xy 87.315328 -393.598844) (xy 87.274111 -393.563129) (xy 87.238396 -393.521912)
			(xy 87.20891 -393.476031) (xy 87.186253 -393.426421) (xy 87.170888 -393.374091) (xy 87.163126 -393.320107)
			(xy 87.16264 -393.292838) (xy 86.72576 -393.292838) (xy 86.725274 -393.320089) (xy 86.717518 -393.374037)
			(xy 86.702163 -393.426332) (xy 86.679521 -393.475909) (xy 86.650055 -393.521759) (xy 86.614364 -393.56295)
			(xy 86.573173 -393.598641) (xy 86.527323 -393.628107) (xy 86.477746 -393.650749) (xy 86.425451 -393.666104)
			(xy 86.371503 -393.67386) (xy 86.317001 -393.67386) (xy 86.263053 -393.666104) (xy 86.210758 -393.650749)
			(xy 86.161181 -393.628107) (xy 86.115331 -393.598641) (xy 86.07414 -393.56295) (xy 86.038449 -393.521759)
			(xy 86.008983 -393.475909) (xy 85.986341 -393.426332) (xy 85.970986 -393.374037) (xy 85.96323 -393.320089)
			(xy 85.962744 -393.292838) (xy 85.525864 -393.292838) (xy 85.525378 -393.320089) (xy 85.517622 -393.374037)
			(xy 85.502267 -393.426332) (xy 85.479625 -393.475909) (xy 85.450159 -393.521759) (xy 85.414468 -393.56295)
			(xy 85.373277 -393.598641) (xy 85.327427 -393.628107) (xy 85.27785 -393.650749) (xy 85.225555 -393.666104)
			(xy 85.171607 -393.67386) (xy 85.117105 -393.67386) (xy 85.063157 -393.666104) (xy 85.010862 -393.650749)
			(xy 84.961285 -393.628107) (xy 84.915435 -393.598641) (xy 84.874244 -393.56295) (xy 84.838553 -393.521759)
			(xy 84.809087 -393.475909) (xy 84.786445 -393.426332) (xy 84.77109 -393.374037) (xy 84.763334 -393.320089)
			(xy 84.762848 -393.292838) (xy 84.325968 -393.292838) (xy 84.325482 -393.320107) (xy 84.31772 -393.374091)
			(xy 84.302355 -393.426421) (xy 84.279698 -393.476031) (xy 84.250212 -393.521912) (xy 84.214497 -393.563129)
			(xy 84.17328 -393.598844) (xy 84.127399 -393.62833) (xy 84.077789 -393.650987) (xy 84.025459 -393.666352)
			(xy 83.971475 -393.674114) (xy 83.916937 -393.674114) (xy 83.862953 -393.666352) (xy 83.810623 -393.650987)
			(xy 83.761013 -393.62833) (xy 83.715132 -393.598844) (xy 83.673915 -393.563129) (xy 83.6382 -393.521912)
			(xy 83.608714 -393.476031) (xy 83.586057 -393.426421) (xy 83.570692 -393.374091) (xy 83.56293 -393.320107)
			(xy 83.562444 -393.292838) (xy 83.126072 -393.292838) (xy 83.125586 -393.320107) (xy 83.117824 -393.374091)
			(xy 83.102459 -393.426421) (xy 83.079802 -393.476031) (xy 83.050316 -393.521912) (xy 83.014601 -393.563129)
			(xy 82.973384 -393.598844) (xy 82.927503 -393.62833) (xy 82.877893 -393.650987) (xy 82.825563 -393.666352)
			(xy 82.771579 -393.674114) (xy 82.717041 -393.674114) (xy 82.663057 -393.666352) (xy 82.610727 -393.650987)
			(xy 82.561117 -393.62833) (xy 82.515236 -393.598844) (xy 82.474019 -393.563129) (xy 82.438304 -393.521912)
			(xy 82.408818 -393.476031) (xy 82.386161 -393.426421) (xy 82.370796 -393.374091) (xy 82.363034 -393.320107)
			(xy 82.362548 -393.292838) (xy 81.925668 -393.292838) (xy 81.925182 -393.320089) (xy 81.917426 -393.374037)
			(xy 81.902071 -393.426332) (xy 81.879429 -393.475909) (xy 81.849963 -393.521759) (xy 81.814272 -393.56295)
			(xy 81.773081 -393.598641) (xy 81.727231 -393.628107) (xy 81.677654 -393.650749) (xy 81.625359 -393.666104)
			(xy 81.571411 -393.67386) (xy 81.516909 -393.67386) (xy 81.462961 -393.666104) (xy 81.410666 -393.650749)
			(xy 81.361089 -393.628107) (xy 81.315239 -393.598641) (xy 81.274048 -393.56295) (xy 81.238357 -393.521759)
			(xy 81.208891 -393.475909) (xy 81.186249 -393.426332) (xy 81.170894 -393.374037) (xy 81.163138 -393.320089)
			(xy 81.162652 -393.292838) (xy 80.725772 -393.292838) (xy 80.725286 -393.320089) (xy 80.71753 -393.374037)
			(xy 80.702175 -393.426332) (xy 80.679533 -393.475909) (xy 80.650067 -393.521759) (xy 80.614376 -393.56295)
			(xy 80.573185 -393.598641) (xy 80.527335 -393.628107) (xy 80.477758 -393.650749) (xy 80.425463 -393.666104)
			(xy 80.371515 -393.67386) (xy 80.317013 -393.67386) (xy 80.263065 -393.666104) (xy 80.21077 -393.650749)
			(xy 80.161193 -393.628107) (xy 80.115343 -393.598641) (xy 80.074152 -393.56295) (xy 80.038461 -393.521759)
			(xy 80.008995 -393.475909) (xy 79.986353 -393.426332) (xy 79.970998 -393.374037) (xy 79.963242 -393.320089)
			(xy 79.962756 -393.292838) (xy 66.197988 -393.292838) (xy 66.197502 -393.320089) (xy 66.189746 -393.374037)
			(xy 66.174391 -393.426332) (xy 66.151749 -393.475909) (xy 66.122283 -393.521759) (xy 66.086592 -393.56295)
			(xy 66.045401 -393.598641) (xy 65.999551 -393.628107) (xy 65.949974 -393.650749) (xy 65.897679 -393.666104)
			(xy 65.843731 -393.67386) (xy 65.789229 -393.67386) (xy 65.735281 -393.666104) (xy 65.682986 -393.650749)
			(xy 65.633409 -393.628107) (xy 65.587559 -393.598641) (xy 65.546368 -393.56295) (xy 65.510677 -393.521759)
			(xy 65.481211 -393.475909) (xy 65.458569 -393.426332) (xy 65.443214 -393.374037) (xy 65.435458 -393.320089)
			(xy 65.434972 -393.292838) (xy 64.998092 -393.292838) (xy 64.997606 -393.320089) (xy 64.98985 -393.374037)
			(xy 64.974495 -393.426332) (xy 64.951853 -393.475909) (xy 64.922387 -393.521759) (xy 64.886696 -393.56295)
			(xy 64.845505 -393.598641) (xy 64.799655 -393.628107) (xy 64.750078 -393.650749) (xy 64.697783 -393.666104)
			(xy 64.643835 -393.67386) (xy 64.589333 -393.67386) (xy 64.535385 -393.666104) (xy 64.48309 -393.650749)
			(xy 64.433513 -393.628107) (xy 64.387663 -393.598641) (xy 64.346472 -393.56295) (xy 64.310781 -393.521759)
			(xy 64.281315 -393.475909) (xy 64.258673 -393.426332) (xy 64.243318 -393.374037) (xy 64.235562 -393.320089)
			(xy 64.235076 -393.292838) (xy 63.798196 -393.292838) (xy 63.79771 -393.320107) (xy 63.789948 -393.374091)
			(xy 63.774583 -393.426421) (xy 63.751926 -393.476031) (xy 63.72244 -393.521912) (xy 63.686725 -393.563129)
			(xy 63.645508 -393.598844) (xy 63.599627 -393.62833) (xy 63.550017 -393.650987) (xy 63.497687 -393.666352)
			(xy 63.443703 -393.674114) (xy 63.389165 -393.674114) (xy 63.335181 -393.666352) (xy 63.282851 -393.650987)
			(xy 63.233241 -393.62833) (xy 63.18736 -393.598844) (xy 63.146143 -393.563129) (xy 63.110428 -393.521912)
			(xy 63.080942 -393.476031) (xy 63.058285 -393.426421) (xy 63.04292 -393.374091) (xy 63.035158 -393.320107)
			(xy 63.034672 -393.292838) (xy 62.5983 -393.292838) (xy 62.597814 -393.320107) (xy 62.590052 -393.374091)
			(xy 62.574687 -393.426421) (xy 62.55203 -393.476031) (xy 62.522544 -393.521912) (xy 62.486829 -393.563129)
			(xy 62.445612 -393.598844) (xy 62.399731 -393.62833) (xy 62.350121 -393.650987) (xy 62.297791 -393.666352)
			(xy 62.243807 -393.674114) (xy 62.189269 -393.674114) (xy 62.135285 -393.666352) (xy 62.082955 -393.650987)
			(xy 62.033345 -393.62833) (xy 61.987464 -393.598844) (xy 61.946247 -393.563129) (xy 61.910532 -393.521912)
			(xy 61.881046 -393.476031) (xy 61.858389 -393.426421) (xy 61.843024 -393.374091) (xy 61.835262 -393.320107)
			(xy 61.834776 -393.292838) (xy 61.398404 -393.292838) (xy 61.397918 -393.320107) (xy 61.390156 -393.374091)
			(xy 61.374791 -393.426421) (xy 61.352134 -393.476031) (xy 61.322648 -393.521912) (xy 61.286933 -393.563129)
			(xy 61.245716 -393.598844) (xy 61.199835 -393.62833) (xy 61.150225 -393.650987) (xy 61.097895 -393.666352)
			(xy 61.043911 -393.674114) (xy 60.989373 -393.674114) (xy 60.935389 -393.666352) (xy 60.883059 -393.650987)
			(xy 60.833449 -393.62833) (xy 60.787568 -393.598844) (xy 60.746351 -393.563129) (xy 60.710636 -393.521912)
			(xy 60.68115 -393.476031) (xy 60.658493 -393.426421) (xy 60.643128 -393.374091) (xy 60.635366 -393.320107)
			(xy 60.63488 -393.292838) (xy 60.198508 -393.292838) (xy 60.198022 -393.320107) (xy 60.19026 -393.374091)
			(xy 60.174895 -393.426421) (xy 60.152238 -393.476031) (xy 60.122752 -393.521912) (xy 60.087037 -393.563129)
			(xy 60.04582 -393.598844) (xy 59.999939 -393.62833) (xy 59.950329 -393.650987) (xy 59.897999 -393.666352)
			(xy 59.844015 -393.674114) (xy 59.789477 -393.674114) (xy 59.735493 -393.666352) (xy 59.683163 -393.650987)
			(xy 59.633553 -393.62833) (xy 59.587672 -393.598844) (xy 59.546455 -393.563129) (xy 59.51074 -393.521912)
			(xy 59.481254 -393.476031) (xy 59.458597 -393.426421) (xy 59.443232 -393.374091) (xy 59.43547 -393.320107)
			(xy 59.434984 -393.292838) (xy 58.998104 -393.292838) (xy 58.997618 -393.320089) (xy 58.989862 -393.374037)
			(xy 58.974507 -393.426332) (xy 58.951865 -393.475909) (xy 58.922399 -393.521759) (xy 58.886708 -393.56295)
			(xy 58.845517 -393.598641) (xy 58.799667 -393.628107) (xy 58.75009 -393.650749) (xy 58.697795 -393.666104)
			(xy 58.643847 -393.67386) (xy 58.589345 -393.67386) (xy 58.535397 -393.666104) (xy 58.483102 -393.650749)
			(xy 58.433525 -393.628107) (xy 58.387675 -393.598641) (xy 58.346484 -393.56295) (xy 58.310793 -393.521759)
			(xy 58.281327 -393.475909) (xy 58.258685 -393.426332) (xy 58.24333 -393.374037) (xy 58.235574 -393.320089)
			(xy 58.235088 -393.292838) (xy 57.798208 -393.292838) (xy 57.797722 -393.320089) (xy 57.789966 -393.374037)
			(xy 57.774611 -393.426332) (xy 57.751969 -393.475909) (xy 57.722503 -393.521759) (xy 57.686812 -393.56295)
			(xy 57.645621 -393.598641) (xy 57.599771 -393.628107) (xy 57.550194 -393.650749) (xy 57.497899 -393.666104)
			(xy 57.443951 -393.67386) (xy 57.389449 -393.67386) (xy 57.335501 -393.666104) (xy 57.283206 -393.650749)
			(xy 57.233629 -393.628107) (xy 57.187779 -393.598641) (xy 57.146588 -393.56295) (xy 57.110897 -393.521759)
			(xy 57.081431 -393.475909) (xy 57.058789 -393.426332) (xy 57.043434 -393.374037) (xy 57.035678 -393.320089)
			(xy 57.035192 -393.292838) (xy 56.598312 -393.292838) (xy 56.597826 -393.320107) (xy 56.590064 -393.374091)
			(xy 56.574699 -393.426421) (xy 56.552042 -393.476031) (xy 56.522556 -393.521912) (xy 56.486841 -393.563129)
			(xy 56.445624 -393.598844) (xy 56.399743 -393.62833) (xy 56.350133 -393.650987) (xy 56.297803 -393.666352)
			(xy 56.243819 -393.674114) (xy 56.189281 -393.674114) (xy 56.135297 -393.666352) (xy 56.082967 -393.650987)
			(xy 56.033357 -393.62833) (xy 55.987476 -393.598844) (xy 55.946259 -393.563129) (xy 55.910544 -393.521912)
			(xy 55.881058 -393.476031) (xy 55.858401 -393.426421) (xy 55.843036 -393.374091) (xy 55.835274 -393.320107)
			(xy 55.834788 -393.292838) (xy 55.398416 -393.292838) (xy 55.39793 -393.320107) (xy 55.390168 -393.374091)
			(xy 55.374803 -393.426421) (xy 55.352146 -393.476031) (xy 55.32266 -393.521912) (xy 55.286945 -393.563129)
			(xy 55.245728 -393.598844) (xy 55.199847 -393.62833) (xy 55.150237 -393.650987) (xy 55.097907 -393.666352)
			(xy 55.043923 -393.674114) (xy 54.989385 -393.674114) (xy 54.935401 -393.666352) (xy 54.883071 -393.650987)
			(xy 54.833461 -393.62833) (xy 54.78758 -393.598844) (xy 54.746363 -393.563129) (xy 54.710648 -393.521912)
			(xy 54.681162 -393.476031) (xy 54.658505 -393.426421) (xy 54.64314 -393.374091) (xy 54.635378 -393.320107)
			(xy 54.634892 -393.292838) (xy 54.198012 -393.292838) (xy 54.197526 -393.320089) (xy 54.18977 -393.374037)
			(xy 54.174415 -393.426332) (xy 54.151773 -393.475909) (xy 54.122307 -393.521759) (xy 54.086616 -393.56295)
			(xy 54.045425 -393.598641) (xy 53.999575 -393.628107) (xy 53.949998 -393.650749) (xy 53.897703 -393.666104)
			(xy 53.843755 -393.67386) (xy 53.789253 -393.67386) (xy 53.735305 -393.666104) (xy 53.68301 -393.650749)
			(xy 53.633433 -393.628107) (xy 53.587583 -393.598641) (xy 53.546392 -393.56295) (xy 53.510701 -393.521759)
			(xy 53.481235 -393.475909) (xy 53.458593 -393.426332) (xy 53.443238 -393.374037) (xy 53.435482 -393.320089)
			(xy 53.434996 -393.292838) (xy 52.998116 -393.292838) (xy 52.99763 -393.320089) (xy 52.989874 -393.374037)
			(xy 52.974519 -393.426332) (xy 52.951877 -393.475909) (xy 52.922411 -393.521759) (xy 52.88672 -393.56295)
			(xy 52.845529 -393.598641) (xy 52.799679 -393.628107) (xy 52.750102 -393.650749) (xy 52.697807 -393.666104)
			(xy 52.643859 -393.67386) (xy 52.589357 -393.67386) (xy 52.535409 -393.666104) (xy 52.483114 -393.650749)
			(xy 52.433537 -393.628107) (xy 52.387687 -393.598641) (xy 52.346496 -393.56295) (xy 52.310805 -393.521759)
			(xy 52.281339 -393.475909) (xy 52.258697 -393.426332) (xy 52.243342 -393.374037) (xy 52.235586 -393.320089)
			(xy 52.2351 -393.292838) (xy 51.79822 -393.292838) (xy 51.797734 -393.320107) (xy 51.789972 -393.374091)
			(xy 51.774607 -393.426421) (xy 51.75195 -393.476031) (xy 51.722464 -393.521912) (xy 51.686749 -393.563129)
			(xy 51.645532 -393.598844) (xy 51.599651 -393.62833) (xy 51.550041 -393.650987) (xy 51.497711 -393.666352)
			(xy 51.443727 -393.674114) (xy 51.389189 -393.674114) (xy 51.335205 -393.666352) (xy 51.282875 -393.650987)
			(xy 51.233265 -393.62833) (xy 51.187384 -393.598844) (xy 51.146167 -393.563129) (xy 51.110452 -393.521912)
			(xy 51.080966 -393.476031) (xy 51.058309 -393.426421) (xy 51.042944 -393.374091) (xy 51.035182 -393.320107)
			(xy 51.034696 -393.292838) (xy 50.598324 -393.292838) (xy 50.597838 -393.320107) (xy 50.590076 -393.374091)
			(xy 50.574711 -393.426421) (xy 50.552054 -393.476031) (xy 50.522568 -393.521912) (xy 50.486853 -393.563129)
			(xy 50.445636 -393.598844) (xy 50.399755 -393.62833) (xy 50.350145 -393.650987) (xy 50.297815 -393.666352)
			(xy 50.243831 -393.674114) (xy 50.189293 -393.674114) (xy 50.135309 -393.666352) (xy 50.082979 -393.650987)
			(xy 50.033369 -393.62833) (xy 49.987488 -393.598844) (xy 49.946271 -393.563129) (xy 49.910556 -393.521912)
			(xy 49.88107 -393.476031) (xy 49.858413 -393.426421) (xy 49.843048 -393.374091) (xy 49.835286 -393.320107)
			(xy 49.8348 -393.292838) (xy 49.39792 -393.292838) (xy 49.397434 -393.320089) (xy 49.389678 -393.374037)
			(xy 49.374323 -393.426332) (xy 49.351681 -393.475909) (xy 49.322215 -393.521759) (xy 49.286524 -393.56295)
			(xy 49.245333 -393.598641) (xy 49.199483 -393.628107) (xy 49.149906 -393.650749) (xy 49.097611 -393.666104)
			(xy 49.043663 -393.67386) (xy 48.989161 -393.67386) (xy 48.935213 -393.666104) (xy 48.882918 -393.650749)
			(xy 48.833341 -393.628107) (xy 48.787491 -393.598641) (xy 48.7463 -393.56295) (xy 48.710609 -393.521759)
			(xy 48.681143 -393.475909) (xy 48.658501 -393.426332) (xy 48.643146 -393.374037) (xy 48.63539 -393.320089)
			(xy 48.634904 -393.292838) (xy 48.198024 -393.292838) (xy 48.197538 -393.320089) (xy 48.189782 -393.374037)
			(xy 48.174427 -393.426332) (xy 48.151785 -393.475909) (xy 48.122319 -393.521759) (xy 48.086628 -393.56295)
			(xy 48.045437 -393.598641) (xy 47.999587 -393.628107) (xy 47.95001 -393.650749) (xy 47.897715 -393.666104)
			(xy 47.843767 -393.67386) (xy 47.789265 -393.67386) (xy 47.735317 -393.666104) (xy 47.683022 -393.650749)
			(xy 47.633445 -393.628107) (xy 47.587595 -393.598641) (xy 47.546404 -393.56295) (xy 47.510713 -393.521759)
			(xy 47.481247 -393.475909) (xy 47.458605 -393.426332) (xy 47.44325 -393.374037) (xy 47.435494 -393.320089)
			(xy 47.435008 -393.292838) (xy 2.509012 -393.292838) (xy 2.509012 -400.50847) (xy 103.485188 -400.50847)
			(xy 103.485723 -400.479553) (xy 103.494444 -400.422381) (xy 103.511697 -400.367182) (xy 103.537085 -400.315219)
			(xy 103.570027 -400.267685) (xy 103.609768 -400.225669) (xy 103.632254 -400.20748) (xy 103.64103 -400.199932)
			(xy 103.651203 -400.179162) (xy 103.651812 -400.167602) (xy 103.651812 -400.087338) (xy 103.651216 -400.075774)
			(xy 103.641039 -400.055003) (xy 103.632254 -400.04746) (xy 103.609742 -400.029303) (xy 103.57001 -399.987275)
			(xy 103.537076 -399.939733) (xy 103.511693 -399.887765) (xy 103.494443 -399.832562) (xy 103.48572 -399.775388)
			(xy 103.485188 -399.74647) (xy 103.485674 -399.719201) (xy 103.493436 -399.665217) (xy 103.508801 -399.612887)
			(xy 103.531458 -399.563277) (xy 103.560944 -399.517396) (xy 103.596659 -399.476179) (xy 103.637876 -399.440464)
			(xy 103.683757 -399.410978) (xy 103.733367 -399.388321) (xy 103.785697 -399.372956) (xy 103.839681 -399.365194)
			(xy 103.894219 -399.365194) (xy 103.948203 -399.372956) (xy 104.000533 -399.388321) (xy 104.050143 -399.410978)
			(xy 104.096024 -399.440464) (xy 104.137241 -399.476179) (xy 104.172956 -399.517396) (xy 104.202442 -399.563277)
			(xy 104.225099 -399.612887) (xy 104.240464 -399.665217) (xy 104.248226 -399.719201) (xy 104.248712 -399.74647)
			(xy 104.248206 -399.775388) (xy 104.239479 -399.832561) (xy 104.222221 -399.887762) (xy 104.196827 -399.939724)
			(xy 104.16388 -399.987257) (xy 104.124134 -400.029272) (xy 104.101646 -400.04746) (xy 104.092897 -400.055034)
			(xy 104.082709 -400.075784) (xy 104.082088 -400.087338) (xy 104.082088 -400.167602) (xy 104.082662 -400.179169)
			(xy 104.092854 -400.19994) (xy 104.101646 -400.20748) (xy 104.124129 -400.225671) (xy 104.163863 -400.267692)
			(xy 104.1968 -400.315227) (xy 104.222188 -400.367188) (xy 104.239445 -400.422385) (xy 104.248176 -400.479554)
			(xy 104.248712 -400.50847) (xy 104.248226 -400.535739) (xy 104.240464 -400.589723) (xy 104.225099 -400.642053)
			(xy 104.202442 -400.691663) (xy 104.172956 -400.737544) (xy 104.137241 -400.778761) (xy 104.096024 -400.814476)
			(xy 104.050143 -400.843962) (xy 104.000533 -400.866619) (xy 103.948203 -400.881984) (xy 103.894219 -400.889746)
			(xy 103.839681 -400.889746) (xy 103.785697 -400.881984) (xy 103.733367 -400.866619) (xy 103.683757 -400.843962)
			(xy 103.637876 -400.814476) (xy 103.596659 -400.778761) (xy 103.560944 -400.737544) (xy 103.531458 -400.691663)
			(xy 103.508801 -400.642053) (xy 103.493436 -400.589723) (xy 103.485674 -400.535739) (xy 103.485188 -400.50847)
			(xy 2.509012 -400.50847) (xy 2.509012 -403.371812) (xy 2.5095 -403.425034) (xy 2.517117 -403.531207)
			(xy 2.532283 -403.636566) (xy 2.554922 -403.740575) (xy 2.584919 -403.842706) (xy 2.622121 -403.942439)
			(xy 2.666338 -404.039266) (xy 2.717346 -404.132693) (xy 2.774884 -404.222247) (xy 2.838661 -404.307471)
			(xy 2.908351 -404.387931) (xy 2.945638 -404.425912) (xy 3.30962 -404.789894) (xy 37.568898 -404.789894)
			(xy 37.57287 -404.611651) (xy 37.584778 -404.433762) (xy 37.604599 -404.25658) (xy 37.632293 -404.080456)
			(xy 37.667805 -403.905741) (xy 37.711065 -403.732782) (xy 37.761987 -403.561921) (xy 37.82047 -403.393499)
			(xy 37.886397 -403.227849) (xy 37.959638 -403.0653) (xy 38.040048 -402.906175) (xy 38.127466 -402.75079)
			(xy 38.221719 -402.599454) (xy 38.32262 -402.452466) (xy 38.429969 -402.310119) (xy 38.543552 -402.172696)
			(xy 38.663145 -402.040469) (xy 38.788509 -401.9137) (xy 38.919396 -401.792642) (xy 39.055545 -401.677535)
			(xy 39.196687 -401.568607) (xy 39.342542 -401.466075) (xy 39.492819 -401.370141) (xy 39.64722 -401.280998)
			(xy 39.805439 -401.198821) (xy 39.967162 -401.123773) (xy 40.132067 -401.056005) (xy 40.299828 -400.995649)
			(xy 40.470111 -400.942827) (xy 40.642578 -400.897643) (xy 40.816886 -400.860186) (xy 40.99269 -400.830532)
			(xy 41.16964 -400.808739) (xy 41.347386 -400.794849) (xy 41.525573 -400.788892) (xy 41.70385 -400.790878)
			(xy 41.881861 -400.800804) (xy 42.059253 -400.81865) (xy 42.235673 -400.84438) (xy 42.410773 -400.877944)
			(xy 42.584204 -400.919274) (xy 42.755621 -400.96829) (xy 42.924684 -401.024892) (xy 43.091059 -401.08897)
			(xy 43.254413 -401.160396) (xy 43.414424 -401.239028) (xy 43.570773 -401.324709) (xy 43.72315 -401.417271)
			(xy 43.871253 -401.516528) (xy 44.014787 -401.622285) (xy 44.153467 -401.73433) (xy 44.287018 -401.852442)
			(xy 44.415175 -401.976386) (xy 44.537684 -402.105916) (xy 44.654301 -402.240775) (xy 44.764794 -402.380695)
			(xy 44.868945 -402.525398) (xy 44.966547 -402.674597) (xy 45.057405 -402.827996) (xy 45.141339 -402.98529)
			(xy 45.218184 -403.146166) (xy 45.287785 -403.310307) (xy 45.350006 -403.477384) (xy 45.404722 -403.647068)
			(xy 45.451824 -403.819021) (xy 45.49122 -403.992901) (xy 45.522831 -404.168364) (xy 45.546595 -404.34506)
			(xy 45.559703 -404.491748) (xy 47.413198 -404.491748) (xy 47.413198 -404.437252) (xy 47.420953 -404.38331)
			(xy 47.436306 -404.331021) (xy 47.458943 -404.281449) (xy 47.488404 -404.235603) (xy 47.52409 -404.194416)
			(xy 47.565274 -404.158726) (xy 47.611117 -404.12926) (xy 47.660687 -404.106618) (xy 47.712975 -404.091261)
			(xy 47.766916 -404.083501) (xy 47.794164 -404.083012) (xy 48.657764 -404.083012) (xy 48.68502 -404.083432)
			(xy 48.738978 -404.091186) (xy 48.791283 -404.106539) (xy 48.84087 -404.129181) (xy 48.88673 -404.15865)
			(xy 48.927929 -404.194345) (xy 48.963629 -404.235541) (xy 48.993102 -404.281398) (xy 49.015748 -404.330984)
			(xy 49.031107 -404.383287) (xy 49.038865 -404.437244) (xy 49.038865 -404.491752) (xy 50.476375 -404.491752)
			(xy 50.476375 -404.437248) (xy 50.484132 -404.3833) (xy 50.499487 -404.331005) (xy 50.522129 -404.281427)
			(xy 50.551596 -404.235576) (xy 50.587288 -404.194385) (xy 50.628479 -404.158693) (xy 50.67433 -404.129227)
			(xy 50.723908 -404.106586) (xy 50.776204 -404.091231) (xy 50.830152 -404.083475) (xy 50.857404 -404.083012)
			(xy 51.721004 -404.083012) (xy 51.748256 -404.083458) (xy 51.802207 -404.091215) (xy 51.854504 -404.106572)
			(xy 51.904083 -404.129214) (xy 51.949935 -404.158682) (xy 51.991127 -404.194376) (xy 52.02682 -404.235568)
			(xy 52.056288 -404.281421) (xy 52.07893 -404.331) (xy 52.094285 -404.383297) (xy 52.102042 -404.437248)
			(xy 52.102042 -404.491752) (xy 52.102042 -404.491753) (xy 53.539575 -404.491753) (xy 53.539575 -404.437247)
			(xy 53.547333 -404.383295) (xy 53.562691 -404.330996) (xy 53.585335 -404.281416) (xy 53.614806 -404.235563)
			(xy 53.650502 -404.194371) (xy 53.691698 -404.158679) (xy 53.737554 -404.129214) (xy 53.787137 -404.106575)
			(xy 53.839438 -404.091224) (xy 53.893391 -404.083472) (xy 53.920644 -404.083012) (xy 54.784244 -404.083012)
			(xy 54.811495 -404.083461) (xy 54.86544 -404.091223) (xy 54.917733 -404.106583) (xy 54.967307 -404.129227)
			(xy 55.013154 -404.158696) (xy 55.054341 -404.19439) (xy 55.09003 -404.235581) (xy 55.119494 -404.281432)
			(xy 55.142133 -404.331009) (xy 55.157487 -404.383303) (xy 55.165242 -404.437249) (xy 55.165242 -404.491749)
			(xy 56.602898 -404.491749) (xy 56.602898 -404.437251) (xy 56.610654 -404.383308) (xy 56.626007 -404.331017)
			(xy 56.648646 -404.281443) (xy 56.678109 -404.235596) (xy 56.713797 -404.194409) (xy 56.754983 -404.158719)
			(xy 56.800829 -404.129254) (xy 56.850402 -404.106613) (xy 56.902692 -404.091257) (xy 56.956635 -404.083499)
			(xy 56.983884 -404.083012) (xy 57.847484 -404.083012) (xy 57.874739 -404.083434) (xy 57.928695 -404.091189)
			(xy 57.980997 -404.106545) (xy 58.030582 -404.129188) (xy 58.07644 -404.158657) (xy 58.117636 -404.194352)
			(xy 58.153334 -404.235548) (xy 58.182805 -404.281404) (xy 58.20545 -404.330988) (xy 58.220807 -404.38329)
			(xy 58.228565 -404.437245) (xy 58.228565 -404.491753) (xy 59.666075 -404.491753) (xy 59.666075 -404.437247)
			(xy 59.673833 -404.383297) (xy 59.689189 -404.331) (xy 59.711832 -404.281421) (xy 59.741301 -404.235569)
			(xy 59.776995 -404.194378) (xy 59.818188 -404.158686) (xy 59.864042 -404.129221) (xy 59.913623 -404.106581)
			(xy 59.965921 -404.091227) (xy 60.019871 -404.083474) (xy 60.047124 -404.083012) (xy 60.910724 -404.083012)
			(xy 60.937976 -404.083459) (xy 60.991924 -404.091219) (xy 61.044218 -404.106577) (xy 61.093795 -404.129221)
			(xy 61.139645 -404.158689) (xy 61.180834 -404.194383) (xy 61.216525 -404.235575) (xy 61.245991 -404.281426)
			(xy 61.268631 -404.331004) (xy 61.283986 -404.3833) (xy 61.291742 -404.437248) (xy 61.291742 -404.491748)
			(xy 62.729398 -404.491748) (xy 62.729398 -404.437252) (xy 62.737153 -404.38331) (xy 62.752506 -404.331021)
			(xy 62.775143 -404.281449) (xy 62.804604 -404.235603) (xy 62.84029 -404.194416) (xy 62.881474 -404.158726)
			(xy 62.927317 -404.12926) (xy 62.976887 -404.106618) (xy 63.029175 -404.091261) (xy 63.083116 -404.083501)
			(xy 63.110364 -404.083012) (xy 63.973964 -404.083012) (xy 64.00122 -404.083432) (xy 64.055178 -404.091186)
			(xy 64.107483 -404.106539) (xy 64.15707 -404.129181) (xy 64.20293 -404.15865) (xy 64.244129 -404.194345)
			(xy 64.279829 -404.235541) (xy 64.309302 -404.281398) (xy 64.331948 -404.330984) (xy 64.347307 -404.383287)
			(xy 64.355065 -404.437244) (xy 64.355065 -404.491752) (xy 65.792575 -404.491752) (xy 65.792575 -404.437248)
			(xy 65.800332 -404.3833) (xy 65.815687 -404.331005) (xy 65.838329 -404.281427) (xy 65.867796 -404.235576)
			(xy 65.903488 -404.194385) (xy 65.944679 -404.158693) (xy 65.99053 -404.129227) (xy 66.040108 -404.106586)
			(xy 66.092404 -404.091231) (xy 66.146352 -404.083475) (xy 66.173604 -404.083012) (xy 67.037204 -404.083012)
			(xy 67.064456 -404.083458) (xy 67.118407 -404.091215) (xy 67.170704 -404.106572) (xy 67.220283 -404.129214)
			(xy 67.266135 -404.158682) (xy 67.307327 -404.194376) (xy 67.34302 -404.235568) (xy 67.372488 -404.281421)
			(xy 67.39513 -404.331) (xy 67.410485 -404.383297) (xy 67.418242 -404.437248) (xy 67.418242 -404.491752)
			(xy 67.418242 -404.491753) (xy 68.855775 -404.491753) (xy 68.855775 -404.437247) (xy 68.863533 -404.383295)
			(xy 68.878891 -404.330996) (xy 68.901535 -404.281416) (xy 68.931006 -404.235563) (xy 68.966702 -404.194371)
			(xy 69.007898 -404.158679) (xy 69.053754 -404.129214) (xy 69.103337 -404.106575) (xy 69.155638 -404.091224)
			(xy 69.209591 -404.083472) (xy 69.236844 -404.083012) (xy 70.100444 -404.083012) (xy 70.127695 -404.083461)
			(xy 70.18164 -404.091223) (xy 70.233933 -404.106583) (xy 70.283507 -404.129227) (xy 70.329354 -404.158696)
			(xy 70.370541 -404.19439) (xy 70.40623 -404.235581) (xy 70.435694 -404.281432) (xy 70.458333 -404.331009)
			(xy 70.473687 -404.383303) (xy 70.481442 -404.437249) (xy 70.481442 -404.491749) (xy 71.919098 -404.491749)
			(xy 71.919098 -404.437251) (xy 71.926854 -404.383308) (xy 71.942207 -404.331017) (xy 71.964846 -404.281443)
			(xy 71.994309 -404.235596) (xy 72.029997 -404.194409) (xy 72.071183 -404.158719) (xy 72.117029 -404.129254)
			(xy 72.166602 -404.106613) (xy 72.218892 -404.091257) (xy 72.272835 -404.083499) (xy 72.300084 -404.083012)
			(xy 73.163684 -404.083012) (xy 73.190939 -404.083434) (xy 73.244895 -404.091189) (xy 73.297197 -404.106545)
			(xy 73.346782 -404.129188) (xy 73.39264 -404.158657) (xy 73.433836 -404.194352) (xy 73.469534 -404.235548)
			(xy 73.499005 -404.281404) (xy 73.52165 -404.330988) (xy 73.537007 -404.38329) (xy 73.544765 -404.437245)
			(xy 73.544765 -404.491753) (xy 74.982275 -404.491753) (xy 74.982275 -404.437247) (xy 74.990033 -404.383297)
			(xy 75.005389 -404.331) (xy 75.028032 -404.281421) (xy 75.057501 -404.235569) (xy 75.093195 -404.194378)
			(xy 75.134388 -404.158686) (xy 75.180242 -404.129221) (xy 75.229823 -404.106581) (xy 75.282121 -404.091227)
			(xy 75.336071 -404.083474) (xy 75.363324 -404.083012) (xy 76.226924 -404.083012) (xy 76.254176 -404.083459)
			(xy 76.308124 -404.091219) (xy 76.360418 -404.106577) (xy 76.409995 -404.129221) (xy 76.455845 -404.158689)
			(xy 76.497034 -404.194383) (xy 76.532725 -404.235575) (xy 76.562191 -404.281426) (xy 76.584831 -404.331004)
			(xy 76.600186 -404.3833) (xy 76.607942 -404.437248) (xy 76.607942 -404.491748) (xy 78.045598 -404.491748)
			(xy 78.045598 -404.437252) (xy 78.053353 -404.38331) (xy 78.068706 -404.331021) (xy 78.091343 -404.281449)
			(xy 78.120804 -404.235603) (xy 78.15649 -404.194416) (xy 78.197674 -404.158726) (xy 78.243517 -404.12926)
			(xy 78.293087 -404.106618) (xy 78.345375 -404.091261) (xy 78.399316 -404.083501) (xy 78.426564 -404.083012)
			(xy 79.290164 -404.083012) (xy 79.31742 -404.083432) (xy 79.371378 -404.091186) (xy 79.423683 -404.106539)
			(xy 79.47327 -404.129181) (xy 79.51913 -404.15865) (xy 79.560329 -404.194345) (xy 79.596029 -404.235541)
			(xy 79.625502 -404.281398) (xy 79.648148 -404.330984) (xy 79.663507 -404.383287) (xy 79.671265 -404.437244)
			(xy 79.671265 -404.491752) (xy 81.108775 -404.491752) (xy 81.108775 -404.437248) (xy 81.116532 -404.3833)
			(xy 81.131887 -404.331005) (xy 81.154529 -404.281427) (xy 81.183996 -404.235576) (xy 81.219688 -404.194385)
			(xy 81.260879 -404.158693) (xy 81.30673 -404.129227) (xy 81.356308 -404.106586) (xy 81.408604 -404.091231)
			(xy 81.462552 -404.083475) (xy 81.489804 -404.083012) (xy 82.353404 -404.083012) (xy 82.380656 -404.083458)
			(xy 82.434607 -404.091215) (xy 82.486904 -404.106572) (xy 82.536483 -404.129214) (xy 82.582335 -404.158682)
			(xy 82.623527 -404.194376) (xy 82.65922 -404.235568) (xy 82.688688 -404.281421) (xy 82.71133 -404.331)
			(xy 82.726685 -404.383297) (xy 82.734442 -404.437248) (xy 82.734442 -404.491752) (xy 82.734442 -404.491753)
			(xy 84.171975 -404.491753) (xy 84.171975 -404.437247) (xy 84.179733 -404.383295) (xy 84.195091 -404.330996)
			(xy 84.217735 -404.281416) (xy 84.247206 -404.235563) (xy 84.282902 -404.194371) (xy 84.324098 -404.158679)
			(xy 84.369954 -404.129214) (xy 84.419537 -404.106575) (xy 84.471838 -404.091224) (xy 84.525791 -404.083472)
			(xy 84.553044 -404.083012) (xy 85.416644 -404.083012) (xy 85.443895 -404.083461) (xy 85.49784 -404.091223)
			(xy 85.550133 -404.106583) (xy 85.599707 -404.129227) (xy 85.645554 -404.158696) (xy 85.686741 -404.19439)
			(xy 85.72243 -404.235581) (xy 85.751894 -404.281432) (xy 85.774533 -404.331009) (xy 85.789887 -404.383303)
			(xy 85.797642 -404.437249) (xy 85.797642 -404.491749) (xy 87.235298 -404.491749) (xy 87.235298 -404.437251)
			(xy 87.243054 -404.383308) (xy 87.258407 -404.331017) (xy 87.281046 -404.281443) (xy 87.310509 -404.235596)
			(xy 87.346197 -404.194409) (xy 87.387383 -404.158719) (xy 87.433229 -404.129254) (xy 87.482802 -404.106613)
			(xy 87.535092 -404.091257) (xy 87.589035 -404.083499) (xy 87.616284 -404.083012) (xy 88.479884 -404.083012)
			(xy 88.507139 -404.083434) (xy 88.561095 -404.091189) (xy 88.613397 -404.106545) (xy 88.662982 -404.129188)
			(xy 88.70884 -404.158657) (xy 88.750036 -404.194352) (xy 88.785734 -404.235548) (xy 88.815205 -404.281404)
			(xy 88.83785 -404.330988) (xy 88.853207 -404.38329) (xy 88.860965 -404.437245) (xy 88.860965 -404.491753)
			(xy 90.298475 -404.491753) (xy 90.298475 -404.437247) (xy 90.306233 -404.383297) (xy 90.321589 -404.331)
			(xy 90.344232 -404.281421) (xy 90.373701 -404.235569) (xy 90.409395 -404.194378) (xy 90.450588 -404.158686)
			(xy 90.496442 -404.129221) (xy 90.546023 -404.106581) (xy 90.598321 -404.091227) (xy 90.652271 -404.083474)
			(xy 90.679524 -404.083012) (xy 91.543124 -404.083012) (xy 91.570376 -404.083459) (xy 91.624324 -404.091219)
			(xy 91.676618 -404.106577) (xy 91.726195 -404.129221) (xy 91.772045 -404.158689) (xy 91.813234 -404.194383)
			(xy 91.848925 -404.235575) (xy 91.878391 -404.281426) (xy 91.901031 -404.331004) (xy 91.916386 -404.3833)
			(xy 91.924142 -404.437248) (xy 91.924142 -404.491748) (xy 93.361798 -404.491748) (xy 93.361798 -404.437252)
			(xy 93.369553 -404.38331) (xy 93.384906 -404.331021) (xy 93.407543 -404.281449) (xy 93.437004 -404.235603)
			(xy 93.47269 -404.194416) (xy 93.513874 -404.158726) (xy 93.559717 -404.12926) (xy 93.609287 -404.106618)
			(xy 93.661575 -404.091261) (xy 93.715516 -404.083501) (xy 93.742764 -404.083012) (xy 94.606364 -404.083012)
			(xy 94.63362 -404.083432) (xy 94.687578 -404.091186) (xy 94.739883 -404.106539) (xy 94.78947 -404.129181)
			(xy 94.83533 -404.15865) (xy 94.876529 -404.194345) (xy 94.912229 -404.235541) (xy 94.941702 -404.281398)
			(xy 94.964348 -404.330984) (xy 94.979707 -404.383287) (xy 94.987465 -404.437244) (xy 94.987465 -404.491752)
			(xy 114.513075 -404.491752) (xy 114.513075 -404.437248) (xy 114.520832 -404.3833) (xy 114.536188 -404.331004)
			(xy 114.558829 -404.281426) (xy 114.588296 -404.235575) (xy 114.623989 -404.194384) (xy 114.66518 -404.158693)
			(xy 114.711031 -404.129226) (xy 114.76061 -404.106585) (xy 114.812906 -404.091231) (xy 114.866854 -404.083475)
			(xy 114.894106 -404.083012) (xy 115.757706 -404.083012) (xy 115.784958 -404.083458) (xy 115.838908 -404.091216)
			(xy 115.891205 -404.106572) (xy 115.940784 -404.129215) (xy 115.986636 -404.158683) (xy 116.027828 -404.194376)
			(xy 116.063521 -404.235569) (xy 116.092988 -404.281421) (xy 116.11563 -404.331001) (xy 116.130985 -404.383298)
			(xy 116.138742 -404.437248) (xy 116.138742 -404.491752) (xy 116.138742 -404.491754) (xy 117.576275 -404.491754)
			(xy 117.576275 -404.437246) (xy 117.584033 -404.383294) (xy 117.599391 -404.330996) (xy 117.622035 -404.281415)
			(xy 117.651506 -404.235562) (xy 117.687203 -404.19437) (xy 117.728399 -404.158679) (xy 117.774255 -404.129213)
			(xy 117.823839 -404.106575) (xy 117.876139 -404.091223) (xy 117.930092 -404.083472) (xy 117.957346 -404.083012)
			(xy 118.820946 -404.083012) (xy 118.848197 -404.083461) (xy 118.902142 -404.091223) (xy 118.954434 -404.106583)
			(xy 119.004008 -404.129228) (xy 119.049855 -404.158697) (xy 119.091042 -404.194391) (xy 119.12673 -404.235582)
			(xy 119.156194 -404.281432) (xy 119.178833 -404.331009) (xy 119.194187 -404.383303) (xy 119.201942 -404.437249)
			(xy 119.201942 -404.491749) (xy 120.639598 -404.491749) (xy 120.639598 -404.437251) (xy 120.647354 -404.383307)
			(xy 120.662708 -404.331016) (xy 120.685346 -404.281443) (xy 120.71481 -404.235596) (xy 120.750498 -404.194408)
			(xy 120.791684 -404.158718) (xy 120.83753 -404.129253) (xy 120.887103 -404.106612) (xy 120.939394 -404.091257)
			(xy 120.993337 -404.083499) (xy 121.020586 -404.083012) (xy 121.884186 -404.083012) (xy 121.911441 -404.083434)
			(xy 121.965396 -404.09119) (xy 122.017699 -404.106545) (xy 122.067283 -404.129188) (xy 122.113141 -404.158657)
			(xy 122.154337 -404.194353) (xy 122.190034 -404.235548) (xy 122.219505 -404.281405) (xy 122.24215 -404.330988)
			(xy 122.257507 -404.38329) (xy 122.265265 -404.437245) (xy 122.265265 -404.491753) (xy 123.702775 -404.491753)
			(xy 123.702775 -404.437247) (xy 123.710533 -404.383297) (xy 123.725889 -404.331) (xy 123.748532 -404.281421)
			(xy 123.778001 -404.235569) (xy 123.813696 -404.194377) (xy 123.854889 -404.158686) (xy 123.900743 -404.12922)
			(xy 123.950324 -404.10658) (xy 124.002622 -404.091227) (xy 124.056573 -404.083474) (xy 124.083826 -404.083012)
			(xy 124.947426 -404.083012) (xy 124.974677 -404.08346) (xy 125.028625 -404.09122) (xy 125.08092 -404.106578)
			(xy 125.130496 -404.129222) (xy 125.176346 -404.15869) (xy 125.217535 -404.194383) (xy 125.253226 -404.235575)
			(xy 125.282691 -404.281427) (xy 125.305331 -404.331005) (xy 125.320686 -404.3833) (xy 125.328442 -404.437249)
			(xy 125.328442 -404.491748) (xy 126.766098 -404.491748) (xy 126.766098 -404.437252) (xy 126.773853 -404.38331)
			(xy 126.789206 -404.331021) (xy 126.811843 -404.281448) (xy 126.841305 -404.235602) (xy 126.876991 -404.194415)
			(xy 126.918175 -404.158725) (xy 126.964018 -404.12926) (xy 127.013589 -404.106618) (xy 127.065877 -404.091261)
			(xy 127.119818 -404.083501) (xy 127.147066 -404.083012) (xy 128.010666 -404.083012) (xy 128.037922 -404.083433)
			(xy 128.091879 -404.091186) (xy 128.144184 -404.10654) (xy 128.193771 -404.129182) (xy 128.239631 -404.15865)
			(xy 128.28083 -404.194346) (xy 128.316529 -404.235542) (xy 128.346002 -404.281399) (xy 128.368648 -404.330984)
			(xy 128.384007 -404.383287) (xy 128.391765 -404.437244) (xy 128.391765 -404.491752) (xy 129.829275 -404.491752)
			(xy 129.829275 -404.437248) (xy 129.837032 -404.3833) (xy 129.852388 -404.331004) (xy 129.875029 -404.281426)
			(xy 129.904496 -404.235575) (xy 129.940189 -404.194384) (xy 129.98138 -404.158693) (xy 130.027231 -404.129226)
			(xy 130.07681 -404.106585) (xy 130.129106 -404.091231) (xy 130.183054 -404.083475) (xy 130.210306 -404.083012)
			(xy 131.073906 -404.083012) (xy 131.101158 -404.083458) (xy 131.155108 -404.091216) (xy 131.207405 -404.106572)
			(xy 131.256984 -404.129215) (xy 131.302836 -404.158683) (xy 131.344028 -404.194376) (xy 131.379721 -404.235569)
			(xy 131.409188 -404.281421) (xy 131.43183 -404.331001) (xy 131.447185 -404.383298) (xy 131.454942 -404.437248)
			(xy 131.454942 -404.491752) (xy 131.454942 -404.491754) (xy 132.892475 -404.491754) (xy 132.892475 -404.437246)
			(xy 132.900233 -404.383294) (xy 132.915591 -404.330996) (xy 132.938235 -404.281415) (xy 132.967706 -404.235562)
			(xy 133.003403 -404.19437) (xy 133.044599 -404.158679) (xy 133.090455 -404.129213) (xy 133.140039 -404.106575)
			(xy 133.192339 -404.091223) (xy 133.246292 -404.083472) (xy 133.273546 -404.083012) (xy 134.137146 -404.083012)
			(xy 134.164397 -404.083461) (xy 134.218342 -404.091223) (xy 134.270634 -404.106583) (xy 134.320208 -404.129228)
			(xy 134.366055 -404.158697) (xy 134.407242 -404.194391) (xy 134.44293 -404.235582) (xy 134.472394 -404.281432)
			(xy 134.495033 -404.331009) (xy 134.510387 -404.383303) (xy 134.518142 -404.437249) (xy 134.518142 -404.491749)
			(xy 135.955798 -404.491749) (xy 135.955798 -404.437251) (xy 135.963554 -404.383307) (xy 135.978908 -404.331016)
			(xy 136.001546 -404.281443) (xy 136.03101 -404.235596) (xy 136.066698 -404.194408) (xy 136.107884 -404.158718)
			(xy 136.15373 -404.129253) (xy 136.203303 -404.106612) (xy 136.255594 -404.091257) (xy 136.309537 -404.083499)
			(xy 136.336786 -404.083012) (xy 137.200386 -404.083012) (xy 137.227641 -404.083434) (xy 137.281596 -404.09119)
			(xy 137.333899 -404.106545) (xy 137.383483 -404.129188) (xy 137.429341 -404.158657) (xy 137.470537 -404.194353)
			(xy 137.506234 -404.235548) (xy 137.535705 -404.281405) (xy 137.55835 -404.330988) (xy 137.573707 -404.38329)
			(xy 137.581465 -404.437245) (xy 137.581465 -404.491753) (xy 139.018975 -404.491753) (xy 139.018975 -404.437247)
			(xy 139.026733 -404.383297) (xy 139.042089 -404.331) (xy 139.064732 -404.281421) (xy 139.094201 -404.235569)
			(xy 139.129896 -404.194377) (xy 139.171089 -404.158686) (xy 139.216943 -404.12922) (xy 139.266524 -404.10658)
			(xy 139.318822 -404.091227) (xy 139.372773 -404.083474) (xy 139.400026 -404.083012) (xy 140.263626 -404.083012)
			(xy 140.290877 -404.08346) (xy 140.344825 -404.09122) (xy 140.39712 -404.106578) (xy 140.446696 -404.129222)
			(xy 140.492546 -404.15869) (xy 140.533735 -404.194383) (xy 140.569426 -404.235575) (xy 140.598891 -404.281427)
			(xy 140.621531 -404.331005) (xy 140.636886 -404.3833) (xy 140.644642 -404.437249) (xy 140.644642 -404.491748)
			(xy 142.082298 -404.491748) (xy 142.082298 -404.437252) (xy 142.090053 -404.38331) (xy 142.105406 -404.331021)
			(xy 142.128043 -404.281448) (xy 142.157505 -404.235602) (xy 142.193191 -404.194415) (xy 142.234375 -404.158725)
			(xy 142.280218 -404.12926) (xy 142.329789 -404.106618) (xy 142.382077 -404.091261) (xy 142.436018 -404.083501)
			(xy 142.463266 -404.083012) (xy 143.326866 -404.083012) (xy 143.354122 -404.083433) (xy 143.408079 -404.091186)
			(xy 143.460384 -404.10654) (xy 143.509971 -404.129182) (xy 143.555831 -404.15865) (xy 143.59703 -404.194346)
			(xy 143.632729 -404.235542) (xy 143.662202 -404.281399) (xy 143.684848 -404.330984) (xy 143.700207 -404.383287)
			(xy 143.707965 -404.437244) (xy 143.707965 -404.491752) (xy 145.145475 -404.491752) (xy 145.145475 -404.437248)
			(xy 145.153232 -404.3833) (xy 145.168588 -404.331004) (xy 145.191229 -404.281426) (xy 145.220696 -404.235575)
			(xy 145.256389 -404.194384) (xy 145.29758 -404.158693) (xy 145.343431 -404.129226) (xy 145.39301 -404.106585)
			(xy 145.445306 -404.091231) (xy 145.499254 -404.083475) (xy 145.526506 -404.083012) (xy 146.390106 -404.083012)
			(xy 146.417358 -404.083458) (xy 146.471308 -404.091216) (xy 146.523605 -404.106572) (xy 146.573184 -404.129215)
			(xy 146.619036 -404.158683) (xy 146.660228 -404.194376) (xy 146.695921 -404.235569) (xy 146.725388 -404.281421)
			(xy 146.74803 -404.331001) (xy 146.763385 -404.383298) (xy 146.771142 -404.437248) (xy 146.771142 -404.491752)
			(xy 146.771142 -404.491754) (xy 148.208675 -404.491754) (xy 148.208675 -404.437246) (xy 148.216433 -404.383294)
			(xy 148.231791 -404.330996) (xy 148.254435 -404.281415) (xy 148.283906 -404.235562) (xy 148.319603 -404.19437)
			(xy 148.360799 -404.158679) (xy 148.406655 -404.129213) (xy 148.456239 -404.106575) (xy 148.508539 -404.091223)
			(xy 148.562492 -404.083472) (xy 148.589746 -404.083012) (xy 149.453346 -404.083012) (xy 149.480597 -404.083461)
			(xy 149.534542 -404.091223) (xy 149.586834 -404.106583) (xy 149.636408 -404.129228) (xy 149.682255 -404.158697)
			(xy 149.723442 -404.194391) (xy 149.75913 -404.235582) (xy 149.788594 -404.281432) (xy 149.811233 -404.331009)
			(xy 149.826587 -404.383303) (xy 149.834342 -404.437249) (xy 149.834342 -404.491749) (xy 151.271998 -404.491749)
			(xy 151.271998 -404.437251) (xy 151.279754 -404.383307) (xy 151.295108 -404.331016) (xy 151.317746 -404.281443)
			(xy 151.34721 -404.235596) (xy 151.382898 -404.194408) (xy 151.424084 -404.158718) (xy 151.46993 -404.129253)
			(xy 151.519503 -404.106612) (xy 151.571794 -404.091257) (xy 151.625737 -404.083499) (xy 151.652986 -404.083012)
			(xy 152.516586 -404.083012) (xy 152.543841 -404.083434) (xy 152.597796 -404.09119) (xy 152.650099 -404.106545)
			(xy 152.699683 -404.129188) (xy 152.745541 -404.158657) (xy 152.786737 -404.194353) (xy 152.822434 -404.235548)
			(xy 152.851905 -404.281405) (xy 152.87455 -404.330988) (xy 152.889907 -404.38329) (xy 152.897665 -404.437245)
			(xy 152.897665 -404.491753) (xy 154.335175 -404.491753) (xy 154.335175 -404.437247) (xy 154.342933 -404.383297)
			(xy 154.358289 -404.331) (xy 154.380932 -404.281421) (xy 154.410401 -404.235569) (xy 154.446096 -404.194377)
			(xy 154.487289 -404.158686) (xy 154.533143 -404.12922) (xy 154.582724 -404.10658) (xy 154.635022 -404.091227)
			(xy 154.688973 -404.083474) (xy 154.716226 -404.083012) (xy 155.579826 -404.083012) (xy 155.607077 -404.08346)
			(xy 155.661025 -404.09122) (xy 155.71332 -404.106578) (xy 155.762896 -404.129222) (xy 155.808746 -404.15869)
			(xy 155.849935 -404.194383) (xy 155.885626 -404.235575) (xy 155.915091 -404.281427) (xy 155.937731 -404.331005)
			(xy 155.953086 -404.3833) (xy 155.960842 -404.437249) (xy 155.960842 -404.491748) (xy 157.398498 -404.491748)
			(xy 157.398498 -404.437252) (xy 157.406253 -404.38331) (xy 157.421606 -404.331021) (xy 157.444243 -404.281448)
			(xy 157.473705 -404.235602) (xy 157.509391 -404.194415) (xy 157.550575 -404.158725) (xy 157.596418 -404.12926)
			(xy 157.645989 -404.106618) (xy 157.698277 -404.091261) (xy 157.752218 -404.083501) (xy 157.779466 -404.083012)
			(xy 158.643066 -404.083012) (xy 158.670322 -404.083433) (xy 158.724279 -404.091186) (xy 158.776584 -404.10654)
			(xy 158.826171 -404.129182) (xy 158.872031 -404.15865) (xy 158.91323 -404.194346) (xy 158.948929 -404.235542)
			(xy 158.978402 -404.281399) (xy 159.001048 -404.330984) (xy 159.016407 -404.383287) (xy 159.024165 -404.437244)
			(xy 159.024165 -404.491752) (xy 160.461675 -404.491752) (xy 160.461675 -404.437248) (xy 160.469432 -404.3833)
			(xy 160.484788 -404.331004) (xy 160.507429 -404.281426) (xy 160.536896 -404.235575) (xy 160.572589 -404.194384)
			(xy 160.61378 -404.158693) (xy 160.659631 -404.129226) (xy 160.70921 -404.106585) (xy 160.761506 -404.091231)
			(xy 160.815454 -404.083475) (xy 160.842706 -404.083012) (xy 161.706306 -404.083012) (xy 161.733558 -404.083458)
			(xy 161.787508 -404.091216) (xy 161.839805 -404.106572) (xy 161.889384 -404.129215) (xy 161.935236 -404.158683)
			(xy 161.976428 -404.194376) (xy 162.012121 -404.235569) (xy 162.041588 -404.281421) (xy 162.06423 -404.331001)
			(xy 162.079585 -404.383298) (xy 162.087342 -404.437248) (xy 162.087342 -404.491752) (xy 162.079585 -404.545702)
			(xy 162.06423 -404.597999) (xy 162.041588 -404.647579) (xy 162.012121 -404.693431) (xy 161.976428 -404.734624)
			(xy 161.935236 -404.770317) (xy 161.904774 -404.789894) (xy 166.998662 -404.789894) (xy 167.002634 -404.611651)
			(xy 167.014542 -404.433762) (xy 167.034363 -404.25658) (xy 167.062057 -404.080456) (xy 167.097569 -403.905741)
			(xy 167.140829 -403.732782) (xy 167.191751 -403.561921) (xy 167.250234 -403.393499) (xy 167.316161 -403.227849)
			(xy 167.389402 -403.0653) (xy 167.469812 -402.906175) (xy 167.55723 -402.75079) (xy 167.651483 -402.599454)
			(xy 167.752384 -402.452466) (xy 167.859733 -402.310119) (xy 167.973316 -402.172696) (xy 168.092909 -402.040469)
			(xy 168.218273 -401.9137) (xy 168.34916 -401.792642) (xy 168.485309 -401.677535) (xy 168.626451 -401.568607)
			(xy 168.772306 -401.466075) (xy 168.922583 -401.370141) (xy 169.076984 -401.280998) (xy 169.235203 -401.198821)
			(xy 169.396926 -401.123773) (xy 169.561831 -401.056005) (xy 169.729592 -400.995649) (xy 169.899875 -400.942827)
			(xy 170.072342 -400.897643) (xy 170.24665 -400.860186) (xy 170.422454 -400.830532) (xy 170.599404 -400.808739)
			(xy 170.77715 -400.794849) (xy 170.955337 -400.788892) (xy 171.133614 -400.790878) (xy 171.311625 -400.800804)
			(xy 171.489017 -400.81865) (xy 171.665437 -400.84438) (xy 171.840537 -400.877944) (xy 172.013968 -400.919274)
			(xy 172.185385 -400.96829) (xy 172.354448 -401.024892) (xy 172.520823 -401.08897) (xy 172.684177 -401.160396)
			(xy 172.844188 -401.239028) (xy 173.000537 -401.324709) (xy 173.152914 -401.417271) (xy 173.301017 -401.516528)
			(xy 173.444551 -401.622285) (xy 173.583231 -401.73433) (xy 173.716782 -401.852442) (xy 173.844939 -401.976386)
			(xy 173.967448 -402.105916) (xy 174.084065 -402.240775) (xy 174.194558 -402.380695) (xy 174.298709 -402.525398)
			(xy 174.396311 -402.674597) (xy 174.487169 -402.827996) (xy 174.571103 -402.98529) (xy 174.647948 -403.146166)
			(xy 174.680622 -403.223222) (xy 183.966612 -403.223222) (xy 183.966612 -403.222714) (xy 183.967041 -403.181385)
			(xy 183.974705 -403.099084) (xy 183.989967 -403.017847) (xy 184.012697 -402.938376) (xy 184.042698 -402.861355)
			(xy 184.079712 -402.787448) (xy 184.12342 -402.717292) (xy 184.173445 -402.651491) (xy 184.201054 -402.620734)
			(xy 184.207126 -402.613482) (xy 184.214027 -402.59589) (xy 184.214516 -402.586444) (xy 184.214516 -402.555964)
			(xy 184.214137 -402.546498) (xy 184.207208 -402.528878) (xy 184.201054 -402.521674) (xy 184.173435 -402.490923)
			(xy 184.123404 -402.425124) (xy 184.07969 -402.354969) (xy 184.042671 -402.281062) (xy 184.012666 -402.20404)
			(xy 183.989932 -402.124568) (xy 183.974667 -402.043329) (xy 183.967002 -401.961026) (xy 183.967002 -401.878366)
			(xy 183.974668 -401.796062) (xy 183.989934 -401.714824) (xy 184.012668 -401.635352) (xy 184.042675 -401.55833)
			(xy 184.079695 -401.484423) (xy 184.123409 -401.414268) (xy 184.173441 -401.34847) (xy 184.201054 -401.317714)
			(xy 184.207134 -401.310468) (xy 184.214031 -401.292871) (xy 184.214516 -401.283424) (xy 184.214516 -401.252944)
			(xy 184.214097 -401.243482) (xy 184.207196 -401.225862) (xy 184.201054 -401.218654) (xy 184.173435 -401.187907)
			(xy 184.12342 -401.1221) (xy 184.079722 -401.05194) (xy 184.042717 -400.97803) (xy 184.012723 -400.901008)
			(xy 183.989999 -400.821537) (xy 183.974741 -400.740302) (xy 183.967081 -400.658002) (xy 183.966612 -400.616674)
			(xy 183.967088 -400.575568) (xy 183.974674 -400.493705) (xy 183.98978 -400.412892) (xy 184.012276 -400.333817)
			(xy 184.041971 -400.257154) (xy 184.078611 -400.183558) (xy 184.121884 -400.113655) (xy 184.171421 -400.048042)
			(xy 184.226799 -399.987279) (xy 184.287547 -399.931883) (xy 184.353145 -399.882327) (xy 184.423036 -399.839034)
			(xy 184.496622 -399.802373) (xy 184.573276 -399.772657) (xy 184.652345 -399.750138) (xy 184.733154 -399.735009)
			(xy 184.815014 -399.727399) (xy 184.85612 -399.726912) (xy 184.900625 -399.727439) (xy 184.989189 -399.736331)
			(xy 185.076422 -399.754024) (xy 185.161452 -399.780341) (xy 185.243428 -399.815019) (xy 185.321531 -399.857711)
			(xy 185.394979 -399.90799) (xy 185.463038 -399.965354) (xy 185.494422 -399.996914) (xy 185.501871 -400.003965)
			(xy 185.52075 -400.011949) (xy 185.530998 -400.012408) (xy 185.603642 -400.012408) (xy 185.613891 -400.011949)
			(xy 185.632766 -400.003963) (xy 185.640218 -399.996914) (xy 185.671594 -399.965346) (xy 185.739655 -399.907985)
			(xy 185.813105 -399.857708) (xy 185.891209 -399.815019) (xy 185.973186 -399.780344) (xy 186.058217 -399.75403)
			(xy 186.145451 -399.736341) (xy 186.234015 -399.727453) (xy 186.27852 -399.726912) (xy 186.32201 -399.727445)
			(xy 186.408572 -399.735955) (xy 186.493892 -399.752871) (xy 186.577152 -399.778033) (xy 186.65756 -399.811201)
			(xy 186.734348 -399.852056) (xy 186.806782 -399.900211) (xy 186.874171 -399.955204) (xy 186.905392 -399.985484)
			(xy 186.905646 -399.985738) (xy 186.913054 -399.992282) (xy 186.931335 -399.999743) (xy 186.941206 -400.000216)
			(xy 187.012834 -400.000216) (xy 187.022717 -399.999799) (xy 187.041016 -399.992329) (xy 187.048394 -399.985738)
			(xy 187.048648 -399.985484) (xy 187.079882 -399.955217) (xy 187.14727 -399.900227) (xy 187.219703 -399.852074)
			(xy 187.296489 -399.811218) (xy 187.376895 -399.77805) (xy 187.460154 -399.752886) (xy 187.54547 -399.735966)
			(xy 187.632031 -399.727452) (xy 187.67552 -399.726912) (xy 187.716616 -399.727347) (xy 187.798457 -399.734931)
			(xy 187.87925 -399.750033) (xy 187.958305 -399.772524) (xy 188.034948 -399.802212) (xy 188.108525 -399.838843)
			(xy 188.178409 -399.882106) (xy 188.244005 -399.931632) (xy 188.304751 -399.986997) (xy 188.360132 -400.047731)
			(xy 188.409673 -400.113314) (xy 188.452953 -400.183188) (xy 188.489602 -400.256756) (xy 188.519308 -400.333392)
			(xy 188.541818 -400.412442) (xy 188.556939 -400.493231) (xy 188.564543 -400.57507) (xy 188.565028 -400.616166)
			(xy 188.565028 -400.616674) (xy 188.564581 -400.658002) (xy 188.556919 -400.740303) (xy 188.541658 -400.821539)
			(xy 188.518931 -400.901009) (xy 188.488932 -400.97803) (xy 188.451921 -401.051937) (xy 188.408216 -401.122094)
			(xy 188.358194 -401.187896) (xy 188.330586 -401.218654) (xy 188.324524 -401.225913) (xy 188.317616 -401.2435)
			(xy 188.317124 -401.252944) (xy 188.317124 -401.283424) (xy 188.3175 -401.292891) (xy 188.32443 -401.310511)
			(xy 188.330586 -401.317714) (xy 188.358194 -401.348474) (xy 188.408229 -401.414271) (xy 188.451946 -401.484425)
			(xy 188.488968 -401.558331) (xy 188.518976 -401.635351) (xy 188.541712 -401.714823) (xy 188.556979 -401.796062)
			(xy 188.564645 -401.878365) (xy 188.564646 -401.961026) (xy 188.55698 -402.04333) (xy 188.541714 -402.124568)
			(xy 188.518979 -402.20404) (xy 188.488972 -402.281061) (xy 188.45195 -402.354968) (xy 188.408234 -402.425122)
			(xy 188.3582 -402.490919) (xy 188.330586 -402.521674) (xy 188.324516 -402.528927) (xy 188.317612 -402.546518)
			(xy 188.317124 -402.555964) (xy 188.317124 -402.586444) (xy 188.31749 -402.595912) (xy 188.324426 -402.613532)
			(xy 188.330586 -402.620734) (xy 188.358206 -402.65148) (xy 188.40822 -402.717288) (xy 188.451917 -402.787448)
			(xy 188.488922 -402.861358) (xy 188.518915 -402.93838) (xy 188.541639 -403.017851) (xy 188.556897 -403.099086)
			(xy 188.564559 -403.181386) (xy 188.565028 -403.222714) (xy 188.56457 -403.265938) (xy 188.556182 -403.351979)
			(xy 188.539486 -403.436801) (xy 188.514639 -403.519602) (xy 188.481877 -403.599602) (xy 188.441508 -403.676046)
			(xy 188.393913 -403.748214) (xy 188.339541 -403.815423) (xy 188.278905 -403.87704) (xy 188.212577 -403.932484)
			(xy 188.17717 -403.957282) (xy 188.169401 -403.962991) (xy 188.158572 -403.978928) (xy 188.15443 -403.997746)
			(xy 188.15558 -404.00732) (xy 188.172598 -404.112984) (xy 188.191902 -404.134828) (xy 188.20638 -404.138892)
			(xy 188.235359 -404.147534) (xy 188.292177 -404.168255) (xy 188.319918 -404.180294) (xy 188.32986 -404.1841)
			(xy 188.351124 -404.1841) (xy 188.361066 -404.180294) (xy 188.403727 -404.162032) (xy 188.492015 -404.133439)
			(xy 188.582798 -404.114182) (xy 188.675091 -404.104469) (xy 188.721492 -404.10384) (xy 188.767894 -404.104473)
			(xy 188.860191 -404.114162) (xy 188.950976 -404.133414) (xy 189.039262 -404.162019) (xy 189.081918 -404.180294)
			(xy 189.09186 -404.1841) (xy 189.113124 -404.1841) (xy 189.123066 -404.180294) (xy 189.165727 -404.162032)
			(xy 189.254015 -404.133439) (xy 189.344798 -404.114182) (xy 189.437091 -404.104469) (xy 189.483492 -404.10384)
			(xy 189.524604 -404.10426) (xy 189.606477 -404.111848) (xy 189.6873 -404.126959) (xy 189.766384 -404.149465)
			(xy 189.843053 -404.179173) (xy 189.916654 -404.21583) (xy 189.986557 -404.259123) (xy 190.052166 -404.308683)
			(xy 190.112922 -404.364086) (xy 190.168305 -404.42486) (xy 190.217843 -404.490486) (xy 190.261113 -404.560403)
			(xy 190.297746 -404.634016) (xy 190.327429 -404.710695) (xy 190.349908 -404.789786) (xy 190.364993 -404.870614)
			(xy 190.372553 -404.95249) (xy 190.373 -404.993602) (xy 190.372419 -405.039998) (xy 190.362773 -405.132286)
			(xy 190.343577 -405.22307) (xy 190.315038 -405.311363) (xy 190.2968 -405.354028) (xy 190.292994 -405.36397)
			(xy 190.292995 -405.385234) (xy 190.2968 -405.395176) (xy 190.315045 -405.437838) (xy 190.343589 -405.52613)
			(xy 190.362782 -405.616916) (xy 190.372415 -405.709206) (xy 190.373 -405.755602) (xy 190.372419 -405.801998)
			(xy 190.362773 -405.894286) (xy 190.343577 -405.98507) (xy 190.315038 -406.073363) (xy 190.2968 -406.116028)
			(xy 190.292994 -406.12597) (xy 190.292995 -406.147234) (xy 190.2968 -406.157176) (xy 190.315045 -406.199838)
			(xy 190.343589 -406.28813) (xy 190.362782 -406.378916) (xy 190.372415 -406.471206) (xy 190.373 -406.517602)
			(xy 190.37258 -406.55737) (xy 190.365551 -406.636594) (xy 190.351469 -406.714872) (xy 190.330446 -406.791578)
			(xy 190.302651 -406.866098) (xy 190.285878 -406.902158) (xy 190.281544 -406.912659) (xy 190.281545 -406.935345)
			(xy 190.285878 -406.945846) (xy 190.302637 -406.981911) (xy 190.330411 -407.056437) (xy 190.351429 -407.133142)
			(xy 190.365522 -407.211416) (xy 190.372579 -407.290635) (xy 190.373 -407.330402) (xy 190.372419 -407.376798)
			(xy 190.362773 -407.469086) (xy 190.343577 -407.55987) (xy 190.315038 -407.648163) (xy 190.2968 -407.690828)
			(xy 190.292994 -407.70077) (xy 190.292995 -407.722034) (xy 190.2968 -407.731976) (xy 190.315022 -407.774579)
			(xy 190.34354 -407.862746) (xy 190.362733 -407.953402) (xy 190.372392 -408.045562) (xy 190.372573 -408.059382)
			(xy 196.354192 -408.059382) (xy 196.354769 -408.012986) (xy 196.364415 -407.920698) (xy 196.383613 -407.829914)
			(xy 196.412153 -407.741621) (xy 196.430392 -407.698956) (xy 196.434208 -407.689017) (xy 196.434201 -407.66775)
			(xy 196.430392 -407.657808) (xy 196.412141 -407.615148) (xy 196.383599 -407.526855) (xy 196.364407 -407.436069)
			(xy 196.354776 -407.343778) (xy 196.354192 -407.297382) (xy 196.354769 -407.250986) (xy 196.364415 -407.158698)
			(xy 196.383613 -407.067914) (xy 196.412153 -406.979621) (xy 196.430392 -406.936956) (xy 196.434208 -406.927017)
			(xy 196.434201 -406.90575) (xy 196.430392 -406.895808) (xy 196.412141 -406.853148) (xy 196.383599 -406.764855)
			(xy 196.364407 -406.674069) (xy 196.354776 -406.581778) (xy 196.354192 -406.535382) (xy 196.354769 -406.488986)
			(xy 196.364415 -406.396698) (xy 196.383613 -406.305914) (xy 196.412153 -406.217621) (xy 196.430392 -406.174956)
			(xy 196.434208 -406.165017) (xy 196.434201 -406.14375) (xy 196.430392 -406.133808) (xy 196.412141 -406.091148)
			(xy 196.383599 -406.002855) (xy 196.364407 -405.912069) (xy 196.354776 -405.819778) (xy 196.354192 -405.773382)
			(xy 196.354769 -405.726986) (xy 196.364415 -405.634698) (xy 196.383613 -405.543914) (xy 196.412153 -405.455621)
			(xy 196.430392 -405.412956) (xy 196.434208 -405.403017) (xy 196.434201 -405.38175) (xy 196.430392 -405.371808)
			(xy 196.412164 -405.329208) (xy 196.383648 -405.241039) (xy 196.364457 -405.150383) (xy 196.354799 -405.058222)
			(xy 196.354192 -405.01189) (xy 196.354192 -405.011382) (xy 196.354695 -404.970276) (xy 196.362281 -404.888416)
			(xy 196.377385 -404.807604) (xy 196.39988 -404.72853) (xy 196.429573 -404.651868) (xy 196.466212 -404.578272)
			(xy 196.509483 -404.50837) (xy 196.559018 -404.442758) (xy 196.614395 -404.381994) (xy 196.67514 -404.326599)
			(xy 196.740737 -404.277043) (xy 196.810626 -404.233749) (xy 196.88421 -404.197087) (xy 196.960862 -404.16737)
			(xy 197.039929 -404.14485) (xy 197.120736 -404.12972) (xy 197.202594 -404.122108) (xy 197.2437 -404.12162)
			(xy 197.290102 -404.122252) (xy 197.382399 -404.131941) (xy 197.473184 -404.151193) (xy 197.56147 -404.179799)
			(xy 197.604126 -404.198074) (xy 197.614068 -404.20188) (xy 197.635332 -404.20188) (xy 197.645274 -404.198074)
			(xy 197.673976 -404.185882) (xy 197.682795 -404.181969) (xy 197.696833 -404.168752) (xy 197.704997 -404.151285)
			(xy 197.70598 -404.141686) (xy 197.711314 -404.049992) (xy 197.711428 -404.040421) (xy 197.705477 -404.022248)
			(xy 197.693313 -404.007492) (xy 197.685152 -404.002494) (xy 197.647554 -403.981253) (xy 197.576288 -403.932477)
			(xy 197.510083 -403.877025) (xy 197.449561 -403.81542) (xy 197.395292 -403.748241) (xy 197.347788 -403.67612)
			(xy 197.307493 -403.599737) (xy 197.274789 -403.519809) (xy 197.249982 -403.437088) (xy 197.233306 -403.352354)
			(xy 197.224918 -403.266402) (xy 197.224396 -403.223222) (xy 197.224864 -403.181887) (xy 197.232535 -403.099572)
			(xy 197.247812 -403.018325) (xy 197.270564 -402.938847) (xy 197.300593 -402.861823) (xy 197.337642 -402.787918)
			(xy 197.38139 -402.717771) (xy 197.431459 -402.651987) (xy 197.459092 -402.621242) (xy 197.465153 -402.613982)
			(xy 197.472063 -402.596396) (xy 197.472554 -402.586952) (xy 197.472554 -402.556472) (xy 197.472185 -402.547004)
			(xy 197.465251 -402.529384) (xy 197.459092 -402.522182) (xy 197.431443 -402.491454) (xy 197.3814 -402.425653)
			(xy 197.337673 -402.355495) (xy 197.300638 -402.281587) (xy 197.270614 -402.204563) (xy 197.24786 -402.125088)
			(xy 197.232571 -402.043846) (xy 197.22488 -401.961536) (xy 197.224396 -401.920202) (xy 197.224852 -401.878866)
			(xy 197.232524 -401.796552) (xy 197.247803 -401.715304) (xy 197.270556 -401.635826) (xy 197.300588 -401.558802)
			(xy 197.337638 -401.484897) (xy 197.381388 -401.414751) (xy 197.431459 -401.348967) (xy 197.459092 -401.318222)
			(xy 197.465161 -401.310968) (xy 197.472066 -401.293378) (xy 197.472554 -401.283932) (xy 197.472554 -401.253452)
			(xy 197.472146 -401.243989) (xy 197.465239 -401.226367) (xy 197.459092 -401.219162) (xy 197.431482 -401.1884)
			(xy 197.381436 -401.122604) (xy 197.337705 -401.052453) (xy 197.300666 -400.978549) (xy 197.270637 -400.90153)
			(xy 197.247877 -400.82206) (xy 197.232582 -400.740821) (xy 197.224883 -400.658515) (xy 197.224396 -400.617182)
			(xy 197.224896 -400.576069) (xy 197.232484 -400.494193) (xy 197.247594 -400.413367) (xy 197.270097 -400.334279)
			(xy 197.299801 -400.257605) (xy 197.336453 -400.183999) (xy 197.379739 -400.114089) (xy 197.429291 -400.04847)
			(xy 197.484686 -399.987703) (xy 197.545451 -399.932307) (xy 197.611069 -399.882753) (xy 197.680978 -399.839464)
			(xy 197.754583 -399.802811) (xy 197.831256 -399.773105) (xy 197.910343 -399.7506) (xy 197.991169 -399.735487)
			(xy 198.073045 -399.727897) (xy 198.114158 -399.72742) (xy 198.158662 -399.727949) (xy 198.247226 -399.736844)
			(xy 198.334458 -399.754538) (xy 198.419487 -399.780856) (xy 198.501463 -399.815534) (xy 198.579565 -399.858225)
			(xy 198.653014 -399.908502) (xy 198.721075 -399.965864) (xy 198.75246 -399.997422) (xy 198.759931 -400.004447)
			(xy 198.778793 -400.012446) (xy 198.789036 -400.012916) (xy 198.86168 -400.012916) (xy 198.871931 -400.012475)
			(xy 198.890805 -400.004477) (xy 198.898256 -399.997422) (xy 198.929663 -399.965886) (xy 198.997719 -399.908523)
			(xy 199.071164 -399.858243) (xy 199.149263 -399.81555) (xy 199.231236 -399.780871) (xy 199.316263 -399.754552)
			(xy 199.403493 -399.736858) (xy 199.492055 -399.727964) (xy 199.536558 -399.72742) (xy 199.580049 -399.727926)
			(xy 199.666612 -399.736439) (xy 199.751932 -399.75336) (xy 199.835193 -399.778526) (xy 199.915601 -399.811696)
			(xy 199.992388 -399.852556) (xy 200.064821 -399.900714) (xy 200.132209 -399.95571) (xy 200.16343 -399.985992)
			(xy 200.163684 -399.986246) (xy 200.171078 -399.992808) (xy 200.189369 -400.000258) (xy 200.199244 -400.000724)
			(xy 200.270872 -400.000724) (xy 200.280751 -400.000273) (xy 200.29905 -399.992827) (xy 200.306432 -399.986246)
			(xy 200.306686 -399.985992) (xy 200.337904 -399.955708) (xy 200.405295 -399.900719) (xy 200.47773 -399.852567)
			(xy 200.554518 -399.811713) (xy 200.634927 -399.778547) (xy 200.718187 -399.753386) (xy 200.803506 -399.736469)
			(xy 200.890068 -399.727958) (xy 200.933558 -399.72742) (xy 200.974672 -399.727938) (xy 201.056549 -399.735522)
			(xy 201.137376 -399.750627) (xy 201.216466 -399.773127) (xy 201.293142 -399.802827) (xy 201.36675 -399.839476)
			(xy 201.436663 -399.882761) (xy 201.502283 -399.932312) (xy 201.563052 -399.987706) (xy 201.61845 -400.04847)
			(xy 201.668005 -400.114088) (xy 201.711294 -400.183998) (xy 201.747948 -400.257603) (xy 201.777654 -400.334277)
			(xy 201.800159 -400.413365) (xy 201.81527 -400.494192) (xy 201.822859 -400.576068) (xy 201.82332 -400.617182)
			(xy 201.82285 -400.658517) (xy 201.815179 -400.740831) (xy 201.799902 -400.822078) (xy 201.777151 -400.901557)
			(xy 201.747121 -400.978581) (xy 201.710073 -401.052485) (xy 201.666325 -401.122632) (xy 201.616256 -401.188416)
			(xy 201.588624 -401.219162) (xy 201.582551 -401.226413) (xy 201.575651 -401.244006) (xy 201.575162 -401.253452)
			(xy 201.575162 -401.283932) (xy 201.575549 -401.293397) (xy 201.582473 -401.311017) (xy 201.588624 -401.318222)
			(xy 201.61626 -401.348962) (xy 201.666306 -401.41476) (xy 201.710036 -401.484914) (xy 201.747073 -401.558821)
			(xy 201.777099 -401.635843) (xy 201.799855 -401.715317) (xy 201.815145 -401.796559) (xy 201.822837 -401.878868)
			(xy 201.82332 -401.920202) (xy 201.822863 -401.961538) (xy 201.81519 -402.043852) (xy 201.799911 -402.125099)
			(xy 201.777158 -402.204578) (xy 201.747126 -402.281602) (xy 201.710076 -402.355506) (xy 201.666327 -402.425653)
			(xy 201.616257 -402.491437) (xy 201.588624 -402.522182) (xy 201.582543 -402.529427) (xy 201.575647 -402.547025)
			(xy 201.575162 -402.556472) (xy 201.575162 -402.586952) (xy 201.575589 -402.596413) (xy 201.582485 -402.614033)
			(xy 201.588624 -402.621242) (xy 201.616222 -402.652015) (xy 201.66627 -402.717808) (xy 201.710004 -402.787957)
			(xy 201.747046 -402.861859) (xy 201.777077 -402.938876) (xy 201.799838 -403.018346) (xy 201.815134 -403.099584)
			(xy 201.822833 -403.18189) (xy 201.82332 -403.223222) (xy 201.822801 -403.266183) (xy 201.814523 -403.351705)
			(xy 201.798036 -403.43603) (xy 201.773494 -403.518372) (xy 201.741125 -403.597963) (xy 201.701232 -403.674062)
			(xy 201.654186 -403.745959) (xy 201.600426 -403.812984) (xy 201.540453 -403.874513) (xy 201.474826 -403.929971)
			(xy 201.404156 -403.978842) (xy 201.366882 -404.000208) (xy 201.35873 -404.005265) (xy 201.346612 -404.020117)
			(xy 201.34076 -404.03837) (xy 201.340974 -404.04796) (xy 201.348086 -404.154386) (xy 201.365358 -404.178008)
			(xy 201.379328 -404.183342) (xy 201.417266 -404.198729) (xy 201.490382 -404.235572) (xy 201.559803 -404.27898)
			(xy 201.62494 -404.328584) (xy 201.685242 -404.383965) (xy 201.740199 -404.444654) (xy 201.789346 -404.510137)
			(xy 201.832266 -404.57986) (xy 201.868597 -404.653232) (xy 201.89803 -404.729633) (xy 201.920317 -404.808416)
			(xy 201.935269 -404.888913) (xy 201.942758 -404.970445) (xy 201.943208 -405.011382) (xy 201.942619 -405.057777)
			(xy 201.932976 -405.150066) (xy 201.913781 -405.240849) (xy 201.885245 -405.329143) (xy 201.867008 -405.371808)
			(xy 201.863213 -405.381753) (xy 201.863206 -405.403014) (xy 201.867008 -405.412956) (xy 201.885247 -405.455621)
			(xy 201.913792 -405.543912) (xy 201.932987 -405.634696) (xy 201.942622 -405.726986) (xy 201.943208 -405.773382)
			(xy 201.942619 -405.819777) (xy 201.932976 -405.912066) (xy 201.913781 -406.002849) (xy 201.885245 -406.091143)
			(xy 201.867008 -406.133808) (xy 201.863213 -406.143753) (xy 201.863206 -406.165014) (xy 201.867008 -406.174956)
			(xy 201.885247 -406.217621) (xy 201.913792 -406.305912) (xy 201.932987 -406.396696) (xy 201.942622 -406.488986)
			(xy 201.943208 -406.535382) (xy 201.942619 -406.581777) (xy 201.932976 -406.674066) (xy 201.913781 -406.764849)
			(xy 201.885245 -406.853143) (xy 201.867008 -406.895808) (xy 201.863213 -406.905753) (xy 201.863206 -406.927014)
			(xy 201.867008 -406.936956) (xy 201.885247 -406.979621) (xy 201.913792 -407.067912) (xy 201.932987 -407.158696)
			(xy 201.942622 -407.250986) (xy 201.943208 -407.297382) (xy 201.942619 -407.343777) (xy 201.932976 -407.436066)
			(xy 201.913781 -407.526849) (xy 201.885245 -407.615143) (xy 201.867008 -407.657808) (xy 201.863213 -407.667753)
			(xy 201.863206 -407.689014) (xy 201.867008 -407.698956) (xy 201.885224 -407.741561) (xy 201.913743 -407.829728)
			(xy 201.932938 -407.920383) (xy 201.942599 -408.012542) (xy 201.943208 -408.058874) (xy 201.943208 -408.059382)
			(xy 201.943201 -408.05989) (xy 206.260192 -408.05989) (xy 206.260192 -408.059382) (xy 206.260717 -408.017997)
			(xy 206.268406 -407.935585) (xy 206.283716 -407.854244) (xy 206.306513 -407.774675) (xy 206.336602 -407.697568)
			(xy 206.373723 -407.623589) (xy 206.417553 -407.553377) (xy 206.467715 -407.487539) (xy 206.523774 -407.426645)
			(xy 206.585247 -407.37122) (xy 206.651602 -407.321743) (xy 206.722265 -407.278644) (xy 206.796625 -407.242293)
			(xy 206.87404 -407.213005) (xy 206.953841 -407.191034) (xy 206.994506 -407.183336) (xy 207.004634 -407.181051)
			(xy 207.021956 -407.169641) (xy 207.033359 -407.152314) (xy 207.035654 -407.142188) (xy 207.043393 -407.101149)
			(xy 207.065607 -407.020638) (xy 207.095268 -406.942562) (xy 207.132115 -406.86761) (xy 207.175825 -406.796441)
			(xy 207.226012 -406.729682) (xy 207.282235 -406.66792) (xy 207.343998 -406.611699) (xy 207.410759 -406.561513)
			(xy 207.481929 -406.517805) (xy 207.556881 -406.48096) (xy 207.634957 -406.4513) (xy 207.715469 -406.429089)
			(xy 207.756506 -406.421336) (xy 207.766634 -406.419051) (xy 207.783956 -406.407641) (xy 207.795359 -406.390314)
			(xy 207.797654 -406.380188) (xy 207.804281 -406.344944) (xy 207.822478 -406.275571) (xy 207.846186 -406.207884)
			(xy 207.860392 -406.174956) (xy 207.864208 -406.165017) (xy 207.864201 -406.14375) (xy 207.860392 -406.133808)
			(xy 207.842141 -406.091148) (xy 207.813599 -406.002855) (xy 207.794407 -405.912069) (xy 207.784776 -405.819778)
			(xy 207.784192 -405.773382) (xy 207.784769 -405.726986) (xy 207.794415 -405.634698) (xy 207.813613 -405.543914)
			(xy 207.842153 -405.455621) (xy 207.860392 -405.412956) (xy 207.864208 -405.403017) (xy 207.864201 -405.38175)
			(xy 207.860392 -405.371808) (xy 207.842164 -405.329208) (xy 207.813648 -405.241039) (xy 207.794457 -405.150383)
			(xy 207.784799 -405.058222) (xy 207.784192 -405.01189) (xy 207.784192 -405.011382) (xy 207.784669 -404.970705)
			(xy 207.792097 -404.889692) (xy 207.80689 -404.809694) (xy 207.828923 -404.731381) (xy 207.858013 -404.655407)
			(xy 207.893918 -404.582405) (xy 207.936336 -404.512985) (xy 207.984914 -404.447728) (xy 208.039247 -404.387177)
			(xy 208.09888 -404.33184) (xy 208.163316 -404.282176) (xy 208.232016 -404.238603) (xy 208.304407 -404.201482)
			(xy 208.341976 -404.185882) (xy 208.350795 -404.181969) (xy 208.364833 -404.168752) (xy 208.372997 -404.151285)
			(xy 208.37398 -404.141686) (xy 208.379314 -404.049992) (xy 208.379428 -404.040421) (xy 208.373477 -404.022248)
			(xy 208.361313 -404.007492) (xy 208.353152 -404.002494) (xy 208.315554 -403.981253) (xy 208.244288 -403.932477)
			(xy 208.178083 -403.877025) (xy 208.117561 -403.81542) (xy 208.063292 -403.748241) (xy 208.015788 -403.67612)
			(xy 207.975493 -403.599737) (xy 207.942789 -403.519809) (xy 207.917982 -403.437088) (xy 207.901306 -403.352354)
			(xy 207.892918 -403.266402) (xy 207.892396 -403.223222) (xy 207.892864 -403.181887) (xy 207.900535 -403.099572)
			(xy 207.915812 -403.018325) (xy 207.938564 -402.938847) (xy 207.968593 -402.861823) (xy 208.005642 -402.787918)
			(xy 208.04939 -402.717771) (xy 208.099459 -402.651987) (xy 208.127092 -402.621242) (xy 208.133153 -402.613982)
			(xy 208.140063 -402.596396) (xy 208.140554 -402.586952) (xy 208.140554 -402.556472) (xy 208.140185 -402.547004)
			(xy 208.133251 -402.529384) (xy 208.127092 -402.522182) (xy 208.099443 -402.491454) (xy 208.0494 -402.425653)
			(xy 208.005673 -402.355495) (xy 207.968638 -402.281587) (xy 207.938614 -402.204563) (xy 207.91586 -402.125088)
			(xy 207.900571 -402.043846) (xy 207.89288 -401.961536) (xy 207.892396 -401.920202) (xy 207.892852 -401.878866)
			(xy 207.900524 -401.796552) (xy 207.915803 -401.715304) (xy 207.938556 -401.635826) (xy 207.968588 -401.558802)
			(xy 208.005638 -401.484897) (xy 208.049388 -401.414751) (xy 208.099459 -401.348967) (xy 208.127092 -401.318222)
			(xy 208.133161 -401.310968) (xy 208.140066 -401.293378) (xy 208.140554 -401.283932) (xy 208.140554 -401.253452)
			(xy 208.140146 -401.243989) (xy 208.133239 -401.226367) (xy 208.127092 -401.219162) (xy 208.099482 -401.1884)
			(xy 208.049436 -401.122604) (xy 208.005705 -401.052453) (xy 207.968666 -400.978549) (xy 207.938637 -400.90153)
			(xy 207.915877 -400.82206) (xy 207.900582 -400.740821) (xy 207.892883 -400.658515) (xy 207.892396 -400.617182)
			(xy 207.892896 -400.576069) (xy 207.900484 -400.494193) (xy 207.915594 -400.413367) (xy 207.938097 -400.334279)
			(xy 207.967801 -400.257605) (xy 208.004453 -400.183999) (xy 208.047739 -400.114089) (xy 208.097291 -400.04847)
			(xy 208.152686 -399.987703) (xy 208.213451 -399.932307) (xy 208.279069 -399.882753) (xy 208.348978 -399.839464)
			(xy 208.422583 -399.802811) (xy 208.499256 -399.773105) (xy 208.578343 -399.7506) (xy 208.659169 -399.735487)
			(xy 208.741045 -399.727897) (xy 208.782158 -399.72742) (xy 208.826662 -399.727949) (xy 208.915226 -399.736844)
			(xy 209.002458 -399.754538) (xy 209.087487 -399.780856) (xy 209.169463 -399.815534) (xy 209.247565 -399.858225)
			(xy 209.321014 -399.908502) (xy 209.389075 -399.965864) (xy 209.42046 -399.997422) (xy 209.427931 -400.004447)
			(xy 209.446793 -400.012446) (xy 209.457036 -400.012916) (xy 209.52968 -400.012916) (xy 209.539931 -400.012475)
			(xy 209.558805 -400.004477) (xy 209.566256 -399.997422) (xy 209.597663 -399.965886) (xy 209.665719 -399.908523)
			(xy 209.739164 -399.858243) (xy 209.817263 -399.81555) (xy 209.899236 -399.780871) (xy 209.984263 -399.754552)
			(xy 210.071493 -399.736858) (xy 210.160055 -399.727964) (xy 210.204558 -399.72742) (xy 210.248049 -399.727926)
			(xy 210.334612 -399.736439) (xy 210.419932 -399.75336) (xy 210.503193 -399.778526) (xy 210.583601 -399.811696)
			(xy 210.660388 -399.852556) (xy 210.732821 -399.900714) (xy 210.800209 -399.95571) (xy 210.83143 -399.985992)
			(xy 210.831684 -399.986246) (xy 210.839078 -399.992808) (xy 210.857369 -400.000258) (xy 210.867244 -400.000724)
			(xy 210.938872 -400.000724) (xy 210.948751 -400.000273) (xy 210.96705 -399.992827) (xy 210.974432 -399.986246)
			(xy 210.974686 -399.985992) (xy 211.005904 -399.955708) (xy 211.073295 -399.900719) (xy 211.14573 -399.852567)
			(xy 211.222518 -399.811713) (xy 211.302927 -399.778547) (xy 211.386187 -399.753386) (xy 211.471506 -399.736469)
			(xy 211.558068 -399.727958) (xy 211.601558 -399.72742) (xy 211.642672 -399.727938) (xy 211.724549 -399.735522)
			(xy 211.805376 -399.750627) (xy 211.884466 -399.773127) (xy 211.961142 -399.802827) (xy 212.03475 -399.839476)
			(xy 212.104663 -399.882761) (xy 212.170283 -399.932312) (xy 212.231052 -399.987706) (xy 212.28645 -400.04847)
			(xy 212.336005 -400.114088) (xy 212.379294 -400.183998) (xy 212.415948 -400.257603) (xy 212.445654 -400.334277)
			(xy 212.468159 -400.413365) (xy 212.48327 -400.494192) (xy 212.490859 -400.576068) (xy 212.49132 -400.617182)
			(xy 212.49085 -400.658517) (xy 212.483179 -400.740831) (xy 212.467902 -400.822078) (xy 212.445151 -400.901557)
			(xy 212.415121 -400.978581) (xy 212.378073 -401.052485) (xy 212.334325 -401.122632) (xy 212.284256 -401.188416)
			(xy 212.256624 -401.219162) (xy 212.250551 -401.226413) (xy 212.243651 -401.244006) (xy 212.243162 -401.253452)
			(xy 212.243162 -401.283932) (xy 212.243549 -401.293397) (xy 212.250473 -401.311017) (xy 212.256624 -401.318222)
			(xy 212.28426 -401.348962) (xy 212.334306 -401.41476) (xy 212.378036 -401.484914) (xy 212.415073 -401.558821)
			(xy 212.445099 -401.635843) (xy 212.467855 -401.715317) (xy 212.483145 -401.796559) (xy 212.490837 -401.878868)
			(xy 212.49132 -401.920202) (xy 212.490863 -401.961538) (xy 212.48319 -402.043852) (xy 212.467911 -402.125099)
			(xy 212.445158 -402.204578) (xy 212.415126 -402.281602) (xy 212.378076 -402.355506) (xy 212.334327 -402.425653)
			(xy 212.284257 -402.491437) (xy 212.256624 -402.522182) (xy 212.250543 -402.529427) (xy 212.243647 -402.547025)
			(xy 212.243162 -402.556472) (xy 212.243162 -402.586952) (xy 212.243589 -402.596413) (xy 212.250485 -402.614033)
			(xy 212.256624 -402.621242) (xy 212.284222 -402.652015) (xy 212.33427 -402.717808) (xy 212.378004 -402.787957)
			(xy 212.415046 -402.861859) (xy 212.445077 -402.938876) (xy 212.467838 -403.018346) (xy 212.483134 -403.099584)
			(xy 212.490833 -403.18189) (xy 212.49132 -403.223222) (xy 212.490801 -403.266183) (xy 212.482523 -403.351705)
			(xy 212.466036 -403.43603) (xy 212.441494 -403.518372) (xy 212.409125 -403.597963) (xy 212.369232 -403.674062)
			(xy 212.322186 -403.745959) (xy 212.268426 -403.812984) (xy 212.208453 -403.874513) (xy 212.142826 -403.929971)
			(xy 212.072156 -403.978842) (xy 212.034882 -404.000208) (xy 212.02673 -404.005265) (xy 212.014612 -404.020117)
			(xy 212.00876 -404.03837) (xy 212.008974 -404.04796) (xy 212.016086 -404.154386) (xy 212.033358 -404.178008)
			(xy 212.047328 -404.183342) (xy 212.085266 -404.198729) (xy 212.158382 -404.235572) (xy 212.227803 -404.27898)
			(xy 212.29294 -404.328584) (xy 212.353242 -404.383965) (xy 212.408199 -404.444654) (xy 212.457346 -404.510137)
			(xy 212.500266 -404.57986) (xy 212.536597 -404.653232) (xy 212.56603 -404.729633) (xy 212.588317 -404.808416)
			(xy 212.603269 -404.888913) (xy 212.610758 -404.970445) (xy 212.611208 -405.011382) (xy 212.610619 -405.057777)
			(xy 212.600976 -405.150066) (xy 212.581781 -405.240849) (xy 212.553245 -405.329143) (xy 212.535008 -405.371808)
			(xy 212.531213 -405.381753) (xy 212.531206 -405.403014) (xy 212.535008 -405.412956) (xy 212.553247 -405.455621)
			(xy 212.581792 -405.543912) (xy 212.600987 -405.634696) (xy 212.610622 -405.726986) (xy 212.611208 -405.773382)
			(xy 212.610619 -405.819777) (xy 212.600976 -405.912066) (xy 212.581781 -406.002849) (xy 212.553245 -406.091143)
			(xy 212.535008 -406.133808) (xy 212.531213 -406.143753) (xy 212.531206 -406.165014) (xy 212.535008 -406.174956)
			(xy 212.549234 -406.207876) (xy 212.572955 -406.275561) (xy 212.591136 -406.34494) (xy 212.597746 -406.380188)
			(xy 212.600055 -406.390309) (xy 212.611454 -406.407631) (xy 212.628772 -406.419037) (xy 212.638894 -406.421336)
			(xy 212.679556 -406.42906) (xy 212.75936 -406.451024) (xy 212.83678 -406.480305) (xy 212.911146 -406.51665)
			(xy 212.981814 -406.559745) (xy 213.048174 -406.609217) (xy 213.109652 -406.66464) (xy 213.165716 -406.725533)
			(xy 213.215883 -406.791369) (xy 213.259718 -406.861581) (xy 213.296841 -406.935561) (xy 213.326933 -407.012669)
			(xy 213.349733 -407.092239) (xy 213.365045 -407.173582) (xy 213.372734 -407.255996) (xy 213.373208 -407.297382)
			(xy 213.373208 -407.29789) (xy 213.372596 -407.344222) (xy 213.362926 -407.436379) (xy 213.343732 -407.527034)
			(xy 213.315222 -407.615202) (xy 213.297008 -407.657808) (xy 213.293213 -407.667753) (xy 213.293206 -407.689014)
			(xy 213.297008 -407.698956) (xy 213.315224 -407.741561) (xy 213.343743 -407.829728) (xy 213.362938 -407.920383)
			(xy 213.372599 -408.012542) (xy 213.373208 -408.058874) (xy 213.373208 -408.059382) (xy 213.373201 -408.05989)
			(xy 216.928192 -408.05989) (xy 216.928192 -408.059382) (xy 216.928717 -408.017997) (xy 216.936406 -407.935585)
			(xy 216.951716 -407.854244) (xy 216.974513 -407.774675) (xy 217.004602 -407.697568) (xy 217.041723 -407.623589)
			(xy 217.085553 -407.553377) (xy 217.135715 -407.487539) (xy 217.191774 -407.426645) (xy 217.253247 -407.37122)
			(xy 217.319602 -407.321743) (xy 217.390265 -407.278644) (xy 217.464625 -407.242293) (xy 217.54204 -407.213005)
			(xy 217.621841 -407.191034) (xy 217.662506 -407.183336) (xy 217.672634 -407.181051) (xy 217.689956 -407.169641)
			(xy 217.701359 -407.152314) (xy 217.703654 -407.142188) (xy 217.711393 -407.101149) (xy 217.733607 -407.020638)
			(xy 217.763268 -406.942562) (xy 217.800115 -406.86761) (xy 217.843825 -406.796441) (xy 217.894012 -406.729682)
			(xy 217.950235 -406.66792) (xy 218.011998 -406.611699) (xy 218.078759 -406.561513) (xy 218.149929 -406.517805)
			(xy 218.224881 -406.48096) (xy 218.302957 -406.4513) (xy 218.383469 -406.429089) (xy 218.424506 -406.421336)
			(xy 218.434634 -406.419051) (xy 218.451956 -406.407641) (xy 218.463359 -406.390314) (xy 218.465654 -406.380188)
			(xy 218.472281 -406.344944) (xy 218.490478 -406.275571) (xy 218.514186 -406.207884) (xy 218.528392 -406.174956)
			(xy 218.532208 -406.165017) (xy 218.532201 -406.14375) (xy 218.528392 -406.133808) (xy 218.510141 -406.091148)
			(xy 218.481599 -406.002855) (xy 218.462407 -405.912069) (xy 218.452776 -405.819778) (xy 218.452192 -405.773382)
			(xy 218.452769 -405.726986) (xy 218.462415 -405.634698) (xy 218.481613 -405.543914) (xy 218.510153 -405.455621)
			(xy 218.528392 -405.412956) (xy 218.532208 -405.403017) (xy 218.532201 -405.38175) (xy 218.528392 -405.371808)
			(xy 218.510164 -405.329208) (xy 218.481648 -405.241039) (xy 218.462457 -405.150383) (xy 218.452799 -405.058222)
			(xy 218.452192 -405.01189) (xy 218.452192 -405.011382) (xy 218.452669 -404.970705) (xy 218.460097 -404.889692)
			(xy 218.47489 -404.809694) (xy 218.496923 -404.731381) (xy 218.526013 -404.655407) (xy 218.561918 -404.582405)
			(xy 218.604336 -404.512985) (xy 218.652914 -404.447728) (xy 218.707247 -404.387177) (xy 218.76688 -404.33184)
			(xy 218.831316 -404.282176) (xy 218.900016 -404.238603) (xy 218.972407 -404.201482) (xy 219.009976 -404.185882)
			(xy 219.018795 -404.181969) (xy 219.032833 -404.168752) (xy 219.040997 -404.151285) (xy 219.04198 -404.141686)
			(xy 219.047314 -404.049992) (xy 219.047428 -404.040421) (xy 219.041477 -404.022248) (xy 219.029313 -404.007492)
			(xy 219.021152 -404.002494) (xy 218.983554 -403.981253) (xy 218.912288 -403.932477) (xy 218.846083 -403.877025)
			(xy 218.785561 -403.81542) (xy 218.731292 -403.748241) (xy 218.683788 -403.67612) (xy 218.643493 -403.599737)
			(xy 218.610789 -403.519809) (xy 218.585982 -403.437088) (xy 218.569306 -403.352354) (xy 218.560918 -403.266402)
			(xy 218.560396 -403.223222) (xy 218.560864 -403.181887) (xy 218.568535 -403.099572) (xy 218.583812 -403.018325)
			(xy 218.606564 -402.938847) (xy 218.636593 -402.861823) (xy 218.673642 -402.787918) (xy 218.71739 -402.717771)
			(xy 218.767459 -402.651987) (xy 218.795092 -402.621242) (xy 218.801153 -402.613982) (xy 218.808063 -402.596396)
			(xy 218.808554 -402.586952) (xy 218.808554 -402.556472) (xy 218.808185 -402.547004) (xy 218.801251 -402.529384)
			(xy 218.795092 -402.522182) (xy 218.767443 -402.491454) (xy 218.7174 -402.425653) (xy 218.673673 -402.355495)
			(xy 218.636638 -402.281587) (xy 218.606614 -402.204563) (xy 218.58386 -402.125088) (xy 218.568571 -402.043846)
			(xy 218.56088 -401.961536) (xy 218.560396 -401.920202) (xy 218.560852 -401.878866) (xy 218.568524 -401.796552)
			(xy 218.583803 -401.715304) (xy 218.606556 -401.635826) (xy 218.636588 -401.558802) (xy 218.673638 -401.484897)
			(xy 218.717388 -401.414751) (xy 218.767459 -401.348967) (xy 218.795092 -401.318222) (xy 218.801161 -401.310968)
			(xy 218.808066 -401.293378) (xy 218.808554 -401.283932) (xy 218.808554 -401.253452) (xy 218.808146 -401.243989)
			(xy 218.801239 -401.226367) (xy 218.795092 -401.219162) (xy 218.767482 -401.1884) (xy 218.717436 -401.122604)
			(xy 218.673705 -401.052453) (xy 218.636666 -400.978549) (xy 218.606637 -400.90153) (xy 218.583877 -400.82206)
			(xy 218.568582 -400.740821) (xy 218.560883 -400.658515) (xy 218.560396 -400.617182) (xy 218.560896 -400.576069)
			(xy 218.568484 -400.494193) (xy 218.583594 -400.413367) (xy 218.606097 -400.334279) (xy 218.635801 -400.257605)
			(xy 218.672453 -400.183999) (xy 218.715739 -400.114089) (xy 218.765291 -400.04847) (xy 218.820686 -399.987703)
			(xy 218.881451 -399.932307) (xy 218.947069 -399.882753) (xy 219.016978 -399.839464) (xy 219.090583 -399.802811)
			(xy 219.167256 -399.773105) (xy 219.246343 -399.7506) (xy 219.327169 -399.735487) (xy 219.409045 -399.727897)
			(xy 219.450158 -399.72742) (xy 219.494662 -399.727949) (xy 219.583226 -399.736844) (xy 219.670458 -399.754538)
			(xy 219.755487 -399.780856) (xy 219.837463 -399.815534) (xy 219.915565 -399.858225) (xy 219.989014 -399.908502)
			(xy 220.057075 -399.965864) (xy 220.08846 -399.997422) (xy 220.095931 -400.004447) (xy 220.114793 -400.012446)
			(xy 220.125036 -400.012916) (xy 220.19768 -400.012916) (xy 220.207931 -400.012475) (xy 220.226805 -400.004477)
			(xy 220.234256 -399.997422) (xy 220.265663 -399.965886) (xy 220.333719 -399.908523) (xy 220.407164 -399.858243)
			(xy 220.485263 -399.81555) (xy 220.567236 -399.780871) (xy 220.652263 -399.754552) (xy 220.739493 -399.736858)
			(xy 220.828055 -399.727964) (xy 220.872558 -399.72742) (xy 220.916049 -399.727926) (xy 221.002612 -399.736439)
			(xy 221.087932 -399.75336) (xy 221.171193 -399.778526) (xy 221.251601 -399.811696) (xy 221.328388 -399.852556)
			(xy 221.400821 -399.900714) (xy 221.468209 -399.95571) (xy 221.49943 -399.985992) (xy 221.499684 -399.986246)
			(xy 221.507078 -399.992808) (xy 221.525369 -400.000258) (xy 221.535244 -400.000724) (xy 221.606872 -400.000724)
			(xy 221.616751 -400.000273) (xy 221.63505 -399.992827) (xy 221.642432 -399.986246) (xy 221.642686 -399.985992)
			(xy 221.673904 -399.955708) (xy 221.741295 -399.900719) (xy 221.81373 -399.852567) (xy 221.890518 -399.811713)
			(xy 221.970927 -399.778547) (xy 222.054187 -399.753386) (xy 222.139506 -399.736469) (xy 222.226068 -399.727958)
			(xy 222.269558 -399.72742) (xy 222.310672 -399.727938) (xy 222.392549 -399.735522) (xy 222.473376 -399.750627)
			(xy 222.552466 -399.773127) (xy 222.629142 -399.802827) (xy 222.70275 -399.839476) (xy 222.772663 -399.882761)
			(xy 222.838283 -399.932312) (xy 222.899052 -399.987706) (xy 222.95445 -400.04847) (xy 223.004005 -400.114088)
			(xy 223.047294 -400.183998) (xy 223.083948 -400.257603) (xy 223.113654 -400.334277) (xy 223.136159 -400.413365)
			(xy 223.15127 -400.494192) (xy 223.158859 -400.576068) (xy 223.15932 -400.617182) (xy 223.15885 -400.658517)
			(xy 223.151179 -400.740831) (xy 223.135902 -400.822078) (xy 223.113151 -400.901557) (xy 223.083121 -400.978581)
			(xy 223.046073 -401.052485) (xy 223.002325 -401.122632) (xy 222.952256 -401.188416) (xy 222.924624 -401.219162)
			(xy 222.918551 -401.226413) (xy 222.911651 -401.244006) (xy 222.911162 -401.253452) (xy 222.911162 -401.283932)
			(xy 222.911549 -401.293397) (xy 222.918473 -401.311017) (xy 222.924624 -401.318222) (xy 222.95226 -401.348962)
			(xy 223.002306 -401.41476) (xy 223.046036 -401.484914) (xy 223.083073 -401.558821) (xy 223.113099 -401.635843)
			(xy 223.135855 -401.715317) (xy 223.151145 -401.796559) (xy 223.158837 -401.878868) (xy 223.15932 -401.920202)
			(xy 223.158863 -401.961538) (xy 223.15119 -402.043852) (xy 223.135911 -402.125099) (xy 223.113158 -402.204578)
			(xy 223.083126 -402.281602) (xy 223.046076 -402.355506) (xy 223.002327 -402.425653) (xy 222.952257 -402.491437)
			(xy 222.924624 -402.522182) (xy 222.918543 -402.529427) (xy 222.911647 -402.547025) (xy 222.911162 -402.556472)
			(xy 222.911162 -402.586952) (xy 222.911589 -402.596413) (xy 222.918485 -402.614033) (xy 222.924624 -402.621242)
			(xy 222.952222 -402.652015) (xy 223.00227 -402.717808) (xy 223.046004 -402.787957) (xy 223.083046 -402.861859)
			(xy 223.113077 -402.938876) (xy 223.135838 -403.018346) (xy 223.151134 -403.099584) (xy 223.158833 -403.18189)
			(xy 223.15932 -403.223222) (xy 223.158801 -403.266183) (xy 223.150523 -403.351705) (xy 223.134036 -403.43603)
			(xy 223.109494 -403.518372) (xy 223.077125 -403.597963) (xy 223.037232 -403.674062) (xy 222.990186 -403.745959)
			(xy 222.936426 -403.812984) (xy 222.876453 -403.874513) (xy 222.810826 -403.929971) (xy 222.740156 -403.978842)
			(xy 222.702882 -404.000208) (xy 222.69473 -404.005265) (xy 222.682612 -404.020117) (xy 222.67676 -404.03837)
			(xy 222.676974 -404.04796) (xy 222.684086 -404.154386) (xy 222.701358 -404.178008) (xy 222.715328 -404.183342)
			(xy 222.753266 -404.198729) (xy 222.826382 -404.235572) (xy 222.895803 -404.27898) (xy 222.96094 -404.328584)
			(xy 223.021242 -404.383965) (xy 223.076199 -404.444654) (xy 223.125346 -404.510137) (xy 223.168266 -404.57986)
			(xy 223.204597 -404.653232) (xy 223.23403 -404.729633) (xy 223.256317 -404.808416) (xy 223.271269 -404.888913)
			(xy 223.278758 -404.970445) (xy 223.279208 -405.011382) (xy 223.278619 -405.057777) (xy 223.268976 -405.150066)
			(xy 223.249781 -405.240849) (xy 223.221245 -405.329143) (xy 223.203008 -405.371808) (xy 223.199213 -405.381753)
			(xy 223.199206 -405.403014) (xy 223.203008 -405.412956) (xy 223.221247 -405.455621) (xy 223.249792 -405.543912)
			(xy 223.268987 -405.634696) (xy 223.278622 -405.726986) (xy 223.279208 -405.773382) (xy 223.278619 -405.819777)
			(xy 223.268976 -405.912066) (xy 223.249781 -406.002849) (xy 223.221245 -406.091143) (xy 223.203008 -406.133808)
			(xy 223.199213 -406.143753) (xy 223.199206 -406.165014) (xy 223.203008 -406.174956) (xy 223.217234 -406.207876)
			(xy 223.240955 -406.275561) (xy 223.259136 -406.34494) (xy 223.265746 -406.380188) (xy 223.268055 -406.390309)
			(xy 223.279454 -406.407631) (xy 223.296772 -406.419037) (xy 223.306894 -406.421336) (xy 223.347556 -406.42906)
			(xy 223.42736 -406.451024) (xy 223.50478 -406.480305) (xy 223.579146 -406.51665) (xy 223.649814 -406.559745)
			(xy 223.716174 -406.609217) (xy 223.777652 -406.66464) (xy 223.833716 -406.725533) (xy 223.883883 -406.791369)
			(xy 223.927718 -406.861581) (xy 223.964841 -406.935561) (xy 223.994933 -407.012669) (xy 224.017733 -407.092239)
			(xy 224.033045 -407.173582) (xy 224.040734 -407.255996) (xy 224.041208 -407.297382) (xy 224.041208 -407.29789)
			(xy 224.040596 -407.344222) (xy 224.030926 -407.436379) (xy 224.011732 -407.527034) (xy 223.983222 -407.615202)
			(xy 223.965008 -407.657808) (xy 223.961213 -407.667753) (xy 223.961206 -407.689014) (xy 223.965008 -407.698956)
			(xy 223.983224 -407.741561) (xy 224.011743 -407.829728) (xy 224.030938 -407.920383) (xy 224.040599 -408.012542)
			(xy 224.041208 -408.058874) (xy 224.041208 -408.059382) (xy 224.041201 -408.05989) (xy 227.596192 -408.05989)
			(xy 227.596192 -408.059382) (xy 227.596717 -408.017997) (xy 227.604406 -407.935585) (xy 227.619716 -407.854244)
			(xy 227.642513 -407.774675) (xy 227.672602 -407.697568) (xy 227.709723 -407.623589) (xy 227.753553 -407.553377)
			(xy 227.803715 -407.487539) (xy 227.859774 -407.426645) (xy 227.921247 -407.37122) (xy 227.987602 -407.321743)
			(xy 228.058265 -407.278644) (xy 228.132625 -407.242293) (xy 228.21004 -407.213005) (xy 228.289841 -407.191034)
			(xy 228.330506 -407.183336) (xy 228.340634 -407.181051) (xy 228.357956 -407.169641) (xy 228.369359 -407.152314)
			(xy 228.371654 -407.142188) (xy 228.379393 -407.101149) (xy 228.401607 -407.020638) (xy 228.431268 -406.942562)
			(xy 228.468115 -406.86761) (xy 228.511825 -406.796441) (xy 228.562012 -406.729682) (xy 228.618235 -406.66792)
			(xy 228.679998 -406.611699) (xy 228.746759 -406.561513) (xy 228.817929 -406.517805) (xy 228.892881 -406.48096)
			(xy 228.970957 -406.4513) (xy 229.051469 -406.429089) (xy 229.092506 -406.421336) (xy 229.102634 -406.419051)
			(xy 229.119956 -406.407641) (xy 229.131359 -406.390314) (xy 229.133654 -406.380188) (xy 229.140281 -406.344944)
			(xy 229.158478 -406.275571) (xy 229.182186 -406.207884) (xy 229.196392 -406.174956) (xy 229.200208 -406.165017)
			(xy 229.200201 -406.14375) (xy 229.196392 -406.133808) (xy 229.178141 -406.091148) (xy 229.149599 -406.002855)
			(xy 229.130407 -405.912069) (xy 229.120776 -405.819778) (xy 229.120192 -405.773382) (xy 229.120769 -405.726986)
			(xy 229.130415 -405.634698) (xy 229.149613 -405.543914) (xy 229.178153 -405.455621) (xy 229.196392 -405.412956)
			(xy 229.200208 -405.403017) (xy 229.200201 -405.38175) (xy 229.196392 -405.371808) (xy 229.178164 -405.329208)
			(xy 229.149648 -405.241039) (xy 229.130457 -405.150383) (xy 229.120799 -405.058222) (xy 229.120192 -405.01189)
			(xy 229.120192 -405.011382) (xy 229.120669 -404.970705) (xy 229.128097 -404.889692) (xy 229.14289 -404.809694)
			(xy 229.164923 -404.731381) (xy 229.194013 -404.655407) (xy 229.229918 -404.582405) (xy 229.272336 -404.512985)
			(xy 229.320914 -404.447728) (xy 229.375247 -404.387177) (xy 229.43488 -404.33184) (xy 229.499316 -404.282176)
			(xy 229.568016 -404.238603) (xy 229.640407 -404.201482) (xy 229.677976 -404.185882) (xy 229.686795 -404.181969)
			(xy 229.700833 -404.168752) (xy 229.708997 -404.151285) (xy 229.70998 -404.141686) (xy 229.715314 -404.049992)
			(xy 229.715428 -404.040421) (xy 229.709477 -404.022248) (xy 229.697313 -404.007492) (xy 229.689152 -404.002494)
			(xy 229.651554 -403.981253) (xy 229.580288 -403.932477) (xy 229.514083 -403.877025) (xy 229.453561 -403.81542)
			(xy 229.399292 -403.748241) (xy 229.351788 -403.67612) (xy 229.311493 -403.599737) (xy 229.278789 -403.519809)
			(xy 229.253982 -403.437088) (xy 229.237306 -403.352354) (xy 229.228918 -403.266402) (xy 229.228396 -403.223222)
			(xy 229.228864 -403.181887) (xy 229.236535 -403.099572) (xy 229.251812 -403.018325) (xy 229.274564 -402.938847)
			(xy 229.304593 -402.861823) (xy 229.341642 -402.787918) (xy 229.38539 -402.717771) (xy 229.435459 -402.651987)
			(xy 229.463092 -402.621242) (xy 229.469153 -402.613982) (xy 229.476063 -402.596396) (xy 229.476554 -402.586952)
			(xy 229.476554 -402.556472) (xy 229.476185 -402.547004) (xy 229.469251 -402.529384) (xy 229.463092 -402.522182)
			(xy 229.435443 -402.491454) (xy 229.3854 -402.425653) (xy 229.341673 -402.355495) (xy 229.304638 -402.281587)
			(xy 229.274614 -402.204563) (xy 229.25186 -402.125088) (xy 229.236571 -402.043846) (xy 229.22888 -401.961536)
			(xy 229.228396 -401.920202) (xy 229.228852 -401.878866) (xy 229.236524 -401.796552) (xy 229.251803 -401.715304)
			(xy 229.274556 -401.635826) (xy 229.304588 -401.558802) (xy 229.341638 -401.484897) (xy 229.385388 -401.414751)
			(xy 229.435459 -401.348967) (xy 229.463092 -401.318222) (xy 229.469161 -401.310968) (xy 229.476066 -401.293378)
			(xy 229.476554 -401.283932) (xy 229.476554 -401.253452) (xy 229.476146 -401.243989) (xy 229.469239 -401.226367)
			(xy 229.463092 -401.219162) (xy 229.435482 -401.1884) (xy 229.385436 -401.122604) (xy 229.341705 -401.052453)
			(xy 229.304666 -400.978549) (xy 229.274637 -400.90153) (xy 229.251877 -400.82206) (xy 229.236582 -400.740821)
			(xy 229.228883 -400.658515) (xy 229.228396 -400.617182) (xy 229.228896 -400.576069) (xy 229.236484 -400.494193)
			(xy 229.251594 -400.413367) (xy 229.274097 -400.334279) (xy 229.303801 -400.257605) (xy 229.340453 -400.183999)
			(xy 229.383739 -400.114089) (xy 229.433291 -400.04847) (xy 229.488686 -399.987703) (xy 229.549451 -399.932307)
			(xy 229.615069 -399.882753) (xy 229.684978 -399.839464) (xy 229.758583 -399.802811) (xy 229.835256 -399.773105)
			(xy 229.914343 -399.7506) (xy 229.995169 -399.735487) (xy 230.077045 -399.727897) (xy 230.118158 -399.72742)
			(xy 230.162662 -399.727949) (xy 230.251226 -399.736844) (xy 230.338458 -399.754538) (xy 230.423487 -399.780856)
			(xy 230.505463 -399.815534) (xy 230.583565 -399.858225) (xy 230.657014 -399.908502) (xy 230.725075 -399.965864)
			(xy 230.75646 -399.997422) (xy 230.763931 -400.004447) (xy 230.782793 -400.012446) (xy 230.793036 -400.012916)
			(xy 230.86568 -400.012916) (xy 230.875931 -400.012475) (xy 230.894805 -400.004477) (xy 230.902256 -399.997422)
			(xy 230.933663 -399.965886) (xy 231.001719 -399.908523) (xy 231.075164 -399.858243) (xy 231.153263 -399.81555)
			(xy 231.235236 -399.780871) (xy 231.320263 -399.754552) (xy 231.407493 -399.736858) (xy 231.496055 -399.727964)
			(xy 231.540558 -399.72742) (xy 231.584049 -399.727926) (xy 231.670612 -399.736439) (xy 231.755932 -399.75336)
			(xy 231.839193 -399.778526) (xy 231.919601 -399.811696) (xy 231.996388 -399.852556) (xy 232.068821 -399.900714)
			(xy 232.136209 -399.95571) (xy 232.16743 -399.985992) (xy 232.167684 -399.986246) (xy 232.175078 -399.992808)
			(xy 232.193369 -400.000258) (xy 232.203244 -400.000724) (xy 232.274872 -400.000724) (xy 232.284751 -400.000273)
			(xy 232.30305 -399.992827) (xy 232.310432 -399.986246) (xy 232.310686 -399.985992) (xy 232.341904 -399.955708)
			(xy 232.409295 -399.900719) (xy 232.48173 -399.852567) (xy 232.558518 -399.811713) (xy 232.638927 -399.778547)
			(xy 232.722187 -399.753386) (xy 232.807506 -399.736469) (xy 232.894068 -399.727958) (xy 232.937558 -399.72742)
			(xy 232.978672 -399.727938) (xy 233.060549 -399.735522) (xy 233.141376 -399.750627) (xy 233.220466 -399.773127)
			(xy 233.297142 -399.802827) (xy 233.37075 -399.839476) (xy 233.440663 -399.882761) (xy 233.506283 -399.932312)
			(xy 233.567052 -399.987706) (xy 233.62245 -400.04847) (xy 233.672005 -400.114088) (xy 233.715294 -400.183998)
			(xy 233.751948 -400.257603) (xy 233.781654 -400.334277) (xy 233.804159 -400.413365) (xy 233.81927 -400.494192)
			(xy 233.826859 -400.576068) (xy 233.82732 -400.617182) (xy 233.82685 -400.658517) (xy 233.819179 -400.740831)
			(xy 233.803902 -400.822078) (xy 233.781151 -400.901557) (xy 233.751121 -400.978581) (xy 233.714073 -401.052485)
			(xy 233.670325 -401.122632) (xy 233.620256 -401.188416) (xy 233.592624 -401.219162) (xy 233.586551 -401.226413)
			(xy 233.579651 -401.244006) (xy 233.579162 -401.253452) (xy 233.579162 -401.283932) (xy 233.579549 -401.293397)
			(xy 233.586473 -401.311017) (xy 233.592624 -401.318222) (xy 233.62026 -401.348962) (xy 233.670306 -401.41476)
			(xy 233.714036 -401.484914) (xy 233.751073 -401.558821) (xy 233.781099 -401.635843) (xy 233.803855 -401.715317)
			(xy 233.819145 -401.796559) (xy 233.826837 -401.878868) (xy 233.82732 -401.920202) (xy 233.826863 -401.961538)
			(xy 233.81919 -402.043852) (xy 233.803911 -402.125099) (xy 233.781158 -402.204578) (xy 233.751126 -402.281602)
			(xy 233.714076 -402.355506) (xy 233.670327 -402.425653) (xy 233.620257 -402.491437) (xy 233.592624 -402.522182)
			(xy 233.586543 -402.529427) (xy 233.579647 -402.547025) (xy 233.579162 -402.556472) (xy 233.579162 -402.586952)
			(xy 233.579589 -402.596413) (xy 233.586485 -402.614033) (xy 233.592624 -402.621242) (xy 233.620222 -402.652015)
			(xy 233.67027 -402.717808) (xy 233.714004 -402.787957) (xy 233.751046 -402.861859) (xy 233.781077 -402.938876)
			(xy 233.803838 -403.018346) (xy 233.819134 -403.099584) (xy 233.826833 -403.18189) (xy 233.82732 -403.223222)
			(xy 233.826801 -403.266183) (xy 233.818523 -403.351705) (xy 233.802036 -403.43603) (xy 233.777494 -403.518372)
			(xy 233.745125 -403.597963) (xy 233.705232 -403.674062) (xy 233.658186 -403.745959) (xy 233.604426 -403.812984)
			(xy 233.544453 -403.874513) (xy 233.478826 -403.929971) (xy 233.408156 -403.978842) (xy 233.370882 -404.000208)
			(xy 233.36273 -404.005265) (xy 233.350612 -404.020117) (xy 233.34476 -404.03837) (xy 233.344974 -404.04796)
			(xy 233.352086 -404.154386) (xy 233.369358 -404.178008) (xy 233.383328 -404.183342) (xy 233.421266 -404.198729)
			(xy 233.494382 -404.235572) (xy 233.563803 -404.27898) (xy 233.62894 -404.328584) (xy 233.689242 -404.383965)
			(xy 233.744199 -404.444654) (xy 233.793346 -404.510137) (xy 233.836266 -404.57986) (xy 233.872597 -404.653232)
			(xy 233.90203 -404.729633) (xy 233.924317 -404.808416) (xy 233.939269 -404.888913) (xy 233.946758 -404.970445)
			(xy 233.947208 -405.011382) (xy 233.946619 -405.057777) (xy 233.936976 -405.150066) (xy 233.917781 -405.240849)
			(xy 233.889245 -405.329143) (xy 233.871008 -405.371808) (xy 233.867213 -405.381753) (xy 233.867206 -405.403014)
			(xy 233.871008 -405.412956) (xy 233.889247 -405.455621) (xy 233.917792 -405.543912) (xy 233.936987 -405.634696)
			(xy 233.946622 -405.726986) (xy 233.947208 -405.773382) (xy 233.946619 -405.819777) (xy 233.936976 -405.912066)
			(xy 233.917781 -406.002849) (xy 233.889245 -406.091143) (xy 233.871008 -406.133808) (xy 233.867213 -406.143753)
			(xy 233.867206 -406.165014) (xy 233.871008 -406.174956) (xy 233.885234 -406.207876) (xy 233.908955 -406.275561)
			(xy 233.927136 -406.34494) (xy 233.933746 -406.380188) (xy 233.936055 -406.390309) (xy 233.947454 -406.407631)
			(xy 233.964772 -406.419037) (xy 233.974894 -406.421336) (xy 234.015556 -406.42906) (xy 234.09536 -406.451024)
			(xy 234.17278 -406.480305) (xy 234.247146 -406.51665) (xy 234.317814 -406.559745) (xy 234.384174 -406.609217)
			(xy 234.445652 -406.66464) (xy 234.501716 -406.725533) (xy 234.551883 -406.791369) (xy 234.595718 -406.861581)
			(xy 234.632841 -406.935561) (xy 234.662933 -407.012669) (xy 234.685733 -407.092239) (xy 234.701045 -407.173582)
			(xy 234.708734 -407.255996) (xy 234.709208 -407.297382) (xy 234.709208 -407.29789) (xy 234.708596 -407.344222)
			(xy 234.698926 -407.436379) (xy 234.679732 -407.527034) (xy 234.651222 -407.615202) (xy 234.633008 -407.657808)
			(xy 234.629213 -407.667753) (xy 234.629206 -407.689014) (xy 234.633008 -407.698956) (xy 234.651224 -407.741561)
			(xy 234.679743 -407.829728) (xy 234.698938 -407.920383) (xy 234.708599 -408.012542) (xy 234.709208 -408.058874)
			(xy 234.709208 -408.059382) (xy 234.70867 -408.100487) (xy 234.701088 -408.182347) (xy 234.685987 -408.263158)
			(xy 234.663495 -408.342232) (xy 234.633804 -408.418893) (xy 234.597168 -408.492489) (xy 234.5539 -408.562391)
			(xy 234.504367 -408.628004) (xy 234.448992 -408.688767) (xy 234.388249 -408.744164) (xy 234.322654 -408.79372)
			(xy 234.252767 -408.837014) (xy 234.179184 -408.873676) (xy 234.102533 -408.903394) (xy 234.023468 -408.925914)
			(xy 233.942662 -408.941044) (xy 233.860805 -408.948656) (xy 233.8197 -408.949144) (xy 233.773298 -408.948515)
			(xy 233.681001 -408.938826) (xy 233.590215 -408.919572) (xy 233.50193 -408.890965) (xy 233.459274 -408.87269)
			(xy 233.449332 -408.868884) (xy 233.428068 -408.868884) (xy 233.418126 -408.87269) (xy 233.375466 -408.890954)
			(xy 233.287177 -408.919546) (xy 233.196394 -408.938803) (xy 233.104101 -408.948515) (xy 233.0577 -408.949144)
			(xy 233.011298 -408.948515) (xy 232.919001 -408.938826) (xy 232.828215 -408.919572) (xy 232.73993 -408.890965)
			(xy 232.697274 -408.87269) (xy 232.687332 -408.868884) (xy 232.666068 -408.868884) (xy 232.656126 -408.87269)
			(xy 232.613466 -408.890954) (xy 232.525177 -408.919546) (xy 232.434394 -408.938803) (xy 232.342101 -408.948515)
			(xy 232.2957 -408.949144) (xy 232.249298 -408.948515) (xy 232.157001 -408.938826) (xy 232.066215 -408.919572)
			(xy 231.97793 -408.890965) (xy 231.935274 -408.87269) (xy 231.925332 -408.868884) (xy 231.904068 -408.868884)
			(xy 231.894126 -408.87269) (xy 231.851466 -408.890954) (xy 231.763177 -408.919546) (xy 231.672394 -408.938803)
			(xy 231.580101 -408.948515) (xy 231.5337 -408.949144) (xy 231.487298 -408.948515) (xy 231.395001 -408.938826)
			(xy 231.304215 -408.919572) (xy 231.21593 -408.890965) (xy 231.173274 -408.87269) (xy 231.163332 -408.868884)
			(xy 231.142068 -408.868884) (xy 231.132126 -408.87269) (xy 231.089466 -408.890954) (xy 231.001177 -408.919546)
			(xy 230.910394 -408.938803) (xy 230.818101 -408.948515) (xy 230.7717 -408.949144) (xy 230.725298 -408.948515)
			(xy 230.633001 -408.938826) (xy 230.542215 -408.919572) (xy 230.45393 -408.890965) (xy 230.411274 -408.87269)
			(xy 230.401332 -408.868884) (xy 230.380068 -408.868884) (xy 230.370126 -408.87269) (xy 230.327466 -408.890954)
			(xy 230.239177 -408.919546) (xy 230.148394 -408.938803) (xy 230.056101 -408.948515) (xy 230.0097 -408.949144)
			(xy 229.963298 -408.948515) (xy 229.871001 -408.938826) (xy 229.780215 -408.919572) (xy 229.69193 -408.890965)
			(xy 229.649274 -408.87269) (xy 229.639332 -408.868884) (xy 229.618068 -408.868884) (xy 229.608126 -408.87269)
			(xy 229.565466 -408.890954) (xy 229.477177 -408.919546) (xy 229.386394 -408.938803) (xy 229.294101 -408.948515)
			(xy 229.2477 -408.949144) (xy 229.201298 -408.948515) (xy 229.109001 -408.938826) (xy 229.018215 -408.919572)
			(xy 228.92993 -408.890965) (xy 228.887274 -408.87269) (xy 228.877332 -408.868884) (xy 228.856068 -408.868884)
			(xy 228.846126 -408.87269) (xy 228.803466 -408.890954) (xy 228.715177 -408.919546) (xy 228.624394 -408.938803)
			(xy 228.532101 -408.948515) (xy 228.4857 -408.949144) (xy 228.444606 -408.948634) (xy 228.362769 -408.941052)
			(xy 228.281979 -408.925953) (xy 228.202928 -408.903466) (xy 228.126287 -408.873782) (xy 228.052712 -408.837155)
			(xy 227.98283 -408.793896) (xy 227.917236 -408.744376) (xy 227.85649 -408.689016) (xy 227.801109 -408.628288)
			(xy 227.751568 -408.56271) (xy 227.708286 -408.492841) (xy 227.671635 -408.419278) (xy 227.641926 -408.342647)
			(xy 227.619413 -408.263603) (xy 227.604288 -408.182819) (xy 227.59668 -408.100984) (xy 227.596192 -408.05989)
			(xy 224.041201 -408.05989) (xy 224.04067 -408.100487) (xy 224.033088 -408.182347) (xy 224.017987 -408.263158)
			(xy 223.995495 -408.342232) (xy 223.965804 -408.418893) (xy 223.929168 -408.492489) (xy 223.8859 -408.562391)
			(xy 223.836367 -408.628004) (xy 223.780992 -408.688767) (xy 223.720249 -408.744164) (xy 223.654654 -408.79372)
			(xy 223.584767 -408.837014) (xy 223.511184 -408.873676) (xy 223.434533 -408.903394) (xy 223.355468 -408.925914)
			(xy 223.274662 -408.941044) (xy 223.192805 -408.948656) (xy 223.1517 -408.949144) (xy 223.105298 -408.948515)
			(xy 223.013001 -408.938826) (xy 222.922215 -408.919572) (xy 222.83393 -408.890965) (xy 222.791274 -408.87269)
			(xy 222.781332 -408.868884) (xy 222.760068 -408.868884) (xy 222.750126 -408.87269) (xy 222.707466 -408.890954)
			(xy 222.619177 -408.919546) (xy 222.528394 -408.938803) (xy 222.436101 -408.948515) (xy 222.3897 -408.949144)
			(xy 222.343298 -408.948515) (xy 222.251001 -408.938826) (xy 222.160215 -408.919572) (xy 222.07193 -408.890965)
			(xy 222.029274 -408.87269) (xy 222.019332 -408.868884) (xy 221.998068 -408.868884) (xy 221.988126 -408.87269)
			(xy 221.945466 -408.890954) (xy 221.857177 -408.919546) (xy 221.766394 -408.938803) (xy 221.674101 -408.948515)
			(xy 221.6277 -408.949144) (xy 221.581298 -408.948515) (xy 221.489001 -408.938826) (xy 221.398215 -408.919572)
			(xy 221.30993 -408.890965) (xy 221.267274 -408.87269) (xy 221.257332 -408.868884) (xy 221.236068 -408.868884)
			(xy 221.226126 -408.87269) (xy 221.183466 -408.890954) (xy 221.095177 -408.919546) (xy 221.004394 -408.938803)
			(xy 220.912101 -408.948515) (xy 220.8657 -408.949144) (xy 220.819298 -408.948515) (xy 220.727001 -408.938826)
			(xy 220.636215 -408.919572) (xy 220.54793 -408.890965) (xy 220.505274 -408.87269) (xy 220.495332 -408.868884)
			(xy 220.474068 -408.868884) (xy 220.464126 -408.87269) (xy 220.421466 -408.890954) (xy 220.333177 -408.919546)
			(xy 220.242394 -408.938803) (xy 220.150101 -408.948515) (xy 220.1037 -408.949144) (xy 220.057298 -408.948515)
			(xy 219.965001 -408.938826) (xy 219.874215 -408.919572) (xy 219.78593 -408.890965) (xy 219.743274 -408.87269)
			(xy 219.733332 -408.868884) (xy 219.712068 -408.868884) (xy 219.702126 -408.87269) (xy 219.659466 -408.890954)
			(xy 219.571177 -408.919546) (xy 219.480394 -408.938803) (xy 219.388101 -408.948515) (xy 219.3417 -408.949144)
			(xy 219.295298 -408.948515) (xy 219.203001 -408.938826) (xy 219.112215 -408.919572) (xy 219.02393 -408.890965)
			(xy 218.981274 -408.87269) (xy 218.971332 -408.868884) (xy 218.950068 -408.868884) (xy 218.940126 -408.87269)
			(xy 218.897466 -408.890954) (xy 218.809177 -408.919546) (xy 218.718394 -408.938803) (xy 218.626101 -408.948515)
			(xy 218.5797 -408.949144) (xy 218.533298 -408.948515) (xy 218.441001 -408.938826) (xy 218.350215 -408.919572)
			(xy 218.26193 -408.890965) (xy 218.219274 -408.87269) (xy 218.209332 -408.868884) (xy 218.188068 -408.868884)
			(xy 218.178126 -408.87269) (xy 218.135466 -408.890954) (xy 218.047177 -408.919546) (xy 217.956394 -408.938803)
			(xy 217.864101 -408.948515) (xy 217.8177 -408.949144) (xy 217.776606 -408.948634) (xy 217.694769 -408.941052)
			(xy 217.613979 -408.925953) (xy 217.534928 -408.903466) (xy 217.458287 -408.873782) (xy 217.384712 -408.837155)
			(xy 217.31483 -408.793896) (xy 217.249236 -408.744376) (xy 217.18849 -408.689016) (xy 217.133109 -408.628288)
			(xy 217.083568 -408.56271) (xy 217.040286 -408.492841) (xy 217.003635 -408.419278) (xy 216.973926 -408.342647)
			(xy 216.951413 -408.263603) (xy 216.936288 -408.182819) (xy 216.92868 -408.100984) (xy 216.928192 -408.05989)
			(xy 213.373201 -408.05989) (xy 213.37267 -408.100487) (xy 213.365088 -408.182347) (xy 213.349987 -408.263158)
			(xy 213.327495 -408.342232) (xy 213.297804 -408.418893) (xy 213.261168 -408.492489) (xy 213.2179 -408.562391)
			(xy 213.168367 -408.628004) (xy 213.112992 -408.688767) (xy 213.052249 -408.744164) (xy 212.986654 -408.79372)
			(xy 212.916767 -408.837014) (xy 212.843184 -408.873676) (xy 212.766533 -408.903394) (xy 212.687468 -408.925914)
			(xy 212.606662 -408.941044) (xy 212.524805 -408.948656) (xy 212.4837 -408.949144) (xy 212.437298 -408.948515)
			(xy 212.345001 -408.938826) (xy 212.254215 -408.919572) (xy 212.16593 -408.890965) (xy 212.123274 -408.87269)
			(xy 212.113332 -408.868884) (xy 212.092068 -408.868884) (xy 212.082126 -408.87269) (xy 212.039466 -408.890954)
			(xy 211.951177 -408.919546) (xy 211.860394 -408.938803) (xy 211.768101 -408.948515) (xy 211.7217 -408.949144)
			(xy 211.675298 -408.948515) (xy 211.583001 -408.938826) (xy 211.492215 -408.919572) (xy 211.40393 -408.890965)
			(xy 211.361274 -408.87269) (xy 211.351332 -408.868884) (xy 211.330068 -408.868884) (xy 211.320126 -408.87269)
			(xy 211.277466 -408.890954) (xy 211.189177 -408.919546) (xy 211.098394 -408.938803) (xy 211.006101 -408.948515)
			(xy 210.9597 -408.949144) (xy 210.913298 -408.948515) (xy 210.821001 -408.938826) (xy 210.730215 -408.919572)
			(xy 210.64193 -408.890965) (xy 210.599274 -408.87269) (xy 210.589332 -408.868884) (xy 210.568068 -408.868884)
			(xy 210.558126 -408.87269) (xy 210.515466 -408.890954) (xy 210.427177 -408.919546) (xy 210.336394 -408.938803)
			(xy 210.244101 -408.948515) (xy 210.1977 -408.949144) (xy 210.151298 -408.948515) (xy 210.059001 -408.938826)
			(xy 209.968215 -408.919572) (xy 209.87993 -408.890965) (xy 209.837274 -408.87269) (xy 209.827332 -408.868884)
			(xy 209.806068 -408.868884) (xy 209.796126 -408.87269) (xy 209.753466 -408.890954) (xy 209.665177 -408.919546)
			(xy 209.574394 -408.938803) (xy 209.482101 -408.948515) (xy 209.4357 -408.949144) (xy 209.389298 -408.948515)
			(xy 209.297001 -408.938826) (xy 209.206215 -408.919572) (xy 209.11793 -408.890965) (xy 209.075274 -408.87269)
			(xy 209.065332 -408.868884) (xy 209.044068 -408.868884) (xy 209.034126 -408.87269) (xy 208.991466 -408.890954)
			(xy 208.903177 -408.919546) (xy 208.812394 -408.938803) (xy 208.720101 -408.948515) (xy 208.6737 -408.949144)
			(xy 208.627298 -408.948515) (xy 208.535001 -408.938826) (xy 208.444215 -408.919572) (xy 208.35593 -408.890965)
			(xy 208.313274 -408.87269) (xy 208.303332 -408.868884) (xy 208.282068 -408.868884) (xy 208.272126 -408.87269)
			(xy 208.229466 -408.890954) (xy 208.141177 -408.919546) (xy 208.050394 -408.938803) (xy 207.958101 -408.948515)
			(xy 207.9117 -408.949144) (xy 207.865298 -408.948515) (xy 207.773001 -408.938826) (xy 207.682215 -408.919572)
			(xy 207.59393 -408.890965) (xy 207.551274 -408.87269) (xy 207.541332 -408.868884) (xy 207.520068 -408.868884)
			(xy 207.510126 -408.87269) (xy 207.467466 -408.890954) (xy 207.379177 -408.919546) (xy 207.288394 -408.938803)
			(xy 207.196101 -408.948515) (xy 207.1497 -408.949144) (xy 207.108606 -408.948634) (xy 207.026769 -408.941052)
			(xy 206.945979 -408.925953) (xy 206.866928 -408.903466) (xy 206.790287 -408.873782) (xy 206.716712 -408.837155)
			(xy 206.64683 -408.793896) (xy 206.581236 -408.744376) (xy 206.52049 -408.689016) (xy 206.465109 -408.628288)
			(xy 206.415568 -408.56271) (xy 206.372286 -408.492841) (xy 206.335635 -408.419278) (xy 206.305926 -408.342647)
			(xy 206.283413 -408.263603) (xy 206.268288 -408.182819) (xy 206.26068 -408.100984) (xy 206.260192 -408.05989)
			(xy 201.943201 -408.05989) (xy 201.94267 -408.100487) (xy 201.935088 -408.182347) (xy 201.919987 -408.263158)
			(xy 201.897495 -408.342232) (xy 201.867804 -408.418893) (xy 201.831168 -408.492489) (xy 201.7879 -408.562391)
			(xy 201.738367 -408.628004) (xy 201.682992 -408.688767) (xy 201.622249 -408.744164) (xy 201.556654 -408.79372)
			(xy 201.486767 -408.837014) (xy 201.413184 -408.873676) (xy 201.336533 -408.903394) (xy 201.257468 -408.925914)
			(xy 201.176662 -408.941044) (xy 201.094805 -408.948656) (xy 201.0537 -408.949144) (xy 201.007298 -408.948515)
			(xy 200.915001 -408.938826) (xy 200.824215 -408.919572) (xy 200.73593 -408.890965) (xy 200.693274 -408.87269)
			(xy 200.683332 -408.868884) (xy 200.662068 -408.868884) (xy 200.652126 -408.87269) (xy 200.609466 -408.890954)
			(xy 200.521177 -408.919546) (xy 200.430394 -408.938803) (xy 200.338101 -408.948515) (xy 200.2917 -408.949144)
			(xy 200.245298 -408.948515) (xy 200.153001 -408.938826) (xy 200.062215 -408.919572) (xy 199.97393 -408.890965)
			(xy 199.931274 -408.87269) (xy 199.921332 -408.868884) (xy 199.900068 -408.868884) (xy 199.890126 -408.87269)
			(xy 199.847466 -408.890954) (xy 199.759177 -408.919546) (xy 199.668394 -408.938803) (xy 199.576101 -408.948515)
			(xy 199.5297 -408.949144) (xy 199.483298 -408.948515) (xy 199.391001 -408.938826) (xy 199.300215 -408.919572)
			(xy 199.21193 -408.890965) (xy 199.169274 -408.87269) (xy 199.159332 -408.868884) (xy 199.138068 -408.868884)
			(xy 199.128126 -408.87269) (xy 199.085466 -408.890954) (xy 198.997177 -408.919546) (xy 198.906394 -408.938803)
			(xy 198.814101 -408.948515) (xy 198.7677 -408.949144) (xy 198.721298 -408.948515) (xy 198.629001 -408.938826)
			(xy 198.538215 -408.919572) (xy 198.44993 -408.890965) (xy 198.407274 -408.87269) (xy 198.397332 -408.868884)
			(xy 198.376068 -408.868884) (xy 198.366126 -408.87269) (xy 198.323466 -408.890954) (xy 198.235177 -408.919546)
			(xy 198.144394 -408.938803) (xy 198.052101 -408.948515) (xy 198.0057 -408.949144) (xy 197.959298 -408.948515)
			(xy 197.867001 -408.938826) (xy 197.776215 -408.919572) (xy 197.68793 -408.890965) (xy 197.645274 -408.87269)
			(xy 197.635332 -408.868884) (xy 197.614068 -408.868884) (xy 197.604126 -408.87269) (xy 197.561466 -408.890954)
			(xy 197.473177 -408.919546) (xy 197.382394 -408.938803) (xy 197.290101 -408.948515) (xy 197.2437 -408.949144)
			(xy 197.20259 -408.948648) (xy 197.120722 -408.94106) (xy 197.039903 -408.92595) (xy 196.960824 -408.903446)
			(xy 196.884158 -408.873741) (xy 196.810562 -408.837087) (xy 196.740661 -408.793799) (xy 196.675054 -408.744244)
			(xy 196.6143 -408.688846) (xy 196.558917 -408.628078) (xy 196.509378 -408.562459) (xy 196.466106 -408.492548)
			(xy 196.429471 -408.418942) (xy 196.399784 -408.342269) (xy 196.3773 -408.263184) (xy 196.36221 -408.182362)
			(xy 196.354642 -408.100492) (xy 196.354192 -408.059382) (xy 190.372573 -408.059382) (xy 190.373 -408.091894)
			(xy 190.373 -408.092402) (xy 190.372489 -408.133508) (xy 190.364905 -408.215368) (xy 190.349802 -408.296181)
			(xy 190.327308 -408.375255) (xy 190.297616 -408.451917) (xy 190.260978 -408.525513) (xy 190.217707 -408.595415)
			(xy 190.168173 -408.661028) (xy 190.112797 -408.721791) (xy 190.052051 -408.777187) (xy 189.986455 -408.826743)
			(xy 189.916566 -408.870037) (xy 189.842982 -408.906699) (xy 189.76633 -408.936416) (xy 189.687263 -408.958936)
			(xy 189.606456 -408.974065) (xy 189.524598 -408.981676) (xy 189.483492 -408.982164) (xy 189.43709 -408.981537)
			(xy 189.344793 -408.971846) (xy 189.254007 -408.952593) (xy 189.165722 -408.923985) (xy 189.123066 -408.90571)
			(xy 189.113124 -408.901904) (xy 189.09186 -408.901904) (xy 189.081918 -408.90571) (xy 189.039259 -408.923977)
			(xy 188.95097 -408.952569) (xy 188.860187 -408.971824) (xy 188.767893 -408.981535) (xy 188.721492 -408.982164)
			(xy 188.67509 -408.981537) (xy 188.582793 -408.971846) (xy 188.492007 -408.952593) (xy 188.403722 -408.923985)
			(xy 188.361066 -408.90571) (xy 188.351124 -408.901904) (xy 188.32986 -408.901904) (xy 188.319918 -408.90571)
			(xy 188.277259 -408.923977) (xy 188.18897 -408.952569) (xy 188.098187 -408.971824) (xy 188.005893 -408.981535)
			(xy 187.959492 -408.982164) (xy 187.91309 -408.981537) (xy 187.820793 -408.971846) (xy 187.730007 -408.952593)
			(xy 187.641722 -408.923985) (xy 187.599066 -408.90571) (xy 187.589124 -408.901904) (xy 187.56786 -408.901904)
			(xy 187.557918 -408.90571) (xy 187.515259 -408.923977) (xy 187.42697 -408.952569) (xy 187.336187 -408.971824)
			(xy 187.243893 -408.981535) (xy 187.197492 -408.982164) (xy 187.15109 -408.981537) (xy 187.058793 -408.971846)
			(xy 186.968007 -408.952593) (xy 186.879722 -408.923985) (xy 186.837066 -408.90571) (xy 186.827124 -408.901904)
			(xy 186.80586 -408.901904) (xy 186.795918 -408.90571) (xy 186.753259 -408.923977) (xy 186.66497 -408.952569)
			(xy 186.574187 -408.971824) (xy 186.481893 -408.981535) (xy 186.435492 -408.982164) (xy 186.38909 -408.981537)
			(xy 186.296793 -408.971846) (xy 186.206007 -408.952593) (xy 186.117722 -408.923985) (xy 186.075066 -408.90571)
			(xy 186.065124 -408.901904) (xy 186.04386 -408.901904) (xy 186.033918 -408.90571) (xy 185.991259 -408.923977)
			(xy 185.90297 -408.952569) (xy 185.812187 -408.971824) (xy 185.719893 -408.981535) (xy 185.673492 -408.982164)
			(xy 185.63238 -408.981755) (xy 185.550507 -408.974166) (xy 185.469683 -408.959054) (xy 185.3906 -408.936547)
			(xy 185.31393 -408.906837) (xy 185.24033 -408.870179) (xy 185.170427 -408.826885) (xy 185.104818 -408.777325)
			(xy 185.044063 -408.721921) (xy 184.98868 -408.661146) (xy 184.939142 -408.59552) (xy 184.895872 -408.525602)
			(xy 184.859239 -408.451989) (xy 184.829556 -408.37531) (xy 184.807076 -408.296219) (xy 184.791992 -408.21539)
			(xy 184.784431 -408.133514) (xy 184.783984 -408.092402) (xy 184.784568 -408.046006) (xy 184.794213 -407.953718)
			(xy 184.813409 -407.862934) (xy 184.841946 -407.774641) (xy 184.860184 -407.731976) (xy 184.863989 -407.722034)
			(xy 184.86399 -407.70077) (xy 184.860184 -407.690828) (xy 184.841939 -407.648166) (xy 184.813395 -407.559873)
			(xy 184.794202 -407.469088) (xy 184.784569 -407.376798) (xy 184.783984 -407.330402) (xy 184.784407 -407.290634)
			(xy 184.791436 -407.211411) (xy 184.805517 -407.133132) (xy 184.826539 -407.056426) (xy 184.854333 -406.981906)
			(xy 184.871106 -406.945846) (xy 184.875438 -406.935345) (xy 184.875439 -406.912659) (xy 184.871106 -406.902158)
			(xy 184.854347 -406.866093) (xy 184.826573 -406.791567) (xy 184.805556 -406.714862) (xy 184.791462 -406.636588)
			(xy 184.784405 -406.557369) (xy 184.783984 -406.517602) (xy 184.784568 -406.471206) (xy 184.794213 -406.378918)
			(xy 184.813409 -406.288134) (xy 184.841946 -406.199841) (xy 184.860184 -406.157176) (xy 184.863989 -406.147234)
			(xy 184.86399 -406.12597) (xy 184.860184 -406.116028) (xy 184.841939 -406.073366) (xy 184.813395 -405.985073)
			(xy 184.794202 -405.894288) (xy 184.784569 -405.801998) (xy 184.783984 -405.755602) (xy 184.784568 -405.709206)
			(xy 184.794213 -405.616918) (xy 184.813409 -405.526134) (xy 184.841946 -405.437841) (xy 184.860184 -405.395176)
			(xy 184.863989 -405.385234) (xy 184.86399 -405.36397) (xy 184.860184 -405.354028) (xy 184.841962 -405.311425)
			(xy 184.813445 -405.223258) (xy 184.794252 -405.132602) (xy 184.784592 -405.040442) (xy 184.783984 -404.99411)
			(xy 184.783984 -404.993602) (xy 184.784497 -404.950127) (xy 184.792981 -404.863592) (xy 184.809868 -404.778298)
			(xy 184.834996 -404.695058) (xy 184.868127 -404.614668) (xy 184.908943 -404.537893) (xy 184.957056 -404.465468)
			(xy 185.012005 -404.398082) (xy 185.073268 -404.33638) (xy 185.140259 -404.28095) (xy 185.212338 -404.232321)
			(xy 185.288819 -404.190956) (xy 185.368971 -404.157252) (xy 185.452028 -404.131529) (xy 185.5372 -404.114033)
			(xy 185.623672 -404.104931) (xy 185.667142 -404.104094) (xy 185.677625 -404.103496) (xy 185.6968 -404.094996)
			(xy 185.710988 -404.07955) (xy 185.714894 -404.069804) (xy 185.745882 -403.978872) (xy 185.748725 -403.96876)
			(xy 185.74698 -403.947853) (xy 185.737043 -403.929376) (xy 185.729118 -403.922484) (xy 185.70573 -403.903812)
			(xy 185.661243 -403.863772) (xy 185.640218 -403.842474) (xy 185.632756 -403.835439) (xy 185.613887 -403.827446)
			(xy 185.603642 -403.82698) (xy 185.530998 -403.82698) (xy 185.520746 -403.827411) (xy 185.501872 -403.835417)
			(xy 185.494422 -403.842474) (xy 185.463025 -403.87402) (xy 185.394968 -403.931383) (xy 185.321521 -403.981662)
			(xy 185.24342 -404.024354) (xy 185.161446 -404.059031) (xy 185.076418 -404.085348) (xy 184.989186 -404.103041)
			(xy 184.900624 -404.111933) (xy 184.85612 -404.112476) (xy 184.815024 -404.112015) (xy 184.733183 -404.104434)
			(xy 184.652391 -404.089335) (xy 184.573336 -404.066848) (xy 184.496692 -404.037162) (xy 184.423115 -404.000533)
			(xy 184.35323 -403.957272) (xy 184.287634 -403.907749) (xy 184.226887 -403.852384) (xy 184.171506 -403.791652)
			(xy 184.121965 -403.72607) (xy 184.078685 -403.656197) (xy 184.042035 -403.582629) (xy 184.012329 -403.505994)
			(xy 183.98982 -403.426945) (xy 183.9747 -403.346156) (xy 183.967097 -403.264318) (xy 183.966612 -403.223222)
			(xy 174.680622 -403.223222) (xy 174.717549 -403.310307) (xy 174.77977 -403.477384) (xy 174.834486 -403.647068)
			(xy 174.881588 -403.819021) (xy 174.920984 -403.992901) (xy 174.952595 -404.168364) (xy 174.976359 -404.34506)
			(xy 174.992227 -404.52264) (xy 175.000169 -404.70075) (xy 175.000666 -404.789894) (xy 175.000169 -404.879038)
			(xy 174.992227 -405.057148) (xy 174.976359 -405.234728) (xy 174.952595 -405.411424) (xy 174.920984 -405.586887)
			(xy 174.881588 -405.760767) (xy 174.834486 -405.93272) (xy 174.77977 -406.102404) (xy 174.717549 -406.269481)
			(xy 174.647948 -406.433622) (xy 174.571103 -406.594498) (xy 174.487169 -406.751792) (xy 174.396311 -406.905191)
			(xy 174.298709 -407.05439) (xy 174.194558 -407.199093) (xy 174.084065 -407.339013) (xy 173.967448 -407.473872)
			(xy 173.844939 -407.603402) (xy 173.716782 -407.727346) (xy 173.583231 -407.845458) (xy 173.444551 -407.957503)
			(xy 173.301017 -408.06326) (xy 173.152914 -408.162517) (xy 173.000537 -408.255079) (xy 172.844188 -408.34076)
			(xy 172.684177 -408.419392) (xy 172.520823 -408.490818) (xy 172.354448 -408.554896) (xy 172.185385 -408.611498)
			(xy 172.013968 -408.660514) (xy 171.840537 -408.701844) (xy 171.665437 -408.735408) (xy 171.489017 -408.761138)
			(xy 171.311625 -408.778984) (xy 171.133614 -408.78891) (xy 170.955337 -408.790896) (xy 170.77715 -408.784939)
			(xy 170.599404 -408.771049) (xy 170.422454 -408.749256) (xy 170.24665 -408.719602) (xy 170.072342 -408.682145)
			(xy 169.899875 -408.636961) (xy 169.729592 -408.584139) (xy 169.561831 -408.523783) (xy 169.396926 -408.456015)
			(xy 169.235203 -408.380967) (xy 169.076984 -408.29879) (xy 168.922583 -408.209647) (xy 168.772306 -408.113713)
			(xy 168.626451 -408.011181) (xy 168.485309 -407.902253) (xy 168.34916 -407.787146) (xy 168.218273 -407.666088)
			(xy 168.092909 -407.539319) (xy 167.973316 -407.407092) (xy 167.859733 -407.269669) (xy 167.752384 -407.127322)
			(xy 167.651483 -406.980334) (xy 167.55723 -406.828998) (xy 167.469812 -406.673613) (xy 167.389402 -406.514488)
			(xy 167.316161 -406.351939) (xy 167.250234 -406.186289) (xy 167.191751 -406.017867) (xy 167.140829 -405.847006)
			(xy 167.097569 -405.674047) (xy 167.062057 -405.499332) (xy 167.034363 -405.323208) (xy 167.014542 -405.146026)
			(xy 167.002634 -404.968137) (xy 166.998662 -404.789894) (xy 161.904774 -404.789894) (xy 161.889384 -404.799785)
			(xy 161.839805 -404.822428) (xy 161.787508 -404.837784) (xy 161.733558 -404.845542) (xy 161.706306 -404.846028)
			(xy 160.842706 -404.846028) (xy 160.815454 -404.845525) (xy 160.761506 -404.837769) (xy 160.70921 -404.822415)
			(xy 160.659631 -404.799774) (xy 160.61378 -404.770307) (xy 160.572589 -404.734616) (xy 160.536896 -404.693425)
			(xy 160.507429 -404.647574) (xy 160.484788 -404.597996) (xy 160.469432 -404.5457) (xy 160.461675 -404.491752)
			(xy 159.024165 -404.491752) (xy 159.024165 -404.491756) (xy 159.016407 -404.545713) (xy 159.001048 -404.598016)
			(xy 158.978402 -404.647601) (xy 158.948929 -404.693458) (xy 158.91323 -404.734654) (xy 158.872031 -404.77035)
			(xy 158.826171 -404.799818) (xy 158.776584 -404.82246) (xy 158.724279 -404.837814) (xy 158.670322 -404.845567)
			(xy 158.643066 -404.846028) (xy 157.779466 -404.846028) (xy 157.752218 -404.845499) (xy 157.698277 -404.837739)
			(xy 157.645989 -404.822382) (xy 157.596418 -404.79974) (xy 157.550575 -404.770275) (xy 157.509391 -404.734585)
			(xy 157.473705 -404.693398) (xy 157.444243 -404.647552) (xy 157.421606 -404.597979) (xy 157.406253 -404.54569)
			(xy 157.398498 -404.491748) (xy 155.960842 -404.491748) (xy 155.960842 -404.491751) (xy 155.953086 -404.5457)
			(xy 155.937731 -404.597995) (xy 155.915091 -404.647573) (xy 155.885626 -404.693425) (xy 155.849935 -404.734617)
			(xy 155.808746 -404.77031) (xy 155.762896 -404.799778) (xy 155.71332 -404.822422) (xy 155.661025 -404.83778)
			(xy 155.607077 -404.84554) (xy 155.579826 -404.846028) (xy 154.716226 -404.846028) (xy 154.688973 -404.845526)
			(xy 154.635022 -404.837773) (xy 154.582724 -404.82242) (xy 154.533143 -404.79978) (xy 154.487289 -404.770314)
			(xy 154.446096 -404.734623) (xy 154.410401 -404.693431) (xy 154.380932 -404.647579) (xy 154.358289 -404.598)
			(xy 154.342933 -404.545703) (xy 154.335175 -404.491753) (xy 152.897665 -404.491753) (xy 152.897665 -404.491755)
			(xy 152.889907 -404.54571) (xy 152.87455 -404.598012) (xy 152.851905 -404.647595) (xy 152.822434 -404.693452)
			(xy 152.786737 -404.734647) (xy 152.745541 -404.770343) (xy 152.699683 -404.799812) (xy 152.650099 -404.822455)
			(xy 152.597796 -404.83781) (xy 152.543841 -404.845566) (xy 152.516586 -404.846028) (xy 151.652986 -404.846028)
			(xy 151.625737 -404.845501) (xy 151.571794 -404.837743) (xy 151.519503 -404.822388) (xy 151.46993 -404.799747)
			(xy 151.424084 -404.770282) (xy 151.382898 -404.734592) (xy 151.34721 -404.693404) (xy 151.317746 -404.647557)
			(xy 151.295108 -404.597984) (xy 151.279754 -404.545693) (xy 151.271998 -404.491749) (xy 149.834342 -404.491749)
			(xy 149.834342 -404.491751) (xy 149.826587 -404.545697) (xy 149.811233 -404.597991) (xy 149.788594 -404.647568)
			(xy 149.75913 -404.693418) (xy 149.723442 -404.734609) (xy 149.682255 -404.770303) (xy 149.636408 -404.799772)
			(xy 149.586834 -404.822417) (xy 149.534542 -404.837777) (xy 149.480597 -404.845539) (xy 149.453346 -404.846028)
			(xy 148.589746 -404.846028) (xy 148.562492 -404.845528) (xy 148.508539 -404.837777) (xy 148.456239 -404.822425)
			(xy 148.406655 -404.799787) (xy 148.360799 -404.770321) (xy 148.319603 -404.73463) (xy 148.283906 -404.693438)
			(xy 148.254435 -404.647585) (xy 148.231791 -404.598004) (xy 148.216433 -404.545706) (xy 148.208675 -404.491754)
			(xy 146.771142 -404.491754) (xy 146.763385 -404.545702) (xy 146.74803 -404.597999) (xy 146.725388 -404.647579)
			(xy 146.695921 -404.693431) (xy 146.660228 -404.734624) (xy 146.619036 -404.770317) (xy 146.573184 -404.799785)
			(xy 146.523605 -404.822428) (xy 146.471308 -404.837784) (xy 146.417358 -404.845542) (xy 146.390106 -404.846028)
			(xy 145.526506 -404.846028) (xy 145.499254 -404.845525) (xy 145.445306 -404.837769) (xy 145.39301 -404.822415)
			(xy 145.343431 -404.799774) (xy 145.29758 -404.770307) (xy 145.256389 -404.734616) (xy 145.220696 -404.693425)
			(xy 145.191229 -404.647574) (xy 145.168588 -404.597996) (xy 145.153232 -404.5457) (xy 145.145475 -404.491752)
			(xy 143.707965 -404.491752) (xy 143.707965 -404.491756) (xy 143.700207 -404.545713) (xy 143.684848 -404.598016)
			(xy 143.662202 -404.647601) (xy 143.632729 -404.693458) (xy 143.59703 -404.734654) (xy 143.555831 -404.77035)
			(xy 143.509971 -404.799818) (xy 143.460384 -404.82246) (xy 143.408079 -404.837814) (xy 143.354122 -404.845567)
			(xy 143.326866 -404.846028) (xy 142.463266 -404.846028) (xy 142.436018 -404.845499) (xy 142.382077 -404.837739)
			(xy 142.329789 -404.822382) (xy 142.280218 -404.79974) (xy 142.234375 -404.770275) (xy 142.193191 -404.734585)
			(xy 142.157505 -404.693398) (xy 142.128043 -404.647552) (xy 142.105406 -404.597979) (xy 142.090053 -404.54569)
			(xy 142.082298 -404.491748) (xy 140.644642 -404.491748) (xy 140.644642 -404.491751) (xy 140.636886 -404.5457)
			(xy 140.621531 -404.597995) (xy 140.598891 -404.647573) (xy 140.569426 -404.693425) (xy 140.533735 -404.734617)
			(xy 140.492546 -404.77031) (xy 140.446696 -404.799778) (xy 140.39712 -404.822422) (xy 140.344825 -404.83778)
			(xy 140.290877 -404.84554) (xy 140.263626 -404.846028) (xy 139.400026 -404.846028) (xy 139.372773 -404.845526)
			(xy 139.318822 -404.837773) (xy 139.266524 -404.82242) (xy 139.216943 -404.79978) (xy 139.171089 -404.770314)
			(xy 139.129896 -404.734623) (xy 139.094201 -404.693431) (xy 139.064732 -404.647579) (xy 139.042089 -404.598)
			(xy 139.026733 -404.545703) (xy 139.018975 -404.491753) (xy 137.581465 -404.491753) (xy 137.581465 -404.491755)
			(xy 137.573707 -404.54571) (xy 137.55835 -404.598012) (xy 137.535705 -404.647595) (xy 137.506234 -404.693452)
			(xy 137.470537 -404.734647) (xy 137.429341 -404.770343) (xy 137.383483 -404.799812) (xy 137.333899 -404.822455)
			(xy 137.281596 -404.83781) (xy 137.227641 -404.845566) (xy 137.200386 -404.846028) (xy 136.336786 -404.846028)
			(xy 136.309537 -404.845501) (xy 136.255594 -404.837743) (xy 136.203303 -404.822388) (xy 136.15373 -404.799747)
			(xy 136.107884 -404.770282) (xy 136.066698 -404.734592) (xy 136.03101 -404.693404) (xy 136.001546 -404.647557)
			(xy 135.978908 -404.597984) (xy 135.963554 -404.545693) (xy 135.955798 -404.491749) (xy 134.518142 -404.491749)
			(xy 134.518142 -404.491751) (xy 134.510387 -404.545697) (xy 134.495033 -404.597991) (xy 134.472394 -404.647568)
			(xy 134.44293 -404.693418) (xy 134.407242 -404.734609) (xy 134.366055 -404.770303) (xy 134.320208 -404.799772)
			(xy 134.270634 -404.822417) (xy 134.218342 -404.837777) (xy 134.164397 -404.845539) (xy 134.137146 -404.846028)
			(xy 133.273546 -404.846028) (xy 133.246292 -404.845528) (xy 133.192339 -404.837777) (xy 133.140039 -404.822425)
			(xy 133.090455 -404.799787) (xy 133.044599 -404.770321) (xy 133.003403 -404.73463) (xy 132.967706 -404.693438)
			(xy 132.938235 -404.647585) (xy 132.915591 -404.598004) (xy 132.900233 -404.545706) (xy 132.892475 -404.491754)
			(xy 131.454942 -404.491754) (xy 131.447185 -404.545702) (xy 131.43183 -404.597999) (xy 131.409188 -404.647579)
			(xy 131.379721 -404.693431) (xy 131.344028 -404.734624) (xy 131.302836 -404.770317) (xy 131.256984 -404.799785)
			(xy 131.207405 -404.822428) (xy 131.155108 -404.837784) (xy 131.101158 -404.845542) (xy 131.073906 -404.846028)
			(xy 130.210306 -404.846028) (xy 130.183054 -404.845525) (xy 130.129106 -404.837769) (xy 130.07681 -404.822415)
			(xy 130.027231 -404.799774) (xy 129.98138 -404.770307) (xy 129.940189 -404.734616) (xy 129.904496 -404.693425)
			(xy 129.875029 -404.647574) (xy 129.852388 -404.597996) (xy 129.837032 -404.5457) (xy 129.829275 -404.491752)
			(xy 128.391765 -404.491752) (xy 128.391765 -404.491756) (xy 128.384007 -404.545713) (xy 128.368648 -404.598016)
			(xy 128.346002 -404.647601) (xy 128.316529 -404.693458) (xy 128.28083 -404.734654) (xy 128.239631 -404.77035)
			(xy 128.193771 -404.799818) (xy 128.144184 -404.82246) (xy 128.091879 -404.837814) (xy 128.037922 -404.845567)
			(xy 128.010666 -404.846028) (xy 127.147066 -404.846028) (xy 127.119818 -404.845499) (xy 127.065877 -404.837739)
			(xy 127.013589 -404.822382) (xy 126.964018 -404.79974) (xy 126.918175 -404.770275) (xy 126.876991 -404.734585)
			(xy 126.841305 -404.693398) (xy 126.811843 -404.647552) (xy 126.789206 -404.597979) (xy 126.773853 -404.54569)
			(xy 126.766098 -404.491748) (xy 125.328442 -404.491748) (xy 125.328442 -404.491751) (xy 125.320686 -404.5457)
			(xy 125.305331 -404.597995) (xy 125.282691 -404.647573) (xy 125.253226 -404.693425) (xy 125.217535 -404.734617)
			(xy 125.176346 -404.77031) (xy 125.130496 -404.799778) (xy 125.08092 -404.822422) (xy 125.028625 -404.83778)
			(xy 124.974677 -404.84554) (xy 124.947426 -404.846028) (xy 124.083826 -404.846028) (xy 124.056573 -404.845526)
			(xy 124.002622 -404.837773) (xy 123.950324 -404.82242) (xy 123.900743 -404.79978) (xy 123.854889 -404.770314)
			(xy 123.813696 -404.734623) (xy 123.778001 -404.693431) (xy 123.748532 -404.647579) (xy 123.725889 -404.598)
			(xy 123.710533 -404.545703) (xy 123.702775 -404.491753) (xy 122.265265 -404.491753) (xy 122.265265 -404.491755)
			(xy 122.257507 -404.54571) (xy 122.24215 -404.598012) (xy 122.219505 -404.647595) (xy 122.190034 -404.693452)
			(xy 122.154337 -404.734647) (xy 122.113141 -404.770343) (xy 122.067283 -404.799812) (xy 122.017699 -404.822455)
			(xy 121.965396 -404.83781) (xy 121.911441 -404.845566) (xy 121.884186 -404.846028) (xy 121.020586 -404.846028)
			(xy 120.993337 -404.845501) (xy 120.939394 -404.837743) (xy 120.887103 -404.822388) (xy 120.83753 -404.799747)
			(xy 120.791684 -404.770282) (xy 120.750498 -404.734592) (xy 120.71481 -404.693404) (xy 120.685346 -404.647557)
			(xy 120.662708 -404.597984) (xy 120.647354 -404.545693) (xy 120.639598 -404.491749) (xy 119.201942 -404.491749)
			(xy 119.201942 -404.491751) (xy 119.194187 -404.545697) (xy 119.178833 -404.597991) (xy 119.156194 -404.647568)
			(xy 119.12673 -404.693418) (xy 119.091042 -404.734609) (xy 119.049855 -404.770303) (xy 119.004008 -404.799772)
			(xy 118.954434 -404.822417) (xy 118.902142 -404.837777) (xy 118.848197 -404.845539) (xy 118.820946 -404.846028)
			(xy 117.957346 -404.846028) (xy 117.930092 -404.845528) (xy 117.876139 -404.837777) (xy 117.823839 -404.822425)
			(xy 117.774255 -404.799787) (xy 117.728399 -404.770321) (xy 117.687203 -404.73463) (xy 117.651506 -404.693438)
			(xy 117.622035 -404.647585) (xy 117.599391 -404.598004) (xy 117.584033 -404.545706) (xy 117.576275 -404.491754)
			(xy 116.138742 -404.491754) (xy 116.130985 -404.545702) (xy 116.11563 -404.597999) (xy 116.092988 -404.647579)
			(xy 116.063521 -404.693431) (xy 116.027828 -404.734624) (xy 115.986636 -404.770317) (xy 115.940784 -404.799785)
			(xy 115.891205 -404.822428) (xy 115.838908 -404.837784) (xy 115.784958 -404.845542) (xy 115.757706 -404.846028)
			(xy 114.894106 -404.846028) (xy 114.866854 -404.845525) (xy 114.812906 -404.837769) (xy 114.76061 -404.822415)
			(xy 114.711031 -404.799774) (xy 114.66518 -404.770307) (xy 114.623989 -404.734616) (xy 114.588296 -404.693425)
			(xy 114.558829 -404.647574) (xy 114.536188 -404.597996) (xy 114.520832 -404.5457) (xy 114.513075 -404.491752)
			(xy 94.987465 -404.491752) (xy 94.987465 -404.491756) (xy 94.979707 -404.545713) (xy 94.964348 -404.598016)
			(xy 94.941702 -404.647602) (xy 94.912229 -404.693459) (xy 94.876529 -404.734655) (xy 94.83533 -404.77035)
			(xy 94.78947 -404.799819) (xy 94.739883 -404.822461) (xy 94.687578 -404.837814) (xy 94.63362 -404.845568)
			(xy 94.606364 -404.846028) (xy 93.742764 -404.846028) (xy 93.715516 -404.845499) (xy 93.661575 -404.837739)
			(xy 93.609287 -404.822382) (xy 93.559717 -404.79974) (xy 93.513874 -404.770274) (xy 93.47269 -404.734584)
			(xy 93.437004 -404.693397) (xy 93.407543 -404.647551) (xy 93.384906 -404.597979) (xy 93.369553 -404.54569)
			(xy 93.361798 -404.491748) (xy 91.924142 -404.491748) (xy 91.924142 -404.491752) (xy 91.916386 -404.5457)
			(xy 91.901031 -404.597996) (xy 91.878391 -404.647574) (xy 91.848925 -404.693425) (xy 91.813234 -404.734617)
			(xy 91.772045 -404.770311) (xy 91.726195 -404.799779) (xy 91.676618 -404.822423) (xy 91.624324 -404.837781)
			(xy 91.570376 -404.845541) (xy 91.543124 -404.846028) (xy 90.679524 -404.846028) (xy 90.652271 -404.845526)
			(xy 90.598321 -404.837773) (xy 90.546023 -404.822419) (xy 90.496442 -404.799779) (xy 90.450588 -404.770314)
			(xy 90.409395 -404.734622) (xy 90.373701 -404.693431) (xy 90.344232 -404.647579) (xy 90.321589 -404.598)
			(xy 90.306233 -404.545703) (xy 90.298475 -404.491753) (xy 88.860965 -404.491753) (xy 88.860965 -404.491755)
			(xy 88.853207 -404.54571) (xy 88.83785 -404.598012) (xy 88.815205 -404.647596) (xy 88.785734 -404.693452)
			(xy 88.750036 -404.734648) (xy 88.70884 -404.770343) (xy 88.662982 -404.799812) (xy 88.613397 -404.822455)
			(xy 88.561095 -404.837811) (xy 88.507139 -404.845566) (xy 88.479884 -404.846028) (xy 87.616284 -404.846028)
			(xy 87.589035 -404.845501) (xy 87.535092 -404.837743) (xy 87.482802 -404.822387) (xy 87.433229 -404.799746)
			(xy 87.387383 -404.770281) (xy 87.346197 -404.734591) (xy 87.310509 -404.693404) (xy 87.281046 -404.647557)
			(xy 87.258407 -404.597983) (xy 87.243054 -404.545692) (xy 87.235298 -404.491749) (xy 85.797642 -404.491749)
			(xy 85.797642 -404.491751) (xy 85.789887 -404.545697) (xy 85.774533 -404.597991) (xy 85.751894 -404.647568)
			(xy 85.72243 -404.693419) (xy 85.686741 -404.73461) (xy 85.645554 -404.770304) (xy 85.599707 -404.799773)
			(xy 85.550133 -404.822417) (xy 85.49784 -404.837777) (xy 85.443895 -404.845539) (xy 85.416644 -404.846028)
			(xy 84.553044 -404.846028) (xy 84.525791 -404.845528) (xy 84.471838 -404.837776) (xy 84.419537 -404.822425)
			(xy 84.369954 -404.799786) (xy 84.324098 -404.770321) (xy 84.282902 -404.734629) (xy 84.247206 -404.693437)
			(xy 84.217735 -404.647584) (xy 84.195091 -404.598004) (xy 84.179733 -404.545705) (xy 84.171975 -404.491753)
			(xy 82.734442 -404.491753) (xy 82.726685 -404.545703) (xy 82.71133 -404.598) (xy 82.688688 -404.647579)
			(xy 82.65922 -404.693432) (xy 82.623527 -404.734624) (xy 82.582335 -404.770318) (xy 82.536483 -404.799786)
			(xy 82.486904 -404.822428) (xy 82.434607 -404.837785) (xy 82.380656 -404.845542) (xy 82.353404 -404.846028)
			(xy 81.489804 -404.846028) (xy 81.462552 -404.845525) (xy 81.408604 -404.837769) (xy 81.356308 -404.822414)
			(xy 81.30673 -404.799773) (xy 81.260879 -404.770307) (xy 81.219688 -404.734615) (xy 81.183996 -404.693424)
			(xy 81.154529 -404.647573) (xy 81.131887 -404.597995) (xy 81.116532 -404.5457) (xy 81.108775 -404.491752)
			(xy 79.671265 -404.491752) (xy 79.671265 -404.491756) (xy 79.663507 -404.545713) (xy 79.648148 -404.598016)
			(xy 79.625502 -404.647602) (xy 79.596029 -404.693459) (xy 79.560329 -404.734655) (xy 79.51913 -404.77035)
			(xy 79.47327 -404.799819) (xy 79.423683 -404.822461) (xy 79.371378 -404.837814) (xy 79.31742 -404.845568)
			(xy 79.290164 -404.846028) (xy 78.426564 -404.846028) (xy 78.399316 -404.845499) (xy 78.345375 -404.837739)
			(xy 78.293087 -404.822382) (xy 78.243517 -404.79974) (xy 78.197674 -404.770274) (xy 78.15649 -404.734584)
			(xy 78.120804 -404.693397) (xy 78.091343 -404.647551) (xy 78.068706 -404.597979) (xy 78.053353 -404.54569)
			(xy 78.045598 -404.491748) (xy 76.607942 -404.491748) (xy 76.607942 -404.491752) (xy 76.600186 -404.5457)
			(xy 76.584831 -404.597996) (xy 76.562191 -404.647574) (xy 76.532725 -404.693425) (xy 76.497034 -404.734617)
			(xy 76.455845 -404.770311) (xy 76.409995 -404.799779) (xy 76.360418 -404.822423) (xy 76.308124 -404.837781)
			(xy 76.254176 -404.845541) (xy 76.226924 -404.846028) (xy 75.363324 -404.846028) (xy 75.336071 -404.845526)
			(xy 75.282121 -404.837773) (xy 75.229823 -404.822419) (xy 75.180242 -404.799779) (xy 75.134388 -404.770314)
			(xy 75.093195 -404.734622) (xy 75.057501 -404.693431) (xy 75.028032 -404.647579) (xy 75.005389 -404.598)
			(xy 74.990033 -404.545703) (xy 74.982275 -404.491753) (xy 73.544765 -404.491753) (xy 73.544765 -404.491755)
			(xy 73.537007 -404.54571) (xy 73.52165 -404.598012) (xy 73.499005 -404.647596) (xy 73.469534 -404.693452)
			(xy 73.433836 -404.734648) (xy 73.39264 -404.770343) (xy 73.346782 -404.799812) (xy 73.297197 -404.822455)
			(xy 73.244895 -404.837811) (xy 73.190939 -404.845566) (xy 73.163684 -404.846028) (xy 72.300084 -404.846028)
			(xy 72.272835 -404.845501) (xy 72.218892 -404.837743) (xy 72.166602 -404.822387) (xy 72.117029 -404.799746)
			(xy 72.071183 -404.770281) (xy 72.029997 -404.734591) (xy 71.994309 -404.693404) (xy 71.964846 -404.647557)
			(xy 71.942207 -404.597983) (xy 71.926854 -404.545692) (xy 71.919098 -404.491749) (xy 70.481442 -404.491749)
			(xy 70.481442 -404.491751) (xy 70.473687 -404.545697) (xy 70.458333 -404.597991) (xy 70.435694 -404.647568)
			(xy 70.40623 -404.693419) (xy 70.370541 -404.73461) (xy 70.329354 -404.770304) (xy 70.283507 -404.799773)
			(xy 70.233933 -404.822417) (xy 70.18164 -404.837777) (xy 70.127695 -404.845539) (xy 70.100444 -404.846028)
			(xy 69.236844 -404.846028) (xy 69.209591 -404.845528) (xy 69.155638 -404.837776) (xy 69.103337 -404.822425)
			(xy 69.053754 -404.799786) (xy 69.007898 -404.770321) (xy 68.966702 -404.734629) (xy 68.931006 -404.693437)
			(xy 68.901535 -404.647584) (xy 68.878891 -404.598004) (xy 68.863533 -404.545705) (xy 68.855775 -404.491753)
			(xy 67.418242 -404.491753) (xy 67.410485 -404.545703) (xy 67.39513 -404.598) (xy 67.372488 -404.647579)
			(xy 67.34302 -404.693432) (xy 67.307327 -404.734624) (xy 67.266135 -404.770318) (xy 67.220283 -404.799786)
			(xy 67.170704 -404.822428) (xy 67.118407 -404.837785) (xy 67.064456 -404.845542) (xy 67.037204 -404.846028)
			(xy 66.173604 -404.846028) (xy 66.146352 -404.845525) (xy 66.092404 -404.837769) (xy 66.040108 -404.822414)
			(xy 65.99053 -404.799773) (xy 65.944679 -404.770307) (xy 65.903488 -404.734615) (xy 65.867796 -404.693424)
			(xy 65.838329 -404.647573) (xy 65.815687 -404.597995) (xy 65.800332 -404.5457) (xy 65.792575 -404.491752)
			(xy 64.355065 -404.491752) (xy 64.355065 -404.491756) (xy 64.347307 -404.545713) (xy 64.331948 -404.598016)
			(xy 64.309302 -404.647602) (xy 64.279829 -404.693459) (xy 64.244129 -404.734655) (xy 64.20293 -404.77035)
			(xy 64.15707 -404.799819) (xy 64.107483 -404.822461) (xy 64.055178 -404.837814) (xy 64.00122 -404.845568)
			(xy 63.973964 -404.846028) (xy 63.110364 -404.846028) (xy 63.083116 -404.845499) (xy 63.029175 -404.837739)
			(xy 62.976887 -404.822382) (xy 62.927317 -404.79974) (xy 62.881474 -404.770274) (xy 62.84029 -404.734584)
			(xy 62.804604 -404.693397) (xy 62.775143 -404.647551) (xy 62.752506 -404.597979) (xy 62.737153 -404.54569)
			(xy 62.729398 -404.491748) (xy 61.291742 -404.491748) (xy 61.291742 -404.491752) (xy 61.283986 -404.5457)
			(xy 61.268631 -404.597996) (xy 61.245991 -404.647574) (xy 61.216525 -404.693425) (xy 61.180834 -404.734617)
			(xy 61.139645 -404.770311) (xy 61.093795 -404.799779) (xy 61.044218 -404.822423) (xy 60.991924 -404.837781)
			(xy 60.937976 -404.845541) (xy 60.910724 -404.846028) (xy 60.047124 -404.846028) (xy 60.019871 -404.845526)
			(xy 59.965921 -404.837773) (xy 59.913623 -404.822419) (xy 59.864042 -404.799779) (xy 59.818188 -404.770314)
			(xy 59.776995 -404.734622) (xy 59.741301 -404.693431) (xy 59.711832 -404.647579) (xy 59.689189 -404.598)
			(xy 59.673833 -404.545703) (xy 59.666075 -404.491753) (xy 58.228565 -404.491753) (xy 58.228565 -404.491755)
			(xy 58.220807 -404.54571) (xy 58.20545 -404.598012) (xy 58.182805 -404.647596) (xy 58.153334 -404.693452)
			(xy 58.117636 -404.734648) (xy 58.07644 -404.770343) (xy 58.030582 -404.799812) (xy 57.980997 -404.822455)
			(xy 57.928695 -404.837811) (xy 57.874739 -404.845566) (xy 57.847484 -404.846028) (xy 56.983884 -404.846028)
			(xy 56.956635 -404.845501) (xy 56.902692 -404.837743) (xy 56.850402 -404.822387) (xy 56.800829 -404.799746)
			(xy 56.754983 -404.770281) (xy 56.713797 -404.734591) (xy 56.678109 -404.693404) (xy 56.648646 -404.647557)
			(xy 56.626007 -404.597983) (xy 56.610654 -404.545692) (xy 56.602898 -404.491749) (xy 55.165242 -404.491749)
			(xy 55.165242 -404.491751) (xy 55.157487 -404.545697) (xy 55.142133 -404.597991) (xy 55.119494 -404.647568)
			(xy 55.09003 -404.693419) (xy 55.054341 -404.73461) (xy 55.013154 -404.770304) (xy 54.967307 -404.799773)
			(xy 54.917733 -404.822417) (xy 54.86544 -404.837777) (xy 54.811495 -404.845539) (xy 54.784244 -404.846028)
			(xy 53.920644 -404.846028) (xy 53.893391 -404.845528) (xy 53.839438 -404.837776) (xy 53.787137 -404.822425)
			(xy 53.737554 -404.799786) (xy 53.691698 -404.770321) (xy 53.650502 -404.734629) (xy 53.614806 -404.693437)
			(xy 53.585335 -404.647584) (xy 53.562691 -404.598004) (xy 53.547333 -404.545705) (xy 53.539575 -404.491753)
			(xy 52.102042 -404.491753) (xy 52.094285 -404.545703) (xy 52.07893 -404.598) (xy 52.056288 -404.647579)
			(xy 52.02682 -404.693432) (xy 51.991127 -404.734624) (xy 51.949935 -404.770318) (xy 51.904083 -404.799786)
			(xy 51.854504 -404.822428) (xy 51.802207 -404.837785) (xy 51.748256 -404.845542) (xy 51.721004 -404.846028)
			(xy 50.857404 -404.846028) (xy 50.830152 -404.845525) (xy 50.776204 -404.837769) (xy 50.723908 -404.822414)
			(xy 50.67433 -404.799773) (xy 50.628479 -404.770307) (xy 50.587288 -404.734615) (xy 50.551596 -404.693424)
			(xy 50.522129 -404.647573) (xy 50.499487 -404.597995) (xy 50.484132 -404.5457) (xy 50.476375 -404.491752)
			(xy 49.038865 -404.491752) (xy 49.038865 -404.491756) (xy 49.031107 -404.545713) (xy 49.015748 -404.598016)
			(xy 48.993102 -404.647602) (xy 48.963629 -404.693459) (xy 48.927929 -404.734655) (xy 48.88673 -404.77035)
			(xy 48.84087 -404.799819) (xy 48.791283 -404.822461) (xy 48.738978 -404.837814) (xy 48.68502 -404.845568)
			(xy 48.657764 -404.846028) (xy 47.794164 -404.846028) (xy 47.766916 -404.845499) (xy 47.712975 -404.837739)
			(xy 47.660687 -404.822382) (xy 47.611117 -404.79974) (xy 47.565274 -404.770274) (xy 47.52409 -404.734584)
			(xy 47.488404 -404.693397) (xy 47.458943 -404.647551) (xy 47.436306 -404.597979) (xy 47.420953 -404.54569)
			(xy 47.413198 -404.491748) (xy 45.559703 -404.491748) (xy 45.562463 -404.52264) (xy 45.570405 -404.70075)
			(xy 45.570902 -404.789894) (xy 45.570405 -404.879038) (xy 45.562463 -405.057148) (xy 45.546595 -405.234728)
			(xy 45.522831 -405.411424) (xy 45.49122 -405.586887) (xy 45.479552 -405.638385) (xy 104.009796 -405.638385)
			(xy 104.013672 -405.584006) (xy 104.025246 -405.530732) (xy 104.044281 -405.479646) (xy 104.070391 -405.431789)
			(xy 104.103044 -405.388132) (xy 104.121966 -405.368506) (xy 104.732582 -404.757636) (xy 104.75423 -404.736857)
			(xy 104.802784 -404.701606) (xy 104.856253 -404.67438) (xy 104.91332 -404.655848) (xy 104.972583 -404.646465)
			(xy 105.002584 -404.645876) (xy 105.029856 -404.646316) (xy 105.083846 -404.654077) (xy 105.136181 -404.669444)
			(xy 105.185797 -404.692102) (xy 105.231683 -404.721592) (xy 105.272904 -404.757312) (xy 105.308622 -404.798535)
			(xy 105.338108 -404.844422) (xy 105.360764 -404.894039) (xy 105.376127 -404.946376) (xy 105.383885 -405.000366)
			(xy 105.384346 -405.027638) (xy 105.383744 -405.057639) (xy 105.374371 -405.116904) (xy 105.355845 -405.173974)
			(xy 105.328623 -405.227445) (xy 105.29971 -405.267273) (xy 106.824184 -405.267273) (xy 106.824184 -405.212727)
			(xy 106.831947 -405.158735) (xy 106.847315 -405.106398) (xy 106.869976 -405.05678) (xy 106.899467 -405.010893)
			(xy 106.935189 -404.969671) (xy 106.976414 -404.933951) (xy 107.022303 -404.904463) (xy 107.071922 -404.881806)
			(xy 107.12426 -404.866441) (xy 107.178252 -404.858682) (xy 107.205526 -404.85822) (xy 108.069126 -404.85822)
			(xy 108.096393 -404.858744) (xy 108.150371 -404.866508) (xy 108.202695 -404.881875) (xy 108.2523 -404.904532)
			(xy 108.298175 -404.934017) (xy 108.339388 -404.969731) (xy 108.375098 -405.010946) (xy 108.404581 -405.056823)
			(xy 108.427234 -405.106429) (xy 108.442597 -405.158754) (xy 108.450358 -405.212733) (xy 108.450358 -405.267267)
			(xy 108.442597 -405.321246) (xy 108.427234 -405.373571) (xy 108.404581 -405.423177) (xy 108.375098 -405.469054)
			(xy 108.339388 -405.510269) (xy 108.298175 -405.545983) (xy 108.2523 -405.575468) (xy 108.202695 -405.598125)
			(xy 108.150371 -405.613492) (xy 108.096393 -405.621256) (xy 108.069126 -405.621744) (xy 107.205526 -405.621744)
			(xy 107.178252 -405.621318) (xy 107.12426 -405.613559) (xy 107.071922 -405.598194) (xy 107.022303 -405.575537)
			(xy 106.976414 -405.546049) (xy 106.935189 -405.510329) (xy 106.899467 -405.469107) (xy 106.869976 -405.42322)
			(xy 106.847315 -405.373602) (xy 106.831947 -405.321265) (xy 106.824184 -405.267273) (xy 105.29971 -405.267273)
			(xy 105.293374 -405.276001) (xy 105.272586 -405.29764) (xy 104.661716 -405.908256) (xy 104.642167 -405.927256)
			(xy 104.598511 -405.959909) (xy 104.550654 -405.986019) (xy 104.499568 -406.005054) (xy 104.446294 -406.016628)
			(xy 104.391915 -406.020504) (xy 104.337538 -406.016603) (xy 104.284269 -406.005006) (xy 104.233192 -405.985949)
			(xy 104.185346 -405.959818) (xy 104.141704 -405.927145) (xy 104.103155 -405.888596) (xy 104.070482 -405.844954)
			(xy 104.044351 -405.797108) (xy 104.025294 -405.746031) (xy 104.013697 -405.692762) (xy 104.009796 -405.638385)
			(xy 45.479552 -405.638385) (xy 45.451824 -405.760767) (xy 45.404722 -405.93272) (xy 45.350006 -406.102404)
			(xy 45.287785 -406.269481) (xy 45.218184 -406.433622) (xy 45.141339 -406.594498) (xy 45.057405 -406.751792)
			(xy 44.966547 -406.905191) (xy 44.883756 -407.031749) (xy 48.944798 -407.031749) (xy 48.944798 -406.977251)
			(xy 48.952554 -406.923308) (xy 48.967907 -406.871017) (xy 48.990546 -406.821443) (xy 49.020009 -406.775596)
			(xy 49.055697 -406.734409) (xy 49.096883 -406.698719) (xy 49.142729 -406.669254) (xy 49.192302 -406.646613)
			(xy 49.244592 -406.631257) (xy 49.298535 -406.623499) (xy 49.325784 -406.623012) (xy 50.189384 -406.623012)
			(xy 50.216639 -406.623434) (xy 50.270595 -406.631189) (xy 50.322897 -406.646545) (xy 50.372482 -406.669188)
			(xy 50.41834 -406.698657) (xy 50.459536 -406.734352) (xy 50.495234 -406.775548) (xy 50.524705 -406.821404)
			(xy 50.54735 -406.870988) (xy 50.562707 -406.92329) (xy 50.570465 -406.977245) (xy 50.570465 -407.031753)
			(xy 52.007975 -407.031753) (xy 52.007975 -406.977247) (xy 52.015733 -406.923297) (xy 52.031089 -406.871)
			(xy 52.053732 -406.821421) (xy 52.083201 -406.775569) (xy 52.118895 -406.734378) (xy 52.160088 -406.698686)
			(xy 52.205942 -406.669221) (xy 52.255523 -406.646581) (xy 52.307821 -406.631227) (xy 52.361771 -406.623474)
			(xy 52.389024 -406.623012) (xy 53.252624 -406.623012) (xy 53.279876 -406.623459) (xy 53.333824 -406.631219)
			(xy 53.386118 -406.646577) (xy 53.435695 -406.669221) (xy 53.481545 -406.698689) (xy 53.522734 -406.734383)
			(xy 53.558425 -406.775575) (xy 53.587891 -406.821426) (xy 53.610531 -406.871004) (xy 53.625886 -406.9233)
			(xy 53.633642 -406.977248) (xy 53.633642 -407.031748) (xy 55.071298 -407.031748) (xy 55.071298 -406.977252)
			(xy 55.079053 -406.92331) (xy 55.094406 -406.871021) (xy 55.117043 -406.821449) (xy 55.146504 -406.775603)
			(xy 55.18219 -406.734416) (xy 55.223374 -406.698726) (xy 55.269217 -406.66926) (xy 55.318787 -406.646618)
			(xy 55.371075 -406.631261) (xy 55.425016 -406.623501) (xy 55.452264 -406.623012) (xy 56.315864 -406.623012)
			(xy 56.34312 -406.623432) (xy 56.397078 -406.631186) (xy 56.449383 -406.646539) (xy 56.49897 -406.669181)
			(xy 56.54483 -406.69865) (xy 56.586029 -406.734345) (xy 56.621729 -406.775541) (xy 56.651202 -406.821398)
			(xy 56.673848 -406.870984) (xy 56.689207 -406.923287) (xy 56.696965 -406.977244) (xy 56.696965 -407.031752)
			(xy 58.134475 -407.031752) (xy 58.134475 -406.977248) (xy 58.142232 -406.9233) (xy 58.157587 -406.871005)
			(xy 58.180229 -406.821427) (xy 58.209696 -406.775576) (xy 58.245388 -406.734385) (xy 58.286579 -406.698693)
			(xy 58.33243 -406.669227) (xy 58.382008 -406.646586) (xy 58.434304 -406.631231) (xy 58.488252 -406.623475)
			(xy 58.515504 -406.623012) (xy 59.379104 -406.623012) (xy 59.406356 -406.623458) (xy 59.460307 -406.631215)
			(xy 59.512604 -406.646572) (xy 59.562183 -406.669214) (xy 59.608035 -406.698682) (xy 59.649227 -406.734376)
			(xy 59.68492 -406.775568) (xy 59.714388 -406.821421) (xy 59.73703 -406.871) (xy 59.752385 -406.923297)
			(xy 59.760142 -406.977248) (xy 59.760142 -407.031752) (xy 59.760142 -407.031753) (xy 61.197675 -407.031753)
			(xy 61.197675 -406.977247) (xy 61.205433 -406.923295) (xy 61.220791 -406.870996) (xy 61.243435 -406.821416)
			(xy 61.272906 -406.775563) (xy 61.308602 -406.734371) (xy 61.349798 -406.698679) (xy 61.395654 -406.669214)
			(xy 61.445237 -406.646575) (xy 61.497538 -406.631224) (xy 61.551491 -406.623472) (xy 61.578744 -406.623012)
			(xy 62.442344 -406.623012) (xy 62.469595 -406.623461) (xy 62.52354 -406.631223) (xy 62.575833 -406.646583)
			(xy 62.625407 -406.669227) (xy 62.671254 -406.698696) (xy 62.712441 -406.73439) (xy 62.74813 -406.775581)
			(xy 62.777594 -406.821432) (xy 62.800233 -406.871009) (xy 62.815587 -406.923303) (xy 62.823342 -406.977249)
			(xy 62.823342 -407.031749) (xy 64.260998 -407.031749) (xy 64.260998 -406.977251) (xy 64.268754 -406.923308)
			(xy 64.284107 -406.871017) (xy 64.306746 -406.821443) (xy 64.336209 -406.775596) (xy 64.371897 -406.734409)
			(xy 64.413083 -406.698719) (xy 64.458929 -406.669254) (xy 64.508502 -406.646613) (xy 64.560792 -406.631257)
			(xy 64.614735 -406.623499) (xy 64.641984 -406.623012) (xy 65.505584 -406.623012) (xy 65.532839 -406.623434)
			(xy 65.586795 -406.631189) (xy 65.639097 -406.646545) (xy 65.688682 -406.669188) (xy 65.73454 -406.698657)
			(xy 65.775736 -406.734352) (xy 65.811434 -406.775548) (xy 65.840905 -406.821404) (xy 65.86355 -406.870988)
			(xy 65.878907 -406.92329) (xy 65.886665 -406.977245) (xy 65.886665 -407.031753) (xy 67.324175 -407.031753)
			(xy 67.324175 -406.977247) (xy 67.331933 -406.923297) (xy 67.347289 -406.871) (xy 67.369932 -406.821421)
			(xy 67.399401 -406.775569) (xy 67.435095 -406.734378) (xy 67.476288 -406.698686) (xy 67.522142 -406.669221)
			(xy 67.571723 -406.646581) (xy 67.624021 -406.631227) (xy 67.677971 -406.623474) (xy 67.705224 -406.623012)
			(xy 68.568824 -406.623012) (xy 68.596076 -406.623459) (xy 68.650024 -406.631219) (xy 68.702318 -406.646577)
			(xy 68.751895 -406.669221) (xy 68.797745 -406.698689) (xy 68.838934 -406.734383) (xy 68.874625 -406.775575)
			(xy 68.904091 -406.821426) (xy 68.926731 -406.871004) (xy 68.942086 -406.9233) (xy 68.949842 -406.977248)
			(xy 68.949842 -407.031748) (xy 70.387498 -407.031748) (xy 70.387498 -406.977252) (xy 70.395253 -406.92331)
			(xy 70.410606 -406.871021) (xy 70.433243 -406.821449) (xy 70.462704 -406.775603) (xy 70.49839 -406.734416)
			(xy 70.539574 -406.698726) (xy 70.585417 -406.66926) (xy 70.634987 -406.646618) (xy 70.687275 -406.631261)
			(xy 70.741216 -406.623501) (xy 70.768464 -406.623012) (xy 71.632064 -406.623012) (xy 71.65932 -406.623432)
			(xy 71.713278 -406.631186) (xy 71.765583 -406.646539) (xy 71.81517 -406.669181) (xy 71.86103 -406.69865)
			(xy 71.902229 -406.734345) (xy 71.937929 -406.775541) (xy 71.967402 -406.821398) (xy 71.990048 -406.870984)
			(xy 72.005407 -406.923287) (xy 72.013165 -406.977244) (xy 72.013165 -407.031752) (xy 73.450675 -407.031752)
			(xy 73.450675 -406.977248) (xy 73.458432 -406.9233) (xy 73.473787 -406.871005) (xy 73.496429 -406.821427)
			(xy 73.525896 -406.775576) (xy 73.561588 -406.734385) (xy 73.602779 -406.698693) (xy 73.64863 -406.669227)
			(xy 73.698208 -406.646586) (xy 73.750504 -406.631231) (xy 73.804452 -406.623475) (xy 73.831704 -406.623012)
			(xy 74.695304 -406.623012) (xy 74.722556 -406.623458) (xy 74.776507 -406.631215) (xy 74.828804 -406.646572)
			(xy 74.878383 -406.669214) (xy 74.924235 -406.698682) (xy 74.965427 -406.734376) (xy 75.00112 -406.775568)
			(xy 75.030588 -406.821421) (xy 75.05323 -406.871) (xy 75.068585 -406.923297) (xy 75.076342 -406.977248)
			(xy 75.076342 -407.031752) (xy 75.076342 -407.031753) (xy 76.513875 -407.031753) (xy 76.513875 -406.977247)
			(xy 76.521633 -406.923295) (xy 76.536991 -406.870996) (xy 76.559635 -406.821416) (xy 76.589106 -406.775563)
			(xy 76.624802 -406.734371) (xy 76.665998 -406.698679) (xy 76.711854 -406.669214) (xy 76.761437 -406.646575)
			(xy 76.813738 -406.631224) (xy 76.867691 -406.623472) (xy 76.894944 -406.623012) (xy 77.758544 -406.623012)
			(xy 77.785795 -406.623461) (xy 77.83974 -406.631223) (xy 77.892033 -406.646583) (xy 77.941607 -406.669227)
			(xy 77.987454 -406.698696) (xy 78.028641 -406.73439) (xy 78.06433 -406.775581) (xy 78.093794 -406.821432)
			(xy 78.116433 -406.871009) (xy 78.131787 -406.923303) (xy 78.139542 -406.977249) (xy 78.139542 -407.031749)
			(xy 79.577198 -407.031749) (xy 79.577198 -406.977251) (xy 79.584954 -406.923308) (xy 79.600307 -406.871017)
			(xy 79.622946 -406.821443) (xy 79.652409 -406.775596) (xy 79.688097 -406.734409) (xy 79.729283 -406.698719)
			(xy 79.775129 -406.669254) (xy 79.824702 -406.646613) (xy 79.876992 -406.631257) (xy 79.930935 -406.623499)
			(xy 79.958184 -406.623012) (xy 80.821784 -406.623012) (xy 80.849039 -406.623434) (xy 80.902995 -406.631189)
			(xy 80.955297 -406.646545) (xy 81.004882 -406.669188) (xy 81.05074 -406.698657) (xy 81.091936 -406.734352)
			(xy 81.127634 -406.775548) (xy 81.157105 -406.821404) (xy 81.17975 -406.870988) (xy 81.195107 -406.92329)
			(xy 81.202865 -406.977245) (xy 81.202865 -407.031753) (xy 82.640375 -407.031753) (xy 82.640375 -406.977247)
			(xy 82.648133 -406.923297) (xy 82.663489 -406.871) (xy 82.686132 -406.821421) (xy 82.715601 -406.775569)
			(xy 82.751295 -406.734378) (xy 82.792488 -406.698686) (xy 82.838342 -406.669221) (xy 82.887923 -406.646581)
			(xy 82.940221 -406.631227) (xy 82.994171 -406.623474) (xy 83.021424 -406.623012) (xy 83.885024 -406.623012)
			(xy 83.912276 -406.623459) (xy 83.966224 -406.631219) (xy 84.018518 -406.646577) (xy 84.068095 -406.669221)
			(xy 84.113945 -406.698689) (xy 84.155134 -406.734383) (xy 84.190825 -406.775575) (xy 84.220291 -406.821426)
			(xy 84.242931 -406.871004) (xy 84.258286 -406.9233) (xy 84.266042 -406.977248) (xy 84.266042 -407.031748)
			(xy 85.703698 -407.031748) (xy 85.703698 -406.977252) (xy 85.711453 -406.92331) (xy 85.726806 -406.871021)
			(xy 85.749443 -406.821449) (xy 85.778904 -406.775603) (xy 85.81459 -406.734416) (xy 85.855774 -406.698726)
			(xy 85.901617 -406.66926) (xy 85.951187 -406.646618) (xy 86.003475 -406.631261) (xy 86.057416 -406.623501)
			(xy 86.084664 -406.623012) (xy 86.948264 -406.623012) (xy 86.97552 -406.623432) (xy 87.029478 -406.631186)
			(xy 87.081783 -406.646539) (xy 87.13137 -406.669181) (xy 87.17723 -406.69865) (xy 87.218429 -406.734345)
			(xy 87.254129 -406.775541) (xy 87.283602 -406.821398) (xy 87.306248 -406.870984) (xy 87.321607 -406.923287)
			(xy 87.329365 -406.977244) (xy 87.329365 -407.031752) (xy 88.766875 -407.031752) (xy 88.766875 -406.977248)
			(xy 88.774632 -406.9233) (xy 88.789987 -406.871005) (xy 88.812629 -406.821427) (xy 88.842096 -406.775576)
			(xy 88.877788 -406.734385) (xy 88.918979 -406.698693) (xy 88.96483 -406.669227) (xy 89.014408 -406.646586)
			(xy 89.066704 -406.631231) (xy 89.120652 -406.623475) (xy 89.147904 -406.623012) (xy 90.011504 -406.623012)
			(xy 90.038756 -406.623458) (xy 90.092707 -406.631215) (xy 90.145004 -406.646572) (xy 90.194583 -406.669214)
			(xy 90.240435 -406.698682) (xy 90.281627 -406.734376) (xy 90.31732 -406.775568) (xy 90.346788 -406.821421)
			(xy 90.36943 -406.871) (xy 90.384785 -406.923297) (xy 90.392542 -406.977248) (xy 90.392542 -407.031752)
			(xy 90.392542 -407.031753) (xy 91.830075 -407.031753) (xy 91.830075 -406.977247) (xy 91.837833 -406.923295)
			(xy 91.853191 -406.870996) (xy 91.875835 -406.821416) (xy 91.905306 -406.775563) (xy 91.941002 -406.734371)
			(xy 91.982198 -406.698679) (xy 92.028054 -406.669214) (xy 92.077637 -406.646575) (xy 92.129938 -406.631224)
			(xy 92.183891 -406.623472) (xy 92.211144 -406.623012) (xy 93.074744 -406.623012) (xy 93.101995 -406.623461)
			(xy 93.15594 -406.631223) (xy 93.208233 -406.646583) (xy 93.257807 -406.669227) (xy 93.303654 -406.698696)
			(xy 93.344841 -406.73439) (xy 93.38053 -406.775581) (xy 93.409994 -406.821432) (xy 93.432633 -406.871009)
			(xy 93.447987 -406.923303) (xy 93.455742 -406.977249) (xy 93.455742 -407.031749) (xy 94.893398 -407.031749)
			(xy 94.893398 -406.977251) (xy 94.901154 -406.923308) (xy 94.916507 -406.871017) (xy 94.939146 -406.821443)
			(xy 94.968609 -406.775596) (xy 95.004297 -406.734409) (xy 95.045483 -406.698719) (xy 95.091329 -406.669254)
			(xy 95.140902 -406.646613) (xy 95.193192 -406.631257) (xy 95.247135 -406.623499) (xy 95.274384 -406.623012)
			(xy 96.137984 -406.623012) (xy 96.165239 -406.623434) (xy 96.219195 -406.631189) (xy 96.271497 -406.646545)
			(xy 96.321082 -406.669188) (xy 96.36694 -406.698657) (xy 96.408136 -406.734352) (xy 96.443834 -406.775548)
			(xy 96.473305 -406.821404) (xy 96.49595 -406.870988) (xy 96.511307 -406.92329) (xy 96.519065 -406.977245)
			(xy 96.519065 -407.031753) (xy 116.044675 -407.031753) (xy 116.044675 -406.977247) (xy 116.052433 -406.923297)
			(xy 116.067789 -406.871) (xy 116.090432 -406.821421) (xy 116.119901 -406.775569) (xy 116.155596 -406.734377)
			(xy 116.196789 -406.698686) (xy 116.242643 -406.66922) (xy 116.292224 -406.64658) (xy 116.344522 -406.631227)
			(xy 116.398473 -406.623474) (xy 116.425726 -406.623012) (xy 117.289326 -406.623012) (xy 117.316577 -406.62346)
			(xy 117.370525 -406.63122) (xy 117.42282 -406.646578) (xy 117.472396 -406.669222) (xy 117.518246 -406.69869)
			(xy 117.559435 -406.734383) (xy 117.595126 -406.775575) (xy 117.624591 -406.821427) (xy 117.647231 -406.871005)
			(xy 117.662586 -406.9233) (xy 117.670342 -406.977249) (xy 117.670342 -407.031748) (xy 119.107998 -407.031748)
			(xy 119.107998 -406.977252) (xy 119.115753 -406.92331) (xy 119.131106 -406.871021) (xy 119.153743 -406.821448)
			(xy 119.183205 -406.775602) (xy 119.218891 -406.734415) (xy 119.260075 -406.698725) (xy 119.305918 -406.66926)
			(xy 119.355489 -406.646618) (xy 119.407777 -406.631261) (xy 119.461718 -406.623501) (xy 119.488966 -406.623012)
			(xy 120.352566 -406.623012) (xy 120.379822 -406.623433) (xy 120.433779 -406.631186) (xy 120.486084 -406.64654)
			(xy 120.535671 -406.669182) (xy 120.581531 -406.69865) (xy 120.62273 -406.734346) (xy 120.658429 -406.775542)
			(xy 120.687902 -406.821399) (xy 120.710548 -406.870984) (xy 120.725907 -406.923287) (xy 120.733665 -406.977244)
			(xy 120.733665 -407.031752) (xy 122.171175 -407.031752) (xy 122.171175 -406.977248) (xy 122.178932 -406.9233)
			(xy 122.194288 -406.871004) (xy 122.216929 -406.821426) (xy 122.246396 -406.775575) (xy 122.282089 -406.734384)
			(xy 122.32328 -406.698693) (xy 122.369131 -406.669226) (xy 122.41871 -406.646585) (xy 122.471006 -406.631231)
			(xy 122.524954 -406.623475) (xy 122.552206 -406.623012) (xy 123.415806 -406.623012) (xy 123.443058 -406.623458)
			(xy 123.497008 -406.631216) (xy 123.549305 -406.646572) (xy 123.598884 -406.669215) (xy 123.644736 -406.698683)
			(xy 123.685928 -406.734376) (xy 123.721621 -406.775569) (xy 123.751088 -406.821421) (xy 123.77373 -406.871001)
			(xy 123.789085 -406.923298) (xy 123.796842 -406.977248) (xy 123.796842 -407.031752) (xy 123.796842 -407.031754)
			(xy 125.234375 -407.031754) (xy 125.234375 -406.977246) (xy 125.242133 -406.923294) (xy 125.257491 -406.870996)
			(xy 125.280135 -406.821415) (xy 125.309606 -406.775562) (xy 125.345303 -406.73437) (xy 125.386499 -406.698679)
			(xy 125.432355 -406.669213) (xy 125.481939 -406.646575) (xy 125.534239 -406.631223) (xy 125.588192 -406.623472)
			(xy 125.615446 -406.623012) (xy 126.479046 -406.623012) (xy 126.506297 -406.623461) (xy 126.560242 -406.631223)
			(xy 126.612534 -406.646583) (xy 126.662108 -406.669228) (xy 126.707955 -406.698697) (xy 126.749142 -406.734391)
			(xy 126.78483 -406.775582) (xy 126.814294 -406.821432) (xy 126.836933 -406.871009) (xy 126.852287 -406.923303)
			(xy 126.860042 -406.977249) (xy 126.860042 -407.031749) (xy 128.297698 -407.031749) (xy 128.297698 -406.977251)
			(xy 128.305454 -406.923307) (xy 128.320808 -406.871016) (xy 128.343446 -406.821443) (xy 128.37291 -406.775596)
			(xy 128.408598 -406.734408) (xy 128.449784 -406.698718) (xy 128.49563 -406.669253) (xy 128.545203 -406.646612)
			(xy 128.597494 -406.631257) (xy 128.651437 -406.623499) (xy 128.678686 -406.623012) (xy 129.542286 -406.623012)
			(xy 129.569541 -406.623434) (xy 129.623496 -406.63119) (xy 129.675799 -406.646545) (xy 129.725383 -406.669188)
			(xy 129.771241 -406.698657) (xy 129.812437 -406.734353) (xy 129.848134 -406.775548) (xy 129.877605 -406.821405)
			(xy 129.90025 -406.870988) (xy 129.915607 -406.92329) (xy 129.923365 -406.977245) (xy 129.923365 -407.031753)
			(xy 131.360875 -407.031753) (xy 131.360875 -406.977247) (xy 131.368633 -406.923297) (xy 131.383989 -406.871)
			(xy 131.406632 -406.821421) (xy 131.436101 -406.775569) (xy 131.471796 -406.734377) (xy 131.512989 -406.698686)
			(xy 131.558843 -406.66922) (xy 131.608424 -406.64658) (xy 131.660722 -406.631227) (xy 131.714673 -406.623474)
			(xy 131.741926 -406.623012) (xy 132.605526 -406.623012) (xy 132.632777 -406.62346) (xy 132.686725 -406.63122)
			(xy 132.73902 -406.646578) (xy 132.788596 -406.669222) (xy 132.834446 -406.69869) (xy 132.875635 -406.734383)
			(xy 132.911326 -406.775575) (xy 132.940791 -406.821427) (xy 132.963431 -406.871005) (xy 132.978786 -406.9233)
			(xy 132.986542 -406.977249) (xy 132.986542 -407.031748) (xy 134.424198 -407.031748) (xy 134.424198 -406.977252)
			(xy 134.431953 -406.92331) (xy 134.447306 -406.871021) (xy 134.469943 -406.821448) (xy 134.499405 -406.775602)
			(xy 134.535091 -406.734415) (xy 134.576275 -406.698725) (xy 134.622118 -406.66926) (xy 134.671689 -406.646618)
			(xy 134.723977 -406.631261) (xy 134.777918 -406.623501) (xy 134.805166 -406.623012) (xy 135.668766 -406.623012)
			(xy 135.696022 -406.623433) (xy 135.749979 -406.631186) (xy 135.802284 -406.64654) (xy 135.851871 -406.669182)
			(xy 135.897731 -406.69865) (xy 135.93893 -406.734346) (xy 135.974629 -406.775542) (xy 136.004102 -406.821399)
			(xy 136.026748 -406.870984) (xy 136.042107 -406.923287) (xy 136.049865 -406.977244) (xy 136.049865 -407.031752)
			(xy 137.487375 -407.031752) (xy 137.487375 -406.977248) (xy 137.495132 -406.9233) (xy 137.510488 -406.871004)
			(xy 137.533129 -406.821426) (xy 137.562596 -406.775575) (xy 137.598289 -406.734384) (xy 137.63948 -406.698693)
			(xy 137.685331 -406.669226) (xy 137.73491 -406.646585) (xy 137.787206 -406.631231) (xy 137.841154 -406.623475)
			(xy 137.868406 -406.623012) (xy 138.732006 -406.623012) (xy 138.759258 -406.623458) (xy 138.813208 -406.631216)
			(xy 138.865505 -406.646572) (xy 138.915084 -406.669215) (xy 138.960936 -406.698683) (xy 139.002128 -406.734376)
			(xy 139.037821 -406.775569) (xy 139.067288 -406.821421) (xy 139.08993 -406.871001) (xy 139.105285 -406.923298)
			(xy 139.113042 -406.977248) (xy 139.113042 -407.031752) (xy 139.113042 -407.031754) (xy 140.550575 -407.031754)
			(xy 140.550575 -406.977246) (xy 140.558333 -406.923294) (xy 140.573691 -406.870996) (xy 140.596335 -406.821415)
			(xy 140.625806 -406.775562) (xy 140.661503 -406.73437) (xy 140.702699 -406.698679) (xy 140.748555 -406.669213)
			(xy 140.798139 -406.646575) (xy 140.850439 -406.631223) (xy 140.904392 -406.623472) (xy 140.931646 -406.623012)
			(xy 141.795246 -406.623012) (xy 141.822497 -406.623461) (xy 141.876442 -406.631223) (xy 141.928734 -406.646583)
			(xy 141.978308 -406.669228) (xy 142.024155 -406.698697) (xy 142.065342 -406.734391) (xy 142.10103 -406.775582)
			(xy 142.130494 -406.821432) (xy 142.153133 -406.871009) (xy 142.168487 -406.923303) (xy 142.176242 -406.977249)
			(xy 142.176242 -407.031749) (xy 143.613898 -407.031749) (xy 143.613898 -406.977251) (xy 143.621654 -406.923307)
			(xy 143.637008 -406.871016) (xy 143.659646 -406.821443) (xy 143.68911 -406.775596) (xy 143.724798 -406.734408)
			(xy 143.765984 -406.698718) (xy 143.81183 -406.669253) (xy 143.861403 -406.646612) (xy 143.913694 -406.631257)
			(xy 143.967637 -406.623499) (xy 143.994886 -406.623012) (xy 144.858486 -406.623012) (xy 144.885741 -406.623434)
			(xy 144.939696 -406.63119) (xy 144.991999 -406.646545) (xy 145.041583 -406.669188) (xy 145.087441 -406.698657)
			(xy 145.128637 -406.734353) (xy 145.164334 -406.775548) (xy 145.193805 -406.821405) (xy 145.21645 -406.870988)
			(xy 145.231807 -406.92329) (xy 145.239565 -406.977245) (xy 145.239565 -407.031753) (xy 146.677075 -407.031753)
			(xy 146.677075 -406.977247) (xy 146.684833 -406.923297) (xy 146.700189 -406.871) (xy 146.722832 -406.821421)
			(xy 146.752301 -406.775569) (xy 146.787996 -406.734377) (xy 146.829189 -406.698686) (xy 146.875043 -406.66922)
			(xy 146.924624 -406.64658) (xy 146.976922 -406.631227) (xy 147.030873 -406.623474) (xy 147.058126 -406.623012)
			(xy 147.921726 -406.623012) (xy 147.948977 -406.62346) (xy 148.002925 -406.63122) (xy 148.05522 -406.646578)
			(xy 148.104796 -406.669222) (xy 148.150646 -406.69869) (xy 148.191835 -406.734383) (xy 148.227526 -406.775575)
			(xy 148.256991 -406.821427) (xy 148.279631 -406.871005) (xy 148.294986 -406.9233) (xy 148.302742 -406.977249)
			(xy 148.302742 -407.031748) (xy 149.740398 -407.031748) (xy 149.740398 -406.977252) (xy 149.748153 -406.92331)
			(xy 149.763506 -406.871021) (xy 149.786143 -406.821448) (xy 149.815605 -406.775602) (xy 149.851291 -406.734415)
			(xy 149.892475 -406.698725) (xy 149.938318 -406.66926) (xy 149.987889 -406.646618) (xy 150.040177 -406.631261)
			(xy 150.094118 -406.623501) (xy 150.121366 -406.623012) (xy 150.984966 -406.623012) (xy 151.012222 -406.623433)
			(xy 151.066179 -406.631186) (xy 151.118484 -406.64654) (xy 151.168071 -406.669182) (xy 151.213931 -406.69865)
			(xy 151.25513 -406.734346) (xy 151.290829 -406.775542) (xy 151.320302 -406.821399) (xy 151.342948 -406.870984)
			(xy 151.358307 -406.923287) (xy 151.366065 -406.977244) (xy 151.366065 -407.031752) (xy 152.803575 -407.031752)
			(xy 152.803575 -406.977248) (xy 152.811332 -406.9233) (xy 152.826688 -406.871004) (xy 152.849329 -406.821426)
			(xy 152.878796 -406.775575) (xy 152.914489 -406.734384) (xy 152.95568 -406.698693) (xy 153.001531 -406.669226)
			(xy 153.05111 -406.646585) (xy 153.103406 -406.631231) (xy 153.157354 -406.623475) (xy 153.184606 -406.623012)
			(xy 154.048206 -406.623012) (xy 154.075458 -406.623458) (xy 154.129408 -406.631216) (xy 154.181705 -406.646572)
			(xy 154.231284 -406.669215) (xy 154.277136 -406.698683) (xy 154.318328 -406.734376) (xy 154.354021 -406.775569)
			(xy 154.383488 -406.821421) (xy 154.40613 -406.871001) (xy 154.421485 -406.923298) (xy 154.429242 -406.977248)
			(xy 154.429242 -407.031752) (xy 154.429242 -407.031754) (xy 155.866775 -407.031754) (xy 155.866775 -406.977246)
			(xy 155.874533 -406.923294) (xy 155.889891 -406.870996) (xy 155.912535 -406.821415) (xy 155.942006 -406.775562)
			(xy 155.977703 -406.73437) (xy 156.018899 -406.698679) (xy 156.064755 -406.669213) (xy 156.114339 -406.646575)
			(xy 156.166639 -406.631223) (xy 156.220592 -406.623472) (xy 156.247846 -406.623012) (xy 157.111446 -406.623012)
			(xy 157.138697 -406.623461) (xy 157.192642 -406.631223) (xy 157.244934 -406.646583) (xy 157.294508 -406.669228)
			(xy 157.340355 -406.698697) (xy 157.381542 -406.734391) (xy 157.41723 -406.775582) (xy 157.446694 -406.821432)
			(xy 157.469333 -406.871009) (xy 157.484687 -406.923303) (xy 157.492442 -406.977249) (xy 157.492442 -407.031749)
			(xy 158.930098 -407.031749) (xy 158.930098 -406.977251) (xy 158.937854 -406.923307) (xy 158.953208 -406.871016)
			(xy 158.975846 -406.821443) (xy 159.00531 -406.775596) (xy 159.040998 -406.734408) (xy 159.082184 -406.698718)
			(xy 159.12803 -406.669253) (xy 159.177603 -406.646612) (xy 159.229894 -406.631257) (xy 159.283837 -406.623499)
			(xy 159.311086 -406.623012) (xy 160.174686 -406.623012) (xy 160.201941 -406.623434) (xy 160.255896 -406.63119)
			(xy 160.308199 -406.646545) (xy 160.357783 -406.669188) (xy 160.403641 -406.698657) (xy 160.444837 -406.734353)
			(xy 160.480534 -406.775548) (xy 160.510005 -406.821405) (xy 160.53265 -406.870988) (xy 160.548007 -406.92329)
			(xy 160.555765 -406.977245) (xy 160.555765 -407.031753) (xy 161.993275 -407.031753) (xy 161.993275 -406.977247)
			(xy 162.001033 -406.923297) (xy 162.016389 -406.871) (xy 162.039032 -406.821421) (xy 162.068501 -406.775569)
			(xy 162.104196 -406.734377) (xy 162.145389 -406.698686) (xy 162.191243 -406.66922) (xy 162.240824 -406.64658)
			(xy 162.293122 -406.631227) (xy 162.347073 -406.623474) (xy 162.374326 -406.623012) (xy 163.237926 -406.623012)
			(xy 163.265177 -406.62346) (xy 163.319125 -406.63122) (xy 163.37142 -406.646578) (xy 163.420996 -406.669222)
			(xy 163.466846 -406.69869) (xy 163.508035 -406.734383) (xy 163.543726 -406.775575) (xy 163.573191 -406.821427)
			(xy 163.595831 -406.871005) (xy 163.611186 -406.9233) (xy 163.618942 -406.977249) (xy 163.618942 -407.031751)
			(xy 163.611186 -407.0857) (xy 163.595831 -407.137995) (xy 163.573191 -407.187573) (xy 163.543726 -407.233425)
			(xy 163.508035 -407.274617) (xy 163.466846 -407.31031) (xy 163.420996 -407.339778) (xy 163.37142 -407.362422)
			(xy 163.319125 -407.37778) (xy 163.265177 -407.38554) (xy 163.237926 -407.386028) (xy 162.374326 -407.386028)
			(xy 162.347073 -407.385526) (xy 162.293122 -407.377773) (xy 162.240824 -407.36242) (xy 162.191243 -407.33978)
			(xy 162.145389 -407.310314) (xy 162.104196 -407.274623) (xy 162.068501 -407.233431) (xy 162.039032 -407.187579)
			(xy 162.016389 -407.138) (xy 162.001033 -407.085703) (xy 161.993275 -407.031753) (xy 160.555765 -407.031753)
			(xy 160.555765 -407.031755) (xy 160.548007 -407.08571) (xy 160.53265 -407.138012) (xy 160.510005 -407.187595)
			(xy 160.480534 -407.233452) (xy 160.444837 -407.274647) (xy 160.403641 -407.310343) (xy 160.357783 -407.339812)
			(xy 160.308199 -407.362455) (xy 160.255896 -407.37781) (xy 160.201941 -407.385566) (xy 160.174686 -407.386028)
			(xy 159.311086 -407.386028) (xy 159.283837 -407.385501) (xy 159.229894 -407.377743) (xy 159.177603 -407.362388)
			(xy 159.12803 -407.339747) (xy 159.082184 -407.310282) (xy 159.040998 -407.274592) (xy 159.00531 -407.233404)
			(xy 158.975846 -407.187557) (xy 158.953208 -407.137984) (xy 158.937854 -407.085693) (xy 158.930098 -407.031749)
			(xy 157.492442 -407.031749) (xy 157.492442 -407.031751) (xy 157.484687 -407.085697) (xy 157.469333 -407.137991)
			(xy 157.446694 -407.187568) (xy 157.41723 -407.233418) (xy 157.381542 -407.274609) (xy 157.340355 -407.310303)
			(xy 157.294508 -407.339772) (xy 157.244934 -407.362417) (xy 157.192642 -407.377777) (xy 157.138697 -407.385539)
			(xy 157.111446 -407.386028) (xy 156.247846 -407.386028) (xy 156.220592 -407.385528) (xy 156.166639 -407.377777)
			(xy 156.114339 -407.362425) (xy 156.064755 -407.339787) (xy 156.018899 -407.310321) (xy 155.977703 -407.27463)
			(xy 155.942006 -407.233438) (xy 155.912535 -407.187585) (xy 155.889891 -407.138004) (xy 155.874533 -407.085706)
			(xy 155.866775 -407.031754) (xy 154.429242 -407.031754) (xy 154.421485 -407.085702) (xy 154.40613 -407.137999)
			(xy 154.383488 -407.187579) (xy 154.354021 -407.233431) (xy 154.318328 -407.274624) (xy 154.277136 -407.310317)
			(xy 154.231284 -407.339785) (xy 154.181705 -407.362428) (xy 154.129408 -407.377784) (xy 154.075458 -407.385542)
			(xy 154.048206 -407.386028) (xy 153.184606 -407.386028) (xy 153.157354 -407.385525) (xy 153.103406 -407.377769)
			(xy 153.05111 -407.362415) (xy 153.001531 -407.339774) (xy 152.95568 -407.310307) (xy 152.914489 -407.274616)
			(xy 152.878796 -407.233425) (xy 152.849329 -407.187574) (xy 152.826688 -407.137996) (xy 152.811332 -407.0857)
			(xy 152.803575 -407.031752) (xy 151.366065 -407.031752) (xy 151.366065 -407.031756) (xy 151.358307 -407.085713)
			(xy 151.342948 -407.138016) (xy 151.320302 -407.187601) (xy 151.290829 -407.233458) (xy 151.25513 -407.274654)
			(xy 151.213931 -407.31035) (xy 151.168071 -407.339818) (xy 151.118484 -407.36246) (xy 151.066179 -407.377814)
			(xy 151.012222 -407.385567) (xy 150.984966 -407.386028) (xy 150.121366 -407.386028) (xy 150.094118 -407.385499)
			(xy 150.040177 -407.377739) (xy 149.987889 -407.362382) (xy 149.938318 -407.33974) (xy 149.892475 -407.310275)
			(xy 149.851291 -407.274585) (xy 149.815605 -407.233398) (xy 149.786143 -407.187552) (xy 149.763506 -407.137979)
			(xy 149.748153 -407.08569) (xy 149.740398 -407.031748) (xy 148.302742 -407.031748) (xy 148.302742 -407.031751)
			(xy 148.294986 -407.0857) (xy 148.279631 -407.137995) (xy 148.256991 -407.187573) (xy 148.227526 -407.233425)
			(xy 148.191835 -407.274617) (xy 148.150646 -407.31031) (xy 148.104796 -407.339778) (xy 148.05522 -407.362422)
			(xy 148.002925 -407.37778) (xy 147.948977 -407.38554) (xy 147.921726 -407.386028) (xy 147.058126 -407.386028)
			(xy 147.030873 -407.385526) (xy 146.976922 -407.377773) (xy 146.924624 -407.36242) (xy 146.875043 -407.33978)
			(xy 146.829189 -407.310314) (xy 146.787996 -407.274623) (xy 146.752301 -407.233431) (xy 146.722832 -407.187579)
			(xy 146.700189 -407.138) (xy 146.684833 -407.085703) (xy 146.677075 -407.031753) (xy 145.239565 -407.031753)
			(xy 145.239565 -407.031755) (xy 145.231807 -407.08571) (xy 145.21645 -407.138012) (xy 145.193805 -407.187595)
			(xy 145.164334 -407.233452) (xy 145.128637 -407.274647) (xy 145.087441 -407.310343) (xy 145.041583 -407.339812)
			(xy 144.991999 -407.362455) (xy 144.939696 -407.37781) (xy 144.885741 -407.385566) (xy 144.858486 -407.386028)
			(xy 143.994886 -407.386028) (xy 143.967637 -407.385501) (xy 143.913694 -407.377743) (xy 143.861403 -407.362388)
			(xy 143.81183 -407.339747) (xy 143.765984 -407.310282) (xy 143.724798 -407.274592) (xy 143.68911 -407.233404)
			(xy 143.659646 -407.187557) (xy 143.637008 -407.137984) (xy 143.621654 -407.085693) (xy 143.613898 -407.031749)
			(xy 142.176242 -407.031749) (xy 142.176242 -407.031751) (xy 142.168487 -407.085697) (xy 142.153133 -407.137991)
			(xy 142.130494 -407.187568) (xy 142.10103 -407.233418) (xy 142.065342 -407.274609) (xy 142.024155 -407.310303)
			(xy 141.978308 -407.339772) (xy 141.928734 -407.362417) (xy 141.876442 -407.377777) (xy 141.822497 -407.385539)
			(xy 141.795246 -407.386028) (xy 140.931646 -407.386028) (xy 140.904392 -407.385528) (xy 140.850439 -407.377777)
			(xy 140.798139 -407.362425) (xy 140.748555 -407.339787) (xy 140.702699 -407.310321) (xy 140.661503 -407.27463)
			(xy 140.625806 -407.233438) (xy 140.596335 -407.187585) (xy 140.573691 -407.138004) (xy 140.558333 -407.085706)
			(xy 140.550575 -407.031754) (xy 139.113042 -407.031754) (xy 139.105285 -407.085702) (xy 139.08993 -407.137999)
			(xy 139.067288 -407.187579) (xy 139.037821 -407.233431) (xy 139.002128 -407.274624) (xy 138.960936 -407.310317)
			(xy 138.915084 -407.339785) (xy 138.865505 -407.362428) (xy 138.813208 -407.377784) (xy 138.759258 -407.385542)
			(xy 138.732006 -407.386028) (xy 137.868406 -407.386028) (xy 137.841154 -407.385525) (xy 137.787206 -407.377769)
			(xy 137.73491 -407.362415) (xy 137.685331 -407.339774) (xy 137.63948 -407.310307) (xy 137.598289 -407.274616)
			(xy 137.562596 -407.233425) (xy 137.533129 -407.187574) (xy 137.510488 -407.137996) (xy 137.495132 -407.0857)
			(xy 137.487375 -407.031752) (xy 136.049865 -407.031752) (xy 136.049865 -407.031756) (xy 136.042107 -407.085713)
			(xy 136.026748 -407.138016) (xy 136.004102 -407.187601) (xy 135.974629 -407.233458) (xy 135.93893 -407.274654)
			(xy 135.897731 -407.31035) (xy 135.851871 -407.339818) (xy 135.802284 -407.36246) (xy 135.749979 -407.377814)
			(xy 135.696022 -407.385567) (xy 135.668766 -407.386028) (xy 134.805166 -407.386028) (xy 134.777918 -407.385499)
			(xy 134.723977 -407.377739) (xy 134.671689 -407.362382) (xy 134.622118 -407.33974) (xy 134.576275 -407.310275)
			(xy 134.535091 -407.274585) (xy 134.499405 -407.233398) (xy 134.469943 -407.187552) (xy 134.447306 -407.137979)
			(xy 134.431953 -407.08569) (xy 134.424198 -407.031748) (xy 132.986542 -407.031748) (xy 132.986542 -407.031751)
			(xy 132.978786 -407.0857) (xy 132.963431 -407.137995) (xy 132.940791 -407.187573) (xy 132.911326 -407.233425)
			(xy 132.875635 -407.274617) (xy 132.834446 -407.31031) (xy 132.788596 -407.339778) (xy 132.73902 -407.362422)
			(xy 132.686725 -407.37778) (xy 132.632777 -407.38554) (xy 132.605526 -407.386028) (xy 131.741926 -407.386028)
			(xy 131.714673 -407.385526) (xy 131.660722 -407.377773) (xy 131.608424 -407.36242) (xy 131.558843 -407.33978)
			(xy 131.512989 -407.310314) (xy 131.471796 -407.274623) (xy 131.436101 -407.233431) (xy 131.406632 -407.187579)
			(xy 131.383989 -407.138) (xy 131.368633 -407.085703) (xy 131.360875 -407.031753) (xy 129.923365 -407.031753)
			(xy 129.923365 -407.031755) (xy 129.915607 -407.08571) (xy 129.90025 -407.138012) (xy 129.877605 -407.187595)
			(xy 129.848134 -407.233452) (xy 129.812437 -407.274647) (xy 129.771241 -407.310343) (xy 129.725383 -407.339812)
			(xy 129.675799 -407.362455) (xy 129.623496 -407.37781) (xy 129.569541 -407.385566) (xy 129.542286 -407.386028)
			(xy 128.678686 -407.386028) (xy 128.651437 -407.385501) (xy 128.597494 -407.377743) (xy 128.545203 -407.362388)
			(xy 128.49563 -407.339747) (xy 128.449784 -407.310282) (xy 128.408598 -407.274592) (xy 128.37291 -407.233404)
			(xy 128.343446 -407.187557) (xy 128.320808 -407.137984) (xy 128.305454 -407.085693) (xy 128.297698 -407.031749)
			(xy 126.860042 -407.031749) (xy 126.860042 -407.031751) (xy 126.852287 -407.085697) (xy 126.836933 -407.137991)
			(xy 126.814294 -407.187568) (xy 126.78483 -407.233418) (xy 126.749142 -407.274609) (xy 126.707955 -407.310303)
			(xy 126.662108 -407.339772) (xy 126.612534 -407.362417) (xy 126.560242 -407.377777) (xy 126.506297 -407.385539)
			(xy 126.479046 -407.386028) (xy 125.615446 -407.386028) (xy 125.588192 -407.385528) (xy 125.534239 -407.377777)
			(xy 125.481939 -407.362425) (xy 125.432355 -407.339787) (xy 125.386499 -407.310321) (xy 125.345303 -407.27463)
			(xy 125.309606 -407.233438) (xy 125.280135 -407.187585) (xy 125.257491 -407.138004) (xy 125.242133 -407.085706)
			(xy 125.234375 -407.031754) (xy 123.796842 -407.031754) (xy 123.789085 -407.085702) (xy 123.77373 -407.137999)
			(xy 123.751088 -407.187579) (xy 123.721621 -407.233431) (xy 123.685928 -407.274624) (xy 123.644736 -407.310317)
			(xy 123.598884 -407.339785) (xy 123.549305 -407.362428) (xy 123.497008 -407.377784) (xy 123.443058 -407.385542)
			(xy 123.415806 -407.386028) (xy 122.552206 -407.386028) (xy 122.524954 -407.385525) (xy 122.471006 -407.377769)
			(xy 122.41871 -407.362415) (xy 122.369131 -407.339774) (xy 122.32328 -407.310307) (xy 122.282089 -407.274616)
			(xy 122.246396 -407.233425) (xy 122.216929 -407.187574) (xy 122.194288 -407.137996) (xy 122.178932 -407.0857)
			(xy 122.171175 -407.031752) (xy 120.733665 -407.031752) (xy 120.733665 -407.031756) (xy 120.725907 -407.085713)
			(xy 120.710548 -407.138016) (xy 120.687902 -407.187601) (xy 120.658429 -407.233458) (xy 120.62273 -407.274654)
			(xy 120.581531 -407.31035) (xy 120.535671 -407.339818) (xy 120.486084 -407.36246) (xy 120.433779 -407.377814)
			(xy 120.379822 -407.385567) (xy 120.352566 -407.386028) (xy 119.488966 -407.386028) (xy 119.461718 -407.385499)
			(xy 119.407777 -407.377739) (xy 119.355489 -407.362382) (xy 119.305918 -407.33974) (xy 119.260075 -407.310275)
			(xy 119.218891 -407.274585) (xy 119.183205 -407.233398) (xy 119.153743 -407.187552) (xy 119.131106 -407.137979)
			(xy 119.115753 -407.08569) (xy 119.107998 -407.031748) (xy 117.670342 -407.031748) (xy 117.670342 -407.031751)
			(xy 117.662586 -407.0857) (xy 117.647231 -407.137995) (xy 117.624591 -407.187573) (xy 117.595126 -407.233425)
			(xy 117.559435 -407.274617) (xy 117.518246 -407.31031) (xy 117.472396 -407.339778) (xy 117.42282 -407.362422)
			(xy 117.370525 -407.37778) (xy 117.316577 -407.38554) (xy 117.289326 -407.386028) (xy 116.425726 -407.386028)
			(xy 116.398473 -407.385526) (xy 116.344522 -407.377773) (xy 116.292224 -407.36242) (xy 116.242643 -407.33978)
			(xy 116.196789 -407.310314) (xy 116.155596 -407.274623) (xy 116.119901 -407.233431) (xy 116.090432 -407.187579)
			(xy 116.067789 -407.138) (xy 116.052433 -407.085703) (xy 116.044675 -407.031753) (xy 96.519065 -407.031753)
			(xy 96.519065 -407.031755) (xy 96.511307 -407.08571) (xy 96.49595 -407.138012) (xy 96.473305 -407.187596)
			(xy 96.443834 -407.233452) (xy 96.408136 -407.274648) (xy 96.36694 -407.310343) (xy 96.321082 -407.339812)
			(xy 96.271497 -407.362455) (xy 96.219195 -407.377811) (xy 96.165239 -407.385566) (xy 96.137984 -407.386028)
			(xy 95.274384 -407.386028) (xy 95.247135 -407.385501) (xy 95.193192 -407.377743) (xy 95.140902 -407.362387)
			(xy 95.091329 -407.339746) (xy 95.045483 -407.310281) (xy 95.004297 -407.274591) (xy 94.968609 -407.233404)
			(xy 94.939146 -407.187557) (xy 94.916507 -407.137983) (xy 94.901154 -407.085692) (xy 94.893398 -407.031749)
			(xy 93.455742 -407.031749) (xy 93.455742 -407.031751) (xy 93.447987 -407.085697) (xy 93.432633 -407.137991)
			(xy 93.409994 -407.187568) (xy 93.38053 -407.233419) (xy 93.344841 -407.27461) (xy 93.303654 -407.310304)
			(xy 93.257807 -407.339773) (xy 93.208233 -407.362417) (xy 93.15594 -407.377777) (xy 93.101995 -407.385539)
			(xy 93.074744 -407.386028) (xy 92.211144 -407.386028) (xy 92.183891 -407.385528) (xy 92.129938 -407.377776)
			(xy 92.077637 -407.362425) (xy 92.028054 -407.339786) (xy 91.982198 -407.310321) (xy 91.941002 -407.274629)
			(xy 91.905306 -407.233437) (xy 91.875835 -407.187584) (xy 91.853191 -407.138004) (xy 91.837833 -407.085705)
			(xy 91.830075 -407.031753) (xy 90.392542 -407.031753) (xy 90.384785 -407.085703) (xy 90.36943 -407.138)
			(xy 90.346788 -407.187579) (xy 90.31732 -407.233432) (xy 90.281627 -407.274624) (xy 90.240435 -407.310318)
			(xy 90.194583 -407.339786) (xy 90.145004 -407.362428) (xy 90.092707 -407.377785) (xy 90.038756 -407.385542)
			(xy 90.011504 -407.386028) (xy 89.147904 -407.386028) (xy 89.120652 -407.385525) (xy 89.066704 -407.377769)
			(xy 89.014408 -407.362414) (xy 88.96483 -407.339773) (xy 88.918979 -407.310307) (xy 88.877788 -407.274615)
			(xy 88.842096 -407.233424) (xy 88.812629 -407.187573) (xy 88.789987 -407.137995) (xy 88.774632 -407.0857)
			(xy 88.766875 -407.031752) (xy 87.329365 -407.031752) (xy 87.329365 -407.031756) (xy 87.321607 -407.085713)
			(xy 87.306248 -407.138016) (xy 87.283602 -407.187602) (xy 87.254129 -407.233459) (xy 87.218429 -407.274655)
			(xy 87.17723 -407.31035) (xy 87.13137 -407.339819) (xy 87.081783 -407.362461) (xy 87.029478 -407.377814)
			(xy 86.97552 -407.385568) (xy 86.948264 -407.386028) (xy 86.084664 -407.386028) (xy 86.057416 -407.385499)
			(xy 86.003475 -407.377739) (xy 85.951187 -407.362382) (xy 85.901617 -407.33974) (xy 85.855774 -407.310274)
			(xy 85.81459 -407.274584) (xy 85.778904 -407.233397) (xy 85.749443 -407.187551) (xy 85.726806 -407.137979)
			(xy 85.711453 -407.08569) (xy 85.703698 -407.031748) (xy 84.266042 -407.031748) (xy 84.266042 -407.031752)
			(xy 84.258286 -407.0857) (xy 84.242931 -407.137996) (xy 84.220291 -407.187574) (xy 84.190825 -407.233425)
			(xy 84.155134 -407.274617) (xy 84.113945 -407.310311) (xy 84.068095 -407.339779) (xy 84.018518 -407.362423)
			(xy 83.966224 -407.377781) (xy 83.912276 -407.385541) (xy 83.885024 -407.386028) (xy 83.021424 -407.386028)
			(xy 82.994171 -407.385526) (xy 82.940221 -407.377773) (xy 82.887923 -407.362419) (xy 82.838342 -407.339779)
			(xy 82.792488 -407.310314) (xy 82.751295 -407.274622) (xy 82.715601 -407.233431) (xy 82.686132 -407.187579)
			(xy 82.663489 -407.138) (xy 82.648133 -407.085703) (xy 82.640375 -407.031753) (xy 81.202865 -407.031753)
			(xy 81.202865 -407.031755) (xy 81.195107 -407.08571) (xy 81.17975 -407.138012) (xy 81.157105 -407.187596)
			(xy 81.127634 -407.233452) (xy 81.091936 -407.274648) (xy 81.05074 -407.310343) (xy 81.004882 -407.339812)
			(xy 80.955297 -407.362455) (xy 80.902995 -407.377811) (xy 80.849039 -407.385566) (xy 80.821784 -407.386028)
			(xy 79.958184 -407.386028) (xy 79.930935 -407.385501) (xy 79.876992 -407.377743) (xy 79.824702 -407.362387)
			(xy 79.775129 -407.339746) (xy 79.729283 -407.310281) (xy 79.688097 -407.274591) (xy 79.652409 -407.233404)
			(xy 79.622946 -407.187557) (xy 79.600307 -407.137983) (xy 79.584954 -407.085692) (xy 79.577198 -407.031749)
			(xy 78.139542 -407.031749) (xy 78.139542 -407.031751) (xy 78.131787 -407.085697) (xy 78.116433 -407.137991)
			(xy 78.093794 -407.187568) (xy 78.06433 -407.233419) (xy 78.028641 -407.27461) (xy 77.987454 -407.310304)
			(xy 77.941607 -407.339773) (xy 77.892033 -407.362417) (xy 77.83974 -407.377777) (xy 77.785795 -407.385539)
			(xy 77.758544 -407.386028) (xy 76.894944 -407.386028) (xy 76.867691 -407.385528) (xy 76.813738 -407.377776)
			(xy 76.761437 -407.362425) (xy 76.711854 -407.339786) (xy 76.665998 -407.310321) (xy 76.624802 -407.274629)
			(xy 76.589106 -407.233437) (xy 76.559635 -407.187584) (xy 76.536991 -407.138004) (xy 76.521633 -407.085705)
			(xy 76.513875 -407.031753) (xy 75.076342 -407.031753) (xy 75.068585 -407.085703) (xy 75.05323 -407.138)
			(xy 75.030588 -407.187579) (xy 75.00112 -407.233432) (xy 74.965427 -407.274624) (xy 74.924235 -407.310318)
			(xy 74.878383 -407.339786) (xy 74.828804 -407.362428) (xy 74.776507 -407.377785) (xy 74.722556 -407.385542)
			(xy 74.695304 -407.386028) (xy 73.831704 -407.386028) (xy 73.804452 -407.385525) (xy 73.750504 -407.377769)
			(xy 73.698208 -407.362414) (xy 73.64863 -407.339773) (xy 73.602779 -407.310307) (xy 73.561588 -407.274615)
			(xy 73.525896 -407.233424) (xy 73.496429 -407.187573) (xy 73.473787 -407.137995) (xy 73.458432 -407.0857)
			(xy 73.450675 -407.031752) (xy 72.013165 -407.031752) (xy 72.013165 -407.031756) (xy 72.005407 -407.085713)
			(xy 71.990048 -407.138016) (xy 71.967402 -407.187602) (xy 71.937929 -407.233459) (xy 71.902229 -407.274655)
			(xy 71.86103 -407.31035) (xy 71.81517 -407.339819) (xy 71.765583 -407.362461) (xy 71.713278 -407.377814)
			(xy 71.65932 -407.385568) (xy 71.632064 -407.386028) (xy 70.768464 -407.386028) (xy 70.741216 -407.385499)
			(xy 70.687275 -407.377739) (xy 70.634987 -407.362382) (xy 70.585417 -407.33974) (xy 70.539574 -407.310274)
			(xy 70.49839 -407.274584) (xy 70.462704 -407.233397) (xy 70.433243 -407.187551) (xy 70.410606 -407.137979)
			(xy 70.395253 -407.08569) (xy 70.387498 -407.031748) (xy 68.949842 -407.031748) (xy 68.949842 -407.031752)
			(xy 68.942086 -407.0857) (xy 68.926731 -407.137996) (xy 68.904091 -407.187574) (xy 68.874625 -407.233425)
			(xy 68.838934 -407.274617) (xy 68.797745 -407.310311) (xy 68.751895 -407.339779) (xy 68.702318 -407.362423)
			(xy 68.650024 -407.377781) (xy 68.596076 -407.385541) (xy 68.568824 -407.386028) (xy 67.705224 -407.386028)
			(xy 67.677971 -407.385526) (xy 67.624021 -407.377773) (xy 67.571723 -407.362419) (xy 67.522142 -407.339779)
			(xy 67.476288 -407.310314) (xy 67.435095 -407.274622) (xy 67.399401 -407.233431) (xy 67.369932 -407.187579)
			(xy 67.347289 -407.138) (xy 67.331933 -407.085703) (xy 67.324175 -407.031753) (xy 65.886665 -407.031753)
			(xy 65.886665 -407.031755) (xy 65.878907 -407.08571) (xy 65.86355 -407.138012) (xy 65.840905 -407.187596)
			(xy 65.811434 -407.233452) (xy 65.775736 -407.274648) (xy 65.73454 -407.310343) (xy 65.688682 -407.339812)
			(xy 65.639097 -407.362455) (xy 65.586795 -407.377811) (xy 65.532839 -407.385566) (xy 65.505584 -407.386028)
			(xy 64.641984 -407.386028) (xy 64.614735 -407.385501) (xy 64.560792 -407.377743) (xy 64.508502 -407.362387)
			(xy 64.458929 -407.339746) (xy 64.413083 -407.310281) (xy 64.371897 -407.274591) (xy 64.336209 -407.233404)
			(xy 64.306746 -407.187557) (xy 64.284107 -407.137983) (xy 64.268754 -407.085692) (xy 64.260998 -407.031749)
			(xy 62.823342 -407.031749) (xy 62.823342 -407.031751) (xy 62.815587 -407.085697) (xy 62.800233 -407.137991)
			(xy 62.777594 -407.187568) (xy 62.74813 -407.233419) (xy 62.712441 -407.27461) (xy 62.671254 -407.310304)
			(xy 62.625407 -407.339773) (xy 62.575833 -407.362417) (xy 62.52354 -407.377777) (xy 62.469595 -407.385539)
			(xy 62.442344 -407.386028) (xy 61.578744 -407.386028) (xy 61.551491 -407.385528) (xy 61.497538 -407.377776)
			(xy 61.445237 -407.362425) (xy 61.395654 -407.339786) (xy 61.349798 -407.310321) (xy 61.308602 -407.274629)
			(xy 61.272906 -407.233437) (xy 61.243435 -407.187584) (xy 61.220791 -407.138004) (xy 61.205433 -407.085705)
			(xy 61.197675 -407.031753) (xy 59.760142 -407.031753) (xy 59.752385 -407.085703) (xy 59.73703 -407.138)
			(xy 59.714388 -407.187579) (xy 59.68492 -407.233432) (xy 59.649227 -407.274624) (xy 59.608035 -407.310318)
			(xy 59.562183 -407.339786) (xy 59.512604 -407.362428) (xy 59.460307 -407.377785) (xy 59.406356 -407.385542)
			(xy 59.379104 -407.386028) (xy 58.515504 -407.386028) (xy 58.488252 -407.385525) (xy 58.434304 -407.377769)
			(xy 58.382008 -407.362414) (xy 58.33243 -407.339773) (xy 58.286579 -407.310307) (xy 58.245388 -407.274615)
			(xy 58.209696 -407.233424) (xy 58.180229 -407.187573) (xy 58.157587 -407.137995) (xy 58.142232 -407.0857)
			(xy 58.134475 -407.031752) (xy 56.696965 -407.031752) (xy 56.696965 -407.031756) (xy 56.689207 -407.085713)
			(xy 56.673848 -407.138016) (xy 56.651202 -407.187602) (xy 56.621729 -407.233459) (xy 56.586029 -407.274655)
			(xy 56.54483 -407.31035) (xy 56.49897 -407.339819) (xy 56.449383 -407.362461) (xy 56.397078 -407.377814)
			(xy 56.34312 -407.385568) (xy 56.315864 -407.386028) (xy 55.452264 -407.386028) (xy 55.425016 -407.385499)
			(xy 55.371075 -407.377739) (xy 55.318787 -407.362382) (xy 55.269217 -407.33974) (xy 55.223374 -407.310274)
			(xy 55.18219 -407.274584) (xy 55.146504 -407.233397) (xy 55.117043 -407.187551) (xy 55.094406 -407.137979)
			(xy 55.079053 -407.08569) (xy 55.071298 -407.031748) (xy 53.633642 -407.031748) (xy 53.633642 -407.031752)
			(xy 53.625886 -407.0857) (xy 53.610531 -407.137996) (xy 53.587891 -407.187574) (xy 53.558425 -407.233425)
			(xy 53.522734 -407.274617) (xy 53.481545 -407.310311) (xy 53.435695 -407.339779) (xy 53.386118 -407.362423)
			(xy 53.333824 -407.377781) (xy 53.279876 -407.385541) (xy 53.252624 -407.386028) (xy 52.389024 -407.386028)
			(xy 52.361771 -407.385526) (xy 52.307821 -407.377773) (xy 52.255523 -407.362419) (xy 52.205942 -407.339779)
			(xy 52.160088 -407.310314) (xy 52.118895 -407.274622) (xy 52.083201 -407.233431) (xy 52.053732 -407.187579)
			(xy 52.031089 -407.138) (xy 52.015733 -407.085703) (xy 52.007975 -407.031753) (xy 50.570465 -407.031753)
			(xy 50.570465 -407.031755) (xy 50.562707 -407.08571) (xy 50.54735 -407.138012) (xy 50.524705 -407.187596)
			(xy 50.495234 -407.233452) (xy 50.459536 -407.274648) (xy 50.41834 -407.310343) (xy 50.372482 -407.339812)
			(xy 50.322897 -407.362455) (xy 50.270595 -407.377811) (xy 50.216639 -407.385566) (xy 50.189384 -407.386028)
			(xy 49.325784 -407.386028) (xy 49.298535 -407.385501) (xy 49.244592 -407.377743) (xy 49.192302 -407.362387)
			(xy 49.142729 -407.339746) (xy 49.096883 -407.310281) (xy 49.055697 -407.274591) (xy 49.020009 -407.233404)
			(xy 48.990546 -407.187557) (xy 48.967907 -407.137983) (xy 48.952554 -407.085692) (xy 48.944798 -407.031749)
			(xy 44.883756 -407.031749) (xy 44.868945 -407.05439) (xy 44.764794 -407.199093) (xy 44.654301 -407.339013)
			(xy 44.537684 -407.473872) (xy 44.415175 -407.603402) (xy 44.287018 -407.727346) (xy 44.153467 -407.845458)
			(xy 44.014787 -407.957503) (xy 43.871253 -408.06326) (xy 43.72315 -408.162517) (xy 43.570773 -408.255079)
			(xy 43.414424 -408.34076) (xy 43.254413 -408.419392) (xy 43.091059 -408.490818) (xy 42.924684 -408.554896)
			(xy 42.755621 -408.611498) (xy 42.584204 -408.660514) (xy 42.410773 -408.701844) (xy 42.235673 -408.735408)
			(xy 42.059253 -408.761138) (xy 41.881861 -408.778984) (xy 41.70385 -408.78891) (xy 41.525573 -408.790896)
			(xy 41.347386 -408.784939) (xy 41.16964 -408.771049) (xy 40.99269 -408.749256) (xy 40.816886 -408.719602)
			(xy 40.642578 -408.682145) (xy 40.470111 -408.636961) (xy 40.299828 -408.584139) (xy 40.132067 -408.523783)
			(xy 39.967162 -408.456015) (xy 39.805439 -408.380967) (xy 39.64722 -408.29879) (xy 39.492819 -408.209647)
			(xy 39.342542 -408.113713) (xy 39.196687 -408.011181) (xy 39.055545 -407.902253) (xy 38.919396 -407.787146)
			(xy 38.788509 -407.666088) (xy 38.663145 -407.539319) (xy 38.543552 -407.407092) (xy 38.429969 -407.269669)
			(xy 38.32262 -407.127322) (xy 38.221719 -406.980334) (xy 38.127466 -406.828998) (xy 38.040048 -406.673613)
			(xy 37.959638 -406.514488) (xy 37.886397 -406.351939) (xy 37.82047 -406.186289) (xy 37.761987 -406.017867)
			(xy 37.711065 -405.847006) (xy 37.667805 -405.674047) (xy 37.632293 -405.499332) (xy 37.604599 -405.323208)
			(xy 37.584778 -405.146026) (xy 37.57287 -404.968137) (xy 37.568898 -404.789894) (xy 3.30962 -404.789894)
			(xy 6.274054 -407.754328) (xy 6.323479 -407.804444) (xy 6.417291 -407.909404) (xy 6.50507 -408.019459)
			(xy 6.58654 -408.134261) (xy 6.661445 -408.253452) (xy 6.72955 -408.376654) (xy 6.79064 -408.503481)
			(xy 6.844523 -408.633534) (xy 6.891029 -408.766403) (xy 6.930013 -408.901671) (xy 6.961351 -409.038912)
			(xy 6.984945 -409.177694) (xy 7.00072 -409.31758) (xy 7.008628 -409.458131) (xy 7.00913 -409.528518)
			(xy 7.00913 -409.563824) (xy 102.192836 -409.563824) (xy 102.192836 -408.700224) (xy 102.193322 -408.672955)
			(xy 102.201084 -408.618971) (xy 102.216449 -408.566641) (xy 102.239106 -408.517031) (xy 102.268592 -408.47115)
			(xy 102.304307 -408.429933) (xy 102.345524 -408.394218) (xy 102.391405 -408.364732) (xy 102.441015 -408.342075)
			(xy 102.493345 -408.32671) (xy 102.547329 -408.318948) (xy 102.601867 -408.318948) (xy 102.655851 -408.32671)
			(xy 102.708181 -408.342075) (xy 102.757791 -408.364732) (xy 102.803672 -408.394218) (xy 102.844889 -408.429933)
			(xy 102.880604 -408.47115) (xy 102.91009 -408.517031) (xy 102.932747 -408.566641) (xy 102.948112 -408.618971)
			(xy 102.955874 -408.672955) (xy 102.95636 -408.700224) (xy 102.95636 -409.563824) (xy 102.955874 -409.591093)
			(xy 102.948112 -409.645077) (xy 102.932747 -409.697407) (xy 102.91009 -409.747017) (xy 102.880604 -409.792898)
			(xy 102.844889 -409.834115) (xy 102.803672 -409.86983) (xy 102.757791 -409.899316) (xy 102.748244 -409.903676)
			(xy 110.559596 -409.903676) (xy 110.559596 -409.040076) (xy 110.560082 -409.012825) (xy 110.567838 -408.958877)
			(xy 110.583193 -408.906582) (xy 110.605835 -408.857005) (xy 110.635301 -408.811155) (xy 110.670992 -408.769964)
			(xy 110.712183 -408.734273) (xy 110.758033 -408.704807) (xy 110.80761 -408.682165) (xy 110.859905 -408.66681)
			(xy 110.913853 -408.659054) (xy 110.968355 -408.659054) (xy 111.022303 -408.66681) (xy 111.074598 -408.682165)
			(xy 111.124175 -408.704807) (xy 111.170025 -408.734273) (xy 111.211216 -408.769964) (xy 111.246907 -408.811155)
			(xy 111.276373 -408.857005) (xy 111.299015 -408.906582) (xy 111.31437 -408.958877) (xy 111.322126 -409.012825)
			(xy 111.322612 -409.040076) (xy 111.322612 -409.903676) (xy 111.322126 -409.930927) (xy 111.31437 -409.984875)
			(xy 111.299015 -410.03717) (xy 111.28975 -410.057456) (xy 116.044623 -410.057456) (xy 116.044623 -410.002944)
			(xy 116.052381 -409.948986) (xy 116.06774 -409.896681) (xy 116.090386 -409.847095) (xy 116.119859 -409.801237)
			(xy 116.155559 -409.76004) (xy 116.196758 -409.724344) (xy 116.242618 -409.694874) (xy 116.292206 -409.672231)
			(xy 116.344511 -409.656876) (xy 116.39847 -409.649121) (xy 116.425726 -409.64866) (xy 117.289326 -409.64866)
			(xy 117.316574 -409.649212) (xy 117.370514 -409.656971) (xy 117.422801 -409.672327) (xy 117.472371 -409.694968)
			(xy 117.518214 -409.724432) (xy 117.559398 -409.760121) (xy 117.595084 -409.801307) (xy 117.624545 -409.847152)
			(xy 117.647182 -409.896723) (xy 117.662535 -409.949011) (xy 117.67029 -410.002952) (xy 117.67029 -410.057448)
			(xy 117.670289 -410.057452) (xy 119.107946 -410.057452) (xy 119.107946 -410.002948) (xy 119.115702 -409.948999)
			(xy 119.131057 -409.896702) (xy 119.153697 -409.847123) (xy 119.183163 -409.801271) (xy 119.218854 -409.760078)
			(xy 119.260043 -409.724383) (xy 119.305893 -409.694914) (xy 119.35547 -409.672269) (xy 119.407765 -409.656909)
			(xy 119.461714 -409.649148) (xy 119.488966 -409.64866) (xy 120.352566 -409.64866) (xy 120.379818 -409.649185)
			(xy 120.433768 -409.656937) (xy 120.486066 -409.672289) (xy 120.535646 -409.694928) (xy 120.5815 -409.724392)
			(xy 120.622693 -409.760083) (xy 120.658387 -409.801273) (xy 120.687856 -409.847124) (xy 120.710499 -409.896702)
			(xy 120.725855 -409.948999) (xy 120.733613 -410.002948) (xy 120.733613 -410.057452) (xy 120.733613 -410.057455)
			(xy 122.171123 -410.057455) (xy 122.171123 -410.002945) (xy 122.178881 -409.948989) (xy 122.194238 -409.896686)
			(xy 122.216883 -409.847101) (xy 122.246354 -409.801244) (xy 122.282052 -409.760047) (xy 122.323249 -409.724351)
			(xy 122.369106 -409.69488) (xy 122.418691 -409.672236) (xy 122.470994 -409.656879) (xy 122.524951 -409.649123)
			(xy 122.552206 -409.64866) (xy 123.415806 -409.64866) (xy 123.443055 -409.649211) (xy 123.496997 -409.656967)
			(xy 123.549287 -409.672321) (xy 123.598859 -409.694961) (xy 123.644705 -409.724425) (xy 123.685891 -409.760113)
			(xy 123.721579 -409.8013) (xy 123.751042 -409.847146) (xy 123.773681 -409.896719) (xy 123.789034 -409.949009)
			(xy 123.79679 -410.002951) (xy 123.79679 -410.057449) (xy 123.796789 -410.057457) (xy 125.234323 -410.057457)
			(xy 125.234323 -410.002943) (xy 125.242082 -409.948983) (xy 125.257442 -409.896677) (xy 125.280089 -409.84709)
			(xy 125.309564 -409.801231) (xy 125.345266 -409.760033) (xy 125.386467 -409.724337) (xy 125.43233 -409.694867)
			(xy 125.48192 -409.672225) (xy 125.534228 -409.656872) (xy 125.588189 -409.64912) (xy 125.615446 -409.64866)
			(xy 126.479046 -409.64866) (xy 126.506293 -409.649213) (xy 126.560231 -409.656975) (xy 126.612516 -409.672332)
			(xy 126.662083 -409.694974) (xy 126.707924 -409.724439) (xy 126.749105 -409.760128) (xy 126.784788 -409.801313)
			(xy 126.814248 -409.847157) (xy 126.836884 -409.896727) (xy 126.852235 -409.949014) (xy 126.85999 -410.002953)
			(xy 126.85999 -410.057447) (xy 126.859989 -410.057453) (xy 128.297646 -410.057453) (xy 128.297646 -410.002947)
			(xy 128.305403 -409.948996) (xy 128.320758 -409.896698) (xy 128.3434 -409.847118) (xy 128.372868 -409.801264)
			(xy 128.408561 -409.760071) (xy 128.449753 -409.724376) (xy 128.495605 -409.694907) (xy 128.545185 -409.672263)
			(xy 128.597482 -409.656906) (xy 128.651433 -409.649147) (xy 128.678686 -409.64866) (xy 129.542286 -409.64866)
			(xy 129.569537 -409.649186) (xy 129.623485 -409.656941) (xy 129.67578 -409.672295) (xy 129.725358 -409.694934)
			(xy 129.771209 -409.724399) (xy 129.8124 -409.76009) (xy 129.848092 -409.80128) (xy 129.877559 -409.84713)
			(xy 129.900201 -409.896707) (xy 129.915556 -409.949001) (xy 129.923313 -410.002949) (xy 129.923313 -410.057451)
			(xy 129.923312 -410.057456) (xy 131.360823 -410.057456) (xy 131.360823 -410.002944) (xy 131.368581 -409.948986)
			(xy 131.38394 -409.896681) (xy 131.406586 -409.847095) (xy 131.436059 -409.801237) (xy 131.471759 -409.76004)
			(xy 131.512958 -409.724344) (xy 131.558818 -409.694874) (xy 131.608406 -409.672231) (xy 131.660711 -409.656876)
			(xy 131.71467 -409.649121) (xy 131.741926 -409.64866) (xy 132.605526 -409.64866) (xy 132.632774 -409.649212)
			(xy 132.686714 -409.656971) (xy 132.739001 -409.672327) (xy 132.788571 -409.694968) (xy 132.834414 -409.724432)
			(xy 132.875598 -409.760121) (xy 132.911284 -409.801307) (xy 132.940745 -409.847152) (xy 132.963382 -409.896723)
			(xy 132.978735 -409.949011) (xy 132.98649 -410.002952) (xy 132.98649 -410.057448) (xy 132.986489 -410.057452)
			(xy 134.424146 -410.057452) (xy 134.424146 -410.002948) (xy 134.431902 -409.948999) (xy 134.447257 -409.896702)
			(xy 134.469897 -409.847123) (xy 134.499363 -409.801271) (xy 134.535054 -409.760078) (xy 134.576243 -409.724383)
			(xy 134.622093 -409.694914) (xy 134.67167 -409.672269) (xy 134.723965 -409.656909) (xy 134.777914 -409.649148)
			(xy 134.805166 -409.64866) (xy 135.668766 -409.64866) (xy 135.696018 -409.649185) (xy 135.749968 -409.656937)
			(xy 135.802266 -409.672289) (xy 135.851846 -409.694928) (xy 135.8977 -409.724392) (xy 135.938893 -409.760083)
			(xy 135.974587 -409.801273) (xy 136.004056 -409.847124) (xy 136.026699 -409.896702) (xy 136.042055 -409.948999)
			(xy 136.049813 -410.002948) (xy 136.049813 -410.057452) (xy 136.049813 -410.057455) (xy 137.487323 -410.057455)
			(xy 137.487323 -410.002945) (xy 137.495081 -409.948989) (xy 137.510438 -409.896686) (xy 137.533083 -409.847101)
			(xy 137.562554 -409.801244) (xy 137.598252 -409.760047) (xy 137.639449 -409.724351) (xy 137.685306 -409.69488)
			(xy 137.734891 -409.672236) (xy 137.787194 -409.656879) (xy 137.841151 -409.649123) (xy 137.868406 -409.64866)
			(xy 138.732006 -409.64866) (xy 138.759255 -409.649211) (xy 138.813197 -409.656967) (xy 138.865487 -409.672321)
			(xy 138.915059 -409.694961) (xy 138.960905 -409.724425) (xy 139.002091 -409.760113) (xy 139.037779 -409.8013)
			(xy 139.067242 -409.847146) (xy 139.089881 -409.896719) (xy 139.105234 -409.949009) (xy 139.11299 -410.002951)
			(xy 139.11299 -410.057449) (xy 139.112989 -410.057457) (xy 140.550523 -410.057457) (xy 140.550523 -410.002943)
			(xy 140.558282 -409.948983) (xy 140.573642 -409.896677) (xy 140.596289 -409.84709) (xy 140.625764 -409.801231)
			(xy 140.661466 -409.760033) (xy 140.702667 -409.724337) (xy 140.74853 -409.694867) (xy 140.79812 -409.672225)
			(xy 140.850428 -409.656872) (xy 140.904389 -409.64912) (xy 140.931646 -409.64866) (xy 141.795246 -409.64866)
			(xy 141.822493 -409.649213) (xy 141.876431 -409.656975) (xy 141.928716 -409.672332) (xy 141.978283 -409.694974)
			(xy 142.024124 -409.724439) (xy 142.065305 -409.760128) (xy 142.100988 -409.801313) (xy 142.130448 -409.847157)
			(xy 142.153084 -409.896727) (xy 142.168435 -409.949014) (xy 142.17619 -410.002953) (xy 142.17619 -410.057447)
			(xy 142.176189 -410.057453) (xy 143.613846 -410.057453) (xy 143.613846 -410.002947) (xy 143.621603 -409.948996)
			(xy 143.636958 -409.896698) (xy 143.6596 -409.847118) (xy 143.689068 -409.801264) (xy 143.724761 -409.760071)
			(xy 143.765953 -409.724376) (xy 143.811805 -409.694907) (xy 143.861385 -409.672263) (xy 143.913682 -409.656906)
			(xy 143.967633 -409.649147) (xy 143.994886 -409.64866) (xy 144.858486 -409.64866) (xy 144.885737 -409.649186)
			(xy 144.939685 -409.656941) (xy 144.99198 -409.672295) (xy 145.041558 -409.694934) (xy 145.087409 -409.724399)
			(xy 145.1286 -409.76009) (xy 145.164292 -409.80128) (xy 145.193759 -409.84713) (xy 145.216401 -409.896707)
			(xy 145.231756 -409.949001) (xy 145.239513 -410.002949) (xy 145.239513 -410.057451) (xy 145.239512 -410.057456)
			(xy 146.677023 -410.057456) (xy 146.677023 -410.002944) (xy 146.684781 -409.948986) (xy 146.70014 -409.896681)
			(xy 146.722786 -409.847095) (xy 146.752259 -409.801237) (xy 146.787959 -409.76004) (xy 146.829158 -409.724344)
			(xy 146.875018 -409.694874) (xy 146.924606 -409.672231) (xy 146.976911 -409.656876) (xy 147.03087 -409.649121)
			(xy 147.058126 -409.64866) (xy 147.921726 -409.64866) (xy 147.948974 -409.649212) (xy 148.002914 -409.656971)
			(xy 148.055201 -409.672327) (xy 148.104771 -409.694968) (xy 148.150614 -409.724432) (xy 148.191798 -409.760121)
			(xy 148.227484 -409.801307) (xy 148.256945 -409.847152) (xy 148.279582 -409.896723) (xy 148.294935 -409.949011)
			(xy 148.30269 -410.002952) (xy 148.30269 -410.057448) (xy 148.302689 -410.057452) (xy 149.740346 -410.057452)
			(xy 149.740346 -410.002948) (xy 149.748102 -409.948999) (xy 149.763457 -409.896702) (xy 149.786097 -409.847123)
			(xy 149.815563 -409.801271) (xy 149.851254 -409.760078) (xy 149.892443 -409.724383) (xy 149.938293 -409.694914)
			(xy 149.98787 -409.672269) (xy 150.040165 -409.656909) (xy 150.094114 -409.649148) (xy 150.121366 -409.64866)
			(xy 150.984966 -409.64866) (xy 151.012218 -409.649185) (xy 151.066168 -409.656937) (xy 151.118466 -409.672289)
			(xy 151.168046 -409.694928) (xy 151.2139 -409.724392) (xy 151.255093 -409.760083) (xy 151.290787 -409.801273)
			(xy 151.320256 -409.847124) (xy 151.342899 -409.896702) (xy 151.358255 -409.948999) (xy 151.366013 -410.002948)
			(xy 151.366013 -410.057452) (xy 151.366013 -410.057455) (xy 152.803523 -410.057455) (xy 152.803523 -410.002945)
			(xy 152.811281 -409.948989) (xy 152.826638 -409.896686) (xy 152.849283 -409.847101) (xy 152.878754 -409.801244)
			(xy 152.914452 -409.760047) (xy 152.955649 -409.724351) (xy 153.001506 -409.69488) (xy 153.051091 -409.672236)
			(xy 153.103394 -409.656879) (xy 153.157351 -409.649123) (xy 153.184606 -409.64866) (xy 154.048206 -409.64866)
			(xy 154.075455 -409.649211) (xy 154.129397 -409.656967) (xy 154.181687 -409.672321) (xy 154.231259 -409.694961)
			(xy 154.277105 -409.724425) (xy 154.318291 -409.760113) (xy 154.353979 -409.8013) (xy 154.383442 -409.847146)
			(xy 154.406081 -409.896719) (xy 154.421434 -409.949009) (xy 154.42919 -410.002951) (xy 154.42919 -410.057449)
			(xy 154.429189 -410.057457) (xy 155.866723 -410.057457) (xy 155.866723 -410.002943) (xy 155.874482 -409.948983)
			(xy 155.889842 -409.896677) (xy 155.912489 -409.84709) (xy 155.941964 -409.801231) (xy 155.977666 -409.760033)
			(xy 156.018867 -409.724337) (xy 156.06473 -409.694867) (xy 156.11432 -409.672225) (xy 156.166628 -409.656872)
			(xy 156.220589 -409.64912) (xy 156.247846 -409.64866) (xy 157.111446 -409.64866) (xy 157.138693 -409.649213)
			(xy 157.192631 -409.656975) (xy 157.244916 -409.672332) (xy 157.294483 -409.694974) (xy 157.340324 -409.724439)
			(xy 157.381505 -409.760128) (xy 157.417188 -409.801313) (xy 157.446648 -409.847157) (xy 157.469284 -409.896727)
			(xy 157.484635 -409.949014) (xy 157.49239 -410.002953) (xy 157.49239 -410.057447) (xy 157.492389 -410.057453)
			(xy 158.930046 -410.057453) (xy 158.930046 -410.002947) (xy 158.937803 -409.948996) (xy 158.953158 -409.896698)
			(xy 158.9758 -409.847118) (xy 159.005268 -409.801264) (xy 159.040961 -409.760071) (xy 159.082153 -409.724376)
			(xy 159.128005 -409.694907) (xy 159.177585 -409.672263) (xy 159.229882 -409.656906) (xy 159.283833 -409.649147)
			(xy 159.311086 -409.64866) (xy 160.174686 -409.64866) (xy 160.201937 -409.649186) (xy 160.255885 -409.656941)
			(xy 160.30818 -409.672295) (xy 160.357758 -409.694934) (xy 160.403609 -409.724399) (xy 160.4448 -409.76009)
			(xy 160.480492 -409.80128) (xy 160.509959 -409.84713) (xy 160.532601 -409.896707) (xy 160.547956 -409.949001)
			(xy 160.555713 -410.002949) (xy 160.555713 -410.057451) (xy 160.555712 -410.057456) (xy 161.993223 -410.057456)
			(xy 161.993223 -410.002944) (xy 162.000981 -409.948986) (xy 162.01634 -409.896681) (xy 162.038986 -409.847095)
			(xy 162.068459 -409.801237) (xy 162.104159 -409.76004) (xy 162.145358 -409.724344) (xy 162.191218 -409.694874)
			(xy 162.240806 -409.672231) (xy 162.293111 -409.656876) (xy 162.34707 -409.649121) (xy 162.374326 -409.64866)
			(xy 163.237926 -409.64866) (xy 163.265174 -409.649212) (xy 163.319114 -409.656971) (xy 163.371401 -409.672327)
			(xy 163.420971 -409.694968) (xy 163.466814 -409.724432) (xy 163.507998 -409.760121) (xy 163.543684 -409.801307)
			(xy 163.573145 -409.847152) (xy 163.595782 -409.896723) (xy 163.611135 -409.949011) (xy 163.61889 -410.002952)
			(xy 163.61889 -410.057448) (xy 163.611135 -410.111389) (xy 163.595782 -410.163677) (xy 163.573145 -410.213248)
			(xy 163.543684 -410.259093) (xy 163.507998 -410.300279) (xy 163.466814 -410.335968) (xy 163.420971 -410.365432)
			(xy 163.371401 -410.388073) (xy 163.319114 -410.403429) (xy 163.265174 -410.411188) (xy 163.237926 -410.411676)
			(xy 162.374326 -410.411676) (xy 162.34707 -410.411279) (xy 162.293111 -410.403524) (xy 162.240806 -410.388169)
			(xy 162.191218 -410.365526) (xy 162.145358 -410.336056) (xy 162.104159 -410.30036) (xy 162.068459 -410.259163)
			(xy 162.038986 -410.213305) (xy 162.01634 -410.163719) (xy 162.000981 -410.111414) (xy 161.993223 -410.057456)
			(xy 160.555712 -410.057456) (xy 160.547956 -410.111399) (xy 160.532601 -410.163693) (xy 160.509959 -410.21327)
			(xy 160.480492 -410.25912) (xy 160.4448 -410.30031) (xy 160.403609 -410.336001) (xy 160.357758 -410.365466)
			(xy 160.30818 -410.388105) (xy 160.255885 -410.403459) (xy 160.201937 -410.411214) (xy 160.174686 -410.411676)
			(xy 159.311086 -410.411676) (xy 159.283833 -410.411253) (xy 159.229882 -410.403494) (xy 159.177585 -410.388137)
			(xy 159.128005 -410.365493) (xy 159.082153 -410.336024) (xy 159.040961 -410.300329) (xy 159.005268 -410.259136)
			(xy 158.9758 -410.213282) (xy 158.953158 -410.163702) (xy 158.937803 -410.111404) (xy 158.930046 -410.057453)
			(xy 157.492389 -410.057453) (xy 157.484635 -410.111386) (xy 157.469284 -410.163673) (xy 157.446648 -410.213243)
			(xy 157.417188 -410.259087) (xy 157.381505 -410.300272) (xy 157.340324 -410.335961) (xy 157.294483 -410.365426)
			(xy 157.244916 -410.388068) (xy 157.192631 -410.403425) (xy 157.138693 -410.411187) (xy 157.111446 -410.411676)
			(xy 156.247846 -410.411676) (xy 156.220589 -410.41128) (xy 156.166628 -410.403528) (xy 156.11432 -410.388175)
			(xy 156.06473 -410.365533) (xy 156.018867 -410.336063) (xy 155.977666 -410.300367) (xy 155.941964 -410.259169)
			(xy 155.912489 -410.21331) (xy 155.889842 -410.163723) (xy 155.874482 -410.111417) (xy 155.866723 -410.057457)
			(xy 154.429189 -410.057457) (xy 154.421434 -410.111391) (xy 154.406081 -410.163681) (xy 154.383442 -410.213254)
			(xy 154.353979 -410.2591) (xy 154.318291 -410.300287) (xy 154.277105 -410.335975) (xy 154.231259 -410.365439)
			(xy 154.181687 -410.388079) (xy 154.129397 -410.403433) (xy 154.075455 -410.411189) (xy 154.048206 -410.411676)
			(xy 153.184606 -410.411676) (xy 153.157351 -410.411277) (xy 153.103394 -410.403521) (xy 153.051091 -410.388164)
			(xy 153.001506 -410.36552) (xy 152.955649 -410.336049) (xy 152.914452 -410.300353) (xy 152.878754 -410.259156)
			(xy 152.849283 -410.213299) (xy 152.826638 -410.163714) (xy 152.811281 -410.111411) (xy 152.803523 -410.057455)
			(xy 151.366013 -410.057455) (xy 151.358255 -410.111402) (xy 151.342899 -410.163698) (xy 151.320256 -410.213276)
			(xy 151.290787 -410.259127) (xy 151.255093 -410.300317) (xy 151.2139 -410.336008) (xy 151.168046 -410.365472)
			(xy 151.118466 -410.388111) (xy 151.066168 -410.403463) (xy 151.012218 -410.411215) (xy 150.984966 -410.411676)
			(xy 150.121366 -410.411676) (xy 150.094114 -410.411252) (xy 150.040165 -410.403491) (xy 149.98787 -410.388131)
			(xy 149.938293 -410.365486) (xy 149.892443 -410.336017) (xy 149.851254 -410.300322) (xy 149.815563 -410.259129)
			(xy 149.786097 -410.213277) (xy 149.763457 -410.163698) (xy 149.748102 -410.111401) (xy 149.740346 -410.057452)
			(xy 148.302689 -410.057452) (xy 148.294935 -410.111389) (xy 148.279582 -410.163677) (xy 148.256945 -410.213248)
			(xy 148.227484 -410.259093) (xy 148.191798 -410.300279) (xy 148.150614 -410.335968) (xy 148.104771 -410.365432)
			(xy 148.055201 -410.388073) (xy 148.002914 -410.403429) (xy 147.948974 -410.411188) (xy 147.921726 -410.411676)
			(xy 147.058126 -410.411676) (xy 147.03087 -410.411279) (xy 146.976911 -410.403524) (xy 146.924606 -410.388169)
			(xy 146.875018 -410.365526) (xy 146.829158 -410.336056) (xy 146.787959 -410.30036) (xy 146.752259 -410.259163)
			(xy 146.722786 -410.213305) (xy 146.70014 -410.163719) (xy 146.684781 -410.111414) (xy 146.677023 -410.057456)
			(xy 145.239512 -410.057456) (xy 145.231756 -410.111399) (xy 145.216401 -410.163693) (xy 145.193759 -410.21327)
			(xy 145.164292 -410.25912) (xy 145.1286 -410.30031) (xy 145.087409 -410.336001) (xy 145.041558 -410.365466)
			(xy 144.99198 -410.388105) (xy 144.939685 -410.403459) (xy 144.885737 -410.411214) (xy 144.858486 -410.411676)
			(xy 143.994886 -410.411676) (xy 143.967633 -410.411253) (xy 143.913682 -410.403494) (xy 143.861385 -410.388137)
			(xy 143.811805 -410.365493) (xy 143.765953 -410.336024) (xy 143.724761 -410.300329) (xy 143.689068 -410.259136)
			(xy 143.6596 -410.213282) (xy 143.636958 -410.163702) (xy 143.621603 -410.111404) (xy 143.613846 -410.057453)
			(xy 142.176189 -410.057453) (xy 142.168435 -410.111386) (xy 142.153084 -410.163673) (xy 142.130448 -410.213243)
			(xy 142.100988 -410.259087) (xy 142.065305 -410.300272) (xy 142.024124 -410.335961) (xy 141.978283 -410.365426)
			(xy 141.928716 -410.388068) (xy 141.876431 -410.403425) (xy 141.822493 -410.411187) (xy 141.795246 -410.411676)
			(xy 140.931646 -410.411676) (xy 140.904389 -410.41128) (xy 140.850428 -410.403528) (xy 140.79812 -410.388175)
			(xy 140.74853 -410.365533) (xy 140.702667 -410.336063) (xy 140.661466 -410.300367) (xy 140.625764 -410.259169)
			(xy 140.596289 -410.21331) (xy 140.573642 -410.163723) (xy 140.558282 -410.111417) (xy 140.550523 -410.057457)
			(xy 139.112989 -410.057457) (xy 139.105234 -410.111391) (xy 139.089881 -410.163681) (xy 139.067242 -410.213254)
			(xy 139.037779 -410.2591) (xy 139.002091 -410.300287) (xy 138.960905 -410.335975) (xy 138.915059 -410.365439)
			(xy 138.865487 -410.388079) (xy 138.813197 -410.403433) (xy 138.759255 -410.411189) (xy 138.732006 -410.411676)
			(xy 137.868406 -410.411676) (xy 137.841151 -410.411277) (xy 137.787194 -410.403521) (xy 137.734891 -410.388164)
			(xy 137.685306 -410.36552) (xy 137.639449 -410.336049) (xy 137.598252 -410.300353) (xy 137.562554 -410.259156)
			(xy 137.533083 -410.213299) (xy 137.510438 -410.163714) (xy 137.495081 -410.111411) (xy 137.487323 -410.057455)
			(xy 136.049813 -410.057455) (xy 136.042055 -410.111402) (xy 136.026699 -410.163698) (xy 136.004056 -410.213276)
			(xy 135.974587 -410.259127) (xy 135.938893 -410.300317) (xy 135.8977 -410.336008) (xy 135.851846 -410.365472)
			(xy 135.802266 -410.388111) (xy 135.749968 -410.403463) (xy 135.696018 -410.411215) (xy 135.668766 -410.411676)
			(xy 134.805166 -410.411676) (xy 134.777914 -410.411252) (xy 134.723965 -410.403491) (xy 134.67167 -410.388131)
			(xy 134.622093 -410.365486) (xy 134.576243 -410.336017) (xy 134.535054 -410.300322) (xy 134.499363 -410.259129)
			(xy 134.469897 -410.213277) (xy 134.447257 -410.163698) (xy 134.431902 -410.111401) (xy 134.424146 -410.057452)
			(xy 132.986489 -410.057452) (xy 132.978735 -410.111389) (xy 132.963382 -410.163677) (xy 132.940745 -410.213248)
			(xy 132.911284 -410.259093) (xy 132.875598 -410.300279) (xy 132.834414 -410.335968) (xy 132.788571 -410.365432)
			(xy 132.739001 -410.388073) (xy 132.686714 -410.403429) (xy 132.632774 -410.411188) (xy 132.605526 -410.411676)
			(xy 131.741926 -410.411676) (xy 131.71467 -410.411279) (xy 131.660711 -410.403524) (xy 131.608406 -410.388169)
			(xy 131.558818 -410.365526) (xy 131.512958 -410.336056) (xy 131.471759 -410.30036) (xy 131.436059 -410.259163)
			(xy 131.406586 -410.213305) (xy 131.38394 -410.163719) (xy 131.368581 -410.111414) (xy 131.360823 -410.057456)
			(xy 129.923312 -410.057456) (xy 129.915556 -410.111399) (xy 129.900201 -410.163693) (xy 129.877559 -410.21327)
			(xy 129.848092 -410.25912) (xy 129.8124 -410.30031) (xy 129.771209 -410.336001) (xy 129.725358 -410.365466)
			(xy 129.67578 -410.388105) (xy 129.623485 -410.403459) (xy 129.569537 -410.411214) (xy 129.542286 -410.411676)
			(xy 128.678686 -410.411676) (xy 128.651433 -410.411253) (xy 128.597482 -410.403494) (xy 128.545185 -410.388137)
			(xy 128.495605 -410.365493) (xy 128.449753 -410.336024) (xy 128.408561 -410.300329) (xy 128.372868 -410.259136)
			(xy 128.3434 -410.213282) (xy 128.320758 -410.163702) (xy 128.305403 -410.111404) (xy 128.297646 -410.057453)
			(xy 126.859989 -410.057453) (xy 126.852235 -410.111386) (xy 126.836884 -410.163673) (xy 126.814248 -410.213243)
			(xy 126.784788 -410.259087) (xy 126.749105 -410.300272) (xy 126.707924 -410.335961) (xy 126.662083 -410.365426)
			(xy 126.612516 -410.388068) (xy 126.560231 -410.403425) (xy 126.506293 -410.411187) (xy 126.479046 -410.411676)
			(xy 125.615446 -410.411676) (xy 125.588189 -410.41128) (xy 125.534228 -410.403528) (xy 125.48192 -410.388175)
			(xy 125.43233 -410.365533) (xy 125.386467 -410.336063) (xy 125.345266 -410.300367) (xy 125.309564 -410.259169)
			(xy 125.280089 -410.21331) (xy 125.257442 -410.163723) (xy 125.242082 -410.111417) (xy 125.234323 -410.057457)
			(xy 123.796789 -410.057457) (xy 123.789034 -410.111391) (xy 123.773681 -410.163681) (xy 123.751042 -410.213254)
			(xy 123.721579 -410.2591) (xy 123.685891 -410.300287) (xy 123.644705 -410.335975) (xy 123.598859 -410.365439)
			(xy 123.549287 -410.388079) (xy 123.496997 -410.403433) (xy 123.443055 -410.411189) (xy 123.415806 -410.411676)
			(xy 122.552206 -410.411676) (xy 122.524951 -410.411277) (xy 122.470994 -410.403521) (xy 122.418691 -410.388164)
			(xy 122.369106 -410.36552) (xy 122.323249 -410.336049) (xy 122.282052 -410.300353) (xy 122.246354 -410.259156)
			(xy 122.216883 -410.213299) (xy 122.194238 -410.163714) (xy 122.178881 -410.111411) (xy 122.171123 -410.057455)
			(xy 120.733613 -410.057455) (xy 120.725855 -410.111402) (xy 120.710499 -410.163698) (xy 120.687856 -410.213276)
			(xy 120.658387 -410.259127) (xy 120.622693 -410.300317) (xy 120.5815 -410.336008) (xy 120.535646 -410.365472)
			(xy 120.486066 -410.388111) (xy 120.433768 -410.403463) (xy 120.379818 -410.411215) (xy 120.352566 -410.411676)
			(xy 119.488966 -410.411676) (xy 119.461714 -410.411252) (xy 119.407765 -410.403491) (xy 119.35547 -410.388131)
			(xy 119.305893 -410.365486) (xy 119.260043 -410.336017) (xy 119.218854 -410.300322) (xy 119.183163 -410.259129)
			(xy 119.153697 -410.213277) (xy 119.131057 -410.163698) (xy 119.115702 -410.111401) (xy 119.107946 -410.057452)
			(xy 117.670289 -410.057452) (xy 117.662535 -410.111389) (xy 117.647182 -410.163677) (xy 117.624545 -410.213248)
			(xy 117.595084 -410.259093) (xy 117.559398 -410.300279) (xy 117.518214 -410.335968) (xy 117.472371 -410.365432)
			(xy 117.422801 -410.388073) (xy 117.370514 -410.403429) (xy 117.316574 -410.411188) (xy 117.289326 -410.411676)
			(xy 116.425726 -410.411676) (xy 116.39847 -410.411279) (xy 116.344511 -410.403524) (xy 116.292206 -410.388169)
			(xy 116.242618 -410.365526) (xy 116.196758 -410.336056) (xy 116.155559 -410.30036) (xy 116.119859 -410.259163)
			(xy 116.090386 -410.213305) (xy 116.06774 -410.163719) (xy 116.052381 -410.111414) (xy 116.044623 -410.057456)
			(xy 111.28975 -410.057456) (xy 111.276373 -410.086747) (xy 111.246907 -410.132597) (xy 111.211216 -410.173788)
			(xy 111.170025 -410.209479) (xy 111.124175 -410.238945) (xy 111.074598 -410.261587) (xy 111.022303 -410.276942)
			(xy 110.968355 -410.284698) (xy 110.913853 -410.284698) (xy 110.859905 -410.276942) (xy 110.80761 -410.261587)
			(xy 110.758033 -410.238945) (xy 110.712183 -410.209479) (xy 110.670992 -410.173788) (xy 110.635301 -410.132597)
			(xy 110.605835 -410.086747) (xy 110.583193 -410.03717) (xy 110.567838 -409.984875) (xy 110.560082 -409.930927)
			(xy 110.559596 -409.903676) (xy 102.748244 -409.903676) (xy 102.708181 -409.921973) (xy 102.655851 -409.937338)
			(xy 102.601867 -409.9451) (xy 102.547329 -409.9451) (xy 102.493345 -409.937338) (xy 102.441015 -409.921973)
			(xy 102.391405 -409.899316) (xy 102.345524 -409.86983) (xy 102.304307 -409.834115) (xy 102.268592 -409.792898)
			(xy 102.239106 -409.747017) (xy 102.216449 -409.697407) (xy 102.201084 -409.645077) (xy 102.193322 -409.591093)
			(xy 102.192836 -409.563824) (xy 7.00913 -409.563824) (xy 7.00913 -410.057453) (xy 48.944746 -410.057453)
			(xy 48.944746 -410.002947) (xy 48.952503 -409.948996) (xy 48.967858 -409.896698) (xy 48.9905 -409.847118)
			(xy 49.019967 -409.801265) (xy 49.05566 -409.760071) (xy 49.096852 -409.724377) (xy 49.142704 -409.694908)
			(xy 49.192283 -409.672264) (xy 49.244581 -409.656906) (xy 49.298531 -409.649147) (xy 49.325784 -409.64866)
			(xy 50.189384 -409.64866) (xy 50.216635 -409.649186) (xy 50.270583 -409.656941) (xy 50.322879 -409.672294)
			(xy 50.372457 -409.694934) (xy 50.418308 -409.724399) (xy 50.459499 -409.760089) (xy 50.495192 -409.801279)
			(xy 50.524659 -409.847129) (xy 50.5473 -409.896706) (xy 50.562656 -409.949001) (xy 50.570413 -410.002949)
			(xy 50.570413 -410.057451) (xy 50.570412 -410.057456) (xy 52.007923 -410.057456) (xy 52.007923 -410.002944)
			(xy 52.015681 -409.948986) (xy 52.03104 -409.896682) (xy 52.053686 -409.847096) (xy 52.083159 -409.801238)
			(xy 52.118858 -409.760041) (xy 52.160057 -409.724344) (xy 52.205917 -409.694874) (xy 52.255504 -409.672231)
			(xy 52.30781 -409.656876) (xy 52.361768 -409.649121) (xy 52.389024 -409.64866) (xy 53.252624 -409.64866)
			(xy 53.279872 -409.649212) (xy 53.333812 -409.65697) (xy 53.3861 -409.672326) (xy 53.43567 -409.694967)
			(xy 53.481513 -409.724431) (xy 53.522697 -409.76012) (xy 53.558383 -409.801306) (xy 53.587845 -409.847151)
			(xy 53.610482 -409.896723) (xy 53.625835 -409.949011) (xy 53.63359 -410.002952) (xy 53.63359 -410.057448)
			(xy 53.633589 -410.057452) (xy 55.071246 -410.057452) (xy 55.071246 -410.002948) (xy 55.079002 -409.948999)
			(xy 55.094357 -409.896703) (xy 55.116997 -409.847124) (xy 55.146462 -409.801271) (xy 55.182153 -409.760079)
			(xy 55.223342 -409.724384) (xy 55.269192 -409.694914) (xy 55.318769 -409.672269) (xy 55.371064 -409.65691)
			(xy 55.425012 -409.649148) (xy 55.452264 -409.64866) (xy 56.315864 -409.64866) (xy 56.343116 -409.649185)
			(xy 56.397067 -409.656937) (xy 56.449364 -409.672289) (xy 56.498945 -409.694927) (xy 56.544799 -409.724392)
			(xy 56.585992 -409.760082) (xy 56.621687 -409.801273) (xy 56.651156 -409.847124) (xy 56.673799 -409.896702)
			(xy 56.689155 -409.948998) (xy 56.696913 -410.002948) (xy 56.696913 -410.057452) (xy 56.696913 -410.057455)
			(xy 58.134423 -410.057455) (xy 58.134423 -410.002945) (xy 58.142181 -409.948989) (xy 58.157538 -409.896686)
			(xy 58.180183 -409.847102) (xy 58.209654 -409.801244) (xy 58.245351 -409.760048) (xy 58.286548 -409.724351)
			(xy 58.332405 -409.694881) (xy 58.38199 -409.672237) (xy 58.434293 -409.65688) (xy 58.488249 -409.649123)
			(xy 58.515504 -409.64866) (xy 59.379104 -409.64866) (xy 59.406353 -409.64921) (xy 59.460295 -409.656967)
			(xy 59.512585 -409.672321) (xy 59.562158 -409.69496) (xy 59.608004 -409.724424) (xy 59.64919 -409.760113)
			(xy 59.684878 -409.801299) (xy 59.714342 -409.847146) (xy 59.73698 -409.896718) (xy 59.752334 -409.949008)
			(xy 59.76009 -410.002951) (xy 59.76009 -410.057449) (xy 59.760089 -410.057457) (xy 61.197623 -410.057457)
			(xy 61.197623 -410.002943) (xy 61.205382 -409.948983) (xy 61.220741 -409.896678) (xy 61.243389 -409.84709)
			(xy 61.272864 -409.801231) (xy 61.308565 -409.760034) (xy 61.349767 -409.724337) (xy 61.395629 -409.694868)
			(xy 61.445219 -409.672226) (xy 61.497527 -409.656872) (xy 61.551487 -409.64912) (xy 61.578744 -409.64866)
			(xy 62.442344 -409.64866) (xy 62.469591 -409.649213) (xy 62.523529 -409.656974) (xy 62.575814 -409.672332)
			(xy 62.625382 -409.694973) (xy 62.671223 -409.724438) (xy 62.712404 -409.760127) (xy 62.748088 -409.801313)
			(xy 62.777548 -409.847157) (xy 62.800184 -409.896727) (xy 62.815535 -409.949014) (xy 62.82329 -410.002953)
			(xy 62.82329 -410.057447) (xy 62.823289 -410.057453) (xy 64.260946 -410.057453) (xy 64.260946 -410.002947)
			(xy 64.268703 -409.948996) (xy 64.284058 -409.896698) (xy 64.3067 -409.847118) (xy 64.336167 -409.801265)
			(xy 64.37186 -409.760071) (xy 64.413052 -409.724377) (xy 64.458904 -409.694908) (xy 64.508483 -409.672264)
			(xy 64.560781 -409.656906) (xy 64.614731 -409.649147) (xy 64.641984 -409.64866) (xy 65.505584 -409.64866)
			(xy 65.532835 -409.649186) (xy 65.586783 -409.656941) (xy 65.639079 -409.672294) (xy 65.688657 -409.694934)
			(xy 65.734508 -409.724399) (xy 65.775699 -409.760089) (xy 65.811392 -409.801279) (xy 65.840859 -409.847129)
			(xy 65.8635 -409.896706) (xy 65.878856 -409.949001) (xy 65.886613 -410.002949) (xy 65.886613 -410.057451)
			(xy 65.886612 -410.057456) (xy 67.324123 -410.057456) (xy 67.324123 -410.002944) (xy 67.331881 -409.948986)
			(xy 67.34724 -409.896682) (xy 67.369886 -409.847096) (xy 67.399359 -409.801238) (xy 67.435058 -409.760041)
			(xy 67.476257 -409.724344) (xy 67.522117 -409.694874) (xy 67.571704 -409.672231) (xy 67.62401 -409.656876)
			(xy 67.677968 -409.649121) (xy 67.705224 -409.64866) (xy 68.568824 -409.64866) (xy 68.596072 -409.649212)
			(xy 68.650012 -409.65697) (xy 68.7023 -409.672326) (xy 68.75187 -409.694967) (xy 68.797713 -409.724431)
			(xy 68.838897 -409.76012) (xy 68.874583 -409.801306) (xy 68.904045 -409.847151) (xy 68.926682 -409.896723)
			(xy 68.942035 -409.949011) (xy 68.94979 -410.002952) (xy 68.94979 -410.057448) (xy 68.949789 -410.057452)
			(xy 70.387446 -410.057452) (xy 70.387446 -410.002948) (xy 70.395202 -409.948999) (xy 70.410557 -409.896703)
			(xy 70.433197 -409.847124) (xy 70.462662 -409.801271) (xy 70.498353 -409.760079) (xy 70.539542 -409.724384)
			(xy 70.585392 -409.694914) (xy 70.634969 -409.672269) (xy 70.687264 -409.65691) (xy 70.741212 -409.649148)
			(xy 70.768464 -409.64866) (xy 71.632064 -409.64866) (xy 71.659316 -409.649185) (xy 71.713267 -409.656937)
			(xy 71.765564 -409.672289) (xy 71.815145 -409.694927) (xy 71.860999 -409.724392) (xy 71.902192 -409.760082)
			(xy 71.937887 -409.801273) (xy 71.967356 -409.847124) (xy 71.989999 -409.896702) (xy 72.005355 -409.948998)
			(xy 72.013113 -410.002948) (xy 72.013113 -410.057452) (xy 72.013113 -410.057455) (xy 73.450623 -410.057455)
			(xy 73.450623 -410.002945) (xy 73.458381 -409.948989) (xy 73.473738 -409.896686) (xy 73.496383 -409.847102)
			(xy 73.525854 -409.801244) (xy 73.561551 -409.760048) (xy 73.602748 -409.724351) (xy 73.648605 -409.694881)
			(xy 73.69819 -409.672237) (xy 73.750493 -409.65688) (xy 73.804449 -409.649123) (xy 73.831704 -409.64866)
			(xy 74.695304 -409.64866) (xy 74.722553 -409.64921) (xy 74.776495 -409.656967) (xy 74.828785 -409.672321)
			(xy 74.878358 -409.69496) (xy 74.924204 -409.724424) (xy 74.96539 -409.760113) (xy 75.001078 -409.801299)
			(xy 75.030542 -409.847146) (xy 75.05318 -409.896718) (xy 75.068534 -409.949008) (xy 75.07629 -410.002951)
			(xy 75.07629 -410.057449) (xy 75.076289 -410.057457) (xy 76.513823 -410.057457) (xy 76.513823 -410.002943)
			(xy 76.521582 -409.948983) (xy 76.536941 -409.896678) (xy 76.559589 -409.84709) (xy 76.589064 -409.801231)
			(xy 76.624765 -409.760034) (xy 76.665967 -409.724337) (xy 76.711829 -409.694868) (xy 76.761419 -409.672226)
			(xy 76.813727 -409.656872) (xy 76.867687 -409.64912) (xy 76.894944 -409.64866) (xy 77.758544 -409.64866)
			(xy 77.785791 -409.649213) (xy 77.839729 -409.656974) (xy 77.892014 -409.672332) (xy 77.941582 -409.694973)
			(xy 77.987423 -409.724438) (xy 78.028604 -409.760127) (xy 78.064288 -409.801313) (xy 78.093748 -409.847157)
			(xy 78.116384 -409.896727) (xy 78.131735 -409.949014) (xy 78.13949 -410.002953) (xy 78.13949 -410.057447)
			(xy 78.139489 -410.057453) (xy 79.577146 -410.057453) (xy 79.577146 -410.002947) (xy 79.584903 -409.948996)
			(xy 79.600258 -409.896698) (xy 79.6229 -409.847118) (xy 79.652367 -409.801265) (xy 79.68806 -409.760071)
			(xy 79.729252 -409.724377) (xy 79.775104 -409.694908) (xy 79.824683 -409.672264) (xy 79.876981 -409.656906)
			(xy 79.930931 -409.649147) (xy 79.958184 -409.64866) (xy 80.821784 -409.64866) (xy 80.849035 -409.649186)
			(xy 80.902983 -409.656941) (xy 80.955279 -409.672294) (xy 81.004857 -409.694934) (xy 81.050708 -409.724399)
			(xy 81.091899 -409.760089) (xy 81.127592 -409.801279) (xy 81.157059 -409.847129) (xy 81.1797 -409.896706)
			(xy 81.195056 -409.949001) (xy 81.202813 -410.002949) (xy 81.202813 -410.057451) (xy 81.202812 -410.057456)
			(xy 82.640323 -410.057456) (xy 82.640323 -410.002944) (xy 82.648081 -409.948986) (xy 82.66344 -409.896682)
			(xy 82.686086 -409.847096) (xy 82.715559 -409.801238) (xy 82.751258 -409.760041) (xy 82.792457 -409.724344)
			(xy 82.838317 -409.694874) (xy 82.887904 -409.672231) (xy 82.94021 -409.656876) (xy 82.994168 -409.649121)
			(xy 83.021424 -409.64866) (xy 83.885024 -409.64866) (xy 83.912272 -409.649212) (xy 83.966212 -409.65697)
			(xy 84.0185 -409.672326) (xy 84.06807 -409.694967) (xy 84.113913 -409.724431) (xy 84.155097 -409.76012)
			(xy 84.190783 -409.801306) (xy 84.220245 -409.847151) (xy 84.242882 -409.896723) (xy 84.258235 -409.949011)
			(xy 84.26599 -410.002952) (xy 84.26599 -410.057448) (xy 84.265989 -410.057452) (xy 85.703646 -410.057452)
			(xy 85.703646 -410.002948) (xy 85.711402 -409.948999) (xy 85.726757 -409.896703) (xy 85.749397 -409.847124)
			(xy 85.778862 -409.801271) (xy 85.814553 -409.760079) (xy 85.855742 -409.724384) (xy 85.901592 -409.694914)
			(xy 85.951169 -409.672269) (xy 86.003464 -409.65691) (xy 86.057412 -409.649148) (xy 86.084664 -409.64866)
			(xy 86.948264 -409.64866) (xy 86.975516 -409.649185) (xy 87.029467 -409.656937) (xy 87.081764 -409.672289)
			(xy 87.131345 -409.694927) (xy 87.177199 -409.724392) (xy 87.218392 -409.760082) (xy 87.254087 -409.801273)
			(xy 87.283556 -409.847124) (xy 87.306199 -409.896702) (xy 87.321555 -409.948998) (xy 87.329313 -410.002948)
			(xy 87.329313 -410.057452) (xy 87.329313 -410.057455) (xy 88.766823 -410.057455) (xy 88.766823 -410.002945)
			(xy 88.774581 -409.948989) (xy 88.789938 -409.896686) (xy 88.812583 -409.847102) (xy 88.842054 -409.801244)
			(xy 88.877751 -409.760048) (xy 88.918948 -409.724351) (xy 88.964805 -409.694881) (xy 89.01439 -409.672237)
			(xy 89.066693 -409.65688) (xy 89.120649 -409.649123) (xy 89.147904 -409.64866) (xy 90.011504 -409.64866)
			(xy 90.038753 -409.64921) (xy 90.092695 -409.656967) (xy 90.144985 -409.672321) (xy 90.194558 -409.69496)
			(xy 90.240404 -409.724424) (xy 90.28159 -409.760113) (xy 90.317278 -409.801299) (xy 90.346742 -409.847146)
			(xy 90.36938 -409.896718) (xy 90.384734 -409.949008) (xy 90.39249 -410.002951) (xy 90.39249 -410.057449)
			(xy 90.392489 -410.057457) (xy 91.830023 -410.057457) (xy 91.830023 -410.002943) (xy 91.837782 -409.948983)
			(xy 91.853141 -409.896678) (xy 91.875789 -409.84709) (xy 91.905264 -409.801231) (xy 91.940965 -409.760034)
			(xy 91.982167 -409.724337) (xy 92.028029 -409.694868) (xy 92.077619 -409.672226) (xy 92.129927 -409.656872)
			(xy 92.183887 -409.64912) (xy 92.211144 -409.64866) (xy 93.074744 -409.64866) (xy 93.101991 -409.649213)
			(xy 93.155929 -409.656974) (xy 93.208214 -409.672332) (xy 93.257782 -409.694973) (xy 93.303623 -409.724438)
			(xy 93.344804 -409.760127) (xy 93.380488 -409.801313) (xy 93.409948 -409.847157) (xy 93.432584 -409.896727)
			(xy 93.447935 -409.949014) (xy 93.45569 -410.002953) (xy 93.45569 -410.057447) (xy 93.455689 -410.057453)
			(xy 94.893346 -410.057453) (xy 94.893346 -410.002947) (xy 94.901103 -409.948996) (xy 94.916458 -409.896698)
			(xy 94.9391 -409.847118) (xy 94.968567 -409.801265) (xy 95.00426 -409.760071) (xy 95.045452 -409.724377)
			(xy 95.091304 -409.694908) (xy 95.140883 -409.672264) (xy 95.193181 -409.656906) (xy 95.247131 -409.649147)
			(xy 95.274384 -409.64866) (xy 96.137984 -409.64866) (xy 96.165235 -409.649186) (xy 96.219183 -409.656941)
			(xy 96.271479 -409.672294) (xy 96.321057 -409.694934) (xy 96.366908 -409.724399) (xy 96.408099 -409.760089)
			(xy 96.443792 -409.801279) (xy 96.473259 -409.847129) (xy 96.4959 -409.896706) (xy 96.511256 -409.949001)
			(xy 96.519013 -410.002949) (xy 96.519013 -410.057451) (xy 96.511256 -410.111399) (xy 96.4959 -410.163694)
			(xy 96.473259 -410.213271) (xy 96.443792 -410.259121) (xy 96.408099 -410.300311) (xy 96.366908 -410.336001)
			(xy 96.321057 -410.365466) (xy 96.271479 -410.388106) (xy 96.219183 -410.403459) (xy 96.165235 -410.411214)
			(xy 96.137984 -410.411676) (xy 95.274384 -410.411676) (xy 95.247131 -410.411253) (xy 95.193181 -410.403494)
			(xy 95.140883 -410.388136) (xy 95.091304 -410.365492) (xy 95.045452 -410.336023) (xy 95.00426 -410.300329)
			(xy 94.968567 -410.259135) (xy 94.9391 -410.213282) (xy 94.916458 -410.163702) (xy 94.901103 -410.111404)
			(xy 94.893346 -410.057453) (xy 93.455689 -410.057453) (xy 93.447935 -410.111386) (xy 93.432584 -410.163673)
			(xy 93.409948 -410.213243) (xy 93.380488 -410.259087) (xy 93.344804 -410.300273) (xy 93.303623 -410.335962)
			(xy 93.257782 -410.365427) (xy 93.208214 -410.388068) (xy 93.155929 -410.403426) (xy 93.101991 -410.411187)
			(xy 93.074744 -410.411676) (xy 92.211144 -410.411676) (xy 92.183887 -410.41128) (xy 92.129927 -410.403528)
			(xy 92.077619 -410.388174) (xy 92.028029 -410.365532) (xy 91.982167 -410.336063) (xy 91.940965 -410.300366)
			(xy 91.905264 -410.259169) (xy 91.875789 -410.21331) (xy 91.853141 -410.163722) (xy 91.837782 -410.111417)
			(xy 91.830023 -410.057457) (xy 90.392489 -410.057457) (xy 90.384734 -410.111392) (xy 90.36938 -410.163682)
			(xy 90.346742 -410.213254) (xy 90.317278 -410.259101) (xy 90.28159 -410.300287) (xy 90.240404 -410.335976)
			(xy 90.194558 -410.36544) (xy 90.144985 -410.388079) (xy 90.092695 -410.403433) (xy 90.038753 -410.41119)
			(xy 90.011504 -410.411676) (xy 89.147904 -410.411676) (xy 89.120649 -410.411277) (xy 89.066693 -410.40352)
			(xy 89.01439 -410.388163) (xy 88.964805 -410.365519) (xy 88.918948 -410.336049) (xy 88.877751 -410.300352)
			(xy 88.842054 -410.259156) (xy 88.812583 -410.213298) (xy 88.789938 -410.163714) (xy 88.774581 -410.111411)
			(xy 88.766823 -410.057455) (xy 87.329313 -410.057455) (xy 87.321555 -410.111402) (xy 87.306199 -410.163698)
			(xy 87.283556 -410.213276) (xy 87.254087 -410.259127) (xy 87.218392 -410.300318) (xy 87.177199 -410.336008)
			(xy 87.131345 -410.365473) (xy 87.081764 -410.388111) (xy 87.029467 -410.403463) (xy 86.975516 -410.411215)
			(xy 86.948264 -410.411676) (xy 86.084664 -410.411676) (xy 86.057412 -410.411252) (xy 86.003464 -410.40349)
			(xy 85.951169 -410.388131) (xy 85.901592 -410.365486) (xy 85.855742 -410.336016) (xy 85.814553 -410.300321)
			(xy 85.778862 -410.259129) (xy 85.749397 -410.213276) (xy 85.726757 -410.163697) (xy 85.711402 -410.111401)
			(xy 85.703646 -410.057452) (xy 84.265989 -410.057452) (xy 84.258235 -410.111389) (xy 84.242882 -410.163677)
			(xy 84.220245 -410.213249) (xy 84.190783 -410.259094) (xy 84.155097 -410.30028) (xy 84.113913 -410.335969)
			(xy 84.06807 -410.365433) (xy 84.0185 -410.388074) (xy 83.966212 -410.40343) (xy 83.912272 -410.411188)
			(xy 83.885024 -410.411676) (xy 83.021424 -410.411676) (xy 82.994168 -410.411279) (xy 82.94021 -410.403524)
			(xy 82.887904 -410.388169) (xy 82.838317 -410.365526) (xy 82.792457 -410.336056) (xy 82.751258 -410.300359)
			(xy 82.715559 -410.259162) (xy 82.686086 -410.213304) (xy 82.66344 -410.163718) (xy 82.648081 -410.111414)
			(xy 82.640323 -410.057456) (xy 81.202812 -410.057456) (xy 81.195056 -410.111399) (xy 81.1797 -410.163694)
			(xy 81.157059 -410.213271) (xy 81.127592 -410.259121) (xy 81.091899 -410.300311) (xy 81.050708 -410.336001)
			(xy 81.004857 -410.365466) (xy 80.955279 -410.388106) (xy 80.902983 -410.403459) (xy 80.849035 -410.411214)
			(xy 80.821784 -410.411676) (xy 79.958184 -410.411676) (xy 79.930931 -410.411253) (xy 79.876981 -410.403494)
			(xy 79.824683 -410.388136) (xy 79.775104 -410.365492) (xy 79.729252 -410.336023) (xy 79.68806 -410.300329)
			(xy 79.652367 -410.259135) (xy 79.6229 -410.213282) (xy 79.600258 -410.163702) (xy 79.584903 -410.111404)
			(xy 79.577146 -410.057453) (xy 78.139489 -410.057453) (xy 78.131735 -410.111386) (xy 78.116384 -410.163673)
			(xy 78.093748 -410.213243) (xy 78.064288 -410.259087) (xy 78.028604 -410.300273) (xy 77.987423 -410.335962)
			(xy 77.941582 -410.365427) (xy 77.892014 -410.388068) (xy 77.839729 -410.403426) (xy 77.785791 -410.411187)
			(xy 77.758544 -410.411676) (xy 76.894944 -410.411676) (xy 76.867687 -410.41128) (xy 76.813727 -410.403528)
			(xy 76.761419 -410.388174) (xy 76.711829 -410.365532) (xy 76.665967 -410.336063) (xy 76.624765 -410.300366)
			(xy 76.589064 -410.259169) (xy 76.559589 -410.21331) (xy 76.536941 -410.163722) (xy 76.521582 -410.111417)
			(xy 76.513823 -410.057457) (xy 75.076289 -410.057457) (xy 75.068534 -410.111392) (xy 75.05318 -410.163682)
			(xy 75.030542 -410.213254) (xy 75.001078 -410.259101) (xy 74.96539 -410.300287) (xy 74.924204 -410.335976)
			(xy 74.878358 -410.36544) (xy 74.828785 -410.388079) (xy 74.776495 -410.403433) (xy 74.722553 -410.41119)
			(xy 74.695304 -410.411676) (xy 73.831704 -410.411676) (xy 73.804449 -410.411277) (xy 73.750493 -410.40352)
			(xy 73.69819 -410.388163) (xy 73.648605 -410.365519) (xy 73.602748 -410.336049) (xy 73.561551 -410.300352)
			(xy 73.525854 -410.259156) (xy 73.496383 -410.213298) (xy 73.473738 -410.163714) (xy 73.458381 -410.111411)
			(xy 73.450623 -410.057455) (xy 72.013113 -410.057455) (xy 72.005355 -410.111402) (xy 71.989999 -410.163698)
			(xy 71.967356 -410.213276) (xy 71.937887 -410.259127) (xy 71.902192 -410.300318) (xy 71.860999 -410.336008)
			(xy 71.815145 -410.365473) (xy 71.765564 -410.388111) (xy 71.713267 -410.403463) (xy 71.659316 -410.411215)
			(xy 71.632064 -410.411676) (xy 70.768464 -410.411676) (xy 70.741212 -410.411252) (xy 70.687264 -410.40349)
			(xy 70.634969 -410.388131) (xy 70.585392 -410.365486) (xy 70.539542 -410.336016) (xy 70.498353 -410.300321)
			(xy 70.462662 -410.259129) (xy 70.433197 -410.213276) (xy 70.410557 -410.163697) (xy 70.395202 -410.111401)
			(xy 70.387446 -410.057452) (xy 68.949789 -410.057452) (xy 68.942035 -410.111389) (xy 68.926682 -410.163677)
			(xy 68.904045 -410.213249) (xy 68.874583 -410.259094) (xy 68.838897 -410.30028) (xy 68.797713 -410.335969)
			(xy 68.75187 -410.365433) (xy 68.7023 -410.388074) (xy 68.650012 -410.40343) (xy 68.596072 -410.411188)
			(xy 68.568824 -410.411676) (xy 67.705224 -410.411676) (xy 67.677968 -410.411279) (xy 67.62401 -410.403524)
			(xy 67.571704 -410.388169) (xy 67.522117 -410.365526) (xy 67.476257 -410.336056) (xy 67.435058 -410.300359)
			(xy 67.399359 -410.259162) (xy 67.369886 -410.213304) (xy 67.34724 -410.163718) (xy 67.331881 -410.111414)
			(xy 67.324123 -410.057456) (xy 65.886612 -410.057456) (xy 65.878856 -410.111399) (xy 65.8635 -410.163694)
			(xy 65.840859 -410.213271) (xy 65.811392 -410.259121) (xy 65.775699 -410.300311) (xy 65.734508 -410.336001)
			(xy 65.688657 -410.365466) (xy 65.639079 -410.388106) (xy 65.586783 -410.403459) (xy 65.532835 -410.411214)
			(xy 65.505584 -410.411676) (xy 64.641984 -410.411676) (xy 64.614731 -410.411253) (xy 64.560781 -410.403494)
			(xy 64.508483 -410.388136) (xy 64.458904 -410.365492) (xy 64.413052 -410.336023) (xy 64.37186 -410.300329)
			(xy 64.336167 -410.259135) (xy 64.3067 -410.213282) (xy 64.284058 -410.163702) (xy 64.268703 -410.111404)
			(xy 64.260946 -410.057453) (xy 62.823289 -410.057453) (xy 62.815535 -410.111386) (xy 62.800184 -410.163673)
			(xy 62.777548 -410.213243) (xy 62.748088 -410.259087) (xy 62.712404 -410.300273) (xy 62.671223 -410.335962)
			(xy 62.625382 -410.365427) (xy 62.575814 -410.388068) (xy 62.523529 -410.403426) (xy 62.469591 -410.411187)
			(xy 62.442344 -410.411676) (xy 61.578744 -410.411676) (xy 61.551487 -410.41128) (xy 61.497527 -410.403528)
			(xy 61.445219 -410.388174) (xy 61.395629 -410.365532) (xy 61.349767 -410.336063) (xy 61.308565 -410.300366)
			(xy 61.272864 -410.259169) (xy 61.243389 -410.21331) (xy 61.220741 -410.163722) (xy 61.205382 -410.111417)
			(xy 61.197623 -410.057457) (xy 59.760089 -410.057457) (xy 59.752334 -410.111392) (xy 59.73698 -410.163682)
			(xy 59.714342 -410.213254) (xy 59.684878 -410.259101) (xy 59.64919 -410.300287) (xy 59.608004 -410.335976)
			(xy 59.562158 -410.36544) (xy 59.512585 -410.388079) (xy 59.460295 -410.403433) (xy 59.406353 -410.41119)
			(xy 59.379104 -410.411676) (xy 58.515504 -410.411676) (xy 58.488249 -410.411277) (xy 58.434293 -410.40352)
			(xy 58.38199 -410.388163) (xy 58.332405 -410.365519) (xy 58.286548 -410.336049) (xy 58.245351 -410.300352)
			(xy 58.209654 -410.259156) (xy 58.180183 -410.213298) (xy 58.157538 -410.163714) (xy 58.142181 -410.111411)
			(xy 58.134423 -410.057455) (xy 56.696913 -410.057455) (xy 56.689155 -410.111402) (xy 56.673799 -410.163698)
			(xy 56.651156 -410.213276) (xy 56.621687 -410.259127) (xy 56.585992 -410.300318) (xy 56.544799 -410.336008)
			(xy 56.498945 -410.365473) (xy 56.449364 -410.388111) (xy 56.397067 -410.403463) (xy 56.343116 -410.411215)
			(xy 56.315864 -410.411676) (xy 55.452264 -410.411676) (xy 55.425012 -410.411252) (xy 55.371064 -410.40349)
			(xy 55.318769 -410.388131) (xy 55.269192 -410.365486) (xy 55.223342 -410.336016) (xy 55.182153 -410.300321)
			(xy 55.146462 -410.259129) (xy 55.116997 -410.213276) (xy 55.094357 -410.163697) (xy 55.079002 -410.111401)
			(xy 55.071246 -410.057452) (xy 53.633589 -410.057452) (xy 53.625835 -410.111389) (xy 53.610482 -410.163677)
			(xy 53.587845 -410.213249) (xy 53.558383 -410.259094) (xy 53.522697 -410.30028) (xy 53.481513 -410.335969)
			(xy 53.43567 -410.365433) (xy 53.3861 -410.388074) (xy 53.333812 -410.40343) (xy 53.279872 -410.411188)
			(xy 53.252624 -410.411676) (xy 52.389024 -410.411676) (xy 52.361768 -410.411279) (xy 52.30781 -410.403524)
			(xy 52.255504 -410.388169) (xy 52.205917 -410.365526) (xy 52.160057 -410.336056) (xy 52.118858 -410.300359)
			(xy 52.083159 -410.259162) (xy 52.053686 -410.213304) (xy 52.03104 -410.163718) (xy 52.015681 -410.111414)
			(xy 52.007923 -410.057456) (xy 50.570412 -410.057456) (xy 50.562656 -410.111399) (xy 50.5473 -410.163694)
			(xy 50.524659 -410.213271) (xy 50.495192 -410.259121) (xy 50.459499 -410.300311) (xy 50.418308 -410.336001)
			(xy 50.372457 -410.365466) (xy 50.322879 -410.388106) (xy 50.270583 -410.403459) (xy 50.216635 -410.411214)
			(xy 50.189384 -410.411676) (xy 49.325784 -410.411676) (xy 49.298531 -410.411253) (xy 49.244581 -410.403494)
			(xy 49.192283 -410.388136) (xy 49.142704 -410.365492) (xy 49.096852 -410.336023) (xy 49.05566 -410.300329)
			(xy 49.019967 -410.259135) (xy 48.9905 -410.213282) (xy 48.967858 -410.163702) (xy 48.952503 -410.111404)
			(xy 48.944746 -410.057453) (xy 7.00913 -410.057453) (xy 7.00913 -413.4485) (xy 38.974268 -413.4485)
			(xy 38.974268 -412.5849) (xy 38.974754 -412.557631) (xy 38.982516 -412.503647) (xy 38.997881 -412.451317)
			(xy 39.020538 -412.401707) (xy 39.050024 -412.355826) (xy 39.085739 -412.314609) (xy 39.126956 -412.278894)
			(xy 39.172837 -412.249408) (xy 39.222447 -412.226751) (xy 39.274777 -412.211386) (xy 39.328761 -412.203624)
			(xy 39.383299 -412.203624) (xy 39.437283 -412.211386) (xy 39.489613 -412.226751) (xy 39.539223 -412.249408)
			(xy 39.585104 -412.278894) (xy 39.626321 -412.314609) (xy 39.662036 -412.355826) (xy 39.691522 -412.401707)
			(xy 39.714179 -412.451317) (xy 39.729544 -412.503647) (xy 39.737306 -412.557631) (xy 39.737792 -412.5849)
			(xy 39.737792 -412.597452) (xy 47.413146 -412.597452) (xy 47.413146 -412.542948) (xy 47.420902 -412.488999)
			(xy 47.436257 -412.436703) (xy 47.458897 -412.387124) (xy 47.488362 -412.341271) (xy 47.524053 -412.300079)
			(xy 47.565242 -412.264384) (xy 47.611092 -412.234914) (xy 47.660669 -412.212269) (xy 47.712964 -412.19691)
			(xy 47.766912 -412.189148) (xy 47.794164 -412.18866) (xy 48.657764 -412.18866) (xy 48.685016 -412.189185)
			(xy 48.738967 -412.196937) (xy 48.791264 -412.212289) (xy 48.840845 -412.234927) (xy 48.886699 -412.264392)
			(xy 48.927892 -412.300082) (xy 48.963587 -412.341273) (xy 48.993056 -412.387124) (xy 49.015699 -412.436702)
			(xy 49.031055 -412.488998) (xy 49.038813 -412.542948) (xy 49.038813 -412.597452) (xy 49.038813 -412.597455)
			(xy 50.476323 -412.597455) (xy 50.476323 -412.542945) (xy 50.484081 -412.488989) (xy 50.499438 -412.436686)
			(xy 50.522083 -412.387102) (xy 50.551554 -412.341244) (xy 50.587251 -412.300048) (xy 50.628448 -412.264351)
			(xy 50.674305 -412.234881) (xy 50.72389 -412.212237) (xy 50.776193 -412.19688) (xy 50.830149 -412.189123)
			(xy 50.857404 -412.18866) (xy 51.721004 -412.18866) (xy 51.748253 -412.18921) (xy 51.802195 -412.196967)
			(xy 51.854485 -412.212321) (xy 51.904058 -412.23496) (xy 51.949904 -412.264424) (xy 51.99109 -412.300113)
			(xy 52.026778 -412.341299) (xy 52.056242 -412.387146) (xy 52.07888 -412.436718) (xy 52.094234 -412.489008)
			(xy 52.10199 -412.542951) (xy 52.10199 -412.597449) (xy 52.101989 -412.597457) (xy 53.539523 -412.597457)
			(xy 53.539523 -412.542943) (xy 53.547282 -412.488983) (xy 53.562641 -412.436678) (xy 53.585289 -412.38709)
			(xy 53.614764 -412.341231) (xy 53.650465 -412.300034) (xy 53.691667 -412.264337) (xy 53.737529 -412.234868)
			(xy 53.787119 -412.212226) (xy 53.839427 -412.196872) (xy 53.893387 -412.18912) (xy 53.920644 -412.18866)
			(xy 54.784244 -412.18866) (xy 54.811491 -412.189213) (xy 54.865429 -412.196974) (xy 54.917714 -412.212332)
			(xy 54.967282 -412.234973) (xy 55.013123 -412.264438) (xy 55.054304 -412.300127) (xy 55.089988 -412.341313)
			(xy 55.119448 -412.387157) (xy 55.142084 -412.436727) (xy 55.157435 -412.489014) (xy 55.16519 -412.542953)
			(xy 55.16519 -412.597447) (xy 55.165189 -412.597453) (xy 56.602846 -412.597453) (xy 56.602846 -412.542947)
			(xy 56.610603 -412.488996) (xy 56.625958 -412.436698) (xy 56.6486 -412.387118) (xy 56.678067 -412.341265)
			(xy 56.71376 -412.300071) (xy 56.754952 -412.264377) (xy 56.800804 -412.234908) (xy 56.850383 -412.212264)
			(xy 56.902681 -412.196906) (xy 56.956631 -412.189147) (xy 56.983884 -412.18866) (xy 57.847484 -412.18866)
			(xy 57.874735 -412.189186) (xy 57.928683 -412.196941) (xy 57.980979 -412.212294) (xy 58.030557 -412.234934)
			(xy 58.076408 -412.264399) (xy 58.117599 -412.300089) (xy 58.153292 -412.341279) (xy 58.182759 -412.387129)
			(xy 58.2054 -412.436706) (xy 58.220756 -412.489001) (xy 58.228513 -412.542949) (xy 58.228513 -412.597451)
			(xy 58.228512 -412.597456) (xy 59.666023 -412.597456) (xy 59.666023 -412.542944) (xy 59.673781 -412.488986)
			(xy 59.68914 -412.436682) (xy 59.711786 -412.387096) (xy 59.741259 -412.341238) (xy 59.776958 -412.300041)
			(xy 59.818157 -412.264344) (xy 59.864017 -412.234874) (xy 59.913604 -412.212231) (xy 59.96591 -412.196876)
			(xy 60.019868 -412.189121) (xy 60.047124 -412.18866) (xy 60.910724 -412.18866) (xy 60.937972 -412.189212)
			(xy 60.991912 -412.19697) (xy 61.0442 -412.212326) (xy 61.09377 -412.234967) (xy 61.139613 -412.264431)
			(xy 61.180797 -412.30012) (xy 61.216483 -412.341306) (xy 61.245945 -412.387151) (xy 61.268582 -412.436723)
			(xy 61.283935 -412.489011) (xy 61.29169 -412.542952) (xy 61.29169 -412.597448) (xy 61.291689 -412.597452)
			(xy 62.729346 -412.597452) (xy 62.729346 -412.542948) (xy 62.737102 -412.488999) (xy 62.752457 -412.436703)
			(xy 62.775097 -412.387124) (xy 62.804562 -412.341271) (xy 62.840253 -412.300079) (xy 62.881442 -412.264384)
			(xy 62.927292 -412.234914) (xy 62.976869 -412.212269) (xy 63.029164 -412.19691) (xy 63.083112 -412.189148)
			(xy 63.110364 -412.18866) (xy 63.973964 -412.18866) (xy 64.001216 -412.189185) (xy 64.055167 -412.196937)
			(xy 64.107464 -412.212289) (xy 64.157045 -412.234927) (xy 64.202899 -412.264392) (xy 64.244092 -412.300082)
			(xy 64.279787 -412.341273) (xy 64.309256 -412.387124) (xy 64.331899 -412.436702) (xy 64.347255 -412.488998)
			(xy 64.355013 -412.542948) (xy 64.355013 -412.597452) (xy 64.355013 -412.597455) (xy 65.792523 -412.597455)
			(xy 65.792523 -412.542945) (xy 65.800281 -412.488989) (xy 65.815638 -412.436686) (xy 65.838283 -412.387102)
			(xy 65.867754 -412.341244) (xy 65.903451 -412.300048) (xy 65.944648 -412.264351) (xy 65.990505 -412.234881)
			(xy 66.04009 -412.212237) (xy 66.092393 -412.19688) (xy 66.146349 -412.189123) (xy 66.173604 -412.18866)
			(xy 67.037204 -412.18866) (xy 67.064453 -412.18921) (xy 67.118395 -412.196967) (xy 67.170685 -412.212321)
			(xy 67.220258 -412.23496) (xy 67.266104 -412.264424) (xy 67.30729 -412.300113) (xy 67.342978 -412.341299)
			(xy 67.372442 -412.387146) (xy 67.39508 -412.436718) (xy 67.410434 -412.489008) (xy 67.41819 -412.542951)
			(xy 67.41819 -412.597449) (xy 67.418189 -412.597457) (xy 68.855723 -412.597457) (xy 68.855723 -412.542943)
			(xy 68.863482 -412.488983) (xy 68.878841 -412.436678) (xy 68.901489 -412.38709) (xy 68.930964 -412.341231)
			(xy 68.966665 -412.300034) (xy 69.007867 -412.264337) (xy 69.053729 -412.234868) (xy 69.103319 -412.212226)
			(xy 69.155627 -412.196872) (xy 69.209587 -412.18912) (xy 69.236844 -412.18866) (xy 70.100444 -412.18866)
			(xy 70.127691 -412.189213) (xy 70.181629 -412.196974) (xy 70.233914 -412.212332) (xy 70.283482 -412.234973)
			(xy 70.329323 -412.264438) (xy 70.370504 -412.300127) (xy 70.406188 -412.341313) (xy 70.435648 -412.387157)
			(xy 70.458284 -412.436727) (xy 70.473635 -412.489014) (xy 70.48139 -412.542953) (xy 70.48139 -412.597447)
			(xy 70.481389 -412.597453) (xy 71.919046 -412.597453) (xy 71.919046 -412.542947) (xy 71.926803 -412.488996)
			(xy 71.942158 -412.436698) (xy 71.9648 -412.387118) (xy 71.994267 -412.341265) (xy 72.02996 -412.300071)
			(xy 72.071152 -412.264377) (xy 72.117004 -412.234908) (xy 72.166583 -412.212264) (xy 72.218881 -412.196906)
			(xy 72.272831 -412.189147) (xy 72.300084 -412.18866) (xy 73.163684 -412.18866) (xy 73.190935 -412.189186)
			(xy 73.244883 -412.196941) (xy 73.297179 -412.212294) (xy 73.346757 -412.234934) (xy 73.392608 -412.264399)
			(xy 73.433799 -412.300089) (xy 73.469492 -412.341279) (xy 73.498959 -412.387129) (xy 73.5216 -412.436706)
			(xy 73.536956 -412.489001) (xy 73.544713 -412.542949) (xy 73.544713 -412.597451) (xy 73.544712 -412.597456)
			(xy 74.982223 -412.597456) (xy 74.982223 -412.542944) (xy 74.989981 -412.488986) (xy 75.00534 -412.436682)
			(xy 75.027986 -412.387096) (xy 75.057459 -412.341238) (xy 75.093158 -412.300041) (xy 75.134357 -412.264344)
			(xy 75.180217 -412.234874) (xy 75.229804 -412.212231) (xy 75.28211 -412.196876) (xy 75.336068 -412.189121)
			(xy 75.363324 -412.18866) (xy 76.226924 -412.18866) (xy 76.254172 -412.189212) (xy 76.308112 -412.19697)
			(xy 76.3604 -412.212326) (xy 76.40997 -412.234967) (xy 76.455813 -412.264431) (xy 76.496997 -412.30012)
			(xy 76.532683 -412.341306) (xy 76.562145 -412.387151) (xy 76.584782 -412.436723) (xy 76.600135 -412.489011)
			(xy 76.60789 -412.542952) (xy 76.60789 -412.597448) (xy 76.607889 -412.597452) (xy 78.045546 -412.597452)
			(xy 78.045546 -412.542948) (xy 78.053302 -412.488999) (xy 78.068657 -412.436703) (xy 78.091297 -412.387124)
			(xy 78.120762 -412.341271) (xy 78.156453 -412.300079) (xy 78.197642 -412.264384) (xy 78.243492 -412.234914)
			(xy 78.293069 -412.212269) (xy 78.345364 -412.19691) (xy 78.399312 -412.189148) (xy 78.426564 -412.18866)
			(xy 79.290164 -412.18866) (xy 79.317416 -412.189185) (xy 79.371367 -412.196937) (xy 79.423664 -412.212289)
			(xy 79.473245 -412.234927) (xy 79.519099 -412.264392) (xy 79.560292 -412.300082) (xy 79.595987 -412.341273)
			(xy 79.625456 -412.387124) (xy 79.648099 -412.436702) (xy 79.663455 -412.488998) (xy 79.671213 -412.542948)
			(xy 79.671213 -412.597452) (xy 79.671213 -412.597455) (xy 81.108723 -412.597455) (xy 81.108723 -412.542945)
			(xy 81.116481 -412.488989) (xy 81.131838 -412.436686) (xy 81.154483 -412.387102) (xy 81.183954 -412.341244)
			(xy 81.219651 -412.300048) (xy 81.260848 -412.264351) (xy 81.306705 -412.234881) (xy 81.35629 -412.212237)
			(xy 81.408593 -412.19688) (xy 81.462549 -412.189123) (xy 81.489804 -412.18866) (xy 82.353404 -412.18866)
			(xy 82.380653 -412.18921) (xy 82.434595 -412.196967) (xy 82.486885 -412.212321) (xy 82.536458 -412.23496)
			(xy 82.582304 -412.264424) (xy 82.62349 -412.300113) (xy 82.659178 -412.341299) (xy 82.688642 -412.387146)
			(xy 82.71128 -412.436718) (xy 82.726634 -412.489008) (xy 82.73439 -412.542951) (xy 82.73439 -412.597449)
			(xy 82.734389 -412.597457) (xy 84.171923 -412.597457) (xy 84.171923 -412.542943) (xy 84.179682 -412.488983)
			(xy 84.195041 -412.436678) (xy 84.217689 -412.38709) (xy 84.247164 -412.341231) (xy 84.282865 -412.300034)
			(xy 84.324067 -412.264337) (xy 84.369929 -412.234868) (xy 84.419519 -412.212226) (xy 84.471827 -412.196872)
			(xy 84.525787 -412.18912) (xy 84.553044 -412.18866) (xy 85.416644 -412.18866) (xy 85.443891 -412.189213)
			(xy 85.497829 -412.196974) (xy 85.550114 -412.212332) (xy 85.599682 -412.234973) (xy 85.645523 -412.264438)
			(xy 85.686704 -412.300127) (xy 85.722388 -412.341313) (xy 85.751848 -412.387157) (xy 85.774484 -412.436727)
			(xy 85.789835 -412.489014) (xy 85.79759 -412.542953) (xy 85.79759 -412.597447) (xy 85.797589 -412.597453)
			(xy 87.235246 -412.597453) (xy 87.235246 -412.542947) (xy 87.243003 -412.488996) (xy 87.258358 -412.436698)
			(xy 87.281 -412.387118) (xy 87.310467 -412.341265) (xy 87.34616 -412.300071) (xy 87.387352 -412.264377)
			(xy 87.433204 -412.234908) (xy 87.482783 -412.212264) (xy 87.535081 -412.196906) (xy 87.589031 -412.189147)
			(xy 87.616284 -412.18866) (xy 88.479884 -412.18866) (xy 88.507135 -412.189186) (xy 88.561083 -412.196941)
			(xy 88.613379 -412.212294) (xy 88.662957 -412.234934) (xy 88.708808 -412.264399) (xy 88.749999 -412.300089)
			(xy 88.785692 -412.341279) (xy 88.815159 -412.387129) (xy 88.8378 -412.436706) (xy 88.853156 -412.489001)
			(xy 88.860913 -412.542949) (xy 88.860913 -412.597451) (xy 88.860912 -412.597456) (xy 90.298423 -412.597456)
			(xy 90.298423 -412.542944) (xy 90.306181 -412.488986) (xy 90.32154 -412.436682) (xy 90.344186 -412.387096)
			(xy 90.373659 -412.341238) (xy 90.409358 -412.300041) (xy 90.450557 -412.264344) (xy 90.496417 -412.234874)
			(xy 90.546004 -412.212231) (xy 90.59831 -412.196876) (xy 90.652268 -412.189121) (xy 90.679524 -412.18866)
			(xy 91.543124 -412.18866) (xy 91.570372 -412.189212) (xy 91.624312 -412.19697) (xy 91.6766 -412.212326)
			(xy 91.72617 -412.234967) (xy 91.772013 -412.264431) (xy 91.813197 -412.30012) (xy 91.848883 -412.341306)
			(xy 91.878345 -412.387151) (xy 91.900982 -412.436723) (xy 91.916335 -412.489011) (xy 91.92409 -412.542952)
			(xy 91.92409 -412.597448) (xy 91.924089 -412.597452) (xy 93.361746 -412.597452) (xy 93.361746 -412.542948)
			(xy 93.369502 -412.488999) (xy 93.384857 -412.436703) (xy 93.407497 -412.387124) (xy 93.436962 -412.341271)
			(xy 93.472653 -412.300079) (xy 93.513842 -412.264384) (xy 93.559692 -412.234914) (xy 93.609269 -412.212269)
			(xy 93.661564 -412.19691) (xy 93.715512 -412.189148) (xy 93.742764 -412.18866) (xy 94.606364 -412.18866)
			(xy 94.633616 -412.189185) (xy 94.687567 -412.196937) (xy 94.739864 -412.212289) (xy 94.789445 -412.234927)
			(xy 94.835299 -412.264392) (xy 94.876492 -412.300082) (xy 94.912187 -412.341273) (xy 94.941656 -412.387124)
			(xy 94.964299 -412.436702) (xy 94.979655 -412.488998) (xy 94.987413 -412.542948) (xy 94.987413 -412.597452)
			(xy 94.987413 -412.597455) (xy 114.513023 -412.597455) (xy 114.513023 -412.542945) (xy 114.520781 -412.488989)
			(xy 114.536138 -412.436686) (xy 114.558783 -412.387101) (xy 114.588254 -412.341244) (xy 114.623952 -412.300047)
			(xy 114.665149 -412.264351) (xy 114.711006 -412.23488) (xy 114.760591 -412.212236) (xy 114.812894 -412.196879)
			(xy 114.866851 -412.189123) (xy 114.894106 -412.18866) (xy 115.757706 -412.18866) (xy 115.784955 -412.189211)
			(xy 115.838897 -412.196967) (xy 115.891187 -412.212321) (xy 115.940759 -412.234961) (xy 115.986605 -412.264425)
			(xy 116.027791 -412.300113) (xy 116.063479 -412.3413) (xy 116.092942 -412.387146) (xy 116.115581 -412.436719)
			(xy 116.130934 -412.489009) (xy 116.13869 -412.542951) (xy 116.13869 -412.597449) (xy 116.138689 -412.597457)
			(xy 117.576223 -412.597457) (xy 117.576223 -412.542943) (xy 117.583982 -412.488983) (xy 117.599342 -412.436677)
			(xy 117.621989 -412.38709) (xy 117.651464 -412.341231) (xy 117.687166 -412.300033) (xy 117.728367 -412.264337)
			(xy 117.77423 -412.234867) (xy 117.82382 -412.212225) (xy 117.876128 -412.196872) (xy 117.930089 -412.18912)
			(xy 117.957346 -412.18866) (xy 118.820946 -412.18866) (xy 118.848193 -412.189213) (xy 118.902131 -412.196975)
			(xy 118.954416 -412.212332) (xy 119.003983 -412.234974) (xy 119.049824 -412.264439) (xy 119.091005 -412.300128)
			(xy 119.126688 -412.341313) (xy 119.156148 -412.387157) (xy 119.178784 -412.436727) (xy 119.194135 -412.489014)
			(xy 119.20189 -412.542953) (xy 119.20189 -412.597447) (xy 119.201889 -412.597453) (xy 120.639546 -412.597453)
			(xy 120.639546 -412.542947) (xy 120.647303 -412.488996) (xy 120.662658 -412.436698) (xy 120.6853 -412.387118)
			(xy 120.714768 -412.341264) (xy 120.750461 -412.300071) (xy 120.791653 -412.264376) (xy 120.837505 -412.234907)
			(xy 120.887085 -412.212263) (xy 120.939382 -412.196906) (xy 120.993333 -412.189147) (xy 121.020586 -412.18866)
			(xy 121.884186 -412.18866) (xy 121.911437 -412.189186) (xy 121.965385 -412.196941) (xy 122.01768 -412.212295)
			(xy 122.067258 -412.234934) (xy 122.113109 -412.264399) (xy 122.1543 -412.30009) (xy 122.189992 -412.34128)
			(xy 122.219459 -412.38713) (xy 122.242101 -412.436707) (xy 122.257456 -412.489001) (xy 122.265213 -412.542949)
			(xy 122.265213 -412.597451) (xy 122.265212 -412.597456) (xy 123.702723 -412.597456) (xy 123.702723 -412.542944)
			(xy 123.710481 -412.488986) (xy 123.72584 -412.436681) (xy 123.748486 -412.387095) (xy 123.777959 -412.341237)
			(xy 123.813659 -412.30004) (xy 123.854858 -412.264344) (xy 123.900718 -412.234874) (xy 123.950306 -412.212231)
			(xy 124.002611 -412.196876) (xy 124.05657 -412.189121) (xy 124.083826 -412.18866) (xy 124.947426 -412.18866)
			(xy 124.974674 -412.189212) (xy 125.028614 -412.196971) (xy 125.080901 -412.212327) (xy 125.130471 -412.234968)
			(xy 125.176314 -412.264432) (xy 125.217498 -412.300121) (xy 125.253184 -412.341307) (xy 125.282645 -412.387152)
			(xy 125.305282 -412.436723) (xy 125.320635 -412.489011) (xy 125.32839 -412.542952) (xy 125.32839 -412.597448)
			(xy 125.328389 -412.597452) (xy 126.766046 -412.597452) (xy 126.766046 -412.542948) (xy 126.773802 -412.488999)
			(xy 126.789157 -412.436702) (xy 126.811797 -412.387123) (xy 126.841263 -412.341271) (xy 126.876954 -412.300078)
			(xy 126.918143 -412.264383) (xy 126.963993 -412.234914) (xy 127.01357 -412.212269) (xy 127.065865 -412.196909)
			(xy 127.119814 -412.189148) (xy 127.147066 -412.18866) (xy 128.010666 -412.18866) (xy 128.037918 -412.189185)
			(xy 128.091868 -412.196937) (xy 128.144166 -412.212289) (xy 128.193746 -412.234928) (xy 128.2396 -412.264392)
			(xy 128.280793 -412.300083) (xy 128.316487 -412.341273) (xy 128.345956 -412.387124) (xy 128.368599 -412.436702)
			(xy 128.383955 -412.488999) (xy 128.391713 -412.542948) (xy 128.391713 -412.597452) (xy 128.391713 -412.597455)
			(xy 129.829223 -412.597455) (xy 129.829223 -412.542945) (xy 129.836981 -412.488989) (xy 129.852338 -412.436686)
			(xy 129.874983 -412.387101) (xy 129.904454 -412.341244) (xy 129.940152 -412.300047) (xy 129.981349 -412.264351)
			(xy 130.027206 -412.23488) (xy 130.076791 -412.212236) (xy 130.129094 -412.196879) (xy 130.183051 -412.189123)
			(xy 130.210306 -412.18866) (xy 131.073906 -412.18866) (xy 131.101155 -412.189211) (xy 131.155097 -412.196967)
			(xy 131.207387 -412.212321) (xy 131.256959 -412.234961) (xy 131.302805 -412.264425) (xy 131.343991 -412.300113)
			(xy 131.379679 -412.3413) (xy 131.409142 -412.387146) (xy 131.431781 -412.436719) (xy 131.447134 -412.489009)
			(xy 131.45489 -412.542951) (xy 131.45489 -412.597449) (xy 131.454889 -412.597457) (xy 132.892423 -412.597457)
			(xy 132.892423 -412.542943) (xy 132.900182 -412.488983) (xy 132.915542 -412.436677) (xy 132.938189 -412.38709)
			(xy 132.967664 -412.341231) (xy 133.003366 -412.300033) (xy 133.044567 -412.264337) (xy 133.09043 -412.234867)
			(xy 133.14002 -412.212225) (xy 133.192328 -412.196872) (xy 133.246289 -412.18912) (xy 133.273546 -412.18866)
			(xy 134.137146 -412.18866) (xy 134.164393 -412.189213) (xy 134.218331 -412.196975) (xy 134.270616 -412.212332)
			(xy 134.320183 -412.234974) (xy 134.366024 -412.264439) (xy 134.407205 -412.300128) (xy 134.442888 -412.341313)
			(xy 134.472348 -412.387157) (xy 134.494984 -412.436727) (xy 134.510335 -412.489014) (xy 134.51809 -412.542953)
			(xy 134.51809 -412.597447) (xy 134.518089 -412.597453) (xy 135.955746 -412.597453) (xy 135.955746 -412.542947)
			(xy 135.963503 -412.488996) (xy 135.978858 -412.436698) (xy 136.0015 -412.387118) (xy 136.030968 -412.341264)
			(xy 136.066661 -412.300071) (xy 136.107853 -412.264376) (xy 136.153705 -412.234907) (xy 136.203285 -412.212263)
			(xy 136.255582 -412.196906) (xy 136.309533 -412.189147) (xy 136.336786 -412.18866) (xy 137.200386 -412.18866)
			(xy 137.227637 -412.189186) (xy 137.281585 -412.196941) (xy 137.33388 -412.212295) (xy 137.383458 -412.234934)
			(xy 137.429309 -412.264399) (xy 137.4705 -412.30009) (xy 137.506192 -412.34128) (xy 137.535659 -412.38713)
			(xy 137.558301 -412.436707) (xy 137.573656 -412.489001) (xy 137.581413 -412.542949) (xy 137.581413 -412.597451)
			(xy 137.581412 -412.597456) (xy 139.018923 -412.597456) (xy 139.018923 -412.542944) (xy 139.026681 -412.488986)
			(xy 139.04204 -412.436681) (xy 139.064686 -412.387095) (xy 139.094159 -412.341237) (xy 139.129859 -412.30004)
			(xy 139.171058 -412.264344) (xy 139.216918 -412.234874) (xy 139.266506 -412.212231) (xy 139.318811 -412.196876)
			(xy 139.37277 -412.189121) (xy 139.400026 -412.18866) (xy 140.263626 -412.18866) (xy 140.290874 -412.189212)
			(xy 140.344814 -412.196971) (xy 140.397101 -412.212327) (xy 140.446671 -412.234968) (xy 140.492514 -412.264432)
			(xy 140.533698 -412.300121) (xy 140.569384 -412.341307) (xy 140.598845 -412.387152) (xy 140.621482 -412.436723)
			(xy 140.636835 -412.489011) (xy 140.64459 -412.542952) (xy 140.64459 -412.597448) (xy 140.644589 -412.597452)
			(xy 142.082246 -412.597452) (xy 142.082246 -412.542948) (xy 142.090002 -412.488999) (xy 142.105357 -412.436702)
			(xy 142.127997 -412.387123) (xy 142.157463 -412.341271) (xy 142.193154 -412.300078) (xy 142.234343 -412.264383)
			(xy 142.280193 -412.234914) (xy 142.32977 -412.212269) (xy 142.382065 -412.196909) (xy 142.436014 -412.189148)
			(xy 142.463266 -412.18866) (xy 143.326866 -412.18866) (xy 143.354118 -412.189185) (xy 143.408068 -412.196937)
			(xy 143.460366 -412.212289) (xy 143.509946 -412.234928) (xy 143.5558 -412.264392) (xy 143.596993 -412.300083)
			(xy 143.632687 -412.341273) (xy 143.662156 -412.387124) (xy 143.684799 -412.436702) (xy 143.700155 -412.488999)
			(xy 143.707913 -412.542948) (xy 143.707913 -412.597452) (xy 143.707913 -412.597455) (xy 145.145423 -412.597455)
			(xy 145.145423 -412.542945) (xy 145.153181 -412.488989) (xy 145.168538 -412.436686) (xy 145.191183 -412.387101)
			(xy 145.220654 -412.341244) (xy 145.256352 -412.300047) (xy 145.297549 -412.264351) (xy 145.343406 -412.23488)
			(xy 145.392991 -412.212236) (xy 145.445294 -412.196879) (xy 145.499251 -412.189123) (xy 145.526506 -412.18866)
			(xy 146.390106 -412.18866) (xy 146.417355 -412.189211) (xy 146.471297 -412.196967) (xy 146.523587 -412.212321)
			(xy 146.573159 -412.234961) (xy 146.619005 -412.264425) (xy 146.660191 -412.300113) (xy 146.695879 -412.3413)
			(xy 146.725342 -412.387146) (xy 146.747981 -412.436719) (xy 146.763334 -412.489009) (xy 146.77109 -412.542951)
			(xy 146.77109 -412.597449) (xy 146.771089 -412.597457) (xy 148.208623 -412.597457) (xy 148.208623 -412.542943)
			(xy 148.216382 -412.488983) (xy 148.231742 -412.436677) (xy 148.254389 -412.38709) (xy 148.283864 -412.341231)
			(xy 148.319566 -412.300033) (xy 148.360767 -412.264337) (xy 148.40663 -412.234867) (xy 148.45622 -412.212225)
			(xy 148.508528 -412.196872) (xy 148.562489 -412.18912) (xy 148.589746 -412.18866) (xy 149.453346 -412.18866)
			(xy 149.480593 -412.189213) (xy 149.534531 -412.196975) (xy 149.586816 -412.212332) (xy 149.636383 -412.234974)
			(xy 149.682224 -412.264439) (xy 149.723405 -412.300128) (xy 149.759088 -412.341313) (xy 149.788548 -412.387157)
			(xy 149.811184 -412.436727) (xy 149.826535 -412.489014) (xy 149.83429 -412.542953) (xy 149.83429 -412.597447)
			(xy 149.834289 -412.597453) (xy 151.271946 -412.597453) (xy 151.271946 -412.542947) (xy 151.279703 -412.488996)
			(xy 151.295058 -412.436698) (xy 151.3177 -412.387118) (xy 151.347168 -412.341264) (xy 151.382861 -412.300071)
			(xy 151.424053 -412.264376) (xy 151.469905 -412.234907) (xy 151.519485 -412.212263) (xy 151.571782 -412.196906)
			(xy 151.625733 -412.189147) (xy 151.652986 -412.18866) (xy 152.516586 -412.18866) (xy 152.543837 -412.189186)
			(xy 152.597785 -412.196941) (xy 152.65008 -412.212295) (xy 152.699658 -412.234934) (xy 152.745509 -412.264399)
			(xy 152.7867 -412.30009) (xy 152.822392 -412.34128) (xy 152.851859 -412.38713) (xy 152.874501 -412.436707)
			(xy 152.889856 -412.489001) (xy 152.897613 -412.542949) (xy 152.897613 -412.597451) (xy 152.897612 -412.597456)
			(xy 154.335123 -412.597456) (xy 154.335123 -412.542944) (xy 154.342881 -412.488986) (xy 154.35824 -412.436681)
			(xy 154.380886 -412.387095) (xy 154.410359 -412.341237) (xy 154.446059 -412.30004) (xy 154.487258 -412.264344)
			(xy 154.533118 -412.234874) (xy 154.582706 -412.212231) (xy 154.635011 -412.196876) (xy 154.68897 -412.189121)
			(xy 154.716226 -412.18866) (xy 155.579826 -412.18866) (xy 155.607074 -412.189212) (xy 155.661014 -412.196971)
			(xy 155.713301 -412.212327) (xy 155.762871 -412.234968) (xy 155.808714 -412.264432) (xy 155.849898 -412.300121)
			(xy 155.885584 -412.341307) (xy 155.915045 -412.387152) (xy 155.937682 -412.436723) (xy 155.953035 -412.489011)
			(xy 155.96079 -412.542952) (xy 155.96079 -412.597448) (xy 155.960789 -412.597452) (xy 157.398446 -412.597452)
			(xy 157.398446 -412.542948) (xy 157.406202 -412.488999) (xy 157.421557 -412.436702) (xy 157.444197 -412.387123)
			(xy 157.473663 -412.341271) (xy 157.509354 -412.300078) (xy 157.550543 -412.264383) (xy 157.596393 -412.234914)
			(xy 157.64597 -412.212269) (xy 157.698265 -412.196909) (xy 157.752214 -412.189148) (xy 157.779466 -412.18866)
			(xy 158.643066 -412.18866) (xy 158.670318 -412.189185) (xy 158.724268 -412.196937) (xy 158.776566 -412.212289)
			(xy 158.826146 -412.234928) (xy 158.872 -412.264392) (xy 158.913193 -412.300083) (xy 158.948887 -412.341273)
			(xy 158.978356 -412.387124) (xy 159.000999 -412.436702) (xy 159.016355 -412.488999) (xy 159.024113 -412.542948)
			(xy 159.024113 -412.597452) (xy 159.024113 -412.597455) (xy 160.461623 -412.597455) (xy 160.461623 -412.542945)
			(xy 160.469381 -412.488989) (xy 160.484738 -412.436686) (xy 160.507383 -412.387101) (xy 160.536854 -412.341244)
			(xy 160.572552 -412.300047) (xy 160.613749 -412.264351) (xy 160.659606 -412.23488) (xy 160.709191 -412.212236)
			(xy 160.761494 -412.196879) (xy 160.815451 -412.189123) (xy 160.842706 -412.18866) (xy 161.706306 -412.18866)
			(xy 161.733555 -412.189211) (xy 161.787497 -412.196967) (xy 161.839787 -412.212321) (xy 161.889359 -412.234961)
			(xy 161.935205 -412.264425) (xy 161.976391 -412.300113) (xy 162.012079 -412.3413) (xy 162.041542 -412.387146)
			(xy 162.064181 -412.436719) (xy 162.079534 -412.489009) (xy 162.08729 -412.542951) (xy 162.08729 -412.597449)
			(xy 162.079534 -412.651391) (xy 162.064181 -412.703681) (xy 162.041542 -412.753254) (xy 162.012079 -412.7991)
			(xy 161.976391 -412.840287) (xy 161.935205 -412.875975) (xy 161.889359 -412.905439) (xy 161.839787 -412.928079)
			(xy 161.787497 -412.943433) (xy 161.733555 -412.951189) (xy 161.706306 -412.951676) (xy 160.842706 -412.951676)
			(xy 160.815451 -412.951277) (xy 160.761494 -412.943521) (xy 160.709191 -412.928164) (xy 160.659606 -412.90552)
			(xy 160.613749 -412.876049) (xy 160.572552 -412.840353) (xy 160.536854 -412.799156) (xy 160.507383 -412.753299)
			(xy 160.484738 -412.703714) (xy 160.469381 -412.651411) (xy 160.461623 -412.597455) (xy 159.024113 -412.597455)
			(xy 159.016355 -412.651402) (xy 159.000999 -412.703698) (xy 158.978356 -412.753276) (xy 158.948887 -412.799127)
			(xy 158.913193 -412.840317) (xy 158.872 -412.876008) (xy 158.826146 -412.905472) (xy 158.776566 -412.928111)
			(xy 158.724268 -412.943463) (xy 158.670318 -412.951215) (xy 158.643066 -412.951676) (xy 157.779466 -412.951676)
			(xy 157.752214 -412.951252) (xy 157.698265 -412.943491) (xy 157.64597 -412.928131) (xy 157.596393 -412.905486)
			(xy 157.550543 -412.876017) (xy 157.509354 -412.840322) (xy 157.473663 -412.799129) (xy 157.444197 -412.753277)
			(xy 157.421557 -412.703698) (xy 157.406202 -412.651401) (xy 157.398446 -412.597452) (xy 155.960789 -412.597452)
			(xy 155.953035 -412.651389) (xy 155.937682 -412.703677) (xy 155.915045 -412.753248) (xy 155.885584 -412.799093)
			(xy 155.849898 -412.840279) (xy 155.808714 -412.875968) (xy 155.762871 -412.905432) (xy 155.713301 -412.928073)
			(xy 155.661014 -412.943429) (xy 155.607074 -412.951188) (xy 155.579826 -412.951676) (xy 154.716226 -412.951676)
			(xy 154.68897 -412.951279) (xy 154.635011 -412.943524) (xy 154.582706 -412.928169) (xy 154.533118 -412.905526)
			(xy 154.487258 -412.876056) (xy 154.446059 -412.84036) (xy 154.410359 -412.799163) (xy 154.380886 -412.753305)
			(xy 154.35824 -412.703719) (xy 154.342881 -412.651414) (xy 154.335123 -412.597456) (xy 152.897612 -412.597456)
			(xy 152.889856 -412.651399) (xy 152.874501 -412.703693) (xy 152.851859 -412.75327) (xy 152.822392 -412.79912)
			(xy 152.7867 -412.84031) (xy 152.745509 -412.876001) (xy 152.699658 -412.905466) (xy 152.65008 -412.928105)
			(xy 152.597785 -412.943459) (xy 152.543837 -412.951214) (xy 152.516586 -412.951676) (xy 151.652986 -412.951676)
			(xy 151.625733 -412.951253) (xy 151.571782 -412.943494) (xy 151.519485 -412.928137) (xy 151.469905 -412.905493)
			(xy 151.424053 -412.876024) (xy 151.382861 -412.840329) (xy 151.347168 -412.799136) (xy 151.3177 -412.753282)
			(xy 151.295058 -412.703702) (xy 151.279703 -412.651404) (xy 151.271946 -412.597453) (xy 149.834289 -412.597453)
			(xy 149.826535 -412.651386) (xy 149.811184 -412.703673) (xy 149.788548 -412.753243) (xy 149.759088 -412.799087)
			(xy 149.723405 -412.840272) (xy 149.682224 -412.875961) (xy 149.636383 -412.905426) (xy 149.586816 -412.928068)
			(xy 149.534531 -412.943425) (xy 149.480593 -412.951187) (xy 149.453346 -412.951676) (xy 148.589746 -412.951676)
			(xy 148.562489 -412.95128) (xy 148.508528 -412.943528) (xy 148.45622 -412.928175) (xy 148.40663 -412.905533)
			(xy 148.360767 -412.876063) (xy 148.319566 -412.840367) (xy 148.283864 -412.799169) (xy 148.254389 -412.75331)
			(xy 148.231742 -412.703723) (xy 148.216382 -412.651417) (xy 148.208623 -412.597457) (xy 146.771089 -412.597457)
			(xy 146.763334 -412.651391) (xy 146.747981 -412.703681) (xy 146.725342 -412.753254) (xy 146.695879 -412.7991)
			(xy 146.660191 -412.840287) (xy 146.619005 -412.875975) (xy 146.573159 -412.905439) (xy 146.523587 -412.928079)
			(xy 146.471297 -412.943433) (xy 146.417355 -412.951189) (xy 146.390106 -412.951676) (xy 145.526506 -412.951676)
			(xy 145.499251 -412.951277) (xy 145.445294 -412.943521) (xy 145.392991 -412.928164) (xy 145.343406 -412.90552)
			(xy 145.297549 -412.876049) (xy 145.256352 -412.840353) (xy 145.220654 -412.799156) (xy 145.191183 -412.753299)
			(xy 145.168538 -412.703714) (xy 145.153181 -412.651411) (xy 145.145423 -412.597455) (xy 143.707913 -412.597455)
			(xy 143.700155 -412.651402) (xy 143.684799 -412.703698) (xy 143.662156 -412.753276) (xy 143.632687 -412.799127)
			(xy 143.596993 -412.840317) (xy 143.5558 -412.876008) (xy 143.509946 -412.905472) (xy 143.460366 -412.928111)
			(xy 143.408068 -412.943463) (xy 143.354118 -412.951215) (xy 143.326866 -412.951676) (xy 142.463266 -412.951676)
			(xy 142.436014 -412.951252) (xy 142.382065 -412.943491) (xy 142.32977 -412.928131) (xy 142.280193 -412.905486)
			(xy 142.234343 -412.876017) (xy 142.193154 -412.840322) (xy 142.157463 -412.799129) (xy 142.127997 -412.753277)
			(xy 142.105357 -412.703698) (xy 142.090002 -412.651401) (xy 142.082246 -412.597452) (xy 140.644589 -412.597452)
			(xy 140.636835 -412.651389) (xy 140.621482 -412.703677) (xy 140.598845 -412.753248) (xy 140.569384 -412.799093)
			(xy 140.533698 -412.840279) (xy 140.492514 -412.875968) (xy 140.446671 -412.905432) (xy 140.397101 -412.928073)
			(xy 140.344814 -412.943429) (xy 140.290874 -412.951188) (xy 140.263626 -412.951676) (xy 139.400026 -412.951676)
			(xy 139.37277 -412.951279) (xy 139.318811 -412.943524) (xy 139.266506 -412.928169) (xy 139.216918 -412.905526)
			(xy 139.171058 -412.876056) (xy 139.129859 -412.84036) (xy 139.094159 -412.799163) (xy 139.064686 -412.753305)
			(xy 139.04204 -412.703719) (xy 139.026681 -412.651414) (xy 139.018923 -412.597456) (xy 137.581412 -412.597456)
			(xy 137.573656 -412.651399) (xy 137.558301 -412.703693) (xy 137.535659 -412.75327) (xy 137.506192 -412.79912)
			(xy 137.4705 -412.84031) (xy 137.429309 -412.876001) (xy 137.383458 -412.905466) (xy 137.33388 -412.928105)
			(xy 137.281585 -412.943459) (xy 137.227637 -412.951214) (xy 137.200386 -412.951676) (xy 136.336786 -412.951676)
			(xy 136.309533 -412.951253) (xy 136.255582 -412.943494) (xy 136.203285 -412.928137) (xy 136.153705 -412.905493)
			(xy 136.107853 -412.876024) (xy 136.066661 -412.840329) (xy 136.030968 -412.799136) (xy 136.0015 -412.753282)
			(xy 135.978858 -412.703702) (xy 135.963503 -412.651404) (xy 135.955746 -412.597453) (xy 134.518089 -412.597453)
			(xy 134.510335 -412.651386) (xy 134.494984 -412.703673) (xy 134.472348 -412.753243) (xy 134.442888 -412.799087)
			(xy 134.407205 -412.840272) (xy 134.366024 -412.875961) (xy 134.320183 -412.905426) (xy 134.270616 -412.928068)
			(xy 134.218331 -412.943425) (xy 134.164393 -412.951187) (xy 134.137146 -412.951676) (xy 133.273546 -412.951676)
			(xy 133.246289 -412.95128) (xy 133.192328 -412.943528) (xy 133.14002 -412.928175) (xy 133.09043 -412.905533)
			(xy 133.044567 -412.876063) (xy 133.003366 -412.840367) (xy 132.967664 -412.799169) (xy 132.938189 -412.75331)
			(xy 132.915542 -412.703723) (xy 132.900182 -412.651417) (xy 132.892423 -412.597457) (xy 131.454889 -412.597457)
			(xy 131.447134 -412.651391) (xy 131.431781 -412.703681) (xy 131.409142 -412.753254) (xy 131.379679 -412.7991)
			(xy 131.343991 -412.840287) (xy 131.302805 -412.875975) (xy 131.256959 -412.905439) (xy 131.207387 -412.928079)
			(xy 131.155097 -412.943433) (xy 131.101155 -412.951189) (xy 131.073906 -412.951676) (xy 130.210306 -412.951676)
			(xy 130.183051 -412.951277) (xy 130.129094 -412.943521) (xy 130.076791 -412.928164) (xy 130.027206 -412.90552)
			(xy 129.981349 -412.876049) (xy 129.940152 -412.840353) (xy 129.904454 -412.799156) (xy 129.874983 -412.753299)
			(xy 129.852338 -412.703714) (xy 129.836981 -412.651411) (xy 129.829223 -412.597455) (xy 128.391713 -412.597455)
			(xy 128.383955 -412.651402) (xy 128.368599 -412.703698) (xy 128.345956 -412.753276) (xy 128.316487 -412.799127)
			(xy 128.280793 -412.840317) (xy 128.2396 -412.876008) (xy 128.193746 -412.905472) (xy 128.144166 -412.928111)
			(xy 128.091868 -412.943463) (xy 128.037918 -412.951215) (xy 128.010666 -412.951676) (xy 127.147066 -412.951676)
			(xy 127.119814 -412.951252) (xy 127.065865 -412.943491) (xy 127.01357 -412.928131) (xy 126.963993 -412.905486)
			(xy 126.918143 -412.876017) (xy 126.876954 -412.840322) (xy 126.841263 -412.799129) (xy 126.811797 -412.753277)
			(xy 126.789157 -412.703698) (xy 126.773802 -412.651401) (xy 126.766046 -412.597452) (xy 125.328389 -412.597452)
			(xy 125.320635 -412.651389) (xy 125.305282 -412.703677) (xy 125.282645 -412.753248) (xy 125.253184 -412.799093)
			(xy 125.217498 -412.840279) (xy 125.176314 -412.875968) (xy 125.130471 -412.905432) (xy 125.080901 -412.928073)
			(xy 125.028614 -412.943429) (xy 124.974674 -412.951188) (xy 124.947426 -412.951676) (xy 124.083826 -412.951676)
			(xy 124.05657 -412.951279) (xy 124.002611 -412.943524) (xy 123.950306 -412.928169) (xy 123.900718 -412.905526)
			(xy 123.854858 -412.876056) (xy 123.813659 -412.84036) (xy 123.777959 -412.799163) (xy 123.748486 -412.753305)
			(xy 123.72584 -412.703719) (xy 123.710481 -412.651414) (xy 123.702723 -412.597456) (xy 122.265212 -412.597456)
			(xy 122.257456 -412.651399) (xy 122.242101 -412.703693) (xy 122.219459 -412.75327) (xy 122.189992 -412.79912)
			(xy 122.1543 -412.84031) (xy 122.113109 -412.876001) (xy 122.067258 -412.905466) (xy 122.01768 -412.928105)
			(xy 121.965385 -412.943459) (xy 121.911437 -412.951214) (xy 121.884186 -412.951676) (xy 121.020586 -412.951676)
			(xy 120.993333 -412.951253) (xy 120.939382 -412.943494) (xy 120.887085 -412.928137) (xy 120.837505 -412.905493)
			(xy 120.791653 -412.876024) (xy 120.750461 -412.840329) (xy 120.714768 -412.799136) (xy 120.6853 -412.753282)
			(xy 120.662658 -412.703702) (xy 120.647303 -412.651404) (xy 120.639546 -412.597453) (xy 119.201889 -412.597453)
			(xy 119.194135 -412.651386) (xy 119.178784 -412.703673) (xy 119.156148 -412.753243) (xy 119.126688 -412.799087)
			(xy 119.091005 -412.840272) (xy 119.049824 -412.875961) (xy 119.003983 -412.905426) (xy 118.954416 -412.928068)
			(xy 118.902131 -412.943425) (xy 118.848193 -412.951187) (xy 118.820946 -412.951676) (xy 117.957346 -412.951676)
			(xy 117.930089 -412.95128) (xy 117.876128 -412.943528) (xy 117.82382 -412.928175) (xy 117.77423 -412.905533)
			(xy 117.728367 -412.876063) (xy 117.687166 -412.840367) (xy 117.651464 -412.799169) (xy 117.621989 -412.75331)
			(xy 117.599342 -412.703723) (xy 117.583982 -412.651417) (xy 117.576223 -412.597457) (xy 116.138689 -412.597457)
			(xy 116.130934 -412.651391) (xy 116.115581 -412.703681) (xy 116.092942 -412.753254) (xy 116.063479 -412.7991)
			(xy 116.027791 -412.840287) (xy 115.986605 -412.875975) (xy 115.940759 -412.905439) (xy 115.891187 -412.928079)
			(xy 115.838897 -412.943433) (xy 115.784955 -412.951189) (xy 115.757706 -412.951676) (xy 114.894106 -412.951676)
			(xy 114.866851 -412.951277) (xy 114.812894 -412.943521) (xy 114.760591 -412.928164) (xy 114.711006 -412.90552)
			(xy 114.665149 -412.876049) (xy 114.623952 -412.840353) (xy 114.588254 -412.799156) (xy 114.558783 -412.753299)
			(xy 114.536138 -412.703714) (xy 114.520781 -412.651411) (xy 114.513023 -412.597455) (xy 94.987413 -412.597455)
			(xy 94.979655 -412.651402) (xy 94.964299 -412.703698) (xy 94.941656 -412.753276) (xy 94.912187 -412.799127)
			(xy 94.876492 -412.840318) (xy 94.835299 -412.876008) (xy 94.789445 -412.905473) (xy 94.739864 -412.928111)
			(xy 94.687567 -412.943463) (xy 94.633616 -412.951215) (xy 94.606364 -412.951676) (xy 93.742764 -412.951676)
			(xy 93.715512 -412.951252) (xy 93.661564 -412.94349) (xy 93.609269 -412.928131) (xy 93.559692 -412.905486)
			(xy 93.513842 -412.876016) (xy 93.472653 -412.840321) (xy 93.436962 -412.799129) (xy 93.407497 -412.753276)
			(xy 93.384857 -412.703697) (xy 93.369502 -412.651401) (xy 93.361746 -412.597452) (xy 91.924089 -412.597452)
			(xy 91.916335 -412.651389) (xy 91.900982 -412.703677) (xy 91.878345 -412.753249) (xy 91.848883 -412.799094)
			(xy 91.813197 -412.84028) (xy 91.772013 -412.875969) (xy 91.72617 -412.905433) (xy 91.6766 -412.928074)
			(xy 91.624312 -412.94343) (xy 91.570372 -412.951188) (xy 91.543124 -412.951676) (xy 90.679524 -412.951676)
			(xy 90.652268 -412.951279) (xy 90.59831 -412.943524) (xy 90.546004 -412.928169) (xy 90.496417 -412.905526)
			(xy 90.450557 -412.876056) (xy 90.409358 -412.840359) (xy 90.373659 -412.799162) (xy 90.344186 -412.753304)
			(xy 90.32154 -412.703718) (xy 90.306181 -412.651414) (xy 90.298423 -412.597456) (xy 88.860912 -412.597456)
			(xy 88.853156 -412.651399) (xy 88.8378 -412.703694) (xy 88.815159 -412.753271) (xy 88.785692 -412.799121)
			(xy 88.749999 -412.840311) (xy 88.708808 -412.876001) (xy 88.662957 -412.905466) (xy 88.613379 -412.928106)
			(xy 88.561083 -412.943459) (xy 88.507135 -412.951214) (xy 88.479884 -412.951676) (xy 87.616284 -412.951676)
			(xy 87.589031 -412.951253) (xy 87.535081 -412.943494) (xy 87.482783 -412.928136) (xy 87.433204 -412.905492)
			(xy 87.387352 -412.876023) (xy 87.34616 -412.840329) (xy 87.310467 -412.799135) (xy 87.281 -412.753282)
			(xy 87.258358 -412.703702) (xy 87.243003 -412.651404) (xy 87.235246 -412.597453) (xy 85.797589 -412.597453)
			(xy 85.789835 -412.651386) (xy 85.774484 -412.703673) (xy 85.751848 -412.753243) (xy 85.722388 -412.799087)
			(xy 85.686704 -412.840273) (xy 85.645523 -412.875962) (xy 85.599682 -412.905427) (xy 85.550114 -412.928068)
			(xy 85.497829 -412.943426) (xy 85.443891 -412.951187) (xy 85.416644 -412.951676) (xy 84.553044 -412.951676)
			(xy 84.525787 -412.95128) (xy 84.471827 -412.943528) (xy 84.419519 -412.928174) (xy 84.369929 -412.905532)
			(xy 84.324067 -412.876063) (xy 84.282865 -412.840366) (xy 84.247164 -412.799169) (xy 84.217689 -412.75331)
			(xy 84.195041 -412.703722) (xy 84.179682 -412.651417) (xy 84.171923 -412.597457) (xy 82.734389 -412.597457)
			(xy 82.726634 -412.651392) (xy 82.71128 -412.703682) (xy 82.688642 -412.753254) (xy 82.659178 -412.799101)
			(xy 82.62349 -412.840287) (xy 82.582304 -412.875976) (xy 82.536458 -412.90544) (xy 82.486885 -412.928079)
			(xy 82.434595 -412.943433) (xy 82.380653 -412.95119) (xy 82.353404 -412.951676) (xy 81.489804 -412.951676)
			(xy 81.462549 -412.951277) (xy 81.408593 -412.94352) (xy 81.35629 -412.928163) (xy 81.306705 -412.905519)
			(xy 81.260848 -412.876049) (xy 81.219651 -412.840352) (xy 81.183954 -412.799156) (xy 81.154483 -412.753298)
			(xy 81.131838 -412.703714) (xy 81.116481 -412.651411) (xy 81.108723 -412.597455) (xy 79.671213 -412.597455)
			(xy 79.663455 -412.651402) (xy 79.648099 -412.703698) (xy 79.625456 -412.753276) (xy 79.595987 -412.799127)
			(xy 79.560292 -412.840318) (xy 79.519099 -412.876008) (xy 79.473245 -412.905473) (xy 79.423664 -412.928111)
			(xy 79.371367 -412.943463) (xy 79.317416 -412.951215) (xy 79.290164 -412.951676) (xy 78.426564 -412.951676)
			(xy 78.399312 -412.951252) (xy 78.345364 -412.94349) (xy 78.293069 -412.928131) (xy 78.243492 -412.905486)
			(xy 78.197642 -412.876016) (xy 78.156453 -412.840321) (xy 78.120762 -412.799129) (xy 78.091297 -412.753276)
			(xy 78.068657 -412.703697) (xy 78.053302 -412.651401) (xy 78.045546 -412.597452) (xy 76.607889 -412.597452)
			(xy 76.600135 -412.651389) (xy 76.584782 -412.703677) (xy 76.562145 -412.753249) (xy 76.532683 -412.799094)
			(xy 76.496997 -412.84028) (xy 76.455813 -412.875969) (xy 76.40997 -412.905433) (xy 76.3604 -412.928074)
			(xy 76.308112 -412.94343) (xy 76.254172 -412.951188) (xy 76.226924 -412.951676) (xy 75.363324 -412.951676)
			(xy 75.336068 -412.951279) (xy 75.28211 -412.943524) (xy 75.229804 -412.928169) (xy 75.180217 -412.905526)
			(xy 75.134357 -412.876056) (xy 75.093158 -412.840359) (xy 75.057459 -412.799162) (xy 75.027986 -412.753304)
			(xy 75.00534 -412.703718) (xy 74.989981 -412.651414) (xy 74.982223 -412.597456) (xy 73.544712 -412.597456)
			(xy 73.536956 -412.651399) (xy 73.5216 -412.703694) (xy 73.498959 -412.753271) (xy 73.469492 -412.799121)
			(xy 73.433799 -412.840311) (xy 73.392608 -412.876001) (xy 73.346757 -412.905466) (xy 73.297179 -412.928106)
			(xy 73.244883 -412.943459) (xy 73.190935 -412.951214) (xy 73.163684 -412.951676) (xy 72.300084 -412.951676)
			(xy 72.272831 -412.951253) (xy 72.218881 -412.943494) (xy 72.166583 -412.928136) (xy 72.117004 -412.905492)
			(xy 72.071152 -412.876023) (xy 72.02996 -412.840329) (xy 71.994267 -412.799135) (xy 71.9648 -412.753282)
			(xy 71.942158 -412.703702) (xy 71.926803 -412.651404) (xy 71.919046 -412.597453) (xy 70.481389 -412.597453)
			(xy 70.473635 -412.651386) (xy 70.458284 -412.703673) (xy 70.435648 -412.753243) (xy 70.406188 -412.799087)
			(xy 70.370504 -412.840273) (xy 70.329323 -412.875962) (xy 70.283482 -412.905427) (xy 70.233914 -412.928068)
			(xy 70.181629 -412.943426) (xy 70.127691 -412.951187) (xy 70.100444 -412.951676) (xy 69.236844 -412.951676)
			(xy 69.209587 -412.95128) (xy 69.155627 -412.943528) (xy 69.103319 -412.928174) (xy 69.053729 -412.905532)
			(xy 69.007867 -412.876063) (xy 68.966665 -412.840366) (xy 68.930964 -412.799169) (xy 68.901489 -412.75331)
			(xy 68.878841 -412.703722) (xy 68.863482 -412.651417) (xy 68.855723 -412.597457) (xy 67.418189 -412.597457)
			(xy 67.410434 -412.651392) (xy 67.39508 -412.703682) (xy 67.372442 -412.753254) (xy 67.342978 -412.799101)
			(xy 67.30729 -412.840287) (xy 67.266104 -412.875976) (xy 67.220258 -412.90544) (xy 67.170685 -412.928079)
			(xy 67.118395 -412.943433) (xy 67.064453 -412.95119) (xy 67.037204 -412.951676) (xy 66.173604 -412.951676)
			(xy 66.146349 -412.951277) (xy 66.092393 -412.94352) (xy 66.04009 -412.928163) (xy 65.990505 -412.905519)
			(xy 65.944648 -412.876049) (xy 65.903451 -412.840352) (xy 65.867754 -412.799156) (xy 65.838283 -412.753298)
			(xy 65.815638 -412.703714) (xy 65.800281 -412.651411) (xy 65.792523 -412.597455) (xy 64.355013 -412.597455)
			(xy 64.347255 -412.651402) (xy 64.331899 -412.703698) (xy 64.309256 -412.753276) (xy 64.279787 -412.799127)
			(xy 64.244092 -412.840318) (xy 64.202899 -412.876008) (xy 64.157045 -412.905473) (xy 64.107464 -412.928111)
			(xy 64.055167 -412.943463) (xy 64.001216 -412.951215) (xy 63.973964 -412.951676) (xy 63.110364 -412.951676)
			(xy 63.083112 -412.951252) (xy 63.029164 -412.94349) (xy 62.976869 -412.928131) (xy 62.927292 -412.905486)
			(xy 62.881442 -412.876016) (xy 62.840253 -412.840321) (xy 62.804562 -412.799129) (xy 62.775097 -412.753276)
			(xy 62.752457 -412.703697) (xy 62.737102 -412.651401) (xy 62.729346 -412.597452) (xy 61.291689 -412.597452)
			(xy 61.283935 -412.651389) (xy 61.268582 -412.703677) (xy 61.245945 -412.753249) (xy 61.216483 -412.799094)
			(xy 61.180797 -412.84028) (xy 61.139613 -412.875969) (xy 61.09377 -412.905433) (xy 61.0442 -412.928074)
			(xy 60.991912 -412.94343) (xy 60.937972 -412.951188) (xy 60.910724 -412.951676) (xy 60.047124 -412.951676)
			(xy 60.019868 -412.951279) (xy 59.96591 -412.943524) (xy 59.913604 -412.928169) (xy 59.864017 -412.905526)
			(xy 59.818157 -412.876056) (xy 59.776958 -412.840359) (xy 59.741259 -412.799162) (xy 59.711786 -412.753304)
			(xy 59.68914 -412.703718) (xy 59.673781 -412.651414) (xy 59.666023 -412.597456) (xy 58.228512 -412.597456)
			(xy 58.220756 -412.651399) (xy 58.2054 -412.703694) (xy 58.182759 -412.753271) (xy 58.153292 -412.799121)
			(xy 58.117599 -412.840311) (xy 58.076408 -412.876001) (xy 58.030557 -412.905466) (xy 57.980979 -412.928106)
			(xy 57.928683 -412.943459) (xy 57.874735 -412.951214) (xy 57.847484 -412.951676) (xy 56.983884 -412.951676)
			(xy 56.956631 -412.951253) (xy 56.902681 -412.943494) (xy 56.850383 -412.928136) (xy 56.800804 -412.905492)
			(xy 56.754952 -412.876023) (xy 56.71376 -412.840329) (xy 56.678067 -412.799135) (xy 56.6486 -412.753282)
			(xy 56.625958 -412.703702) (xy 56.610603 -412.651404) (xy 56.602846 -412.597453) (xy 55.165189 -412.597453)
			(xy 55.157435 -412.651386) (xy 55.142084 -412.703673) (xy 55.119448 -412.753243) (xy 55.089988 -412.799087)
			(xy 55.054304 -412.840273) (xy 55.013123 -412.875962) (xy 54.967282 -412.905427) (xy 54.917714 -412.928068)
			(xy 54.865429 -412.943426) (xy 54.811491 -412.951187) (xy 54.784244 -412.951676) (xy 53.920644 -412.951676)
			(xy 53.893387 -412.95128) (xy 53.839427 -412.943528) (xy 53.787119 -412.928174) (xy 53.737529 -412.905532)
			(xy 53.691667 -412.876063) (xy 53.650465 -412.840366) (xy 53.614764 -412.799169) (xy 53.585289 -412.75331)
			(xy 53.562641 -412.703722) (xy 53.547282 -412.651417) (xy 53.539523 -412.597457) (xy 52.101989 -412.597457)
			(xy 52.094234 -412.651392) (xy 52.07888 -412.703682) (xy 52.056242 -412.753254) (xy 52.026778 -412.799101)
			(xy 51.99109 -412.840287) (xy 51.949904 -412.875976) (xy 51.904058 -412.90544) (xy 51.854485 -412.928079)
			(xy 51.802195 -412.943433) (xy 51.748253 -412.95119) (xy 51.721004 -412.951676) (xy 50.857404 -412.951676)
			(xy 50.830149 -412.951277) (xy 50.776193 -412.94352) (xy 50.72389 -412.928163) (xy 50.674305 -412.905519)
			(xy 50.628448 -412.876049) (xy 50.587251 -412.840352) (xy 50.551554 -412.799156) (xy 50.522083 -412.753298)
			(xy 50.499438 -412.703714) (xy 50.484081 -412.651411) (xy 50.476323 -412.597455) (xy 49.038813 -412.597455)
			(xy 49.031055 -412.651402) (xy 49.015699 -412.703698) (xy 48.993056 -412.753276) (xy 48.963587 -412.799127)
			(xy 48.927892 -412.840318) (xy 48.886699 -412.876008) (xy 48.840845 -412.905473) (xy 48.791264 -412.928111)
			(xy 48.738967 -412.943463) (xy 48.685016 -412.951215) (xy 48.657764 -412.951676) (xy 47.794164 -412.951676)
			(xy 47.766912 -412.951252) (xy 47.712964 -412.94349) (xy 47.660669 -412.928131) (xy 47.611092 -412.905486)
			(xy 47.565242 -412.876016) (xy 47.524053 -412.840321) (xy 47.488362 -412.799129) (xy 47.458897 -412.753276)
			(xy 47.436257 -412.703697) (xy 47.420902 -412.651401) (xy 47.413146 -412.597452) (xy 39.737792 -412.597452)
			(xy 39.737792 -413.4485) (xy 39.737556 -413.461769) (xy 105.629431 -413.461769) (xy 105.629431 -413.407231)
			(xy 105.637193 -413.353247) (xy 105.652559 -413.300918) (xy 105.675215 -413.251308) (xy 105.704702 -413.205427)
			(xy 105.740417 -413.16421) (xy 105.781635 -413.128496) (xy 105.827517 -413.099011) (xy 105.877127 -413.076355)
			(xy 105.929457 -413.060991) (xy 105.983441 -413.053231) (xy 106.01071 -413.052768) (xy 106.87431 -413.052768)
			(xy 106.901581 -413.053195) (xy 106.955568 -413.060959) (xy 107.0079 -413.076326) (xy 107.057513 -413.098985)
			(xy 107.103396 -413.128473) (xy 107.144616 -413.164191) (xy 107.180333 -413.205412) (xy 107.20982 -413.251296)
			(xy 107.232477 -413.300909) (xy 107.247844 -413.353242) (xy 107.255606 -413.407229) (xy 107.255606 -413.461771)
			(xy 107.247844 -413.515758) (xy 107.232477 -413.568091) (xy 107.20982 -413.617704) (xy 107.180333 -413.663588)
			(xy 107.144616 -413.704809) (xy 107.103396 -413.740527) (xy 107.057513 -413.770015) (xy 107.0079 -413.792674)
			(xy 106.955568 -413.808041) (xy 106.901581 -413.815805) (xy 106.87431 -413.816292) (xy 106.01071 -413.816292)
			(xy 105.983441 -413.815769) (xy 105.929457 -413.808009) (xy 105.877127 -413.792645) (xy 105.827517 -413.769989)
			(xy 105.781635 -413.740504) (xy 105.740417 -413.70479) (xy 105.704702 -413.663573) (xy 105.675215 -413.617692)
			(xy 105.652559 -413.568082) (xy 105.637193 -413.515753) (xy 105.629431 -413.461769) (xy 39.737556 -413.461769)
			(xy 39.737306 -413.475769) (xy 39.729544 -413.529753) (xy 39.714179 -413.582083) (xy 39.691522 -413.631693)
			(xy 39.662036 -413.677574) (xy 39.626321 -413.718791) (xy 39.585104 -413.754506) (xy 39.539223 -413.783992)
			(xy 39.489613 -413.806649) (xy 39.437283 -413.822014) (xy 39.383299 -413.829776) (xy 39.328761 -413.829776)
			(xy 39.274777 -413.822014) (xy 39.222447 -413.806649) (xy 39.172837 -413.783992) (xy 39.126956 -413.754506)
			(xy 39.085739 -413.718791) (xy 39.050024 -413.677574) (xy 39.020538 -413.631693) (xy 38.997881 -413.582083)
			(xy 38.982516 -413.529753) (xy 38.974754 -413.475769) (xy 38.974268 -413.4485) (xy 7.00913 -413.4485)
			(xy 7.00913 -415.383726) (xy 41.206928 -415.383726) (xy 41.206928 -414.520126) (xy 41.207414 -414.492857)
			(xy 41.215176 -414.438873) (xy 41.230541 -414.386543) (xy 41.253198 -414.336933) (xy 41.282684 -414.291052)
			(xy 41.318399 -414.249835) (xy 41.359616 -414.21412) (xy 41.405497 -414.184634) (xy 41.455107 -414.161977)
			(xy 41.507437 -414.146612) (xy 41.561421 -414.13885) (xy 41.615959 -414.13885) (xy 41.669943 -414.146612)
			(xy 41.722273 -414.161977) (xy 41.771883 -414.184634) (xy 41.817764 -414.21412) (xy 41.858981 -414.249835)
			(xy 41.894696 -414.291052) (xy 41.924182 -414.336933) (xy 41.946839 -414.386543) (xy 41.962204 -414.438873)
			(xy 41.969966 -414.492857) (xy 41.970452 -414.520126) (xy 41.970452 -415.383726) (xy 41.969966 -415.410995)
			(xy 41.962204 -415.464979) (xy 41.946839 -415.517309) (xy 41.924182 -415.566919) (xy 41.894696 -415.6128)
			(xy 41.858981 -415.654017) (xy 41.817764 -415.689732) (xy 41.771883 -415.719218) (xy 41.722273 -415.741875)
			(xy 41.669943 -415.75724) (xy 41.615959 -415.765002) (xy 41.561421 -415.765002) (xy 41.507437 -415.75724)
			(xy 41.455107 -415.741875) (xy 41.405497 -415.719218) (xy 41.359616 -415.689732) (xy 41.318399 -415.654017)
			(xy 41.282684 -415.6128) (xy 41.253198 -415.566919) (xy 41.230541 -415.517309) (xy 41.215176 -415.464979)
			(xy 41.207414 -415.410995) (xy 41.206928 -415.383726) (xy 7.00913 -415.383726) (xy 7.00913 -417.465002)
			(xy 35.832796 -417.465002) (xy 35.832796 -416.601402) (xy 35.833282 -416.574151) (xy 35.841038 -416.520203)
			(xy 35.856393 -416.467908) (xy 35.879035 -416.418331) (xy 35.908501 -416.372481) (xy 35.944192 -416.33129)
			(xy 35.985383 -416.295599) (xy 36.031233 -416.266133) (xy 36.08081 -416.243491) (xy 36.133105 -416.228136)
			(xy 36.187053 -416.22038) (xy 36.241555 -416.22038) (xy 36.295503 -416.228136) (xy 36.347798 -416.243491)
			(xy 36.397375 -416.266133) (xy 36.443225 -416.295599) (xy 36.484416 -416.33129) (xy 36.520107 -416.372481)
			(xy 36.549573 -416.418331) (xy 36.572215 -416.467908) (xy 36.58757 -416.520203) (xy 36.595326 -416.574151)
			(xy 36.595812 -416.601402) (xy 36.595812 -417.436808) (xy 48.812704 -417.436808) (xy 48.812704 -416.573208)
			(xy 48.81319 -416.545939) (xy 48.820952 -416.491955) (xy 48.836317 -416.439625) (xy 48.858974 -416.390015)
			(xy 48.88846 -416.344134) (xy 48.924175 -416.302917) (xy 48.965392 -416.267202) (xy 49.011273 -416.237716)
			(xy 49.060883 -416.215059) (xy 49.113213 -416.199694) (xy 49.167197 -416.191932) (xy 49.221735 -416.191932)
			(xy 49.275719 -416.199694) (xy 49.328049 -416.215059) (xy 49.377659 -416.237716) (xy 49.42354 -416.267202)
			(xy 49.464757 -416.302917) (xy 49.500472 -416.344134) (xy 49.529958 -416.390015) (xy 49.552615 -416.439625)
			(xy 49.56798 -416.491955) (xy 49.575742 -416.545939) (xy 49.576228 -416.573208) (xy 49.576228 -417.436808)
			(xy 49.575742 -417.464077) (xy 49.56798 -417.518061) (xy 49.552615 -417.570391) (xy 49.529958 -417.620001)
			(xy 49.500472 -417.665882) (xy 49.464757 -417.707099) (xy 49.42354 -417.742814) (xy 49.377659 -417.7723)
			(xy 49.328049 -417.794957) (xy 49.275719 -417.810322) (xy 49.221735 -417.818084) (xy 49.167197 -417.818084)
			(xy 49.113213 -417.810322) (xy 49.060883 -417.794957) (xy 49.011273 -417.7723) (xy 48.965392 -417.742814)
			(xy 48.924175 -417.707099) (xy 48.88846 -417.665882) (xy 48.858974 -417.620001) (xy 48.836317 -417.570391)
			(xy 48.820952 -417.518061) (xy 48.81319 -417.464077) (xy 48.812704 -417.436808) (xy 36.595812 -417.436808)
			(xy 36.595812 -417.465002) (xy 36.595326 -417.492253) (xy 36.58757 -417.546201) (xy 36.572215 -417.598496)
			(xy 36.549573 -417.648073) (xy 36.520107 -417.693923) (xy 36.484416 -417.735114) (xy 36.443225 -417.770805)
			(xy 36.397375 -417.800271) (xy 36.347798 -417.822913) (xy 36.295503 -417.838268) (xy 36.241555 -417.846024)
			(xy 36.187053 -417.846024) (xy 36.133105 -417.838268) (xy 36.08081 -417.822913) (xy 36.031233 -417.800271)
			(xy 35.985383 -417.770805) (xy 35.944192 -417.735114) (xy 35.908501 -417.693923) (xy 35.879035 -417.648073)
			(xy 35.856393 -417.598496) (xy 35.841038 -417.546201) (xy 35.833282 -417.492253) (xy 35.832796 -417.465002)
			(xy 7.00913 -417.465002) (xy 7.00913 -419.64102) (xy 51.809904 -419.64102) (xy 51.809904 -418.77742)
			(xy 51.81039 -418.750151) (xy 51.818152 -418.696167) (xy 51.833517 -418.643837) (xy 51.856174 -418.594227)
			(xy 51.88566 -418.548346) (xy 51.921375 -418.507129) (xy 51.962592 -418.471414) (xy 52.008473 -418.441928)
			(xy 52.058083 -418.419271) (xy 52.110413 -418.403906) (xy 52.164397 -418.396144) (xy 52.218935 -418.396144)
			(xy 52.272919 -418.403906) (xy 52.325249 -418.419271) (xy 52.374859 -418.441928) (xy 52.42074 -418.471414)
			(xy 52.461957 -418.507129) (xy 52.497672 -418.548346) (xy 52.527158 -418.594227) (xy 52.549815 -418.643837)
			(xy 52.56518 -418.696167) (xy 52.572942 -418.750151) (xy 52.573428 -418.77742) (xy 52.573428 -419.64102)
			(xy 52.572942 -419.668289) (xy 52.56518 -419.722273) (xy 52.549815 -419.774603) (xy 52.527158 -419.824213)
			(xy 52.497672 -419.870094) (xy 52.461957 -419.911311) (xy 52.42074 -419.947026) (xy 52.374859 -419.976512)
			(xy 52.325249 -419.999169) (xy 52.272919 -420.014534) (xy 52.218935 -420.022296) (xy 52.164397 -420.022296)
			(xy 52.110413 -420.014534) (xy 52.058083 -419.999169) (xy 52.008473 -419.976512) (xy 51.962592 -419.947026)
			(xy 51.921375 -419.911311) (xy 51.88566 -419.870094) (xy 51.856174 -419.824213) (xy 51.833517 -419.774603)
			(xy 51.818152 -419.722273) (xy 51.81039 -419.668289) (xy 51.809904 -419.64102) (xy 7.00913 -419.64102)
			(xy 7.00913 -421.200326) (xy 10.01268 -421.200326) (xy 10.01268 -420.336726) (xy 10.013166 -420.309475)
			(xy 10.020922 -420.255527) (xy 10.036277 -420.203232) (xy 10.058919 -420.153655) (xy 10.088385 -420.107805)
			(xy 10.124076 -420.066614) (xy 10.165267 -420.030923) (xy 10.211117 -420.001457) (xy 10.260694 -419.978815)
			(xy 10.312989 -419.96346) (xy 10.366937 -419.955704) (xy 10.421439 -419.955704) (xy 10.475387 -419.96346)
			(xy 10.527682 -419.978815) (xy 10.577259 -420.001457) (xy 10.623109 -420.030923) (xy 10.6643 -420.066614)
			(xy 10.699991 -420.107805) (xy 10.729457 -420.153655) (xy 10.752099 -420.203232) (xy 10.767454 -420.255527)
			(xy 10.77521 -420.309475) (xy 10.775696 -420.336726) (xy 10.775696 -421.200326) (xy 10.77521 -421.227577)
			(xy 10.769122 -421.269922) (xy 21.420836 -421.269922) (xy 21.420836 -420.406322) (xy 21.421322 -420.379071)
			(xy 21.429078 -420.325123) (xy 21.444433 -420.272828) (xy 21.467075 -420.223251) (xy 21.496541 -420.177401)
			(xy 21.532232 -420.13621) (xy 21.573423 -420.100519) (xy 21.619273 -420.071053) (xy 21.66885 -420.048411)
			(xy 21.721145 -420.033056) (xy 21.775093 -420.0253) (xy 21.829595 -420.0253) (xy 21.883543 -420.033056)
			(xy 21.935838 -420.048411) (xy 21.985415 -420.071053) (xy 22.031265 -420.100519) (xy 22.072456 -420.13621)
			(xy 22.108147 -420.177401) (xy 22.137613 -420.223251) (xy 22.160255 -420.272828) (xy 22.17561 -420.325123)
			(xy 22.183366 -420.379071) (xy 22.183852 -420.406322) (xy 22.183852 -420.760398) (xy 58.141108 -420.760398)
			(xy 58.141108 -418.218874) (xy 58.141589 -418.206761) (xy 58.14908 -418.183722) (xy 58.16332 -418.164123)
			(xy 58.182918 -418.149882) (xy 58.205957 -418.14239) (xy 58.21807 -418.141912) (xy 59.15787 -418.141912)
			(xy 59.169989 -418.142385) (xy 59.193042 -418.149866) (xy 59.212655 -418.164105) (xy 59.226908 -418.183708)
			(xy 59.234406 -418.206756) (xy 59.234832 -418.218874) (xy 59.234832 -420.760398) (xy 59.234438 -420.772524)
			(xy 59.226942 -420.795587) (xy 59.212685 -420.815205) (xy 59.193062 -420.829455) (xy 59.169996 -420.836942)
			(xy 59.15787 -420.83736) (xy 58.21807 -420.83736) (xy 58.205954 -420.836914) (xy 58.182909 -420.829418)
			(xy 58.163308 -420.81517) (xy 58.149067 -420.795562) (xy 58.141581 -420.772515) (xy 58.141108 -420.760398)
			(xy 22.183852 -420.760398) (xy 22.183852 -421.269922) (xy 22.183366 -421.297173) (xy 22.17561 -421.351121)
			(xy 22.160255 -421.403416) (xy 22.137613 -421.452993) (xy 22.108147 -421.498843) (xy 22.072456 -421.540034)
			(xy 22.031265 -421.575725) (xy 21.985415 -421.605191) (xy 21.935838 -421.627833) (xy 21.883543 -421.643188)
			(xy 21.829595 -421.650944) (xy 21.775093 -421.650944) (xy 21.721145 -421.643188) (xy 21.66885 -421.627833)
			(xy 21.619273 -421.605191) (xy 21.573423 -421.575725) (xy 21.532232 -421.540034) (xy 21.496541 -421.498843)
			(xy 21.467075 -421.452993) (xy 21.444433 -421.403416) (xy 21.429078 -421.351121) (xy 21.421322 -421.297173)
			(xy 21.420836 -421.269922) (xy 10.769122 -421.269922) (xy 10.767454 -421.281525) (xy 10.752099 -421.33382)
			(xy 10.729457 -421.383397) (xy 10.699991 -421.429247) (xy 10.6643 -421.470438) (xy 10.623109 -421.506129)
			(xy 10.577259 -421.535595) (xy 10.527682 -421.558237) (xy 10.475387 -421.573592) (xy 10.421439 -421.581348)
			(xy 10.366937 -421.581348) (xy 10.312989 -421.573592) (xy 10.260694 -421.558237) (xy 10.211117 -421.535595)
			(xy 10.165267 -421.506129) (xy 10.124076 -421.470438) (xy 10.088385 -421.429247) (xy 10.058919 -421.383397)
			(xy 10.036277 -421.33382) (xy 10.020922 -421.281525) (xy 10.013166 -421.227577) (xy 10.01268 -421.200326)
			(xy 7.00913 -421.200326) (xy 7.00913 -422.130474) (xy 24.87676 -422.130474) (xy 24.87676 -421.266874)
			(xy 24.877246 -421.239605) (xy 24.885008 -421.185621) (xy 24.900373 -421.133291) (xy 24.92303 -421.083681)
			(xy 24.952516 -421.0378) (xy 24.988231 -420.996583) (xy 25.029448 -420.960868) (xy 25.075329 -420.931382)
			(xy 25.124939 -420.908725) (xy 25.177269 -420.89336) (xy 25.231253 -420.885598) (xy 25.285791 -420.885598)
			(xy 25.339775 -420.89336) (xy 25.392105 -420.908725) (xy 25.441715 -420.931382) (xy 25.487596 -420.960868)
			(xy 25.528813 -420.996583) (xy 25.564528 -421.0378) (xy 25.594014 -421.083681) (xy 25.616671 -421.133291)
			(xy 25.632036 -421.185621) (xy 25.639798 -421.239605) (xy 25.640284 -421.266874) (xy 25.640284 -421.726974)
			(xy 27.323192 -421.726974) (xy 27.323192 -421.672426) (xy 27.330955 -421.618434) (xy 27.346324 -421.566097)
			(xy 27.368985 -421.51648) (xy 27.398477 -421.470593) (xy 27.4342 -421.429371) (xy 27.475427 -421.393652)
			(xy 27.521317 -421.364165) (xy 27.570936 -421.341509) (xy 27.623276 -421.326146) (xy 27.677268 -421.318389)
			(xy 27.704542 -421.317928) (xy 28.568142 -421.317928) (xy 28.595409 -421.318437) (xy 28.649386 -421.326204)
			(xy 28.701709 -421.341572) (xy 28.751313 -421.36423) (xy 28.797187 -421.393716) (xy 28.838399 -421.429431)
			(xy 28.874109 -421.470646) (xy 28.90359 -421.516524) (xy 28.926243 -421.56613) (xy 28.941605 -421.618455)
			(xy 28.949366 -421.672433) (xy 28.949366 -421.726967) (xy 28.941605 -421.780945) (xy 28.926243 -421.83327)
			(xy 28.90359 -421.882876) (xy 28.874109 -421.928754) (xy 28.838399 -421.969969) (xy 28.797187 -422.005684)
			(xy 28.751313 -422.03517) (xy 28.701709 -422.057828) (xy 28.649386 -422.073196) (xy 28.595409 -422.080963)
			(xy 28.568142 -422.081452) (xy 27.704542 -422.081452) (xy 27.677268 -422.081011) (xy 27.623276 -422.073254)
			(xy 27.570936 -422.057891) (xy 27.521317 -422.035235) (xy 27.475427 -422.005748) (xy 27.4342 -421.970029)
			(xy 27.398477 -421.928807) (xy 27.368985 -421.88292) (xy 27.346324 -421.833303) (xy 27.330955 -421.780966)
			(xy 27.323192 -421.726974) (xy 25.640284 -421.726974) (xy 25.640284 -422.130474) (xy 25.639798 -422.157743)
			(xy 25.632036 -422.211727) (xy 25.616671 -422.264057) (xy 25.594014 -422.313667) (xy 25.564528 -422.359548)
			(xy 25.528813 -422.400765) (xy 25.487596 -422.43648) (xy 25.441715 -422.465966) (xy 25.392105 -422.488623)
			(xy 25.339775 -422.503988) (xy 25.285791 -422.51175) (xy 25.231253 -422.51175) (xy 25.177269 -422.503988)
			(xy 25.124939 -422.488623) (xy 25.075329 -422.465966) (xy 25.029448 -422.43648) (xy 24.988231 -422.400765)
			(xy 24.952516 -422.359548) (xy 24.92303 -422.313667) (xy 24.900373 -422.264057) (xy 24.885008 -422.211727)
			(xy 24.877246 -422.157743) (xy 24.87676 -422.130474) (xy 7.00913 -422.130474) (xy 7.00913 -422.66627)
			(xy 38.762906 -422.66627) (xy 38.762906 -422.61173) (xy 38.770668 -422.557744) (xy 38.786034 -422.505412)
			(xy 38.808691 -422.4558) (xy 38.838178 -422.409918) (xy 38.873894 -422.368698) (xy 38.915113 -422.332981)
			(xy 38.960995 -422.303494) (xy 39.010607 -422.280836) (xy 39.062938 -422.26547) (xy 39.116924 -422.257707)
			(xy 39.144194 -422.25722) (xy 40.007794 -422.25722) (xy 40.035064 -422.257719) (xy 40.089049 -422.26548)
			(xy 40.14138 -422.280845) (xy 40.190991 -422.303501) (xy 40.236874 -422.332987) (xy 40.278093 -422.368703)
			(xy 40.313809 -422.409921) (xy 40.343296 -422.455803) (xy 40.365953 -422.505414) (xy 40.381319 -422.557745)
			(xy 40.389081 -422.61173) (xy 40.389081 -422.66627) (xy 40.381319 -422.720255) (xy 40.365953 -422.772586)
			(xy 40.343296 -422.822197) (xy 40.313809 -422.868079) (xy 40.278093 -422.909297) (xy 40.236874 -422.945013)
			(xy 40.190991 -422.974499) (xy 40.14138 -422.997155) (xy 40.089049 -423.01252) (xy 40.035064 -423.020281)
			(xy 40.007794 -423.020744) (xy 39.144194 -423.020744) (xy 39.116924 -423.020293) (xy 39.062938 -423.01253)
			(xy 39.010607 -422.997164) (xy 38.960995 -422.974506) (xy 38.915113 -422.945019) (xy 38.873894 -422.909302)
			(xy 38.838178 -422.868082) (xy 38.808691 -422.8222) (xy 38.786034 -422.772588) (xy 38.770668 -422.720256)
			(xy 38.762906 -422.66627) (xy 7.00913 -422.66627) (xy 7.00913 -423.057828) (xy 41.652952 -423.057828)
			(xy 41.652952 -422.194228) (xy 41.653438 -422.166959) (xy 41.6612 -422.112975) (xy 41.676565 -422.060645)
			(xy 41.699222 -422.011035) (xy 41.728708 -421.965154) (xy 41.764423 -421.923937) (xy 41.80564 -421.888222)
			(xy 41.851521 -421.858736) (xy 41.901131 -421.836079) (xy 41.953461 -421.820714) (xy 42.007445 -421.812952)
			(xy 42.061983 -421.812952) (xy 42.115967 -421.820714) (xy 42.168297 -421.836079) (xy 42.217907 -421.858736)
			(xy 42.263788 -421.888222) (xy 42.305005 -421.923937) (xy 42.34072 -421.965154) (xy 42.370206 -422.011035)
			(xy 42.392863 -422.060645) (xy 42.408228 -422.112975) (xy 42.41599 -422.166959) (xy 42.416476 -422.194228)
			(xy 42.416476 -423.057828) (xy 42.41599 -423.085097) (xy 42.408228 -423.139081) (xy 42.392863 -423.191411)
			(xy 42.370206 -423.241021) (xy 42.34072 -423.286902) (xy 42.305005 -423.328119) (xy 42.263788 -423.363834)
			(xy 42.217907 -423.39332) (xy 42.168297 -423.415977) (xy 42.115967 -423.431342) (xy 42.061983 -423.439104)
			(xy 42.007445 -423.439104) (xy 41.953461 -423.431342) (xy 41.901131 -423.415977) (xy 41.851521 -423.39332)
			(xy 41.80564 -423.363834) (xy 41.764423 -423.328119) (xy 41.728708 -423.286902) (xy 41.699222 -423.241021)
			(xy 41.676565 -423.191411) (xy 41.6612 -423.139081) (xy 41.653438 -423.085097) (xy 41.652952 -423.057828)
			(xy 7.00913 -423.057828) (xy 7.00913 -425.887642) (xy 10.204704 -425.887642) (xy 10.204704 -425.024042)
			(xy 10.20519 -424.996773) (xy 10.212952 -424.942789) (xy 10.228317 -424.890459) (xy 10.250974 -424.840849)
			(xy 10.28046 -424.794968) (xy 10.316175 -424.753751) (xy 10.357392 -424.718036) (xy 10.403273 -424.68855)
			(xy 10.452883 -424.665893) (xy 10.505213 -424.650528) (xy 10.559197 -424.642766) (xy 10.613735 -424.642766)
			(xy 10.667719 -424.650528) (xy 10.720049 -424.665893) (xy 10.769659 -424.68855) (xy 10.81554 -424.718036)
			(xy 10.856757 -424.753751) (xy 10.892472 -424.794968) (xy 10.921958 -424.840849) (xy 10.944615 -424.890459)
			(xy 10.95998 -424.942789) (xy 10.967742 -424.996773) (xy 10.968228 -425.024042) (xy 10.968228 -425.328334)
			(xy 21.942552 -425.328334) (xy 21.942552 -424.464734) (xy 21.943038 -424.437465) (xy 21.9508 -424.383481)
			(xy 21.966165 -424.331151) (xy 21.988822 -424.281541) (xy 22.018308 -424.23566) (xy 22.054023 -424.194443)
			(xy 22.09524 -424.158728) (xy 22.141121 -424.129242) (xy 22.190731 -424.106585) (xy 22.243061 -424.09122)
			(xy 22.297045 -424.083458) (xy 22.351583 -424.083458) (xy 22.405567 -424.09122) (xy 22.457897 -424.106585)
			(xy 22.507507 -424.129242) (xy 22.553388 -424.158728) (xy 22.594605 -424.194443) (xy 22.63032 -424.23566)
			(xy 22.659806 -424.281541) (xy 22.682463 -424.331151) (xy 22.691108 -424.360594) (xy 58.141108 -424.360594)
			(xy 58.141108 -421.81907) (xy 58.141586 -421.806957) (xy 58.149077 -421.783918) (xy 58.163319 -421.764319)
			(xy 58.182918 -421.750077) (xy 58.205957 -421.742586) (xy 58.21807 -421.742108) (xy 59.15787 -421.742108)
			(xy 59.16998 -421.742637) (xy 59.193017 -421.750112) (xy 59.207184 -421.760396) (xy 60.141104 -421.760396)
			(xy 60.141104 -419.218872) (xy 60.141536 -419.20682) (xy 60.148977 -419.183893) (xy 60.163125 -419.164377)
			(xy 60.182601 -419.150175) (xy 60.205507 -419.14267) (xy 60.217558 -419.142164) (xy 61.157866 -419.142164)
			(xy 61.169956 -419.142637) (xy 61.19296 -419.150087) (xy 61.212542 -419.164271) (xy 61.226793 -419.183805)
			(xy 61.234322 -419.206783) (xy 61.234828 -419.218872) (xy 61.234828 -421.760396) (xy 61.234337 -421.772443)
			(xy 61.226909 -421.795364) (xy 61.212775 -421.814877) (xy 61.193313 -421.829082) (xy 61.170419 -421.836593)
			(xy 61.158374 -421.837104) (xy 60.218066 -421.837104) (xy 60.205979 -421.836623) (xy 60.182985 -421.829162)
			(xy 60.163409 -421.814977) (xy 60.149158 -421.79545) (xy 60.141619 -421.772481) (xy 60.141104 -421.760396)
			(xy 59.207184 -421.760396) (xy 59.212617 -421.76434) (xy 59.22686 -421.783929) (xy 59.234354 -421.80696)
			(xy 59.234832 -421.81907) (xy 59.234832 -424.360594) (xy 62.1411 -424.360594) (xy 62.1411 -421.81907)
			(xy 62.141585 -421.806958) (xy 62.149076 -421.78392) (xy 62.163316 -421.764322) (xy 62.182913 -421.75008)
			(xy 62.20595 -421.742587) (xy 62.218062 -421.742108) (xy 63.157862 -421.742108) (xy 63.16998 -421.742592)
			(xy 63.193032 -421.75007) (xy 63.207258 -421.760396) (xy 68.141088 -421.760396) (xy 68.141088 -419.218872)
			(xy 68.141536 -419.206822) (xy 68.148975 -419.183897) (xy 68.163119 -419.164383) (xy 68.182591 -419.15018)
			(xy 68.205493 -419.142672) (xy 68.217542 -419.142164) (xy 69.15785 -419.142164) (xy 69.169939 -419.14265)
			(xy 69.192942 -419.150096) (xy 69.212525 -419.164277) (xy 69.226777 -419.183808) (xy 69.234306 -419.206784)
			(xy 69.234812 -419.218872) (xy 69.234812 -420.760398) (xy 70.141084 -420.760398) (xy 70.141084 -418.218874)
			(xy 70.141438 -418.206745) (xy 70.148943 -418.183678) (xy 70.16321 -418.164059) (xy 70.182842 -418.14981)
			(xy 70.205917 -418.142327) (xy 70.218046 -418.141912) (xy 71.157846 -418.141912) (xy 71.16996 -418.142372)
			(xy 71.193001 -418.149869) (xy 71.212599 -418.164115) (xy 71.22684 -418.183717) (xy 71.234331 -418.20676)
			(xy 71.234808 -418.218874) (xy 71.234808 -418.3761) (xy 77.661008 -418.3761) (xy 77.661008 -417.5125)
			(xy 77.661494 -417.485231) (xy 77.669256 -417.431247) (xy 77.684621 -417.378917) (xy 77.707278 -417.329307)
			(xy 77.736764 -417.283426) (xy 77.772479 -417.242209) (xy 77.813696 -417.206494) (xy 77.859577 -417.177008)
			(xy 77.909187 -417.154351) (xy 77.961517 -417.138986) (xy 78.015501 -417.131224) (xy 78.070039 -417.131224)
			(xy 78.124023 -417.138986) (xy 78.176353 -417.154351) (xy 78.225963 -417.177008) (xy 78.271844 -417.206494)
			(xy 78.313061 -417.242209) (xy 78.348776 -417.283426) (xy 78.378262 -417.329307) (xy 78.400919 -417.378917)
			(xy 78.416284 -417.431247) (xy 78.424046 -417.485231) (xy 78.424532 -417.5125) (xy 78.424532 -418.3761)
			(xy 78.424046 -418.403369) (xy 78.416284 -418.457353) (xy 78.400919 -418.509683) (xy 78.378262 -418.559293)
			(xy 78.348776 -418.605174) (xy 78.313061 -418.646391) (xy 78.271844 -418.682106) (xy 78.225963 -418.711592)
			(xy 78.176353 -418.734249) (xy 78.124023 -418.749614) (xy 78.070039 -418.757376) (xy 78.015501 -418.757376)
			(xy 77.961517 -418.749614) (xy 77.909187 -418.734249) (xy 77.859577 -418.711592) (xy 77.813696 -418.682106)
			(xy 77.772479 -418.646391) (xy 77.736764 -418.605174) (xy 77.707278 -418.559293) (xy 77.684621 -418.509683)
			(xy 77.669256 -418.457353) (xy 77.661494 -418.403369) (xy 77.661008 -418.3761) (xy 71.234808 -418.3761)
			(xy 71.234808 -420.760398) (xy 71.234287 -420.772508) (xy 71.226806 -420.795543) (xy 71.212575 -420.815141)
			(xy 71.192986 -420.829384) (xy 71.169956 -420.83688) (xy 71.157846 -420.83736) (xy 70.218046 -420.83736)
			(xy 70.205925 -420.836901) (xy 70.182868 -420.829421) (xy 70.163252 -420.81518) (xy 70.148999 -420.795572)
			(xy 70.141506 -420.772518) (xy 70.141084 -420.760398) (xy 69.234812 -420.760398) (xy 69.234812 -421.760396)
			(xy 69.234337 -421.772445) (xy 69.226907 -421.795368) (xy 69.212769 -421.814883) (xy 69.193303 -421.829087)
			(xy 69.170405 -421.836595) (xy 69.158358 -421.837104) (xy 68.21805 -421.837104) (xy 68.205967 -421.836551)
			(xy 68.182976 -421.829113) (xy 68.163399 -421.814947) (xy 68.149145 -421.795434) (xy 68.141604 -421.772476)
			(xy 68.141088 -421.760396) (xy 63.207258 -421.760396) (xy 63.212645 -421.764306) (xy 63.226899 -421.783907)
			(xy 63.234398 -421.806953) (xy 63.234824 -421.81907) (xy 63.234824 -424.360594) (xy 63.234434 -424.37272)
			(xy 63.226939 -424.395785) (xy 63.212681 -424.415404) (xy 63.193057 -424.429654) (xy 63.169988 -424.437139)
			(xy 63.157862 -424.437556) (xy 62.218062 -424.437556) (xy 62.205945 -424.437121) (xy 62.182899 -424.429622)
			(xy 62.163298 -424.415371) (xy 62.149058 -424.395761) (xy 62.141572 -424.372711) (xy 62.1411 -424.360594)
			(xy 59.234832 -424.360594) (xy 59.234434 -424.372719) (xy 59.22694 -424.395783) (xy 59.212684 -424.415401)
			(xy 59.193062 -424.429651) (xy 59.169996 -424.437138) (xy 59.15787 -424.437556) (xy 58.21807 -424.437556)
			(xy 58.205953 -424.437114) (xy 58.182908 -424.429618) (xy 58.163306 -424.415368) (xy 58.149066 -424.39576)
			(xy 58.14158 -424.372711) (xy 58.141108 -424.360594) (xy 22.691108 -424.360594) (xy 22.697828 -424.383481)
			(xy 22.70559 -424.437465) (xy 22.706076 -424.464734) (xy 22.706076 -425.328334) (xy 22.70559 -425.355603)
			(xy 22.697828 -425.409587) (xy 22.682463 -425.461917) (xy 22.659806 -425.511527) (xy 22.63032 -425.557408)
			(xy 22.594605 -425.598625) (xy 22.553388 -425.63434) (xy 22.507507 -425.663826) (xy 22.457897 -425.686483)
			(xy 22.405567 -425.701848) (xy 22.351583 -425.70961) (xy 22.297045 -425.70961) (xy 22.243061 -425.701848)
			(xy 22.190731 -425.686483) (xy 22.141121 -425.663826) (xy 22.09524 -425.63434) (xy 22.054023 -425.598625)
			(xy 22.018308 -425.557408) (xy 21.988822 -425.511527) (xy 21.966165 -425.461917) (xy 21.9508 -425.409587)
			(xy 21.943038 -425.355603) (xy 21.942552 -425.328334) (xy 10.968228 -425.328334) (xy 10.968228 -425.887642)
			(xy 10.967742 -425.914911) (xy 10.964527 -425.937273) (xy 38.737196 -425.937273) (xy 38.737196 -425.882727)
			(xy 38.744959 -425.828736) (xy 38.760327 -425.776399) (xy 38.782988 -425.726782) (xy 38.81248 -425.680896)
			(xy 38.848202 -425.639674) (xy 38.889428 -425.603956) (xy 38.935317 -425.574469) (xy 38.984936 -425.551813)
			(xy 39.037275 -425.53645) (xy 39.091267 -425.528693) (xy 39.11854 -425.528232) (xy 39.98214 -425.528232)
			(xy 40.009407 -425.528733) (xy 40.063385 -425.536499) (xy 40.115709 -425.551868) (xy 40.165314 -425.574526)
			(xy 40.211189 -425.604012) (xy 40.252401 -425.639727) (xy 40.288112 -425.680943) (xy 40.317593 -425.726821)
			(xy 40.340246 -425.776428) (xy 40.355609 -425.828754) (xy 40.36337 -425.882733) (xy 40.36337 -425.937267)
			(xy 40.355609 -425.991246) (xy 40.340246 -426.043572) (xy 40.317593 -426.093179) (xy 40.288112 -426.139057)
			(xy 40.252401 -426.180273) (xy 40.211189 -426.215988) (xy 40.165314 -426.245474) (xy 40.115709 -426.268132)
			(xy 40.063385 -426.283501) (xy 40.009407 -426.291267) (xy 39.98214 -426.291756) (xy 39.11854 -426.291756)
			(xy 39.091267 -426.291307) (xy 39.037275 -426.28355) (xy 38.984936 -426.268187) (xy 38.935317 -426.245531)
			(xy 38.889428 -426.216044) (xy 38.848202 -426.180326) (xy 38.81248 -426.139104) (xy 38.782988 -426.093218)
			(xy 38.760327 -426.043601) (xy 38.744959 -425.991264) (xy 38.737196 -425.937273) (xy 10.964527 -425.937273)
			(xy 10.95998 -425.968895) (xy 10.944615 -426.021225) (xy 10.921958 -426.070835) (xy 10.892472 -426.116716)
			(xy 10.856757 -426.157933) (xy 10.81554 -426.193648) (xy 10.769659 -426.223134) (xy 10.720049 -426.245791)
			(xy 10.667719 -426.261156) (xy 10.613735 -426.268918) (xy 10.559197 -426.268918) (xy 10.505213 -426.261156)
			(xy 10.452883 -426.245791) (xy 10.403273 -426.223134) (xy 10.357392 -426.193648) (xy 10.316175 -426.157933)
			(xy 10.28046 -426.116716) (xy 10.250974 -426.070835) (xy 10.228317 -426.021225) (xy 10.212952 -425.968895)
			(xy 10.20519 -425.914911) (xy 10.204704 -425.887642) (xy 7.00913 -425.887642) (xy 7.00913 -426.333158)
			(xy 41.613836 -426.333158) (xy 41.613836 -425.469558) (xy 41.614322 -425.442307) (xy 41.622078 -425.388359)
			(xy 41.637433 -425.336064) (xy 41.660075 -425.286487) (xy 41.689541 -425.240637) (xy 41.725232 -425.199446)
			(xy 41.766423 -425.163755) (xy 41.812273 -425.134289) (xy 41.86185 -425.111647) (xy 41.914145 -425.096292)
			(xy 41.968093 -425.088536) (xy 42.022595 -425.088536) (xy 42.076543 -425.096292) (xy 42.128838 -425.111647)
			(xy 42.178415 -425.134289) (xy 42.224265 -425.163755) (xy 42.265456 -425.199446) (xy 42.301147 -425.240637)
			(xy 42.330613 -425.286487) (xy 42.353255 -425.336064) (xy 42.36861 -425.388359) (xy 42.376366 -425.442307)
			(xy 42.376852 -425.469558) (xy 42.376852 -426.333158) (xy 42.376366 -426.360409) (xy 42.36861 -426.414357)
			(xy 42.353255 -426.466652) (xy 42.330613 -426.516229) (xy 42.301147 -426.562079) (xy 42.265456 -426.60327)
			(xy 42.224265 -426.638961) (xy 42.178415 -426.668427) (xy 42.128838 -426.691069) (xy 42.076543 -426.706424)
			(xy 42.022595 -426.71418) (xy 41.968093 -426.71418) (xy 41.914145 -426.706424) (xy 41.86185 -426.691069)
			(xy 41.812273 -426.668427) (xy 41.766423 -426.638961) (xy 41.725232 -426.60327) (xy 41.689541 -426.562079)
			(xy 41.660075 -426.516229) (xy 41.637433 -426.466652) (xy 41.622078 -426.414357) (xy 41.614322 -426.360409)
			(xy 41.613836 -426.333158) (xy 7.00913 -426.333158) (xy 7.00913 -428.615602) (xy 25.13076 -428.615602)
			(xy 25.13076 -427.752002) (xy 25.131246 -427.724733) (xy 25.139008 -427.670749) (xy 25.154373 -427.618419)
			(xy 25.17703 -427.568809) (xy 25.206516 -427.522928) (xy 25.242231 -427.481711) (xy 25.283448 -427.445996)
			(xy 25.329329 -427.41651) (xy 25.378939 -427.393853) (xy 25.431269 -427.378488) (xy 25.485253 -427.370726)
			(xy 25.539791 -427.370726) (xy 25.593775 -427.378488) (xy 25.646105 -427.393853) (xy 25.695715 -427.41651)
			(xy 25.741596 -427.445996) (xy 25.782813 -427.481711) (xy 25.818528 -427.522928) (xy 25.848014 -427.568809)
			(xy 25.870671 -427.618419) (xy 25.886036 -427.670749) (xy 25.893798 -427.724733) (xy 25.894284 -427.752002)
			(xy 25.894284 -428.211072) (xy 26.941204 -428.211072) (xy 26.941204 -428.156528) (xy 26.948966 -428.102539)
			(xy 26.964334 -428.050205) (xy 26.986993 -428.00059) (xy 27.016483 -427.954705) (xy 27.052203 -427.913485)
			(xy 27.093426 -427.877767) (xy 27.139313 -427.848281) (xy 27.188929 -427.825625) (xy 27.241265 -427.810261)
			(xy 27.295254 -427.802502) (xy 27.322526 -427.80204) (xy 28.186126 -427.80204) (xy 28.213394 -427.802524)
			(xy 28.267375 -427.810289) (xy 28.319702 -427.825657) (xy 28.369309 -427.848314) (xy 28.415187 -427.877801)
			(xy 28.456402 -427.913517) (xy 28.492114 -427.954734) (xy 28.495843 -427.960536) (xy 58.141108 -427.960536)
			(xy 58.141108 -425.419012) (xy 58.14157 -425.406962) (xy 58.149001 -425.384035) (xy 58.163141 -425.364518)
			(xy 58.182611 -425.350315) (xy 58.205513 -425.34281) (xy 58.217562 -425.342304) (xy 59.15787 -425.342304)
			(xy 59.169954 -425.342832) (xy 59.192948 -425.350276) (xy 59.212525 -425.364448) (xy 59.226778 -425.383967)
			(xy 59.234317 -425.40693) (xy 59.234832 -425.419012) (xy 59.234832 -427.960536) (xy 59.234372 -427.972585)
			(xy 59.226933 -427.995506) (xy 59.212791 -428.015019) (xy 59.193323 -428.029222) (xy 59.170425 -428.036733)
			(xy 59.158378 -428.037244) (xy 58.21807 -428.037244) (xy 58.205977 -428.036818) (xy 58.182973 -428.029351)
			(xy 58.163392 -428.015154) (xy 58.149143 -427.995612) (xy 58.141615 -427.972627) (xy 58.141108 -427.960536)
			(xy 28.495843 -427.960536) (xy 28.521598 -428.000614) (xy 28.544253 -428.050222) (xy 28.559617 -428.10255)
			(xy 28.567378 -428.156532) (xy 28.567378 -428.211068) (xy 28.559617 -428.26505) (xy 28.544253 -428.317378)
			(xy 28.521598 -428.366986) (xy 28.492114 -428.412866) (xy 28.456402 -428.454083) (xy 28.415187 -428.489799)
			(xy 28.369309 -428.519286) (xy 28.319702 -428.541943) (xy 28.267375 -428.557311) (xy 28.213394 -428.565076)
			(xy 28.186126 -428.565564) (xy 27.322526 -428.565564) (xy 27.295254 -428.565098) (xy 27.241265 -428.557339)
			(xy 27.188929 -428.541975) (xy 27.139313 -428.519319) (xy 27.093426 -428.489833) (xy 27.052203 -428.454115)
			(xy 27.016483 -428.412895) (xy 26.986993 -428.36701) (xy 26.964334 -428.317395) (xy 26.948966 -428.265061)
			(xy 26.941204 -428.211072) (xy 25.894284 -428.211072) (xy 25.894284 -428.615602) (xy 25.893798 -428.642871)
			(xy 25.886036 -428.696855) (xy 25.870671 -428.749185) (xy 25.848014 -428.798795) (xy 25.818528 -428.844676)
			(xy 25.782813 -428.885893) (xy 25.741596 -428.921608) (xy 25.695715 -428.951094) (xy 25.646105 -428.973751)
			(xy 25.593775 -428.989116) (xy 25.539791 -428.996878) (xy 25.485253 -428.996878) (xy 25.431269 -428.989116)
			(xy 25.378939 -428.973751) (xy 25.329329 -428.951094) (xy 25.283448 -428.921608) (xy 25.242231 -428.885893)
			(xy 25.206516 -428.844676) (xy 25.17703 -428.798795) (xy 25.154373 -428.749185) (xy 25.139008 -428.696855)
			(xy 25.131246 -428.642871) (xy 25.13076 -428.615602) (xy 7.00913 -428.615602) (xy 7.00913 -431.560478)
			(xy 58.141108 -431.560478) (xy 58.141108 -430.83353) (xy 58.141421 -430.82476) (xy 58.145529 -430.807702)
			(xy 58.149236 -430.799748) (xy 58.149236 -430.79924) (xy 58.382662 -430.323244) (xy 58.387387 -430.312737)
			(xy 58.390865 -430.289973) (xy 58.387371 -430.267211) (xy 58.382662 -430.256696) (xy 58.149236 -429.7807)
			(xy 58.149236 -429.780192) (xy 58.145507 -429.772245) (xy 58.141403 -429.755183) (xy 58.141108 -429.74641)
			(xy 58.141108 -429.018954) (xy 58.141572 -429.00684) (xy 58.149068 -428.9838) (xy 58.163313 -428.964202)
			(xy 58.182915 -428.949961) (xy 58.205956 -428.94247) (xy 58.21807 -428.941992) (xy 59.15787 -428.941992)
			(xy 59.169978 -428.942537) (xy 59.193013 -428.95001) (xy 59.207512 -428.960534) (xy 60.141104 -428.960534)
			(xy 60.141104 -426.41901) (xy 60.14162 -426.406899) (xy 60.1491 -426.383862) (xy 60.163332 -426.364263)
			(xy 60.182923 -426.35002) (xy 60.205956 -426.342527) (xy 60.218066 -426.342048) (xy 61.157866 -426.342048)
			(xy 61.169988 -426.342489) (xy 61.193047 -426.349973) (xy 61.212664 -426.364219) (xy 61.226916 -426.383831)
			(xy 61.234407 -426.406888) (xy 61.234828 -426.41901) (xy 61.234828 -427.960536) (xy 62.1411 -427.960536)
			(xy 62.1411 -425.419012) (xy 62.14157 -425.406962) (xy 62.149 -425.384037) (xy 62.163138 -425.364521)
			(xy 62.182606 -425.350318) (xy 62.205506 -425.342811) (xy 62.217554 -425.342304) (xy 63.157862 -425.342304)
			(xy 63.169946 -425.342839) (xy 63.192939 -425.350281) (xy 63.207185 -425.360592) (xy 64.141096 -425.360592)
			(xy 64.141096 -422.819068) (xy 64.141532 -422.807017) (xy 64.148973 -422.784091) (xy 64.16312 -422.764576)
			(xy 64.182595 -422.750373) (xy 64.2055 -422.742867) (xy 64.21755 -422.74236) (xy 65.157858 -422.74236)
			(xy 65.169947 -422.742843) (xy 65.19295 -422.750291) (xy 65.212532 -422.764473) (xy 65.226784 -422.784004)
			(xy 65.234313 -422.80698) (xy 65.23482 -422.819068) (xy 65.23482 -425.360592) (xy 65.234334 -425.37264)
			(xy 65.226905 -425.395562) (xy 65.212771 -425.415076) (xy 65.193307 -425.42928) (xy 65.170412 -425.43679)
			(xy 65.158366 -425.4373) (xy 64.218058 -425.4373) (xy 64.20597 -425.436829) (xy 64.182975 -425.429366)
			(xy 64.163399 -425.415179) (xy 64.149149 -425.395649) (xy 64.141611 -425.372678) (xy 64.141096 -425.360592)
			(xy 63.207185 -425.360592) (xy 63.212517 -425.364451) (xy 63.22677 -425.383968) (xy 63.234309 -425.40693)
			(xy 63.234824 -425.419012) (xy 63.234824 -427.960536) (xy 63.234371 -427.972586) (xy 63.226932 -427.995508)
			(xy 63.212788 -428.015022) (xy 63.193318 -428.029225) (xy 63.170418 -428.036734) (xy 63.15837 -428.037244)
			(xy 62.218062 -428.037244) (xy 62.205969 -428.036825) (xy 62.182964 -428.029356) (xy 62.163384 -428.015157)
			(xy 62.149135 -427.995613) (xy 62.141607 -427.972628) (xy 62.1411 -427.960536) (xy 61.234828 -427.960536)
			(xy 61.234828 -428.960534) (xy 61.234417 -428.972654) (xy 61.226916 -428.995704) (xy 61.21266 -429.015308)
			(xy 61.193043 -429.029547) (xy 61.169986 -429.037027) (xy 61.157866 -429.037496) (xy 60.218066 -429.037496)
			(xy 60.205953 -429.037018) (xy 60.182914 -429.029525) (xy 60.163316 -429.015284) (xy 60.149075 -428.995686)
			(xy 60.141582 -428.972647) (xy 60.141104 -428.960534) (xy 59.207512 -428.960534) (xy 59.212611 -428.964235)
			(xy 59.226855 -428.983819) (xy 59.234351 -429.006846) (xy 59.234832 -429.018954) (xy 59.234832 -431.560478)
			(xy 59.234421 -431.572603) (xy 59.226931 -431.595666) (xy 59.212678 -431.615284) (xy 59.193059 -431.629535)
			(xy 59.169995 -431.637022) (xy 59.15787 -431.63744) (xy 58.21807 -431.63744) (xy 58.205952 -431.637014)
			(xy 58.182904 -431.629515) (xy 58.163301 -431.615262) (xy 58.149061 -431.59565) (xy 58.141578 -431.572597)
			(xy 58.141108 -431.560478) (xy 7.00913 -431.560478) (xy 7.00913 -435.16042) (xy 58.141108 -435.16042)
			(xy 58.141108 -434.433472) (xy 58.141434 -434.424703) (xy 58.145533 -434.407645) (xy 58.149236 -434.39969)
			(xy 58.149236 -434.399182) (xy 58.382662 -433.923186) (xy 58.387358 -433.912668) (xy 58.390846 -433.889911)
			(xy 58.387364 -433.867153) (xy 58.382662 -433.856638) (xy 58.149236 -433.380642) (xy 58.149236 -433.380134)
			(xy 58.145521 -433.372182) (xy 58.141408 -433.355124) (xy 58.141108 -433.346352) (xy 58.141108 -432.618896)
			(xy 58.141557 -432.606845) (xy 58.148992 -432.583918) (xy 58.163135 -432.564401) (xy 58.182608 -432.550199)
			(xy 58.205512 -432.542694) (xy 58.217562 -432.542188) (xy 59.15787 -432.542188) (xy 59.169963 -432.542634)
			(xy 59.19297 -432.550088) (xy 59.207307 -432.560476) (xy 60.141104 -432.560476) (xy 60.141104 -431.833528)
			(xy 60.141417 -431.824758) (xy 60.145525 -431.8077) (xy 60.149232 -431.799746) (xy 60.149232 -431.799238)
			(xy 60.382658 -431.323242) (xy 60.387385 -431.312736) (xy 60.390862 -431.289971) (xy 60.387367 -431.267209)
			(xy 60.382658 -431.256694) (xy 60.149232 -430.780698) (xy 60.149232 -430.78019) (xy 60.145503 -430.772244)
			(xy 60.141399 -430.755181) (xy 60.141104 -430.746408) (xy 60.141104 -430.018952) (xy 60.141519 -430.006899)
			(xy 60.148965 -429.983971) (xy 60.163118 -429.964456) (xy 60.182597 -429.950254) (xy 60.205506 -429.94275)
			(xy 60.217558 -429.942244) (xy 61.157866 -429.942244) (xy 61.169954 -429.942736) (xy 61.192954 -429.950184)
			(xy 61.212535 -429.964364) (xy 61.226787 -429.983893) (xy 61.234319 -430.006866) (xy 61.234828 -430.018952)
			(xy 61.234828 -431.560478) (xy 62.1411 -431.560478) (xy 62.1411 -430.83353) (xy 62.141404 -430.824759)
			(xy 62.145517 -430.807701) (xy 62.149228 -430.799748) (xy 62.149228 -430.79924) (xy 62.382654 -430.323244)
			(xy 62.387379 -430.312737) (xy 62.390858 -430.289973) (xy 62.387363 -430.267211) (xy 62.382654 -430.256696)
			(xy 62.149228 -429.7807) (xy 62.149228 -429.780192) (xy 62.145499 -429.772246) (xy 62.141395 -429.755183)
			(xy 62.1411 -429.74641) (xy 62.1411 -429.018954) (xy 62.141572 -429.006841) (xy 62.149067 -428.983803)
			(xy 62.163311 -428.964205) (xy 62.18291 -428.949964) (xy 62.205949 -428.942471) (xy 62.218062 -428.941992)
			(xy 63.157862 -428.941992) (xy 63.16997 -428.942543) (xy 63.193004 -428.950015) (xy 63.207499 -428.960534)
			(xy 64.141096 -428.960534) (xy 64.141096 -426.41901) (xy 64.14162 -426.4069) (xy 64.149099 -426.383864)
			(xy 64.163329 -426.364266) (xy 64.182918 -426.350023) (xy 64.205948 -426.342528) (xy 64.218058 -426.342048)
			(xy 65.157858 -426.342048) (xy 65.16998 -426.342496) (xy 65.193039 -426.349978) (xy 65.212655 -426.364222)
			(xy 65.226908 -426.383833) (xy 65.234399 -426.406889) (xy 65.23482 -426.41901) (xy 65.23482 -427.960536)
			(xy 66.141092 -427.960536) (xy 66.141092 -425.419012) (xy 66.14157 -425.406963) (xy 66.148998 -425.384039)
			(xy 66.163135 -425.364524) (xy 66.182601 -425.35032) (xy 66.205499 -425.342812) (xy 66.217546 -425.342304)
			(xy 67.157854 -425.342304) (xy 67.169938 -425.342846) (xy 67.192931 -425.350286) (xy 67.207172 -425.360592)
			(xy 68.141088 -425.360592) (xy 68.141088 -422.819068) (xy 68.141532 -422.807017) (xy 68.148972 -422.784093)
			(xy 68.163118 -422.764578) (xy 68.18259 -422.750376) (xy 68.205493 -422.742868) (xy 68.217542 -422.74236)
			(xy 69.15785 -422.74236) (xy 69.169939 -422.74285) (xy 69.192941 -422.750296) (xy 69.212524 -422.764475)
			(xy 69.226775 -422.784006) (xy 69.234305 -422.806981) (xy 69.234812 -422.819068) (xy 69.234812 -424.360594)
			(xy 70.141084 -424.360594) (xy 70.141084 -421.81907) (xy 70.141435 -421.806941) (xy 70.148941 -421.783873)
			(xy 70.163209 -421.764255) (xy 70.182842 -421.750006) (xy 70.205917 -421.742523) (xy 70.218046 -421.742108)
			(xy 71.157846 -421.742108) (xy 71.16996 -421.742572) (xy 71.193 -421.750068) (xy 71.207209 -421.760396)
			(xy 72.14108 -421.760396) (xy 72.14108 -419.218872) (xy 72.141535 -419.206822) (xy 72.148973 -419.183899)
			(xy 72.163116 -419.164386) (xy 72.182586 -419.150182) (xy 72.205486 -419.142673) (xy 72.217534 -419.142164)
			(xy 73.157842 -419.142164) (xy 73.169936 -419.142572) (xy 73.192942 -419.150043) (xy 73.212524 -419.164244)
			(xy 73.226772 -419.183791) (xy 73.234298 -419.206779) (xy 73.234804 -419.218872) (xy 73.234804 -420.921688)
			(xy 75.13828 -420.921688) (xy 75.13828 -420.058088) (xy 75.138766 -420.030819) (xy 75.146528 -419.976835)
			(xy 75.161893 -419.924505) (xy 75.18455 -419.874895) (xy 75.214036 -419.829014) (xy 75.249751 -419.787797)
			(xy 75.290968 -419.752082) (xy 75.336849 -419.722596) (xy 75.386459 -419.699939) (xy 75.438789 -419.684574)
			(xy 75.492773 -419.676812) (xy 75.547311 -419.676812) (xy 75.601295 -419.684574) (xy 75.653625 -419.699939)
			(xy 75.703235 -419.722596) (xy 75.749116 -419.752082) (xy 75.790333 -419.787797) (xy 75.826048 -419.829014)
			(xy 75.855534 -419.874895) (xy 75.878191 -419.924505) (xy 75.893556 -419.976835) (xy 75.901318 -420.030819)
			(xy 75.901804 -420.058088) (xy 75.901804 -420.921688) (xy 75.901318 -420.948957) (xy 75.893556 -421.002941)
			(xy 75.878191 -421.055271) (xy 75.855534 -421.104881) (xy 75.844472 -421.122094) (xy 97.149412 -421.122094)
			(xy 97.149412 -414.328102) (xy 97.149934 -414.317948) (xy 97.157703 -414.299183) (xy 97.17206 -414.284819)
			(xy 97.19082 -414.27704) (xy 97.200974 -414.27654) (xy 102.099618 -414.27654) (xy 102.109777 -414.277018)
			(xy 102.128547 -414.284799) (xy 102.142912 -414.29917) (xy 102.150685 -414.317943) (xy 102.15118 -414.328102)
			(xy 102.15118 -420.700708) (xy 194.5894 -420.700708) (xy 194.5894 -413.816038) (xy 194.589861 -413.791087)
			(xy 194.597682 -413.741803) (xy 194.613107 -413.694345) (xy 194.635757 -413.649879) (xy 194.665075 -413.609499)
			(xy 194.682364 -413.591502) (xy 195.567808 -412.706058) (xy 195.585788 -412.68875) (xy 195.626166 -412.659421)
			(xy 195.670635 -412.63677) (xy 195.718099 -412.621355) (xy 195.767391 -412.613554) (xy 195.792344 -412.613094)
			(xy 226.774756 -412.613094) (xy 226.784823 -412.612647) (xy 226.803421 -412.604942) (xy 226.810824 -412.598108)
			(xy 229.320852 -410.08808) (xy 229.338817 -410.070757) (xy 229.379202 -410.041438) (xy 229.423675 -410.018797)
			(xy 229.471142 -410.003391) (xy 229.520435 -409.995598) (xy 229.545388 -409.995116) (xy 234.56519 -409.995116)
			(xy 234.575262 -409.994708) (xy 234.593861 -409.986977) (xy 234.601258 -409.98013) (xy 238.550196 -406.031192)
			(xy 238.557032 -406.023788) (xy 238.564754 -406.005192) (xy 238.565182 -405.995124) (xy 238.565182 -394.001498)
			(xy 238.565686 -393.976549) (xy 238.573497 -393.927266) (xy 238.588912 -393.879809) (xy 238.611553 -393.835343)
			(xy 238.640862 -393.79496) (xy 238.658146 -393.776962) (xy 238.727234 -393.707874) (xy 238.733961 -393.700496)
			(xy 238.741558 -393.682047) (xy 238.741546 -393.662096) (xy 238.733929 -393.643656) (xy 238.727234 -393.636246)
			(xy 238.579914 -393.488672) (xy 238.553014 -393.461125) (xy 238.504928 -393.400988) (xy 238.463885 -393.33584)
			(xy 238.430403 -393.266502) (xy 238.404904 -393.193848) (xy 238.387709 -393.118794) (xy 238.379036 -393.042285)
			(xy 238.378492 -393.003786) (xy 238.378492 -384.337306) (xy 238.379215 -384.306679) (xy 238.390978 -384.246564)
			(xy 238.40186 -384.217926) (xy 238.457994 -384.079496) (xy 238.466633 -384.059188) (xy 238.488684 -384.020961)
			(xy 238.515818 -383.986157) (xy 238.5314 -383.97053) (xy 238.583216 -383.920746) (xy 238.583724 -383.920238)
			(xy 239.05718 -383.446782) (xy 239.084743 -383.419899) (xy 239.144878 -383.371812) (xy 239.210023 -383.330768)
			(xy 239.279359 -383.297284) (xy 239.35201 -383.271782) (xy 239.427061 -383.254584) (xy 239.503568 -383.245906)
			(xy 239.542066 -383.24536) (xy 273.481546 -383.24536) (xy 273.512174 -383.24607) (xy 273.572289 -383.257841)
			(xy 273.600926 -383.268728) (xy 273.739356 -383.324862) (xy 273.759667 -383.333494) (xy 273.797892 -383.355549)
			(xy 273.832695 -383.382685) (xy 273.848322 -383.398268) (xy 273.898106 -383.450084) (xy 273.898614 -383.450592)
			(xy 274.11807 -383.670048) (xy 274.1422 -383.695194) (xy 274.149515 -383.702446) (xy 274.168248 -383.710967)
			(xy 274.178522 -383.711704) (xy 274.251674 -383.713482) (xy 274.262067 -383.713236) (xy 274.281342 -383.705512)
			(xy 274.289012 -383.698496) (xy 274.649184 -383.338324) (xy 274.667186 -383.321041) (xy 274.70756 -383.291715)
			(xy 274.752024 -383.269066) (xy 274.799483 -383.25365) (xy 274.84877 -383.245848) (xy 274.87372 -383.24536)
			(xy 280.202132 -383.24536) (xy 280.227081 -383.245851) (xy 280.276364 -383.253667) (xy 280.323821 -383.269085)
			(xy 280.368287 -383.291728) (xy 280.40867 -383.321039) (xy 280.426668 -383.338324) (xy 281.135836 -384.047492)
			(xy 281.153135 -384.065481) (xy 281.182465 -384.105856) (xy 281.205118 -384.150322) (xy 281.220536 -384.197785)
			(xy 281.228338 -384.247076) (xy 281.2288 -384.272028) (xy 281.2288 -384.869944) (xy 287.06878 -384.869944)
			(xy 287.072752 -384.691701) (xy 287.08466 -384.513812) (xy 287.104481 -384.33663) (xy 287.132175 -384.160506)
			(xy 287.167687 -383.985791) (xy 287.210947 -383.812832) (xy 287.261869 -383.641971) (xy 287.320352 -383.473549)
			(xy 287.386279 -383.307899) (xy 287.45952 -383.14535) (xy 287.53993 -382.986225) (xy 287.627348 -382.83084)
			(xy 287.721601 -382.679504) (xy 287.822502 -382.532516) (xy 287.929851 -382.390169) (xy 288.043434 -382.252746)
			(xy 288.163027 -382.120519) (xy 288.288391 -381.99375) (xy 288.419278 -381.872692) (xy 288.555427 -381.757585)
			(xy 288.696569 -381.648657) (xy 288.842424 -381.546125) (xy 288.992701 -381.450191) (xy 289.147102 -381.361048)
			(xy 289.305321 -381.278871) (xy 289.467044 -381.203823) (xy 289.631949 -381.136055) (xy 289.79971 -381.075699)
			(xy 289.969993 -381.022877) (xy 290.14246 -380.977693) (xy 290.316768 -380.940236) (xy 290.492572 -380.910582)
			(xy 290.669522 -380.888789) (xy 290.847268 -380.874899) (xy 291.025455 -380.868942) (xy 291.203732 -380.870928)
			(xy 291.381743 -380.880854) (xy 291.559135 -380.8987) (xy 291.735555 -380.92443) (xy 291.910655 -380.957994)
			(xy 292.084086 -380.999324) (xy 292.255503 -381.04834) (xy 292.424566 -381.104942) (xy 292.590941 -381.16902)
			(xy 292.754295 -381.240446) (xy 292.914306 -381.319078) (xy 293.070655 -381.404759) (xy 293.223032 -381.497321)
			(xy 293.371135 -381.596578) (xy 293.514669 -381.702335) (xy 293.653349 -381.81438) (xy 293.7869 -381.932492)
			(xy 293.915057 -382.056436) (xy 294.037566 -382.185966) (xy 294.154183 -382.320825) (xy 294.194727 -382.372167)
			(xy 303.739054 -382.372167) (xy 303.739054 -382.317633) (xy 303.746815 -382.263654) (xy 303.762179 -382.211329)
			(xy 303.784833 -382.161723) (xy 303.814317 -382.115846) (xy 303.850029 -382.074631) (xy 303.891242 -382.038919)
			(xy 303.937119 -382.009435) (xy 303.986725 -381.986781) (xy 304.03905 -381.971416) (xy 304.093029 -381.963655)
			(xy 304.120296 -381.963168) (xy 304.983896 -381.963168) (xy 305.011169 -381.963571) (xy 305.065161 -381.971334)
			(xy 305.117498 -381.986701) (xy 305.167116 -382.00936) (xy 305.213003 -382.03885) (xy 305.254227 -382.07457)
			(xy 305.289948 -382.115793) (xy 305.319438 -382.161681) (xy 305.342098 -382.211298) (xy 305.357466 -382.263635)
			(xy 305.365228 -382.317627) (xy 305.365228 -382.372167) (xy 310.546254 -382.372167) (xy 310.546254 -382.317633)
			(xy 310.554015 -382.263654) (xy 310.569379 -382.211329) (xy 310.592033 -382.161723) (xy 310.621517 -382.115846)
			(xy 310.657229 -382.074631) (xy 310.698442 -382.038919) (xy 310.744319 -382.009435) (xy 310.793925 -381.986781)
			(xy 310.84625 -381.971416) (xy 310.900229 -381.963655) (xy 310.927496 -381.963168) (xy 311.791096 -381.963168)
			(xy 311.818369 -381.963571) (xy 311.872361 -381.971334) (xy 311.924698 -381.986701) (xy 311.974316 -382.00936)
			(xy 312.020203 -382.03885) (xy 312.061427 -382.07457) (xy 312.097148 -382.115793) (xy 312.126638 -382.161681)
			(xy 312.149298 -382.211298) (xy 312.164666 -382.263635) (xy 312.172428 -382.317627) (xy 312.172428 -382.372167)
			(xy 317.353454 -382.372167) (xy 317.353454 -382.317633) (xy 317.361215 -382.263654) (xy 317.376579 -382.211329)
			(xy 317.399233 -382.161723) (xy 317.428717 -382.115846) (xy 317.464429 -382.074631) (xy 317.505642 -382.038919)
			(xy 317.551519 -382.009435) (xy 317.601125 -381.986781) (xy 317.65345 -381.971416) (xy 317.707429 -381.963655)
			(xy 317.734696 -381.963168) (xy 318.598296 -381.963168) (xy 318.625569 -381.963571) (xy 318.679561 -381.971334)
			(xy 318.731898 -381.986701) (xy 318.781516 -382.00936) (xy 318.827403 -382.03885) (xy 318.868627 -382.07457)
			(xy 318.904348 -382.115793) (xy 318.933838 -382.161681) (xy 318.956498 -382.211298) (xy 318.971866 -382.263635)
			(xy 318.979628 -382.317627) (xy 318.979628 -382.372171) (xy 336.266732 -382.372171) (xy 336.266732 -382.317629)
			(xy 336.274494 -382.263643) (xy 336.289861 -382.211311) (xy 336.312521 -382.161698) (xy 336.34201 -382.115816)
			(xy 336.377729 -382.074598) (xy 336.418951 -382.038884) (xy 336.464837 -382.009399) (xy 336.514452 -381.986746)
			(xy 336.566786 -381.971385) (xy 336.620773 -381.963628) (xy 336.648044 -381.963168) (xy 337.511644 -381.963168)
			(xy 337.538913 -381.963598) (xy 337.592897 -381.971365) (xy 337.645225 -381.986735) (xy 337.694833 -382.009396)
			(xy 337.740712 -382.038885) (xy 337.781928 -382.074603) (xy 337.817641 -382.115823) (xy 337.847125 -382.161705)
			(xy 337.86978 -382.211316) (xy 337.885144 -382.263647) (xy 337.892906 -382.31763) (xy 337.892906 -382.37217)
			(xy 337.892906 -382.372171) (xy 343.073932 -382.372171) (xy 343.073932 -382.317629) (xy 343.081694 -382.263643)
			(xy 343.097061 -382.211311) (xy 343.119721 -382.161698) (xy 343.14921 -382.115816) (xy 343.184929 -382.074598)
			(xy 343.226151 -382.038884) (xy 343.272037 -382.009399) (xy 343.321652 -381.986746) (xy 343.373986 -381.971385)
			(xy 343.427973 -381.963628) (xy 343.455244 -381.963168) (xy 344.318844 -381.963168) (xy 344.346113 -381.963598)
			(xy 344.400097 -381.971365) (xy 344.452425 -381.986735) (xy 344.502033 -382.009396) (xy 344.547912 -382.038885)
			(xy 344.589128 -382.074603) (xy 344.624841 -382.115823) (xy 344.654325 -382.161705) (xy 344.67698 -382.211316)
			(xy 344.692344 -382.263647) (xy 344.700106 -382.31763) (xy 344.700106 -382.37217) (xy 344.700106 -382.372171)
			(xy 349.881132 -382.372171) (xy 349.881132 -382.317629) (xy 349.888894 -382.263643) (xy 349.904261 -382.211311)
			(xy 349.926921 -382.161698) (xy 349.95641 -382.115816) (xy 349.992129 -382.074598) (xy 350.033351 -382.038884)
			(xy 350.079237 -382.009399) (xy 350.128852 -381.986746) (xy 350.181186 -381.971385) (xy 350.235173 -381.963628)
			(xy 350.262444 -381.963168) (xy 351.126044 -381.963168) (xy 351.153313 -381.963598) (xy 351.207297 -381.971365)
			(xy 351.259625 -381.986735) (xy 351.309233 -382.009396) (xy 351.355112 -382.038885) (xy 351.396328 -382.074603)
			(xy 351.432041 -382.115823) (xy 351.461525 -382.161705) (xy 351.48418 -382.211316) (xy 351.499544 -382.263647)
			(xy 351.507306 -382.31763) (xy 351.507306 -382.372167) (xy 370.839254 -382.372167) (xy 370.839254 -382.317633)
			(xy 370.847015 -382.263654) (xy 370.862379 -382.21133) (xy 370.885033 -382.161724) (xy 370.914516 -382.115847)
			(xy 370.950227 -382.074633) (xy 370.991441 -382.03892) (xy 371.037317 -382.009437) (xy 371.086922 -381.986782)
			(xy 371.139247 -381.971417) (xy 371.193225 -381.963655) (xy 371.220492 -381.963168) (xy 372.084092 -381.963168)
			(xy 372.111366 -381.963571) (xy 372.165357 -381.971333) (xy 372.217695 -381.9867) (xy 372.267313 -382.009359)
			(xy 372.313202 -382.038848) (xy 372.354426 -382.074568) (xy 372.390147 -382.115792) (xy 372.419638 -382.16168)
			(xy 372.442298 -382.211297) (xy 372.457665 -382.263635) (xy 372.465428 -382.317626) (xy 372.465428 -382.372167)
			(xy 377.646454 -382.372167) (xy 377.646454 -382.317633) (xy 377.654215 -382.263654) (xy 377.669579 -382.21133)
			(xy 377.692233 -382.161724) (xy 377.721716 -382.115847) (xy 377.757427 -382.074633) (xy 377.798641 -382.03892)
			(xy 377.844517 -382.009437) (xy 377.894122 -381.986782) (xy 377.946447 -381.971417) (xy 378.000425 -381.963655)
			(xy 378.027692 -381.963168) (xy 378.891292 -381.963168) (xy 378.918566 -381.963571) (xy 378.972557 -381.971333)
			(xy 379.024895 -381.9867) (xy 379.074513 -382.009359) (xy 379.120402 -382.038848) (xy 379.161626 -382.074568)
			(xy 379.197347 -382.115792) (xy 379.226838 -382.16168) (xy 379.249498 -382.211297) (xy 379.264865 -382.263635)
			(xy 379.272628 -382.317626) (xy 379.272628 -382.372167) (xy 384.453654 -382.372167) (xy 384.453654 -382.317633)
			(xy 384.461415 -382.263654) (xy 384.476779 -382.21133) (xy 384.499433 -382.161724) (xy 384.528916 -382.115847)
			(xy 384.564627 -382.074633) (xy 384.605841 -382.03892) (xy 384.651717 -382.009437) (xy 384.701322 -381.986782)
			(xy 384.753647 -381.971417) (xy 384.807625 -381.963655) (xy 384.834892 -381.963168) (xy 385.698492 -381.963168)
			(xy 385.725766 -381.963571) (xy 385.779757 -381.971333) (xy 385.832095 -381.9867) (xy 385.881713 -382.009359)
			(xy 385.927602 -382.038848) (xy 385.968826 -382.074568) (xy 386.004547 -382.115792) (xy 386.034038 -382.16168)
			(xy 386.056698 -382.211297) (xy 386.072065 -382.263635) (xy 386.079828 -382.317626) (xy 386.079828 -382.372171)
			(xy 403.366932 -382.372171) (xy 403.366932 -382.317629) (xy 403.374694 -382.263643) (xy 403.390061 -382.211311)
			(xy 403.41272 -382.161699) (xy 403.442209 -382.115817) (xy 403.477928 -382.0746) (xy 403.51915 -382.038885)
			(xy 403.565035 -382.009401) (xy 403.614649 -381.986747) (xy 403.666982 -381.971386) (xy 403.720969 -381.963629)
			(xy 403.74824 -381.963168) (xy 404.61184 -381.963168) (xy 404.63911 -381.963597) (xy 404.693093 -381.971364)
			(xy 404.745422 -381.986734) (xy 404.795031 -382.009394) (xy 404.840911 -382.038884) (xy 404.882127 -382.074602)
			(xy 404.91784 -382.115822) (xy 404.947325 -382.161704) (xy 404.96998 -382.211316) (xy 404.985344 -382.263646)
			(xy 404.993106 -382.31763) (xy 404.993106 -382.37217) (xy 404.993106 -382.372171) (xy 410.174132 -382.372171)
			(xy 410.174132 -382.317629) (xy 410.181894 -382.263643) (xy 410.197261 -382.211311) (xy 410.21992 -382.161699)
			(xy 410.249409 -382.115817) (xy 410.285128 -382.0746) (xy 410.32635 -382.038885) (xy 410.372235 -382.009401)
			(xy 410.421849 -381.986747) (xy 410.474182 -381.971386) (xy 410.528169 -381.963629) (xy 410.55544 -381.963168)
			(xy 411.41904 -381.963168) (xy 411.44631 -381.963597) (xy 411.500293 -381.971364) (xy 411.552622 -381.986734)
			(xy 411.602231 -382.009394) (xy 411.648111 -382.038884) (xy 411.689327 -382.074602) (xy 411.72504 -382.115822)
			(xy 411.754525 -382.161704) (xy 411.77718 -382.211316) (xy 411.792544 -382.263646) (xy 411.800306 -382.31763)
			(xy 411.800306 -382.37217) (xy 411.800306 -382.372171) (xy 416.981332 -382.372171) (xy 416.981332 -382.317629)
			(xy 416.989094 -382.263643) (xy 417.004461 -382.211311) (xy 417.02712 -382.161699) (xy 417.056609 -382.115817)
			(xy 417.092328 -382.0746) (xy 417.13355 -382.038885) (xy 417.179435 -382.009401) (xy 417.229049 -381.986747)
			(xy 417.281382 -381.971386) (xy 417.335369 -381.963629) (xy 417.36264 -381.963168) (xy 418.22624 -381.963168)
			(xy 418.25351 -381.963597) (xy 418.307493 -381.971364) (xy 418.359822 -381.986734) (xy 418.409431 -382.009394)
			(xy 418.455311 -382.038884) (xy 418.496527 -382.074602) (xy 418.53224 -382.115822) (xy 418.561725 -382.161704)
			(xy 418.58438 -382.211316) (xy 418.599744 -382.263646) (xy 418.607506 -382.31763) (xy 418.607506 -382.37217)
			(xy 418.599744 -382.426154) (xy 418.58438 -382.478484) (xy 418.561725 -382.528096) (xy 418.53224 -382.573978)
			(xy 418.496527 -382.615198) (xy 418.455311 -382.650916) (xy 418.409431 -382.680406) (xy 418.359822 -382.703066)
			(xy 418.307493 -382.718436) (xy 418.25351 -382.726203) (xy 418.22624 -382.726692) (xy 417.36264 -382.726692)
			(xy 417.335369 -382.726171) (xy 417.281382 -382.718414) (xy 417.229049 -382.703053) (xy 417.179435 -382.680399)
			(xy 417.13355 -382.650915) (xy 417.092328 -382.6152) (xy 417.056609 -382.573983) (xy 417.02712 -382.528101)
			(xy 417.004461 -382.478489) (xy 416.989094 -382.426157) (xy 416.981332 -382.372171) (xy 411.800306 -382.372171)
			(xy 411.792544 -382.426154) (xy 411.77718 -382.478484) (xy 411.754525 -382.528096) (xy 411.72504 -382.573978)
			(xy 411.689327 -382.615198) (xy 411.648111 -382.650916) (xy 411.602231 -382.680406) (xy 411.552622 -382.703066)
			(xy 411.500293 -382.718436) (xy 411.44631 -382.726203) (xy 411.41904 -382.726692) (xy 410.55544 -382.726692)
			(xy 410.528169 -382.726171) (xy 410.474182 -382.718414) (xy 410.421849 -382.703053) (xy 410.372235 -382.680399)
			(xy 410.32635 -382.650915) (xy 410.285128 -382.6152) (xy 410.249409 -382.573983) (xy 410.21992 -382.528101)
			(xy 410.197261 -382.478489) (xy 410.181894 -382.426157) (xy 410.174132 -382.372171) (xy 404.993106 -382.372171)
			(xy 404.985344 -382.426154) (xy 404.96998 -382.478484) (xy 404.947325 -382.528096) (xy 404.91784 -382.573978)
			(xy 404.882127 -382.615198) (xy 404.840911 -382.650916) (xy 404.795031 -382.680406) (xy 404.745422 -382.703066)
			(xy 404.693093 -382.718436) (xy 404.63911 -382.726203) (xy 404.61184 -382.726692) (xy 403.74824 -382.726692)
			(xy 403.720969 -382.726171) (xy 403.666982 -382.718414) (xy 403.614649 -382.703053) (xy 403.565035 -382.680399)
			(xy 403.51915 -382.650915) (xy 403.477928 -382.6152) (xy 403.442209 -382.573983) (xy 403.41272 -382.528101)
			(xy 403.390061 -382.478489) (xy 403.374694 -382.426157) (xy 403.366932 -382.372171) (xy 386.079828 -382.372171)
			(xy 386.079828 -382.372174) (xy 386.072065 -382.426165) (xy 386.056698 -382.478503) (xy 386.034038 -382.52812)
			(xy 386.004547 -382.574008) (xy 385.968826 -382.615232) (xy 385.927602 -382.650952) (xy 385.881713 -382.680441)
			(xy 385.832095 -382.7031) (xy 385.779757 -382.718467) (xy 385.725766 -382.726229) (xy 385.698492 -382.726692)
			(xy 384.834892 -382.726692) (xy 384.807625 -382.726145) (xy 384.753647 -382.718383) (xy 384.701322 -382.703018)
			(xy 384.651717 -382.680363) (xy 384.605841 -382.65088) (xy 384.564627 -382.615167) (xy 384.528916 -382.573953)
			(xy 384.499433 -382.528076) (xy 384.476779 -382.47847) (xy 384.461415 -382.426146) (xy 384.453654 -382.372167)
			(xy 379.272628 -382.372167) (xy 379.272628 -382.372174) (xy 379.264865 -382.426165) (xy 379.249498 -382.478503)
			(xy 379.226838 -382.52812) (xy 379.197347 -382.574008) (xy 379.161626 -382.615232) (xy 379.120402 -382.650952)
			(xy 379.074513 -382.680441) (xy 379.024895 -382.7031) (xy 378.972557 -382.718467) (xy 378.918566 -382.726229)
			(xy 378.891292 -382.726692) (xy 378.027692 -382.726692) (xy 378.000425 -382.726145) (xy 377.946447 -382.718383)
			(xy 377.894122 -382.703018) (xy 377.844517 -382.680363) (xy 377.798641 -382.65088) (xy 377.757427 -382.615167)
			(xy 377.721716 -382.573953) (xy 377.692233 -382.528076) (xy 377.669579 -382.47847) (xy 377.654215 -382.426146)
			(xy 377.646454 -382.372167) (xy 372.465428 -382.372167) (xy 372.465428 -382.372174) (xy 372.457665 -382.426165)
			(xy 372.442298 -382.478503) (xy 372.419638 -382.52812) (xy 372.390147 -382.574008) (xy 372.354426 -382.615232)
			(xy 372.313202 -382.650952) (xy 372.267313 -382.680441) (xy 372.217695 -382.7031) (xy 372.165357 -382.718467)
			(xy 372.111366 -382.726229) (xy 372.084092 -382.726692) (xy 371.220492 -382.726692) (xy 371.193225 -382.726145)
			(xy 371.139247 -382.718383) (xy 371.086922 -382.703018) (xy 371.037317 -382.680363) (xy 370.991441 -382.65088)
			(xy 370.950227 -382.615167) (xy 370.914516 -382.573953) (xy 370.885033 -382.528076) (xy 370.862379 -382.47847)
			(xy 370.847015 -382.426146) (xy 370.839254 -382.372167) (xy 351.507306 -382.372167) (xy 351.507306 -382.37217)
			(xy 351.499544 -382.426153) (xy 351.48418 -382.478484) (xy 351.461525 -382.528095) (xy 351.432041 -382.573977)
			(xy 351.396328 -382.615197) (xy 351.355112 -382.650915) (xy 351.309233 -382.680404) (xy 351.259625 -382.703065)
			(xy 351.207297 -382.718435) (xy 351.153313 -382.726202) (xy 351.126044 -382.726692) (xy 350.262444 -382.726692)
			(xy 350.235173 -382.726172) (xy 350.181186 -382.718415) (xy 350.128852 -382.703054) (xy 350.079237 -382.680401)
			(xy 350.033351 -382.650916) (xy 349.992129 -382.615202) (xy 349.95641 -382.573984) (xy 349.926921 -382.528102)
			(xy 349.904261 -382.478489) (xy 349.888894 -382.426157) (xy 349.881132 -382.372171) (xy 344.700106 -382.372171)
			(xy 344.692344 -382.426153) (xy 344.67698 -382.478484) (xy 344.654325 -382.528095) (xy 344.624841 -382.573977)
			(xy 344.589128 -382.615197) (xy 344.547912 -382.650915) (xy 344.502033 -382.680404) (xy 344.452425 -382.703065)
			(xy 344.400097 -382.718435) (xy 344.346113 -382.726202) (xy 344.318844 -382.726692) (xy 343.455244 -382.726692)
			(xy 343.427973 -382.726172) (xy 343.373986 -382.718415) (xy 343.321652 -382.703054) (xy 343.272037 -382.680401)
			(xy 343.226151 -382.650916) (xy 343.184929 -382.615202) (xy 343.14921 -382.573984) (xy 343.119721 -382.528102)
			(xy 343.097061 -382.478489) (xy 343.081694 -382.426157) (xy 343.073932 -382.372171) (xy 337.892906 -382.372171)
			(xy 337.885144 -382.426153) (xy 337.86978 -382.478484) (xy 337.847125 -382.528095) (xy 337.817641 -382.573977)
			(xy 337.781928 -382.615197) (xy 337.740712 -382.650915) (xy 337.694833 -382.680404) (xy 337.645225 -382.703065)
			(xy 337.592897 -382.718435) (xy 337.538913 -382.726202) (xy 337.511644 -382.726692) (xy 336.648044 -382.726692)
			(xy 336.620773 -382.726172) (xy 336.566786 -382.718415) (xy 336.514452 -382.703054) (xy 336.464837 -382.680401)
			(xy 336.418951 -382.650916) (xy 336.377729 -382.615202) (xy 336.34201 -382.573984) (xy 336.312521 -382.528102)
			(xy 336.289861 -382.478489) (xy 336.274494 -382.426157) (xy 336.266732 -382.372171) (xy 318.979628 -382.372171)
			(xy 318.979628 -382.372173) (xy 318.971866 -382.426165) (xy 318.956498 -382.478502) (xy 318.933838 -382.528119)
			(xy 318.904348 -382.574007) (xy 318.868627 -382.61523) (xy 318.827403 -382.65095) (xy 318.781516 -382.68044)
			(xy 318.731898 -382.703099) (xy 318.679561 -382.718466) (xy 318.625569 -382.726229) (xy 318.598296 -382.726692)
			(xy 317.734696 -382.726692) (xy 317.707429 -382.726145) (xy 317.65345 -382.718384) (xy 317.601125 -382.703019)
			(xy 317.551519 -382.680365) (xy 317.505642 -382.650881) (xy 317.464429 -382.615169) (xy 317.428717 -382.573954)
			(xy 317.399233 -382.528077) (xy 317.376579 -382.478471) (xy 317.361215 -382.426146) (xy 317.353454 -382.372167)
			(xy 312.172428 -382.372167) (xy 312.172428 -382.372173) (xy 312.164666 -382.426165) (xy 312.149298 -382.478502)
			(xy 312.126638 -382.528119) (xy 312.097148 -382.574007) (xy 312.061427 -382.61523) (xy 312.020203 -382.65095)
			(xy 311.974316 -382.68044) (xy 311.924698 -382.703099) (xy 311.872361 -382.718466) (xy 311.818369 -382.726229)
			(xy 311.791096 -382.726692) (xy 310.927496 -382.726692) (xy 310.900229 -382.726145) (xy 310.84625 -382.718384)
			(xy 310.793925 -382.703019) (xy 310.744319 -382.680365) (xy 310.698442 -382.650881) (xy 310.657229 -382.615169)
			(xy 310.621517 -382.573954) (xy 310.592033 -382.528077) (xy 310.569379 -382.478471) (xy 310.554015 -382.426146)
			(xy 310.546254 -382.372167) (xy 305.365228 -382.372167) (xy 305.365228 -382.372173) (xy 305.357466 -382.426165)
			(xy 305.342098 -382.478502) (xy 305.319438 -382.528119) (xy 305.289948 -382.574007) (xy 305.254227 -382.61523)
			(xy 305.213003 -382.65095) (xy 305.167116 -382.68044) (xy 305.117498 -382.703099) (xy 305.065161 -382.718466)
			(xy 305.011169 -382.726229) (xy 304.983896 -382.726692) (xy 304.120296 -382.726692) (xy 304.093029 -382.726145)
			(xy 304.03905 -382.718384) (xy 303.986725 -382.703019) (xy 303.937119 -382.680365) (xy 303.891242 -382.650881)
			(xy 303.850029 -382.615169) (xy 303.814317 -382.573954) (xy 303.784833 -382.528077) (xy 303.762179 -382.478471)
			(xy 303.746815 -382.426146) (xy 303.739054 -382.372167) (xy 294.194727 -382.372167) (xy 294.264676 -382.460745)
			(xy 294.368827 -382.605448) (xy 294.466429 -382.754647) (xy 294.557287 -382.908046) (xy 294.641221 -383.06534)
			(xy 294.718066 -383.226216) (xy 294.787667 -383.390357) (xy 294.849888 -383.557434) (xy 294.904604 -383.727118)
			(xy 294.951706 -383.899071) (xy 294.991102 -384.072951) (xy 295.022713 -384.248414) (xy 295.046477 -384.42511)
			(xy 295.062345 -384.60269) (xy 295.070287 -384.7808) (xy 295.070784 -384.869944) (xy 295.070287 -384.959088)
			(xy 295.062345 -385.137198) (xy 295.055495 -385.21386) (xy 297.048936 -385.21386) (xy 297.048936 -384.35026)
			(xy 297.049422 -384.323009) (xy 297.057178 -384.269061) (xy 297.072533 -384.216766) (xy 297.095175 -384.167189)
			(xy 297.124641 -384.121339) (xy 297.160332 -384.080148) (xy 297.201523 -384.044457) (xy 297.247373 -384.014991)
			(xy 297.29695 -383.992349) (xy 297.349245 -383.976994) (xy 297.403193 -383.969238) (xy 297.457695 -383.969238)
			(xy 297.511643 -383.976994) (xy 297.563938 -383.992349) (xy 297.613515 -384.014991) (xy 297.659365 -384.044457)
			(xy 297.700556 -384.080148) (xy 297.736247 -384.121339) (xy 297.765713 -384.167189) (xy 297.788355 -384.216766)
			(xy 297.80371 -384.269061) (xy 297.811466 -384.323009) (xy 297.811952 -384.35026) (xy 297.811952 -385.21386)
			(xy 297.811466 -385.241111) (xy 297.80371 -385.295059) (xy 297.790858 -385.338828) (xy 326.895968 -385.338828)
			(xy 326.895968 -384.475228) (xy 326.896454 -384.447977) (xy 326.90421 -384.394029) (xy 326.919565 -384.341734)
			(xy 326.942207 -384.292157) (xy 326.971673 -384.246307) (xy 327.007364 -384.205116) (xy 327.048555 -384.169425)
			(xy 327.094405 -384.139959) (xy 327.143982 -384.117317) (xy 327.196277 -384.101962) (xy 327.250225 -384.094206)
			(xy 327.304727 -384.094206) (xy 327.358675 -384.101962) (xy 327.41097 -384.117317) (xy 327.460547 -384.139959)
			(xy 327.506397 -384.169425) (xy 327.547588 -384.205116) (xy 327.583279 -384.246307) (xy 327.612745 -384.292157)
			(xy 327.635387 -384.341734) (xy 327.650742 -384.394029) (xy 327.658498 -384.447977) (xy 327.658984 -384.475228)
			(xy 327.658984 -385.21386) (xy 329.576684 -385.21386) (xy 329.576684 -384.35026) (xy 329.57717 -384.323009)
			(xy 329.584926 -384.269061) (xy 329.600281 -384.216766) (xy 329.622923 -384.167189) (xy 329.652389 -384.121339)
			(xy 329.68808 -384.080148) (xy 329.729271 -384.044457) (xy 329.775121 -384.014991) (xy 329.824698 -383.992349)
			(xy 329.876993 -383.976994) (xy 329.930941 -383.969238) (xy 329.985443 -383.969238) (xy 330.039391 -383.976994)
			(xy 330.091686 -383.992349) (xy 330.141263 -384.014991) (xy 330.187113 -384.044457) (xy 330.228304 -384.080148)
			(xy 330.263995 -384.121339) (xy 330.293461 -384.167189) (xy 330.316103 -384.216766) (xy 330.331458 -384.269061)
			(xy 330.339214 -384.323009) (xy 330.3397 -384.35026) (xy 330.3397 -385.21386) (xy 330.339214 -385.241111)
			(xy 330.331458 -385.295059) (xy 330.318606 -385.338828) (xy 359.423716 -385.338828) (xy 359.423716 -384.475228)
			(xy 359.424202 -384.447977) (xy 359.431958 -384.394029) (xy 359.447313 -384.341734) (xy 359.469955 -384.292157)
			(xy 359.499421 -384.246307) (xy 359.535112 -384.205116) (xy 359.576303 -384.169425) (xy 359.622153 -384.139959)
			(xy 359.67173 -384.117317) (xy 359.724025 -384.101962) (xy 359.777973 -384.094206) (xy 359.832475 -384.094206)
			(xy 359.886423 -384.101962) (xy 359.938718 -384.117317) (xy 359.988295 -384.139959) (xy 360.034145 -384.169425)
			(xy 360.075336 -384.205116) (xy 360.111027 -384.246307) (xy 360.140493 -384.292157) (xy 360.163135 -384.341734)
			(xy 360.17849 -384.394029) (xy 360.186246 -384.447977) (xy 360.186732 -384.475228) (xy 360.186732 -385.21386)
			(xy 364.149132 -385.21386) (xy 364.149132 -384.35026) (xy 364.149618 -384.323009) (xy 364.157374 -384.269061)
			(xy 364.172729 -384.216766) (xy 364.195371 -384.167189) (xy 364.224837 -384.121339) (xy 364.260528 -384.080148)
			(xy 364.301719 -384.044457) (xy 364.347569 -384.014991) (xy 364.397146 -383.992349) (xy 364.449441 -383.976994)
			(xy 364.503389 -383.969238) (xy 364.557891 -383.969238) (xy 364.611839 -383.976994) (xy 364.664134 -383.992349)
			(xy 364.713711 -384.014991) (xy 364.759561 -384.044457) (xy 364.800752 -384.080148) (xy 364.836443 -384.121339)
			(xy 364.865909 -384.167189) (xy 364.888551 -384.216766) (xy 364.903906 -384.269061) (xy 364.911662 -384.323009)
			(xy 364.912148 -384.35026) (xy 364.912148 -385.21386) (xy 364.911662 -385.241111) (xy 364.903906 -385.295059)
			(xy 364.891054 -385.338828) (xy 393.996164 -385.338828) (xy 393.996164 -384.475228) (xy 393.99665 -384.447977)
			(xy 394.004406 -384.394029) (xy 394.019761 -384.341734) (xy 394.042403 -384.292157) (xy 394.071869 -384.246307)
			(xy 394.10756 -384.205116) (xy 394.148751 -384.169425) (xy 394.194601 -384.139959) (xy 394.244178 -384.117317)
			(xy 394.296473 -384.101962) (xy 394.350421 -384.094206) (xy 394.404923 -384.094206) (xy 394.458871 -384.101962)
			(xy 394.511166 -384.117317) (xy 394.560743 -384.139959) (xy 394.606593 -384.169425) (xy 394.647784 -384.205116)
			(xy 394.683475 -384.246307) (xy 394.712941 -384.292157) (xy 394.735583 -384.341734) (xy 394.750938 -384.394029)
			(xy 394.758694 -384.447977) (xy 394.75918 -384.475228) (xy 394.75918 -385.21386) (xy 396.67688 -385.21386)
			(xy 396.67688 -384.35026) (xy 396.677366 -384.323009) (xy 396.685122 -384.269061) (xy 396.700477 -384.216766)
			(xy 396.723119 -384.167189) (xy 396.752585 -384.121339) (xy 396.788276 -384.080148) (xy 396.829467 -384.044457)
			(xy 396.875317 -384.014991) (xy 396.924894 -383.992349) (xy 396.977189 -383.976994) (xy 397.031137 -383.969238)
			(xy 397.085639 -383.969238) (xy 397.139587 -383.976994) (xy 397.191882 -383.992349) (xy 397.241459 -384.014991)
			(xy 397.287309 -384.044457) (xy 397.3285 -384.080148) (xy 397.364191 -384.121339) (xy 397.393657 -384.167189)
			(xy 397.416299 -384.216766) (xy 397.431654 -384.269061) (xy 397.43941 -384.323009) (xy 397.439896 -384.35026)
			(xy 397.439896 -385.21386) (xy 397.43941 -385.241111) (xy 397.431654 -385.295059) (xy 397.418802 -385.338828)
			(xy 426.523912 -385.338828) (xy 426.523912 -384.475228) (xy 426.524398 -384.447977) (xy 426.532154 -384.394029)
			(xy 426.547509 -384.341734) (xy 426.570151 -384.292157) (xy 426.599617 -384.246307) (xy 426.635308 -384.205116)
			(xy 426.676499 -384.169425) (xy 426.722349 -384.139959) (xy 426.771926 -384.117317) (xy 426.824221 -384.101962)
			(xy 426.878169 -384.094206) (xy 426.932671 -384.094206) (xy 426.986619 -384.101962) (xy 427.038914 -384.117317)
			(xy 427.088491 -384.139959) (xy 427.134341 -384.169425) (xy 427.175532 -384.205116) (xy 427.211223 -384.246307)
			(xy 427.240689 -384.292157) (xy 427.263331 -384.341734) (xy 427.278686 -384.394029) (xy 427.286442 -384.447977)
			(xy 427.286928 -384.475228) (xy 427.286928 -384.869944) (xy 429.498772 -384.869944) (xy 429.502744 -384.691701)
			(xy 429.514652 -384.513812) (xy 429.534473 -384.33663) (xy 429.562167 -384.160506) (xy 429.597679 -383.985791)
			(xy 429.640939 -383.812832) (xy 429.691861 -383.641971) (xy 429.750344 -383.473549) (xy 429.816271 -383.307899)
			(xy 429.889512 -383.14535) (xy 429.969922 -382.986225) (xy 430.05734 -382.83084) (xy 430.151593 -382.679504)
			(xy 430.252494 -382.532516) (xy 430.359843 -382.390169) (xy 430.473426 -382.252746) (xy 430.593019 -382.120519)
			(xy 430.718383 -381.99375) (xy 430.84927 -381.872692) (xy 430.985419 -381.757585) (xy 431.126561 -381.648657)
			(xy 431.272416 -381.546125) (xy 431.422693 -381.450191) (xy 431.577094 -381.361048) (xy 431.735313 -381.278871)
			(xy 431.897036 -381.203823) (xy 432.061941 -381.136055) (xy 432.229702 -381.075699) (xy 432.399985 -381.022877)
			(xy 432.572452 -380.977693) (xy 432.74676 -380.940236) (xy 432.922564 -380.910582) (xy 433.099514 -380.888789)
			(xy 433.27726 -380.874899) (xy 433.455447 -380.868942) (xy 433.633724 -380.870928) (xy 433.811735 -380.880854)
			(xy 433.989127 -380.8987) (xy 434.165547 -380.92443) (xy 434.340647 -380.957994) (xy 434.514078 -380.999324)
			(xy 434.685495 -381.04834) (xy 434.854558 -381.104942) (xy 435.020933 -381.16902) (xy 435.184287 -381.240446)
			(xy 435.344298 -381.319078) (xy 435.500647 -381.404759) (xy 435.653024 -381.497321) (xy 435.801127 -381.596578)
			(xy 435.944661 -381.702335) (xy 436.083341 -381.81438) (xy 436.216892 -381.932492) (xy 436.345049 -382.056436)
			(xy 436.467558 -382.185966) (xy 436.584175 -382.320825) (xy 436.694668 -382.460745) (xy 436.798819 -382.605448)
			(xy 436.896421 -382.754647) (xy 436.987279 -382.908046) (xy 437.071213 -383.06534) (xy 437.148058 -383.226216)
			(xy 437.217659 -383.390357) (xy 437.27988 -383.557434) (xy 437.334596 -383.727118) (xy 437.381698 -383.899071)
			(xy 437.421094 -384.072951) (xy 437.452705 -384.248414) (xy 437.476469 -384.42511) (xy 437.492337 -384.60269)
			(xy 437.500279 -384.7808) (xy 437.500776 -384.869944) (xy 437.500279 -384.959088) (xy 437.492337 -385.137198)
			(xy 437.476469 -385.314778) (xy 437.452705 -385.491474) (xy 437.421094 -385.666937) (xy 437.381698 -385.840817)
			(xy 437.334596 -386.01277) (xy 437.27988 -386.182454) (xy 437.217659 -386.349531) (xy 437.148058 -386.513672)
			(xy 437.071213 -386.674548) (xy 436.987279 -386.831842) (xy 436.896421 -386.985241) (xy 436.798819 -387.13444)
			(xy 436.694668 -387.279143) (xy 436.584175 -387.419063) (xy 436.467558 -387.553922) (xy 436.345049 -387.683452)
			(xy 436.216892 -387.807396) (xy 436.083341 -387.925508) (xy 435.944661 -388.037553) (xy 435.801127 -388.14331)
			(xy 435.653024 -388.242567) (xy 435.500647 -388.335129) (xy 435.344298 -388.42081) (xy 435.184287 -388.499442)
			(xy 435.020933 -388.570868) (xy 434.854558 -388.634946) (xy 434.685495 -388.691548) (xy 434.514078 -388.740564)
			(xy 434.340647 -388.781894) (xy 434.165547 -388.815458) (xy 433.989127 -388.841188) (xy 433.811735 -388.859034)
			(xy 433.633724 -388.86896) (xy 433.455447 -388.870946) (xy 433.27726 -388.864989) (xy 433.099514 -388.851099)
			(xy 432.922564 -388.829306) (xy 432.74676 -388.799652) (xy 432.572452 -388.762195) (xy 432.399985 -388.717011)
			(xy 432.229702 -388.664189) (xy 432.061941 -388.603833) (xy 431.897036 -388.536065) (xy 431.735313 -388.461017)
			(xy 431.577094 -388.37884) (xy 431.422693 -388.289697) (xy 431.272416 -388.193763) (xy 431.126561 -388.091231)
			(xy 430.985419 -387.982303) (xy 430.84927 -387.867196) (xy 430.718383 -387.746138) (xy 430.593019 -387.619369)
			(xy 430.473426 -387.487142) (xy 430.359843 -387.349719) (xy 430.252494 -387.207372) (xy 430.151593 -387.060384)
			(xy 430.05734 -386.909048) (xy 429.969922 -386.753663) (xy 429.889512 -386.594538) (xy 429.816271 -386.431989)
			(xy 429.750344 -386.266339) (xy 429.691861 -386.097917) (xy 429.640939 -385.927056) (xy 429.597679 -385.754097)
			(xy 429.562167 -385.579382) (xy 429.534473 -385.403258) (xy 429.514652 -385.226076) (xy 429.502744 -385.048187)
			(xy 429.498772 -384.869944) (xy 427.286928 -384.869944) (xy 427.286928 -385.338828) (xy 427.286442 -385.366079)
			(xy 427.278686 -385.420027) (xy 427.263331 -385.472322) (xy 427.240689 -385.521899) (xy 427.211223 -385.567749)
			(xy 427.175532 -385.60894) (xy 427.134341 -385.644631) (xy 427.088491 -385.674097) (xy 427.038914 -385.696739)
			(xy 426.986619 -385.712094) (xy 426.932671 -385.71985) (xy 426.878169 -385.71985) (xy 426.824221 -385.712094)
			(xy 426.771926 -385.696739) (xy 426.722349 -385.674097) (xy 426.676499 -385.644631) (xy 426.635308 -385.60894)
			(xy 426.599617 -385.567749) (xy 426.570151 -385.521899) (xy 426.547509 -385.472322) (xy 426.532154 -385.420027)
			(xy 426.524398 -385.366079) (xy 426.523912 -385.338828) (xy 397.418802 -385.338828) (xy 397.416299 -385.347354)
			(xy 397.393657 -385.396931) (xy 397.364191 -385.442781) (xy 397.3285 -385.483972) (xy 397.287309 -385.519663)
			(xy 397.241459 -385.549129) (xy 397.191882 -385.571771) (xy 397.139587 -385.587126) (xy 397.085639 -385.594882)
			(xy 397.031137 -385.594882) (xy 396.977189 -385.587126) (xy 396.924894 -385.571771) (xy 396.875317 -385.549129)
			(xy 396.829467 -385.519663) (xy 396.788276 -385.483972) (xy 396.752585 -385.442781) (xy 396.723119 -385.396931)
			(xy 396.700477 -385.347354) (xy 396.685122 -385.295059) (xy 396.677366 -385.241111) (xy 396.67688 -385.21386)
			(xy 394.75918 -385.21386) (xy 394.75918 -385.338828) (xy 394.758694 -385.366079) (xy 394.750938 -385.420027)
			(xy 394.735583 -385.472322) (xy 394.712941 -385.521899) (xy 394.683475 -385.567749) (xy 394.647784 -385.60894)
			(xy 394.606593 -385.644631) (xy 394.560743 -385.674097) (xy 394.511166 -385.696739) (xy 394.458871 -385.712094)
			(xy 394.404923 -385.71985) (xy 394.350421 -385.71985) (xy 394.296473 -385.712094) (xy 394.244178 -385.696739)
			(xy 394.194601 -385.674097) (xy 394.148751 -385.644631) (xy 394.10756 -385.60894) (xy 394.071869 -385.567749)
			(xy 394.042403 -385.521899) (xy 394.019761 -385.472322) (xy 394.004406 -385.420027) (xy 393.99665 -385.366079)
			(xy 393.996164 -385.338828) (xy 364.891054 -385.338828) (xy 364.888551 -385.347354) (xy 364.865909 -385.396931)
			(xy 364.836443 -385.442781) (xy 364.800752 -385.483972) (xy 364.759561 -385.519663) (xy 364.713711 -385.549129)
			(xy 364.664134 -385.571771) (xy 364.611839 -385.587126) (xy 364.557891 -385.594882) (xy 364.503389 -385.594882)
			(xy 364.449441 -385.587126) (xy 364.397146 -385.571771) (xy 364.347569 -385.549129) (xy 364.301719 -385.519663)
			(xy 364.260528 -385.483972) (xy 364.224837 -385.442781) (xy 364.195371 -385.396931) (xy 364.172729 -385.347354)
			(xy 364.157374 -385.295059) (xy 364.149618 -385.241111) (xy 364.149132 -385.21386) (xy 360.186732 -385.21386)
			(xy 360.186732 -385.338828) (xy 360.186246 -385.366079) (xy 360.17849 -385.420027) (xy 360.163135 -385.472322)
			(xy 360.140493 -385.521899) (xy 360.111027 -385.567749) (xy 360.075336 -385.60894) (xy 360.034145 -385.644631)
			(xy 359.988295 -385.674097) (xy 359.938718 -385.696739) (xy 359.886423 -385.712094) (xy 359.832475 -385.71985)
			(xy 359.777973 -385.71985) (xy 359.724025 -385.712094) (xy 359.67173 -385.696739) (xy 359.622153 -385.674097)
			(xy 359.576303 -385.644631) (xy 359.535112 -385.60894) (xy 359.499421 -385.567749) (xy 359.469955 -385.521899)
			(xy 359.447313 -385.472322) (xy 359.431958 -385.420027) (xy 359.424202 -385.366079) (xy 359.423716 -385.338828)
			(xy 330.318606 -385.338828) (xy 330.316103 -385.347354) (xy 330.293461 -385.396931) (xy 330.263995 -385.442781)
			(xy 330.228304 -385.483972) (xy 330.187113 -385.519663) (xy 330.141263 -385.549129) (xy 330.091686 -385.571771)
			(xy 330.039391 -385.587126) (xy 329.985443 -385.594882) (xy 329.930941 -385.594882) (xy 329.876993 -385.587126)
			(xy 329.824698 -385.571771) (xy 329.775121 -385.549129) (xy 329.729271 -385.519663) (xy 329.68808 -385.483972)
			(xy 329.652389 -385.442781) (xy 329.622923 -385.396931) (xy 329.600281 -385.347354) (xy 329.584926 -385.295059)
			(xy 329.57717 -385.241111) (xy 329.576684 -385.21386) (xy 327.658984 -385.21386) (xy 327.658984 -385.338828)
			(xy 327.658498 -385.366079) (xy 327.650742 -385.420027) (xy 327.635387 -385.472322) (xy 327.612745 -385.521899)
			(xy 327.583279 -385.567749) (xy 327.547588 -385.60894) (xy 327.506397 -385.644631) (xy 327.460547 -385.674097)
			(xy 327.41097 -385.696739) (xy 327.358675 -385.712094) (xy 327.304727 -385.71985) (xy 327.250225 -385.71985)
			(xy 327.196277 -385.712094) (xy 327.143982 -385.696739) (xy 327.094405 -385.674097) (xy 327.048555 -385.644631)
			(xy 327.007364 -385.60894) (xy 326.971673 -385.567749) (xy 326.942207 -385.521899) (xy 326.919565 -385.472322)
			(xy 326.90421 -385.420027) (xy 326.896454 -385.366079) (xy 326.895968 -385.338828) (xy 297.790858 -385.338828)
			(xy 297.788355 -385.347354) (xy 297.765713 -385.396931) (xy 297.736247 -385.442781) (xy 297.700556 -385.483972)
			(xy 297.659365 -385.519663) (xy 297.613515 -385.549129) (xy 297.563938 -385.571771) (xy 297.511643 -385.587126)
			(xy 297.457695 -385.594882) (xy 297.403193 -385.594882) (xy 297.349245 -385.587126) (xy 297.29695 -385.571771)
			(xy 297.247373 -385.549129) (xy 297.201523 -385.519663) (xy 297.160332 -385.483972) (xy 297.124641 -385.442781)
			(xy 297.095175 -385.396931) (xy 297.072533 -385.347354) (xy 297.057178 -385.295059) (xy 297.049422 -385.241111)
			(xy 297.048936 -385.21386) (xy 295.055495 -385.21386) (xy 295.046477 -385.314778) (xy 295.022713 -385.491474)
			(xy 294.991102 -385.666937) (xy 294.951706 -385.840817) (xy 294.904604 -386.01277) (xy 294.849888 -386.182454)
			(xy 294.787667 -386.349531) (xy 294.718066 -386.513672) (xy 294.641221 -386.674548) (xy 294.557287 -386.831842)
			(xy 294.466429 -386.985241) (xy 294.368827 -387.13444) (xy 294.264676 -387.279143) (xy 294.154183 -387.419063)
			(xy 294.037566 -387.553922) (xy 293.915057 -387.683452) (xy 293.7869 -387.807396) (xy 293.653349 -387.925508)
			(xy 293.514669 -388.037553) (xy 293.371135 -388.14331) (xy 293.223032 -388.242567) (xy 293.070655 -388.335129)
			(xy 292.914306 -388.42081) (xy 292.754295 -388.499442) (xy 292.590941 -388.570868) (xy 292.424566 -388.634946)
			(xy 292.255503 -388.691548) (xy 292.084086 -388.740564) (xy 292.076264 -388.742428) (xy 326.895968 -388.742428)
			(xy 326.895968 -387.878828) (xy 326.896454 -387.851577) (xy 326.90421 -387.797629) (xy 326.919565 -387.745334)
			(xy 326.942207 -387.695757) (xy 326.971673 -387.649907) (xy 327.007364 -387.608716) (xy 327.048555 -387.573025)
			(xy 327.094405 -387.543559) (xy 327.143982 -387.520917) (xy 327.196277 -387.505562) (xy 327.250225 -387.497806)
			(xy 327.304727 -387.497806) (xy 327.358675 -387.505562) (xy 327.41097 -387.520917) (xy 327.460547 -387.543559)
			(xy 327.506397 -387.573025) (xy 327.547588 -387.608716) (xy 327.583279 -387.649907) (xy 327.612745 -387.695757)
			(xy 327.635387 -387.745334) (xy 327.650742 -387.797629) (xy 327.658498 -387.851577) (xy 327.658984 -387.878828)
			(xy 327.658984 -388.742428) (xy 359.423716 -388.742428) (xy 359.423716 -387.878828) (xy 359.424202 -387.851577)
			(xy 359.431958 -387.797629) (xy 359.447313 -387.745334) (xy 359.469955 -387.695757) (xy 359.499421 -387.649907)
			(xy 359.535112 -387.608716) (xy 359.576303 -387.573025) (xy 359.622153 -387.543559) (xy 359.67173 -387.520917)
			(xy 359.724025 -387.505562) (xy 359.777973 -387.497806) (xy 359.832475 -387.497806) (xy 359.886423 -387.505562)
			(xy 359.938718 -387.520917) (xy 359.988295 -387.543559) (xy 360.034145 -387.573025) (xy 360.075336 -387.608716)
			(xy 360.111027 -387.649907) (xy 360.140493 -387.695757) (xy 360.163135 -387.745334) (xy 360.17849 -387.797629)
			(xy 360.186246 -387.851577) (xy 360.186732 -387.878828) (xy 360.186732 -388.742428) (xy 393.996164 -388.742428)
			(xy 393.996164 -387.878828) (xy 393.99665 -387.851577) (xy 394.004406 -387.797629) (xy 394.019761 -387.745334)
			(xy 394.042403 -387.695757) (xy 394.071869 -387.649907) (xy 394.10756 -387.608716) (xy 394.148751 -387.573025)
			(xy 394.194601 -387.543559) (xy 394.244178 -387.520917) (xy 394.296473 -387.505562) (xy 394.350421 -387.497806)
			(xy 394.404923 -387.497806) (xy 394.458871 -387.505562) (xy 394.511166 -387.520917) (xy 394.560743 -387.543559)
			(xy 394.606593 -387.573025) (xy 394.647784 -387.608716) (xy 394.683475 -387.649907) (xy 394.712941 -387.695757)
			(xy 394.735583 -387.745334) (xy 394.750938 -387.797629) (xy 394.758694 -387.851577) (xy 394.75918 -387.878828)
			(xy 394.75918 -388.742428) (xy 426.523912 -388.742428) (xy 426.523912 -387.878828) (xy 426.524398 -387.851577)
			(xy 426.532154 -387.797629) (xy 426.547509 -387.745334) (xy 426.570151 -387.695757) (xy 426.599617 -387.649907)
			(xy 426.635308 -387.608716) (xy 426.676499 -387.573025) (xy 426.722349 -387.543559) (xy 426.771926 -387.520917)
			(xy 426.824221 -387.505562) (xy 426.878169 -387.497806) (xy 426.932671 -387.497806) (xy 426.986619 -387.505562)
			(xy 427.038914 -387.520917) (xy 427.088491 -387.543559) (xy 427.134341 -387.573025) (xy 427.175532 -387.608716)
			(xy 427.211223 -387.649907) (xy 427.240689 -387.695757) (xy 427.263331 -387.745334) (xy 427.278686 -387.797629)
			(xy 427.286442 -387.851577) (xy 427.286928 -387.878828) (xy 427.286928 -388.742428) (xy 427.286442 -388.769679)
			(xy 427.278686 -388.823627) (xy 427.263331 -388.875922) (xy 427.240689 -388.925499) (xy 427.211223 -388.971349)
			(xy 427.175532 -389.01254) (xy 427.134341 -389.048231) (xy 427.088491 -389.077697) (xy 427.038914 -389.100339)
			(xy 426.986619 -389.115694) (xy 426.932671 -389.12345) (xy 426.878169 -389.12345) (xy 426.824221 -389.115694)
			(xy 426.771926 -389.100339) (xy 426.722349 -389.077697) (xy 426.676499 -389.048231) (xy 426.635308 -389.01254)
			(xy 426.599617 -388.971349) (xy 426.570151 -388.925499) (xy 426.547509 -388.875922) (xy 426.532154 -388.823627)
			(xy 426.524398 -388.769679) (xy 426.523912 -388.742428) (xy 394.75918 -388.742428) (xy 394.758694 -388.769679)
			(xy 394.750938 -388.823627) (xy 394.735583 -388.875922) (xy 394.712941 -388.925499) (xy 394.683475 -388.971349)
			(xy 394.647784 -389.01254) (xy 394.606593 -389.048231) (xy 394.560743 -389.077697) (xy 394.511166 -389.100339)
			(xy 394.458871 -389.115694) (xy 394.404923 -389.12345) (xy 394.350421 -389.12345) (xy 394.296473 -389.115694)
			(xy 394.244178 -389.100339) (xy 394.194601 -389.077697) (xy 394.148751 -389.048231) (xy 394.10756 -389.01254)
			(xy 394.071869 -388.971349) (xy 394.042403 -388.925499) (xy 394.019761 -388.875922) (xy 394.004406 -388.823627)
			(xy 393.99665 -388.769679) (xy 393.996164 -388.742428) (xy 360.186732 -388.742428) (xy 360.186246 -388.769679)
			(xy 360.17849 -388.823627) (xy 360.163135 -388.875922) (xy 360.140493 -388.925499) (xy 360.111027 -388.971349)
			(xy 360.075336 -389.01254) (xy 360.034145 -389.048231) (xy 359.988295 -389.077697) (xy 359.938718 -389.100339)
			(xy 359.886423 -389.115694) (xy 359.832475 -389.12345) (xy 359.777973 -389.12345) (xy 359.724025 -389.115694)
			(xy 359.67173 -389.100339) (xy 359.622153 -389.077697) (xy 359.576303 -389.048231) (xy 359.535112 -389.01254)
			(xy 359.499421 -388.971349) (xy 359.469955 -388.925499) (xy 359.447313 -388.875922) (xy 359.431958 -388.823627)
			(xy 359.424202 -388.769679) (xy 359.423716 -388.742428) (xy 327.658984 -388.742428) (xy 327.658498 -388.769679)
			(xy 327.650742 -388.823627) (xy 327.635387 -388.875922) (xy 327.612745 -388.925499) (xy 327.583279 -388.971349)
			(xy 327.547588 -389.01254) (xy 327.506397 -389.048231) (xy 327.460547 -389.077697) (xy 327.41097 -389.100339)
			(xy 327.358675 -389.115694) (xy 327.304727 -389.12345) (xy 327.250225 -389.12345) (xy 327.196277 -389.115694)
			(xy 327.143982 -389.100339) (xy 327.094405 -389.077697) (xy 327.048555 -389.048231) (xy 327.007364 -389.01254)
			(xy 326.971673 -388.971349) (xy 326.942207 -388.925499) (xy 326.919565 -388.875922) (xy 326.90421 -388.823627)
			(xy 326.896454 -388.769679) (xy 326.895968 -388.742428) (xy 292.076264 -388.742428) (xy 291.910655 -388.781894)
			(xy 291.735555 -388.815458) (xy 291.559135 -388.841188) (xy 291.381743 -388.859034) (xy 291.203732 -388.86896)
			(xy 291.025455 -388.870946) (xy 290.847268 -388.864989) (xy 290.669522 -388.851099) (xy 290.492572 -388.829306)
			(xy 290.316768 -388.799652) (xy 290.14246 -388.762195) (xy 289.969993 -388.717011) (xy 289.79971 -388.664189)
			(xy 289.631949 -388.603833) (xy 289.467044 -388.536065) (xy 289.305321 -388.461017) (xy 289.147102 -388.37884)
			(xy 288.992701 -388.289697) (xy 288.842424 -388.193763) (xy 288.696569 -388.091231) (xy 288.555427 -387.982303)
			(xy 288.419278 -387.867196) (xy 288.288391 -387.746138) (xy 288.163027 -387.619369) (xy 288.043434 -387.487142)
			(xy 287.929851 -387.349719) (xy 287.822502 -387.207372) (xy 287.721601 -387.060384) (xy 287.627348 -386.909048)
			(xy 287.53993 -386.753663) (xy 287.45952 -386.594538) (xy 287.386279 -386.431989) (xy 287.320352 -386.266339)
			(xy 287.261869 -386.097917) (xy 287.210947 -385.927056) (xy 287.167687 -385.754097) (xy 287.132175 -385.579382)
			(xy 287.104481 -385.403258) (xy 287.08466 -385.226076) (xy 287.072752 -385.048187) (xy 287.06878 -384.869944)
			(xy 281.2288 -384.869944) (xy 281.2288 -387.36016) (xy 281.229256 -387.369896) (xy 281.236578 -387.387944)
			(xy 281.250076 -387.401984) (xy 281.258772 -387.406388) (xy 281.283524 -387.41805) (xy 281.329666 -387.447457)
			(xy 281.371135 -387.483154) (xy 281.407078 -387.524408) (xy 281.43676 -387.570374) (xy 281.45957 -387.620109)
			(xy 281.475042 -387.672592) (xy 281.482858 -387.726748) (xy 281.482857 -387.781464) (xy 281.47504 -387.835619)
			(xy 281.459566 -387.888102) (xy 281.436754 -387.937836) (xy 281.407071 -387.983801) (xy 281.371126 -388.025055)
			(xy 281.329657 -388.06075) (xy 281.283514 -388.090155) (xy 281.258772 -388.10184) (xy 281.250056 -388.106224)
			(xy 281.23652 -388.120246) (xy 281.229232 -388.138322) (xy 281.2288 -388.148068) (xy 281.2288 -390.75106)
			(xy 297.048936 -390.75106) (xy 297.048936 -389.88746) (xy 297.049422 -389.860209) (xy 297.057178 -389.806261)
			(xy 297.072533 -389.753966) (xy 297.095175 -389.704389) (xy 297.124641 -389.658539) (xy 297.160332 -389.617348)
			(xy 297.201523 -389.581657) (xy 297.247373 -389.552191) (xy 297.29695 -389.529549) (xy 297.349245 -389.514194)
			(xy 297.403193 -389.506438) (xy 297.457695 -389.506438) (xy 297.511643 -389.514194) (xy 297.563938 -389.529549)
			(xy 297.613515 -389.552191) (xy 297.659365 -389.581657) (xy 297.700556 -389.617348) (xy 297.736247 -389.658539)
			(xy 297.765713 -389.704389) (xy 297.788355 -389.753966) (xy 297.80371 -389.806261) (xy 297.811466 -389.860209)
			(xy 297.811952 -389.88746) (xy 297.811952 -390.75106) (xy 329.576684 -390.75106) (xy 329.576684 -389.88746)
			(xy 329.57717 -389.860209) (xy 329.584926 -389.806261) (xy 329.600281 -389.753966) (xy 329.622923 -389.704389)
			(xy 329.652389 -389.658539) (xy 329.68808 -389.617348) (xy 329.729271 -389.581657) (xy 329.775121 -389.552191)
			(xy 329.824698 -389.529549) (xy 329.876993 -389.514194) (xy 329.930941 -389.506438) (xy 329.985443 -389.506438)
			(xy 330.039391 -389.514194) (xy 330.091686 -389.529549) (xy 330.141263 -389.552191) (xy 330.187113 -389.581657)
			(xy 330.228304 -389.617348) (xy 330.263995 -389.658539) (xy 330.293461 -389.704389) (xy 330.316103 -389.753966)
			(xy 330.331458 -389.806261) (xy 330.339214 -389.860209) (xy 330.3397 -389.88746) (xy 330.3397 -390.75106)
			(xy 364.149132 -390.75106) (xy 364.149132 -389.88746) (xy 364.149618 -389.860209) (xy 364.157374 -389.806261)
			(xy 364.172729 -389.753966) (xy 364.195371 -389.704389) (xy 364.224837 -389.658539) (xy 364.260528 -389.617348)
			(xy 364.301719 -389.581657) (xy 364.347569 -389.552191) (xy 364.397146 -389.529549) (xy 364.449441 -389.514194)
			(xy 364.503389 -389.506438) (xy 364.557891 -389.506438) (xy 364.611839 -389.514194) (xy 364.664134 -389.529549)
			(xy 364.713711 -389.552191) (xy 364.759561 -389.581657) (xy 364.800752 -389.617348) (xy 364.836443 -389.658539)
			(xy 364.865909 -389.704389) (xy 364.888551 -389.753966) (xy 364.903906 -389.806261) (xy 364.911662 -389.860209)
			(xy 364.912148 -389.88746) (xy 364.912148 -390.75106) (xy 396.67688 -390.75106) (xy 396.67688 -389.88746)
			(xy 396.677366 -389.860209) (xy 396.685122 -389.806261) (xy 396.700477 -389.753966) (xy 396.723119 -389.704389)
			(xy 396.752585 -389.658539) (xy 396.788276 -389.617348) (xy 396.829467 -389.581657) (xy 396.875317 -389.552191)
			(xy 396.924894 -389.529549) (xy 396.977189 -389.514194) (xy 397.031137 -389.506438) (xy 397.085639 -389.506438)
			(xy 397.139587 -389.514194) (xy 397.191882 -389.529549) (xy 397.241459 -389.552191) (xy 397.287309 -389.581657)
			(xy 397.3285 -389.617348) (xy 397.364191 -389.658539) (xy 397.393657 -389.704389) (xy 397.416299 -389.753966)
			(xy 397.431654 -389.806261) (xy 397.43941 -389.860209) (xy 397.439896 -389.88746) (xy 397.439896 -390.75106)
			(xy 397.43941 -390.778311) (xy 397.431654 -390.832259) (xy 397.416299 -390.884554) (xy 397.393657 -390.934131)
			(xy 397.364191 -390.979981) (xy 397.3285 -391.021172) (xy 397.287309 -391.056863) (xy 397.241459 -391.086329)
			(xy 397.191882 -391.108971) (xy 397.139587 -391.124326) (xy 397.085639 -391.132082) (xy 397.031137 -391.132082)
			(xy 396.977189 -391.124326) (xy 396.924894 -391.108971) (xy 396.875317 -391.086329) (xy 396.829467 -391.056863)
			(xy 396.788276 -391.021172) (xy 396.752585 -390.979981) (xy 396.723119 -390.934131) (xy 396.700477 -390.884554)
			(xy 396.685122 -390.832259) (xy 396.677366 -390.778311) (xy 396.67688 -390.75106) (xy 364.912148 -390.75106)
			(xy 364.911662 -390.778311) (xy 364.903906 -390.832259) (xy 364.888551 -390.884554) (xy 364.865909 -390.934131)
			(xy 364.836443 -390.979981) (xy 364.800752 -391.021172) (xy 364.759561 -391.056863) (xy 364.713711 -391.086329)
			(xy 364.664134 -391.108971) (xy 364.611839 -391.124326) (xy 364.557891 -391.132082) (xy 364.503389 -391.132082)
			(xy 364.449441 -391.124326) (xy 364.397146 -391.108971) (xy 364.347569 -391.086329) (xy 364.301719 -391.056863)
			(xy 364.260528 -391.021172) (xy 364.224837 -390.979981) (xy 364.195371 -390.934131) (xy 364.172729 -390.884554)
			(xy 364.157374 -390.832259) (xy 364.149618 -390.778311) (xy 364.149132 -390.75106) (xy 330.3397 -390.75106)
			(xy 330.339214 -390.778311) (xy 330.331458 -390.832259) (xy 330.316103 -390.884554) (xy 330.293461 -390.934131)
			(xy 330.263995 -390.979981) (xy 330.228304 -391.021172) (xy 330.187113 -391.056863) (xy 330.141263 -391.086329)
			(xy 330.091686 -391.108971) (xy 330.039391 -391.124326) (xy 329.985443 -391.132082) (xy 329.930941 -391.132082)
			(xy 329.876993 -391.124326) (xy 329.824698 -391.108971) (xy 329.775121 -391.086329) (xy 329.729271 -391.056863)
			(xy 329.68808 -391.021172) (xy 329.652389 -390.979981) (xy 329.622923 -390.934131) (xy 329.600281 -390.884554)
			(xy 329.584926 -390.832259) (xy 329.57717 -390.778311) (xy 329.576684 -390.75106) (xy 297.811952 -390.75106)
			(xy 297.811466 -390.778311) (xy 297.80371 -390.832259) (xy 297.788355 -390.884554) (xy 297.765713 -390.934131)
			(xy 297.736247 -390.979981) (xy 297.700556 -391.021172) (xy 297.659365 -391.056863) (xy 297.613515 -391.086329)
			(xy 297.563938 -391.108971) (xy 297.511643 -391.124326) (xy 297.457695 -391.132082) (xy 297.403193 -391.132082)
			(xy 297.349245 -391.124326) (xy 297.29695 -391.108971) (xy 297.247373 -391.086329) (xy 297.201523 -391.056863)
			(xy 297.160332 -391.021172) (xy 297.124641 -390.979981) (xy 297.095175 -390.934131) (xy 297.072533 -390.884554)
			(xy 297.057178 -390.832259) (xy 297.049422 -390.778311) (xy 297.048936 -390.75106) (xy 281.2288 -390.75106)
			(xy 281.2288 -392.180572) (xy 281.228283 -392.20552) (xy 281.220475 -392.254803) (xy 281.205064 -392.30226)
			(xy 281.182426 -392.346726) (xy 281.153119 -392.387109) (xy 281.135836 -392.405108) (xy 280.810462 -392.730482)
			(xy 280.803632 -392.73789) (xy 280.795908 -392.756483) (xy 280.795476 -392.76655) (xy 280.795476 -393.110974)
			(xy 280.794938 -393.135921) (xy 280.787132 -393.185202) (xy 280.771724 -393.232658) (xy 280.749092 -393.277124)
			(xy 280.719792 -393.31751) (xy 280.702512 -393.33551) (xy 280.345134 -393.692888) (xy 303.485804 -393.692888)
			(xy 303.485804 -393.69238) (xy 303.486244 -393.668388) (xy 303.493754 -393.620994) (xy 303.508585 -393.575359)
			(xy 303.530372 -393.532605) (xy 303.558579 -393.493786) (xy 303.592511 -393.459858) (xy 303.631333 -393.431655)
			(xy 303.674088 -393.409872) (xy 303.719725 -393.395046) (xy 303.76712 -393.387542) (xy 303.791112 -393.387072)
			(xy 303.815046 -393.38757) (xy 303.862329 -393.395022) (xy 303.907871 -393.409757) (xy 303.950558 -393.431416)
			(xy 303.989344 -393.459467) (xy 304.02328 -393.493224) (xy 304.051536 -393.531861) (xy 304.062892 -393.552934)
			(xy 304.0634 -393.55395) (xy 304.143706 -393.692888) (xy 304.6857 -393.692888) (xy 304.6857 -393.69238)
			(xy 304.686144 -393.668388) (xy 304.693654 -393.620995) (xy 304.708484 -393.57536) (xy 304.730271 -393.532606)
			(xy 304.758477 -393.493788) (xy 304.792409 -393.459859) (xy 304.83123 -393.431656) (xy 304.873986 -393.409873)
			(xy 304.919622 -393.395047) (xy 304.967016 -393.387542) (xy 304.991008 -393.387072) (xy 305.014941 -393.387573)
			(xy 305.062224 -393.395024) (xy 305.107767 -393.409759) (xy 305.150453 -393.431417) (xy 305.189239 -393.459468)
			(xy 305.223176 -393.493224) (xy 305.251432 -393.531861) (xy 305.262788 -393.552934) (xy 305.263296 -393.55395)
			(xy 305.343602 -393.692888) (xy 305.885596 -393.692888) (xy 305.885596 -393.69238) (xy 305.886044 -393.668388)
			(xy 305.893553 -393.620995) (xy 305.908384 -393.575361) (xy 305.93017 -393.532608) (xy 305.958376 -393.493789)
			(xy 305.992307 -393.459861) (xy 306.031128 -393.431658) (xy 306.073883 -393.409875) (xy 306.119519 -393.395048)
			(xy 306.166912 -393.387542) (xy 306.190904 -393.387072) (xy 306.191158 -393.387072) (xy 306.215093 -393.387532)
			(xy 306.262378 -393.394992) (xy 306.307921 -393.409734) (xy 306.350607 -393.431398) (xy 306.389393 -393.459455)
			(xy 306.423328 -393.493217) (xy 306.451583 -393.531859) (xy 306.462938 -393.552934) (xy 306.463446 -393.55395)
			(xy 306.543752 -393.692888) (xy 307.085492 -393.692888) (xy 307.085492 -393.69238) (xy 307.085943 -393.668401)
			(xy 307.093444 -393.621033) (xy 307.108259 -393.57542) (xy 307.130023 -393.532685) (xy 307.158201 -393.493877)
			(xy 307.192099 -393.459953) (xy 307.230885 -393.431745) (xy 307.273604 -393.409949) (xy 307.319205 -393.395099)
			(xy 307.366567 -393.387562) (xy 307.390546 -393.387072) (xy 307.391054 -393.387072) (xy 307.414989 -393.387536)
			(xy 307.462274 -393.394994) (xy 307.507817 -393.409736) (xy 307.550503 -393.4314) (xy 307.589289 -393.459456)
			(xy 307.623224 -393.493218) (xy 307.651479 -393.531859) (xy 307.662834 -393.552934) (xy 307.663342 -393.55395)
			(xy 307.743648 -393.692888) (xy 308.285388 -393.692888) (xy 308.285388 -393.69238) (xy 308.285843 -393.668401)
			(xy 308.293344 -393.621034) (xy 308.308159 -393.575421) (xy 308.329922 -393.532686) (xy 308.358099 -393.493879)
			(xy 308.391998 -393.459954) (xy 308.430783 -393.431747) (xy 308.473501 -393.40995) (xy 308.519102 -393.3951)
			(xy 308.566463 -393.387562) (xy 308.590442 -393.387072) (xy 308.59095 -393.387072) (xy 308.614885 -393.387539)
			(xy 308.662169 -393.394997) (xy 308.707712 -393.409738) (xy 308.750399 -393.431401) (xy 308.789184 -393.459457)
			(xy 308.82312 -393.493218) (xy 308.851375 -393.531859) (xy 308.86273 -393.552934) (xy 308.863238 -393.55395)
			(xy 308.943544 -393.692888) (xy 309.485792 -393.692888) (xy 309.485792 -393.69238) (xy 309.486244 -393.668388)
			(xy 309.493753 -393.620996) (xy 309.508583 -393.575362) (xy 309.530369 -393.532609) (xy 309.558575 -393.49379)
			(xy 309.592506 -393.459862) (xy 309.631326 -393.431659) (xy 309.67408 -393.409876) (xy 309.719715 -393.395049)
			(xy 309.767108 -393.387543) (xy 309.7911 -393.387072) (xy 309.815033 -393.38758) (xy 309.862316 -393.39503)
			(xy 309.907858 -393.409764) (xy 309.950544 -393.43142) (xy 309.989331 -393.45947) (xy 310.023268 -393.493226)
			(xy 310.051524 -393.531862) (xy 310.06288 -393.552934) (xy 310.063388 -393.55395) (xy 310.143694 -393.692888)
			(xy 310.685688 -393.692888) (xy 310.685688 -393.69238) (xy 310.686144 -393.668388) (xy 310.693653 -393.620996)
			(xy 310.708483 -393.575362) (xy 310.730269 -393.53261) (xy 310.758474 -393.493792) (xy 310.792404 -393.459863)
			(xy 310.831224 -393.43166) (xy 310.873977 -393.409877) (xy 310.919612 -393.395049) (xy 310.967004 -393.387543)
			(xy 310.990996 -393.387072) (xy 311.014932 -393.387502) (xy 311.062218 -393.394966) (xy 311.107762 -393.409714)
			(xy 311.150449 -393.431384) (xy 311.189234 -393.459445) (xy 311.223168 -393.493212) (xy 311.251422 -393.531857)
			(xy 311.262776 -393.552934) (xy 311.263284 -393.55395) (xy 311.34359 -393.692888) (xy 311.885584 -393.692888)
			(xy 311.885584 -393.69238) (xy 311.886044 -393.668389) (xy 311.893553 -393.620997) (xy 311.908383 -393.575363)
			(xy 311.930168 -393.532611) (xy 311.958373 -393.493793) (xy 311.992302 -393.459865) (xy 312.031121 -393.431662)
			(xy 312.073874 -393.409878) (xy 312.119509 -393.39505) (xy 312.166901 -393.387543) (xy 312.190892 -393.387072)
			(xy 312.191146 -393.387072) (xy 312.215081 -393.387542) (xy 312.262365 -393.394999) (xy 312.307908 -393.40974)
			(xy 312.350594 -393.431403) (xy 312.38938 -393.459458) (xy 312.423316 -393.493219) (xy 312.451571 -393.531859)
			(xy 312.462926 -393.552934) (xy 312.463434 -393.55395) (xy 312.54374 -393.692888) (xy 313.08548 -393.692888)
			(xy 313.08548 -393.69238) (xy 313.085921 -393.668374) (xy 313.093438 -393.620955) (xy 313.108284 -393.575296)
			(xy 313.130093 -393.532524) (xy 313.158327 -393.493692) (xy 313.192291 -393.459757) (xy 313.231147 -393.431556)
			(xy 313.273939 -393.409783) (xy 313.31961 -393.394977) (xy 313.367036 -393.3875) (xy 313.391042 -393.387072)
			(xy 313.391296 -393.387072) (xy 313.415232 -393.387502) (xy 313.462518 -393.394966) (xy 313.508062 -393.409714)
			(xy 313.550749 -393.431384) (xy 313.589534 -393.459445) (xy 313.623468 -393.493212) (xy 313.651722 -393.531857)
			(xy 313.663076 -393.552934) (xy 313.663584 -393.55395) (xy 313.74389 -393.692888) (xy 314.285376 -393.692888)
			(xy 314.285376 -393.69238) (xy 314.285821 -393.668374) (xy 314.293338 -393.620955) (xy 314.308183 -393.575297)
			(xy 314.329992 -393.532525) (xy 314.358226 -393.493693) (xy 314.392189 -393.459758) (xy 314.431045 -393.431557)
			(xy 314.473836 -393.409785) (xy 314.519507 -393.394977) (xy 314.566932 -393.3875) (xy 314.590938 -393.387072)
			(xy 314.591192 -393.387072) (xy 314.615128 -393.387505) (xy 314.662414 -393.394969) (xy 314.707958 -393.409716)
			(xy 314.750644 -393.431385) (xy 314.78943 -393.459446) (xy 314.823364 -393.493212) (xy 314.851618 -393.531857)
			(xy 314.862972 -393.552934) (xy 314.86348 -393.55395) (xy 314.943786 -393.692888) (xy 315.48578 -393.692888)
			(xy 315.48578 -393.69238) (xy 315.486244 -393.668389) (xy 315.493753 -393.620998) (xy 315.508582 -393.575364)
			(xy 315.530367 -393.532612) (xy 315.558571 -393.493795) (xy 315.592501 -393.459866) (xy 315.631319 -393.431663)
			(xy 315.674072 -393.409879) (xy 315.719705 -393.395051) (xy 315.767097 -393.387543) (xy 315.791088 -393.387072)
			(xy 315.815024 -393.387508) (xy 315.86231 -393.394972) (xy 315.907853 -393.409718) (xy 315.95054 -393.431387)
			(xy 315.989325 -393.459447) (xy 316.02326 -393.493213) (xy 316.051514 -393.531858) (xy 316.062868 -393.552934)
			(xy 316.063376 -393.55395) (xy 316.143682 -393.692888) (xy 316.685676 -393.692888) (xy 316.685676 -393.69238)
			(xy 316.686144 -393.668389) (xy 316.693653 -393.620998) (xy 316.708482 -393.575365) (xy 316.730267 -393.532614)
			(xy 316.75847 -393.493796) (xy 316.792399 -393.459868) (xy 316.831217 -393.431664) (xy 316.873969 -393.40988)
			(xy 316.919602 -393.395052) (xy 316.966993 -393.387544) (xy 316.990984 -393.387072) (xy 316.991238 -393.387072)
			(xy 317.015172 -393.387549) (xy 317.062456 -393.395005) (xy 317.107999 -393.409744) (xy 317.150686 -393.431406)
			(xy 317.189472 -393.45946) (xy 317.223407 -393.49322) (xy 317.251663 -393.53186) (xy 317.263018 -393.552934)
			(xy 317.263526 -393.55395) (xy 317.343832 -393.692888) (xy 317.885572 -393.692888) (xy 317.885572 -393.69238)
			(xy 317.886043 -393.668402) (xy 317.893544 -393.621036) (xy 317.908357 -393.575425) (xy 317.930119 -393.532691)
			(xy 317.958295 -393.493884) (xy 317.992191 -393.45996) (xy 318.030974 -393.431752) (xy 318.07369 -393.409954)
			(xy 318.119289 -393.395103) (xy 318.166648 -393.387563) (xy 318.190626 -393.387072) (xy 318.191134 -393.387072)
			(xy 318.215068 -393.387552) (xy 318.262352 -393.395007) (xy 318.307895 -393.409746) (xy 318.350581 -393.431407)
			(xy 318.389367 -393.459461) (xy 318.423303 -393.493221) (xy 318.451559 -393.53186) (xy 318.462914 -393.552934)
			(xy 318.463422 -393.55395) (xy 318.543728 -393.692888) (xy 319.085468 -393.692888) (xy 319.085468 -393.69238)
			(xy 319.085921 -393.668375) (xy 319.093437 -393.620957) (xy 319.108283 -393.575299) (xy 319.130091 -393.532527)
			(xy 319.158324 -393.493696) (xy 319.192286 -393.459761) (xy 319.231141 -393.43156) (xy 319.27393 -393.409787)
			(xy 319.3196 -393.394979) (xy 319.367024 -393.387501) (xy 319.39103 -393.387072) (xy 319.391284 -393.387072)
			(xy 319.41522 -393.387511) (xy 319.462506 -393.394974) (xy 319.508049 -393.40972) (xy 319.550736 -393.431388)
			(xy 319.589521 -393.459448) (xy 319.623456 -393.493214) (xy 319.65171 -393.531858) (xy 319.663064 -393.552934)
			(xy 319.663572 -393.55395) (xy 319.743878 -393.692888) (xy 320.285872 -393.692888) (xy 320.285872 -393.69238)
			(xy 320.286344 -393.668389) (xy 320.293853 -393.620999) (xy 320.308681 -393.575366) (xy 320.330466 -393.532615)
			(xy 320.358669 -393.493797) (xy 320.392597 -393.459869) (xy 320.431415 -393.431666) (xy 320.474166 -393.409881)
			(xy 320.519799 -393.395053) (xy 320.567189 -393.387544) (xy 320.59118 -393.387072) (xy 320.615116 -393.387515)
			(xy 320.662401 -393.394977) (xy 320.707945 -393.409722) (xy 320.750631 -393.43139) (xy 320.789417 -393.459449)
			(xy 320.823352 -393.493214) (xy 320.851606 -393.531858) (xy 320.86296 -393.552934) (xy 320.863468 -393.55395)
			(xy 320.943774 -393.692888) (xy 321.485768 -393.692888) (xy 321.485768 -393.69238) (xy 321.486244 -393.668389)
			(xy 321.493752 -393.620999) (xy 321.508581 -393.575367) (xy 321.530365 -393.532616) (xy 321.558568 -393.493799)
			(xy 321.592496 -393.459871) (xy 321.631313 -393.431667) (xy 321.674063 -393.409883) (xy 321.719695 -393.395053)
			(xy 321.767085 -393.387544) (xy 321.791076 -393.387072) (xy 321.815011 -393.387518) (xy 321.862297 -393.39498)
			(xy 321.90784 -393.409724) (xy 321.950527 -393.431391) (xy 321.989312 -393.45945) (xy 322.023247 -393.493215)
			(xy 322.051501 -393.531858) (xy 322.062856 -393.552934) (xy 322.063364 -393.55395) (xy 322.14367 -393.692888)
			(xy 336.013552 -393.692888) (xy 336.013552 -393.69238) (xy 336.014044 -393.66839) (xy 336.021552 -393.621002)
			(xy 336.03638 -393.575371) (xy 336.058162 -393.532621) (xy 336.086363 -393.493804) (xy 336.120289 -393.459876)
			(xy 336.159104 -393.431673) (xy 336.201852 -393.409887) (xy 336.247482 -393.395057) (xy 336.29487 -393.387546)
			(xy 336.31886 -393.387072) (xy 336.342795 -393.387531) (xy 336.39008 -393.39499) (xy 336.435623 -393.409733)
			(xy 336.47831 -393.431398) (xy 336.517095 -393.459455) (xy 336.551031 -393.493217) (xy 336.579285 -393.531859)
			(xy 336.59064 -393.552934) (xy 336.591148 -393.55395) (xy 336.671454 -393.692888) (xy 337.213448 -393.692888)
			(xy 337.213448 -393.69238) (xy 337.213944 -393.66839) (xy 337.221452 -393.621002) (xy 337.236279 -393.575372)
			(xy 337.258061 -393.532622) (xy 337.286262 -393.493805) (xy 337.320187 -393.459878) (xy 337.359001 -393.431674)
			(xy 337.401749 -393.409888) (xy 337.447379 -393.395057) (xy 337.494766 -393.387546) (xy 337.518756 -393.387072)
			(xy 337.542691 -393.387534) (xy 337.589976 -393.394993) (xy 337.635519 -393.409735) (xy 337.678205 -393.431399)
			(xy 337.716991 -393.459456) (xy 337.750926 -393.493218) (xy 337.779181 -393.531859) (xy 337.790536 -393.552934)
			(xy 337.791044 -393.55395) (xy 337.87135 -393.692888) (xy 338.413344 -393.692888) (xy 338.413344 -393.69238)
			(xy 338.413843 -393.668403) (xy 338.421343 -393.62104) (xy 338.436154 -393.575431) (xy 338.457914 -393.532699)
			(xy 338.486087 -393.493894) (xy 338.519979 -393.45997) (xy 338.558758 -393.431762) (xy 338.60147 -393.409962)
			(xy 338.647065 -393.395109) (xy 338.694422 -393.387565) (xy 338.718398 -393.387072) (xy 338.718906 -393.387072)
			(xy 338.742839 -393.387575) (xy 338.790122 -393.395026) (xy 338.835664 -393.40976) (xy 338.878351 -393.431418)
			(xy 338.917137 -393.459468) (xy 338.951074 -393.493225) (xy 338.97933 -393.531861) (xy 338.990686 -393.552934)
			(xy 338.991194 -393.55395) (xy 339.0715 -393.692888) (xy 339.61324 -393.692888) (xy 339.61324 -393.69238)
			(xy 339.613643 -393.668399) (xy 339.621146 -393.621026) (xy 339.635964 -393.575409) (xy 339.657732 -393.53267)
			(xy 339.685915 -393.493861) (xy 339.719819 -393.459936) (xy 339.758612 -393.431729) (xy 339.801337 -393.409935)
			(xy 339.846945 -393.395089) (xy 339.894313 -393.387558) (xy 339.918294 -393.387072) (xy 339.918802 -393.387072)
			(xy 339.942735 -393.387578) (xy 339.990018 -393.395028) (xy 340.03556 -393.409763) (xy 340.078247 -393.43142)
			(xy 340.117033 -393.459469) (xy 340.15097 -393.493225) (xy 340.179226 -393.531861) (xy 340.190582 -393.552934)
			(xy 340.19109 -393.55395) (xy 340.271396 -393.692888) (xy 340.813136 -393.692888) (xy 340.813136 -393.69238)
			(xy 340.813543 -393.668399) (xy 340.821046 -393.621027) (xy 340.835863 -393.57541) (xy 340.857631 -393.532672)
			(xy 340.885813 -393.493862) (xy 340.919718 -393.459937) (xy 340.958509 -393.43173) (xy 341.001234 -393.409936)
			(xy 341.046841 -393.39509) (xy 341.094209 -393.387558) (xy 341.11819 -393.387072) (xy 341.118698 -393.387072)
			(xy 341.142634 -393.3875) (xy 341.189921 -393.394965) (xy 341.235464 -393.409713) (xy 341.278151 -393.431383)
			(xy 341.316936 -393.459445) (xy 341.35087 -393.493212) (xy 341.379124 -393.531857) (xy 341.390478 -393.552934)
			(xy 341.390986 -393.55395) (xy 341.471292 -393.692888) (xy 342.01354 -393.692888) (xy 342.01354 -393.69238)
			(xy 342.01392 -393.668384) (xy 342.021431 -393.620983) (xy 342.036265 -393.575341) (xy 342.058057 -393.532582)
			(xy 342.08627 -393.493758) (xy 342.12021 -393.459826) (xy 342.15904 -393.431622) (xy 342.201804 -393.409839)
			(xy 342.247449 -393.395015) (xy 342.294852 -393.387515) (xy 342.318848 -393.387072) (xy 342.342783 -393.387541)
			(xy 342.390067 -393.394998) (xy 342.43561 -393.409739) (xy 342.478297 -393.431402) (xy 342.517082 -393.459458)
			(xy 342.551018 -393.493219) (xy 342.579273 -393.531859) (xy 342.590628 -393.552934) (xy 342.591136 -393.55395)
			(xy 342.671442 -393.692888) (xy 343.213436 -393.692888) (xy 343.213436 -393.69238) (xy 343.21382 -393.668384)
			(xy 343.221331 -393.620984) (xy 343.236165 -393.575342) (xy 343.257957 -393.532583) (xy 343.286169 -393.493759)
			(xy 343.320108 -393.459828) (xy 343.358938 -393.431623) (xy 343.401701 -393.40984) (xy 343.447346 -393.395016)
			(xy 343.494748 -393.387515) (xy 343.518744 -393.387072) (xy 343.542678 -393.387544) (xy 343.589963 -393.395001)
			(xy 343.635506 -393.409741) (xy 343.678192 -393.431404) (xy 343.716978 -393.459459) (xy 343.750914 -393.493219)
			(xy 343.779169 -393.53186) (xy 343.790524 -393.552934) (xy 343.791032 -393.55395) (xy 343.871338 -393.692888)
			(xy 344.413332 -393.692888) (xy 344.413332 -393.69238) (xy 344.413743 -393.668399) (xy 344.421246 -393.621027)
			(xy 344.436063 -393.575411) (xy 344.45783 -393.532673) (xy 344.486012 -393.493864) (xy 344.519916 -393.459939)
			(xy 344.558707 -393.431732) (xy 344.601432 -393.409937) (xy 344.647038 -393.395091) (xy 344.694405 -393.387559)
			(xy 344.718386 -393.387072) (xy 344.718894 -393.387072) (xy 344.74283 -393.387503) (xy 344.790116 -393.394968)
			(xy 344.83566 -393.409715) (xy 344.878347 -393.431385) (xy 344.917132 -393.459446) (xy 344.951066 -393.493212)
			(xy 344.97932 -393.531857) (xy 344.990674 -393.552934) (xy 344.991182 -393.55395) (xy 345.071488 -393.692888)
			(xy 345.613228 -393.692888) (xy 345.613228 -393.69238) (xy 345.613643 -393.668399) (xy 345.621146 -393.621028)
			(xy 345.635962 -393.575412) (xy 345.657729 -393.532674) (xy 345.685911 -393.493865) (xy 345.719814 -393.45994)
			(xy 345.758605 -393.431733) (xy 345.801329 -393.409938) (xy 345.846935 -393.395092) (xy 345.894301 -393.387559)
			(xy 345.918282 -393.387072) (xy 345.91879 -393.387072) (xy 345.942726 -393.387506) (xy 345.990012 -393.39497)
			(xy 346.035556 -393.409717) (xy 346.078242 -393.431386) (xy 346.117027 -393.459447) (xy 346.150962 -393.493213)
			(xy 346.179216 -393.531857) (xy 346.19057 -393.552934) (xy 346.191078 -393.55395) (xy 346.271384 -393.692888)
			(xy 346.813124 -393.692888) (xy 346.813124 -393.69238) (xy 346.813543 -393.668399) (xy 346.821045 -393.621028)
			(xy 346.835862 -393.575413) (xy 346.857629 -393.532675) (xy 346.88581 -393.493866) (xy 346.919713 -393.459941)
			(xy 346.958503 -393.431734) (xy 347.001226 -393.40994) (xy 347.046832 -393.395093) (xy 347.094198 -393.387559)
			(xy 347.118178 -393.387072) (xy 347.118686 -393.387072) (xy 347.142622 -393.38751) (xy 347.189908 -393.394973)
			(xy 347.235451 -393.409719) (xy 347.278138 -393.431388) (xy 347.316923 -393.459448) (xy 347.350858 -393.493213)
			(xy 347.379112 -393.531858) (xy 347.390466 -393.552934) (xy 347.390974 -393.55395) (xy 347.47128 -393.692888)
			(xy 348.013528 -393.692888) (xy 348.013528 -393.69238) (xy 348.01392 -393.668385) (xy 348.021431 -393.620985)
			(xy 348.036264 -393.575344) (xy 348.058055 -393.532585) (xy 348.086267 -393.493762) (xy 348.120205 -393.45983)
			(xy 348.159033 -393.431626) (xy 348.201796 -393.409843) (xy 348.247439 -393.395018) (xy 348.29484 -393.387515)
			(xy 348.318836 -393.387072) (xy 348.34277 -393.38755) (xy 348.390054 -393.395006) (xy 348.435597 -393.409745)
			(xy 348.478284 -393.431407) (xy 348.517069 -393.459461) (xy 348.551005 -393.49322) (xy 348.579261 -393.53186)
			(xy 348.590616 -393.552934) (xy 348.591124 -393.55395) (xy 348.67143 -393.692888) (xy 349.213424 -393.692888)
			(xy 349.213424 -393.69238) (xy 349.21382 -393.668385) (xy 349.221331 -393.620985) (xy 349.236164 -393.575345)
			(xy 349.257954 -393.532586) (xy 349.286166 -393.493764) (xy 349.320103 -393.459832) (xy 349.358931 -393.431627)
			(xy 349.401693 -393.409844) (xy 349.447336 -393.395018) (xy 349.494737 -393.387516) (xy 349.518732 -393.387072)
			(xy 349.542666 -393.387554) (xy 349.58995 -393.395009) (xy 349.635493 -393.409747) (xy 349.678179 -393.431408)
			(xy 349.716965 -393.459462) (xy 349.750901 -393.493221) (xy 349.779157 -393.53186) (xy 349.790512 -393.552934)
			(xy 349.79102 -393.55395) (xy 349.871326 -393.692888) (xy 350.41332 -393.692888) (xy 350.41332 -393.69238)
			(xy 350.413743 -393.6684) (xy 350.421245 -393.621029) (xy 350.436062 -393.575414) (xy 350.457828 -393.532676)
			(xy 350.486009 -393.493868) (xy 350.519911 -393.459943) (xy 350.5587 -393.431736) (xy 350.601423 -393.409941)
			(xy 350.647028 -393.395093) (xy 350.694394 -393.387559) (xy 350.718374 -393.387072) (xy 350.718882 -393.387072)
			(xy 350.742818 -393.387513) (xy 350.790103 -393.394976) (xy 350.835647 -393.409721) (xy 350.878334 -393.431389)
			(xy 350.917119 -393.459449) (xy 350.951054 -393.493214) (xy 350.979308 -393.531858) (xy 350.990662 -393.552934)
			(xy 350.99117 -393.55395) (xy 351.071476 -393.692888) (xy 351.613216 -393.692888) (xy 351.613216 -393.69238)
			(xy 351.613643 -393.6684) (xy 351.621145 -393.621029) (xy 351.635961 -393.575415) (xy 351.657727 -393.532678)
			(xy 351.685908 -393.493869) (xy 351.719809 -393.459944) (xy 351.758598 -393.431737) (xy 351.80132 -393.409942)
			(xy 351.846925 -393.395094) (xy 351.89429 -393.38756) (xy 351.91827 -393.387072) (xy 351.918778 -393.387072)
			(xy 351.942713 -393.387516) (xy 351.989999 -393.394978) (xy 352.035543 -393.409723) (xy 352.078229 -393.431391)
			(xy 352.117015 -393.45945) (xy 352.150949 -393.493214) (xy 352.179204 -393.531858) (xy 352.190558 -393.552934)
			(xy 352.191066 -393.55395) (xy 352.271372 -393.692888) (xy 352.81362 -393.692888) (xy 352.81362 -393.69238)
			(xy 352.81402 -393.668385) (xy 352.82153 -393.620986) (xy 352.836363 -393.575346) (xy 352.858154 -393.532588)
			(xy 352.886365 -393.493765) (xy 352.920301 -393.459833) (xy 352.959129 -393.431629) (xy 353.00189 -393.409845)
			(xy 353.047533 -393.395019) (xy 353.094933 -393.387516) (xy 353.118928 -393.387072) (xy 353.142862 -393.387557)
			(xy 353.190146 -393.395011) (xy 353.235688 -393.409749) (xy 353.278375 -393.43141) (xy 353.317161 -393.459463)
			(xy 353.351097 -393.493222) (xy 353.379353 -393.53186) (xy 353.390708 -393.552934) (xy 353.391216 -393.55395)
			(xy 353.471522 -393.692888) (xy 354.013516 -393.692888) (xy 354.013516 -393.69238) (xy 354.01392 -393.668385)
			(xy 354.02143 -393.620987) (xy 354.036263 -393.575347) (xy 354.058053 -393.532589) (xy 354.086263 -393.493766)
			(xy 354.1202 -393.459835) (xy 354.159026 -393.43163) (xy 354.201787 -393.409846) (xy 354.247429 -393.39502)
			(xy 354.294829 -393.387516) (xy 354.318824 -393.387072) (xy 354.342758 -393.38756) (xy 354.390042 -393.395014)
			(xy 354.435584 -393.409751) (xy 354.478271 -393.431411) (xy 354.517057 -393.459464) (xy 354.550993 -393.493222)
			(xy 354.579249 -393.53186) (xy 354.590604 -393.552934) (xy 354.591112 -393.55395) (xy 354.671418 -393.692888)
			(xy 370.586 -393.692888) (xy 370.586 -393.69238) (xy 370.586444 -393.668388) (xy 370.593954 -393.620995)
			(xy 370.608784 -393.57536) (xy 370.630571 -393.532606) (xy 370.658777 -393.493788) (xy 370.692709 -393.459859)
			(xy 370.73153 -393.431656) (xy 370.774286 -393.409873) (xy 370.819922 -393.395047) (xy 370.867316 -393.387542)
			(xy 370.891308 -393.387072) (xy 370.915241 -393.387573) (xy 370.962524 -393.395024) (xy 371.008067 -393.409759)
			(xy 371.050753 -393.431417) (xy 371.089539 -393.459468) (xy 371.123476 -393.493224) (xy 371.151732 -393.531861)
			(xy 371.163088 -393.552934) (xy 371.163596 -393.55395) (xy 371.243902 -393.692888) (xy 371.785896 -393.692888)
			(xy 371.785896 -393.69238) (xy 371.786344 -393.668388) (xy 371.793853 -393.620995) (xy 371.808684 -393.575361)
			(xy 371.83047 -393.532608) (xy 371.858676 -393.493789) (xy 371.892607 -393.459861) (xy 371.931428 -393.431658)
			(xy 371.974183 -393.409875) (xy 372.019819 -393.395048) (xy 372.067212 -393.387542) (xy 372.091204 -393.387072)
			(xy 372.115137 -393.387576) (xy 372.16242 -393.395027) (xy 372.207962 -393.409762) (xy 372.250649 -393.431419)
			(xy 372.289435 -393.459469) (xy 372.323372 -393.493225) (xy 372.351628 -393.531861) (xy 372.362984 -393.552934)
			(xy 372.363492 -393.55395) (xy 372.443798 -393.692888) (xy 372.985792 -393.692888) (xy 372.985792 -393.69238)
			(xy 372.986244 -393.668388) (xy 372.993753 -393.620996) (xy 373.008583 -393.575362) (xy 373.030369 -393.532609)
			(xy 373.058575 -393.49379) (xy 373.092506 -393.459862) (xy 373.131326 -393.431659) (xy 373.17408 -393.409876)
			(xy 373.219715 -393.395049) (xy 373.267108 -393.387543) (xy 373.2911 -393.387072) (xy 373.315033 -393.38758)
			(xy 373.362316 -393.39503) (xy 373.407858 -393.409764) (xy 373.450544 -393.43142) (xy 373.489331 -393.45947)
			(xy 373.523268 -393.493226) (xy 373.551524 -393.531862) (xy 373.56288 -393.552934) (xy 373.563388 -393.55395)
			(xy 373.643694 -393.692888) (xy 374.185688 -393.692888) (xy 374.185688 -393.69238) (xy 374.186143 -393.668401)
			(xy 374.193644 -393.621034) (xy 374.208459 -393.575421) (xy 374.230222 -393.532686) (xy 374.258399 -393.493879)
			(xy 374.292298 -393.459954) (xy 374.331083 -393.431747) (xy 374.373801 -393.40995) (xy 374.419402 -393.3951)
			(xy 374.466763 -393.387562) (xy 374.490742 -393.387072) (xy 374.49125 -393.387072) (xy 374.515185 -393.387539)
			(xy 374.562469 -393.394997) (xy 374.608012 -393.409738) (xy 374.650699 -393.431401) (xy 374.689484 -393.459457)
			(xy 374.72342 -393.493218) (xy 374.751675 -393.531859) (xy 374.76303 -393.552934) (xy 374.763538 -393.55395)
			(xy 374.843844 -393.692888) (xy 375.385584 -393.692888) (xy 375.385584 -393.69238) (xy 375.386043 -393.668401)
			(xy 375.393544 -393.621034) (xy 375.408358 -393.575422) (xy 375.430121 -393.532687) (xy 375.458298 -393.49388)
			(xy 375.492196 -393.459956) (xy 375.53098 -393.431748) (xy 375.573698 -393.409951) (xy 375.619298 -393.395101)
			(xy 375.66666 -393.387562) (xy 375.690638 -393.387072) (xy 375.691146 -393.387072) (xy 375.715081 -393.387542)
			(xy 375.762365 -393.394999) (xy 375.807908 -393.40974) (xy 375.850594 -393.431403) (xy 375.88938 -393.459458)
			(xy 375.923316 -393.493219) (xy 375.951571 -393.531859) (xy 375.962926 -393.552934) (xy 375.963434 -393.55395)
			(xy 376.04374 -393.692888) (xy 376.585988 -393.692888) (xy 376.585988 -393.69238) (xy 376.586444 -393.668388)
			(xy 376.593953 -393.620996) (xy 376.608783 -393.575362) (xy 376.630569 -393.53261) (xy 376.658774 -393.493792)
			(xy 376.692704 -393.459863) (xy 376.731524 -393.43166) (xy 376.774277 -393.409877) (xy 376.819912 -393.395049)
			(xy 376.867304 -393.387543) (xy 376.891296 -393.387072) (xy 376.915232 -393.387502) (xy 376.962518 -393.394966)
			(xy 377.008062 -393.409714) (xy 377.050749 -393.431384) (xy 377.089534 -393.459445) (xy 377.123468 -393.493212)
			(xy 377.151722 -393.531857) (xy 377.163076 -393.552934) (xy 377.163584 -393.55395) (xy 377.24389 -393.692888)
			(xy 377.785884 -393.692888) (xy 377.785884 -393.69238) (xy 377.786344 -393.668389) (xy 377.793853 -393.620997)
			(xy 377.808683 -393.575363) (xy 377.830468 -393.532611) (xy 377.858673 -393.493793) (xy 377.892602 -393.459865)
			(xy 377.931421 -393.431662) (xy 377.974174 -393.409878) (xy 378.019809 -393.39505) (xy 378.067201 -393.387543)
			(xy 378.091192 -393.387072) (xy 378.115128 -393.387505) (xy 378.162414 -393.394969) (xy 378.207958 -393.409716)
			(xy 378.250644 -393.431385) (xy 378.28943 -393.459446) (xy 378.323364 -393.493212) (xy 378.351618 -393.531857)
			(xy 378.362972 -393.552934) (xy 378.36348 -393.55395) (xy 378.443786 -393.692888) (xy 378.98578 -393.692888)
			(xy 378.98578 -393.69238) (xy 378.986244 -393.668389) (xy 378.993753 -393.620998) (xy 379.008582 -393.575364)
			(xy 379.030367 -393.532612) (xy 379.058571 -393.493795) (xy 379.092501 -393.459866) (xy 379.131319 -393.431663)
			(xy 379.174072 -393.409879) (xy 379.219705 -393.395051) (xy 379.267097 -393.387543) (xy 379.291088 -393.387072)
			(xy 379.315024 -393.387508) (xy 379.36231 -393.394972) (xy 379.407853 -393.409718) (xy 379.45054 -393.431387)
			(xy 379.489325 -393.459447) (xy 379.52326 -393.493213) (xy 379.551514 -393.531858) (xy 379.562868 -393.552934)
			(xy 379.563376 -393.55395) (xy 379.643682 -393.692888) (xy 380.185676 -393.692888) (xy 380.185676 -393.69238)
			(xy 380.186143 -393.668402) (xy 380.193644 -393.621035) (xy 380.208457 -393.575424) (xy 380.23022 -393.532689)
			(xy 380.258396 -393.493883) (xy 380.292292 -393.459959) (xy 380.331076 -393.431751) (xy 380.373793 -393.409953)
			(xy 380.419392 -393.395102) (xy 380.466752 -393.387563) (xy 380.49073 -393.387072) (xy 380.491238 -393.387072)
			(xy 380.515172 -393.387549) (xy 380.562456 -393.395005) (xy 380.607999 -393.409744) (xy 380.650686 -393.431406)
			(xy 380.689472 -393.45946) (xy 380.723407 -393.49322) (xy 380.751663 -393.53186) (xy 380.763018 -393.552934)
			(xy 380.763526 -393.55395) (xy 380.843832 -393.692888) (xy 381.385572 -393.692888) (xy 381.385572 -393.69238)
			(xy 381.386043 -393.668402) (xy 381.393544 -393.621036) (xy 381.408357 -393.575425) (xy 381.430119 -393.532691)
			(xy 381.458295 -393.493884) (xy 381.492191 -393.45996) (xy 381.530974 -393.431752) (xy 381.57369 -393.409954)
			(xy 381.619289 -393.395103) (xy 381.666648 -393.387563) (xy 381.690626 -393.387072) (xy 381.691134 -393.387072)
			(xy 381.715068 -393.387552) (xy 381.762352 -393.395007) (xy 381.807895 -393.409746) (xy 381.850581 -393.431407)
			(xy 381.889367 -393.459461) (xy 381.923303 -393.493221) (xy 381.951559 -393.53186) (xy 381.962914 -393.552934)
			(xy 381.963422 -393.55395) (xy 382.043728 -393.692888) (xy 382.585976 -393.692888) (xy 382.585976 -393.69238)
			(xy 382.586444 -393.668389) (xy 382.593953 -393.620998) (xy 382.608782 -393.575365) (xy 382.630567 -393.532614)
			(xy 382.65877 -393.493796) (xy 382.692699 -393.459868) (xy 382.731517 -393.431664) (xy 382.774269 -393.40988)
			(xy 382.819902 -393.395052) (xy 382.867293 -393.387544) (xy 382.891284 -393.387072) (xy 382.91522 -393.387511)
			(xy 382.962506 -393.394974) (xy 383.008049 -393.40972) (xy 383.050736 -393.431388) (xy 383.089521 -393.459448)
			(xy 383.123456 -393.493214) (xy 383.15171 -393.531858) (xy 383.163064 -393.552934) (xy 383.163572 -393.55395)
			(xy 383.243878 -393.692888) (xy 383.785872 -393.692888) (xy 383.785872 -393.69238) (xy 383.786344 -393.668389)
			(xy 383.793853 -393.620999) (xy 383.808681 -393.575366) (xy 383.830466 -393.532615) (xy 383.858669 -393.493797)
			(xy 383.892597 -393.459869) (xy 383.931415 -393.431666) (xy 383.974166 -393.409881) (xy 384.019799 -393.395053)
			(xy 384.067189 -393.387544) (xy 384.09118 -393.387072) (xy 384.115116 -393.387515) (xy 384.162401 -393.394977)
			(xy 384.207945 -393.409722) (xy 384.250631 -393.43139) (xy 384.289417 -393.459449) (xy 384.323352 -393.493214)
			(xy 384.351606 -393.531858) (xy 384.36296 -393.552934) (xy 384.363468 -393.55395) (xy 384.443774 -393.692888)
			(xy 384.985768 -393.692888) (xy 384.985768 -393.69238) (xy 384.986244 -393.668389) (xy 384.993752 -393.620999)
			(xy 385.008581 -393.575367) (xy 385.030365 -393.532616) (xy 385.058568 -393.493799) (xy 385.092496 -393.459871)
			(xy 385.131313 -393.431667) (xy 385.174063 -393.409883) (xy 385.219695 -393.395053) (xy 385.267085 -393.387544)
			(xy 385.291076 -393.387072) (xy 385.315011 -393.387518) (xy 385.362297 -393.39498) (xy 385.40784 -393.409724)
			(xy 385.450527 -393.431391) (xy 385.489312 -393.45945) (xy 385.523247 -393.493215) (xy 385.551501 -393.531858)
			(xy 385.562856 -393.552934) (xy 385.563364 -393.55395) (xy 385.64367 -393.692888) (xy 386.185664 -393.692888)
			(xy 386.185664 -393.69238) (xy 386.186143 -393.668402) (xy 386.193643 -393.621037) (xy 386.208456 -393.575427)
			(xy 386.230218 -393.532693) (xy 386.258392 -393.493887) (xy 386.292287 -393.459963) (xy 386.331069 -393.431755)
			(xy 386.373784 -393.409957) (xy 386.419382 -393.395105) (xy 386.466741 -393.387564) (xy 386.490718 -393.387072)
			(xy 386.491226 -393.387072) (xy 386.51516 -393.387558) (xy 386.562444 -393.395013) (xy 386.607986 -393.40975)
			(xy 386.650673 -393.43141) (xy 386.689459 -393.459463) (xy 386.723395 -393.493222) (xy 386.751651 -393.53186)
			(xy 386.763006 -393.552934) (xy 386.763514 -393.55395) (xy 386.84382 -393.692888) (xy 387.38556 -393.692888)
			(xy 387.38556 -393.69238) (xy 387.386043 -393.668403) (xy 387.393543 -393.621038) (xy 387.408356 -393.575428)
			(xy 387.430117 -393.532694) (xy 387.458291 -393.493888) (xy 387.492186 -393.459964) (xy 387.530967 -393.431756)
			(xy 387.573682 -393.409958) (xy 387.619279 -393.395105) (xy 387.666637 -393.387564) (xy 387.690614 -393.387072)
			(xy 387.691122 -393.387072) (xy 387.715056 -393.387562) (xy 387.762339 -393.395015) (xy 387.807882 -393.409752)
			(xy 387.850568 -393.431412) (xy 387.889354 -393.459464) (xy 387.923291 -393.493222) (xy 387.951547 -393.531861)
			(xy 387.962902 -393.552934) (xy 387.96341 -393.55395) (xy 388.043716 -393.692888) (xy 388.585964 -393.692888)
			(xy 388.585964 -393.69238) (xy 388.586444 -393.66839) (xy 388.593952 -393.621) (xy 388.608781 -393.575368)
			(xy 388.630564 -393.532617) (xy 388.658767 -393.4938) (xy 388.692694 -393.459872) (xy 388.73151 -393.431668)
			(xy 388.774261 -393.409884) (xy 388.819892 -393.395054) (xy 388.867282 -393.387545) (xy 388.891272 -393.387072)
			(xy 388.915207 -393.387521) (xy 388.962493 -393.394982) (xy 389.008036 -393.409727) (xy 389.050723 -393.431393)
			(xy 389.089508 -393.459451) (xy 389.123443 -393.493215) (xy 389.151697 -393.531858) (xy 389.163052 -393.552934)
			(xy 389.16356 -393.55395) (xy 389.243866 -393.692888) (xy 403.113748 -393.692888) (xy 403.113748 -393.69238)
			(xy 403.114244 -393.66839) (xy 403.121752 -393.621002) (xy 403.136579 -393.575372) (xy 403.158361 -393.532622)
			(xy 403.186562 -393.493805) (xy 403.220487 -393.459878) (xy 403.259301 -393.431674) (xy 403.302049 -393.409888)
			(xy 403.347679 -393.395057) (xy 403.395066 -393.387546) (xy 403.419056 -393.387072) (xy 403.442991 -393.387534)
			(xy 403.490276 -393.394993) (xy 403.535819 -393.409735) (xy 403.578505 -393.431399) (xy 403.617291 -393.459456)
			(xy 403.651226 -393.493218) (xy 403.679481 -393.531859) (xy 403.690836 -393.552934) (xy 403.691344 -393.55395)
			(xy 403.77165 -393.692888) (xy 404.313644 -393.692888) (xy 404.313644 -393.69238) (xy 404.314144 -393.668391)
			(xy 404.321652 -393.621003) (xy 404.336479 -393.575373) (xy 404.358261 -393.532623) (xy 404.386461 -393.493807)
			(xy 404.420386 -393.459879) (xy 404.459199 -393.431675) (xy 404.501947 -393.40989) (xy 404.547576 -393.395058)
			(xy 404.594963 -393.387546) (xy 404.618952 -393.387072) (xy 404.642887 -393.387537) (xy 404.690171 -393.394995)
			(xy 404.735714 -393.409737) (xy 404.778401 -393.431401) (xy 404.817187 -393.459457) (xy 404.851122 -393.493218)
			(xy 404.879377 -393.531859) (xy 404.890732 -393.552934) (xy 404.89124 -393.55395) (xy 404.971546 -393.692888)
			(xy 405.51354 -393.692888) (xy 405.51354 -393.69238) (xy 405.51392 -393.668384) (xy 405.521431 -393.620983)
			(xy 405.536265 -393.575341) (xy 405.558057 -393.532582) (xy 405.58627 -393.493758) (xy 405.62021 -393.459826)
			(xy 405.65904 -393.431622) (xy 405.701804 -393.409839) (xy 405.747449 -393.395015) (xy 405.794852 -393.387515)
			(xy 405.818848 -393.387072) (xy 405.842783 -393.387541) (xy 405.890067 -393.394998) (xy 405.93561 -393.409739)
			(xy 405.978297 -393.431402) (xy 406.017082 -393.459458) (xy 406.051018 -393.493219) (xy 406.079273 -393.531859)
			(xy 406.090628 -393.552934) (xy 406.091136 -393.55395) (xy 406.171442 -393.692888) (xy 406.713436 -393.692888)
			(xy 406.713436 -393.69238) (xy 406.713843 -393.668399) (xy 406.721346 -393.621027) (xy 406.736163 -393.57541)
			(xy 406.757931 -393.532672) (xy 406.786113 -393.493862) (xy 406.820018 -393.459937) (xy 406.858809 -393.43173)
			(xy 406.901534 -393.409936) (xy 406.947141 -393.39509) (xy 406.994509 -393.387558) (xy 407.01849 -393.387072)
			(xy 407.018998 -393.387072) (xy 407.042934 -393.3875) (xy 407.090221 -393.394965) (xy 407.135764 -393.409713)
			(xy 407.178451 -393.431383) (xy 407.217236 -393.459445) (xy 407.25117 -393.493212) (xy 407.279424 -393.531857)
			(xy 407.290778 -393.552934) (xy 407.291286 -393.55395) (xy 407.371592 -393.692888) (xy 407.913332 -393.692888)
			(xy 407.913332 -393.69238) (xy 407.913743 -393.668399) (xy 407.921246 -393.621027) (xy 407.936063 -393.575411)
			(xy 407.95783 -393.532673) (xy 407.986012 -393.493864) (xy 408.019916 -393.459939) (xy 408.058707 -393.431732)
			(xy 408.101432 -393.409937) (xy 408.147038 -393.395091) (xy 408.194405 -393.387559) (xy 408.218386 -393.387072)
			(xy 408.218894 -393.387072) (xy 408.24283 -393.387503) (xy 408.290116 -393.394968) (xy 408.33566 -393.409715)
			(xy 408.378347 -393.431385) (xy 408.417132 -393.459446) (xy 408.451066 -393.493212) (xy 408.47932 -393.531857)
			(xy 408.490674 -393.552934) (xy 408.491182 -393.55395) (xy 408.571488 -393.692888) (xy 409.113736 -393.692888)
			(xy 409.113736 -393.69238) (xy 409.11412 -393.668384) (xy 409.121631 -393.620984) (xy 409.136465 -393.575342)
			(xy 409.158257 -393.532583) (xy 409.186469 -393.493759) (xy 409.220408 -393.459828) (xy 409.259238 -393.431623)
			(xy 409.302001 -393.40984) (xy 409.347646 -393.395016) (xy 409.395048 -393.387515) (xy 409.419044 -393.387072)
			(xy 409.442978 -393.387544) (xy 409.490263 -393.395001) (xy 409.535806 -393.409741) (xy 409.578492 -393.431404)
			(xy 409.617278 -393.459459) (xy 409.651214 -393.493219) (xy 409.679469 -393.53186) (xy 409.690824 -393.552934)
			(xy 409.691332 -393.55395) (xy 409.771638 -393.692888) (xy 410.313632 -393.692888) (xy 410.313632 -393.69238)
			(xy 410.31402 -393.668384) (xy 410.321531 -393.620984) (xy 410.336365 -393.575343) (xy 410.358156 -393.532584)
			(xy 410.386368 -393.493761) (xy 410.420306 -393.459829) (xy 410.459135 -393.431624) (xy 410.501898 -393.409842)
			(xy 410.547543 -393.395017) (xy 410.594944 -393.387515) (xy 410.61894 -393.387072) (xy 410.642874 -393.387547)
			(xy 410.690159 -393.395003) (xy 410.735701 -393.409743) (xy 410.778388 -393.431405) (xy 410.817174 -393.45946)
			(xy 410.85111 -393.49322) (xy 410.879365 -393.53186) (xy 410.89072 -393.552934) (xy 410.891228 -393.55395)
			(xy 410.971534 -393.692888) (xy 411.513528 -393.692888) (xy 411.513528 -393.69238) (xy 411.51392 -393.668385)
			(xy 411.521431 -393.620985) (xy 411.536264 -393.575344) (xy 411.558055 -393.532585) (xy 411.586267 -393.493762)
			(xy 411.620205 -393.45983) (xy 411.659033 -393.431626) (xy 411.701796 -393.409843) (xy 411.747439 -393.395018)
			(xy 411.79484 -393.387515) (xy 411.818836 -393.387072) (xy 411.84277 -393.38755) (xy 411.890054 -393.395006)
			(xy 411.935597 -393.409745) (xy 411.978284 -393.431407) (xy 412.017069 -393.459461) (xy 412.051005 -393.49322)
			(xy 412.079261 -393.53186) (xy 412.090616 -393.552934) (xy 412.091124 -393.55395) (xy 412.17143 -393.692888)
			(xy 412.713424 -393.692888) (xy 412.713424 -393.69238) (xy 412.713843 -393.668399) (xy 412.721345 -393.621028)
			(xy 412.736162 -393.575413) (xy 412.757929 -393.532675) (xy 412.78611 -393.493866) (xy 412.820013 -393.459941)
			(xy 412.858803 -393.431734) (xy 412.901526 -393.40994) (xy 412.947132 -393.395093) (xy 412.994498 -393.387559)
			(xy 413.018478 -393.387072) (xy 413.018986 -393.387072) (xy 413.042922 -393.38751) (xy 413.090208 -393.394973)
			(xy 413.135751 -393.409719) (xy 413.178438 -393.431388) (xy 413.217223 -393.459448) (xy 413.251158 -393.493213)
			(xy 413.279412 -393.531858) (xy 413.290766 -393.552934) (xy 413.291274 -393.55395) (xy 413.37158 -393.692888)
			(xy 413.91332 -393.692888) (xy 413.91332 -393.69238) (xy 413.913743 -393.6684) (xy 413.921245 -393.621029)
			(xy 413.936062 -393.575414) (xy 413.957828 -393.532676) (xy 413.986009 -393.493868) (xy 414.019911 -393.459943)
			(xy 414.0587 -393.431736) (xy 414.101423 -393.409941) (xy 414.147028 -393.395093) (xy 414.194394 -393.387559)
			(xy 414.218374 -393.387072) (xy 414.218882 -393.387072) (xy 414.242818 -393.387513) (xy 414.290103 -393.394976)
			(xy 414.335647 -393.409721) (xy 414.378334 -393.431389) (xy 414.417119 -393.459449) (xy 414.451054 -393.493214)
			(xy 414.479308 -393.531858) (xy 414.490662 -393.552934) (xy 414.49117 -393.55395) (xy 414.571476 -393.692888)
			(xy 415.113724 -393.692888) (xy 415.113724 -393.69238) (xy 415.11412 -393.668385) (xy 415.121631 -393.620985)
			(xy 415.136464 -393.575345) (xy 415.158254 -393.532586) (xy 415.186466 -393.493764) (xy 415.220403 -393.459832)
			(xy 415.259231 -393.431627) (xy 415.301993 -393.409844) (xy 415.347636 -393.395018) (xy 415.395037 -393.387516)
			(xy 415.419032 -393.387072) (xy 415.442966 -393.387554) (xy 415.49025 -393.395009) (xy 415.535793 -393.409747)
			(xy 415.578479 -393.431408) (xy 415.617265 -393.459462) (xy 415.651201 -393.493221) (xy 415.679457 -393.53186)
			(xy 415.690812 -393.552934) (xy 415.69132 -393.55395) (xy 415.771626 -393.692888) (xy 416.31362 -393.692888)
			(xy 416.31362 -393.69238) (xy 416.31402 -393.668385) (xy 416.32153 -393.620986) (xy 416.336363 -393.575346)
			(xy 416.358154 -393.532588) (xy 416.386365 -393.493765) (xy 416.420301 -393.459833) (xy 416.459129 -393.431629)
			(xy 416.50189 -393.409845) (xy 416.547533 -393.395019) (xy 416.594933 -393.387516) (xy 416.618928 -393.387072)
			(xy 416.642862 -393.387557) (xy 416.690146 -393.395011) (xy 416.735688 -393.409749) (xy 416.778375 -393.43141)
			(xy 416.817161 -393.459463) (xy 416.851097 -393.493222) (xy 416.879353 -393.53186) (xy 416.890708 -393.552934)
			(xy 416.891216 -393.55395) (xy 416.971522 -393.692888) (xy 417.513516 -393.692888) (xy 417.513516 -393.69238)
			(xy 417.51392 -393.668385) (xy 417.52143 -393.620987) (xy 417.536263 -393.575347) (xy 417.558053 -393.532589)
			(xy 417.586263 -393.493766) (xy 417.6202 -393.459835) (xy 417.659026 -393.43163) (xy 417.701787 -393.409846)
			(xy 417.747429 -393.39502) (xy 417.794829 -393.387516) (xy 417.818824 -393.387072) (xy 417.842758 -393.38756)
			(xy 417.890042 -393.395014) (xy 417.935584 -393.409751) (xy 417.978271 -393.431411) (xy 418.017057 -393.459464)
			(xy 418.050993 -393.493222) (xy 418.079249 -393.53186) (xy 418.090604 -393.552934) (xy 418.091112 -393.55395)
			(xy 418.171418 -393.692888) (xy 418.713412 -393.692888) (xy 418.713412 -393.69238) (xy 418.713843 -393.6684)
			(xy 418.721345 -393.62103) (xy 418.736161 -393.575416) (xy 418.757927 -393.532679) (xy 418.786106 -393.493871)
			(xy 418.820008 -393.459946) (xy 418.858796 -393.431739) (xy 418.901518 -393.409943) (xy 418.947122 -393.395095)
			(xy 418.994486 -393.38756) (xy 419.018466 -393.387072) (xy 419.018974 -393.387072) (xy 419.042909 -393.387519)
			(xy 419.090195 -393.394981) (xy 419.135738 -393.409726) (xy 419.178425 -393.431392) (xy 419.21721 -393.459451)
			(xy 419.251145 -393.493215) (xy 419.279399 -393.531858) (xy 419.290754 -393.552934) (xy 419.291262 -393.55395)
			(xy 419.371568 -393.692888) (xy 419.913308 -393.692888) (xy 419.913308 -393.69238) (xy 419.913743 -393.6684)
			(xy 419.921245 -393.621031) (xy 419.936061 -393.575417) (xy 419.957826 -393.53268) (xy 419.986005 -393.493872)
			(xy 420.019906 -393.459947) (xy 420.058694 -393.43174) (xy 420.101415 -393.409944) (xy 420.147018 -393.395096)
			(xy 420.194382 -393.38756) (xy 420.218362 -393.387072) (xy 420.21887 -393.387072) (xy 420.242805 -393.387523)
			(xy 420.290091 -393.394984) (xy 420.335634 -393.409728) (xy 420.378321 -393.431394) (xy 420.417106 -393.459452)
			(xy 420.451041 -393.493216) (xy 420.479295 -393.531858) (xy 420.49065 -393.552934) (xy 420.491158 -393.55395)
			(xy 420.571464 -393.692888) (xy 421.113712 -393.692888) (xy 421.113712 -393.69238) (xy 421.114144 -393.668387)
			(xy 421.121654 -393.620993) (xy 421.136485 -393.575357) (xy 421.158273 -393.532603) (xy 421.186481 -393.493784)
			(xy 421.220414 -393.459855) (xy 421.259237 -393.431652) (xy 421.301994 -393.40987) (xy 421.347632 -393.395045)
			(xy 421.395027 -393.387541) (xy 421.41902 -393.387072) (xy 421.442954 -393.387563) (xy 421.490237 -393.395017)
			(xy 421.53578 -393.409753) (xy 421.578466 -393.431413) (xy 421.617252 -393.459465) (xy 421.651189 -393.493223)
			(xy 421.679444 -393.531861) (xy 421.6908 -393.552934) (xy 421.691308 -393.55395) (xy 422.083738 -394.232892)
			(xy 422.096563 -394.256225) (xy 422.114783 -394.306247) (xy 422.124043 -394.358673) (xy 422.124632 -394.385292)
			(xy 422.124131 -394.409269) (xy 422.116635 -394.456634) (xy 422.101826 -394.502244) (xy 422.080067 -394.544978)
			(xy 422.051895 -394.583784) (xy 422.018002 -394.617709) (xy 421.979222 -394.645918) (xy 421.936509 -394.667716)
			(xy 421.890912 -394.682568) (xy 421.843555 -394.690109) (xy 421.819578 -394.6906) (xy 421.81907 -394.6906)
			(xy 421.795495 -394.69023) (xy 421.748906 -394.682984) (xy 421.703987 -394.668654) (xy 421.661808 -394.647582)
			(xy 421.623376 -394.620268) (xy 421.589605 -394.587365) (xy 421.5613 -394.549657) (xy 421.54983 -394.529056)
			(xy 421.549322 -394.528294) (xy 421.151558 -393.839954) (xy 421.139699 -393.817269) (xy 421.122842 -393.76894)
			(xy 421.114262 -393.71848) (xy 421.113712 -393.692888) (xy 420.571464 -393.692888) (xy 420.883588 -394.232892)
			(xy 420.89632 -394.256211) (xy 420.914415 -394.306158) (xy 420.923631 -394.358477) (xy 420.924228 -394.385038)
			(xy 420.924228 -394.385292) (xy 420.92373 -394.409282) (xy 420.916226 -394.456672) (xy 420.901401 -394.502304)
			(xy 420.87962 -394.545055) (xy 420.85142 -394.583873) (xy 420.817494 -394.617801) (xy 420.778679 -394.646005)
			(xy 420.73593 -394.66779) (xy 420.690299 -394.682619) (xy 420.64291 -394.690128) (xy 420.61892 -394.6906)
			(xy 420.595347 -394.69019) (xy 420.548759 -394.682952) (xy 420.503841 -394.668629) (xy 420.461662 -394.647563)
			(xy 420.423229 -394.620256) (xy 420.389457 -394.587358) (xy 420.361151 -394.549655) (xy 420.34968 -394.529056)
			(xy 420.349172 -394.528294) (xy 419.951408 -393.839954) (xy 419.939474 -393.817295) (xy 419.922543 -393.768965)
			(xy 419.913891 -393.718491) (xy 419.913308 -393.692888) (xy 419.371568 -393.692888) (xy 419.683692 -394.232892)
			(xy 419.696424 -394.25621) (xy 419.714519 -394.306158) (xy 419.723735 -394.358477) (xy 419.724332 -394.385038)
			(xy 419.724332 -394.385292) (xy 419.72383 -394.409282) (xy 419.716326 -394.456671) (xy 419.701501 -394.502303)
			(xy 419.679721 -394.545054) (xy 419.651521 -394.583871) (xy 419.617596 -394.6178) (xy 419.578781 -394.646004)
			(xy 419.536032 -394.667789) (xy 419.490402 -394.682618) (xy 419.443014 -394.690128) (xy 419.419024 -394.6906)
			(xy 419.395451 -394.690187) (xy 419.348863 -394.682949) (xy 419.303945 -394.668627) (xy 419.261767 -394.647561)
			(xy 419.223333 -394.620255) (xy 419.189561 -394.587358) (xy 419.161255 -394.549655) (xy 419.149784 -394.529056)
			(xy 419.149276 -394.528294) (xy 418.751512 -393.839954) (xy 418.739579 -393.817295) (xy 418.722647 -393.768965)
			(xy 418.713995 -393.718491) (xy 418.713412 -393.692888) (xy 418.171418 -393.692888) (xy 418.483542 -394.232892)
			(xy 418.496367 -394.256224) (xy 418.514587 -394.306247) (xy 418.523847 -394.358673) (xy 418.524436 -394.385292)
			(xy 418.523931 -394.409269) (xy 418.516435 -394.456633) (xy 418.501626 -394.502243) (xy 418.479868 -394.544977)
			(xy 418.451696 -394.583783) (xy 418.417804 -394.617708) (xy 418.379024 -394.645916) (xy 418.336311 -394.667715)
			(xy 418.290716 -394.682567) (xy 418.243358 -394.690108) (xy 418.219382 -394.6906) (xy 418.218874 -394.6906)
			(xy 418.195299 -394.690227) (xy 418.14871 -394.682982) (xy 418.103791 -394.668652) (xy 418.061613 -394.64758)
			(xy 418.02318 -394.620267) (xy 417.989409 -394.587365) (xy 417.961104 -394.549657) (xy 417.949634 -394.529056)
			(xy 417.949126 -394.528294) (xy 417.551362 -393.839954) (xy 417.539504 -393.817268) (xy 417.522646 -393.76894)
			(xy 417.514066 -393.71848) (xy 417.513516 -393.692888) (xy 416.971522 -393.692888) (xy 417.283646 -394.232892)
			(xy 417.296471 -394.256224) (xy 417.314691 -394.306247) (xy 417.323951 -394.358673) (xy 417.32454 -394.385292)
			(xy 417.324031 -394.409269) (xy 417.316535 -394.456633) (xy 417.301726 -394.502242) (xy 417.279969 -394.544976)
			(xy 417.251798 -394.583782) (xy 417.217906 -394.617706) (xy 417.179127 -394.645915) (xy 417.136414 -394.667714)
			(xy 417.090819 -394.682566) (xy 417.043462 -394.690108) (xy 417.019486 -394.6906) (xy 417.018978 -394.6906)
			(xy 416.995403 -394.690224) (xy 416.948814 -394.682979) (xy 416.903895 -394.66865) (xy 416.861717 -394.647579)
			(xy 416.823284 -394.620266) (xy 416.789513 -394.587364) (xy 416.761208 -394.549657) (xy 416.749738 -394.529056)
			(xy 416.74923 -394.528294) (xy 416.351466 -393.839954) (xy 416.339608 -393.817268) (xy 416.32275 -393.76894)
			(xy 416.31417 -393.71848) (xy 416.31362 -393.692888) (xy 415.771626 -393.692888) (xy 416.08375 -394.232892)
			(xy 416.096576 -394.256224) (xy 416.114795 -394.306247) (xy 416.124055 -394.358673) (xy 416.124644 -394.385292)
			(xy 416.124131 -394.409269) (xy 416.116635 -394.456632) (xy 416.101827 -394.502241) (xy 416.080069 -394.544974)
			(xy 416.051899 -394.58378) (xy 416.018007 -394.617705) (xy 415.979229 -394.645913) (xy 415.936517 -394.667712)
			(xy 415.890922 -394.682566) (xy 415.843566 -394.690108) (xy 415.81959 -394.6906) (xy 415.819082 -394.6906)
			(xy 415.795507 -394.690221) (xy 415.748919 -394.682977) (xy 415.704 -394.668648) (xy 415.661821 -394.647577)
			(xy 415.623388 -394.620265) (xy 415.589617 -394.587364) (xy 415.561312 -394.549657) (xy 415.549842 -394.529056)
			(xy 415.549334 -394.528294) (xy 415.15157 -393.839954) (xy 415.139712 -393.817268) (xy 415.122855 -393.768939)
			(xy 415.114274 -393.71848) (xy 415.113724 -393.692888) (xy 414.571476 -393.692888) (xy 414.8836 -394.232892)
			(xy 414.896333 -394.25621) (xy 414.914427 -394.306158) (xy 414.923643 -394.358477) (xy 414.92424 -394.385038)
			(xy 414.92424 -394.385292) (xy 414.92373 -394.409281) (xy 414.916226 -394.45667) (xy 414.901402 -394.502301)
			(xy 414.879622 -394.545051) (xy 414.851423 -394.583869) (xy 414.817499 -394.617797) (xy 414.778686 -394.646001)
			(xy 414.735938 -394.667787) (xy 414.690309 -394.682617) (xy 414.642921 -394.690127) (xy 414.618932 -394.6906)
			(xy 414.595359 -394.69018) (xy 414.548772 -394.682944) (xy 414.503854 -394.668623) (xy 414.461675 -394.647558)
			(xy 414.423242 -394.620253) (xy 414.38947 -394.587357) (xy 414.361163 -394.549654) (xy 414.349692 -394.529056)
			(xy 414.349184 -394.528294) (xy 413.95142 -393.839954) (xy 413.939487 -393.817294) (xy 413.922556 -393.768965)
			(xy 413.913903 -393.718491) (xy 413.91332 -393.692888) (xy 413.37158 -393.692888) (xy 413.683704 -394.232892)
			(xy 413.696437 -394.25621) (xy 413.714531 -394.306158) (xy 413.723747 -394.358477) (xy 413.724344 -394.385038)
			(xy 413.724344 -394.385292) (xy 413.72383 -394.409281) (xy 413.716326 -394.456669) (xy 413.701502 -394.5023)
			(xy 413.679723 -394.54505) (xy 413.651524 -394.583867) (xy 413.617601 -394.617796) (xy 413.578788 -394.646)
			(xy 413.536041 -394.667785) (xy 413.490412 -394.682616) (xy 413.443025 -394.690127) (xy 413.419036 -394.6906)
			(xy 413.395463 -394.690177) (xy 413.348876 -394.682941) (xy 413.303958 -394.668621) (xy 413.26178 -394.647557)
			(xy 413.223346 -394.620252) (xy 413.189574 -394.587356) (xy 413.161267 -394.549654) (xy 413.149796 -394.529056)
			(xy 413.149288 -394.528294) (xy 412.751524 -393.839954) (xy 412.739592 -393.817294) (xy 412.72266 -393.768965)
			(xy 412.714007 -393.718491) (xy 412.713424 -393.692888) (xy 412.17143 -393.692888) (xy 412.483554 -394.232892)
			(xy 412.49638 -394.256224) (xy 412.514599 -394.306247) (xy 412.523859 -394.358673) (xy 412.524448 -394.385292)
			(xy 412.523931 -394.409268) (xy 412.516436 -394.456632) (xy 412.501627 -394.50224) (xy 412.47987 -394.544973)
			(xy 412.4517 -394.583779) (xy 412.417809 -394.617703) (xy 412.379031 -394.645912) (xy 412.33632 -394.667711)
			(xy 412.290726 -394.682565) (xy 412.24337 -394.690107) (xy 412.219394 -394.6906) (xy 412.218886 -394.6906)
			(xy 412.195312 -394.690217) (xy 412.148723 -394.682974) (xy 412.103804 -394.668646) (xy 412.061626 -394.647576)
			(xy 412.023193 -394.620264) (xy 411.989421 -394.587363) (xy 411.961116 -394.549656) (xy 411.949646 -394.529056)
			(xy 411.949138 -394.528294) (xy 411.551374 -393.839954) (xy 411.539517 -393.817268) (xy 411.522659 -393.768939)
			(xy 411.514078 -393.718479) (xy 411.513528 -393.692888) (xy 410.971534 -393.692888) (xy 411.283658 -394.232892)
			(xy 411.296484 -394.256224) (xy 411.314704 -394.306247) (xy 411.323963 -394.358673) (xy 411.324552 -394.385292)
			(xy 411.324031 -394.409268) (xy 411.316536 -394.456631) (xy 411.301727 -394.502239) (xy 411.279971 -394.544972)
			(xy 411.251801 -394.583778) (xy 411.217911 -394.617702) (xy 411.179133 -394.645911) (xy 411.136423 -394.66771)
			(xy 411.090829 -394.682564) (xy 411.043474 -394.690107) (xy 411.019498 -394.6906) (xy 411.01899 -394.6906)
			(xy 410.995416 -394.690214) (xy 410.948827 -394.682971) (xy 410.903908 -394.668644) (xy 410.86173 -394.647574)
			(xy 410.823297 -394.620263) (xy 410.789526 -394.587363) (xy 410.76122 -394.549656) (xy 410.74975 -394.529056)
			(xy 410.749242 -394.528294) (xy 410.351478 -393.839954) (xy 410.339621 -393.817268) (xy 410.322763 -393.768939)
			(xy 410.314182 -393.718479) (xy 410.313632 -393.692888) (xy 409.771638 -393.692888) (xy 410.083762 -394.232892)
			(xy 410.096589 -394.256224) (xy 410.114808 -394.306247) (xy 410.124067 -394.358673) (xy 410.124656 -394.385292)
			(xy 410.124131 -394.409268) (xy 410.116636 -394.45663) (xy 410.101828 -394.502239) (xy 410.080072 -394.544971)
			(xy 410.051902 -394.583776) (xy 410.018012 -394.617701) (xy 409.979235 -394.645909) (xy 409.936525 -394.667709)
			(xy 409.890932 -394.682563) (xy 409.843577 -394.690107) (xy 409.819602 -394.6906) (xy 409.819094 -394.6906)
			(xy 409.79552 -394.690211) (xy 409.748931 -394.682969) (xy 409.704013 -394.668642) (xy 409.661834 -394.647573)
			(xy 409.623401 -394.620262) (xy 409.58963 -394.587362) (xy 409.561324 -394.549656) (xy 409.549854 -394.529056)
			(xy 409.549346 -394.528294) (xy 409.151582 -393.839954) (xy 409.139725 -393.817268) (xy 409.122867 -393.768939)
			(xy 409.114286 -393.718479) (xy 409.113736 -393.692888) (xy 408.571488 -393.692888) (xy 408.883612 -394.232892)
			(xy 408.896346 -394.25621) (xy 408.914439 -394.306158) (xy 408.923655 -394.358477) (xy 408.924252 -394.385038)
			(xy 408.924252 -394.385292) (xy 408.92373 -394.409281) (xy 408.916227 -394.456668) (xy 408.901403 -394.502298)
			(xy 408.879624 -394.545048) (xy 408.851427 -394.583865) (xy 408.817504 -394.617793) (xy 408.778692 -394.645997)
			(xy 408.735946 -394.667783) (xy 408.690319 -394.682614) (xy 408.642933 -394.690126) (xy 408.618944 -394.6906)
			(xy 408.595371 -394.690171) (xy 408.548785 -394.682936) (xy 408.503867 -394.668616) (xy 408.461689 -394.647554)
			(xy 408.423255 -394.620249) (xy 408.389482 -394.587355) (xy 408.361175 -394.549654) (xy 408.349704 -394.529056)
			(xy 408.349196 -394.528294) (xy 407.951432 -393.839954) (xy 407.9395 -393.817294) (xy 407.922568 -393.768965)
			(xy 407.913915 -393.718491) (xy 407.913332 -393.692888) (xy 407.371592 -393.692888) (xy 407.683716 -394.232892)
			(xy 407.69645 -394.256209) (xy 407.714543 -394.306158) (xy 407.723759 -394.358477) (xy 407.724356 -394.385038)
			(xy 407.724356 -394.385292) (xy 407.72383 -394.409281) (xy 407.716327 -394.456667) (xy 407.701503 -394.502297)
			(xy 407.679725 -394.545047) (xy 407.651528 -394.583863) (xy 407.617606 -394.617791) (xy 407.578794 -394.645996)
			(xy 407.536049 -394.667782) (xy 407.490422 -394.682614) (xy 407.443037 -394.690126) (xy 407.419048 -394.6906)
			(xy 407.395475 -394.690168) (xy 407.348889 -394.682933) (xy 407.303971 -394.668614) (xy 407.261793 -394.647552)
			(xy 407.223359 -394.620248) (xy 407.189586 -394.587354) (xy 407.161279 -394.549654) (xy 407.149808 -394.529056)
			(xy 407.1493 -394.528294) (xy 406.751536 -393.839954) (xy 406.739605 -393.817294) (xy 406.722672 -393.768964)
			(xy 406.714019 -393.718491) (xy 406.713436 -393.692888) (xy 406.171442 -393.692888) (xy 406.483566 -394.232892)
			(xy 406.496393 -394.256223) (xy 406.514612 -394.306247) (xy 406.523871 -394.358673) (xy 406.52446 -394.385292)
			(xy 406.524031 -394.409273) (xy 406.516532 -394.456644) (xy 406.501719 -394.502261) (xy 406.479954 -394.544999)
			(xy 406.451774 -394.583809) (xy 406.417872 -394.617735) (xy 406.379082 -394.645942) (xy 406.336359 -394.667737)
			(xy 406.290753 -394.682582) (xy 406.243386 -394.690114) (xy 406.219406 -394.6906) (xy 406.218898 -394.6906)
			(xy 406.195324 -394.690208) (xy 406.148736 -394.682966) (xy 406.103817 -394.66864) (xy 406.061639 -394.647571)
			(xy 406.023206 -394.620261) (xy 405.989434 -394.587361) (xy 405.961128 -394.549656) (xy 405.949658 -394.529056)
			(xy 405.94915 -394.528294) (xy 405.551386 -393.839954) (xy 405.53953 -393.817267) (xy 405.522671 -393.768939)
			(xy 405.51409 -393.718479) (xy 405.51354 -393.692888) (xy 404.971546 -393.692888) (xy 405.28367 -394.232892)
			(xy 405.296497 -394.256223) (xy 405.314716 -394.306247) (xy 405.323975 -394.358673) (xy 405.324564 -394.385292)
			(xy 405.324131 -394.409273) (xy 405.316633 -394.456644) (xy 405.301819 -394.50226) (xy 405.280055 -394.544998)
			(xy 405.251875 -394.583808) (xy 405.217974 -394.617733) (xy 405.179184 -394.645941) (xy 405.136461 -394.667735)
			(xy 405.090856 -394.682581) (xy 405.04349 -394.690114) (xy 405.01951 -394.6906) (xy 405.019002 -394.6906)
			(xy 404.995428 -394.690205) (xy 404.94884 -394.682963) (xy 404.903921 -394.668638) (xy 404.861743 -394.64757)
			(xy 404.82331 -394.62026) (xy 404.789538 -394.587361) (xy 404.761233 -394.549656) (xy 404.749762 -394.529056)
			(xy 404.749254 -394.528294) (xy 404.35149 -393.839954) (xy 404.339634 -393.817267) (xy 404.322775 -393.768939)
			(xy 404.314194 -393.718479) (xy 404.313644 -393.692888) (xy 403.77165 -393.692888) (xy 404.083774 -394.232892)
			(xy 404.096601 -394.256223) (xy 404.11482 -394.306247) (xy 404.124079 -394.358673) (xy 404.124668 -394.385292)
			(xy 404.124231 -394.409272) (xy 404.116733 -394.456643) (xy 404.101919 -394.502259) (xy 404.080155 -394.544997)
			(xy 404.051976 -394.583806) (xy 404.018075 -394.617732) (xy 403.979287 -394.645939) (xy 403.936564 -394.667734)
			(xy 403.890959 -394.682581) (xy 403.843594 -394.690113) (xy 403.819614 -394.6906) (xy 403.819106 -394.6906)
			(xy 403.795532 -394.690201) (xy 403.748944 -394.682961) (xy 403.704026 -394.668636) (xy 403.661847 -394.647568)
			(xy 403.623414 -394.620259) (xy 403.589642 -394.58736) (xy 403.561337 -394.549655) (xy 403.549866 -394.529056)
			(xy 403.549358 -394.528294) (xy 403.151594 -393.839954) (xy 403.139738 -393.817267) (xy 403.122879 -393.768939)
			(xy 403.114298 -393.718479) (xy 403.113748 -393.692888) (xy 389.243866 -393.692888) (xy 389.55599 -394.232892)
			(xy 389.568819 -394.256222) (xy 389.587037 -394.306246) (xy 389.596295 -394.358673) (xy 389.596884 -394.385292)
			(xy 389.596431 -394.409272) (xy 389.588933 -394.456641) (xy 389.574121 -394.502255) (xy 389.552358 -394.544992)
			(xy 389.524181 -394.583801) (xy 389.490282 -394.617726) (xy 389.451496 -394.645934) (xy 389.408775 -394.66773)
			(xy 389.363173 -394.682578) (xy 389.315809 -394.690112) (xy 389.29183 -394.6906) (xy 389.291322 -394.6906)
			(xy 389.267749 -394.690188) (xy 389.221161 -394.68295) (xy 389.176243 -394.668628) (xy 389.134065 -394.647562)
			(xy 389.095631 -394.620255) (xy 389.061859 -394.587358) (xy 389.033553 -394.549655) (xy 389.022082 -394.529056)
			(xy 389.021574 -394.528294) (xy 388.62381 -393.839954) (xy 388.611948 -393.81727) (xy 388.595093 -393.76894)
			(xy 388.586513 -393.71848) (xy 388.585964 -393.692888) (xy 388.043716 -393.692888) (xy 388.35584 -394.232892)
			(xy 388.368576 -394.256208) (xy 388.386668 -394.306157) (xy 388.395883 -394.358476) (xy 388.39648 -394.385038)
			(xy 388.39648 -394.385292) (xy 388.396054 -394.409286) (xy 388.388548 -394.456684) (xy 388.373719 -394.502324)
			(xy 388.351932 -394.545082) (xy 388.323724 -394.583905) (xy 388.28979 -394.617837) (xy 388.250965 -394.646042)
			(xy 388.208206 -394.667826) (xy 388.162565 -394.682653) (xy 388.115166 -394.690156) (xy 388.091172 -394.6906)
			(xy 388.067597 -394.690229) (xy 388.021008 -394.682983) (xy 387.976089 -394.668653) (xy 387.93391 -394.647581)
			(xy 387.895478 -394.620268) (xy 387.861707 -394.587365) (xy 387.833402 -394.549657) (xy 387.821932 -394.529056)
			(xy 387.821424 -394.528294) (xy 387.42366 -393.839954) (xy 387.41173 -393.817293) (xy 387.394797 -393.768964)
			(xy 387.386143 -393.718491) (xy 387.38556 -393.692888) (xy 386.84382 -393.692888) (xy 387.155944 -394.232892)
			(xy 387.16868 -394.256208) (xy 387.186772 -394.306157) (xy 387.195988 -394.358476) (xy 387.196584 -394.385038)
			(xy 387.196584 -394.385292) (xy 387.196154 -394.409286) (xy 387.188648 -394.456684) (xy 387.173819 -394.502323)
			(xy 387.152033 -394.545081) (xy 387.123825 -394.583904) (xy 387.089892 -394.617836) (xy 387.051067 -394.646041)
			(xy 387.008308 -394.667825) (xy 386.962668 -394.682652) (xy 386.91527 -394.690156) (xy 386.891276 -394.6906)
			(xy 386.867701 -394.690226) (xy 386.821112 -394.68298) (xy 386.776193 -394.668651) (xy 386.734015 -394.647579)
			(xy 386.695582 -394.620267) (xy 386.661811 -394.587365) (xy 386.633506 -394.549657) (xy 386.622036 -394.529056)
			(xy 386.621528 -394.528294) (xy 386.223764 -393.839954) (xy 386.211835 -393.817292) (xy 386.194901 -393.768964)
			(xy 386.186248 -393.718491) (xy 386.185664 -393.692888) (xy 385.64367 -393.692888) (xy 385.955794 -394.232892)
			(xy 385.968623 -394.256222) (xy 385.986841 -394.306246) (xy 385.996099 -394.358673) (xy 385.996688 -394.385292)
			(xy 385.996231 -394.409271) (xy 385.988733 -394.45664) (xy 385.973921 -394.502254) (xy 385.952159 -394.544991)
			(xy 385.923982 -394.5838) (xy 385.890084 -394.617725) (xy 385.851298 -394.645932) (xy 385.808578 -394.667728)
			(xy 385.762976 -394.682577) (xy 385.715613 -394.690112) (xy 385.691634 -394.6906) (xy 385.691126 -394.6906)
			(xy 385.667553 -394.690185) (xy 385.620965 -394.682948) (xy 385.576047 -394.668626) (xy 385.533869 -394.64756)
			(xy 385.495436 -394.620254) (xy 385.461663 -394.587357) (xy 385.433357 -394.549655) (xy 385.421886 -394.529056)
			(xy 385.421378 -394.528294) (xy 385.023614 -393.839954) (xy 385.011752 -393.81727) (xy 384.994897 -393.76894)
			(xy 384.986317 -393.71848) (xy 384.985768 -393.692888) (xy 384.443774 -393.692888) (xy 384.755898 -394.232892)
			(xy 384.768719 -394.256226) (xy 384.786942 -394.306248) (xy 384.796203 -394.358674) (xy 384.796792 -394.385292)
			(xy 384.796331 -394.409271) (xy 384.788834 -394.45664) (xy 384.774022 -394.502253) (xy 384.75226 -394.54499)
			(xy 384.724083 -394.583798) (xy 384.690186 -394.617723) (xy 384.6514 -394.645931) (xy 384.608681 -394.667727)
			(xy 384.563079 -394.682576) (xy 384.515717 -394.690112) (xy 384.491738 -394.6906) (xy 384.49123 -394.6906)
			(xy 384.467657 -394.690182) (xy 384.42107 -394.682945) (xy 384.376152 -394.668624) (xy 384.333973 -394.647559)
			(xy 384.29554 -394.620253) (xy 384.261768 -394.587357) (xy 384.233461 -394.549654) (xy 384.22199 -394.529056)
			(xy 384.221482 -394.528294) (xy 383.823718 -393.839954) (xy 383.811856 -393.81727) (xy 383.795001 -393.76894)
			(xy 383.786421 -393.71848) (xy 383.785872 -393.692888) (xy 383.243878 -393.692888) (xy 383.556002 -394.232892)
			(xy 383.568824 -394.256226) (xy 383.587046 -394.306248) (xy 383.596307 -394.358674) (xy 383.596896 -394.385292)
			(xy 383.596431 -394.409271) (xy 383.588934 -394.456639) (xy 383.574122 -394.502252) (xy 383.552361 -394.544989)
			(xy 383.524185 -394.583797) (xy 383.490287 -394.617722) (xy 383.451502 -394.64593) (xy 383.408784 -394.667726)
			(xy 383.363183 -394.682575) (xy 383.315821 -394.690111) (xy 383.291842 -394.6906) (xy 383.291334 -394.6906)
			(xy 383.267761 -394.690179) (xy 383.221174 -394.682942) (xy 383.176256 -394.668622) (xy 383.134078 -394.647557)
			(xy 383.095644 -394.620252) (xy 383.061872 -394.587356) (xy 383.033565 -394.549654) (xy 383.022094 -394.529056)
			(xy 383.021586 -394.528294) (xy 382.623822 -393.839954) (xy 382.611961 -393.81727) (xy 382.595105 -393.76894)
			(xy 382.586526 -393.71848) (xy 382.585976 -393.692888) (xy 382.043728 -393.692888) (xy 382.355852 -394.232892)
			(xy 382.368589 -394.256208) (xy 382.386681 -394.306157) (xy 382.395896 -394.358476) (xy 382.396492 -394.385038)
			(xy 382.396492 -394.385292) (xy 382.396054 -394.409286) (xy 382.388548 -394.456682) (xy 382.37372 -394.502321)
			(xy 382.351934 -394.545079) (xy 382.323728 -394.583901) (xy 382.289795 -394.617833) (xy 382.250972 -394.646038)
			(xy 382.208214 -394.667823) (xy 382.162575 -394.68265) (xy 382.115178 -394.690155) (xy 382.091184 -394.6906)
			(xy 382.06761 -394.690219) (xy 382.021021 -394.682975) (xy 381.976102 -394.668647) (xy 381.933923 -394.647576)
			(xy 381.895491 -394.620265) (xy 381.861719 -394.587363) (xy 381.833414 -394.549656) (xy 381.821944 -394.529056)
			(xy 381.821436 -394.528294) (xy 381.423672 -393.839954) (xy 381.411736 -393.817296) (xy 381.394806 -393.768965)
			(xy 381.386155 -393.718492) (xy 381.385572 -393.692888) (xy 380.843832 -393.692888) (xy 381.155956 -394.232892)
			(xy 381.168693 -394.256208) (xy 381.186785 -394.306157) (xy 381.196 -394.358476) (xy 381.196596 -394.385038)
			(xy 381.196596 -394.385292) (xy 381.196154 -394.409286) (xy 381.188648 -394.456682) (xy 381.17382 -394.50232)
			(xy 381.152035 -394.545077) (xy 381.123829 -394.5839) (xy 381.089897 -394.617831) (xy 381.051074 -394.646037)
			(xy 381.008317 -394.667822) (xy 380.962678 -394.682649) (xy 380.915282 -394.690155) (xy 380.891288 -394.6906)
			(xy 380.867714 -394.690216) (xy 380.821125 -394.682973) (xy 380.776206 -394.668645) (xy 380.734028 -394.647575)
			(xy 380.695595 -394.620264) (xy 380.661823 -394.587363) (xy 380.633518 -394.549656) (xy 380.622048 -394.529056)
			(xy 380.62154 -394.528294) (xy 380.223776 -393.839954) (xy 380.21184 -393.817296) (xy 380.19491 -393.768965)
			(xy 380.186259 -393.718492) (xy 380.185676 -393.692888) (xy 379.643682 -393.692888) (xy 379.955806 -394.232892)
			(xy 379.968628 -394.256226) (xy 379.98685 -394.306248) (xy 379.996111 -394.358674) (xy 379.9967 -394.385292)
			(xy 379.996231 -394.409271) (xy 379.988734 -394.456639) (xy 379.973922 -394.502251) (xy 379.952161 -394.544988)
			(xy 379.923986 -394.583795) (xy 379.890089 -394.617721) (xy 379.851304 -394.645928) (xy 379.808586 -394.667725)
			(xy 379.762986 -394.682574) (xy 379.715624 -394.690111) (xy 379.691646 -394.6906) (xy 379.691138 -394.6906)
			(xy 379.667565 -394.690176) (xy 379.620978 -394.68294) (xy 379.57606 -394.66862) (xy 379.533882 -394.647556)
			(xy 379.495448 -394.620251) (xy 379.461676 -394.587356) (xy 379.433369 -394.549654) (xy 379.421898 -394.529056)
			(xy 379.42139 -394.528294) (xy 379.023626 -393.839954) (xy 379.011765 -393.81727) (xy 378.994909 -393.76894)
			(xy 378.98633 -393.71848) (xy 378.98578 -393.692888) (xy 378.443786 -393.692888) (xy 378.75591 -394.232892)
			(xy 378.768732 -394.256226) (xy 378.786954 -394.306248) (xy 378.796215 -394.358673) (xy 378.796804 -394.385292)
			(xy 378.796331 -394.409271) (xy 378.788834 -394.456638) (xy 378.774023 -394.502251) (xy 378.752262 -394.544986)
			(xy 378.724087 -394.583794) (xy 378.690191 -394.617719) (xy 378.651407 -394.645927) (xy 378.608689 -394.667724)
			(xy 378.563089 -394.682574) (xy 378.515728 -394.690111) (xy 378.49175 -394.6906) (xy 378.491242 -394.6906)
			(xy 378.467669 -394.690172) (xy 378.421083 -394.682937) (xy 378.376165 -394.668617) (xy 378.333986 -394.647554)
			(xy 378.295553 -394.62025) (xy 378.26178 -394.587355) (xy 378.233473 -394.549654) (xy 378.222002 -394.529056)
			(xy 378.221494 -394.528294) (xy 377.82373 -393.839954) (xy 377.811869 -393.81727) (xy 377.795013 -393.76894)
			(xy 377.786434 -393.71848) (xy 377.785884 -393.692888) (xy 377.24389 -393.692888) (xy 377.556014 -394.232892)
			(xy 377.568837 -394.256226) (xy 377.587058 -394.306248) (xy 377.596319 -394.358673) (xy 377.596908 -394.385292)
			(xy 377.596431 -394.40927) (xy 377.588934 -394.456637) (xy 377.574123 -394.50225) (xy 377.552363 -394.544985)
			(xy 377.524188 -394.583793) (xy 377.490292 -394.617718) (xy 377.451509 -394.645926) (xy 377.408792 -394.667723)
			(xy 377.363192 -394.682573) (xy 377.315832 -394.69011) (xy 377.291854 -394.6906) (xy 377.291346 -394.6906)
			(xy 377.267773 -394.690169) (xy 377.221187 -394.682935) (xy 377.176269 -394.668615) (xy 377.134091 -394.647553)
			(xy 377.095657 -394.620249) (xy 377.061884 -394.587355) (xy 377.033577 -394.549654) (xy 377.022106 -394.529056)
			(xy 377.021598 -394.528294) (xy 376.623834 -393.839954) (xy 376.611974 -393.81727) (xy 376.595118 -393.76894)
			(xy 376.586538 -393.71848) (xy 376.585988 -393.692888) (xy 376.04374 -393.692888) (xy 376.355864 -394.232892)
			(xy 376.368602 -394.256207) (xy 376.386693 -394.306157) (xy 376.395908 -394.358476) (xy 376.396504 -394.385038)
			(xy 376.396504 -394.385292) (xy 376.396054 -394.409285) (xy 376.388549 -394.456681) (xy 376.373721 -394.502319)
			(xy 376.351936 -394.545075) (xy 376.323731 -394.583897) (xy 376.2898 -394.617829) (xy 376.250978 -394.646034)
			(xy 376.208222 -394.66782) (xy 376.162585 -394.682648) (xy 376.115189 -394.690154) (xy 376.091196 -394.6906)
			(xy 376.067622 -394.690209) (xy 376.021033 -394.682967) (xy 375.976115 -394.668641) (xy 375.933936 -394.647572)
			(xy 375.895503 -394.620262) (xy 375.861732 -394.587362) (xy 375.833426 -394.549656) (xy 375.821956 -394.529056)
			(xy 375.821448 -394.528294) (xy 375.423684 -393.839954) (xy 375.411748 -393.817296) (xy 375.394819 -393.768965)
			(xy 375.386167 -393.718492) (xy 375.385584 -393.692888) (xy 374.843844 -393.692888) (xy 375.155968 -394.232892)
			(xy 375.168706 -394.256207) (xy 375.186797 -394.306157) (xy 375.196012 -394.358476) (xy 375.196608 -394.385038)
			(xy 375.196608 -394.385292) (xy 375.196154 -394.409285) (xy 375.188649 -394.45668) (xy 375.173821 -394.502318)
			(xy 375.152037 -394.545074) (xy 375.123832 -394.583896) (xy 375.089902 -394.617827) (xy 375.051081 -394.646033)
			(xy 375.008325 -394.667818) (xy 374.962688 -394.682647) (xy 374.915293 -394.690154) (xy 374.8913 -394.6906)
			(xy 374.867726 -394.690206) (xy 374.821138 -394.682965) (xy 374.776219 -394.668639) (xy 374.734041 -394.64757)
			(xy 374.695608 -394.620261) (xy 374.661836 -394.587361) (xy 374.63353 -394.549656) (xy 374.62206 -394.529056)
			(xy 374.621552 -394.528294) (xy 374.223788 -393.839954) (xy 374.211853 -393.817296) (xy 374.194923 -393.768965)
			(xy 374.186271 -393.718491) (xy 374.185688 -393.692888) (xy 373.643694 -393.692888) (xy 373.955818 -394.232892)
			(xy 373.968641 -394.256226) (xy 373.986862 -394.306248) (xy 373.996123 -394.358673) (xy 373.996712 -394.385292)
			(xy 373.996231 -394.40927) (xy 373.988734 -394.456637) (xy 373.973924 -394.502249) (xy 373.952164 -394.544984)
			(xy 373.923989 -394.583791) (xy 373.890094 -394.617716) (xy 373.851311 -394.645924) (xy 373.808595 -394.667722)
			(xy 373.762996 -394.682572) (xy 373.715636 -394.69011) (xy 373.691658 -394.6906) (xy 373.69115 -394.6906)
			(xy 373.667577 -394.690166) (xy 373.620991 -394.682932) (xy 373.576073 -394.668613) (xy 373.533895 -394.647551)
			(xy 373.495461 -394.620248) (xy 373.461688 -394.587354) (xy 373.433381 -394.549653) (xy 373.42191 -394.529056)
			(xy 373.421402 -394.528294) (xy 373.023638 -393.839954) (xy 373.011778 -393.817269) (xy 372.994922 -393.76894)
			(xy 372.986342 -393.71848) (xy 372.985792 -393.692888) (xy 372.443798 -393.692888) (xy 372.755922 -394.232892)
			(xy 372.768745 -394.256225) (xy 372.786966 -394.306248) (xy 372.796227 -394.358673) (xy 372.796816 -394.385292)
			(xy 372.796331 -394.40927) (xy 372.788834 -394.456636) (xy 372.774024 -394.502248) (xy 372.752264 -394.544983)
			(xy 372.72409 -394.58379) (xy 372.690196 -394.617715) (xy 372.651413 -394.645923) (xy 372.608698 -394.66772)
			(xy 372.563099 -394.682571) (xy 372.51574 -394.69011) (xy 372.491762 -394.6906) (xy 372.491254 -394.6906)
			(xy 372.467682 -394.690163) (xy 372.421095 -394.682929) (xy 372.376178 -394.668611) (xy 372.333999 -394.64755)
			(xy 372.295566 -394.620247) (xy 372.261793 -394.587353) (xy 372.233485 -394.549653) (xy 372.222014 -394.529056)
			(xy 372.221506 -394.528294) (xy 371.823742 -393.839954) (xy 371.811882 -393.817269) (xy 371.795026 -393.76894)
			(xy 371.786446 -393.71848) (xy 371.785896 -393.692888) (xy 371.243902 -393.692888) (xy 371.556026 -394.232892)
			(xy 371.56885 -394.256225) (xy 371.587071 -394.306247) (xy 371.596331 -394.358673) (xy 371.59692 -394.385292)
			(xy 371.596431 -394.40927) (xy 371.588935 -394.456636) (xy 371.574124 -394.502247) (xy 371.552365 -394.544982)
			(xy 371.524192 -394.583789) (xy 371.490297 -394.617713) (xy 371.451516 -394.645922) (xy 371.4088 -394.667719)
			(xy 371.363202 -394.68257) (xy 371.315843 -394.69011) (xy 371.291866 -394.6906) (xy 371.291358 -394.6906)
			(xy 371.267786 -394.690159) (xy 371.2212 -394.682927) (xy 371.176282 -394.668609) (xy 371.134104 -394.647548)
			(xy 371.09567 -394.620246) (xy 371.061897 -394.587353) (xy 371.03359 -394.549653) (xy 371.022118 -394.529056)
			(xy 371.02161 -394.528294) (xy 370.623846 -393.839954) (xy 370.611986 -393.817269) (xy 370.59513 -393.76894)
			(xy 370.58655 -393.71848) (xy 370.586 -393.692888) (xy 354.671418 -393.692888) (xy 354.983542 -394.232892)
			(xy 354.996367 -394.256224) (xy 355.014587 -394.306247) (xy 355.023847 -394.358673) (xy 355.024436 -394.385292)
			(xy 355.023931 -394.409269) (xy 355.016435 -394.456633) (xy 355.001626 -394.502243) (xy 354.979868 -394.544977)
			(xy 354.951696 -394.583783) (xy 354.917804 -394.617708) (xy 354.879024 -394.645916) (xy 354.836311 -394.667715)
			(xy 354.790716 -394.682567) (xy 354.743358 -394.690108) (xy 354.719382 -394.6906) (xy 354.718874 -394.6906)
			(xy 354.695299 -394.690227) (xy 354.64871 -394.682982) (xy 354.603791 -394.668652) (xy 354.561613 -394.64758)
			(xy 354.52318 -394.620267) (xy 354.489409 -394.587365) (xy 354.461104 -394.549657) (xy 354.449634 -394.529056)
			(xy 354.449126 -394.528294) (xy 354.051362 -393.839954) (xy 354.039504 -393.817268) (xy 354.022646 -393.76894)
			(xy 354.014066 -393.71848) (xy 354.013516 -393.692888) (xy 353.471522 -393.692888) (xy 353.783646 -394.232892)
			(xy 353.796471 -394.256224) (xy 353.814691 -394.306247) (xy 353.823951 -394.358673) (xy 353.82454 -394.385292)
			(xy 353.824031 -394.409269) (xy 353.816535 -394.456633) (xy 353.801726 -394.502242) (xy 353.779969 -394.544976)
			(xy 353.751798 -394.583782) (xy 353.717906 -394.617706) (xy 353.679127 -394.645915) (xy 353.636414 -394.667714)
			(xy 353.590819 -394.682566) (xy 353.543462 -394.690108) (xy 353.519486 -394.6906) (xy 353.518978 -394.6906)
			(xy 353.495403 -394.690224) (xy 353.448814 -394.682979) (xy 353.403895 -394.66865) (xy 353.361717 -394.647579)
			(xy 353.323284 -394.620266) (xy 353.289513 -394.587364) (xy 353.261208 -394.549657) (xy 353.249738 -394.529056)
			(xy 353.24923 -394.528294) (xy 352.851466 -393.839954) (xy 352.839608 -393.817268) (xy 352.82275 -393.76894)
			(xy 352.81417 -393.71848) (xy 352.81362 -393.692888) (xy 352.271372 -393.692888) (xy 352.583496 -394.232892)
			(xy 352.596228 -394.25621) (xy 352.614323 -394.306158) (xy 352.623539 -394.358477) (xy 352.624136 -394.385038)
			(xy 352.624136 -394.385292) (xy 352.62363 -394.409282) (xy 352.616126 -394.45667) (xy 352.601301 -394.502302)
			(xy 352.579521 -394.545053) (xy 352.551322 -394.58387) (xy 352.517397 -394.617798) (xy 352.478583 -394.646002)
			(xy 352.435835 -394.667788) (xy 352.390205 -394.682618) (xy 352.342818 -394.690127) (xy 352.318828 -394.6906)
			(xy 352.295255 -394.690184) (xy 352.248668 -394.682946) (xy 352.20375 -394.668625) (xy 352.161571 -394.64756)
			(xy 352.123138 -394.620254) (xy 352.089365 -394.587357) (xy 352.061059 -394.549654) (xy 352.049588 -394.529056)
			(xy 352.04908 -394.528294) (xy 351.651316 -393.839954) (xy 351.639383 -393.817294) (xy 351.622452 -393.768965)
			(xy 351.613799 -393.718491) (xy 351.613216 -393.692888) (xy 351.071476 -393.692888) (xy 351.3836 -394.232892)
			(xy 351.396333 -394.25621) (xy 351.414427 -394.306158) (xy 351.423643 -394.358477) (xy 351.42424 -394.385038)
			(xy 351.42424 -394.385292) (xy 351.42373 -394.409281) (xy 351.416226 -394.45667) (xy 351.401402 -394.502301)
			(xy 351.379622 -394.545051) (xy 351.351423 -394.583869) (xy 351.317499 -394.617797) (xy 351.278686 -394.646001)
			(xy 351.235938 -394.667787) (xy 351.190309 -394.682617) (xy 351.142921 -394.690127) (xy 351.118932 -394.6906)
			(xy 351.095359 -394.69018) (xy 351.048772 -394.682944) (xy 351.003854 -394.668623) (xy 350.961675 -394.647558)
			(xy 350.923242 -394.620253) (xy 350.88947 -394.587357) (xy 350.861163 -394.549654) (xy 350.849692 -394.529056)
			(xy 350.849184 -394.528294) (xy 350.45142 -393.839954) (xy 350.439487 -393.817294) (xy 350.422556 -393.768965)
			(xy 350.413903 -393.718491) (xy 350.41332 -393.692888) (xy 349.871326 -393.692888) (xy 350.18345 -394.232892)
			(xy 350.196276 -394.256224) (xy 350.214495 -394.306247) (xy 350.223755 -394.358673) (xy 350.224344 -394.385292)
			(xy 350.223831 -394.409269) (xy 350.216335 -394.456632) (xy 350.201527 -394.502241) (xy 350.179769 -394.544974)
			(xy 350.151599 -394.58378) (xy 350.117707 -394.617705) (xy 350.078929 -394.645913) (xy 350.036217 -394.667712)
			(xy 349.990622 -394.682566) (xy 349.943266 -394.690108) (xy 349.91929 -394.6906) (xy 349.918782 -394.6906)
			(xy 349.895207 -394.690221) (xy 349.848619 -394.682977) (xy 349.8037 -394.668648) (xy 349.761521 -394.647577)
			(xy 349.723088 -394.620265) (xy 349.689317 -394.587364) (xy 349.661012 -394.549657) (xy 349.649542 -394.529056)
			(xy 349.649034 -394.528294) (xy 349.25127 -393.839954) (xy 349.239412 -393.817268) (xy 349.222555 -393.768939)
			(xy 349.213974 -393.71848) (xy 349.213424 -393.692888) (xy 348.67143 -393.692888) (xy 348.983554 -394.232892)
			(xy 348.99638 -394.256224) (xy 349.014599 -394.306247) (xy 349.023859 -394.358673) (xy 349.024448 -394.385292)
			(xy 349.023931 -394.409268) (xy 349.016436 -394.456632) (xy 349.001627 -394.50224) (xy 348.97987 -394.544973)
			(xy 348.9517 -394.583779) (xy 348.917809 -394.617703) (xy 348.879031 -394.645912) (xy 348.83632 -394.667711)
			(xy 348.790726 -394.682565) (xy 348.74337 -394.690107) (xy 348.719394 -394.6906) (xy 348.718886 -394.6906)
			(xy 348.695312 -394.690217) (xy 348.648723 -394.682974) (xy 348.603804 -394.668646) (xy 348.561626 -394.647576)
			(xy 348.523193 -394.620264) (xy 348.489421 -394.587363) (xy 348.461116 -394.549656) (xy 348.449646 -394.529056)
			(xy 348.449138 -394.528294) (xy 348.051374 -393.839954) (xy 348.039517 -393.817268) (xy 348.022659 -393.768939)
			(xy 348.014078 -393.718479) (xy 348.013528 -393.692888) (xy 347.47128 -393.692888) (xy 347.783404 -394.232892)
			(xy 347.796137 -394.25621) (xy 347.814231 -394.306158) (xy 347.823447 -394.358477) (xy 347.824044 -394.385038)
			(xy 347.824044 -394.385292) (xy 347.82353 -394.409281) (xy 347.816026 -394.456669) (xy 347.801202 -394.5023)
			(xy 347.779423 -394.54505) (xy 347.751224 -394.583867) (xy 347.717301 -394.617796) (xy 347.678488 -394.646)
			(xy 347.635741 -394.667785) (xy 347.590112 -394.682616) (xy 347.542725 -394.690127) (xy 347.518736 -394.6906)
			(xy 347.495163 -394.690177) (xy 347.448576 -394.682941) (xy 347.403658 -394.668621) (xy 347.36148 -394.647557)
			(xy 347.323046 -394.620252) (xy 347.289274 -394.587356) (xy 347.260967 -394.549654) (xy 347.249496 -394.529056)
			(xy 347.248988 -394.528294) (xy 346.851224 -393.839954) (xy 346.839292 -393.817294) (xy 346.82236 -393.768965)
			(xy 346.813707 -393.718491) (xy 346.813124 -393.692888) (xy 346.271384 -393.692888) (xy 346.583508 -394.232892)
			(xy 346.596241 -394.25621) (xy 346.614335 -394.306158) (xy 346.623551 -394.358477) (xy 346.624148 -394.385038)
			(xy 346.624148 -394.385292) (xy 346.62363 -394.409281) (xy 346.616126 -394.456669) (xy 346.601303 -394.502299)
			(xy 346.579524 -394.545049) (xy 346.551325 -394.583866) (xy 346.517403 -394.617794) (xy 346.47859 -394.645998)
			(xy 346.435843 -394.667784) (xy 346.390215 -394.682615) (xy 346.342829 -394.690126) (xy 346.31884 -394.6906)
			(xy 346.295267 -394.690174) (xy 346.24868 -394.682939) (xy 346.203763 -394.668618) (xy 346.161584 -394.647555)
			(xy 346.123151 -394.620251) (xy 346.089378 -394.587355) (xy 346.061071 -394.549654) (xy 346.0496 -394.529056)
			(xy 346.049092 -394.528294) (xy 345.651328 -393.839954) (xy 345.639396 -393.817294) (xy 345.622464 -393.768965)
			(xy 345.613811 -393.718491) (xy 345.613228 -393.692888) (xy 345.071488 -393.692888) (xy 345.383612 -394.232892)
			(xy 345.396346 -394.25621) (xy 345.414439 -394.306158) (xy 345.423655 -394.358477) (xy 345.424252 -394.385038)
			(xy 345.424252 -394.385292) (xy 345.42373 -394.409281) (xy 345.416227 -394.456668) (xy 345.401403 -394.502298)
			(xy 345.379624 -394.545048) (xy 345.351427 -394.583865) (xy 345.317504 -394.617793) (xy 345.278692 -394.645997)
			(xy 345.235946 -394.667783) (xy 345.190319 -394.682614) (xy 345.142933 -394.690126) (xy 345.118944 -394.6906)
			(xy 345.095371 -394.690171) (xy 345.048785 -394.682936) (xy 345.003867 -394.668616) (xy 344.961689 -394.647554)
			(xy 344.923255 -394.620249) (xy 344.889482 -394.587355) (xy 344.861175 -394.549654) (xy 344.849704 -394.529056)
			(xy 344.849196 -394.528294) (xy 344.451432 -393.839954) (xy 344.4395 -393.817294) (xy 344.422568 -393.768965)
			(xy 344.413915 -393.718491) (xy 344.413332 -393.692888) (xy 343.871338 -393.692888) (xy 344.183462 -394.232892)
			(xy 344.196289 -394.256224) (xy 344.214508 -394.306247) (xy 344.223767 -394.358673) (xy 344.224356 -394.385292)
			(xy 344.223831 -394.409268) (xy 344.216336 -394.45663) (xy 344.201528 -394.502239) (xy 344.179772 -394.544971)
			(xy 344.151602 -394.583776) (xy 344.117712 -394.617701) (xy 344.078935 -394.645909) (xy 344.036225 -394.667709)
			(xy 343.990632 -394.682563) (xy 343.943277 -394.690107) (xy 343.919302 -394.6906) (xy 343.918794 -394.6906)
			(xy 343.89522 -394.690211) (xy 343.848631 -394.682969) (xy 343.803713 -394.668642) (xy 343.761534 -394.647573)
			(xy 343.723101 -394.620262) (xy 343.68933 -394.587362) (xy 343.661024 -394.549656) (xy 343.649554 -394.529056)
			(xy 343.649046 -394.528294) (xy 343.251282 -393.839954) (xy 343.239425 -393.817268) (xy 343.222567 -393.768939)
			(xy 343.213986 -393.718479) (xy 343.213436 -393.692888) (xy 342.671442 -393.692888) (xy 342.983566 -394.232892)
			(xy 342.996393 -394.256223) (xy 343.014612 -394.306247) (xy 343.023871 -394.358673) (xy 343.02446 -394.385292)
			(xy 343.024031 -394.409273) (xy 343.016532 -394.456644) (xy 343.001719 -394.502261) (xy 342.979954 -394.544999)
			(xy 342.951774 -394.583809) (xy 342.917872 -394.617735) (xy 342.879082 -394.645942) (xy 342.836359 -394.667737)
			(xy 342.790753 -394.682582) (xy 342.743386 -394.690114) (xy 342.719406 -394.6906) (xy 342.718898 -394.6906)
			(xy 342.695324 -394.690208) (xy 342.648736 -394.682966) (xy 342.603817 -394.66864) (xy 342.561639 -394.647571)
			(xy 342.523206 -394.620261) (xy 342.489434 -394.587361) (xy 342.461128 -394.549656) (xy 342.449658 -394.529056)
			(xy 342.44915 -394.528294) (xy 342.051386 -393.839954) (xy 342.03953 -393.817267) (xy 342.022671 -393.768939)
			(xy 342.01409 -393.718479) (xy 342.01354 -393.692888) (xy 341.471292 -393.692888) (xy 341.783416 -394.232892)
			(xy 341.79615 -394.256209) (xy 341.814243 -394.306158) (xy 341.823459 -394.358477) (xy 341.824056 -394.385038)
			(xy 341.824056 -394.385292) (xy 341.82353 -394.409281) (xy 341.816027 -394.456667) (xy 341.801203 -394.502297)
			(xy 341.779425 -394.545047) (xy 341.751228 -394.583863) (xy 341.717306 -394.617791) (xy 341.678494 -394.645996)
			(xy 341.635749 -394.667782) (xy 341.590122 -394.682614) (xy 341.542737 -394.690126) (xy 341.518748 -394.6906)
			(xy 341.495175 -394.690168) (xy 341.448589 -394.682933) (xy 341.403671 -394.668614) (xy 341.361493 -394.647552)
			(xy 341.323059 -394.620248) (xy 341.289286 -394.587354) (xy 341.260979 -394.549654) (xy 341.249508 -394.529056)
			(xy 341.249 -394.528294) (xy 340.851236 -393.839954) (xy 340.839305 -393.817294) (xy 340.822372 -393.768964)
			(xy 340.813719 -393.718491) (xy 340.813136 -393.692888) (xy 340.271396 -393.692888) (xy 340.58352 -394.232892)
			(xy 340.596254 -394.256209) (xy 340.614348 -394.306158) (xy 340.623563 -394.358476) (xy 340.62416 -394.385038)
			(xy 340.62416 -394.385292) (xy 340.623754 -394.409287) (xy 340.616247 -394.456687) (xy 340.601417 -394.502329)
			(xy 340.579628 -394.545088) (xy 340.551418 -394.583912) (xy 340.517482 -394.617844) (xy 340.478654 -394.646049)
			(xy 340.435892 -394.667832) (xy 340.390248 -394.682657) (xy 340.342847 -394.690157) (xy 340.318852 -394.6906)
			(xy 340.295279 -394.690164) (xy 340.248693 -394.682931) (xy 340.203776 -394.668612) (xy 340.161597 -394.647551)
			(xy 340.123164 -394.620247) (xy 340.089391 -394.587354) (xy 340.061083 -394.549653) (xy 340.049612 -394.529056)
			(xy 340.049104 -394.528294) (xy 339.65134 -393.839954) (xy 339.639409 -393.817293) (xy 339.622476 -393.768964)
			(xy 339.613823 -393.718491) (xy 339.61324 -393.692888) (xy 339.0715 -393.692888) (xy 339.383624 -394.232892)
			(xy 339.396359 -394.256209) (xy 339.414452 -394.306158) (xy 339.423667 -394.358476) (xy 339.424264 -394.385038)
			(xy 339.424264 -394.385292) (xy 339.423854 -394.409287) (xy 339.416347 -394.456687) (xy 339.401517 -394.502328)
			(xy 339.379729 -394.545087) (xy 339.351519 -394.583911) (xy 339.317583 -394.617843) (xy 339.278756 -394.646048)
			(xy 339.235995 -394.667831) (xy 339.190352 -394.682656) (xy 339.142951 -394.690157) (xy 339.118956 -394.6906)
			(xy 339.095384 -394.690161) (xy 339.048797 -394.682928) (xy 339.00388 -394.66861) (xy 338.961702 -394.647549)
			(xy 338.923268 -394.620246) (xy 338.889495 -394.587353) (xy 338.861187 -394.549653) (xy 338.849716 -394.529056)
			(xy 338.849208 -394.528294) (xy 338.451444 -393.839954) (xy 338.439513 -393.817293) (xy 338.42258 -393.768964)
			(xy 338.413927 -393.718491) (xy 338.413344 -393.692888) (xy 337.87135 -393.692888) (xy 338.183474 -394.232892)
			(xy 338.196301 -394.256223) (xy 338.21452 -394.306247) (xy 338.223779 -394.358673) (xy 338.224368 -394.385292)
			(xy 338.223931 -394.409272) (xy 338.216433 -394.456643) (xy 338.201619 -394.502259) (xy 338.179855 -394.544997)
			(xy 338.151676 -394.583806) (xy 338.117775 -394.617732) (xy 338.078987 -394.645939) (xy 338.036264 -394.667734)
			(xy 337.990659 -394.682581) (xy 337.943294 -394.690113) (xy 337.919314 -394.6906) (xy 337.918806 -394.6906)
			(xy 337.895232 -394.690201) (xy 337.848644 -394.682961) (xy 337.803726 -394.668636) (xy 337.761547 -394.647568)
			(xy 337.723114 -394.620259) (xy 337.689342 -394.58736) (xy 337.661037 -394.549655) (xy 337.649566 -394.529056)
			(xy 337.649058 -394.528294) (xy 337.251294 -393.839954) (xy 337.239438 -393.817267) (xy 337.222579 -393.768939)
			(xy 337.213998 -393.718479) (xy 337.213448 -393.692888) (xy 336.671454 -393.692888) (xy 336.983578 -394.232892)
			(xy 336.996406 -394.256223) (xy 337.014624 -394.306247) (xy 337.023883 -394.358673) (xy 337.024472 -394.385292)
			(xy 337.024031 -394.409272) (xy 337.016533 -394.456643) (xy 337.00172 -394.502258) (xy 336.979956 -394.544996)
			(xy 336.951778 -394.583805) (xy 336.917877 -394.617731) (xy 336.879089 -394.645938) (xy 336.836367 -394.667733)
			(xy 336.790763 -394.68258) (xy 336.743398 -394.690113) (xy 336.719418 -394.6906) (xy 336.71891 -394.6906)
			(xy 336.695336 -394.690198) (xy 336.648748 -394.682958) (xy 336.60383 -394.668634) (xy 336.561652 -394.647566)
			(xy 336.523218 -394.620258) (xy 336.489447 -394.58736) (xy 336.461141 -394.549655) (xy 336.44967 -394.529056)
			(xy 336.449162 -394.528294) (xy 336.051398 -393.839954) (xy 336.039542 -393.817267) (xy 336.022683 -393.768939)
			(xy 336.014102 -393.718479) (xy 336.013552 -393.692888) (xy 322.14367 -393.692888) (xy 322.455794 -394.232892)
			(xy 322.468623 -394.256222) (xy 322.486841 -394.306246) (xy 322.496099 -394.358673) (xy 322.496688 -394.385292)
			(xy 322.496231 -394.409271) (xy 322.488733 -394.45664) (xy 322.473921 -394.502254) (xy 322.452159 -394.544991)
			(xy 322.423982 -394.5838) (xy 322.390084 -394.617725) (xy 322.351298 -394.645932) (xy 322.308578 -394.667728)
			(xy 322.262976 -394.682577) (xy 322.215613 -394.690112) (xy 322.191634 -394.6906) (xy 322.191126 -394.6906)
			(xy 322.167553 -394.690185) (xy 322.120965 -394.682948) (xy 322.076047 -394.668626) (xy 322.033869 -394.64756)
			(xy 321.995436 -394.620254) (xy 321.961663 -394.587357) (xy 321.933357 -394.549655) (xy 321.921886 -394.529056)
			(xy 321.921378 -394.528294) (xy 321.523614 -393.839954) (xy 321.511752 -393.81727) (xy 321.494897 -393.76894)
			(xy 321.486317 -393.71848) (xy 321.485768 -393.692888) (xy 320.943774 -393.692888) (xy 321.255898 -394.232892)
			(xy 321.268719 -394.256226) (xy 321.286942 -394.306248) (xy 321.296203 -394.358674) (xy 321.296792 -394.385292)
			(xy 321.296331 -394.409271) (xy 321.288834 -394.45664) (xy 321.274022 -394.502253) (xy 321.25226 -394.54499)
			(xy 321.224083 -394.583798) (xy 321.190186 -394.617723) (xy 321.1514 -394.645931) (xy 321.108681 -394.667727)
			(xy 321.063079 -394.682576) (xy 321.015717 -394.690112) (xy 320.991738 -394.6906) (xy 320.99123 -394.6906)
			(xy 320.967657 -394.690182) (xy 320.92107 -394.682945) (xy 320.876152 -394.668624) (xy 320.833973 -394.647559)
			(xy 320.79554 -394.620253) (xy 320.761768 -394.587357) (xy 320.733461 -394.549654) (xy 320.72199 -394.529056)
			(xy 320.721482 -394.528294) (xy 320.323718 -393.839954) (xy 320.311856 -393.81727) (xy 320.295001 -393.76894)
			(xy 320.286421 -393.71848) (xy 320.285872 -393.692888) (xy 319.743878 -393.692888) (xy 320.056002 -394.232892)
			(xy 320.068824 -394.256226) (xy 320.087046 -394.306248) (xy 320.096307 -394.358674) (xy 320.096896 -394.385292)
			(xy 320.096453 -394.409298) (xy 320.08894 -394.456719) (xy 320.074096 -394.502379) (xy 320.052288 -394.545153)
			(xy 320.024055 -394.583987) (xy 319.99009 -394.617922) (xy 319.951233 -394.646123) (xy 319.908441 -394.667895)
			(xy 319.862768 -394.6827) (xy 319.815341 -394.690174) (xy 319.791334 -394.6906) (xy 319.79108 -394.6906)
			(xy 319.767505 -394.690222) (xy 319.720916 -394.682978) (xy 319.675997 -394.668649) (xy 319.633819 -394.647578)
			(xy 319.595386 -394.620266) (xy 319.561615 -394.587364) (xy 319.53331 -394.549657) (xy 319.52184 -394.529056)
			(xy 319.521332 -394.528294) (xy 319.123568 -393.839954) (xy 319.111639 -393.817292) (xy 319.094706 -393.768964)
			(xy 319.086052 -393.718491) (xy 319.085468 -393.692888) (xy 318.543728 -393.692888) (xy 318.855852 -394.232892)
			(xy 318.868589 -394.256208) (xy 318.886681 -394.306157) (xy 318.895896 -394.358476) (xy 318.896492 -394.385038)
			(xy 318.896492 -394.385292) (xy 318.896054 -394.409286) (xy 318.888548 -394.456682) (xy 318.87372 -394.502321)
			(xy 318.851934 -394.545079) (xy 318.823728 -394.583901) (xy 318.789795 -394.617833) (xy 318.750972 -394.646038)
			(xy 318.708214 -394.667823) (xy 318.662575 -394.68265) (xy 318.615178 -394.690155) (xy 318.591184 -394.6906)
			(xy 318.56761 -394.690219) (xy 318.521021 -394.682975) (xy 318.476102 -394.668647) (xy 318.433923 -394.647576)
			(xy 318.395491 -394.620265) (xy 318.361719 -394.587363) (xy 318.333414 -394.549656) (xy 318.321944 -394.529056)
			(xy 318.321436 -394.528294) (xy 317.923672 -393.839954) (xy 317.911736 -393.817296) (xy 317.894806 -393.768965)
			(xy 317.886155 -393.718492) (xy 317.885572 -393.692888) (xy 317.343832 -393.692888) (xy 317.655956 -394.232892)
			(xy 317.668693 -394.256208) (xy 317.686785 -394.306157) (xy 317.696 -394.358476) (xy 317.696596 -394.385038)
			(xy 317.696596 -394.385292) (xy 317.696154 -394.409286) (xy 317.688648 -394.456682) (xy 317.67382 -394.50232)
			(xy 317.652035 -394.545077) (xy 317.623829 -394.5839) (xy 317.589897 -394.617831) (xy 317.551074 -394.646037)
			(xy 317.508317 -394.667822) (xy 317.462678 -394.682649) (xy 317.415282 -394.690155) (xy 317.391288 -394.6906)
			(xy 317.391034 -394.6906) (xy 317.367461 -394.690179) (xy 317.320874 -394.682942) (xy 317.275956 -394.668622)
			(xy 317.233778 -394.647557) (xy 317.195344 -394.620252) (xy 317.161572 -394.587356) (xy 317.133265 -394.549654)
			(xy 317.121794 -394.529056) (xy 317.121286 -394.528294) (xy 316.723522 -393.839954) (xy 316.711661 -393.81727)
			(xy 316.694805 -393.76894) (xy 316.686226 -393.71848) (xy 316.685676 -393.692888) (xy 316.143682 -393.692888)
			(xy 316.455806 -394.232892) (xy 316.468628 -394.256226) (xy 316.48685 -394.306248) (xy 316.496111 -394.358674)
			(xy 316.4967 -394.385292) (xy 316.496231 -394.409271) (xy 316.488734 -394.456639) (xy 316.473922 -394.502251)
			(xy 316.452161 -394.544988) (xy 316.423986 -394.583795) (xy 316.390089 -394.617721) (xy 316.351304 -394.645928)
			(xy 316.308586 -394.667725) (xy 316.262986 -394.682574) (xy 316.215624 -394.690111) (xy 316.191646 -394.6906)
			(xy 316.191138 -394.6906) (xy 316.167565 -394.690176) (xy 316.120978 -394.68294) (xy 316.07606 -394.66862)
			(xy 316.033882 -394.647556) (xy 315.995448 -394.620251) (xy 315.961676 -394.587356) (xy 315.933369 -394.549654)
			(xy 315.921898 -394.529056) (xy 315.92139 -394.528294) (xy 315.523626 -393.839954) (xy 315.511765 -393.81727)
			(xy 315.494909 -393.76894) (xy 315.48633 -393.71848) (xy 315.48578 -393.692888) (xy 314.943786 -393.692888)
			(xy 315.25591 -394.232892) (xy 315.268732 -394.256226) (xy 315.286954 -394.306248) (xy 315.296215 -394.358673)
			(xy 315.296804 -394.385292) (xy 315.296354 -394.409298) (xy 315.28884 -394.456718) (xy 315.273997 -394.502377)
			(xy 315.25219 -394.545151) (xy 315.223957 -394.583984) (xy 315.189994 -394.61792) (xy 315.151137 -394.646121)
			(xy 315.108346 -394.667893) (xy 315.062674 -394.682698) (xy 315.015248 -394.690173) (xy 314.991242 -394.6906)
			(xy 314.990988 -394.6906) (xy 314.967414 -394.690216) (xy 314.920825 -394.682973) (xy 314.875906 -394.668645)
			(xy 314.833728 -394.647575) (xy 314.795295 -394.620264) (xy 314.761523 -394.587363) (xy 314.733218 -394.549656)
			(xy 314.721748 -394.529056) (xy 314.72124 -394.528294) (xy 314.323476 -393.839954) (xy 314.31154 -393.817296)
			(xy 314.29461 -393.768965) (xy 314.285959 -393.718492) (xy 314.285376 -393.692888) (xy 313.74389 -393.692888)
			(xy 314.056014 -394.232892) (xy 314.068837 -394.256226) (xy 314.087058 -394.306248) (xy 314.096319 -394.358673)
			(xy 314.096908 -394.385292) (xy 314.096454 -394.409298) (xy 314.08894 -394.456717) (xy 314.074097 -394.502377)
			(xy 314.052291 -394.54515) (xy 314.024058 -394.583983) (xy 313.990095 -394.617918) (xy 313.95124 -394.646119)
			(xy 313.908449 -394.667891) (xy 313.862778 -394.682698) (xy 313.815352 -394.690173) (xy 313.791346 -394.6906)
			(xy 313.791092 -394.6906) (xy 313.767518 -394.690213) (xy 313.720929 -394.68297) (xy 313.67601 -394.668643)
			(xy 313.633832 -394.647573) (xy 313.595399 -394.620263) (xy 313.561628 -394.587362) (xy 313.533322 -394.549656)
			(xy 313.521852 -394.529056) (xy 313.521344 -394.528294) (xy 313.12358 -393.839954) (xy 313.111644 -393.817296)
			(xy 313.094715 -393.768965) (xy 313.086063 -393.718492) (xy 313.08548 -393.692888) (xy 312.54374 -393.692888)
			(xy 312.855864 -394.232892) (xy 312.868602 -394.256207) (xy 312.886693 -394.306157) (xy 312.895908 -394.358476)
			(xy 312.896504 -394.385038) (xy 312.896504 -394.385292) (xy 312.896054 -394.409285) (xy 312.888549 -394.456681)
			(xy 312.873721 -394.502319) (xy 312.851936 -394.545075) (xy 312.823731 -394.583897) (xy 312.7898 -394.617829)
			(xy 312.750978 -394.646034) (xy 312.708222 -394.66782) (xy 312.662585 -394.682648) (xy 312.615189 -394.690154)
			(xy 312.591196 -394.6906) (xy 312.590942 -394.6906) (xy 312.567369 -394.690172) (xy 312.520783 -394.682937)
			(xy 312.475865 -394.668617) (xy 312.433686 -394.647554) (xy 312.395253 -394.62025) (xy 312.36148 -394.587355)
			(xy 312.333173 -394.549654) (xy 312.321702 -394.529056) (xy 312.321194 -394.528294) (xy 311.92343 -393.839954)
			(xy 311.911569 -393.81727) (xy 311.894713 -393.76894) (xy 311.886134 -393.71848) (xy 311.885584 -393.692888)
			(xy 311.34359 -393.692888) (xy 311.655714 -394.232892) (xy 311.668537 -394.256226) (xy 311.686758 -394.306248)
			(xy 311.696019 -394.358673) (xy 311.696608 -394.385292) (xy 311.696131 -394.40927) (xy 311.688634 -394.456637)
			(xy 311.673823 -394.50225) (xy 311.652063 -394.544985) (xy 311.623888 -394.583793) (xy 311.589992 -394.617718)
			(xy 311.551209 -394.645926) (xy 311.508492 -394.667723) (xy 311.462892 -394.682573) (xy 311.415532 -394.69011)
			(xy 311.391554 -394.6906) (xy 311.391046 -394.6906) (xy 311.367473 -394.690169) (xy 311.320887 -394.682935)
			(xy 311.275969 -394.668615) (xy 311.233791 -394.647553) (xy 311.195357 -394.620249) (xy 311.161584 -394.587355)
			(xy 311.133277 -394.549654) (xy 311.121806 -394.529056) (xy 311.121298 -394.528294) (xy 310.723534 -393.839954)
			(xy 310.711674 -393.81727) (xy 310.694818 -393.76894) (xy 310.686238 -393.71848) (xy 310.685688 -393.692888)
			(xy 310.143694 -393.692888) (xy 310.455818 -394.232892) (xy 310.468641 -394.256226) (xy 310.486862 -394.306248)
			(xy 310.496123 -394.358673) (xy 310.496712 -394.385292) (xy 310.496231 -394.40927) (xy 310.488734 -394.456637)
			(xy 310.473924 -394.502249) (xy 310.452164 -394.544984) (xy 310.423989 -394.583791) (xy 310.390094 -394.617716)
			(xy 310.351311 -394.645924) (xy 310.308595 -394.667722) (xy 310.262996 -394.682572) (xy 310.215636 -394.69011)
			(xy 310.191658 -394.6906) (xy 310.19115 -394.6906) (xy 310.167577 -394.690166) (xy 310.120991 -394.682932)
			(xy 310.076073 -394.668613) (xy 310.033895 -394.647551) (xy 309.995461 -394.620248) (xy 309.961688 -394.587354)
			(xy 309.933381 -394.549653) (xy 309.92191 -394.529056) (xy 309.921402 -394.528294) (xy 309.523638 -393.839954)
			(xy 309.511778 -393.817269) (xy 309.494922 -393.76894) (xy 309.486342 -393.71848) (xy 309.485792 -393.692888)
			(xy 308.943544 -393.692888) (xy 309.255668 -394.232892) (xy 309.268406 -394.256207) (xy 309.286497 -394.306157)
			(xy 309.295712 -394.358476) (xy 309.296308 -394.385038) (xy 309.296308 -394.385292) (xy 309.295854 -394.409285)
			(xy 309.288349 -394.45668) (xy 309.273521 -394.502318) (xy 309.251737 -394.545074) (xy 309.223532 -394.583896)
			(xy 309.189602 -394.617827) (xy 309.150781 -394.646033) (xy 309.108025 -394.667818) (xy 309.062388 -394.682647)
			(xy 309.014993 -394.690154) (xy 308.991 -394.6906) (xy 308.967426 -394.690206) (xy 308.920838 -394.682965)
			(xy 308.875919 -394.668639) (xy 308.833741 -394.64757) (xy 308.795308 -394.620261) (xy 308.761536 -394.587361)
			(xy 308.73323 -394.549656) (xy 308.72176 -394.529056) (xy 308.721252 -394.528294) (xy 308.323488 -393.839954)
			(xy 308.311553 -393.817296) (xy 308.294623 -393.768965) (xy 308.285971 -393.718491) (xy 308.285388 -393.692888)
			(xy 307.743648 -393.692888) (xy 308.055772 -394.232892) (xy 308.068511 -394.256207) (xy 308.086601 -394.306157)
			(xy 308.095816 -394.358476) (xy 308.096412 -394.385038) (xy 308.096412 -394.385292) (xy 308.095954 -394.409285)
			(xy 308.088449 -394.45668) (xy 308.073622 -394.502317) (xy 308.051838 -394.545073) (xy 308.023634 -394.583894)
			(xy 307.989703 -394.617826) (xy 307.950883 -394.646032) (xy 307.908128 -394.667817) (xy 307.862491 -394.682646)
			(xy 307.815097 -394.690154) (xy 307.791104 -394.6906) (xy 307.76753 -394.690203) (xy 307.720942 -394.682962)
			(xy 307.676023 -394.668637) (xy 307.633845 -394.647569) (xy 307.595412 -394.62026) (xy 307.56164 -394.587361)
			(xy 307.533335 -394.549656) (xy 307.521864 -394.529056) (xy 307.521356 -394.528294) (xy 307.123592 -393.839954)
			(xy 307.111657 -393.817295) (xy 307.094727 -393.768965) (xy 307.086075 -393.718491) (xy 307.085492 -393.692888)
			(xy 306.543752 -393.692888) (xy 306.855876 -394.232892) (xy 306.868615 -394.256207) (xy 306.886705 -394.306157)
			(xy 306.89592 -394.358476) (xy 306.896516 -394.385038) (xy 306.896516 -394.385292) (xy 306.89603 -394.409283)
			(xy 306.888525 -394.456673) (xy 306.8737 -394.502306) (xy 306.851918 -394.545059) (xy 306.823716 -394.583877)
			(xy 306.789789 -394.617806) (xy 306.750972 -394.646009) (xy 306.708221 -394.667793) (xy 306.662589 -394.682622)
			(xy 306.615199 -394.690129) (xy 306.591208 -394.6906) (xy 306.590954 -394.6906) (xy 306.567382 -394.690163)
			(xy 306.520795 -394.682929) (xy 306.475878 -394.668611) (xy 306.433699 -394.64755) (xy 306.395266 -394.620247)
			(xy 306.361493 -394.587353) (xy 306.333185 -394.549653) (xy 306.321714 -394.529056) (xy 306.321206 -394.528294)
			(xy 305.923442 -393.839954) (xy 305.911582 -393.817269) (xy 305.894726 -393.76894) (xy 305.886146 -393.71848)
			(xy 305.885596 -393.692888) (xy 305.343602 -393.692888) (xy 305.655726 -394.232892) (xy 305.66855 -394.256225)
			(xy 305.686771 -394.306247) (xy 305.696031 -394.358673) (xy 305.69662 -394.385292) (xy 305.696131 -394.40927)
			(xy 305.688635 -394.456636) (xy 305.673824 -394.502247) (xy 305.652065 -394.544982) (xy 305.623892 -394.583789)
			(xy 305.589997 -394.617713) (xy 305.551216 -394.645922) (xy 305.5085 -394.667719) (xy 305.462902 -394.68257)
			(xy 305.415543 -394.69011) (xy 305.391566 -394.6906) (xy 305.391058 -394.6906) (xy 305.367486 -394.690159)
			(xy 305.3209 -394.682927) (xy 305.275982 -394.668609) (xy 305.233804 -394.647548) (xy 305.19537 -394.620246)
			(xy 305.161597 -394.587353) (xy 305.13329 -394.549653) (xy 305.121818 -394.529056) (xy 305.12131 -394.528294)
			(xy 304.723546 -393.839954) (xy 304.711686 -393.817269) (xy 304.69483 -393.76894) (xy 304.68625 -393.71848)
			(xy 304.6857 -393.692888) (xy 304.143706 -393.692888) (xy 304.45583 -394.232892) (xy 304.468654 -394.256225)
			(xy 304.486875 -394.306247) (xy 304.496135 -394.358673) (xy 304.496724 -394.385292) (xy 304.496231 -394.40927)
			(xy 304.488735 -394.456635) (xy 304.473925 -394.502246) (xy 304.452166 -394.54498) (xy 304.423993 -394.583787)
			(xy 304.390099 -394.617712) (xy 304.351318 -394.64592) (xy 304.308603 -394.667718) (xy 304.263006 -394.68257)
			(xy 304.215647 -394.690109) (xy 304.19167 -394.6906) (xy 304.191162 -394.6906) (xy 304.16759 -394.690156)
			(xy 304.121004 -394.682924) (xy 304.076086 -394.668607) (xy 304.033908 -394.647547) (xy 303.995474 -394.620245)
			(xy 303.961701 -394.587352) (xy 303.933394 -394.549653) (xy 303.921922 -394.529056) (xy 303.921414 -394.528294)
			(xy 303.52365 -393.839954) (xy 303.511791 -393.817269) (xy 303.494934 -393.76894) (xy 303.486354 -393.71848)
			(xy 303.485804 -393.692888) (xy 280.345134 -393.692888) (xy 280.093674 -393.944348) (xy 280.08686 -393.951769)
			(xy 280.079126 -393.970352) (xy 280.078688 -393.980416) (xy 280.079196 -394.062966) (xy 280.08707 -394.081508)
			(xy 280.094436 -394.08862) (xy 280.100532 -394.094716) (xy 280.483818 -394.478002) (xy 280.510712 -394.505555)
			(xy 280.558798 -394.565692) (xy 280.599841 -394.630839) (xy 280.633323 -394.700176) (xy 280.658823 -394.772829)
			(xy 280.67602 -394.847882) (xy 280.684696 -394.924389) (xy 280.68524 -394.962888) (xy 280.68524 -396.171674)
			(xy 296.901108 -396.171674) (xy 296.901108 -395.308074) (xy 296.901594 -395.280823) (xy 296.90935 -395.226875)
			(xy 296.924705 -395.17458) (xy 296.947347 -395.125003) (xy 296.976813 -395.079153) (xy 297.012504 -395.037962)
			(xy 297.053695 -395.002271) (xy 297.099545 -394.972805) (xy 297.149122 -394.950163) (xy 297.201417 -394.934808)
			(xy 297.255365 -394.927052) (xy 297.309867 -394.927052) (xy 297.363815 -394.934808) (xy 297.41611 -394.950163)
			(xy 297.465687 -394.972805) (xy 297.511537 -395.002271) (xy 297.552728 -395.037962) (xy 297.588419 -395.079153)
			(xy 297.617885 -395.125003) (xy 297.640527 -395.17458) (xy 297.655882 -395.226875) (xy 297.663638 -395.280823)
			(xy 297.664124 -395.308074) (xy 297.664124 -396.171674) (xy 329.428856 -396.171674) (xy 329.428856 -395.308074)
			(xy 329.429342 -395.280823) (xy 329.437098 -395.226875) (xy 329.452453 -395.17458) (xy 329.475095 -395.125003)
			(xy 329.504561 -395.079153) (xy 329.540252 -395.037962) (xy 329.581443 -395.002271) (xy 329.627293 -394.972805)
			(xy 329.67687 -394.950163) (xy 329.729165 -394.934808) (xy 329.783113 -394.927052) (xy 329.837615 -394.927052)
			(xy 329.891563 -394.934808) (xy 329.943858 -394.950163) (xy 329.993435 -394.972805) (xy 330.039285 -395.002271)
			(xy 330.080476 -395.037962) (xy 330.116167 -395.079153) (xy 330.145633 -395.125003) (xy 330.168275 -395.17458)
			(xy 330.18363 -395.226875) (xy 330.191386 -395.280823) (xy 330.191872 -395.308074) (xy 330.191872 -396.171674)
			(xy 364.001304 -396.171674) (xy 364.001304 -395.308074) (xy 364.00179 -395.280823) (xy 364.009546 -395.226875)
			(xy 364.024901 -395.17458) (xy 364.047543 -395.125003) (xy 364.077009 -395.079153) (xy 364.1127 -395.037962)
			(xy 364.153891 -395.002271) (xy 364.199741 -394.972805) (xy 364.249318 -394.950163) (xy 364.301613 -394.934808)
			(xy 364.355561 -394.927052) (xy 364.410063 -394.927052) (xy 364.464011 -394.934808) (xy 364.516306 -394.950163)
			(xy 364.565883 -394.972805) (xy 364.611733 -395.002271) (xy 364.652924 -395.037962) (xy 364.688615 -395.079153)
			(xy 364.718081 -395.125003) (xy 364.740723 -395.17458) (xy 364.756078 -395.226875) (xy 364.763834 -395.280823)
			(xy 364.76432 -395.308074) (xy 364.76432 -396.171674) (xy 396.529052 -396.171674) (xy 396.529052 -395.308074)
			(xy 396.529538 -395.280823) (xy 396.537294 -395.226875) (xy 396.552649 -395.17458) (xy 396.575291 -395.125003)
			(xy 396.604757 -395.079153) (xy 396.640448 -395.037962) (xy 396.681639 -395.002271) (xy 396.727489 -394.972805)
			(xy 396.777066 -394.950163) (xy 396.829361 -394.934808) (xy 396.883309 -394.927052) (xy 396.937811 -394.927052)
			(xy 396.991759 -394.934808) (xy 397.044054 -394.950163) (xy 397.093631 -394.972805) (xy 397.139481 -395.002271)
			(xy 397.180672 -395.037962) (xy 397.216363 -395.079153) (xy 397.245829 -395.125003) (xy 397.268471 -395.17458)
			(xy 397.283826 -395.226875) (xy 397.291582 -395.280823) (xy 397.292068 -395.308074) (xy 397.292068 -396.171674)
			(xy 397.291582 -396.198925) (xy 397.283826 -396.252873) (xy 397.268471 -396.305168) (xy 397.245829 -396.354745)
			(xy 397.216363 -396.400595) (xy 397.180672 -396.441786) (xy 397.139481 -396.477477) (xy 397.093631 -396.506943)
			(xy 397.044054 -396.529585) (xy 396.991759 -396.54494) (xy 396.937811 -396.552696) (xy 396.883309 -396.552696)
			(xy 396.829361 -396.54494) (xy 396.777066 -396.529585) (xy 396.727489 -396.506943) (xy 396.681639 -396.477477)
			(xy 396.640448 -396.441786) (xy 396.604757 -396.400595) (xy 396.575291 -396.354745) (xy 396.552649 -396.305168)
			(xy 396.537294 -396.252873) (xy 396.529538 -396.198925) (xy 396.529052 -396.171674) (xy 364.76432 -396.171674)
			(xy 364.763834 -396.198925) (xy 364.756078 -396.252873) (xy 364.740723 -396.305168) (xy 364.718081 -396.354745)
			(xy 364.688615 -396.400595) (xy 364.652924 -396.441786) (xy 364.611733 -396.477477) (xy 364.565883 -396.506943)
			(xy 364.516306 -396.529585) (xy 364.464011 -396.54494) (xy 364.410063 -396.552696) (xy 364.355561 -396.552696)
			(xy 364.301613 -396.54494) (xy 364.249318 -396.529585) (xy 364.199741 -396.506943) (xy 364.153891 -396.477477)
			(xy 364.1127 -396.441786) (xy 364.077009 -396.400595) (xy 364.047543 -396.354745) (xy 364.024901 -396.305168)
			(xy 364.009546 -396.252873) (xy 364.00179 -396.198925) (xy 364.001304 -396.171674) (xy 330.191872 -396.171674)
			(xy 330.191386 -396.198925) (xy 330.18363 -396.252873) (xy 330.168275 -396.305168) (xy 330.145633 -396.354745)
			(xy 330.116167 -396.400595) (xy 330.080476 -396.441786) (xy 330.039285 -396.477477) (xy 329.993435 -396.506943)
			(xy 329.943858 -396.529585) (xy 329.891563 -396.54494) (xy 329.837615 -396.552696) (xy 329.783113 -396.552696)
			(xy 329.729165 -396.54494) (xy 329.67687 -396.529585) (xy 329.627293 -396.506943) (xy 329.581443 -396.477477)
			(xy 329.540252 -396.441786) (xy 329.504561 -396.400595) (xy 329.475095 -396.354745) (xy 329.452453 -396.305168)
			(xy 329.437098 -396.252873) (xy 329.429342 -396.198925) (xy 329.428856 -396.171674) (xy 297.664124 -396.171674)
			(xy 297.663638 -396.198925) (xy 297.655882 -396.252873) (xy 297.640527 -396.305168) (xy 297.617885 -396.354745)
			(xy 297.588419 -396.400595) (xy 297.552728 -396.441786) (xy 297.511537 -396.477477) (xy 297.465687 -396.506943)
			(xy 297.41611 -396.529585) (xy 297.363815 -396.54494) (xy 297.309867 -396.552696) (xy 297.255365 -396.552696)
			(xy 297.201417 -396.54494) (xy 297.149122 -396.529585) (xy 297.099545 -396.506943) (xy 297.053695 -396.477477)
			(xy 297.012504 -396.441786) (xy 296.976813 -396.400595) (xy 296.947347 -396.354745) (xy 296.924705 -396.305168)
			(xy 296.90935 -396.252873) (xy 296.901594 -396.198925) (xy 296.901108 -396.171674) (xy 280.68524 -396.171674)
			(xy 280.68524 -397.15694) (xy 303.485804 -397.15694) (xy 303.485804 -397.156432) (xy 303.486268 -397.132439)
			(xy 303.49377 -397.085044) (xy 303.508595 -397.039405) (xy 303.530377 -396.996648) (xy 303.558581 -396.957826)
			(xy 303.592511 -396.923894) (xy 303.631331 -396.895688) (xy 303.674087 -396.873903) (xy 303.719724 -396.859075)
			(xy 303.767119 -396.851569) (xy 303.791112 -396.851124) (xy 303.815047 -396.851594) (xy 303.862333 -396.859047)
			(xy 303.907877 -396.873786) (xy 303.950565 -396.895448) (xy 303.989351 -396.923504) (xy 304.023286 -396.957267)
			(xy 304.051539 -396.99591) (xy 304.062892 -397.016986) (xy 304.0634 -397.018002) (xy 304.143706 -397.15694)
			(xy 304.6857 -397.15694) (xy 304.6857 -397.156432) (xy 304.686168 -397.132439) (xy 304.69367 -397.085044)
			(xy 304.708495 -397.039406) (xy 304.730277 -396.99665) (xy 304.75848 -396.957827) (xy 304.792409 -396.923895)
			(xy 304.831229 -396.895689) (xy 304.873984 -396.873904) (xy 304.919621 -396.859076) (xy 304.967015 -396.85157)
			(xy 304.991008 -396.851124) (xy 305.014943 -396.851597) (xy 305.062229 -396.85905) (xy 305.107773 -396.873788)
			(xy 305.150461 -396.89545) (xy 305.189247 -396.923505) (xy 305.223182 -396.957268) (xy 305.251435 -396.99591)
			(xy 305.262788 -397.016986) (xy 305.263296 -397.018002) (xy 305.343602 -397.15694) (xy 305.885596 -397.15694)
			(xy 305.885596 -397.156432) (xy 305.886068 -397.13244) (xy 305.89357 -397.085045) (xy 305.908394 -397.039407)
			(xy 305.930176 -396.996651) (xy 305.958378 -396.957829) (xy 305.992307 -396.923897) (xy 306.031127 -396.895691)
			(xy 306.073881 -396.873905) (xy 306.119517 -396.859076) (xy 306.166912 -396.85157) (xy 306.190904 -396.851124)
			(xy 306.214839 -396.8516) (xy 306.262124 -396.859053) (xy 306.307668 -396.87379) (xy 306.350356 -396.895451)
			(xy 306.389142 -396.923506) (xy 306.423077 -396.957268) (xy 306.451331 -396.99591) (xy 306.462684 -397.016986)
			(xy 306.463192 -397.018002) (xy 306.543498 -397.15694) (xy 307.085492 -397.15694) (xy 307.085492 -397.156432)
			(xy 307.085991 -397.132454) (xy 307.093484 -397.085088) (xy 307.108292 -397.039476) (xy 307.130049 -396.996741)
			(xy 307.158222 -396.957933) (xy 307.192115 -396.924008) (xy 307.230897 -396.895799) (xy 307.273612 -396.874002)
			(xy 307.31921 -396.859151) (xy 307.366569 -396.851614) (xy 307.390546 -396.851124) (xy 307.391054 -396.851124)
			(xy 307.41499 -396.85156) (xy 307.462278 -396.85902) (xy 307.507823 -396.873764) (xy 307.550511 -396.895432)
			(xy 307.589296 -396.923493) (xy 307.62323 -396.957261) (xy 307.651481 -396.995908) (xy 307.662834 -397.016986)
			(xy 307.663342 -397.018002) (xy 307.743648 -397.15694) (xy 308.285388 -397.15694) (xy 308.285388 -397.156432)
			(xy 308.285891 -397.132455) (xy 308.293384 -397.085089) (xy 308.308192 -397.039477) (xy 308.329949 -396.996742)
			(xy 308.35812 -396.957934) (xy 308.392013 -396.924009) (xy 308.430794 -396.895801) (xy 308.473509 -396.874003)
			(xy 308.519106 -396.859152) (xy 308.566465 -396.851614) (xy 308.590442 -396.851124) (xy 308.59095 -396.851124)
			(xy 308.614886 -396.851563) (xy 308.662173 -396.859022) (xy 308.707718 -396.873766) (xy 308.750406 -396.895434)
			(xy 308.789192 -396.923494) (xy 308.823126 -396.957262) (xy 308.851377 -396.995908) (xy 308.86273 -397.016986)
			(xy 308.863238 -397.018002) (xy 308.943544 -397.15694) (xy 309.485792 -397.15694) (xy 309.485792 -397.156432)
			(xy 309.486268 -397.13244) (xy 309.49377 -397.085045) (xy 309.508594 -397.039408) (xy 309.530375 -396.996652)
			(xy 309.558577 -396.95783) (xy 309.592506 -396.923898) (xy 309.631325 -396.895692) (xy 309.674079 -396.873906)
			(xy 309.719714 -396.859077) (xy 309.767108 -396.85157) (xy 309.7911 -396.851124) (xy 309.815035 -396.851603)
			(xy 309.86232 -396.859055) (xy 309.907864 -396.873792) (xy 309.950552 -396.895453) (xy 309.989338 -396.923507)
			(xy 310.023273 -396.957269) (xy 310.051526 -396.995911) (xy 310.06288 -397.016986) (xy 310.063388 -397.018002)
			(xy 310.143694 -397.15694) (xy 310.685688 -397.15694) (xy 310.685688 -397.156432) (xy 310.686168 -397.13244)
			(xy 310.69367 -397.085046) (xy 310.708493 -397.039409) (xy 310.730274 -396.996653) (xy 310.758476 -396.957831)
			(xy 310.792404 -396.9239) (xy 310.831223 -396.895693) (xy 310.873976 -396.873907) (xy 310.919611 -396.859078)
			(xy 310.967004 -396.851571) (xy 310.990996 -396.851124) (xy 311.014933 -396.851526) (xy 311.062223 -396.858992)
			(xy 311.107768 -396.873742) (xy 311.150456 -396.895416) (xy 311.189241 -396.923483) (xy 311.223174 -396.957255)
			(xy 311.251424 -396.995906) (xy 311.262776 -397.016986) (xy 311.263284 -397.018002) (xy 311.34359 -397.15694)
			(xy 311.885584 -397.15694) (xy 311.885584 -397.156432) (xy 311.886068 -397.13244) (xy 311.893569 -397.085046)
			(xy 311.908393 -397.03941) (xy 311.930174 -396.996654) (xy 311.958375 -396.957833) (xy 311.992302 -396.923901)
			(xy 312.03112 -396.895695) (xy 312.073873 -396.873908) (xy 312.119508 -396.859079) (xy 312.1669 -396.851571)
			(xy 312.190892 -396.851124) (xy 312.214829 -396.851529) (xy 312.262118 -396.858995) (xy 312.307664 -396.873745)
			(xy 312.350352 -396.895418) (xy 312.389137 -396.923484) (xy 312.42307 -396.957256) (xy 312.45132 -396.995906)
			(xy 312.462672 -397.016986) (xy 312.46318 -397.018002) (xy 312.543486 -397.15694) (xy 313.08548 -397.15694)
			(xy 313.08548 -397.156432) (xy 313.085991 -397.132455) (xy 313.093484 -397.08509) (xy 313.108291 -397.039479)
			(xy 313.130047 -396.996744) (xy 313.158218 -396.957937) (xy 313.19211 -396.924012) (xy 313.23089 -396.895803)
			(xy 313.273603 -396.874005) (xy 313.3192 -396.859154) (xy 313.366557 -396.851614) (xy 313.390534 -396.851124)
			(xy 313.391042 -396.851124) (xy 313.414978 -396.851569) (xy 313.462265 -396.859028) (xy 313.50781 -396.87377)
			(xy 313.550497 -396.895437) (xy 313.589283 -396.923496) (xy 313.623217 -396.957263) (xy 313.651469 -396.995909)
			(xy 313.662822 -397.016986) (xy 313.66333 -397.018002) (xy 313.743636 -397.15694) (xy 314.285376 -397.15694)
			(xy 314.285376 -397.156432) (xy 314.285891 -397.132455) (xy 314.293384 -397.08509) (xy 314.308191 -397.03948)
			(xy 314.329947 -396.996746) (xy 314.358117 -396.957938) (xy 314.392008 -396.924013) (xy 314.430788 -396.895805)
			(xy 314.473501 -396.874006) (xy 314.519096 -396.859155) (xy 314.566454 -396.851615) (xy 314.59043 -396.851124)
			(xy 314.590938 -396.851124) (xy 314.614874 -396.851573) (xy 314.662161 -396.85903) (xy 314.707705 -396.873772)
			(xy 314.750393 -396.895438) (xy 314.789179 -396.923498) (xy 314.823113 -396.957263) (xy 314.851365 -396.995909)
			(xy 314.862718 -397.016986) (xy 314.863226 -397.018002) (xy 314.943532 -397.15694) (xy 315.48578 -397.15694)
			(xy 315.48578 -397.156432) (xy 315.486268 -397.13244) (xy 315.493769 -397.085047) (xy 315.508593 -397.039411)
			(xy 315.530373 -396.996656) (xy 315.558574 -396.957834) (xy 315.592501 -396.923902) (xy 315.631318 -396.895696)
			(xy 315.67407 -396.87391) (xy 315.719704 -396.85908) (xy 315.767096 -396.851571) (xy 315.791088 -396.851124)
			(xy 315.815025 -396.851532) (xy 315.862314 -396.858997) (xy 315.90786 -396.873747) (xy 315.950547 -396.895419)
			(xy 315.989333 -396.923485) (xy 316.023266 -396.957256) (xy 316.051516 -396.995907) (xy 316.062868 -397.016986)
			(xy 316.063376 -397.018002) (xy 316.143682 -397.15694) (xy 316.685676 -397.15694) (xy 316.685676 -397.156432)
			(xy 316.686168 -397.132441) (xy 316.693669 -397.085048) (xy 316.708492 -397.039412) (xy 316.730272 -396.996657)
			(xy 316.758473 -396.957836) (xy 316.792399 -396.923904) (xy 316.831216 -396.895697) (xy 316.873967 -396.873911)
			(xy 316.919601 -396.85908) (xy 316.966993 -396.851571) (xy 316.990984 -396.851124) (xy 317.014921 -396.851535)
			(xy 317.06221 -396.859) (xy 317.107755 -396.873749) (xy 317.150443 -396.895421) (xy 317.189228 -396.923486)
			(xy 317.223161 -396.957257) (xy 317.251412 -396.995907) (xy 317.262764 -397.016986) (xy 317.263272 -397.018002)
			(xy 317.343578 -397.15694) (xy 317.885572 -397.15694) (xy 317.885572 -397.156432) (xy 317.886068 -397.132441)
			(xy 317.893569 -397.085048) (xy 317.908392 -397.039413) (xy 317.930172 -396.996658) (xy 317.958371 -396.957837)
			(xy 317.992297 -396.923905) (xy 318.031114 -396.895699) (xy 318.073865 -396.873912) (xy 318.119498 -396.859081)
			(xy 318.166889 -396.851572) (xy 318.19088 -396.851124) (xy 318.214817 -396.851539) (xy 318.262105 -396.859002)
			(xy 318.307651 -396.873751) (xy 318.350339 -396.895422) (xy 318.389124 -396.923487) (xy 318.423057 -396.957257)
			(xy 318.451308 -396.995907) (xy 318.46266 -397.016986) (xy 318.463168 -397.018002) (xy 318.543474 -397.15694)
			(xy 319.085468 -397.15694) (xy 319.085468 -397.156432) (xy 319.085991 -397.132456) (xy 319.093484 -397.085092)
			(xy 319.10829 -397.039482) (xy 319.130045 -396.996748) (xy 319.158215 -396.957941) (xy 319.192105 -396.924016)
			(xy 319.230883 -396.895807) (xy 319.273595 -396.874009) (xy 319.31919 -396.859156) (xy 319.366546 -396.851615)
			(xy 319.390522 -396.851124) (xy 319.39103 -396.851124) (xy 319.414965 -396.851579) (xy 319.462252 -396.859035)
			(xy 319.507797 -396.873776) (xy 319.550484 -396.895441) (xy 319.58927 -396.9235) (xy 319.623205 -396.957264)
			(xy 319.651457 -396.995909) (xy 319.66281 -397.016986) (xy 319.663318 -397.018002) (xy 319.743624 -397.15694)
			(xy 320.285364 -397.15694) (xy 320.285364 -397.156432) (xy 320.285891 -397.132456) (xy 320.293383 -397.085092)
			(xy 320.308189 -397.039483) (xy 320.329944 -396.996749) (xy 320.358113 -396.957943) (xy 320.392003 -396.924018)
			(xy 320.430781 -396.895809) (xy 320.473492 -396.87401) (xy 320.519086 -396.859157) (xy 320.566442 -396.851616)
			(xy 320.590418 -396.851124) (xy 320.590926 -396.851124) (xy 320.614861 -396.851582) (xy 320.662148 -396.859038)
			(xy 320.707692 -396.873778) (xy 320.75038 -396.895443) (xy 320.789166 -396.923501) (xy 320.823101 -396.957265)
			(xy 320.851353 -396.995909) (xy 320.862706 -397.016986) (xy 320.863214 -397.018002) (xy 320.94352 -397.15694)
			(xy 321.485768 -397.15694) (xy 321.485768 -397.156432) (xy 321.486268 -397.132441) (xy 321.493769 -397.085049)
			(xy 321.508592 -397.039414) (xy 321.530371 -396.996659) (xy 321.55857 -396.957838) (xy 321.592496 -396.923907)
			(xy 321.631311 -396.8957) (xy 321.674062 -396.873913) (xy 321.719694 -396.859082) (xy 321.767085 -396.851572)
			(xy 321.791076 -396.851124) (xy 321.815013 -396.851542) (xy 321.862301 -396.859005) (xy 321.907847 -396.873753)
			(xy 321.950534 -396.895424) (xy 321.98932 -396.923488) (xy 322.023253 -396.957258) (xy 322.051504 -396.995907)
			(xy 322.062856 -397.016986) (xy 322.063364 -397.018002) (xy 322.14367 -397.15694) (xy 336.013552 -397.15694)
			(xy 336.013552 -397.156432) (xy 336.014092 -397.132444) (xy 336.021592 -397.085057) (xy 336.036413 -397.039427)
			(xy 336.058189 -396.996677) (xy 336.086384 -396.95786) (xy 336.120305 -396.923931) (xy 336.159115 -396.895726)
			(xy 336.20186 -396.87394) (xy 336.247487 -396.859109) (xy 336.294872 -396.851598) (xy 336.31886 -396.851124)
			(xy 336.342796 -396.851555) (xy 336.390084 -396.859016) (xy 336.435629 -396.873761) (xy 336.478317 -396.89543)
			(xy 336.517103 -396.923492) (xy 336.551036 -396.95726) (xy 336.579288 -396.995908) (xy 336.59064 -397.016986)
			(xy 336.591148 -397.018002) (xy 336.671454 -397.15694) (xy 337.213448 -397.15694) (xy 337.213448 -397.156432)
			(xy 337.213992 -397.132444) (xy 337.221492 -397.085057) (xy 337.236312 -397.039428) (xy 337.258088 -396.996678)
			(xy 337.286283 -396.957861) (xy 337.320203 -396.923933) (xy 337.359013 -396.895728) (xy 337.401757 -396.873941)
			(xy 337.447383 -396.85911) (xy 337.494768 -396.851598) (xy 337.518756 -396.851124) (xy 337.542692 -396.851558)
			(xy 337.58998 -396.859018) (xy 337.635525 -396.873763) (xy 337.678213 -396.895431) (xy 337.716998 -396.923493)
			(xy 337.750932 -396.957261) (xy 337.779183 -396.995908) (xy 337.790536 -397.016986) (xy 337.791044 -397.018002)
			(xy 337.87135 -397.15694) (xy 338.413344 -397.15694) (xy 338.413344 -397.156432) (xy 338.413892 -397.132444)
			(xy 338.421392 -397.085058) (xy 338.436212 -397.039429) (xy 338.457987 -396.996679) (xy 338.486182 -396.957862)
			(xy 338.520101 -396.923934) (xy 338.558911 -396.895729) (xy 338.601655 -396.873943) (xy 338.64728 -396.859111)
			(xy 338.694664 -396.851598) (xy 338.718652 -396.851124) (xy 338.742588 -396.851561) (xy 338.789876 -396.859021)
			(xy 338.835421 -396.873765) (xy 338.878108 -396.895433) (xy 338.916894 -396.923494) (xy 338.950828 -396.957261)
			(xy 338.979079 -396.995908) (xy 338.990432 -397.016986) (xy 338.99094 -397.018002) (xy 339.071246 -397.15694)
			(xy 339.61324 -397.15694) (xy 339.61324 -397.156432) (xy 339.613691 -397.132452) (xy 339.621186 -397.085081)
			(xy 339.635997 -397.039465) (xy 339.657758 -396.996726) (xy 339.685936 -396.957917) (xy 339.719835 -396.92399)
			(xy 339.758623 -396.895783) (xy 339.801345 -396.873988) (xy 339.846949 -396.859142) (xy 339.894314 -396.85161)
			(xy 339.918294 -396.851124) (xy 339.918802 -396.851124) (xy 339.942737 -396.851602) (xy 339.990022 -396.859054)
			(xy 340.035566 -396.873791) (xy 340.078254 -396.895452) (xy 340.11704 -396.923507) (xy 340.150975 -396.957268)
			(xy 340.179229 -396.99591) (xy 340.190582 -397.016986) (xy 340.19109 -397.018002) (xy 340.271396 -397.15694)
			(xy 340.813136 -397.15694) (xy 340.813136 -397.156432) (xy 340.813591 -397.132452) (xy 340.821086 -397.085082)
			(xy 340.835896 -397.039466) (xy 340.857658 -396.996728) (xy 340.885834 -396.957918) (xy 340.919734 -396.923992)
			(xy 340.958521 -396.895784) (xy 341.001242 -396.873989) (xy 341.046846 -396.859143) (xy 341.09421 -396.85161)
			(xy 341.11819 -396.851124) (xy 341.118698 -396.851124) (xy 341.142635 -396.851524) (xy 341.189925 -396.858991)
			(xy 341.235471 -396.873741) (xy 341.278158 -396.895415) (xy 341.316943 -396.923482) (xy 341.350876 -396.957255)
			(xy 341.379126 -396.995906) (xy 341.390478 -397.016986) (xy 341.390986 -397.018002) (xy 341.471292 -397.15694)
			(xy 342.01354 -397.15694) (xy 342.01354 -397.156432) (xy 342.013968 -397.132437) (xy 342.021471 -397.085038)
			(xy 342.036298 -397.039397) (xy 342.058084 -396.996638) (xy 342.086291 -396.957814) (xy 342.120226 -396.923881)
			(xy 342.159051 -396.895676) (xy 342.201812 -396.873892) (xy 342.247454 -396.859068) (xy 342.294853 -396.851567)
			(xy 342.318848 -396.851124) (xy 342.342784 -396.851565) (xy 342.390071 -396.859024) (xy 342.435616 -396.873767)
			(xy 342.478304 -396.895434) (xy 342.51709 -396.923495) (xy 342.551024 -396.957262) (xy 342.579275 -396.995908)
			(xy 342.590628 -397.016986) (xy 342.591136 -397.018002) (xy 342.671442 -397.15694) (xy 343.213436 -397.15694)
			(xy 343.213436 -397.156432) (xy 343.213868 -397.132438) (xy 343.221371 -397.085039) (xy 343.236198 -397.039398)
			(xy 343.257983 -396.996639) (xy 343.28619 -396.957815) (xy 343.320124 -396.923882) (xy 343.358949 -396.895677)
			(xy 343.401709 -396.873893) (xy 343.447351 -396.859068) (xy 343.49475 -396.851567) (xy 343.518744 -396.851124)
			(xy 343.54268 -396.851568) (xy 343.589967 -396.859026) (xy 343.635512 -396.873769) (xy 343.6782 -396.895436)
			(xy 343.716985 -396.923496) (xy 343.750919 -396.957262) (xy 343.779171 -396.995909) (xy 343.790524 -397.016986)
			(xy 343.791032 -397.018002) (xy 343.871338 -397.15694) (xy 344.413332 -397.15694) (xy 344.413332 -397.156432)
			(xy 344.413768 -397.132438) (xy 344.421271 -397.085039) (xy 344.436098 -397.039399) (xy 344.457883 -396.99664)
			(xy 344.486089 -396.957816) (xy 344.520022 -396.923884) (xy 344.558847 -396.895678) (xy 344.601606 -396.873895)
			(xy 344.647247 -396.859069) (xy 344.694646 -396.851567) (xy 344.71864 -396.851124) (xy 344.742576 -396.851571)
			(xy 344.789863 -396.859029) (xy 344.835408 -396.873771) (xy 344.878095 -396.895437) (xy 344.916881 -396.923497)
			(xy 344.950815 -396.957263) (xy 344.979067 -396.995909) (xy 344.99042 -397.016986) (xy 344.990928 -397.018002)
			(xy 345.071234 -397.15694) (xy 345.613228 -397.15694) (xy 345.613228 -397.156432) (xy 345.613691 -397.132453)
			(xy 345.621186 -397.085083) (xy 345.635996 -397.039468) (xy 345.657756 -396.99673) (xy 345.685932 -396.957921)
			(xy 345.71983 -396.923995) (xy 345.758617 -396.895787) (xy 345.801337 -396.873991) (xy 345.846939 -396.859144)
			(xy 345.894303 -396.851611) (xy 345.918282 -396.851124) (xy 345.91879 -396.851124) (xy 345.942727 -396.85153)
			(xy 345.990016 -396.858996) (xy 346.035562 -396.873746) (xy 346.07825 -396.895419) (xy 346.117035 -396.923484)
			(xy 346.150968 -396.957256) (xy 346.179218 -396.995907) (xy 346.19057 -397.016986) (xy 346.191078 -397.018002)
			(xy 346.271384 -397.15694) (xy 346.813124 -397.15694) (xy 346.813124 -397.156432) (xy 346.813591 -397.132453)
			(xy 346.821086 -397.085083) (xy 346.835895 -397.039469) (xy 346.857655 -396.996731) (xy 346.885831 -396.957922)
			(xy 346.919729 -396.923996) (xy 346.958514 -396.895788) (xy 347.001234 -396.873993) (xy 347.046836 -396.859145)
			(xy 347.094199 -396.851611) (xy 347.118178 -396.851124) (xy 347.118686 -396.851124) (xy 347.142623 -396.851534)
			(xy 347.189912 -396.858998) (xy 347.235457 -396.873748) (xy 347.278145 -396.89542) (xy 347.31693 -396.923485)
			(xy 347.350864 -396.957256) (xy 347.379114 -396.995907) (xy 347.390466 -397.016986) (xy 347.390974 -397.018002)
			(xy 347.47128 -397.15694) (xy 348.013528 -397.15694) (xy 348.013528 -397.156432) (xy 348.013968 -397.132438)
			(xy 348.021471 -397.08504) (xy 348.036297 -397.0394) (xy 348.058082 -396.996641) (xy 348.086288 -396.957818)
			(xy 348.120221 -396.923885) (xy 348.159045 -396.89568) (xy 348.201804 -396.873896) (xy 348.247444 -396.85907)
			(xy 348.294842 -396.851568) (xy 348.318836 -396.851124) (xy 348.342772 -396.851574) (xy 348.390058 -396.859031)
			(xy 348.435603 -396.873773) (xy 348.478291 -396.895439) (xy 348.517077 -396.923498) (xy 348.551011 -396.957264)
			(xy 348.579263 -396.995909) (xy 348.590616 -397.016986) (xy 348.591124 -397.018002) (xy 348.67143 -397.15694)
			(xy 349.213424 -397.15694) (xy 349.213424 -397.156432) (xy 349.213868 -397.132438) (xy 349.221371 -397.085041)
			(xy 349.236197 -397.039401) (xy 349.257981 -396.996643) (xy 349.286187 -396.957819) (xy 349.320119 -396.923887)
			(xy 349.358943 -396.895681) (xy 349.401701 -396.873897) (xy 349.447341 -396.859071) (xy 349.494738 -396.851568)
			(xy 349.518732 -396.851124) (xy 349.542668 -396.851578) (xy 349.589954 -396.859034) (xy 349.635499 -396.873775)
			(xy 349.678187 -396.89544) (xy 349.716972 -396.923499) (xy 349.750907 -396.957264) (xy 349.779159 -396.995909)
			(xy 349.790512 -397.016986) (xy 349.79102 -397.018002) (xy 349.871326 -397.15694) (xy 350.41332 -397.15694)
			(xy 350.41332 -397.156432) (xy 350.413768 -397.132438) (xy 350.421271 -397.085041) (xy 350.436097 -397.039402)
			(xy 350.45788 -396.996644) (xy 350.486086 -396.95782) (xy 350.520017 -396.923888) (xy 350.55884 -396.895682)
			(xy 350.601598 -396.873898) (xy 350.647237 -396.859072) (xy 350.694634 -396.851568) (xy 350.718628 -396.851124)
			(xy 350.742563 -396.851581) (xy 350.78985 -396.859037) (xy 350.835395 -396.873777) (xy 350.878082 -396.895442)
			(xy 350.916868 -396.9235) (xy 350.950803 -396.957265) (xy 350.979055 -396.995909) (xy 350.990408 -397.016986)
			(xy 350.990916 -397.018002) (xy 351.071222 -397.15694) (xy 351.613216 -397.15694) (xy 351.613216 -397.156432)
			(xy 351.613691 -397.132453) (xy 351.621185 -397.085085) (xy 351.635994 -397.039471) (xy 351.657754 -396.996734)
			(xy 351.685929 -396.957925) (xy 351.719825 -396.923999) (xy 351.75861 -396.895791) (xy 351.801328 -396.873995)
			(xy 351.846929 -396.859147) (xy 351.894292 -396.851612) (xy 351.91827 -396.851124) (xy 351.918778 -396.851124)
			(xy 351.942715 -396.85154) (xy 351.990003 -396.859004) (xy 352.035549 -396.873752) (xy 352.078237 -396.895423)
			(xy 352.117022 -396.923487) (xy 352.150955 -396.957258) (xy 352.179206 -396.995907) (xy 352.190558 -397.016986)
			(xy 352.191066 -397.018002) (xy 352.271372 -397.15694) (xy 352.813112 -397.15694) (xy 352.813112 -397.156432)
			(xy 352.813591 -397.132453) (xy 352.821085 -397.085085) (xy 352.835894 -397.039472) (xy 352.857653 -396.996735)
			(xy 352.885827 -396.957926) (xy 352.919724 -396.924) (xy 352.958508 -396.895792) (xy 353.001225 -396.873996)
			(xy 353.046826 -396.859147) (xy 353.094188 -396.851612) (xy 353.118166 -396.851124) (xy 353.118674 -396.851124)
			(xy 353.142611 -396.851543) (xy 353.189899 -396.859006) (xy 353.235444 -396.873754) (xy 353.278132 -396.895425)
			(xy 353.316918 -396.923488) (xy 353.350851 -396.957258) (xy 353.379102 -396.995907) (xy 353.390454 -397.016986)
			(xy 353.390962 -397.018002) (xy 353.471268 -397.15694) (xy 354.013516 -397.15694) (xy 354.013516 -397.156432)
			(xy 354.013968 -397.132439) (xy 354.021471 -397.085042) (xy 354.036296 -397.039403) (xy 354.05808 -396.996645)
			(xy 354.086284 -396.957822) (xy 354.120216 -396.92389) (xy 354.159038 -396.895684) (xy 354.201795 -396.873899)
			(xy 354.247434 -396.859072) (xy 354.294831 -396.851568) (xy 354.318824 -396.851124) (xy 354.342759 -396.851584)
			(xy 354.390046 -396.859039) (xy 354.43559 -396.873779) (xy 354.478278 -396.895444) (xy 354.517064 -396.923501)
			(xy 354.550998 -396.957265) (xy 354.579251 -396.99591) (xy 354.590604 -397.016986) (xy 354.591112 -397.018002)
			(xy 354.671418 -397.15694) (xy 370.586 -397.15694) (xy 370.586 -397.156432) (xy 370.586468 -397.132439)
			(xy 370.59397 -397.085044) (xy 370.608795 -397.039406) (xy 370.630577 -396.99665) (xy 370.65878 -396.957827)
			(xy 370.692709 -396.923895) (xy 370.731529 -396.895689) (xy 370.774284 -396.873904) (xy 370.819921 -396.859076)
			(xy 370.867315 -396.85157) (xy 370.891308 -396.851124) (xy 370.915243 -396.851597) (xy 370.962529 -396.85905)
			(xy 371.008073 -396.873788) (xy 371.050761 -396.89545) (xy 371.089547 -396.923505) (xy 371.123482 -396.957268)
			(xy 371.151735 -396.99591) (xy 371.163088 -397.016986) (xy 371.163596 -397.018002) (xy 371.243902 -397.15694)
			(xy 371.785896 -397.15694) (xy 371.785896 -397.156432) (xy 371.786368 -397.13244) (xy 371.79387 -397.085045)
			(xy 371.808694 -397.039407) (xy 371.830476 -396.996651) (xy 371.858678 -396.957829) (xy 371.892607 -396.923897)
			(xy 371.931427 -396.895691) (xy 371.974181 -396.873905) (xy 372.019817 -396.859076) (xy 372.067212 -396.85157)
			(xy 372.091204 -396.851124) (xy 372.115139 -396.8516) (xy 372.162424 -396.859053) (xy 372.207968 -396.87379)
			(xy 372.250656 -396.895451) (xy 372.289442 -396.923506) (xy 372.323377 -396.957268) (xy 372.351631 -396.99591)
			(xy 372.362984 -397.016986) (xy 372.363492 -397.018002) (xy 372.443798 -397.15694) (xy 372.985792 -397.15694)
			(xy 372.985792 -397.156432) (xy 372.986268 -397.13244) (xy 372.99377 -397.085045) (xy 373.008594 -397.039408)
			(xy 373.030375 -396.996652) (xy 373.058577 -396.95783) (xy 373.092506 -396.923898) (xy 373.131325 -396.895692)
			(xy 373.174079 -396.873906) (xy 373.219714 -396.859077) (xy 373.267108 -396.85157) (xy 373.2911 -396.851124)
			(xy 373.315035 -396.851603) (xy 373.36232 -396.859055) (xy 373.407864 -396.873792) (xy 373.450552 -396.895453)
			(xy 373.489338 -396.923507) (xy 373.523273 -396.957269) (xy 373.551526 -396.995911) (xy 373.56288 -397.016986)
			(xy 373.563388 -397.018002) (xy 373.643694 -397.15694) (xy 374.185688 -397.15694) (xy 374.185688 -397.156432)
			(xy 374.186191 -397.132455) (xy 374.193684 -397.085089) (xy 374.208492 -397.039477) (xy 374.230249 -396.996742)
			(xy 374.25842 -396.957934) (xy 374.292313 -396.924009) (xy 374.331094 -396.895801) (xy 374.373809 -396.874003)
			(xy 374.419406 -396.859152) (xy 374.466765 -396.851614) (xy 374.490742 -396.851124) (xy 374.49125 -396.851124)
			(xy 374.515186 -396.851563) (xy 374.562473 -396.859022) (xy 374.608018 -396.873766) (xy 374.650706 -396.895434)
			(xy 374.689492 -396.923494) (xy 374.723426 -396.957262) (xy 374.751677 -396.995908) (xy 374.76303 -397.016986)
			(xy 374.763538 -397.018002) (xy 374.843844 -397.15694) (xy 375.385584 -397.15694) (xy 375.385584 -397.156432)
			(xy 375.386091 -397.132455) (xy 375.393584 -397.085089) (xy 375.408391 -397.039478) (xy 375.430148 -396.996743)
			(xy 375.458319 -396.957936) (xy 375.492212 -396.92401) (xy 375.530992 -396.895802) (xy 375.573706 -396.874004)
			(xy 375.619303 -396.859153) (xy 375.666661 -396.851614) (xy 375.690638 -396.851124) (xy 375.691146 -396.851124)
			(xy 375.715082 -396.851566) (xy 375.762369 -396.859025) (xy 375.807914 -396.873768) (xy 375.850602 -396.895435)
			(xy 375.889387 -396.923495) (xy 375.923322 -396.957262) (xy 375.951573 -396.995909) (xy 375.962926 -397.016986)
			(xy 375.963434 -397.018002) (xy 376.04374 -397.15694) (xy 376.585988 -397.15694) (xy 376.585988 -397.156432)
			(xy 376.586468 -397.13244) (xy 376.59397 -397.085046) (xy 376.608793 -397.039409) (xy 376.630574 -396.996653)
			(xy 376.658776 -396.957831) (xy 376.692704 -396.9239) (xy 376.731523 -396.895693) (xy 376.774276 -396.873907)
			(xy 376.819911 -396.859078) (xy 376.867304 -396.851571) (xy 376.891296 -396.851124) (xy 376.915233 -396.851526)
			(xy 376.962523 -396.858992) (xy 377.008068 -396.873742) (xy 377.050756 -396.895416) (xy 377.089541 -396.923483)
			(xy 377.123474 -396.957255) (xy 377.151724 -396.995906) (xy 377.163076 -397.016986) (xy 377.163584 -397.018002)
			(xy 377.24389 -397.15694) (xy 377.785884 -397.15694) (xy 377.785884 -397.156432) (xy 377.786368 -397.13244)
			(xy 377.793869 -397.085046) (xy 377.808693 -397.03941) (xy 377.830474 -396.996654) (xy 377.858675 -396.957833)
			(xy 377.892602 -396.923901) (xy 377.93142 -396.895695) (xy 377.974173 -396.873908) (xy 378.019808 -396.859079)
			(xy 378.0672 -396.851571) (xy 378.091192 -396.851124) (xy 378.115129 -396.851529) (xy 378.162418 -396.858995)
			(xy 378.207964 -396.873745) (xy 378.250652 -396.895418) (xy 378.289437 -396.923484) (xy 378.32337 -396.957256)
			(xy 378.35162 -396.995906) (xy 378.362972 -397.016986) (xy 378.36348 -397.018002) (xy 378.443786 -397.15694)
			(xy 378.98578 -397.15694) (xy 378.98578 -397.156432) (xy 378.986268 -397.13244) (xy 378.993769 -397.085047)
			(xy 379.008593 -397.039411) (xy 379.030373 -396.996656) (xy 379.058574 -396.957834) (xy 379.092501 -396.923902)
			(xy 379.131318 -396.895696) (xy 379.17407 -396.87391) (xy 379.219704 -396.85908) (xy 379.267096 -396.851571)
			(xy 379.291088 -396.851124) (xy 379.315025 -396.851532) (xy 379.362314 -396.858997) (xy 379.40786 -396.873747)
			(xy 379.450547 -396.895419) (xy 379.489333 -396.923485) (xy 379.523266 -396.957256) (xy 379.551516 -396.995907)
			(xy 379.562868 -397.016986) (xy 379.563376 -397.018002) (xy 379.643682 -397.15694) (xy 380.185676 -397.15694)
			(xy 380.185676 -397.156432) (xy 380.186191 -397.132455) (xy 380.193684 -397.08509) (xy 380.208491 -397.03948)
			(xy 380.230247 -396.996746) (xy 380.258417 -396.957938) (xy 380.292308 -396.924013) (xy 380.331088 -396.895805)
			(xy 380.373801 -396.874006) (xy 380.419396 -396.859155) (xy 380.466754 -396.851615) (xy 380.49073 -396.851124)
			(xy 380.491238 -396.851124) (xy 380.515174 -396.851573) (xy 380.562461 -396.85903) (xy 380.608005 -396.873772)
			(xy 380.650693 -396.895438) (xy 380.689479 -396.923498) (xy 380.723413 -396.957263) (xy 380.751665 -396.995909)
			(xy 380.763018 -397.016986) (xy 380.763526 -397.018002) (xy 380.843832 -397.15694) (xy 381.385572 -397.15694)
			(xy 381.385572 -397.156432) (xy 381.386091 -397.132455) (xy 381.393584 -397.085091) (xy 381.40839 -397.039481)
			(xy 381.430146 -396.996747) (xy 381.458316 -396.95794) (xy 381.492207 -396.924015) (xy 381.530985 -396.895806)
			(xy 381.573698 -396.874007) (xy 381.619293 -396.859155) (xy 381.66665 -396.851615) (xy 381.690626 -396.851124)
			(xy 381.691134 -396.851124) (xy 381.71507 -396.851576) (xy 381.762356 -396.859033) (xy 381.807901 -396.873774)
			(xy 381.850589 -396.89544) (xy 381.889375 -396.923499) (xy 381.923309 -396.957264) (xy 381.951561 -396.995909)
			(xy 381.962914 -397.016986) (xy 381.963422 -397.018002) (xy 382.043728 -397.15694) (xy 382.585976 -397.15694)
			(xy 382.585976 -397.156432) (xy 382.586468 -397.132441) (xy 382.593969 -397.085048) (xy 382.608792 -397.039412)
			(xy 382.630572 -396.996657) (xy 382.658773 -396.957836) (xy 382.692699 -396.923904) (xy 382.731516 -396.895697)
			(xy 382.774267 -396.873911) (xy 382.819901 -396.85908) (xy 382.867293 -396.851571) (xy 382.891284 -396.851124)
			(xy 382.915221 -396.851535) (xy 382.96251 -396.859) (xy 383.008055 -396.873749) (xy 383.050743 -396.895421)
			(xy 383.089528 -396.923486) (xy 383.123461 -396.957257) (xy 383.151712 -396.995907) (xy 383.163064 -397.016986)
			(xy 383.163572 -397.018002) (xy 383.243878 -397.15694) (xy 383.785872 -397.15694) (xy 383.785872 -397.156432)
			(xy 383.786368 -397.132441) (xy 383.793869 -397.085048) (xy 383.808692 -397.039413) (xy 383.830472 -396.996658)
			(xy 383.858671 -396.957837) (xy 383.892597 -396.923905) (xy 383.931414 -396.895699) (xy 383.974165 -396.873912)
			(xy 384.019798 -396.859081) (xy 384.067189 -396.851572) (xy 384.09118 -396.851124) (xy 384.115117 -396.851539)
			(xy 384.162405 -396.859002) (xy 384.207951 -396.873751) (xy 384.250639 -396.895422) (xy 384.289424 -396.923487)
			(xy 384.323357 -396.957257) (xy 384.351608 -396.995907) (xy 384.36296 -397.016986) (xy 384.363468 -397.018002)
			(xy 384.443774 -397.15694) (xy 384.985768 -397.15694) (xy 384.985768 -397.156432) (xy 384.986268 -397.132441)
			(xy 384.993769 -397.085049) (xy 385.008592 -397.039414) (xy 385.030371 -396.996659) (xy 385.05857 -396.957838)
			(xy 385.092496 -396.923907) (xy 385.131311 -396.8957) (xy 385.174062 -396.873913) (xy 385.219694 -396.859082)
			(xy 385.267085 -396.851572) (xy 385.291076 -396.851124) (xy 385.315013 -396.851542) (xy 385.362301 -396.859005)
			(xy 385.407847 -396.873753) (xy 385.450534 -396.895424) (xy 385.48932 -396.923488) (xy 385.523253 -396.957258)
			(xy 385.551504 -396.995907) (xy 385.562856 -397.016986) (xy 385.563364 -397.018002) (xy 385.64367 -397.15694)
			(xy 386.185664 -397.15694) (xy 386.185664 -397.156432) (xy 386.186191 -397.132456) (xy 386.193683 -397.085092)
			(xy 386.208489 -397.039483) (xy 386.230244 -396.996749) (xy 386.258413 -396.957943) (xy 386.292303 -396.924018)
			(xy 386.331081 -396.895809) (xy 386.373792 -396.87401) (xy 386.419386 -396.859157) (xy 386.466742 -396.851616)
			(xy 386.490718 -396.851124) (xy 386.491226 -396.851124) (xy 386.515161 -396.851582) (xy 386.562448 -396.859038)
			(xy 386.607992 -396.873778) (xy 386.65068 -396.895443) (xy 386.689466 -396.923501) (xy 386.723401 -396.957265)
			(xy 386.751653 -396.995909) (xy 386.763006 -397.016986) (xy 386.763514 -397.018002) (xy 386.84382 -397.15694)
			(xy 387.38556 -397.15694) (xy 387.38556 -397.156432) (xy 387.386091 -397.132456) (xy 387.393583 -397.085093)
			(xy 387.408389 -397.039484) (xy 387.430144 -396.99675) (xy 387.458312 -396.957944) (xy 387.492202 -396.924019)
			(xy 387.530979 -396.89581) (xy 387.573689 -396.874011) (xy 387.619283 -396.859158) (xy 387.666638 -396.851616)
			(xy 387.690614 -396.851124) (xy 387.691122 -396.851124) (xy 387.715057 -396.851586) (xy 387.762343 -396.859041)
			(xy 387.807888 -396.873781) (xy 387.850576 -396.895444) (xy 387.889362 -396.923502) (xy 387.923296 -396.957266)
			(xy 387.951549 -396.99591) (xy 387.962902 -397.016986) (xy 387.96341 -397.018002) (xy 388.043716 -397.15694)
			(xy 388.585964 -397.15694) (xy 388.585964 -397.156432) (xy 388.586468 -397.132441) (xy 388.593969 -397.085049)
			(xy 388.608791 -397.039415) (xy 388.63057 -396.99666) (xy 388.658769 -396.95784) (xy 388.692694 -396.923908)
			(xy 388.731509 -396.895701) (xy 388.774259 -396.873914) (xy 388.819891 -396.859083) (xy 388.867281 -396.851572)
			(xy 388.891272 -396.851124) (xy 388.915209 -396.851545) (xy 388.962497 -396.859008) (xy 389.008042 -396.873755)
			(xy 389.05073 -396.895425) (xy 389.089515 -396.923489) (xy 389.123449 -396.957258) (xy 389.1517 -396.995907)
			(xy 389.163052 -397.016986) (xy 389.16356 -397.018002) (xy 389.243866 -397.15694) (xy 403.113748 -397.15694)
			(xy 403.113748 -397.156432) (xy 403.114292 -397.132444) (xy 403.121792 -397.085057) (xy 403.136612 -397.039428)
			(xy 403.158388 -396.996678) (xy 403.186583 -396.957861) (xy 403.220503 -396.923933) (xy 403.259313 -396.895728)
			(xy 403.302057 -396.873941) (xy 403.347683 -396.85911) (xy 403.395068 -396.851598) (xy 403.419056 -396.851124)
			(xy 403.442992 -396.851558) (xy 403.49028 -396.859018) (xy 403.535825 -396.873763) (xy 403.578513 -396.895431)
			(xy 403.617298 -396.923493) (xy 403.651232 -396.957261) (xy 403.679483 -396.995908) (xy 403.690836 -397.016986)
			(xy 403.691344 -397.018002) (xy 403.77165 -397.15694) (xy 404.313644 -397.15694) (xy 404.313644 -397.156432)
			(xy 404.314192 -397.132444) (xy 404.321692 -397.085058) (xy 404.336512 -397.039429) (xy 404.358287 -396.996679)
			(xy 404.386482 -396.957862) (xy 404.420401 -396.923934) (xy 404.459211 -396.895729) (xy 404.501955 -396.873943)
			(xy 404.54758 -396.859111) (xy 404.594964 -396.851598) (xy 404.618952 -396.851124) (xy 404.642888 -396.851561)
			(xy 404.690176 -396.859021) (xy 404.735721 -396.873765) (xy 404.778408 -396.895433) (xy 404.817194 -396.923494)
			(xy 404.851128 -396.957261) (xy 404.879379 -396.995908) (xy 404.890732 -397.016986) (xy 404.89124 -397.018002)
			(xy 404.971546 -397.15694) (xy 405.51354 -397.15694) (xy 405.51354 -397.156432) (xy 405.513968 -397.132437)
			(xy 405.521471 -397.085038) (xy 405.536298 -397.039397) (xy 405.558084 -396.996638) (xy 405.586291 -396.957814)
			(xy 405.620226 -396.923881) (xy 405.659051 -396.895676) (xy 405.701812 -396.873892) (xy 405.747454 -396.859068)
			(xy 405.794853 -396.851567) (xy 405.818848 -396.851124) (xy 405.842784 -396.851565) (xy 405.890071 -396.859024)
			(xy 405.935616 -396.873767) (xy 405.978304 -396.895434) (xy 406.01709 -396.923495) (xy 406.051024 -396.957262)
			(xy 406.079275 -396.995908) (xy 406.090628 -397.016986) (xy 406.091136 -397.018002) (xy 406.171442 -397.15694)
			(xy 406.713436 -397.15694) (xy 406.713436 -397.156432) (xy 406.713891 -397.132452) (xy 406.721386 -397.085082)
			(xy 406.736196 -397.039466) (xy 406.757958 -396.996728) (xy 406.786134 -396.957918) (xy 406.820034 -396.923992)
			(xy 406.858821 -396.895784) (xy 406.901542 -396.873989) (xy 406.947146 -396.859143) (xy 406.99451 -396.85161)
			(xy 407.01849 -396.851124) (xy 407.018998 -396.851124) (xy 407.042935 -396.851524) (xy 407.090225 -396.858991)
			(xy 407.135771 -396.873741) (xy 407.178458 -396.895415) (xy 407.217243 -396.923482) (xy 407.251176 -396.957255)
			(xy 407.279426 -396.995906) (xy 407.290778 -397.016986) (xy 407.291286 -397.018002) (xy 407.371592 -397.15694)
			(xy 407.913332 -397.15694) (xy 407.913332 -397.156432) (xy 407.913791 -397.132452) (xy 407.921286 -397.085082)
			(xy 407.936096 -397.039467) (xy 407.957857 -396.996729) (xy 407.986033 -396.957919) (xy 408.019932 -396.923993)
			(xy 408.058719 -396.895786) (xy 408.101439 -396.87399) (xy 408.147043 -396.859143) (xy 408.194407 -396.851611)
			(xy 408.218386 -396.851124) (xy 408.218894 -396.851124) (xy 408.242831 -396.851527) (xy 408.29012 -396.858993)
			(xy 408.335666 -396.873744) (xy 408.378354 -396.895417) (xy 408.417139 -396.923483) (xy 408.451072 -396.957255)
			(xy 408.479322 -396.995906) (xy 408.490674 -397.016986) (xy 408.491182 -397.018002) (xy 408.571488 -397.15694)
			(xy 409.113736 -397.15694) (xy 409.113736 -397.156432) (xy 409.114168 -397.132438) (xy 409.121671 -397.085039)
			(xy 409.136498 -397.039398) (xy 409.158283 -396.996639) (xy 409.18649 -396.957815) (xy 409.220424 -396.923882)
			(xy 409.259249 -396.895677) (xy 409.302009 -396.873893) (xy 409.347651 -396.859068) (xy 409.39505 -396.851567)
			(xy 409.419044 -396.851124) (xy 409.44298 -396.851568) (xy 409.490267 -396.859026) (xy 409.535812 -396.873769)
			(xy 409.5785 -396.895436) (xy 409.617285 -396.923496) (xy 409.651219 -396.957262) (xy 409.679471 -396.995909)
			(xy 409.690824 -397.016986) (xy 409.691332 -397.018002) (xy 409.771638 -397.15694) (xy 410.313632 -397.15694)
			(xy 410.313632 -397.156432) (xy 410.314068 -397.132438) (xy 410.321571 -397.085039) (xy 410.336398 -397.039399)
			(xy 410.358183 -396.99664) (xy 410.386389 -396.957816) (xy 410.420322 -396.923884) (xy 410.459147 -396.895678)
			(xy 410.501906 -396.873895) (xy 410.547547 -396.859069) (xy 410.594946 -396.851567) (xy 410.61894 -396.851124)
			(xy 410.642876 -396.851571) (xy 410.690163 -396.859029) (xy 410.735708 -396.873771) (xy 410.778395 -396.895437)
			(xy 410.817181 -396.923497) (xy 410.851115 -396.957263) (xy 410.879367 -396.995909) (xy 410.89072 -397.016986)
			(xy 410.891228 -397.018002) (xy 410.971534 -397.15694) (xy 411.513528 -397.15694) (xy 411.513528 -397.156432)
			(xy 411.513968 -397.132438) (xy 411.521471 -397.08504) (xy 411.536297 -397.0394) (xy 411.558082 -396.996641)
			(xy 411.586288 -396.957818) (xy 411.620221 -396.923885) (xy 411.659045 -396.89568) (xy 411.701804 -396.873896)
			(xy 411.747444 -396.85907) (xy 411.794842 -396.851568) (xy 411.818836 -396.851124) (xy 411.842772 -396.851574)
			(xy 411.890058 -396.859031) (xy 411.935603 -396.873773) (xy 411.978291 -396.895439) (xy 412.017077 -396.923498)
			(xy 412.051011 -396.957264) (xy 412.079263 -396.995909) (xy 412.090616 -397.016986) (xy 412.091124 -397.018002)
			(xy 412.17143 -397.15694) (xy 412.713424 -397.15694) (xy 412.713424 -397.156432) (xy 412.713891 -397.132453)
			(xy 412.721386 -397.085083) (xy 412.736195 -397.039469) (xy 412.757955 -396.996731) (xy 412.786131 -396.957922)
			(xy 412.820029 -396.923996) (xy 412.858814 -396.895788) (xy 412.901534 -396.873993) (xy 412.947136 -396.859145)
			(xy 412.994499 -396.851611) (xy 413.018478 -396.851124) (xy 413.018986 -396.851124) (xy 413.042923 -396.851534)
			(xy 413.090212 -396.858998) (xy 413.135757 -396.873748) (xy 413.178445 -396.89542) (xy 413.21723 -396.923485)
			(xy 413.251164 -396.957256) (xy 413.279414 -396.995907) (xy 413.290766 -397.016986) (xy 413.291274 -397.018002)
			(xy 413.37158 -397.15694) (xy 413.91332 -397.15694) (xy 413.91332 -397.156432) (xy 413.913791 -397.132453)
			(xy 413.921285 -397.085084) (xy 413.936095 -397.03947) (xy 413.957855 -396.996732) (xy 413.98603 -396.957923)
			(xy 414.019927 -396.923998) (xy 414.058712 -396.89579) (xy 414.101431 -396.873994) (xy 414.147033 -396.859146)
			(xy 414.194395 -396.851612) (xy 414.218374 -396.851124) (xy 414.218882 -396.851124) (xy 414.242819 -396.851537)
			(xy 414.290108 -396.859001) (xy 414.335653 -396.87375) (xy 414.378341 -396.895422) (xy 414.417126 -396.923486)
			(xy 414.451059 -396.957257) (xy 414.47931 -396.995907) (xy 414.490662 -397.016986) (xy 414.49117 -397.018002)
			(xy 414.571476 -397.15694) (xy 415.113724 -397.15694) (xy 415.113724 -397.156432) (xy 415.114168 -397.132438)
			(xy 415.121671 -397.085041) (xy 415.136497 -397.039401) (xy 415.158281 -396.996643) (xy 415.186487 -396.957819)
			(xy 415.220419 -396.923887) (xy 415.259243 -396.895681) (xy 415.302001 -396.873897) (xy 415.347641 -396.859071)
			(xy 415.395038 -396.851568) (xy 415.419032 -396.851124) (xy 415.442968 -396.851578) (xy 415.490254 -396.859034)
			(xy 415.535799 -396.873775) (xy 415.578487 -396.89544) (xy 415.617272 -396.923499) (xy 415.651207 -396.957264)
			(xy 415.679459 -396.995909) (xy 415.690812 -397.016986) (xy 415.69132 -397.018002) (xy 415.771626 -397.15694)
			(xy 416.31362 -397.15694) (xy 416.31362 -397.156432) (xy 416.314068 -397.132438) (xy 416.321571 -397.085041)
			(xy 416.336397 -397.039402) (xy 416.35818 -396.996644) (xy 416.386386 -396.95782) (xy 416.420317 -396.923888)
			(xy 416.45914 -396.895682) (xy 416.501898 -396.873898) (xy 416.547537 -396.859072) (xy 416.594934 -396.851568)
			(xy 416.618928 -396.851124) (xy 416.642863 -396.851581) (xy 416.69015 -396.859037) (xy 416.735695 -396.873777)
			(xy 416.778382 -396.895442) (xy 416.817168 -396.9235) (xy 416.851103 -396.957265) (xy 416.879355 -396.995909)
			(xy 416.890708 -397.016986) (xy 416.891216 -397.018002) (xy 416.971522 -397.15694) (xy 417.513516 -397.15694)
			(xy 417.513516 -397.156432) (xy 417.513968 -397.132439) (xy 417.521471 -397.085042) (xy 417.536296 -397.039403)
			(xy 417.55808 -396.996645) (xy 417.586284 -396.957822) (xy 417.620216 -396.92389) (xy 417.659038 -396.895684)
			(xy 417.701795 -396.873899) (xy 417.747434 -396.859072) (xy 417.794831 -396.851568) (xy 417.818824 -396.851124)
			(xy 417.842759 -396.851584) (xy 417.890046 -396.859039) (xy 417.93559 -396.873779) (xy 417.978278 -396.895444)
			(xy 418.017064 -396.923501) (xy 418.050998 -396.957265) (xy 418.079251 -396.99591) (xy 418.090604 -397.016986)
			(xy 418.091112 -397.018002) (xy 418.171418 -397.15694) (xy 418.713412 -397.15694) (xy 418.713412 -397.156432)
			(xy 418.713891 -397.132453) (xy 418.721385 -397.085085) (xy 418.736194 -397.039472) (xy 418.757953 -396.996735)
			(xy 418.786127 -396.957926) (xy 418.820024 -396.924) (xy 418.858808 -396.895792) (xy 418.901525 -396.873996)
			(xy 418.947126 -396.859147) (xy 418.994488 -396.851612) (xy 419.018466 -396.851124) (xy 419.018974 -396.851124)
			(xy 419.042911 -396.851543) (xy 419.090199 -396.859006) (xy 419.135744 -396.873754) (xy 419.178432 -396.895425)
			(xy 419.217218 -396.923488) (xy 419.251151 -396.957258) (xy 419.279402 -396.995907) (xy 419.290754 -397.016986)
			(xy 419.291262 -397.018002) (xy 419.371568 -397.15694) (xy 419.913308 -397.15694) (xy 419.913308 -397.156432)
			(xy 419.913791 -397.132454) (xy 419.921285 -397.085086) (xy 419.936094 -397.039473) (xy 419.957852 -396.996736)
			(xy 419.986026 -396.957927) (xy 420.019922 -396.924002) (xy 420.058705 -396.895794) (xy 420.101423 -396.873997)
			(xy 420.147023 -396.859148) (xy 420.194384 -396.851612) (xy 420.218362 -396.851124) (xy 420.21887 -396.851124)
			(xy 420.242807 -396.851547) (xy 420.290095 -396.859009) (xy 420.33564 -396.873756) (xy 420.378328 -396.895426)
			(xy 420.417113 -396.923489) (xy 420.451047 -396.957259) (xy 420.479298 -396.995907) (xy 420.49065 -397.016986)
			(xy 420.491158 -397.018002) (xy 420.571464 -397.15694) (xy 421.113712 -397.15694) (xy 421.113712 -397.156432)
			(xy 421.114168 -397.132439) (xy 421.12167 -397.085042) (xy 421.136496 -397.039404) (xy 421.158279 -396.996646)
			(xy 421.186483 -396.957823) (xy 421.220414 -396.923891) (xy 421.259236 -396.895685) (xy 421.301992 -396.8739)
			(xy 421.347631 -396.859073) (xy 421.395027 -396.851569) (xy 421.41902 -396.851124) (xy 421.442955 -396.851587)
			(xy 421.490241 -396.859042) (xy 421.535786 -396.873782) (xy 421.578474 -396.895445) (xy 421.61726 -396.923502)
			(xy 421.651194 -396.957266) (xy 421.679447 -396.99591) (xy 421.6908 -397.016986) (xy 421.691308 -397.018002)
			(xy 422.083738 -397.696944) (xy 422.096544 -397.720286) (xy 422.114771 -397.770304) (xy 422.124039 -397.822727)
			(xy 422.124632 -397.849344) (xy 422.124179 -397.873323) (xy 422.116675 -397.920689) (xy 422.101859 -397.9663)
			(xy 422.080094 -398.009034) (xy 422.051916 -398.04784) (xy 422.018018 -398.081764) (xy 421.979234 -398.109971)
			(xy 421.936517 -398.131769) (xy 421.890917 -398.14662) (xy 421.843556 -398.154161) (xy 421.819578 -398.154652)
			(xy 421.81907 -398.154652) (xy 421.795497 -398.154255) (xy 421.74891 -398.14701) (xy 421.703993 -398.132683)
			(xy 421.661815 -398.111614) (xy 421.623383 -398.084306) (xy 421.58961 -398.051409) (xy 421.561302 -398.013706)
			(xy 421.54983 -397.993108) (xy 421.549322 -397.992346) (xy 421.151558 -397.304006) (xy 421.139682 -397.281329)
			(xy 421.122831 -397.232996) (xy 421.114258 -397.182533) (xy 421.113712 -397.15694) (xy 420.571464 -397.15694)
			(xy 420.883588 -397.696944) (xy 420.896302 -397.720272) (xy 420.914403 -397.770215) (xy 420.923627 -397.82253)
			(xy 420.924228 -397.84909) (xy 420.924228 -397.849344) (xy 420.923778 -397.873335) (xy 420.916266 -397.920727)
			(xy 420.901434 -397.96636) (xy 420.879647 -398.009111) (xy 420.851441 -398.047928) (xy 420.81751 -398.081856)
			(xy 420.778691 -398.110059) (xy 420.735937 -398.131843) (xy 420.690303 -398.146672) (xy 420.642911 -398.15418)
			(xy 420.61892 -398.154652) (xy 420.595348 -398.154215) (xy 420.548763 -398.146978) (xy 420.503847 -398.132658)
			(xy 420.46167 -398.111595) (xy 420.423236 -398.084293) (xy 420.389462 -398.051402) (xy 420.361153 -398.013704)
			(xy 420.34968 -397.993108) (xy 420.349172 -397.992346) (xy 419.951408 -397.304006) (xy 419.939493 -397.281337)
			(xy 419.922555 -397.233012) (xy 419.913896 -397.182542) (xy 419.913308 -397.15694) (xy 419.371568 -397.15694)
			(xy 419.683692 -397.696944) (xy 419.696406 -397.720272) (xy 419.714507 -397.770215) (xy 419.723731 -397.82253)
			(xy 419.724332 -397.84909) (xy 419.724332 -397.849344) (xy 419.723878 -397.873335) (xy 419.716366 -397.920726)
			(xy 419.701534 -397.966359) (xy 419.679747 -398.00911) (xy 419.651542 -398.047927) (xy 419.617612 -398.081855)
			(xy 419.578793 -398.110058) (xy 419.53604 -398.131842) (xy 419.490407 -398.146671) (xy 419.443015 -398.15418)
			(xy 419.419024 -398.154652) (xy 419.395452 -398.154211) (xy 419.348867 -398.146975) (xy 419.303951 -398.132656)
			(xy 419.261774 -398.111594) (xy 419.223341 -398.084292) (xy 419.189567 -398.051401) (xy 419.161257 -398.013704)
			(xy 419.149784 -397.993108) (xy 419.149276 -397.992346) (xy 418.751512 -397.304006) (xy 418.739598 -397.281337)
			(xy 418.72266 -397.233012) (xy 418.714 -397.182542) (xy 418.713412 -397.15694) (xy 418.171418 -397.15694)
			(xy 418.483542 -397.696944) (xy 418.496349 -397.720286) (xy 418.514576 -397.770304) (xy 418.523843 -397.822727)
			(xy 418.524436 -397.849344) (xy 418.523979 -397.873322) (xy 418.516475 -397.920688) (xy 418.501659 -397.966299)
			(xy 418.479895 -398.009033) (xy 418.451717 -398.047839) (xy 418.41782 -398.081762) (xy 418.379036 -398.10997)
			(xy 418.336319 -398.131768) (xy 418.29072 -398.14662) (xy 418.24336 -398.15416) (xy 418.219382 -398.154652)
			(xy 418.218874 -398.154652) (xy 418.195301 -398.154252) (xy 418.148714 -398.147008) (xy 418.103797 -398.132681)
			(xy 418.06162 -398.111613) (xy 418.023187 -398.084305) (xy 417.989414 -398.051408) (xy 417.961106 -398.013706)
			(xy 417.949634 -397.993108) (xy 417.949126 -397.992346) (xy 417.551362 -397.304006) (xy 417.539486 -397.281329)
			(xy 417.522635 -397.232996) (xy 417.514062 -397.182533) (xy 417.513516 -397.15694) (xy 416.971522 -397.15694)
			(xy 417.283646 -397.696944) (xy 417.296453 -397.720286) (xy 417.31468 -397.770304) (xy 417.323947 -397.822727)
			(xy 417.32454 -397.849344) (xy 417.324079 -397.873322) (xy 417.316575 -397.920688) (xy 417.301759 -397.966298)
			(xy 417.279995 -398.009032) (xy 417.251818 -398.047837) (xy 417.217922 -398.081761) (xy 417.179138 -398.109969)
			(xy 417.136422 -398.131767) (xy 417.090824 -398.146619) (xy 417.043464 -398.15416) (xy 417.019486 -398.154652)
			(xy 417.018978 -398.154652) (xy 416.995405 -398.154249) (xy 416.948818 -398.147005) (xy 416.903901 -398.132679)
			(xy 416.861724 -398.111611) (xy 416.823291 -398.084304) (xy 416.789518 -398.051408) (xy 416.76121 -398.013706)
			(xy 416.749738 -397.993108) (xy 416.74923 -397.992346) (xy 416.351466 -397.304006) (xy 416.339591 -397.281329)
			(xy 416.322739 -397.232996) (xy 416.314166 -397.182533) (xy 416.31362 -397.15694) (xy 415.771626 -397.15694)
			(xy 416.08375 -397.696944) (xy 416.096557 -397.720285) (xy 416.114784 -397.770304) (xy 416.124051 -397.822726)
			(xy 416.124644 -397.849344) (xy 416.124179 -397.873322) (xy 416.116676 -397.920687) (xy 416.10186 -397.966297)
			(xy 416.080096 -398.00903) (xy 416.05192 -398.047836) (xy 416.018023 -398.08176) (xy 415.97924 -398.109967)
			(xy 415.936525 -398.131765) (xy 415.890927 -398.146618) (xy 415.843568 -398.15416) (xy 415.81959 -398.154652)
			(xy 415.819082 -398.154652) (xy 415.795509 -398.154245) (xy 415.748922 -398.147003) (xy 415.704006 -398.132677)
			(xy 415.661828 -398.11161) (xy 415.623395 -398.084303) (xy 415.589623 -398.051407) (xy 415.561314 -398.013706)
			(xy 415.549842 -397.993108) (xy 415.549334 -397.992346) (xy 415.15157 -397.304006) (xy 415.139695 -397.281329)
			(xy 415.122843 -397.232996) (xy 415.11427 -397.182533) (xy 415.113724 -397.15694) (xy 414.571476 -397.15694)
			(xy 414.8836 -397.696944) (xy 414.896315 -397.720271) (xy 414.914415 -397.770215) (xy 414.923639 -397.82253)
			(xy 414.92424 -397.84909) (xy 414.92424 -397.849344) (xy 414.923778 -397.873335) (xy 414.916266 -397.920725)
			(xy 414.901435 -397.966357) (xy 414.879649 -398.009107) (xy 414.851444 -398.047924) (xy 414.817515 -398.081852)
			(xy 414.778697 -398.110055) (xy 414.735946 -398.13184) (xy 414.690313 -398.146669) (xy 414.642923 -398.154179)
			(xy 414.618932 -398.154652) (xy 414.59536 -398.154205) (xy 414.548776 -398.14697) (xy 414.50386 -398.132651)
			(xy 414.461683 -398.111591) (xy 414.423249 -398.08429) (xy 414.389475 -398.0514) (xy 414.361165 -398.013703)
			(xy 414.349692 -397.993108) (xy 414.349184 -397.992346) (xy 413.95142 -397.304006) (xy 413.939506 -397.281337)
			(xy 413.922568 -397.233012) (xy 413.913908 -397.182542) (xy 413.91332 -397.15694) (xy 413.37158 -397.15694)
			(xy 413.683704 -397.696944) (xy 413.696419 -397.720271) (xy 413.71452 -397.770214) (xy 413.723743 -397.82253)
			(xy 413.724344 -397.84909) (xy 413.724344 -397.849344) (xy 413.723878 -397.873335) (xy 413.716367 -397.920724)
			(xy 413.701535 -397.966356) (xy 413.679749 -398.009106) (xy 413.651545 -398.047923) (xy 413.617617 -398.08185)
			(xy 413.578799 -398.110054) (xy 413.536049 -398.131838) (xy 413.490417 -398.146668) (xy 413.443027 -398.154179)
			(xy 413.419036 -398.154652) (xy 413.395464 -398.154202) (xy 413.34888 -398.146967) (xy 413.303964 -398.132649)
			(xy 413.261787 -398.111589) (xy 413.223353 -398.084289) (xy 413.189579 -398.051399) (xy 413.161269 -398.013703)
			(xy 413.149796 -397.993108) (xy 413.149288 -397.992346) (xy 412.751524 -397.304006) (xy 412.739611 -397.281337)
			(xy 412.722672 -397.233012) (xy 412.714012 -397.182542) (xy 412.713424 -397.15694) (xy 412.17143 -397.15694)
			(xy 412.483554 -397.696944) (xy 412.496362 -397.720285) (xy 412.514588 -397.770304) (xy 412.523855 -397.822726)
			(xy 412.524448 -397.849344) (xy 412.523979 -397.873322) (xy 412.516476 -397.920687) (xy 412.50166 -397.966296)
			(xy 412.479897 -398.009029) (xy 412.451721 -398.047835) (xy 412.417825 -398.081758) (xy 412.379043 -398.109966)
			(xy 412.336328 -398.131764) (xy 412.29073 -398.146617) (xy 412.243371 -398.154159) (xy 412.219394 -398.154652)
			(xy 412.218886 -398.154652) (xy 412.195313 -398.154242) (xy 412.148727 -398.147) (xy 412.10381 -398.132675)
			(xy 412.061633 -398.111608) (xy 412.0232 -398.084302) (xy 411.989427 -398.051406) (xy 411.961119 -398.013705)
			(xy 411.949646 -397.993108) (xy 411.949138 -397.992346) (xy 411.551374 -397.304006) (xy 411.539499 -397.281329)
			(xy 411.522648 -397.232996) (xy 411.514074 -397.182533) (xy 411.513528 -397.15694) (xy 410.971534 -397.15694)
			(xy 411.283658 -397.696944) (xy 411.296466 -397.720285) (xy 411.314692 -397.770304) (xy 411.323959 -397.822726)
			(xy 411.324552 -397.849344) (xy 411.324079 -397.873322) (xy 411.316576 -397.920686) (xy 411.301761 -397.966295)
			(xy 411.279998 -398.009028) (xy 411.251822 -398.047833) (xy 411.217927 -398.081757) (xy 411.179145 -398.109965)
			(xy 411.13643 -398.131763) (xy 411.090833 -398.146616) (xy 411.043475 -398.154159) (xy 411.019498 -398.154652)
			(xy 411.01899 -398.154652) (xy 410.995417 -398.154239) (xy 410.948831 -398.146997) (xy 410.903914 -398.132673)
			(xy 410.861737 -398.111607) (xy 410.823304 -398.084301) (xy 410.789531 -398.051406) (xy 410.761223 -398.013705)
			(xy 410.74975 -397.993108) (xy 410.749242 -397.992346) (xy 410.351478 -397.304006) (xy 410.339603 -397.281328)
			(xy 410.322752 -397.232996) (xy 410.314178 -397.182533) (xy 410.313632 -397.15694) (xy 409.771638 -397.15694)
			(xy 410.083762 -397.696944) (xy 410.09657 -397.720285) (xy 410.114796 -397.770304) (xy 410.124063 -397.822726)
			(xy 410.124656 -397.849344) (xy 410.124179 -397.873321) (xy 410.116676 -397.920686) (xy 410.101861 -397.966295)
			(xy 410.080098 -398.009027) (xy 410.051923 -398.047832) (xy 410.018028 -398.081755) (xy 409.979247 -398.109963)
			(xy 409.936533 -398.131762) (xy 409.890937 -398.146616) (xy 409.843579 -398.154159) (xy 409.819602 -398.154652)
			(xy 409.819094 -398.154652) (xy 409.795521 -398.154236) (xy 409.748935 -398.146995) (xy 409.704019 -398.132671)
			(xy 409.661841 -398.111605) (xy 409.623408 -398.0843) (xy 409.589635 -398.051405) (xy 409.561327 -398.013705)
			(xy 409.549854 -397.993108) (xy 409.549346 -397.992346) (xy 409.151582 -397.304006) (xy 409.139708 -397.281328)
			(xy 409.122856 -397.232996) (xy 409.114282 -397.182533) (xy 409.113736 -397.15694) (xy 408.571488 -397.15694)
			(xy 408.883612 -397.696944) (xy 408.896328 -397.720271) (xy 408.914428 -397.770214) (xy 408.923651 -397.82253)
			(xy 408.924252 -397.84909) (xy 408.924252 -397.849344) (xy 408.923778 -397.873334) (xy 408.916267 -397.920723)
			(xy 408.901436 -397.966354) (xy 408.879651 -398.009104) (xy 408.851448 -398.04792) (xy 408.81752 -398.081848)
			(xy 408.778704 -398.110051) (xy 408.735954 -398.131836) (xy 408.690323 -398.146667) (xy 408.642934 -398.154178)
			(xy 408.618944 -398.154652) (xy 408.595373 -398.154195) (xy 408.548789 -398.146962) (xy 408.503873 -398.132645)
			(xy 408.461696 -398.111586) (xy 408.423262 -398.084287) (xy 408.389488 -398.051398) (xy 408.361178 -398.013703)
			(xy 408.349704 -397.993108) (xy 408.349196 -397.992346) (xy 407.951432 -397.304006) (xy 407.939519 -397.281336)
			(xy 407.92258 -397.233012) (xy 407.91392 -397.182542) (xy 407.913332 -397.15694) (xy 407.371592 -397.15694)
			(xy 407.683716 -397.696944) (xy 407.696432 -397.720271) (xy 407.714532 -397.770214) (xy 407.723755 -397.82253)
			(xy 407.724356 -397.84909) (xy 407.724356 -397.849344) (xy 407.723878 -397.873334) (xy 407.716367 -397.920723)
			(xy 407.701536 -397.966353) (xy 407.679752 -398.009103) (xy 407.651549 -398.047919) (xy 407.617622 -398.081846)
			(xy 407.578806 -398.11005) (xy 407.536057 -398.131835) (xy 407.490427 -398.146666) (xy 407.443038 -398.154178)
			(xy 407.419048 -398.154652) (xy 407.395477 -398.154192) (xy 407.348893 -398.146959) (xy 407.303977 -398.132643)
			(xy 407.2618 -398.111585) (xy 407.223366 -398.084286) (xy 407.189592 -398.051398) (xy 407.161282 -398.013703)
			(xy 407.149808 -397.993108) (xy 407.1493 -397.992346) (xy 406.751536 -397.304006) (xy 406.739623 -397.281336)
			(xy 406.722684 -397.233012) (xy 406.714024 -397.182542) (xy 406.713436 -397.15694) (xy 406.171442 -397.15694)
			(xy 406.483566 -397.696944) (xy 406.496375 -397.720285) (xy 406.5146 -397.770303) (xy 406.523867 -397.822726)
			(xy 406.52446 -397.849344) (xy 406.524079 -397.873326) (xy 406.516573 -397.9207) (xy 406.501752 -397.966317)
			(xy 406.479981 -398.009055) (xy 406.451795 -398.047865) (xy 406.417888 -398.08179) (xy 406.379094 -398.109996)
			(xy 406.336367 -398.13179) (xy 406.290757 -398.146635) (xy 406.243388 -398.154166) (xy 406.219406 -398.154652)
			(xy 406.218898 -398.154652) (xy 406.195325 -398.154232) (xy 406.14874 -398.146992) (xy 406.103823 -398.132669)
			(xy 406.061646 -398.111604) (xy 406.023213 -398.084299) (xy 405.989439 -398.051405) (xy 405.961131 -398.013705)
			(xy 405.949658 -397.993108) (xy 405.94915 -397.992346) (xy 405.551386 -397.304006) (xy 405.539512 -397.281328)
			(xy 405.52266 -397.232996) (xy 405.514086 -397.182533) (xy 405.51354 -397.15694) (xy 404.971546 -397.15694)
			(xy 405.28367 -397.696944) (xy 405.296479 -397.720285) (xy 405.314704 -397.770303) (xy 405.323971 -397.822726)
			(xy 405.324564 -397.849344) (xy 405.324179 -397.873326) (xy 405.316673 -397.920699) (xy 405.301852 -397.966316)
			(xy 405.280081 -398.009054) (xy 405.251896 -398.047863) (xy 405.21799 -398.081788) (xy 405.179196 -398.109994)
			(xy 405.136469 -398.131788) (xy 405.090861 -398.146634) (xy 405.043492 -398.154166) (xy 405.01951 -398.154652)
			(xy 405.019002 -398.154652) (xy 404.995429 -398.154229) (xy 404.948844 -398.14699) (xy 404.903927 -398.132667)
			(xy 404.86175 -398.111602) (xy 404.823317 -398.084298) (xy 404.789544 -398.051404) (xy 404.761235 -398.013705)
			(xy 404.749762 -397.993108) (xy 404.749254 -397.992346) (xy 404.35149 -397.304006) (xy 404.339616 -397.281328)
			(xy 404.322764 -397.232995) (xy 404.31419 -397.182533) (xy 404.313644 -397.15694) (xy 403.77165 -397.15694)
			(xy 404.083774 -397.696944) (xy 404.096583 -397.720284) (xy 404.114808 -397.770303) (xy 404.124075 -397.822726)
			(xy 404.124668 -397.849344) (xy 404.124279 -397.873326) (xy 404.116773 -397.920698) (xy 404.101952 -397.966315)
			(xy 404.080182 -398.009053) (xy 404.051997 -398.047862) (xy 404.018091 -398.081787) (xy 403.979298 -398.109993)
			(xy 403.936572 -398.131787) (xy 403.890964 -398.146633) (xy 403.843595 -398.154165) (xy 403.819614 -398.154652)
			(xy 403.819106 -398.154652) (xy 403.795534 -398.154226) (xy 403.748948 -398.146987) (xy 403.704032 -398.132665)
			(xy 403.661854 -398.111601) (xy 403.623421 -398.084297) (xy 403.589648 -398.051404) (xy 403.561339 -398.013705)
			(xy 403.549866 -397.993108) (xy 403.549358 -397.992346) (xy 403.151594 -397.304006) (xy 403.139721 -397.281328)
			(xy 403.122868 -397.232995) (xy 403.114294 -397.182532) (xy 403.113748 -397.15694) (xy 389.243866 -397.15694)
			(xy 389.55599 -397.696944) (xy 389.568801 -397.720284) (xy 389.587025 -397.770303) (xy 389.596291 -397.822726)
			(xy 389.596884 -397.849344) (xy 389.596479 -397.873325) (xy 389.588973 -397.920696) (xy 389.574154 -397.966311)
			(xy 389.552385 -398.009048) (xy 389.524202 -398.047856) (xy 389.490298 -398.081781) (xy 389.451507 -398.109988)
			(xy 389.408783 -398.131783) (xy 389.363177 -398.14663) (xy 389.315811 -398.154164) (xy 389.29183 -398.154652)
			(xy 389.291322 -398.154652) (xy 389.26775 -398.154213) (xy 389.221165 -398.146976) (xy 389.176249 -398.132657)
			(xy 389.134072 -398.111595) (xy 389.095638 -398.084293) (xy 389.061865 -398.051401) (xy 389.033555 -398.013704)
			(xy 389.022082 -397.993108) (xy 389.021574 -397.992346) (xy 388.62381 -397.304006) (xy 388.61193 -397.281331)
			(xy 388.595082 -397.232997) (xy 388.58651 -397.182533) (xy 388.585964 -397.15694) (xy 388.043716 -397.15694)
			(xy 388.35584 -397.696944) (xy 388.368558 -397.72027) (xy 388.386657 -397.770214) (xy 388.395879 -397.82253)
			(xy 388.39648 -397.84909) (xy 388.39648 -397.849344) (xy 388.396078 -397.873338) (xy 388.388564 -397.920734)
			(xy 388.373729 -397.966371) (xy 388.351938 -398.009125) (xy 388.323726 -398.047945) (xy 388.28979 -398.081873)
			(xy 388.250964 -398.110075) (xy 388.208204 -398.131857) (xy 388.162564 -398.146681) (xy 388.115166 -398.154184)
			(xy 388.091172 -398.154652) (xy 388.067599 -398.154253) (xy 388.021012 -398.147009) (xy 387.976095 -398.132682)
			(xy 387.933917 -398.111614) (xy 387.895485 -398.084306) (xy 387.861712 -398.051408) (xy 387.833404 -398.013706)
			(xy 387.821932 -397.993108) (xy 387.821424 -397.992346) (xy 387.42366 -397.304006) (xy 387.411749 -397.281335)
			(xy 387.394809 -397.233011) (xy 387.386148 -397.182542) (xy 387.38556 -397.15694) (xy 386.84382 -397.15694)
			(xy 387.155944 -397.696944) (xy 387.168662 -397.720269) (xy 387.186761 -397.770214) (xy 387.195983 -397.82253)
			(xy 387.196584 -397.84909) (xy 387.196584 -397.849344) (xy 387.196178 -397.873338) (xy 387.188664 -397.920733)
			(xy 387.17383 -397.96637) (xy 387.152038 -398.009124) (xy 387.123828 -398.047943) (xy 387.089892 -398.081872)
			(xy 387.051066 -398.110074) (xy 387.008307 -398.131856) (xy 386.962667 -398.14668) (xy 386.91527 -398.154183)
			(xy 386.891276 -398.154652) (xy 386.867703 -398.15425) (xy 386.821116 -398.147007) (xy 386.776199 -398.13268)
			(xy 386.734022 -398.111612) (xy 386.695589 -398.084305) (xy 386.661816 -398.051408) (xy 386.633508 -398.013706)
			(xy 386.622036 -397.993108) (xy 386.621528 -397.992346) (xy 386.223764 -397.304006) (xy 386.211854 -397.281335)
			(xy 386.194914 -397.233011) (xy 386.186252 -397.182542) (xy 386.185664 -397.15694) (xy 385.64367 -397.15694)
			(xy 385.955794 -397.696944) (xy 385.968605 -397.720283) (xy 385.986829 -397.770303) (xy 385.996095 -397.822726)
			(xy 385.996688 -397.849344) (xy 385.996279 -397.873325) (xy 385.988774 -397.920695) (xy 385.973954 -397.96631)
			(xy 385.952186 -398.009047) (xy 385.924003 -398.047855) (xy 385.8901 -398.08178) (xy 385.851309 -398.109986)
			(xy 385.808586 -398.131782) (xy 385.76298 -398.146629) (xy 385.715614 -398.154164) (xy 385.691634 -398.154652)
			(xy 385.691126 -398.154652) (xy 385.667554 -398.15421) (xy 385.620969 -398.146974) (xy 385.576053 -398.132654)
			(xy 385.533876 -398.111593) (xy 385.495443 -398.084292) (xy 385.461669 -398.051401) (xy 385.433359 -398.013704)
			(xy 385.421886 -397.993108) (xy 385.421378 -397.992346) (xy 385.023614 -397.304006) (xy 385.011735 -397.281331)
			(xy 384.994886 -397.232997) (xy 384.986314 -397.182533) (xy 384.985768 -397.15694) (xy 384.443774 -397.15694)
			(xy 384.755898 -397.696944) (xy 384.768701 -397.720288) (xy 384.78693 -397.770305) (xy 384.796199 -397.822727)
			(xy 384.796792 -397.849344) (xy 384.796379 -397.873325) (xy 384.788874 -397.920695) (xy 384.774055 -397.966309)
			(xy 384.752287 -398.009046) (xy 384.724104 -398.047854) (xy 384.690201 -398.081778) (xy 384.651412 -398.109985)
			(xy 384.608689 -398.13178) (xy 384.563084 -398.146628) (xy 384.515718 -398.154164) (xy 384.491738 -398.154652)
			(xy 384.49123 -398.154652) (xy 384.467658 -398.154207) (xy 384.421074 -398.146971) (xy 384.376158 -398.132652)
			(xy 384.33398 -398.111592) (xy 384.295547 -398.084291) (xy 384.261773 -398.0514) (xy 384.233463 -398.013704)
			(xy 384.22199 -397.993108) (xy 384.221482 -397.992346) (xy 383.823718 -397.304006) (xy 383.811839 -397.281331)
			(xy 383.79499 -397.232997) (xy 383.786418 -397.182533) (xy 383.785872 -397.15694) (xy 383.243878 -397.15694)
			(xy 383.556002 -397.696944) (xy 383.568805 -397.720288) (xy 383.587034 -397.770305) (xy 383.596303 -397.822727)
			(xy 383.596896 -397.849344) (xy 383.596479 -397.873324) (xy 383.588974 -397.920694) (xy 383.574155 -397.966308)
			(xy 383.552387 -398.009045) (xy 383.524206 -398.047852) (xy 383.490303 -398.081777) (xy 383.451514 -398.109984)
			(xy 383.408792 -398.131779) (xy 383.363187 -398.146628) (xy 383.315822 -398.154163) (xy 383.291842 -398.154652)
			(xy 383.291334 -398.154652) (xy 383.267762 -398.154203) (xy 383.221178 -398.146969) (xy 383.176262 -398.13265)
			(xy 383.134085 -398.11159) (xy 383.095651 -398.08429) (xy 383.061877 -398.0514) (xy 383.033567 -398.013703)
			(xy 383.022094 -397.993108) (xy 383.021586 -397.992346) (xy 382.623822 -397.304006) (xy 382.611943 -397.281331)
			(xy 382.595094 -397.232996) (xy 382.586522 -397.182533) (xy 382.585976 -397.15694) (xy 382.043728 -397.15694)
			(xy 382.355852 -397.696944) (xy 382.368571 -397.720269) (xy 382.386669 -397.770214) (xy 382.395891 -397.82253)
			(xy 382.396492 -397.84909) (xy 382.396492 -397.849344) (xy 382.396078 -397.873337) (xy 382.388565 -397.920732)
			(xy 382.37373 -397.966368) (xy 382.35194 -398.009122) (xy 382.32373 -398.047941) (xy 382.289795 -398.081869)
			(xy 382.250971 -398.110071) (xy 382.208212 -398.131853) (xy 382.162574 -398.146679) (xy 382.115177 -398.154183)
			(xy 382.091184 -398.154652) (xy 382.067611 -398.154244) (xy 382.021025 -398.147001) (xy 381.976108 -398.132676)
			(xy 381.933931 -398.111609) (xy 381.895498 -398.084302) (xy 381.861725 -398.051407) (xy 381.833416 -398.013706)
			(xy 381.821944 -397.993108) (xy 381.821436 -397.992346) (xy 381.423672 -397.304006) (xy 381.411754 -397.281339)
			(xy 381.394818 -397.233013) (xy 381.386159 -397.182542) (xy 381.385572 -397.15694) (xy 380.843832 -397.15694)
			(xy 381.155956 -397.696944) (xy 381.168675 -397.720269) (xy 381.186773 -397.770214) (xy 381.195995 -397.822529)
			(xy 381.196596 -397.84909) (xy 381.196596 -397.849344) (xy 381.196178 -397.873337) (xy 381.188665 -397.920731)
			(xy 381.173831 -397.966367) (xy 381.152041 -398.009121) (xy 381.123831 -398.047939) (xy 381.089897 -398.081868)
			(xy 381.051073 -398.11007) (xy 381.008315 -398.131852) (xy 380.962677 -398.146678) (xy 380.915281 -398.154182)
			(xy 380.891288 -398.154652) (xy 380.867715 -398.154241) (xy 380.821129 -398.146999) (xy 380.776212 -398.132674)
			(xy 380.734035 -398.111608) (xy 380.695602 -398.084301) (xy 380.661829 -398.051406) (xy 380.633521 -398.013705)
			(xy 380.622048 -397.993108) (xy 380.62154 -397.992346) (xy 380.223776 -397.304006) (xy 380.211859 -397.281339)
			(xy 380.194923 -397.233013) (xy 380.186263 -397.182542) (xy 380.185676 -397.15694) (xy 379.643682 -397.15694)
			(xy 379.955806 -397.696944) (xy 379.96861 -397.720287) (xy 379.986838 -397.770304) (xy 379.996107 -397.822727)
			(xy 379.9967 -397.849344) (xy 379.996279 -397.873324) (xy 379.988774 -397.920694) (xy 379.973956 -397.966307)
			(xy 379.952188 -398.009044) (xy 379.924007 -398.047851) (xy 379.890105 -398.081775) (xy 379.851316 -398.109982)
			(xy 379.808594 -398.131778) (xy 379.76299 -398.146627) (xy 379.715626 -398.154163) (xy 379.691646 -398.154652)
			(xy 379.691138 -398.154652) (xy 379.667566 -398.1542) (xy 379.620982 -398.146966) (xy 379.576066 -398.132648)
			(xy 379.533889 -398.111589) (xy 379.495456 -398.084289) (xy 379.461681 -398.051399) (xy 379.433371 -398.013703)
			(xy 379.421898 -397.993108) (xy 379.42139 -397.992346) (xy 379.023626 -397.304006) (xy 379.011747 -397.28133)
			(xy 378.994898 -397.232996) (xy 378.986326 -397.182533) (xy 378.98578 -397.15694) (xy 378.443786 -397.15694)
			(xy 378.75591 -397.696944) (xy 378.768714 -397.720287) (xy 378.786943 -397.770304) (xy 378.796211 -397.822727)
			(xy 378.796804 -397.849344) (xy 378.796379 -397.873324) (xy 378.788874 -397.920693) (xy 378.774056 -397.966307)
			(xy 378.752289 -398.009042) (xy 378.724108 -398.04785) (xy 378.690206 -398.081774) (xy 378.651418 -398.109981)
			(xy 378.608697 -398.131777) (xy 378.563094 -398.146626) (xy 378.51573 -398.154163) (xy 378.49175 -398.154652)
			(xy 378.491242 -398.154652) (xy 378.467671 -398.154197) (xy 378.421086 -398.146963) (xy 378.376171 -398.132646)
			(xy 378.333993 -398.111587) (xy 378.29556 -398.084288) (xy 378.261786 -398.051398) (xy 378.233476 -398.013703)
			(xy 378.222002 -397.993108) (xy 378.221494 -397.992346) (xy 377.82373 -397.304006) (xy 377.811852 -397.28133)
			(xy 377.795002 -397.232996) (xy 377.78643 -397.182533) (xy 377.785884 -397.15694) (xy 377.24389 -397.15694)
			(xy 377.556014 -397.696944) (xy 377.568818 -397.720287) (xy 377.587047 -397.770304) (xy 377.596315 -397.822727)
			(xy 377.596908 -397.849344) (xy 377.596479 -397.873324) (xy 377.588974 -397.920693) (xy 377.574156 -397.966306)
			(xy 377.552389 -398.009041) (xy 377.524209 -398.047848) (xy 377.490308 -398.081772) (xy 377.45152 -398.10998)
			(xy 377.4088 -398.131776) (xy 377.363197 -398.146625) (xy 377.315833 -398.154162) (xy 377.291854 -398.154652)
			(xy 377.291346 -398.154652) (xy 377.267775 -398.154194) (xy 377.221191 -398.146961) (xy 377.176275 -398.132644)
			(xy 377.134098 -398.111586) (xy 377.095664 -398.084287) (xy 377.06189 -398.051398) (xy 377.03358 -398.013703)
			(xy 377.022106 -397.993108) (xy 377.021598 -397.992346) (xy 376.623834 -397.304006) (xy 376.611956 -397.28133)
			(xy 376.595106 -397.232996) (xy 376.586534 -397.182533) (xy 376.585988 -397.15694) (xy 376.04374 -397.15694)
			(xy 376.355864 -397.696944) (xy 376.368584 -397.720268) (xy 376.386681 -397.770213) (xy 376.395904 -397.822529)
			(xy 376.396504 -397.84909) (xy 376.396504 -397.849344) (xy 376.396078 -397.873337) (xy 376.388565 -397.92073)
			(xy 376.373731 -397.966365) (xy 376.351942 -398.009118) (xy 376.323733 -398.047937) (xy 376.2898 -398.081865)
			(xy 376.250977 -398.110067) (xy 376.208221 -398.13185) (xy 376.162583 -398.146676) (xy 376.115189 -398.154182)
			(xy 376.091196 -398.154652) (xy 376.067623 -398.154234) (xy 376.021037 -398.146993) (xy 375.976121 -398.13267)
			(xy 375.933944 -398.111605) (xy 375.89551 -398.084299) (xy 375.861737 -398.051405) (xy 375.833429 -398.013705)
			(xy 375.821956 -397.993108) (xy 375.821448 -397.992346) (xy 375.423684 -397.304006) (xy 375.411767 -397.281338)
			(xy 375.394831 -397.233013) (xy 375.386171 -397.182542) (xy 375.385584 -397.15694) (xy 374.843844 -397.15694)
			(xy 375.155968 -397.696944) (xy 375.168688 -397.720268) (xy 375.186786 -397.770213) (xy 375.196008 -397.822529)
			(xy 375.196608 -397.84909) (xy 375.196608 -397.849344) (xy 375.196178 -397.873336) (xy 375.188665 -397.92073)
			(xy 375.173832 -397.966364) (xy 375.152043 -398.009117) (xy 375.123835 -398.047935) (xy 375.089902 -398.081863)
			(xy 375.051079 -398.110066) (xy 375.008324 -398.131849) (xy 374.962687 -398.146676) (xy 374.915292 -398.154181)
			(xy 374.8913 -398.154652) (xy 374.867727 -398.154231) (xy 374.821142 -398.146991) (xy 374.776225 -398.132668)
			(xy 374.734048 -398.111603) (xy 374.695615 -398.084298) (xy 374.661842 -398.051404) (xy 374.633533 -398.013705)
			(xy 374.62206 -397.993108) (xy 374.621552 -397.992346) (xy 374.223788 -397.304006) (xy 374.211872 -397.281338)
			(xy 374.194935 -397.233013) (xy 374.186275 -397.182542) (xy 374.185688 -397.15694) (xy 373.643694 -397.15694)
			(xy 373.955818 -397.696944) (xy 373.968623 -397.720287) (xy 373.986851 -397.770304) (xy 373.996119 -397.822727)
			(xy 373.996712 -397.849344) (xy 373.996279 -397.873324) (xy 373.988774 -397.920692) (xy 373.973957 -397.966305)
			(xy 373.95219 -398.00904) (xy 373.92401 -398.047847) (xy 373.89011 -398.081771) (xy 373.851323 -398.109978)
			(xy 373.808603 -398.131775) (xy 373.763 -398.146624) (xy 373.715637 -398.154162) (xy 373.691658 -398.154652)
			(xy 373.69115 -398.154652) (xy 373.667579 -398.154191) (xy 373.620995 -398.146958) (xy 373.576079 -398.132642)
			(xy 373.533902 -398.111584) (xy 373.495468 -398.084286) (xy 373.461694 -398.051397) (xy 373.433384 -398.013703)
			(xy 373.42191 -397.993108) (xy 373.421402 -397.992346) (xy 373.023638 -397.304006) (xy 373.01176 -397.28133)
			(xy 372.994911 -397.232996) (xy 372.986338 -397.182533) (xy 372.985792 -397.15694) (xy 372.443798 -397.15694)
			(xy 372.755922 -397.696944) (xy 372.768727 -397.720287) (xy 372.786955 -397.770304) (xy 372.796223 -397.822727)
			(xy 372.796816 -397.849344) (xy 372.796379 -397.873323) (xy 372.788875 -397.920691) (xy 372.774057 -397.966304)
			(xy 372.752291 -398.009039) (xy 372.724111 -398.047846) (xy 372.690212 -398.08177) (xy 372.651425 -398.109977)
			(xy 372.608705 -398.131773) (xy 372.563104 -398.146624) (xy 372.515741 -398.154162) (xy 372.491762 -398.154652)
			(xy 372.491254 -398.154652) (xy 372.467683 -398.154187) (xy 372.421099 -398.146955) (xy 372.376184 -398.13264)
			(xy 372.334006 -398.111583) (xy 372.295573 -398.084285) (xy 372.261798 -398.051397) (xy 372.233488 -398.013702)
			(xy 372.222014 -397.993108) (xy 372.221506 -397.992346) (xy 371.823742 -397.304006) (xy 371.811865 -397.28133)
			(xy 371.795015 -397.232996) (xy 371.786442 -397.182533) (xy 371.785896 -397.15694) (xy 371.243902 -397.15694)
			(xy 371.556026 -397.696944) (xy 371.568831 -397.720286) (xy 371.587059 -397.770304) (xy 371.596327 -397.822727)
			(xy 371.59692 -397.849344) (xy 371.596479 -397.873323) (xy 371.588975 -397.920691) (xy 371.574157 -397.966303)
			(xy 371.552392 -398.009038) (xy 371.524213 -398.047844) (xy 371.490313 -398.081768) (xy 371.451527 -398.109975)
			(xy 371.408808 -398.131772) (xy 371.363207 -398.146623) (xy 371.315845 -398.154162) (xy 371.291866 -398.154652)
			(xy 371.291358 -398.154652) (xy 371.267787 -398.154184) (xy 371.221204 -398.146953) (xy 371.176288 -398.132638)
			(xy 371.134111 -398.111581) (xy 371.095677 -398.084284) (xy 371.061902 -398.051396) (xy 371.033592 -398.013702)
			(xy 371.022118 -397.993108) (xy 371.02161 -397.992346) (xy 370.623846 -397.304006) (xy 370.611969 -397.28133)
			(xy 370.595119 -397.232996) (xy 370.586546 -397.182533) (xy 370.586 -397.15694) (xy 354.671418 -397.15694)
			(xy 354.983542 -397.696944) (xy 354.996349 -397.720286) (xy 355.014576 -397.770304) (xy 355.023843 -397.822727)
			(xy 355.024436 -397.849344) (xy 355.023979 -397.873322) (xy 355.016475 -397.920688) (xy 355.001659 -397.966299)
			(xy 354.979895 -398.009033) (xy 354.951717 -398.047839) (xy 354.91782 -398.081762) (xy 354.879036 -398.10997)
			(xy 354.836319 -398.131768) (xy 354.79072 -398.14662) (xy 354.74336 -398.15416) (xy 354.719382 -398.154652)
			(xy 354.718874 -398.154652) (xy 354.695301 -398.154252) (xy 354.648714 -398.147008) (xy 354.603797 -398.132681)
			(xy 354.56162 -398.111613) (xy 354.523187 -398.084305) (xy 354.489414 -398.051408) (xy 354.461106 -398.013706)
			(xy 354.449634 -397.993108) (xy 354.449126 -397.992346) (xy 354.051362 -397.304006) (xy 354.039486 -397.281329)
			(xy 354.022635 -397.232996) (xy 354.014062 -397.182533) (xy 354.013516 -397.15694) (xy 353.471268 -397.15694)
			(xy 353.783392 -397.696944) (xy 353.796106 -397.720272) (xy 353.814207 -397.770215) (xy 353.823431 -397.82253)
			(xy 353.824032 -397.84909) (xy 353.824032 -397.849344) (xy 353.823578 -397.873335) (xy 353.816066 -397.920726)
			(xy 353.801234 -397.966359) (xy 353.779447 -398.00911) (xy 353.751242 -398.047927) (xy 353.717312 -398.081855)
			(xy 353.678493 -398.110058) (xy 353.63574 -398.131842) (xy 353.590107 -398.146671) (xy 353.542715 -398.15418)
			(xy 353.518724 -398.154652) (xy 353.495152 -398.154211) (xy 353.448567 -398.146975) (xy 353.403651 -398.132656)
			(xy 353.361474 -398.111594) (xy 353.323041 -398.084292) (xy 353.289267 -398.051401) (xy 353.260957 -398.013704)
			(xy 353.249484 -397.993108) (xy 353.248976 -397.992346) (xy 352.851212 -397.304006) (xy 352.839298 -397.281337)
			(xy 352.82236 -397.233012) (xy 352.8137 -397.182542) (xy 352.813112 -397.15694) (xy 352.271372 -397.15694)
			(xy 352.583496 -397.696944) (xy 352.59621 -397.720271) (xy 352.614311 -397.770215) (xy 352.623535 -397.82253)
			(xy 352.624136 -397.84909) (xy 352.624136 -397.849344) (xy 352.623678 -397.873335) (xy 352.616166 -397.920726)
			(xy 352.601335 -397.966358) (xy 352.579548 -398.009109) (xy 352.551343 -398.047926) (xy 352.517413 -398.081853)
			(xy 352.478595 -398.110056) (xy 352.435843 -398.131841) (xy 352.39021 -398.14667) (xy 352.342819 -398.154179)
			(xy 352.318828 -398.154652) (xy 352.295256 -398.154208) (xy 352.248672 -398.146972) (xy 352.203756 -398.132653)
			(xy 352.161578 -398.111592) (xy 352.123145 -398.084291) (xy 352.089371 -398.0514) (xy 352.061061 -398.013704)
			(xy 352.049588 -397.993108) (xy 352.04908 -397.992346) (xy 351.651316 -397.304006) (xy 351.639402 -397.281337)
			(xy 351.622464 -397.233012) (xy 351.613804 -397.182542) (xy 351.613216 -397.15694) (xy 351.071222 -397.15694)
			(xy 351.383346 -397.696944) (xy 351.396153 -397.720286) (xy 351.41438 -397.770304) (xy 351.423647 -397.822727)
			(xy 351.42424 -397.849344) (xy 351.423779 -397.873322) (xy 351.416275 -397.920688) (xy 351.401459 -397.966298)
			(xy 351.379695 -398.009032) (xy 351.351518 -398.047837) (xy 351.317622 -398.081761) (xy 351.278838 -398.109969)
			(xy 351.236122 -398.131767) (xy 351.190524 -398.146619) (xy 351.143164 -398.15416) (xy 351.119186 -398.154652)
			(xy 351.118678 -398.154652) (xy 351.095105 -398.154249) (xy 351.048518 -398.147005) (xy 351.003601 -398.132679)
			(xy 350.961424 -398.111611) (xy 350.922991 -398.084304) (xy 350.889218 -398.051408) (xy 350.86091 -398.013706)
			(xy 350.849438 -397.993108) (xy 350.84893 -397.992346) (xy 350.451166 -397.304006) (xy 350.439291 -397.281329)
			(xy 350.422439 -397.232996) (xy 350.413866 -397.182533) (xy 350.41332 -397.15694) (xy 349.871326 -397.15694)
			(xy 350.18345 -397.696944) (xy 350.196257 -397.720285) (xy 350.214484 -397.770304) (xy 350.223751 -397.822726)
			(xy 350.224344 -397.849344) (xy 350.223879 -397.873322) (xy 350.216376 -397.920687) (xy 350.20156 -397.966297)
			(xy 350.179796 -398.00903) (xy 350.15162 -398.047836) (xy 350.117723 -398.08176) (xy 350.07894 -398.109967)
			(xy 350.036225 -398.131765) (xy 349.990627 -398.146618) (xy 349.943268 -398.15416) (xy 349.91929 -398.154652)
			(xy 349.918782 -398.154652) (xy 349.895209 -398.154245) (xy 349.848622 -398.147003) (xy 349.803706 -398.132677)
			(xy 349.761528 -398.11161) (xy 349.723095 -398.084303) (xy 349.689323 -398.051407) (xy 349.661014 -398.013706)
			(xy 349.649542 -397.993108) (xy 349.649034 -397.992346) (xy 349.25127 -397.304006) (xy 349.239395 -397.281329)
			(xy 349.222543 -397.232996) (xy 349.21397 -397.182533) (xy 349.213424 -397.15694) (xy 348.67143 -397.15694)
			(xy 348.983554 -397.696944) (xy 348.996362 -397.720285) (xy 349.014588 -397.770304) (xy 349.023855 -397.822726)
			(xy 349.024448 -397.849344) (xy 349.023979 -397.873322) (xy 349.016476 -397.920687) (xy 349.00166 -397.966296)
			(xy 348.979897 -398.009029) (xy 348.951721 -398.047835) (xy 348.917825 -398.081758) (xy 348.879043 -398.109966)
			(xy 348.836328 -398.131764) (xy 348.79073 -398.146617) (xy 348.743371 -398.154159) (xy 348.719394 -398.154652)
			(xy 348.718886 -398.154652) (xy 348.695313 -398.154242) (xy 348.648727 -398.147) (xy 348.60381 -398.132675)
			(xy 348.561633 -398.111608) (xy 348.5232 -398.084302) (xy 348.489427 -398.051406) (xy 348.461119 -398.013705)
			(xy 348.449646 -397.993108) (xy 348.449138 -397.992346) (xy 348.051374 -397.304006) (xy 348.039499 -397.281329)
			(xy 348.022648 -397.232996) (xy 348.014074 -397.182533) (xy 348.013528 -397.15694) (xy 347.47128 -397.15694)
			(xy 347.783404 -397.696944) (xy 347.796119 -397.720271) (xy 347.81422 -397.770214) (xy 347.823443 -397.82253)
			(xy 347.824044 -397.84909) (xy 347.824044 -397.849344) (xy 347.823578 -397.873335) (xy 347.816067 -397.920724)
			(xy 347.801235 -397.966356) (xy 347.779449 -398.009106) (xy 347.751245 -398.047923) (xy 347.717317 -398.08185)
			(xy 347.678499 -398.110054) (xy 347.635749 -398.131838) (xy 347.590117 -398.146668) (xy 347.542727 -398.154179)
			(xy 347.518736 -398.154652) (xy 347.495164 -398.154202) (xy 347.44858 -398.146967) (xy 347.403664 -398.132649)
			(xy 347.361487 -398.111589) (xy 347.323053 -398.084289) (xy 347.289279 -398.051399) (xy 347.260969 -398.013703)
			(xy 347.249496 -397.993108) (xy 347.248988 -397.992346) (xy 346.851224 -397.304006) (xy 346.839311 -397.281337)
			(xy 346.822372 -397.233012) (xy 346.813712 -397.182542) (xy 346.813124 -397.15694) (xy 346.271384 -397.15694)
			(xy 346.583508 -397.696944) (xy 346.596223 -397.720271) (xy 346.614324 -397.770214) (xy 346.623547 -397.82253)
			(xy 346.624148 -397.84909) (xy 346.624148 -397.849344) (xy 346.623678 -397.873334) (xy 346.616167 -397.920724)
			(xy 346.601336 -397.966355) (xy 346.57955 -398.009105) (xy 346.551346 -398.047922) (xy 346.517418 -398.081849)
			(xy 346.478602 -398.110052) (xy 346.435851 -398.131837) (xy 346.39022 -398.146668) (xy 346.34283 -398.154178)
			(xy 346.31884 -398.154652) (xy 346.295269 -398.154199) (xy 346.248684 -398.146965) (xy 346.203769 -398.132647)
			(xy 346.161591 -398.111588) (xy 346.123158 -398.084288) (xy 346.089383 -398.051399) (xy 346.061073 -398.013703)
			(xy 346.0496 -397.993108) (xy 346.049092 -397.992346) (xy 345.651328 -397.304006) (xy 345.639415 -397.281337)
			(xy 345.622476 -397.233012) (xy 345.613816 -397.182542) (xy 345.613228 -397.15694) (xy 345.071234 -397.15694)
			(xy 345.383358 -397.696944) (xy 345.396166 -397.720285) (xy 345.414392 -397.770304) (xy 345.423659 -397.822726)
			(xy 345.424252 -397.849344) (xy 345.423779 -397.873322) (xy 345.416276 -397.920686) (xy 345.401461 -397.966295)
			(xy 345.379698 -398.009028) (xy 345.351522 -398.047833) (xy 345.317627 -398.081757) (xy 345.278845 -398.109965)
			(xy 345.23613 -398.131763) (xy 345.190533 -398.146616) (xy 345.143175 -398.154159) (xy 345.119198 -398.154652)
			(xy 345.11869 -398.154652) (xy 345.095117 -398.154239) (xy 345.048531 -398.146997) (xy 345.003614 -398.132673)
			(xy 344.961437 -398.111607) (xy 344.923004 -398.084301) (xy 344.889231 -398.051406) (xy 344.860923 -398.013705)
			(xy 344.84945 -397.993108) (xy 344.848942 -397.992346) (xy 344.451178 -397.304006) (xy 344.439303 -397.281328)
			(xy 344.422452 -397.232996) (xy 344.413878 -397.182533) (xy 344.413332 -397.15694) (xy 343.871338 -397.15694)
			(xy 344.183462 -397.696944) (xy 344.19627 -397.720285) (xy 344.214496 -397.770304) (xy 344.223763 -397.822726)
			(xy 344.224356 -397.849344) (xy 344.223879 -397.873321) (xy 344.216376 -397.920686) (xy 344.201561 -397.966295)
			(xy 344.179798 -398.009027) (xy 344.151623 -398.047832) (xy 344.117728 -398.081755) (xy 344.078947 -398.109963)
			(xy 344.036233 -398.131762) (xy 343.990637 -398.146616) (xy 343.943279 -398.154159) (xy 343.919302 -398.154652)
			(xy 343.918794 -398.154652) (xy 343.895221 -398.154236) (xy 343.848635 -398.146995) (xy 343.803719 -398.132671)
			(xy 343.761541 -398.111605) (xy 343.723108 -398.0843) (xy 343.689335 -398.051405) (xy 343.661027 -398.013705)
			(xy 343.649554 -397.993108) (xy 343.649046 -397.992346) (xy 343.251282 -397.304006) (xy 343.239408 -397.281328)
			(xy 343.222556 -397.232996) (xy 343.213982 -397.182533) (xy 343.213436 -397.15694) (xy 342.671442 -397.15694)
			(xy 342.983566 -397.696944) (xy 342.996375 -397.720285) (xy 343.0146 -397.770303) (xy 343.023867 -397.822726)
			(xy 343.02446 -397.849344) (xy 343.024079 -397.873326) (xy 343.016573 -397.9207) (xy 343.001752 -397.966317)
			(xy 342.979981 -398.009055) (xy 342.951795 -398.047865) (xy 342.917888 -398.08179) (xy 342.879094 -398.109996)
			(xy 342.836367 -398.13179) (xy 342.790757 -398.146635) (xy 342.743388 -398.154166) (xy 342.719406 -398.154652)
			(xy 342.718898 -398.154652) (xy 342.695325 -398.154232) (xy 342.64874 -398.146992) (xy 342.603823 -398.132669)
			(xy 342.561646 -398.111604) (xy 342.523213 -398.084299) (xy 342.489439 -398.051405) (xy 342.461131 -398.013705)
			(xy 342.449658 -397.993108) (xy 342.44915 -397.992346) (xy 342.051386 -397.304006) (xy 342.039512 -397.281328)
			(xy 342.02266 -397.232996) (xy 342.014086 -397.182533) (xy 342.01354 -397.15694) (xy 341.471292 -397.15694)
			(xy 341.783416 -397.696944) (xy 341.796132 -397.720271) (xy 341.814232 -397.770214) (xy 341.823455 -397.82253)
			(xy 341.824056 -397.84909) (xy 341.824056 -397.849344) (xy 341.823578 -397.873334) (xy 341.816067 -397.920723)
			(xy 341.801236 -397.966353) (xy 341.779452 -398.009103) (xy 341.751249 -398.047919) (xy 341.717322 -398.081846)
			(xy 341.678506 -398.11005) (xy 341.635757 -398.131835) (xy 341.590127 -398.146666) (xy 341.542738 -398.154178)
			(xy 341.518748 -398.154652) (xy 341.495177 -398.154192) (xy 341.448593 -398.146959) (xy 341.403677 -398.132643)
			(xy 341.3615 -398.111585) (xy 341.323066 -398.084286) (xy 341.289292 -398.051398) (xy 341.260982 -398.013703)
			(xy 341.249508 -397.993108) (xy 341.249 -397.992346) (xy 340.851236 -397.304006) (xy 340.839323 -397.281336)
			(xy 340.822384 -397.233012) (xy 340.813724 -397.182542) (xy 340.813136 -397.15694) (xy 340.271396 -397.15694)
			(xy 340.58352 -397.696944) (xy 340.596236 -397.72027) (xy 340.614336 -397.770214) (xy 340.623559 -397.82253)
			(xy 340.62416 -397.84909) (xy 340.62416 -397.849344) (xy 340.623802 -397.873341) (xy 340.616287 -397.920742)
			(xy 340.60145 -397.966385) (xy 340.579655 -398.009144) (xy 340.551439 -398.047968) (xy 340.517498 -398.081899)
			(xy 340.478666 -398.110103) (xy 340.4359 -398.131885) (xy 340.390253 -398.146709) (xy 340.342849 -398.154209)
			(xy 340.318852 -398.154652) (xy 340.295281 -398.154189) (xy 340.248697 -398.146957) (xy 340.203782 -398.132641)
			(xy 340.161604 -398.111583) (xy 340.123171 -398.084285) (xy 340.089396 -398.051397) (xy 340.061086 -398.013703)
			(xy 340.049612 -397.993108) (xy 340.049104 -397.992346) (xy 339.65134 -397.304006) (xy 339.639428 -397.281336)
			(xy 339.622488 -397.233012) (xy 339.613828 -397.182542) (xy 339.61324 -397.15694) (xy 339.071246 -397.15694)
			(xy 339.38337 -397.696944) (xy 339.396179 -397.720285) (xy 339.414404 -397.770303) (xy 339.423671 -397.822726)
			(xy 339.424264 -397.849344) (xy 339.423879 -397.873326) (xy 339.416373 -397.920699) (xy 339.401552 -397.966316)
			(xy 339.379781 -398.009054) (xy 339.351596 -398.047863) (xy 339.31769 -398.081788) (xy 339.278896 -398.109994)
			(xy 339.236169 -398.131788) (xy 339.190561 -398.146634) (xy 339.143192 -398.154166) (xy 339.11921 -398.154652)
			(xy 339.118702 -398.154652) (xy 339.095129 -398.154229) (xy 339.048544 -398.14699) (xy 339.003627 -398.132667)
			(xy 338.96145 -398.111602) (xy 338.923017 -398.084298) (xy 338.889244 -398.051404) (xy 338.860935 -398.013705)
			(xy 338.849462 -397.993108) (xy 338.848954 -397.992346) (xy 338.45119 -397.304006) (xy 338.439316 -397.281328)
			(xy 338.422464 -397.232995) (xy 338.41389 -397.182533) (xy 338.413344 -397.15694) (xy 337.87135 -397.15694)
			(xy 338.183474 -397.696944) (xy 338.196283 -397.720284) (xy 338.214508 -397.770303) (xy 338.223775 -397.822726)
			(xy 338.224368 -397.849344) (xy 338.223979 -397.873326) (xy 338.216473 -397.920698) (xy 338.201652 -397.966315)
			(xy 338.179882 -398.009053) (xy 338.151697 -398.047862) (xy 338.117791 -398.081787) (xy 338.078998 -398.109993)
			(xy 338.036272 -398.131787) (xy 337.990664 -398.146633) (xy 337.943295 -398.154165) (xy 337.919314 -398.154652)
			(xy 337.918806 -398.154652) (xy 337.895234 -398.154226) (xy 337.848648 -398.146987) (xy 337.803732 -398.132665)
			(xy 337.761554 -398.111601) (xy 337.723121 -398.084297) (xy 337.689348 -398.051404) (xy 337.661039 -398.013705)
			(xy 337.649566 -397.993108) (xy 337.649058 -397.992346) (xy 337.251294 -397.304006) (xy 337.239421 -397.281328)
			(xy 337.222568 -397.232995) (xy 337.213994 -397.182532) (xy 337.213448 -397.15694) (xy 336.671454 -397.15694)
			(xy 336.983578 -397.696944) (xy 336.996388 -397.720284) (xy 337.014613 -397.770303) (xy 337.023879 -397.822726)
			(xy 337.024472 -397.849344) (xy 337.024079 -397.873326) (xy 337.016573 -397.920698) (xy 337.001753 -397.966314)
			(xy 336.979983 -398.009052) (xy 336.951799 -398.047861) (xy 336.917893 -398.081785) (xy 336.8791 -398.109992)
			(xy 336.836375 -398.131786) (xy 336.790767 -398.146632) (xy 336.743399 -398.154165) (xy 336.719418 -398.154652)
			(xy 336.71891 -398.154652) (xy 336.695338 -398.154223) (xy 336.648752 -398.146984) (xy 336.603836 -398.132663)
			(xy 336.561659 -398.111599) (xy 336.523225 -398.084296) (xy 336.489452 -398.051403) (xy 336.461143 -398.013704)
			(xy 336.44967 -397.993108) (xy 336.449162 -397.992346) (xy 336.051398 -397.304006) (xy 336.039525 -397.281328)
			(xy 336.022672 -397.232995) (xy 336.014098 -397.182532) (xy 336.013552 -397.15694) (xy 322.14367 -397.15694)
			(xy 322.455794 -397.696944) (xy 322.468605 -397.720283) (xy 322.486829 -397.770303) (xy 322.496095 -397.822726)
			(xy 322.496688 -397.849344) (xy 322.496279 -397.873325) (xy 322.488774 -397.920695) (xy 322.473954 -397.96631)
			(xy 322.452186 -398.009047) (xy 322.424003 -398.047855) (xy 322.3901 -398.08178) (xy 322.351309 -398.109986)
			(xy 322.308586 -398.131782) (xy 322.26298 -398.146629) (xy 322.215614 -398.154164) (xy 322.191634 -398.154652)
			(xy 322.191126 -398.154652) (xy 322.167554 -398.15421) (xy 322.120969 -398.146974) (xy 322.076053 -398.132654)
			(xy 322.033876 -398.111593) (xy 321.995443 -398.084292) (xy 321.961669 -398.051401) (xy 321.933359 -398.013704)
			(xy 321.921886 -397.993108) (xy 321.921378 -397.992346) (xy 321.523614 -397.304006) (xy 321.511735 -397.281331)
			(xy 321.494886 -397.232997) (xy 321.486314 -397.182533) (xy 321.485768 -397.15694) (xy 320.94352 -397.15694)
			(xy 321.255644 -397.696944) (xy 321.268362 -397.720269) (xy 321.286461 -397.770214) (xy 321.295683 -397.82253)
			(xy 321.296284 -397.84909) (xy 321.296284 -397.849344) (xy 321.295878 -397.873338) (xy 321.288364 -397.920733)
			(xy 321.27353 -397.96637) (xy 321.251738 -398.009124) (xy 321.223528 -398.047943) (xy 321.189592 -398.081872)
			(xy 321.150766 -398.110074) (xy 321.108007 -398.131856) (xy 321.062367 -398.14668) (xy 321.01497 -398.154183)
			(xy 320.990976 -398.154652) (xy 320.967403 -398.15425) (xy 320.920816 -398.147007) (xy 320.875899 -398.13268)
			(xy 320.833722 -398.111612) (xy 320.795289 -398.084305) (xy 320.761516 -398.051408) (xy 320.733208 -398.013706)
			(xy 320.721736 -397.993108) (xy 320.721228 -397.992346) (xy 320.323464 -397.304006) (xy 320.311554 -397.281335)
			(xy 320.294614 -397.233011) (xy 320.285952 -397.182542) (xy 320.285364 -397.15694) (xy 319.743624 -397.15694)
			(xy 320.055748 -397.696944) (xy 320.068467 -397.720269) (xy 320.086565 -397.770214) (xy 320.095787 -397.82253)
			(xy 320.096388 -397.84909) (xy 320.096388 -397.849344) (xy 320.095978 -397.873337) (xy 320.088465 -397.920733)
			(xy 320.07363 -397.966369) (xy 320.051839 -398.009123) (xy 320.023629 -398.047942) (xy 319.989693 -398.08187)
			(xy 319.950868 -398.110073) (xy 319.90811 -398.131854) (xy 319.86247 -398.14668) (xy 319.815074 -398.154183)
			(xy 319.79108 -398.154652) (xy 319.767507 -398.154247) (xy 319.72092 -398.147004) (xy 319.676003 -398.132678)
			(xy 319.633826 -398.111611) (xy 319.595393 -398.084304) (xy 319.561621 -398.051407) (xy 319.533312 -398.013706)
			(xy 319.52184 -397.993108) (xy 319.521332 -397.992346) (xy 319.123568 -397.304006) (xy 319.111658 -397.281335)
			(xy 319.094718 -397.233011) (xy 319.086056 -397.182542) (xy 319.085468 -397.15694) (xy 318.543474 -397.15694)
			(xy 318.855598 -397.696944) (xy 318.868401 -397.720288) (xy 318.88663 -397.770305) (xy 318.895899 -397.822727)
			(xy 318.896492 -397.849344) (xy 318.896079 -397.873325) (xy 318.888574 -397.920695) (xy 318.873755 -397.966309)
			(xy 318.851987 -398.009046) (xy 318.823804 -398.047854) (xy 318.789901 -398.081778) (xy 318.751112 -398.109985)
			(xy 318.708389 -398.13178) (xy 318.662784 -398.146628) (xy 318.615418 -398.154164) (xy 318.591438 -398.154652)
			(xy 318.59093 -398.154652) (xy 318.567358 -398.154207) (xy 318.520774 -398.146971) (xy 318.475858 -398.132652)
			(xy 318.43368 -398.111592) (xy 318.395247 -398.084291) (xy 318.361473 -398.0514) (xy 318.333163 -398.013704)
			(xy 318.32169 -397.993108) (xy 318.321182 -397.992346) (xy 317.923418 -397.304006) (xy 317.911539 -397.281331)
			(xy 317.89469 -397.232997) (xy 317.886118 -397.182533) (xy 317.885572 -397.15694) (xy 317.343578 -397.15694)
			(xy 317.655702 -397.696944) (xy 317.668505 -397.720288) (xy 317.686734 -397.770305) (xy 317.696003 -397.822727)
			(xy 317.696596 -397.849344) (xy 317.696179 -397.873324) (xy 317.688674 -397.920694) (xy 317.673855 -397.966308)
			(xy 317.652087 -398.009045) (xy 317.623906 -398.047852) (xy 317.590003 -398.081777) (xy 317.551214 -398.109984)
			(xy 317.508492 -398.131779) (xy 317.462887 -398.146628) (xy 317.415522 -398.154163) (xy 317.391542 -398.154652)
			(xy 317.391034 -398.154652) (xy 317.367462 -398.154203) (xy 317.320878 -398.146969) (xy 317.275962 -398.13265)
			(xy 317.233785 -398.11159) (xy 317.195351 -398.08429) (xy 317.161577 -398.0514) (xy 317.133267 -398.013703)
			(xy 317.121794 -397.993108) (xy 317.121286 -397.992346) (xy 316.723522 -397.304006) (xy 316.711643 -397.281331)
			(xy 316.694794 -397.232996) (xy 316.686222 -397.182533) (xy 316.685676 -397.15694) (xy 316.143682 -397.15694)
			(xy 316.455806 -397.696944) (xy 316.46861 -397.720287) (xy 316.486838 -397.770304) (xy 316.496107 -397.822727)
			(xy 316.4967 -397.849344) (xy 316.496279 -397.873324) (xy 316.488774 -397.920694) (xy 316.473956 -397.966307)
			(xy 316.452188 -398.009044) (xy 316.424007 -398.047851) (xy 316.390105 -398.081775) (xy 316.351316 -398.109982)
			(xy 316.308594 -398.131778) (xy 316.26299 -398.146627) (xy 316.215626 -398.154163) (xy 316.191646 -398.154652)
			(xy 316.191138 -398.154652) (xy 316.167566 -398.1542) (xy 316.120982 -398.146966) (xy 316.076066 -398.132648)
			(xy 316.033889 -398.111589) (xy 315.995456 -398.084289) (xy 315.961681 -398.051399) (xy 315.933371 -398.013703)
			(xy 315.921898 -397.993108) (xy 315.92139 -397.992346) (xy 315.523626 -397.304006) (xy 315.511747 -397.28133)
			(xy 315.494898 -397.232996) (xy 315.486326 -397.182533) (xy 315.48578 -397.15694) (xy 314.943532 -397.15694)
			(xy 315.255656 -397.696944) (xy 315.268375 -397.720269) (xy 315.286473 -397.770214) (xy 315.295695 -397.822529)
			(xy 315.296296 -397.84909) (xy 315.296296 -397.849344) (xy 315.295878 -397.873337) (xy 315.288365 -397.920731)
			(xy 315.273531 -397.966367) (xy 315.251741 -398.009121) (xy 315.223531 -398.047939) (xy 315.189597 -398.081868)
			(xy 315.150773 -398.11007) (xy 315.108015 -398.131852) (xy 315.062377 -398.146678) (xy 315.014981 -398.154182)
			(xy 314.990988 -398.154652) (xy 314.967415 -398.154241) (xy 314.920829 -398.146999) (xy 314.875912 -398.132674)
			(xy 314.833735 -398.111608) (xy 314.795302 -398.084301) (xy 314.761529 -398.051406) (xy 314.733221 -398.013705)
			(xy 314.721748 -397.993108) (xy 314.72124 -397.992346) (xy 314.323476 -397.304006) (xy 314.311559 -397.281339)
			(xy 314.294623 -397.233013) (xy 314.285963 -397.182542) (xy 314.285376 -397.15694) (xy 313.743636 -397.15694)
			(xy 314.05576 -397.696944) (xy 314.06848 -397.720269) (xy 314.086577 -397.770214) (xy 314.095799 -397.822529)
			(xy 314.0964 -397.84909) (xy 314.0964 -397.849344) (xy 314.095978 -397.873337) (xy 314.088465 -397.920731)
			(xy 314.073631 -397.966366) (xy 314.051841 -398.009119) (xy 314.023632 -398.047938) (xy 313.989698 -398.081866)
			(xy 313.950875 -398.110069) (xy 313.908118 -398.131851) (xy 313.86248 -398.146677) (xy 313.815085 -398.154182)
			(xy 313.791092 -398.154652) (xy 313.767519 -398.154237) (xy 313.720933 -398.146996) (xy 313.676016 -398.132672)
			(xy 313.633839 -398.111606) (xy 313.595406 -398.0843) (xy 313.561633 -398.051406) (xy 313.533325 -398.013705)
			(xy 313.521852 -397.993108) (xy 313.521344 -397.992346) (xy 313.12358 -397.304006) (xy 313.111663 -397.281339)
			(xy 313.094727 -397.233013) (xy 313.086067 -397.182542) (xy 313.08548 -397.15694) (xy 312.543486 -397.15694)
			(xy 312.85561 -397.696944) (xy 312.868414 -397.720287) (xy 312.886643 -397.770304) (xy 312.895911 -397.822727)
			(xy 312.896504 -397.849344) (xy 312.896079 -397.873324) (xy 312.888574 -397.920693) (xy 312.873756 -397.966307)
			(xy 312.851989 -398.009042) (xy 312.823808 -398.04785) (xy 312.789906 -398.081774) (xy 312.751118 -398.109981)
			(xy 312.708397 -398.131777) (xy 312.662794 -398.146626) (xy 312.61543 -398.154163) (xy 312.59145 -398.154652)
			(xy 312.590942 -398.154652) (xy 312.567371 -398.154197) (xy 312.520786 -398.146963) (xy 312.475871 -398.132646)
			(xy 312.433693 -398.111587) (xy 312.39526 -398.084288) (xy 312.361486 -398.051398) (xy 312.333176 -398.013703)
			(xy 312.321702 -397.993108) (xy 312.321194 -397.992346) (xy 311.92343 -397.304006) (xy 311.911552 -397.28133)
			(xy 311.894702 -397.232996) (xy 311.88613 -397.182533) (xy 311.885584 -397.15694) (xy 311.34359 -397.15694)
			(xy 311.655714 -397.696944) (xy 311.668518 -397.720287) (xy 311.686747 -397.770304) (xy 311.696015 -397.822727)
			(xy 311.696608 -397.849344) (xy 311.696179 -397.873324) (xy 311.688674 -397.920693) (xy 311.673856 -397.966306)
			(xy 311.652089 -398.009041) (xy 311.623909 -398.047848) (xy 311.590008 -398.081772) (xy 311.55122 -398.10998)
			(xy 311.5085 -398.131776) (xy 311.462897 -398.146625) (xy 311.415533 -398.154162) (xy 311.391554 -398.154652)
			(xy 311.391046 -398.154652) (xy 311.367475 -398.154194) (xy 311.320891 -398.146961) (xy 311.275975 -398.132644)
			(xy 311.233798 -398.111586) (xy 311.195364 -398.084287) (xy 311.16159 -398.051398) (xy 311.13328 -398.013703)
			(xy 311.121806 -397.993108) (xy 311.121298 -397.992346) (xy 310.723534 -397.304006) (xy 310.711656 -397.28133)
			(xy 310.694806 -397.232996) (xy 310.686234 -397.182533) (xy 310.685688 -397.15694) (xy 310.143694 -397.15694)
			(xy 310.455818 -397.696944) (xy 310.468623 -397.720287) (xy 310.486851 -397.770304) (xy 310.496119 -397.822727)
			(xy 310.496712 -397.849344) (xy 310.496279 -397.873324) (xy 310.488774 -397.920692) (xy 310.473957 -397.966305)
			(xy 310.45219 -398.00904) (xy 310.42401 -398.047847) (xy 310.39011 -398.081771) (xy 310.351323 -398.109978)
			(xy 310.308603 -398.131775) (xy 310.263 -398.146624) (xy 310.215637 -398.154162) (xy 310.191658 -398.154652)
			(xy 310.19115 -398.154652) (xy 310.167579 -398.154191) (xy 310.120995 -398.146958) (xy 310.076079 -398.132642)
			(xy 310.033902 -398.111584) (xy 309.995468 -398.084286) (xy 309.961694 -398.051397) (xy 309.933384 -398.013703)
			(xy 309.92191 -397.993108) (xy 309.921402 -397.992346) (xy 309.523638 -397.304006) (xy 309.51176 -397.28133)
			(xy 309.494911 -397.232996) (xy 309.486338 -397.182533) (xy 309.485792 -397.15694) (xy 308.943544 -397.15694)
			(xy 309.255668 -397.696944) (xy 309.268388 -397.720268) (xy 309.286486 -397.770213) (xy 309.295708 -397.822529)
			(xy 309.296308 -397.84909) (xy 309.296308 -397.849344) (xy 309.295878 -397.873336) (xy 309.288365 -397.92073)
			(xy 309.273532 -397.966364) (xy 309.251743 -398.009117) (xy 309.223535 -398.047935) (xy 309.189602 -398.081863)
			(xy 309.150779 -398.110066) (xy 309.108024 -398.131849) (xy 309.062387 -398.146676) (xy 309.014992 -398.154181)
			(xy 308.991 -398.154652) (xy 308.967427 -398.154231) (xy 308.920842 -398.146991) (xy 308.875925 -398.132668)
			(xy 308.833748 -398.111603) (xy 308.795315 -398.084298) (xy 308.761542 -398.051404) (xy 308.733233 -398.013705)
			(xy 308.72176 -397.993108) (xy 308.721252 -397.992346) (xy 308.323488 -397.304006) (xy 308.311572 -397.281338)
			(xy 308.294635 -397.233013) (xy 308.285975 -397.182542) (xy 308.285388 -397.15694) (xy 307.743648 -397.15694)
			(xy 308.055772 -397.696944) (xy 308.068493 -397.720268) (xy 308.08659 -397.770213) (xy 308.095812 -397.822529)
			(xy 308.096412 -397.84909) (xy 308.096412 -397.849344) (xy 308.095978 -397.873336) (xy 308.088465 -397.920729)
			(xy 308.073632 -397.966363) (xy 308.051844 -398.009116) (xy 308.023636 -398.047934) (xy 307.989703 -398.081862)
			(xy 307.950882 -398.110065) (xy 307.908126 -398.131848) (xy 307.86249 -398.146675) (xy 307.815096 -398.154181)
			(xy 307.791104 -398.154652) (xy 307.767532 -398.154228) (xy 307.720946 -398.146988) (xy 307.676029 -398.132666)
			(xy 307.633852 -398.111602) (xy 307.595419 -398.084297) (xy 307.561646 -398.051404) (xy 307.533337 -398.013705)
			(xy 307.521864 -397.993108) (xy 307.521356 -397.992346) (xy 307.123592 -397.304006) (xy 307.111676 -397.281338)
			(xy 307.094739 -397.233012) (xy 307.086079 -397.182542) (xy 307.085492 -397.15694) (xy 306.543498 -397.15694)
			(xy 306.855622 -397.696944) (xy 306.868427 -397.720287) (xy 306.886655 -397.770304) (xy 306.895923 -397.822727)
			(xy 306.896516 -397.849344) (xy 306.896079 -397.873323) (xy 306.888575 -397.920691) (xy 306.873757 -397.966304)
			(xy 306.851991 -398.009039) (xy 306.823811 -398.047846) (xy 306.789912 -398.08177) (xy 306.751125 -398.109977)
			(xy 306.708405 -398.131773) (xy 306.662804 -398.146624) (xy 306.615441 -398.154162) (xy 306.591462 -398.154652)
			(xy 306.590954 -398.154652) (xy 306.567383 -398.154187) (xy 306.520799 -398.146955) (xy 306.475884 -398.13264)
			(xy 306.433706 -398.111583) (xy 306.395273 -398.084285) (xy 306.361498 -398.051397) (xy 306.333188 -398.013702)
			(xy 306.321714 -397.993108) (xy 306.321206 -397.992346) (xy 305.923442 -397.304006) (xy 305.911565 -397.28133)
			(xy 305.894715 -397.232996) (xy 305.886142 -397.182533) (xy 305.885596 -397.15694) (xy 305.343602 -397.15694)
			(xy 305.655726 -397.696944) (xy 305.668531 -397.720286) (xy 305.686759 -397.770304) (xy 305.696027 -397.822727)
			(xy 305.69662 -397.849344) (xy 305.696179 -397.873323) (xy 305.688675 -397.920691) (xy 305.673857 -397.966303)
			(xy 305.652092 -398.009038) (xy 305.623913 -398.047844) (xy 305.590013 -398.081768) (xy 305.551227 -398.109975)
			(xy 305.508508 -398.131772) (xy 305.462907 -398.146623) (xy 305.415545 -398.154162) (xy 305.391566 -398.154652)
			(xy 305.391058 -398.154652) (xy 305.367487 -398.154184) (xy 305.320904 -398.146953) (xy 305.275988 -398.132638)
			(xy 305.233811 -398.111581) (xy 305.195377 -398.084284) (xy 305.161602 -398.051396) (xy 305.133292 -398.013702)
			(xy 305.121818 -397.993108) (xy 305.12131 -397.992346) (xy 304.723546 -397.304006) (xy 304.711669 -397.28133)
			(xy 304.694819 -397.232996) (xy 304.686246 -397.182533) (xy 304.6857 -397.15694) (xy 304.143706 -397.15694)
			(xy 304.45583 -397.696944) (xy 304.468636 -397.720286) (xy 304.486863 -397.770304) (xy 304.496131 -397.822727)
			(xy 304.496724 -397.849344) (xy 304.496279 -397.873323) (xy 304.488775 -397.92069) (xy 304.473958 -397.966302)
			(xy 304.452192 -398.009036) (xy 304.424014 -398.047843) (xy 304.390115 -398.081767) (xy 304.351329 -398.109974)
			(xy 304.308611 -398.131771) (xy 304.26301 -398.146622) (xy 304.215649 -398.154161) (xy 304.19167 -398.154652)
			(xy 304.191162 -398.154652) (xy 304.167591 -398.154181) (xy 304.121008 -398.14695) (xy 304.076092 -398.132636)
			(xy 304.033915 -398.11158) (xy 303.995481 -398.084283) (xy 303.961707 -398.051396) (xy 303.933396 -398.013702)
			(xy 303.921922 -397.993108) (xy 303.921414 -397.992346) (xy 303.52365 -397.304006) (xy 303.511773 -397.281329)
			(xy 303.494923 -397.232996) (xy 303.48635 -397.182533) (xy 303.485804 -397.15694) (xy 280.68524 -397.15694)
			(xy 280.68524 -401.674838) (xy 303.434496 -401.674838) (xy 303.434496 -400.811238) (xy 303.434982 -400.783969)
			(xy 303.442744 -400.729985) (xy 303.458109 -400.677655) (xy 303.480766 -400.628045) (xy 303.510252 -400.582164)
			(xy 303.545967 -400.540947) (xy 303.587184 -400.505232) (xy 303.633065 -400.475746) (xy 303.682675 -400.453089)
			(xy 303.735005 -400.437724) (xy 303.788989 -400.429962) (xy 303.843527 -400.429962) (xy 303.897511 -400.437724)
			(xy 303.949841 -400.453089) (xy 303.999451 -400.475746) (xy 304.045332 -400.505232) (xy 304.086549 -400.540947)
			(xy 304.122264 -400.582164) (xy 304.15175 -400.628045) (xy 304.174407 -400.677655) (xy 304.189772 -400.729985)
			(xy 304.197534 -400.783969) (xy 304.19802 -400.811238) (xy 304.19802 -401.674838) (xy 304.634392 -401.674838)
			(xy 304.634392 -400.811238) (xy 304.634878 -400.783969) (xy 304.64264 -400.729985) (xy 304.658005 -400.677655)
			(xy 304.680662 -400.628045) (xy 304.710148 -400.582164) (xy 304.745863 -400.540947) (xy 304.78708 -400.505232)
			(xy 304.832961 -400.475746) (xy 304.882571 -400.453089) (xy 304.934901 -400.437724) (xy 304.988885 -400.429962)
			(xy 305.043423 -400.429962) (xy 305.097407 -400.437724) (xy 305.149737 -400.453089) (xy 305.199347 -400.475746)
			(xy 305.245228 -400.505232) (xy 305.286445 -400.540947) (xy 305.32216 -400.582164) (xy 305.351646 -400.628045)
			(xy 305.374303 -400.677655) (xy 305.389668 -400.729985) (xy 305.39743 -400.783969) (xy 305.397916 -400.811238)
			(xy 305.397916 -401.674838) (xy 305.834796 -401.674838) (xy 305.834796 -400.811238) (xy 305.835282 -400.783987)
			(xy 305.843038 -400.730039) (xy 305.858393 -400.677744) (xy 305.881035 -400.628167) (xy 305.910501 -400.582317)
			(xy 305.946192 -400.541126) (xy 305.987383 -400.505435) (xy 306.033233 -400.475969) (xy 306.08281 -400.453327)
			(xy 306.135105 -400.437972) (xy 306.189053 -400.430216) (xy 306.243555 -400.430216) (xy 306.297503 -400.437972)
			(xy 306.349798 -400.453327) (xy 306.399375 -400.475969) (xy 306.445225 -400.505435) (xy 306.486416 -400.541126)
			(xy 306.522107 -400.582317) (xy 306.551573 -400.628167) (xy 306.574215 -400.677744) (xy 306.58957 -400.730039)
			(xy 306.597326 -400.783987) (xy 306.597812 -400.811238) (xy 306.597812 -401.674838) (xy 307.034692 -401.674838)
			(xy 307.034692 -400.811238) (xy 307.035178 -400.783987) (xy 307.042934 -400.730039) (xy 307.058289 -400.677744)
			(xy 307.080931 -400.628167) (xy 307.110397 -400.582317) (xy 307.146088 -400.541126) (xy 307.187279 -400.505435)
			(xy 307.233129 -400.475969) (xy 307.282706 -400.453327) (xy 307.335001 -400.437972) (xy 307.388949 -400.430216)
			(xy 307.443451 -400.430216) (xy 307.497399 -400.437972) (xy 307.549694 -400.453327) (xy 307.599271 -400.475969)
			(xy 307.645121 -400.505435) (xy 307.686312 -400.541126) (xy 307.722003 -400.582317) (xy 307.751469 -400.628167)
			(xy 307.774111 -400.677744) (xy 307.789466 -400.730039) (xy 307.797222 -400.783987) (xy 307.797708 -400.811238)
			(xy 307.797708 -401.674838) (xy 308.234588 -401.674838) (xy 308.234588 -400.811238) (xy 308.235074 -400.783969)
			(xy 308.242836 -400.729985) (xy 308.258201 -400.677655) (xy 308.280858 -400.628045) (xy 308.310344 -400.582164)
			(xy 308.346059 -400.540947) (xy 308.387276 -400.505232) (xy 308.433157 -400.475746) (xy 308.482767 -400.453089)
			(xy 308.535097 -400.437724) (xy 308.589081 -400.429962) (xy 308.643619 -400.429962) (xy 308.697603 -400.437724)
			(xy 308.749933 -400.453089) (xy 308.799543 -400.475746) (xy 308.845424 -400.505232) (xy 308.886641 -400.540947)
			(xy 308.922356 -400.582164) (xy 308.951842 -400.628045) (xy 308.974499 -400.677655) (xy 308.989864 -400.729985)
			(xy 308.997626 -400.783969) (xy 308.998112 -400.811238) (xy 308.998112 -401.674838) (xy 309.434484 -401.674838)
			(xy 309.434484 -400.811238) (xy 309.43497 -400.783969) (xy 309.442732 -400.729985) (xy 309.458097 -400.677655)
			(xy 309.480754 -400.628045) (xy 309.51024 -400.582164) (xy 309.545955 -400.540947) (xy 309.587172 -400.505232)
			(xy 309.633053 -400.475746) (xy 309.682663 -400.453089) (xy 309.734993 -400.437724) (xy 309.788977 -400.429962)
			(xy 309.843515 -400.429962) (xy 309.897499 -400.437724) (xy 309.949829 -400.453089) (xy 309.999439 -400.475746)
			(xy 310.04532 -400.505232) (xy 310.086537 -400.540947) (xy 310.122252 -400.582164) (xy 310.151738 -400.628045)
			(xy 310.174395 -400.677655) (xy 310.18976 -400.729985) (xy 310.197522 -400.783969) (xy 310.198008 -400.811238)
			(xy 310.198008 -401.674838) (xy 310.634888 -401.674838) (xy 310.634888 -400.811238) (xy 310.635374 -400.783987)
			(xy 310.64313 -400.730039) (xy 310.658485 -400.677744) (xy 310.681127 -400.628167) (xy 310.710593 -400.582317)
			(xy 310.746284 -400.541126) (xy 310.787475 -400.505435) (xy 310.833325 -400.475969) (xy 310.882902 -400.453327)
			(xy 310.935197 -400.437972) (xy 310.989145 -400.430216) (xy 311.043647 -400.430216) (xy 311.097595 -400.437972)
			(xy 311.14989 -400.453327) (xy 311.199467 -400.475969) (xy 311.245317 -400.505435) (xy 311.286508 -400.541126)
			(xy 311.322199 -400.582317) (xy 311.351665 -400.628167) (xy 311.374307 -400.677744) (xy 311.389662 -400.730039)
			(xy 311.397418 -400.783987) (xy 311.397904 -400.811238) (xy 311.397904 -401.674838) (xy 311.834784 -401.674838)
			(xy 311.834784 -400.811238) (xy 311.83527 -400.783987) (xy 311.843026 -400.730039) (xy 311.858381 -400.677744)
			(xy 311.881023 -400.628167) (xy 311.910489 -400.582317) (xy 311.94618 -400.541126) (xy 311.987371 -400.505435)
			(xy 312.033221 -400.475969) (xy 312.082798 -400.453327) (xy 312.135093 -400.437972) (xy 312.189041 -400.430216)
			(xy 312.243543 -400.430216) (xy 312.297491 -400.437972) (xy 312.349786 -400.453327) (xy 312.399363 -400.475969)
			(xy 312.445213 -400.505435) (xy 312.486404 -400.541126) (xy 312.522095 -400.582317) (xy 312.551561 -400.628167)
			(xy 312.574203 -400.677744) (xy 312.589558 -400.730039) (xy 312.597314 -400.783987) (xy 312.5978 -400.811238)
			(xy 312.5978 -401.674838) (xy 313.03468 -401.674838) (xy 313.03468 -400.811238) (xy 313.035166 -400.783969)
			(xy 313.042928 -400.729985) (xy 313.058293 -400.677655) (xy 313.08095 -400.628045) (xy 313.110436 -400.582164)
			(xy 313.146151 -400.540947) (xy 313.187368 -400.505232) (xy 313.233249 -400.475746) (xy 313.282859 -400.453089)
			(xy 313.335189 -400.437724) (xy 313.389173 -400.429962) (xy 313.443711 -400.429962) (xy 313.497695 -400.437724)
			(xy 313.550025 -400.453089) (xy 313.599635 -400.475746) (xy 313.645516 -400.505232) (xy 313.686733 -400.540947)
			(xy 313.722448 -400.582164) (xy 313.751934 -400.628045) (xy 313.774591 -400.677655) (xy 313.789956 -400.729985)
			(xy 313.797718 -400.783969) (xy 313.798204 -400.811238) (xy 313.798204 -401.674838) (xy 314.234576 -401.674838)
			(xy 314.234576 -400.811238) (xy 314.235062 -400.783969) (xy 314.242824 -400.729985) (xy 314.258189 -400.677655)
			(xy 314.280846 -400.628045) (xy 314.310332 -400.582164) (xy 314.346047 -400.540947) (xy 314.387264 -400.505232)
			(xy 314.433145 -400.475746) (xy 314.482755 -400.453089) (xy 314.535085 -400.437724) (xy 314.589069 -400.429962)
			(xy 314.643607 -400.429962) (xy 314.697591 -400.437724) (xy 314.749921 -400.453089) (xy 314.799531 -400.475746)
			(xy 314.845412 -400.505232) (xy 314.886629 -400.540947) (xy 314.922344 -400.582164) (xy 314.95183 -400.628045)
			(xy 314.974487 -400.677655) (xy 314.989852 -400.729985) (xy 314.997614 -400.783969) (xy 314.9981 -400.811238)
			(xy 314.9981 -401.674838) (xy 315.43498 -401.674838) (xy 315.43498 -400.811238) (xy 315.435466 -400.783987)
			(xy 315.443222 -400.730039) (xy 315.458577 -400.677744) (xy 315.481219 -400.628167) (xy 315.510685 -400.582317)
			(xy 315.546376 -400.541126) (xy 315.587567 -400.505435) (xy 315.633417 -400.475969) (xy 315.682994 -400.453327)
			(xy 315.735289 -400.437972) (xy 315.789237 -400.430216) (xy 315.843739 -400.430216) (xy 315.897687 -400.437972)
			(xy 315.949982 -400.453327) (xy 315.999559 -400.475969) (xy 316.045409 -400.505435) (xy 316.0866 -400.541126)
			(xy 316.122291 -400.582317) (xy 316.151757 -400.628167) (xy 316.174399 -400.677744) (xy 316.189754 -400.730039)
			(xy 316.19751 -400.783987) (xy 316.197996 -400.811238) (xy 316.197996 -401.674838) (xy 316.634876 -401.674838)
			(xy 316.634876 -400.811238) (xy 316.635362 -400.783987) (xy 316.643118 -400.730039) (xy 316.658473 -400.677744)
			(xy 316.681115 -400.628167) (xy 316.710581 -400.582317) (xy 316.746272 -400.541126) (xy 316.787463 -400.505435)
			(xy 316.833313 -400.475969) (xy 316.88289 -400.453327) (xy 316.935185 -400.437972) (xy 316.989133 -400.430216)
			(xy 317.043635 -400.430216) (xy 317.097583 -400.437972) (xy 317.149878 -400.453327) (xy 317.199455 -400.475969)
			(xy 317.245305 -400.505435) (xy 317.286496 -400.541126) (xy 317.322187 -400.582317) (xy 317.351653 -400.628167)
			(xy 317.374295 -400.677744) (xy 317.38965 -400.730039) (xy 317.397406 -400.783987) (xy 317.397892 -400.811238)
			(xy 317.397892 -401.674838) (xy 317.834772 -401.674838) (xy 317.834772 -400.811238) (xy 317.835258 -400.783987)
			(xy 317.843014 -400.730039) (xy 317.858369 -400.677744) (xy 317.881011 -400.628167) (xy 317.910477 -400.582317)
			(xy 317.946168 -400.541126) (xy 317.987359 -400.505435) (xy 318.033209 -400.475969) (xy 318.082786 -400.453327)
			(xy 318.135081 -400.437972) (xy 318.189029 -400.430216) (xy 318.243531 -400.430216) (xy 318.297479 -400.437972)
			(xy 318.349774 -400.453327) (xy 318.399351 -400.475969) (xy 318.445201 -400.505435) (xy 318.486392 -400.541126)
			(xy 318.522083 -400.582317) (xy 318.551549 -400.628167) (xy 318.574191 -400.677744) (xy 318.589546 -400.730039)
			(xy 318.597302 -400.783987) (xy 318.597788 -400.811238) (xy 318.597788 -401.674838) (xy 319.034668 -401.674838)
			(xy 319.034668 -400.811238) (xy 319.035154 -400.783987) (xy 319.04291 -400.730039) (xy 319.058265 -400.677744)
			(xy 319.080907 -400.628167) (xy 319.110373 -400.582317) (xy 319.146064 -400.541126) (xy 319.187255 -400.505435)
			(xy 319.233105 -400.475969) (xy 319.282682 -400.453327) (xy 319.334977 -400.437972) (xy 319.388925 -400.430216)
			(xy 319.443427 -400.430216) (xy 319.497375 -400.437972) (xy 319.54967 -400.453327) (xy 319.599247 -400.475969)
			(xy 319.645097 -400.505435) (xy 319.686288 -400.541126) (xy 319.721979 -400.582317) (xy 319.751445 -400.628167)
			(xy 319.774087 -400.677744) (xy 319.789442 -400.730039) (xy 319.797198 -400.783987) (xy 319.797684 -400.811238)
			(xy 319.797684 -401.674838) (xy 320.234564 -401.674838) (xy 320.234564 -400.811238) (xy 320.23505 -400.783969)
			(xy 320.242812 -400.729985) (xy 320.258177 -400.677655) (xy 320.280834 -400.628045) (xy 320.31032 -400.582164)
			(xy 320.346035 -400.540947) (xy 320.387252 -400.505232) (xy 320.433133 -400.475746) (xy 320.482743 -400.453089)
			(xy 320.535073 -400.437724) (xy 320.589057 -400.429962) (xy 320.643595 -400.429962) (xy 320.697579 -400.437724)
			(xy 320.749909 -400.453089) (xy 320.799519 -400.475746) (xy 320.8454 -400.505232) (xy 320.886617 -400.540947)
			(xy 320.922332 -400.582164) (xy 320.951818 -400.628045) (xy 320.974475 -400.677655) (xy 320.98984 -400.729985)
			(xy 320.997602 -400.783969) (xy 320.998088 -400.811238) (xy 320.998088 -401.674838) (xy 321.43446 -401.674838)
			(xy 321.43446 -400.811238) (xy 321.434946 -400.783969) (xy 321.442708 -400.729985) (xy 321.458073 -400.677655)
			(xy 321.48073 -400.628045) (xy 321.510216 -400.582164) (xy 321.545931 -400.540947) (xy 321.587148 -400.505232)
			(xy 321.633029 -400.475746) (xy 321.682639 -400.453089) (xy 321.734969 -400.437724) (xy 321.788953 -400.429962)
			(xy 321.843491 -400.429962) (xy 321.897475 -400.437724) (xy 321.949805 -400.453089) (xy 321.999415 -400.475746)
			(xy 322.045296 -400.505232) (xy 322.086513 -400.540947) (xy 322.122228 -400.582164) (xy 322.151714 -400.628045)
			(xy 322.174371 -400.677655) (xy 322.189736 -400.729985) (xy 322.197498 -400.783969) (xy 322.197984 -400.811238)
			(xy 322.197984 -401.674838) (xy 335.962244 -401.674838) (xy 335.962244 -400.811238) (xy 335.96273 -400.783969)
			(xy 335.970492 -400.729985) (xy 335.985857 -400.677655) (xy 336.008514 -400.628045) (xy 336.038 -400.582164)
			(xy 336.073715 -400.540947) (xy 336.114932 -400.505232) (xy 336.160813 -400.475746) (xy 336.210423 -400.453089)
			(xy 336.262753 -400.437724) (xy 336.316737 -400.429962) (xy 336.371275 -400.429962) (xy 336.425259 -400.437724)
			(xy 336.477589 -400.453089) (xy 336.527199 -400.475746) (xy 336.57308 -400.505232) (xy 336.614297 -400.540947)
			(xy 336.650012 -400.582164) (xy 336.679498 -400.628045) (xy 336.702155 -400.677655) (xy 336.71752 -400.729985)
			(xy 336.725282 -400.783969) (xy 336.725768 -400.811238) (xy 336.725768 -401.674838) (xy 337.16214 -401.674838)
			(xy 337.16214 -400.811238) (xy 337.162626 -400.783969) (xy 337.170388 -400.729985) (xy 337.185753 -400.677655)
			(xy 337.20841 -400.628045) (xy 337.237896 -400.582164) (xy 337.273611 -400.540947) (xy 337.314828 -400.505232)
			(xy 337.360709 -400.475746) (xy 337.410319 -400.453089) (xy 337.462649 -400.437724) (xy 337.516633 -400.429962)
			(xy 337.571171 -400.429962) (xy 337.625155 -400.437724) (xy 337.677485 -400.453089) (xy 337.727095 -400.475746)
			(xy 337.772976 -400.505232) (xy 337.814193 -400.540947) (xy 337.849908 -400.582164) (xy 337.879394 -400.628045)
			(xy 337.902051 -400.677655) (xy 337.917416 -400.729985) (xy 337.925178 -400.783969) (xy 337.925664 -400.811238)
			(xy 337.925664 -401.674838) (xy 338.362544 -401.674838) (xy 338.362544 -400.811238) (xy 338.36303 -400.783987)
			(xy 338.370786 -400.730039) (xy 338.386141 -400.677744) (xy 338.408783 -400.628167) (xy 338.438249 -400.582317)
			(xy 338.47394 -400.541126) (xy 338.515131 -400.505435) (xy 338.560981 -400.475969) (xy 338.610558 -400.453327)
			(xy 338.662853 -400.437972) (xy 338.716801 -400.430216) (xy 338.771303 -400.430216) (xy 338.825251 -400.437972)
			(xy 338.877546 -400.453327) (xy 338.927123 -400.475969) (xy 338.972973 -400.505435) (xy 339.014164 -400.541126)
			(xy 339.049855 -400.582317) (xy 339.079321 -400.628167) (xy 339.101963 -400.677744) (xy 339.117318 -400.730039)
			(xy 339.125074 -400.783987) (xy 339.12556 -400.811238) (xy 339.12556 -401.674838) (xy 339.56244 -401.674838)
			(xy 339.56244 -400.811238) (xy 339.562926 -400.783987) (xy 339.570682 -400.730039) (xy 339.586037 -400.677744)
			(xy 339.608679 -400.628167) (xy 339.638145 -400.582317) (xy 339.673836 -400.541126) (xy 339.715027 -400.505435)
			(xy 339.760877 -400.475969) (xy 339.810454 -400.453327) (xy 339.862749 -400.437972) (xy 339.916697 -400.430216)
			(xy 339.971199 -400.430216) (xy 340.025147 -400.437972) (xy 340.077442 -400.453327) (xy 340.127019 -400.475969)
			(xy 340.172869 -400.505435) (xy 340.21406 -400.541126) (xy 340.249751 -400.582317) (xy 340.279217 -400.628167)
			(xy 340.301859 -400.677744) (xy 340.317214 -400.730039) (xy 340.32497 -400.783987) (xy 340.325456 -400.811238)
			(xy 340.325456 -401.674838) (xy 340.762336 -401.674838) (xy 340.762336 -400.811238) (xy 340.762822 -400.783969)
			(xy 340.770584 -400.729985) (xy 340.785949 -400.677655) (xy 340.808606 -400.628045) (xy 340.838092 -400.582164)
			(xy 340.873807 -400.540947) (xy 340.915024 -400.505232) (xy 340.960905 -400.475746) (xy 341.010515 -400.453089)
			(xy 341.062845 -400.437724) (xy 341.116829 -400.429962) (xy 341.171367 -400.429962) (xy 341.225351 -400.437724)
			(xy 341.277681 -400.453089) (xy 341.327291 -400.475746) (xy 341.373172 -400.505232) (xy 341.414389 -400.540947)
			(xy 341.450104 -400.582164) (xy 341.47959 -400.628045) (xy 341.502247 -400.677655) (xy 341.517612 -400.729985)
			(xy 341.525374 -400.783969) (xy 341.52586 -400.811238) (xy 341.52586 -401.674838) (xy 341.962232 -401.674838)
			(xy 341.962232 -400.811238) (xy 341.962718 -400.783969) (xy 341.97048 -400.729985) (xy 341.985845 -400.677655)
			(xy 342.008502 -400.628045) (xy 342.037988 -400.582164) (xy 342.073703 -400.540947) (xy 342.11492 -400.505232)
			(xy 342.160801 -400.475746) (xy 342.210411 -400.453089) (xy 342.262741 -400.437724) (xy 342.316725 -400.429962)
			(xy 342.371263 -400.429962) (xy 342.425247 -400.437724) (xy 342.477577 -400.453089) (xy 342.527187 -400.475746)
			(xy 342.573068 -400.505232) (xy 342.614285 -400.540947) (xy 342.65 -400.582164) (xy 342.679486 -400.628045)
			(xy 342.702143 -400.677655) (xy 342.717508 -400.729985) (xy 342.72527 -400.783969) (xy 342.725756 -400.811238)
			(xy 342.725756 -401.674838) (xy 343.162636 -401.674838) (xy 343.162636 -400.811238) (xy 343.163122 -400.783987)
			(xy 343.170878 -400.730039) (xy 343.186233 -400.677744) (xy 343.208875 -400.628167) (xy 343.238341 -400.582317)
			(xy 343.274032 -400.541126) (xy 343.315223 -400.505435) (xy 343.361073 -400.475969) (xy 343.41065 -400.453327)
			(xy 343.462945 -400.437972) (xy 343.516893 -400.430216) (xy 343.571395 -400.430216) (xy 343.625343 -400.437972)
			(xy 343.677638 -400.453327) (xy 343.727215 -400.475969) (xy 343.773065 -400.505435) (xy 343.814256 -400.541126)
			(xy 343.849947 -400.582317) (xy 343.879413 -400.628167) (xy 343.902055 -400.677744) (xy 343.91741 -400.730039)
			(xy 343.925166 -400.783987) (xy 343.925652 -400.811238) (xy 343.925652 -401.674838) (xy 344.362532 -401.674838)
			(xy 344.362532 -400.811238) (xy 344.363018 -400.783987) (xy 344.370774 -400.730039) (xy 344.386129 -400.677744)
			(xy 344.408771 -400.628167) (xy 344.438237 -400.582317) (xy 344.473928 -400.541126) (xy 344.515119 -400.505435)
			(xy 344.560969 -400.475969) (xy 344.610546 -400.453327) (xy 344.662841 -400.437972) (xy 344.716789 -400.430216)
			(xy 344.771291 -400.430216) (xy 344.825239 -400.437972) (xy 344.877534 -400.453327) (xy 344.927111 -400.475969)
			(xy 344.972961 -400.505435) (xy 345.014152 -400.541126) (xy 345.049843 -400.582317) (xy 345.079309 -400.628167)
			(xy 345.101951 -400.677744) (xy 345.117306 -400.730039) (xy 345.125062 -400.783987) (xy 345.125548 -400.811238)
			(xy 345.125548 -401.674838) (xy 345.562428 -401.674838) (xy 345.562428 -400.811238) (xy 345.562914 -400.783969)
			(xy 345.570676 -400.729985) (xy 345.586041 -400.677655) (xy 345.608698 -400.628045) (xy 345.638184 -400.582164)
			(xy 345.673899 -400.540947) (xy 345.715116 -400.505232) (xy 345.760997 -400.475746) (xy 345.810607 -400.453089)
			(xy 345.862937 -400.437724) (xy 345.916921 -400.429962) (xy 345.971459 -400.429962) (xy 346.025443 -400.437724)
			(xy 346.077773 -400.453089) (xy 346.127383 -400.475746) (xy 346.173264 -400.505232) (xy 346.214481 -400.540947)
			(xy 346.250196 -400.582164) (xy 346.279682 -400.628045) (xy 346.302339 -400.677655) (xy 346.317704 -400.729985)
			(xy 346.325466 -400.783969) (xy 346.325952 -400.811238) (xy 346.325952 -401.674838) (xy 346.762324 -401.674838)
			(xy 346.762324 -400.811238) (xy 346.76281 -400.783969) (xy 346.770572 -400.729985) (xy 346.785937 -400.677655)
			(xy 346.808594 -400.628045) (xy 346.83808 -400.582164) (xy 346.873795 -400.540947) (xy 346.915012 -400.505232)
			(xy 346.960893 -400.475746) (xy 347.010503 -400.453089) (xy 347.062833 -400.437724) (xy 347.116817 -400.429962)
			(xy 347.171355 -400.429962) (xy 347.225339 -400.437724) (xy 347.277669 -400.453089) (xy 347.327279 -400.475746)
			(xy 347.37316 -400.505232) (xy 347.414377 -400.540947) (xy 347.450092 -400.582164) (xy 347.479578 -400.628045)
			(xy 347.502235 -400.677655) (xy 347.5176 -400.729985) (xy 347.525362 -400.783969) (xy 347.525848 -400.811238)
			(xy 347.525848 -401.674838) (xy 347.962728 -401.674838) (xy 347.962728 -400.811238) (xy 347.963214 -400.783987)
			(xy 347.97097 -400.730039) (xy 347.986325 -400.677744) (xy 348.008967 -400.628167) (xy 348.038433 -400.582317)
			(xy 348.074124 -400.541126) (xy 348.115315 -400.505435) (xy 348.161165 -400.475969) (xy 348.210742 -400.453327)
			(xy 348.263037 -400.437972) (xy 348.316985 -400.430216) (xy 348.371487 -400.430216) (xy 348.425435 -400.437972)
			(xy 348.47773 -400.453327) (xy 348.527307 -400.475969) (xy 348.573157 -400.505435) (xy 348.614348 -400.541126)
			(xy 348.650039 -400.582317) (xy 348.679505 -400.628167) (xy 348.702147 -400.677744) (xy 348.717502 -400.730039)
			(xy 348.725258 -400.783987) (xy 348.725744 -400.811238) (xy 348.725744 -401.674838) (xy 349.162624 -401.674838)
			(xy 349.162624 -400.811238) (xy 349.16311 -400.783987) (xy 349.170866 -400.730039) (xy 349.186221 -400.677744)
			(xy 349.208863 -400.628167) (xy 349.238329 -400.582317) (xy 349.27402 -400.541126) (xy 349.315211 -400.505435)
			(xy 349.361061 -400.475969) (xy 349.410638 -400.453327) (xy 349.462933 -400.437972) (xy 349.516881 -400.430216)
			(xy 349.571383 -400.430216) (xy 349.625331 -400.437972) (xy 349.677626 -400.453327) (xy 349.727203 -400.475969)
			(xy 349.773053 -400.505435) (xy 349.814244 -400.541126) (xy 349.849935 -400.582317) (xy 349.879401 -400.628167)
			(xy 349.902043 -400.677744) (xy 349.917398 -400.730039) (xy 349.925154 -400.783987) (xy 349.92564 -400.811238)
			(xy 349.92564 -401.674838) (xy 350.36252 -401.674838) (xy 350.36252 -400.811238) (xy 350.363006 -400.783987)
			(xy 350.370762 -400.730039) (xy 350.386117 -400.677744) (xy 350.408759 -400.628167) (xy 350.438225 -400.582317)
			(xy 350.473916 -400.541126) (xy 350.515107 -400.505435) (xy 350.560957 -400.475969) (xy 350.610534 -400.453327)
			(xy 350.662829 -400.437972) (xy 350.716777 -400.430216) (xy 350.771279 -400.430216) (xy 350.825227 -400.437972)
			(xy 350.877522 -400.453327) (xy 350.927099 -400.475969) (xy 350.972949 -400.505435) (xy 351.01414 -400.541126)
			(xy 351.049831 -400.582317) (xy 351.079297 -400.628167) (xy 351.101939 -400.677744) (xy 351.117294 -400.730039)
			(xy 351.12505 -400.783987) (xy 351.125536 -400.811238) (xy 351.125536 -401.674838) (xy 351.562416 -401.674838)
			(xy 351.562416 -400.811238) (xy 351.562902 -400.783987) (xy 351.570658 -400.730039) (xy 351.586013 -400.677744)
			(xy 351.608655 -400.628167) (xy 351.638121 -400.582317) (xy 351.673812 -400.541126) (xy 351.715003 -400.505435)
			(xy 351.760853 -400.475969) (xy 351.81043 -400.453327) (xy 351.862725 -400.437972) (xy 351.916673 -400.430216)
			(xy 351.971175 -400.430216) (xy 352.025123 -400.437972) (xy 352.077418 -400.453327) (xy 352.126995 -400.475969)
			(xy 352.172845 -400.505435) (xy 352.214036 -400.541126) (xy 352.249727 -400.582317) (xy 352.279193 -400.628167)
			(xy 352.301835 -400.677744) (xy 352.31719 -400.730039) (xy 352.324946 -400.783987) (xy 352.325432 -400.811238)
			(xy 352.325432 -401.674838) (xy 352.762312 -401.674838) (xy 352.762312 -400.811238) (xy 352.762798 -400.783969)
			(xy 352.77056 -400.729985) (xy 352.785925 -400.677655) (xy 352.808582 -400.628045) (xy 352.838068 -400.582164)
			(xy 352.873783 -400.540947) (xy 352.915 -400.505232) (xy 352.960881 -400.475746) (xy 353.010491 -400.453089)
			(xy 353.062821 -400.437724) (xy 353.116805 -400.429962) (xy 353.171343 -400.429962) (xy 353.225327 -400.437724)
			(xy 353.277657 -400.453089) (xy 353.327267 -400.475746) (xy 353.373148 -400.505232) (xy 353.414365 -400.540947)
			(xy 353.45008 -400.582164) (xy 353.479566 -400.628045) (xy 353.502223 -400.677655) (xy 353.517588 -400.729985)
			(xy 353.52535 -400.783969) (xy 353.525836 -400.811238) (xy 353.525836 -401.674838) (xy 353.962208 -401.674838)
			(xy 353.962208 -400.811238) (xy 353.962694 -400.783969) (xy 353.970456 -400.729985) (xy 353.985821 -400.677655)
			(xy 354.008478 -400.628045) (xy 354.037964 -400.582164) (xy 354.073679 -400.540947) (xy 354.114896 -400.505232)
			(xy 354.160777 -400.475746) (xy 354.210387 -400.453089) (xy 354.262717 -400.437724) (xy 354.316701 -400.429962)
			(xy 354.371239 -400.429962) (xy 354.425223 -400.437724) (xy 354.477553 -400.453089) (xy 354.527163 -400.475746)
			(xy 354.573044 -400.505232) (xy 354.614261 -400.540947) (xy 354.649976 -400.582164) (xy 354.679462 -400.628045)
			(xy 354.702119 -400.677655) (xy 354.717484 -400.729985) (xy 354.725246 -400.783969) (xy 354.725732 -400.811238)
			(xy 354.725732 -401.674838) (xy 370.534692 -401.674838) (xy 370.534692 -400.811238) (xy 370.535178 -400.783969)
			(xy 370.54294 -400.729985) (xy 370.558305 -400.677655) (xy 370.580962 -400.628045) (xy 370.610448 -400.582164)
			(xy 370.646163 -400.540947) (xy 370.68738 -400.505232) (xy 370.733261 -400.475746) (xy 370.782871 -400.453089)
			(xy 370.835201 -400.437724) (xy 370.889185 -400.429962) (xy 370.943723 -400.429962) (xy 370.997707 -400.437724)
			(xy 371.050037 -400.453089) (xy 371.099647 -400.475746) (xy 371.145528 -400.505232) (xy 371.186745 -400.540947)
			(xy 371.22246 -400.582164) (xy 371.251946 -400.628045) (xy 371.274603 -400.677655) (xy 371.289968 -400.729985)
			(xy 371.29773 -400.783969) (xy 371.298216 -400.811238) (xy 371.298216 -401.674838) (xy 371.734588 -401.674838)
			(xy 371.734588 -400.811238) (xy 371.735074 -400.783969) (xy 371.742836 -400.729985) (xy 371.758201 -400.677655)
			(xy 371.780858 -400.628045) (xy 371.810344 -400.582164) (xy 371.846059 -400.540947) (xy 371.887276 -400.505232)
			(xy 371.933157 -400.475746) (xy 371.982767 -400.453089) (xy 372.035097 -400.437724) (xy 372.089081 -400.429962)
			(xy 372.143619 -400.429962) (xy 372.197603 -400.437724) (xy 372.249933 -400.453089) (xy 372.299543 -400.475746)
			(xy 372.345424 -400.505232) (xy 372.386641 -400.540947) (xy 372.422356 -400.582164) (xy 372.451842 -400.628045)
			(xy 372.474499 -400.677655) (xy 372.489864 -400.729985) (xy 372.497626 -400.783969) (xy 372.498112 -400.811238)
			(xy 372.498112 -401.674838) (xy 372.934992 -401.674838) (xy 372.934992 -400.811238) (xy 372.935478 -400.783987)
			(xy 372.943234 -400.730039) (xy 372.958589 -400.677744) (xy 372.981231 -400.628167) (xy 373.010697 -400.582317)
			(xy 373.046388 -400.541126) (xy 373.087579 -400.505435) (xy 373.133429 -400.475969) (xy 373.183006 -400.453327)
			(xy 373.235301 -400.437972) (xy 373.289249 -400.430216) (xy 373.343751 -400.430216) (xy 373.397699 -400.437972)
			(xy 373.449994 -400.453327) (xy 373.499571 -400.475969) (xy 373.545421 -400.505435) (xy 373.586612 -400.541126)
			(xy 373.622303 -400.582317) (xy 373.651769 -400.628167) (xy 373.674411 -400.677744) (xy 373.689766 -400.730039)
			(xy 373.697522 -400.783987) (xy 373.698008 -400.811238) (xy 373.698008 -401.674838) (xy 374.134888 -401.674838)
			(xy 374.134888 -400.811238) (xy 374.135374 -400.783987) (xy 374.14313 -400.730039) (xy 374.158485 -400.677744)
			(xy 374.181127 -400.628167) (xy 374.210593 -400.582317) (xy 374.246284 -400.541126) (xy 374.287475 -400.505435)
			(xy 374.333325 -400.475969) (xy 374.382902 -400.453327) (xy 374.435197 -400.437972) (xy 374.489145 -400.430216)
			(xy 374.543647 -400.430216) (xy 374.597595 -400.437972) (xy 374.64989 -400.453327) (xy 374.699467 -400.475969)
			(xy 374.745317 -400.505435) (xy 374.786508 -400.541126) (xy 374.822199 -400.582317) (xy 374.851665 -400.628167)
			(xy 374.874307 -400.677744) (xy 374.889662 -400.730039) (xy 374.897418 -400.783987) (xy 374.897904 -400.811238)
			(xy 374.897904 -401.674838) (xy 375.334784 -401.674838) (xy 375.334784 -400.811238) (xy 375.33527 -400.783969)
			(xy 375.343032 -400.729985) (xy 375.358397 -400.677655) (xy 375.381054 -400.628045) (xy 375.41054 -400.582164)
			(xy 375.446255 -400.540947) (xy 375.487472 -400.505232) (xy 375.533353 -400.475746) (xy 375.582963 -400.453089)
			(xy 375.635293 -400.437724) (xy 375.689277 -400.429962) (xy 375.743815 -400.429962) (xy 375.797799 -400.437724)
			(xy 375.850129 -400.453089) (xy 375.899739 -400.475746) (xy 375.94562 -400.505232) (xy 375.986837 -400.540947)
			(xy 376.022552 -400.582164) (xy 376.052038 -400.628045) (xy 376.074695 -400.677655) (xy 376.09006 -400.729985)
			(xy 376.097822 -400.783969) (xy 376.098308 -400.811238) (xy 376.098308 -401.674838) (xy 376.53468 -401.674838)
			(xy 376.53468 -400.811238) (xy 376.535166 -400.783969) (xy 376.542928 -400.729985) (xy 376.558293 -400.677655)
			(xy 376.58095 -400.628045) (xy 376.610436 -400.582164) (xy 376.646151 -400.540947) (xy 376.687368 -400.505232)
			(xy 376.733249 -400.475746) (xy 376.782859 -400.453089) (xy 376.835189 -400.437724) (xy 376.889173 -400.429962)
			(xy 376.943711 -400.429962) (xy 376.997695 -400.437724) (xy 377.050025 -400.453089) (xy 377.099635 -400.475746)
			(xy 377.145516 -400.505232) (xy 377.186733 -400.540947) (xy 377.222448 -400.582164) (xy 377.251934 -400.628045)
			(xy 377.274591 -400.677655) (xy 377.289956 -400.729985) (xy 377.297718 -400.783969) (xy 377.298204 -400.811238)
			(xy 377.298204 -401.674838) (xy 377.735084 -401.674838) (xy 377.735084 -400.811238) (xy 377.73557 -400.783987)
			(xy 377.743326 -400.730039) (xy 377.758681 -400.677744) (xy 377.781323 -400.628167) (xy 377.810789 -400.582317)
			(xy 377.84648 -400.541126) (xy 377.887671 -400.505435) (xy 377.933521 -400.475969) (xy 377.983098 -400.453327)
			(xy 378.035393 -400.437972) (xy 378.089341 -400.430216) (xy 378.143843 -400.430216) (xy 378.197791 -400.437972)
			(xy 378.250086 -400.453327) (xy 378.299663 -400.475969) (xy 378.345513 -400.505435) (xy 378.386704 -400.541126)
			(xy 378.422395 -400.582317) (xy 378.451861 -400.628167) (xy 378.474503 -400.677744) (xy 378.489858 -400.730039)
			(xy 378.497614 -400.783987) (xy 378.4981 -400.811238) (xy 378.4981 -401.674838) (xy 378.93498 -401.674838)
			(xy 378.93498 -400.811238) (xy 378.935466 -400.783987) (xy 378.943222 -400.730039) (xy 378.958577 -400.677744)
			(xy 378.981219 -400.628167) (xy 379.010685 -400.582317) (xy 379.046376 -400.541126) (xy 379.087567 -400.505435)
			(xy 379.133417 -400.475969) (xy 379.182994 -400.453327) (xy 379.235289 -400.437972) (xy 379.289237 -400.430216)
			(xy 379.343739 -400.430216) (xy 379.397687 -400.437972) (xy 379.449982 -400.453327) (xy 379.499559 -400.475969)
			(xy 379.545409 -400.505435) (xy 379.5866 -400.541126) (xy 379.622291 -400.582317) (xy 379.651757 -400.628167)
			(xy 379.674399 -400.677744) (xy 379.689754 -400.730039) (xy 379.69751 -400.783987) (xy 379.697996 -400.811238)
			(xy 379.697996 -401.674838) (xy 380.134876 -401.674838) (xy 380.134876 -400.811238) (xy 380.135362 -400.783969)
			(xy 380.143124 -400.729985) (xy 380.158489 -400.677655) (xy 380.181146 -400.628045) (xy 380.210632 -400.582164)
			(xy 380.246347 -400.540947) (xy 380.287564 -400.505232) (xy 380.333445 -400.475746) (xy 380.383055 -400.453089)
			(xy 380.435385 -400.437724) (xy 380.489369 -400.429962) (xy 380.543907 -400.429962) (xy 380.597891 -400.437724)
			(xy 380.650221 -400.453089) (xy 380.699831 -400.475746) (xy 380.745712 -400.505232) (xy 380.786929 -400.540947)
			(xy 380.822644 -400.582164) (xy 380.85213 -400.628045) (xy 380.874787 -400.677655) (xy 380.890152 -400.729985)
			(xy 380.897914 -400.783969) (xy 380.8984 -400.811238) (xy 380.8984 -401.674838) (xy 381.334772 -401.674838)
			(xy 381.334772 -400.811238) (xy 381.335258 -400.783969) (xy 381.34302 -400.729985) (xy 381.358385 -400.677655)
			(xy 381.381042 -400.628045) (xy 381.410528 -400.582164) (xy 381.446243 -400.540947) (xy 381.48746 -400.505232)
			(xy 381.533341 -400.475746) (xy 381.582951 -400.453089) (xy 381.635281 -400.437724) (xy 381.689265 -400.429962)
			(xy 381.743803 -400.429962) (xy 381.797787 -400.437724) (xy 381.850117 -400.453089) (xy 381.899727 -400.475746)
			(xy 381.945608 -400.505232) (xy 381.986825 -400.540947) (xy 382.02254 -400.582164) (xy 382.052026 -400.628045)
			(xy 382.074683 -400.677655) (xy 382.090048 -400.729985) (xy 382.09781 -400.783969) (xy 382.098296 -400.811238)
			(xy 382.098296 -401.674838) (xy 382.535176 -401.674838) (xy 382.535176 -400.811238) (xy 382.535662 -400.783987)
			(xy 382.543418 -400.730039) (xy 382.558773 -400.677744) (xy 382.581415 -400.628167) (xy 382.610881 -400.582317)
			(xy 382.646572 -400.541126) (xy 382.687763 -400.505435) (xy 382.733613 -400.475969) (xy 382.78319 -400.453327)
			(xy 382.835485 -400.437972) (xy 382.889433 -400.430216) (xy 382.943935 -400.430216) (xy 382.997883 -400.437972)
			(xy 383.050178 -400.453327) (xy 383.099755 -400.475969) (xy 383.145605 -400.505435) (xy 383.186796 -400.541126)
			(xy 383.222487 -400.582317) (xy 383.251953 -400.628167) (xy 383.274595 -400.677744) (xy 383.28995 -400.730039)
			(xy 383.297706 -400.783987) (xy 383.298192 -400.811238) (xy 383.298192 -401.674838) (xy 383.735072 -401.674838)
			(xy 383.735072 -400.811238) (xy 383.735558 -400.783987) (xy 383.743314 -400.730039) (xy 383.758669 -400.677744)
			(xy 383.781311 -400.628167) (xy 383.810777 -400.582317) (xy 383.846468 -400.541126) (xy 383.887659 -400.505435)
			(xy 383.933509 -400.475969) (xy 383.983086 -400.453327) (xy 384.035381 -400.437972) (xy 384.089329 -400.430216)
			(xy 384.143831 -400.430216) (xy 384.197779 -400.437972) (xy 384.250074 -400.453327) (xy 384.299651 -400.475969)
			(xy 384.345501 -400.505435) (xy 384.386692 -400.541126) (xy 384.422383 -400.582317) (xy 384.451849 -400.628167)
			(xy 384.474491 -400.677744) (xy 384.489846 -400.730039) (xy 384.497602 -400.783987) (xy 384.498088 -400.811238)
			(xy 384.498088 -401.674838) (xy 384.934968 -401.674838) (xy 384.934968 -400.811238) (xy 384.935454 -400.783987)
			(xy 384.94321 -400.730039) (xy 384.958565 -400.677744) (xy 384.981207 -400.628167) (xy 385.010673 -400.582317)
			(xy 385.046364 -400.541126) (xy 385.087555 -400.505435) (xy 385.133405 -400.475969) (xy 385.182982 -400.453327)
			(xy 385.235277 -400.437972) (xy 385.289225 -400.430216) (xy 385.343727 -400.430216) (xy 385.397675 -400.437972)
			(xy 385.44997 -400.453327) (xy 385.499547 -400.475969) (xy 385.545397 -400.505435) (xy 385.586588 -400.541126)
			(xy 385.622279 -400.582317) (xy 385.651745 -400.628167) (xy 385.674387 -400.677744) (xy 385.689742 -400.730039)
			(xy 385.697498 -400.783987) (xy 385.697984 -400.811238) (xy 385.697984 -401.674838) (xy 386.134864 -401.674838)
			(xy 386.134864 -400.811238) (xy 386.13535 -400.783987) (xy 386.143106 -400.730039) (xy 386.158461 -400.677744)
			(xy 386.181103 -400.628167) (xy 386.210569 -400.582317) (xy 386.24626 -400.541126) (xy 386.287451 -400.505435)
			(xy 386.333301 -400.475969) (xy 386.382878 -400.453327) (xy 386.435173 -400.437972) (xy 386.489121 -400.430216)
			(xy 386.543623 -400.430216) (xy 386.597571 -400.437972) (xy 386.649866 -400.453327) (xy 386.699443 -400.475969)
			(xy 386.745293 -400.505435) (xy 386.786484 -400.541126) (xy 386.822175 -400.582317) (xy 386.851641 -400.628167)
			(xy 386.874283 -400.677744) (xy 386.889638 -400.730039) (xy 386.897394 -400.783987) (xy 386.89788 -400.811238)
			(xy 386.89788 -401.674838) (xy 387.33476 -401.674838) (xy 387.33476 -400.811238) (xy 387.335246 -400.783969)
			(xy 387.343008 -400.729985) (xy 387.358373 -400.677655) (xy 387.38103 -400.628045) (xy 387.410516 -400.582164)
			(xy 387.446231 -400.540947) (xy 387.487448 -400.505232) (xy 387.533329 -400.475746) (xy 387.582939 -400.453089)
			(xy 387.635269 -400.437724) (xy 387.689253 -400.429962) (xy 387.743791 -400.429962) (xy 387.797775 -400.437724)
			(xy 387.850105 -400.453089) (xy 387.899715 -400.475746) (xy 387.945596 -400.505232) (xy 387.986813 -400.540947)
			(xy 388.022528 -400.582164) (xy 388.052014 -400.628045) (xy 388.074671 -400.677655) (xy 388.090036 -400.729985)
			(xy 388.097798 -400.783969) (xy 388.098284 -400.811238) (xy 388.098284 -401.674838) (xy 388.534656 -401.674838)
			(xy 388.534656 -400.811238) (xy 388.535142 -400.783969) (xy 388.542904 -400.729985) (xy 388.558269 -400.677655)
			(xy 388.580926 -400.628045) (xy 388.610412 -400.582164) (xy 388.646127 -400.540947) (xy 388.687344 -400.505232)
			(xy 388.733225 -400.475746) (xy 388.782835 -400.453089) (xy 388.835165 -400.437724) (xy 388.889149 -400.429962)
			(xy 388.943687 -400.429962) (xy 388.997671 -400.437724) (xy 389.050001 -400.453089) (xy 389.099611 -400.475746)
			(xy 389.145492 -400.505232) (xy 389.186709 -400.540947) (xy 389.222424 -400.582164) (xy 389.25191 -400.628045)
			(xy 389.274567 -400.677655) (xy 389.289932 -400.729985) (xy 389.297694 -400.783969) (xy 389.29818 -400.811238)
			(xy 389.29818 -401.674838) (xy 403.06244 -401.674838) (xy 403.06244 -400.811238) (xy 403.062926 -400.783969)
			(xy 403.070688 -400.729985) (xy 403.086053 -400.677655) (xy 403.10871 -400.628045) (xy 403.138196 -400.582164)
			(xy 403.173911 -400.540947) (xy 403.215128 -400.505232) (xy 403.261009 -400.475746) (xy 403.310619 -400.453089)
			(xy 403.362949 -400.437724) (xy 403.416933 -400.429962) (xy 403.471471 -400.429962) (xy 403.525455 -400.437724)
			(xy 403.577785 -400.453089) (xy 403.627395 -400.475746) (xy 403.673276 -400.505232) (xy 403.714493 -400.540947)
			(xy 403.750208 -400.582164) (xy 403.779694 -400.628045) (xy 403.802351 -400.677655) (xy 403.817716 -400.729985)
			(xy 403.825478 -400.783969) (xy 403.825964 -400.811238) (xy 403.825964 -401.674838) (xy 404.262336 -401.674838)
			(xy 404.262336 -400.811238) (xy 404.262822 -400.783969) (xy 404.270584 -400.729985) (xy 404.285949 -400.677655)
			(xy 404.308606 -400.628045) (xy 404.338092 -400.582164) (xy 404.373807 -400.540947) (xy 404.415024 -400.505232)
			(xy 404.460905 -400.475746) (xy 404.510515 -400.453089) (xy 404.562845 -400.437724) (xy 404.616829 -400.429962)
			(xy 404.671367 -400.429962) (xy 404.725351 -400.437724) (xy 404.777681 -400.453089) (xy 404.827291 -400.475746)
			(xy 404.873172 -400.505232) (xy 404.914389 -400.540947) (xy 404.950104 -400.582164) (xy 404.97959 -400.628045)
			(xy 405.002247 -400.677655) (xy 405.017612 -400.729985) (xy 405.025374 -400.783969) (xy 405.02586 -400.811238)
			(xy 405.02586 -401.674838) (xy 405.46274 -401.674838) (xy 405.46274 -400.811238) (xy 405.463226 -400.783987)
			(xy 405.470982 -400.730039) (xy 405.486337 -400.677744) (xy 405.508979 -400.628167) (xy 405.538445 -400.582317)
			(xy 405.574136 -400.541126) (xy 405.615327 -400.505435) (xy 405.661177 -400.475969) (xy 405.710754 -400.453327)
			(xy 405.763049 -400.437972) (xy 405.816997 -400.430216) (xy 405.871499 -400.430216) (xy 405.925447 -400.437972)
			(xy 405.977742 -400.453327) (xy 406.027319 -400.475969) (xy 406.073169 -400.505435) (xy 406.11436 -400.541126)
			(xy 406.150051 -400.582317) (xy 406.179517 -400.628167) (xy 406.202159 -400.677744) (xy 406.217514 -400.730039)
			(xy 406.22527 -400.783987) (xy 406.225756 -400.811238) (xy 406.225756 -401.674838) (xy 406.662636 -401.674838)
			(xy 406.662636 -400.811238) (xy 406.663122 -400.783987) (xy 406.670878 -400.730039) (xy 406.686233 -400.677744)
			(xy 406.708875 -400.628167) (xy 406.738341 -400.582317) (xy 406.774032 -400.541126) (xy 406.815223 -400.505435)
			(xy 406.861073 -400.475969) (xy 406.91065 -400.453327) (xy 406.962945 -400.437972) (xy 407.016893 -400.430216)
			(xy 407.071395 -400.430216) (xy 407.125343 -400.437972) (xy 407.177638 -400.453327) (xy 407.227215 -400.475969)
			(xy 407.273065 -400.505435) (xy 407.314256 -400.541126) (xy 407.349947 -400.582317) (xy 407.379413 -400.628167)
			(xy 407.402055 -400.677744) (xy 407.41741 -400.730039) (xy 407.425166 -400.783987) (xy 407.425652 -400.811238)
			(xy 407.425652 -401.674838) (xy 407.862532 -401.674838) (xy 407.862532 -400.811238) (xy 407.863018 -400.783969)
			(xy 407.87078 -400.729985) (xy 407.886145 -400.677655) (xy 407.908802 -400.628045) (xy 407.938288 -400.582164)
			(xy 407.974003 -400.540947) (xy 408.01522 -400.505232) (xy 408.061101 -400.475746) (xy 408.110711 -400.453089)
			(xy 408.163041 -400.437724) (xy 408.217025 -400.429962) (xy 408.271563 -400.429962) (xy 408.325547 -400.437724)
			(xy 408.377877 -400.453089) (xy 408.427487 -400.475746) (xy 408.473368 -400.505232) (xy 408.514585 -400.540947)
			(xy 408.5503 -400.582164) (xy 408.579786 -400.628045) (xy 408.602443 -400.677655) (xy 408.617808 -400.729985)
			(xy 408.62557 -400.783969) (xy 408.626056 -400.811238) (xy 408.626056 -401.674838) (xy 409.062428 -401.674838)
			(xy 409.062428 -400.811238) (xy 409.062914 -400.783969) (xy 409.070676 -400.729985) (xy 409.086041 -400.677655)
			(xy 409.108698 -400.628045) (xy 409.138184 -400.582164) (xy 409.173899 -400.540947) (xy 409.215116 -400.505232)
			(xy 409.260997 -400.475746) (xy 409.310607 -400.453089) (xy 409.362937 -400.437724) (xy 409.416921 -400.429962)
			(xy 409.471459 -400.429962) (xy 409.525443 -400.437724) (xy 409.577773 -400.453089) (xy 409.627383 -400.475746)
			(xy 409.673264 -400.505232) (xy 409.714481 -400.540947) (xy 409.750196 -400.582164) (xy 409.779682 -400.628045)
			(xy 409.802339 -400.677655) (xy 409.817704 -400.729985) (xy 409.825466 -400.783969) (xy 409.825952 -400.811238)
			(xy 409.825952 -401.674838) (xy 410.262832 -401.674838) (xy 410.262832 -400.811238) (xy 410.263318 -400.783987)
			(xy 410.271074 -400.730039) (xy 410.286429 -400.677744) (xy 410.309071 -400.628167) (xy 410.338537 -400.582317)
			(xy 410.374228 -400.541126) (xy 410.415419 -400.505435) (xy 410.461269 -400.475969) (xy 410.510846 -400.453327)
			(xy 410.563141 -400.437972) (xy 410.617089 -400.430216) (xy 410.671591 -400.430216) (xy 410.725539 -400.437972)
			(xy 410.777834 -400.453327) (xy 410.827411 -400.475969) (xy 410.873261 -400.505435) (xy 410.914452 -400.541126)
			(xy 410.950143 -400.582317) (xy 410.979609 -400.628167) (xy 411.002251 -400.677744) (xy 411.017606 -400.730039)
			(xy 411.025362 -400.783987) (xy 411.025848 -400.811238) (xy 411.025848 -401.674838) (xy 411.462728 -401.674838)
			(xy 411.462728 -400.811238) (xy 411.463214 -400.783987) (xy 411.47097 -400.730039) (xy 411.486325 -400.677744)
			(xy 411.508967 -400.628167) (xy 411.538433 -400.582317) (xy 411.574124 -400.541126) (xy 411.615315 -400.505435)
			(xy 411.661165 -400.475969) (xy 411.710742 -400.453327) (xy 411.763037 -400.437972) (xy 411.816985 -400.430216)
			(xy 411.871487 -400.430216) (xy 411.925435 -400.437972) (xy 411.97773 -400.453327) (xy 412.027307 -400.475969)
			(xy 412.073157 -400.505435) (xy 412.114348 -400.541126) (xy 412.150039 -400.582317) (xy 412.179505 -400.628167)
			(xy 412.202147 -400.677744) (xy 412.217502 -400.730039) (xy 412.225258 -400.783987) (xy 412.225744 -400.811238)
			(xy 412.225744 -401.674838) (xy 412.662624 -401.674838) (xy 412.662624 -400.811238) (xy 412.66311 -400.783969)
			(xy 412.670872 -400.729985) (xy 412.686237 -400.677655) (xy 412.708894 -400.628045) (xy 412.73838 -400.582164)
			(xy 412.774095 -400.540947) (xy 412.815312 -400.505232) (xy 412.861193 -400.475746) (xy 412.910803 -400.453089)
			(xy 412.963133 -400.437724) (xy 413.017117 -400.429962) (xy 413.071655 -400.429962) (xy 413.125639 -400.437724)
			(xy 413.177969 -400.453089) (xy 413.227579 -400.475746) (xy 413.27346 -400.505232) (xy 413.314677 -400.540947)
			(xy 413.350392 -400.582164) (xy 413.379878 -400.628045) (xy 413.402535 -400.677655) (xy 413.4179 -400.729985)
			(xy 413.425662 -400.783969) (xy 413.426148 -400.811238) (xy 413.426148 -401.674838) (xy 413.86252 -401.674838)
			(xy 413.86252 -400.811238) (xy 413.863006 -400.783969) (xy 413.870768 -400.729985) (xy 413.886133 -400.677655)
			(xy 413.90879 -400.628045) (xy 413.938276 -400.582164) (xy 413.973991 -400.540947) (xy 414.015208 -400.505232)
			(xy 414.061089 -400.475746) (xy 414.110699 -400.453089) (xy 414.163029 -400.437724) (xy 414.217013 -400.429962)
			(xy 414.271551 -400.429962) (xy 414.325535 -400.437724) (xy 414.377865 -400.453089) (xy 414.427475 -400.475746)
			(xy 414.473356 -400.505232) (xy 414.514573 -400.540947) (xy 414.550288 -400.582164) (xy 414.579774 -400.628045)
			(xy 414.602431 -400.677655) (xy 414.617796 -400.729985) (xy 414.625558 -400.783969) (xy 414.626044 -400.811238)
			(xy 414.626044 -401.674838) (xy 415.062924 -401.674838) (xy 415.062924 -400.811238) (xy 415.06341 -400.783987)
			(xy 415.071166 -400.730039) (xy 415.086521 -400.677744) (xy 415.109163 -400.628167) (xy 415.138629 -400.582317)
			(xy 415.17432 -400.541126) (xy 415.215511 -400.505435) (xy 415.261361 -400.475969) (xy 415.310938 -400.453327)
			(xy 415.363233 -400.437972) (xy 415.417181 -400.430216) (xy 415.471683 -400.430216) (xy 415.525631 -400.437972)
			(xy 415.577926 -400.453327) (xy 415.627503 -400.475969) (xy 415.673353 -400.505435) (xy 415.714544 -400.541126)
			(xy 415.750235 -400.582317) (xy 415.779701 -400.628167) (xy 415.802343 -400.677744) (xy 415.817698 -400.730039)
			(xy 415.825454 -400.783987) (xy 415.82594 -400.811238) (xy 415.82594 -401.674838) (xy 416.26282 -401.674838)
			(xy 416.26282 -400.811238) (xy 416.263306 -400.783987) (xy 416.271062 -400.730039) (xy 416.286417 -400.677744)
			(xy 416.309059 -400.628167) (xy 416.338525 -400.582317) (xy 416.374216 -400.541126) (xy 416.415407 -400.505435)
			(xy 416.461257 -400.475969) (xy 416.510834 -400.453327) (xy 416.563129 -400.437972) (xy 416.617077 -400.430216)
			(xy 416.671579 -400.430216) (xy 416.725527 -400.437972) (xy 416.777822 -400.453327) (xy 416.827399 -400.475969)
			(xy 416.873249 -400.505435) (xy 416.91444 -400.541126) (xy 416.950131 -400.582317) (xy 416.979597 -400.628167)
			(xy 417.002239 -400.677744) (xy 417.017594 -400.730039) (xy 417.02535 -400.783987) (xy 417.025836 -400.811238)
			(xy 417.025836 -401.674838) (xy 417.462716 -401.674838) (xy 417.462716 -400.811238) (xy 417.463202 -400.783987)
			(xy 417.470958 -400.730039) (xy 417.486313 -400.677744) (xy 417.508955 -400.628167) (xy 417.538421 -400.582317)
			(xy 417.574112 -400.541126) (xy 417.615303 -400.505435) (xy 417.661153 -400.475969) (xy 417.71073 -400.453327)
			(xy 417.763025 -400.437972) (xy 417.816973 -400.430216) (xy 417.871475 -400.430216) (xy 417.925423 -400.437972)
			(xy 417.977718 -400.453327) (xy 418.027295 -400.475969) (xy 418.073145 -400.505435) (xy 418.114336 -400.541126)
			(xy 418.150027 -400.582317) (xy 418.179493 -400.628167) (xy 418.202135 -400.677744) (xy 418.21749 -400.730039)
			(xy 418.225246 -400.783987) (xy 418.225732 -400.811238) (xy 418.225732 -401.674838) (xy 418.662612 -401.674838)
			(xy 418.662612 -400.811238) (xy 418.663098 -400.783987) (xy 418.670854 -400.730039) (xy 418.686209 -400.677744)
			(xy 418.708851 -400.628167) (xy 418.738317 -400.582317) (xy 418.774008 -400.541126) (xy 418.815199 -400.505435)
			(xy 418.861049 -400.475969) (xy 418.910626 -400.453327) (xy 418.962921 -400.437972) (xy 419.016869 -400.430216)
			(xy 419.071371 -400.430216) (xy 419.125319 -400.437972) (xy 419.177614 -400.453327) (xy 419.227191 -400.475969)
			(xy 419.273041 -400.505435) (xy 419.314232 -400.541126) (xy 419.349923 -400.582317) (xy 419.379389 -400.628167)
			(xy 419.402031 -400.677744) (xy 419.417386 -400.730039) (xy 419.425142 -400.783987) (xy 419.425628 -400.811238)
			(xy 419.425628 -401.674838) (xy 419.862508 -401.674838) (xy 419.862508 -400.811238) (xy 419.862994 -400.783969)
			(xy 419.870756 -400.729985) (xy 419.886121 -400.677655) (xy 419.908778 -400.628045) (xy 419.938264 -400.582164)
			(xy 419.973979 -400.540947) (xy 420.015196 -400.505232) (xy 420.061077 -400.475746) (xy 420.110687 -400.453089)
			(xy 420.163017 -400.437724) (xy 420.217001 -400.429962) (xy 420.271539 -400.429962) (xy 420.325523 -400.437724)
			(xy 420.377853 -400.453089) (xy 420.427463 -400.475746) (xy 420.473344 -400.505232) (xy 420.514561 -400.540947)
			(xy 420.550276 -400.582164) (xy 420.579762 -400.628045) (xy 420.602419 -400.677655) (xy 420.617784 -400.729985)
			(xy 420.625546 -400.783969) (xy 420.626032 -400.811238) (xy 420.626032 -401.674838) (xy 421.062404 -401.674838)
			(xy 421.062404 -400.811238) (xy 421.06289 -400.783969) (xy 421.070652 -400.729985) (xy 421.086017 -400.677655)
			(xy 421.108674 -400.628045) (xy 421.13816 -400.582164) (xy 421.173875 -400.540947) (xy 421.215092 -400.505232)
			(xy 421.260973 -400.475746) (xy 421.310583 -400.453089) (xy 421.362913 -400.437724) (xy 421.416897 -400.429962)
			(xy 421.471435 -400.429962) (xy 421.525419 -400.437724) (xy 421.577749 -400.453089) (xy 421.627359 -400.475746)
			(xy 421.67324 -400.505232) (xy 421.714457 -400.540947) (xy 421.750172 -400.582164) (xy 421.779658 -400.628045)
			(xy 421.802315 -400.677655) (xy 421.81768 -400.729985) (xy 421.825442 -400.783969) (xy 421.825928 -400.811238)
			(xy 421.825928 -401.674838) (xy 421.825442 -401.702107) (xy 421.81768 -401.756091) (xy 421.802315 -401.808421)
			(xy 421.779658 -401.858031) (xy 421.750172 -401.903912) (xy 421.714457 -401.945129) (xy 421.67324 -401.980844)
			(xy 421.627359 -402.01033) (xy 421.577749 -402.032987) (xy 421.525419 -402.048352) (xy 421.471435 -402.056114)
			(xy 421.416897 -402.056114) (xy 421.362913 -402.048352) (xy 421.310583 -402.032987) (xy 421.260973 -402.01033)
			(xy 421.215092 -401.980844) (xy 421.173875 -401.945129) (xy 421.13816 -401.903912) (xy 421.108674 -401.858031)
			(xy 421.086017 -401.808421) (xy 421.070652 -401.756091) (xy 421.06289 -401.702107) (xy 421.062404 -401.674838)
			(xy 420.626032 -401.674838) (xy 420.625546 -401.702107) (xy 420.617784 -401.756091) (xy 420.602419 -401.808421)
			(xy 420.579762 -401.858031) (xy 420.550276 -401.903912) (xy 420.514561 -401.945129) (xy 420.473344 -401.980844)
			(xy 420.427463 -402.01033) (xy 420.377853 -402.032987) (xy 420.325523 -402.048352) (xy 420.271539 -402.056114)
			(xy 420.217001 -402.056114) (xy 420.163017 -402.048352) (xy 420.110687 -402.032987) (xy 420.061077 -402.01033)
			(xy 420.015196 -401.980844) (xy 419.973979 -401.945129) (xy 419.938264 -401.903912) (xy 419.908778 -401.858031)
			(xy 419.886121 -401.808421) (xy 419.870756 -401.756091) (xy 419.862994 -401.702107) (xy 419.862508 -401.674838)
			(xy 419.425628 -401.674838) (xy 419.425142 -401.702089) (xy 419.417386 -401.756037) (xy 419.402031 -401.808332)
			(xy 419.379389 -401.857909) (xy 419.349923 -401.903759) (xy 419.314232 -401.94495) (xy 419.273041 -401.980641)
			(xy 419.227191 -402.010107) (xy 419.177614 -402.032749) (xy 419.125319 -402.048104) (xy 419.071371 -402.05586)
			(xy 419.016869 -402.05586) (xy 418.962921 -402.048104) (xy 418.910626 -402.032749) (xy 418.861049 -402.010107)
			(xy 418.815199 -401.980641) (xy 418.774008 -401.94495) (xy 418.738317 -401.903759) (xy 418.708851 -401.857909)
			(xy 418.686209 -401.808332) (xy 418.670854 -401.756037) (xy 418.663098 -401.702089) (xy 418.662612 -401.674838)
			(xy 418.225732 -401.674838) (xy 418.225246 -401.702089) (xy 418.21749 -401.756037) (xy 418.202135 -401.808332)
			(xy 418.179493 -401.857909) (xy 418.150027 -401.903759) (xy 418.114336 -401.94495) (xy 418.073145 -401.980641)
			(xy 418.027295 -402.010107) (xy 417.977718 -402.032749) (xy 417.925423 -402.048104) (xy 417.871475 -402.05586)
			(xy 417.816973 -402.05586) (xy 417.763025 -402.048104) (xy 417.71073 -402.032749) (xy 417.661153 -402.010107)
			(xy 417.615303 -401.980641) (xy 417.574112 -401.94495) (xy 417.538421 -401.903759) (xy 417.508955 -401.857909)
			(xy 417.486313 -401.808332) (xy 417.470958 -401.756037) (xy 417.463202 -401.702089) (xy 417.462716 -401.674838)
			(xy 417.025836 -401.674838) (xy 417.02535 -401.702089) (xy 417.017594 -401.756037) (xy 417.002239 -401.808332)
			(xy 416.979597 -401.857909) (xy 416.950131 -401.903759) (xy 416.91444 -401.94495) (xy 416.873249 -401.980641)
			(xy 416.827399 -402.010107) (xy 416.777822 -402.032749) (xy 416.725527 -402.048104) (xy 416.671579 -402.05586)
			(xy 416.617077 -402.05586) (xy 416.563129 -402.048104) (xy 416.510834 -402.032749) (xy 416.461257 -402.010107)
			(xy 416.415407 -401.980641) (xy 416.374216 -401.94495) (xy 416.338525 -401.903759) (xy 416.309059 -401.857909)
			(xy 416.286417 -401.808332) (xy 416.271062 -401.756037) (xy 416.263306 -401.702089) (xy 416.26282 -401.674838)
			(xy 415.82594 -401.674838) (xy 415.825454 -401.702089) (xy 415.817698 -401.756037) (xy 415.802343 -401.808332)
			(xy 415.779701 -401.857909) (xy 415.750235 -401.903759) (xy 415.714544 -401.94495) (xy 415.673353 -401.980641)
			(xy 415.627503 -402.010107) (xy 415.577926 -402.032749) (xy 415.525631 -402.048104) (xy 415.471683 -402.05586)
			(xy 415.417181 -402.05586) (xy 415.363233 -402.048104) (xy 415.310938 -402.032749) (xy 415.261361 -402.010107)
			(xy 415.215511 -401.980641) (xy 415.17432 -401.94495) (xy 415.138629 -401.903759) (xy 415.109163 -401.857909)
			(xy 415.086521 -401.808332) (xy 415.071166 -401.756037) (xy 415.06341 -401.702089) (xy 415.062924 -401.674838)
			(xy 414.626044 -401.674838) (xy 414.625558 -401.702107) (xy 414.617796 -401.756091) (xy 414.602431 -401.808421)
			(xy 414.579774 -401.858031) (xy 414.550288 -401.903912) (xy 414.514573 -401.945129) (xy 414.473356 -401.980844)
			(xy 414.427475 -402.01033) (xy 414.377865 -402.032987) (xy 414.325535 -402.048352) (xy 414.271551 -402.056114)
			(xy 414.217013 -402.056114) (xy 414.163029 -402.048352) (xy 414.110699 -402.032987) (xy 414.061089 -402.01033)
			(xy 414.015208 -401.980844) (xy 413.973991 -401.945129) (xy 413.938276 -401.903912) (xy 413.90879 -401.858031)
			(xy 413.886133 -401.808421) (xy 413.870768 -401.756091) (xy 413.863006 -401.702107) (xy 413.86252 -401.674838)
			(xy 413.426148 -401.674838) (xy 413.425662 -401.702107) (xy 413.4179 -401.756091) (xy 413.402535 -401.808421)
			(xy 413.379878 -401.858031) (xy 413.350392 -401.903912) (xy 413.314677 -401.945129) (xy 413.27346 -401.980844)
			(xy 413.227579 -402.01033) (xy 413.177969 -402.032987) (xy 413.125639 -402.048352) (xy 413.071655 -402.056114)
			(xy 413.017117 -402.056114) (xy 412.963133 -402.048352) (xy 412.910803 -402.032987) (xy 412.861193 -402.01033)
			(xy 412.815312 -401.980844) (xy 412.774095 -401.945129) (xy 412.73838 -401.903912) (xy 412.708894 -401.858031)
			(xy 412.686237 -401.808421) (xy 412.670872 -401.756091) (xy 412.66311 -401.702107) (xy 412.662624 -401.674838)
			(xy 412.225744 -401.674838) (xy 412.225258 -401.702089) (xy 412.217502 -401.756037) (xy 412.202147 -401.808332)
			(xy 412.179505 -401.857909) (xy 412.150039 -401.903759) (xy 412.114348 -401.94495) (xy 412.073157 -401.980641)
			(xy 412.027307 -402.010107) (xy 411.97773 -402.032749) (xy 411.925435 -402.048104) (xy 411.871487 -402.05586)
			(xy 411.816985 -402.05586) (xy 411.763037 -402.048104) (xy 411.710742 -402.032749) (xy 411.661165 -402.010107)
			(xy 411.615315 -401.980641) (xy 411.574124 -401.94495) (xy 411.538433 -401.903759) (xy 411.508967 -401.857909)
			(xy 411.486325 -401.808332) (xy 411.47097 -401.756037) (xy 411.463214 -401.702089) (xy 411.462728 -401.674838)
			(xy 411.025848 -401.674838) (xy 411.025362 -401.702089) (xy 411.017606 -401.756037) (xy 411.002251 -401.808332)
			(xy 410.979609 -401.857909) (xy 410.950143 -401.903759) (xy 410.914452 -401.94495) (xy 410.873261 -401.980641)
			(xy 410.827411 -402.010107) (xy 410.777834 -402.032749) (xy 410.725539 -402.048104) (xy 410.671591 -402.05586)
			(xy 410.617089 -402.05586) (xy 410.563141 -402.048104) (xy 410.510846 -402.032749) (xy 410.461269 -402.010107)
			(xy 410.415419 -401.980641) (xy 410.374228 -401.94495) (xy 410.338537 -401.903759) (xy 410.309071 -401.857909)
			(xy 410.286429 -401.808332) (xy 410.271074 -401.756037) (xy 410.263318 -401.702089) (xy 410.262832 -401.674838)
			(xy 409.825952 -401.674838) (xy 409.825466 -401.702107) (xy 409.817704 -401.756091) (xy 409.802339 -401.808421)
			(xy 409.779682 -401.858031) (xy 409.750196 -401.903912) (xy 409.714481 -401.945129) (xy 409.673264 -401.980844)
			(xy 409.627383 -402.01033) (xy 409.577773 -402.032987) (xy 409.525443 -402.048352) (xy 409.471459 -402.056114)
			(xy 409.416921 -402.056114) (xy 409.362937 -402.048352) (xy 409.310607 -402.032987) (xy 409.260997 -402.01033)
			(xy 409.215116 -401.980844) (xy 409.173899 -401.945129) (xy 409.138184 -401.903912) (xy 409.108698 -401.858031)
			(xy 409.086041 -401.808421) (xy 409.070676 -401.756091) (xy 409.062914 -401.702107) (xy 409.062428 -401.674838)
			(xy 408.626056 -401.674838) (xy 408.62557 -401.702107) (xy 408.617808 -401.756091) (xy 408.602443 -401.808421)
			(xy 408.579786 -401.858031) (xy 408.5503 -401.903912) (xy 408.514585 -401.945129) (xy 408.473368 -401.980844)
			(xy 408.427487 -402.01033) (xy 408.377877 -402.032987) (xy 408.325547 -402.048352) (xy 408.271563 -402.056114)
			(xy 408.217025 -402.056114) (xy 408.163041 -402.048352) (xy 408.110711 -402.032987) (xy 408.061101 -402.01033)
			(xy 408.01522 -401.980844) (xy 407.974003 -401.945129) (xy 407.938288 -401.903912) (xy 407.908802 -401.858031)
			(xy 407.886145 -401.808421) (xy 407.87078 -401.756091) (xy 407.863018 -401.702107) (xy 407.862532 -401.674838)
			(xy 407.425652 -401.674838) (xy 407.425166 -401.702089) (xy 407.41741 -401.756037) (xy 407.402055 -401.808332)
			(xy 407.379413 -401.857909) (xy 407.349947 -401.903759) (xy 407.314256 -401.94495) (xy 407.273065 -401.980641)
			(xy 407.227215 -402.010107) (xy 407.177638 -402.032749) (xy 407.125343 -402.048104) (xy 407.071395 -402.05586)
			(xy 407.016893 -402.05586) (xy 406.962945 -402.048104) (xy 406.91065 -402.032749) (xy 406.861073 -402.010107)
			(xy 406.815223 -401.980641) (xy 406.774032 -401.94495) (xy 406.738341 -401.903759) (xy 406.708875 -401.857909)
			(xy 406.686233 -401.808332) (xy 406.670878 -401.756037) (xy 406.663122 -401.702089) (xy 406.662636 -401.674838)
			(xy 406.225756 -401.674838) (xy 406.22527 -401.702089) (xy 406.217514 -401.756037) (xy 406.202159 -401.808332)
			(xy 406.179517 -401.857909) (xy 406.150051 -401.903759) (xy 406.11436 -401.94495) (xy 406.073169 -401.980641)
			(xy 406.027319 -402.010107) (xy 405.977742 -402.032749) (xy 405.925447 -402.048104) (xy 405.871499 -402.05586)
			(xy 405.816997 -402.05586) (xy 405.763049 -402.048104) (xy 405.710754 -402.032749) (xy 405.661177 -402.010107)
			(xy 405.615327 -401.980641) (xy 405.574136 -401.94495) (xy 405.538445 -401.903759) (xy 405.508979 -401.857909)
			(xy 405.486337 -401.808332) (xy 405.470982 -401.756037) (xy 405.463226 -401.702089) (xy 405.46274 -401.674838)
			(xy 405.02586 -401.674838) (xy 405.025374 -401.702107) (xy 405.017612 -401.756091) (xy 405.002247 -401.808421)
			(xy 404.97959 -401.858031) (xy 404.950104 -401.903912) (xy 404.914389 -401.945129) (xy 404.873172 -401.980844)
			(xy 404.827291 -402.01033) (xy 404.777681 -402.032987) (xy 404.725351 -402.048352) (xy 404.671367 -402.056114)
			(xy 404.616829 -402.056114) (xy 404.562845 -402.048352) (xy 404.510515 -402.032987) (xy 404.460905 -402.01033)
			(xy 404.415024 -401.980844) (xy 404.373807 -401.945129) (xy 404.338092 -401.903912) (xy 404.308606 -401.858031)
			(xy 404.285949 -401.808421) (xy 404.270584 -401.756091) (xy 404.262822 -401.702107) (xy 404.262336 -401.674838)
			(xy 403.825964 -401.674838) (xy 403.825478 -401.702107) (xy 403.817716 -401.756091) (xy 403.802351 -401.808421)
			(xy 403.779694 -401.858031) (xy 403.750208 -401.903912) (xy 403.714493 -401.945129) (xy 403.673276 -401.980844)
			(xy 403.627395 -402.01033) (xy 403.577785 -402.032987) (xy 403.525455 -402.048352) (xy 403.471471 -402.056114)
			(xy 403.416933 -402.056114) (xy 403.362949 -402.048352) (xy 403.310619 -402.032987) (xy 403.261009 -402.01033)
			(xy 403.215128 -401.980844) (xy 403.173911 -401.945129) (xy 403.138196 -401.903912) (xy 403.10871 -401.858031)
			(xy 403.086053 -401.808421) (xy 403.070688 -401.756091) (xy 403.062926 -401.702107) (xy 403.06244 -401.674838)
			(xy 389.29818 -401.674838) (xy 389.297694 -401.702107) (xy 389.289932 -401.756091) (xy 389.274567 -401.808421)
			(xy 389.25191 -401.858031) (xy 389.222424 -401.903912) (xy 389.186709 -401.945129) (xy 389.145492 -401.980844)
			(xy 389.099611 -402.01033) (xy 389.050001 -402.032987) (xy 388.997671 -402.048352) (xy 388.943687 -402.056114)
			(xy 388.889149 -402.056114) (xy 388.835165 -402.048352) (xy 388.782835 -402.032987) (xy 388.733225 -402.01033)
			(xy 388.687344 -401.980844) (xy 388.646127 -401.945129) (xy 388.610412 -401.903912) (xy 388.580926 -401.858031)
			(xy 388.558269 -401.808421) (xy 388.542904 -401.756091) (xy 388.535142 -401.702107) (xy 388.534656 -401.674838)
			(xy 388.098284 -401.674838) (xy 388.097798 -401.702107) (xy 388.090036 -401.756091) (xy 388.074671 -401.808421)
			(xy 388.052014 -401.858031) (xy 388.022528 -401.903912) (xy 387.986813 -401.945129) (xy 387.945596 -401.980844)
			(xy 387.899715 -402.01033) (xy 387.850105 -402.032987) (xy 387.797775 -402.048352) (xy 387.743791 -402.056114)
			(xy 387.689253 -402.056114) (xy 387.635269 -402.048352) (xy 387.582939 -402.032987) (xy 387.533329 -402.01033)
			(xy 387.487448 -401.980844) (xy 387.446231 -401.945129) (xy 387.410516 -401.903912) (xy 387.38103 -401.858031)
			(xy 387.358373 -401.808421) (xy 387.343008 -401.756091) (xy 387.335246 -401.702107) (xy 387.33476 -401.674838)
			(xy 386.89788 -401.674838) (xy 386.897394 -401.702089) (xy 386.889638 -401.756037) (xy 386.874283 -401.808332)
			(xy 386.851641 -401.857909) (xy 386.822175 -401.903759) (xy 386.786484 -401.94495) (xy 386.745293 -401.980641)
			(xy 386.699443 -402.010107) (xy 386.649866 -402.032749) (xy 386.597571 -402.048104) (xy 386.543623 -402.05586)
			(xy 386.489121 -402.05586) (xy 386.435173 -402.048104) (xy 386.382878 -402.032749) (xy 386.333301 -402.010107)
			(xy 386.287451 -401.980641) (xy 386.24626 -401.94495) (xy 386.210569 -401.903759) (xy 386.181103 -401.857909)
			(xy 386.158461 -401.808332) (xy 386.143106 -401.756037) (xy 386.13535 -401.702089) (xy 386.134864 -401.674838)
			(xy 385.697984 -401.674838) (xy 385.697498 -401.702089) (xy 385.689742 -401.756037) (xy 385.674387 -401.808332)
			(xy 385.651745 -401.857909) (xy 385.622279 -401.903759) (xy 385.586588 -401.94495) (xy 385.545397 -401.980641)
			(xy 385.499547 -402.010107) (xy 385.44997 -402.032749) (xy 385.397675 -402.048104) (xy 385.343727 -402.05586)
			(xy 385.289225 -402.05586) (xy 385.235277 -402.048104) (xy 385.182982 -402.032749) (xy 385.133405 -402.010107)
			(xy 385.087555 -401.980641) (xy 385.046364 -401.94495) (xy 385.010673 -401.903759) (xy 384.981207 -401.857909)
			(xy 384.958565 -401.808332) (xy 384.94321 -401.756037) (xy 384.935454 -401.702089) (xy 384.934968 -401.674838)
			(xy 384.498088 -401.674838) (xy 384.497602 -401.702089) (xy 384.489846 -401.756037) (xy 384.474491 -401.808332)
			(xy 384.451849 -401.857909) (xy 384.422383 -401.903759) (xy 384.386692 -401.94495) (xy 384.345501 -401.980641)
			(xy 384.299651 -402.010107) (xy 384.250074 -402.032749) (xy 384.197779 -402.048104) (xy 384.143831 -402.05586)
			(xy 384.089329 -402.05586) (xy 384.035381 -402.048104) (xy 383.983086 -402.032749) (xy 383.933509 -402.010107)
			(xy 383.887659 -401.980641) (xy 383.846468 -401.94495) (xy 383.810777 -401.903759) (xy 383.781311 -401.857909)
			(xy 383.758669 -401.808332) (xy 383.743314 -401.756037) (xy 383.735558 -401.702089) (xy 383.735072 -401.674838)
			(xy 383.298192 -401.674838) (xy 383.297706 -401.702089) (xy 383.28995 -401.756037) (xy 383.274595 -401.808332)
			(xy 383.251953 -401.857909) (xy 383.222487 -401.903759) (xy 383.186796 -401.94495) (xy 383.145605 -401.980641)
			(xy 383.099755 -402.010107) (xy 383.050178 -402.032749) (xy 382.997883 -402.048104) (xy 382.943935 -402.05586)
			(xy 382.889433 -402.05586) (xy 382.835485 -402.048104) (xy 382.78319 -402.032749) (xy 382.733613 -402.010107)
			(xy 382.687763 -401.980641) (xy 382.646572 -401.94495) (xy 382.610881 -401.903759) (xy 382.581415 -401.857909)
			(xy 382.558773 -401.808332) (xy 382.543418 -401.756037) (xy 382.535662 -401.702089) (xy 382.535176 -401.674838)
			(xy 382.098296 -401.674838) (xy 382.09781 -401.702107) (xy 382.090048 -401.756091) (xy 382.074683 -401.808421)
			(xy 382.052026 -401.858031) (xy 382.02254 -401.903912) (xy 381.986825 -401.945129) (xy 381.945608 -401.980844)
			(xy 381.899727 -402.01033) (xy 381.850117 -402.032987) (xy 381.797787 -402.048352) (xy 381.743803 -402.056114)
			(xy 381.689265 -402.056114) (xy 381.635281 -402.048352) (xy 381.582951 -402.032987) (xy 381.533341 -402.01033)
			(xy 381.48746 -401.980844) (xy 381.446243 -401.945129) (xy 381.410528 -401.903912) (xy 381.381042 -401.858031)
			(xy 381.358385 -401.808421) (xy 381.34302 -401.756091) (xy 381.335258 -401.702107) (xy 381.334772 -401.674838)
			(xy 380.8984 -401.674838) (xy 380.897914 -401.702107) (xy 380.890152 -401.756091) (xy 380.874787 -401.808421)
			(xy 380.85213 -401.858031) (xy 380.822644 -401.903912) (xy 380.786929 -401.945129) (xy 380.745712 -401.980844)
			(xy 380.699831 -402.01033) (xy 380.650221 -402.032987) (xy 380.597891 -402.048352) (xy 380.543907 -402.056114)
			(xy 380.489369 -402.056114) (xy 380.435385 -402.048352) (xy 380.383055 -402.032987) (xy 380.333445 -402.01033)
			(xy 380.287564 -401.980844) (xy 380.246347 -401.945129) (xy 380.210632 -401.903912) (xy 380.181146 -401.858031)
			(xy 380.158489 -401.808421) (xy 380.143124 -401.756091) (xy 380.135362 -401.702107) (xy 380.134876 -401.674838)
			(xy 379.697996 -401.674838) (xy 379.69751 -401.702089) (xy 379.689754 -401.756037) (xy 379.674399 -401.808332)
			(xy 379.651757 -401.857909) (xy 379.622291 -401.903759) (xy 379.5866 -401.94495) (xy 379.545409 -401.980641)
			(xy 379.499559 -402.010107) (xy 379.449982 -402.032749) (xy 379.397687 -402.048104) (xy 379.343739 -402.05586)
			(xy 379.289237 -402.05586) (xy 379.235289 -402.048104) (xy 379.182994 -402.032749) (xy 379.133417 -402.010107)
			(xy 379.087567 -401.980641) (xy 379.046376 -401.94495) (xy 379.010685 -401.903759) (xy 378.981219 -401.857909)
			(xy 378.958577 -401.808332) (xy 378.943222 -401.756037) (xy 378.935466 -401.702089) (xy 378.93498 -401.674838)
			(xy 378.4981 -401.674838) (xy 378.497614 -401.702089) (xy 378.489858 -401.756037) (xy 378.474503 -401.808332)
			(xy 378.451861 -401.857909) (xy 378.422395 -401.903759) (xy 378.386704 -401.94495) (xy 378.345513 -401.980641)
			(xy 378.299663 -402.010107) (xy 378.250086 -402.032749) (xy 378.197791 -402.048104) (xy 378.143843 -402.05586)
			(xy 378.089341 -402.05586) (xy 378.035393 -402.048104) (xy 377.983098 -402.032749) (xy 377.933521 -402.010107)
			(xy 377.887671 -401.980641) (xy 377.84648 -401.94495) (xy 377.810789 -401.903759) (xy 377.781323 -401.857909)
			(xy 377.758681 -401.808332) (xy 377.743326 -401.756037) (xy 377.73557 -401.702089) (xy 377.735084 -401.674838)
			(xy 377.298204 -401.674838) (xy 377.297718 -401.702107) (xy 377.289956 -401.756091) (xy 377.274591 -401.808421)
			(xy 377.251934 -401.858031) (xy 377.222448 -401.903912) (xy 377.186733 -401.945129) (xy 377.145516 -401.980844)
			(xy 377.099635 -402.01033) (xy 377.050025 -402.032987) (xy 376.997695 -402.048352) (xy 376.943711 -402.056114)
			(xy 376.889173 -402.056114) (xy 376.835189 -402.048352) (xy 376.782859 -402.032987) (xy 376.733249 -402.01033)
			(xy 376.687368 -401.980844) (xy 376.646151 -401.945129) (xy 376.610436 -401.903912) (xy 376.58095 -401.858031)
			(xy 376.558293 -401.808421) (xy 376.542928 -401.756091) (xy 376.535166 -401.702107) (xy 376.53468 -401.674838)
			(xy 376.098308 -401.674838) (xy 376.097822 -401.702107) (xy 376.09006 -401.756091) (xy 376.074695 -401.808421)
			(xy 376.052038 -401.858031) (xy 376.022552 -401.903912) (xy 375.986837 -401.945129) (xy 375.94562 -401.980844)
			(xy 375.899739 -402.01033) (xy 375.850129 -402.032987) (xy 375.797799 -402.048352) (xy 375.743815 -402.056114)
			(xy 375.689277 -402.056114) (xy 375.635293 -402.048352) (xy 375.582963 -402.032987) (xy 375.533353 -402.01033)
			(xy 375.487472 -401.980844) (xy 375.446255 -401.945129) (xy 375.41054 -401.903912) (xy 375.381054 -401.858031)
			(xy 375.358397 -401.808421) (xy 375.343032 -401.756091) (xy 375.33527 -401.702107) (xy 375.334784 -401.674838)
			(xy 374.897904 -401.674838) (xy 374.897418 -401.702089) (xy 374.889662 -401.756037) (xy 374.874307 -401.808332)
			(xy 374.851665 -401.857909) (xy 374.822199 -401.903759) (xy 374.786508 -401.94495) (xy 374.745317 -401.980641)
			(xy 374.699467 -402.010107) (xy 374.64989 -402.032749) (xy 374.597595 -402.048104) (xy 374.543647 -402.05586)
			(xy 374.489145 -402.05586) (xy 374.435197 -402.048104) (xy 374.382902 -402.032749) (xy 374.333325 -402.010107)
			(xy 374.287475 -401.980641) (xy 374.246284 -401.94495) (xy 374.210593 -401.903759) (xy 374.181127 -401.857909)
			(xy 374.158485 -401.808332) (xy 374.14313 -401.756037) (xy 374.135374 -401.702089) (xy 374.134888 -401.674838)
			(xy 373.698008 -401.674838) (xy 373.697522 -401.702089) (xy 373.689766 -401.756037) (xy 373.674411 -401.808332)
			(xy 373.651769 -401.857909) (xy 373.622303 -401.903759) (xy 373.586612 -401.94495) (xy 373.545421 -401.980641)
			(xy 373.499571 -402.010107) (xy 373.449994 -402.032749) (xy 373.397699 -402.048104) (xy 373.343751 -402.05586)
			(xy 373.289249 -402.05586) (xy 373.235301 -402.048104) (xy 373.183006 -402.032749) (xy 373.133429 -402.010107)
			(xy 373.087579 -401.980641) (xy 373.046388 -401.94495) (xy 373.010697 -401.903759) (xy 372.981231 -401.857909)
			(xy 372.958589 -401.808332) (xy 372.943234 -401.756037) (xy 372.935478 -401.702089) (xy 372.934992 -401.674838)
			(xy 372.498112 -401.674838) (xy 372.497626 -401.702107) (xy 372.489864 -401.756091) (xy 372.474499 -401.808421)
			(xy 372.451842 -401.858031) (xy 372.422356 -401.903912) (xy 372.386641 -401.945129) (xy 372.345424 -401.980844)
			(xy 372.299543 -402.01033) (xy 372.249933 -402.032987) (xy 372.197603 -402.048352) (xy 372.143619 -402.056114)
			(xy 372.089081 -402.056114) (xy 372.035097 -402.048352) (xy 371.982767 -402.032987) (xy 371.933157 -402.01033)
			(xy 371.887276 -401.980844) (xy 371.846059 -401.945129) (xy 371.810344 -401.903912) (xy 371.780858 -401.858031)
			(xy 371.758201 -401.808421) (xy 371.742836 -401.756091) (xy 371.735074 -401.702107) (xy 371.734588 -401.674838)
			(xy 371.298216 -401.674838) (xy 371.29773 -401.702107) (xy 371.289968 -401.756091) (xy 371.274603 -401.808421)
			(xy 371.251946 -401.858031) (xy 371.22246 -401.903912) (xy 371.186745 -401.945129) (xy 371.145528 -401.980844)
			(xy 371.099647 -402.01033) (xy 371.050037 -402.032987) (xy 370.997707 -402.048352) (xy 370.943723 -402.056114)
			(xy 370.889185 -402.056114) (xy 370.835201 -402.048352) (xy 370.782871 -402.032987) (xy 370.733261 -402.01033)
			(xy 370.68738 -401.980844) (xy 370.646163 -401.945129) (xy 370.610448 -401.903912) (xy 370.580962 -401.858031)
			(xy 370.558305 -401.808421) (xy 370.54294 -401.756091) (xy 370.535178 -401.702107) (xy 370.534692 -401.674838)
			(xy 354.725732 -401.674838) (xy 354.725246 -401.702107) (xy 354.717484 -401.756091) (xy 354.702119 -401.808421)
			(xy 354.679462 -401.858031) (xy 354.649976 -401.903912) (xy 354.614261 -401.945129) (xy 354.573044 -401.980844)
			(xy 354.527163 -402.01033) (xy 354.477553 -402.032987) (xy 354.425223 -402.048352) (xy 354.371239 -402.056114)
			(xy 354.316701 -402.056114) (xy 354.262717 -402.048352) (xy 354.210387 -402.032987) (xy 354.160777 -402.01033)
			(xy 354.114896 -401.980844) (xy 354.073679 -401.945129) (xy 354.037964 -401.903912) (xy 354.008478 -401.858031)
			(xy 353.985821 -401.808421) (xy 353.970456 -401.756091) (xy 353.962694 -401.702107) (xy 353.962208 -401.674838)
			(xy 353.525836 -401.674838) (xy 353.52535 -401.702107) (xy 353.517588 -401.756091) (xy 353.502223 -401.808421)
			(xy 353.479566 -401.858031) (xy 353.45008 -401.903912) (xy 353.414365 -401.945129) (xy 353.373148 -401.980844)
			(xy 353.327267 -402.01033) (xy 353.277657 -402.032987) (xy 353.225327 -402.048352) (xy 353.171343 -402.056114)
			(xy 353.116805 -402.056114) (xy 353.062821 -402.048352) (xy 353.010491 -402.032987) (xy 352.960881 -402.01033)
			(xy 352.915 -401.980844) (xy 352.873783 -401.945129) (xy 352.838068 -401.903912) (xy 352.808582 -401.858031)
			(xy 352.785925 -401.808421) (xy 352.77056 -401.756091) (xy 352.762798 -401.702107) (xy 352.762312 -401.674838)
			(xy 352.325432 -401.674838) (xy 352.324946 -401.702089) (xy 352.31719 -401.756037) (xy 352.301835 -401.808332)
			(xy 352.279193 -401.857909) (xy 352.249727 -401.903759) (xy 352.214036 -401.94495) (xy 352.172845 -401.980641)
			(xy 352.126995 -402.010107) (xy 352.077418 -402.032749) (xy 352.025123 -402.048104) (xy 351.971175 -402.05586)
			(xy 351.916673 -402.05586) (xy 351.862725 -402.048104) (xy 351.81043 -402.032749) (xy 351.760853 -402.010107)
			(xy 351.715003 -401.980641) (xy 351.673812 -401.94495) (xy 351.638121 -401.903759) (xy 351.608655 -401.857909)
			(xy 351.586013 -401.808332) (xy 351.570658 -401.756037) (xy 351.562902 -401.702089) (xy 351.562416 -401.674838)
			(xy 351.125536 -401.674838) (xy 351.12505 -401.702089) (xy 351.117294 -401.756037) (xy 351.101939 -401.808332)
			(xy 351.079297 -401.857909) (xy 351.049831 -401.903759) (xy 351.01414 -401.94495) (xy 350.972949 -401.980641)
			(xy 350.927099 -402.010107) (xy 350.877522 -402.032749) (xy 350.825227 -402.048104) (xy 350.771279 -402.05586)
			(xy 350.716777 -402.05586) (xy 350.662829 -402.048104) (xy 350.610534 -402.032749) (xy 350.560957 -402.010107)
			(xy 350.515107 -401.980641) (xy 350.473916 -401.94495) (xy 350.438225 -401.903759) (xy 350.408759 -401.857909)
			(xy 350.386117 -401.808332) (xy 350.370762 -401.756037) (xy 350.363006 -401.702089) (xy 350.36252 -401.674838)
			(xy 349.92564 -401.674838) (xy 349.925154 -401.702089) (xy 349.917398 -401.756037) (xy 349.902043 -401.808332)
			(xy 349.879401 -401.857909) (xy 349.849935 -401.903759) (xy 349.814244 -401.94495) (xy 349.773053 -401.980641)
			(xy 349.727203 -402.010107) (xy 349.677626 -402.032749) (xy 349.625331 -402.048104) (xy 349.571383 -402.05586)
			(xy 349.516881 -402.05586) (xy 349.462933 -402.048104) (xy 349.410638 -402.032749) (xy 349.361061 -402.010107)
			(xy 349.315211 -401.980641) (xy 349.27402 -401.94495) (xy 349.238329 -401.903759) (xy 349.208863 -401.857909)
			(xy 349.186221 -401.808332) (xy 349.170866 -401.756037) (xy 349.16311 -401.702089) (xy 349.162624 -401.674838)
			(xy 348.725744 -401.674838) (xy 348.725258 -401.702089) (xy 348.717502 -401.756037) (xy 348.702147 -401.808332)
			(xy 348.679505 -401.857909) (xy 348.650039 -401.903759) (xy 348.614348 -401.94495) (xy 348.573157 -401.980641)
			(xy 348.527307 -402.010107) (xy 348.47773 -402.032749) (xy 348.425435 -402.048104) (xy 348.371487 -402.05586)
			(xy 348.316985 -402.05586) (xy 348.263037 -402.048104) (xy 348.210742 -402.032749) (xy 348.161165 -402.010107)
			(xy 348.115315 -401.980641) (xy 348.074124 -401.94495) (xy 348.038433 -401.903759) (xy 348.008967 -401.857909)
			(xy 347.986325 -401.808332) (xy 347.97097 -401.756037) (xy 347.963214 -401.702089) (xy 347.962728 -401.674838)
			(xy 347.525848 -401.674838) (xy 347.525362 -401.702107) (xy 347.5176 -401.756091) (xy 347.502235 -401.808421)
			(xy 347.479578 -401.858031) (xy 347.450092 -401.903912) (xy 347.414377 -401.945129) (xy 347.37316 -401.980844)
			(xy 347.327279 -402.01033) (xy 347.277669 -402.032987) (xy 347.225339 -402.048352) (xy 347.171355 -402.056114)
			(xy 347.116817 -402.056114) (xy 347.062833 -402.048352) (xy 347.010503 -402.032987) (xy 346.960893 -402.01033)
			(xy 346.915012 -401.980844) (xy 346.873795 -401.945129) (xy 346.83808 -401.903912) (xy 346.808594 -401.858031)
			(xy 346.785937 -401.808421) (xy 346.770572 -401.756091) (xy 346.76281 -401.702107) (xy 346.762324 -401.674838)
			(xy 346.325952 -401.674838) (xy 346.325466 -401.702107) (xy 346.317704 -401.756091) (xy 346.302339 -401.808421)
			(xy 346.279682 -401.858031) (xy 346.250196 -401.903912) (xy 346.214481 -401.945129) (xy 346.173264 -401.980844)
			(xy 346.127383 -402.01033) (xy 346.077773 -402.032987) (xy 346.025443 -402.048352) (xy 345.971459 -402.056114)
			(xy 345.916921 -402.056114) (xy 345.862937 -402.048352) (xy 345.810607 -402.032987) (xy 345.760997 -402.01033)
			(xy 345.715116 -401.980844) (xy 345.673899 -401.945129) (xy 345.638184 -401.903912) (xy 345.608698 -401.858031)
			(xy 345.586041 -401.808421) (xy 345.570676 -401.756091) (xy 345.562914 -401.702107) (xy 345.562428 -401.674838)
			(xy 345.125548 -401.674838) (xy 345.125062 -401.702089) (xy 345.117306 -401.756037) (xy 345.101951 -401.808332)
			(xy 345.079309 -401.857909) (xy 345.049843 -401.903759) (xy 345.014152 -401.94495) (xy 344.972961 -401.980641)
			(xy 344.927111 -402.010107) (xy 344.877534 -402.032749) (xy 344.825239 -402.048104) (xy 344.771291 -402.05586)
			(xy 344.716789 -402.05586) (xy 344.662841 -402.048104) (xy 344.610546 -402.032749) (xy 344.560969 -402.010107)
			(xy 344.515119 -401.980641) (xy 344.473928 -401.94495) (xy 344.438237 -401.903759) (xy 344.408771 -401.857909)
			(xy 344.386129 -401.808332) (xy 344.370774 -401.756037) (xy 344.363018 -401.702089) (xy 344.362532 -401.674838)
			(xy 343.925652 -401.674838) (xy 343.925166 -401.702089) (xy 343.91741 -401.756037) (xy 343.902055 -401.808332)
			(xy 343.879413 -401.857909) (xy 343.849947 -401.903759) (xy 343.814256 -401.94495) (xy 343.773065 -401.980641)
			(xy 343.727215 -402.010107) (xy 343.677638 -402.032749) (xy 343.625343 -402.048104) (xy 343.571395 -402.05586)
			(xy 343.516893 -402.05586) (xy 343.462945 -402.048104) (xy 343.41065 -402.032749) (xy 343.361073 -402.010107)
			(xy 343.315223 -401.980641) (xy 343.274032 -401.94495) (xy 343.238341 -401.903759) (xy 343.208875 -401.857909)
			(xy 343.186233 -401.808332) (xy 343.170878 -401.756037) (xy 343.163122 -401.702089) (xy 343.162636 -401.674838)
			(xy 342.725756 -401.674838) (xy 342.72527 -401.702107) (xy 342.717508 -401.756091) (xy 342.702143 -401.808421)
			(xy 342.679486 -401.858031) (xy 342.65 -401.903912) (xy 342.614285 -401.945129) (xy 342.573068 -401.980844)
			(xy 342.527187 -402.01033) (xy 342.477577 -402.032987) (xy 342.425247 -402.048352) (xy 342.371263 -402.056114)
			(xy 342.316725 -402.056114) (xy 342.262741 -402.048352) (xy 342.210411 -402.032987) (xy 342.160801 -402.01033)
			(xy 342.11492 -401.980844) (xy 342.073703 -401.945129) (xy 342.037988 -401.903912) (xy 342.008502 -401.858031)
			(xy 341.985845 -401.808421) (xy 341.97048 -401.756091) (xy 341.962718 -401.702107) (xy 341.962232 -401.674838)
			(xy 341.52586 -401.674838) (xy 341.525374 -401.702107) (xy 341.517612 -401.756091) (xy 341.502247 -401.808421)
			(xy 341.47959 -401.858031) (xy 341.450104 -401.903912) (xy 341.414389 -401.945129) (xy 341.373172 -401.980844)
			(xy 341.327291 -402.01033) (xy 341.277681 -402.032987) (xy 341.225351 -402.048352) (xy 341.171367 -402.056114)
			(xy 341.116829 -402.056114) (xy 341.062845 -402.048352) (xy 341.010515 -402.032987) (xy 340.960905 -402.01033)
			(xy 340.915024 -401.980844) (xy 340.873807 -401.945129) (xy 340.838092 -401.903912) (xy 340.808606 -401.858031)
			(xy 340.785949 -401.808421) (xy 340.770584 -401.756091) (xy 340.762822 -401.702107) (xy 340.762336 -401.674838)
			(xy 340.325456 -401.674838) (xy 340.32497 -401.702089) (xy 340.317214 -401.756037) (xy 340.301859 -401.808332)
			(xy 340.279217 -401.857909) (xy 340.249751 -401.903759) (xy 340.21406 -401.94495) (xy 340.172869 -401.980641)
			(xy 340.127019 -402.010107) (xy 340.077442 -402.032749) (xy 340.025147 -402.048104) (xy 339.971199 -402.05586)
			(xy 339.916697 -402.05586) (xy 339.862749 -402.048104) (xy 339.810454 -402.032749) (xy 339.760877 -402.010107)
			(xy 339.715027 -401.980641) (xy 339.673836 -401.94495) (xy 339.638145 -401.903759) (xy 339.608679 -401.857909)
			(xy 339.586037 -401.808332) (xy 339.570682 -401.756037) (xy 339.562926 -401.702089) (xy 339.56244 -401.674838)
			(xy 339.12556 -401.674838) (xy 339.125074 -401.702089) (xy 339.117318 -401.756037) (xy 339.101963 -401.808332)
			(xy 339.079321 -401.857909) (xy 339.049855 -401.903759) (xy 339.014164 -401.94495) (xy 338.972973 -401.980641)
			(xy 338.927123 -402.010107) (xy 338.877546 -402.032749) (xy 338.825251 -402.048104) (xy 338.771303 -402.05586)
			(xy 338.716801 -402.05586) (xy 338.662853 -402.048104) (xy 338.610558 -402.032749) (xy 338.560981 -402.010107)
			(xy 338.515131 -401.980641) (xy 338.47394 -401.94495) (xy 338.438249 -401.903759) (xy 338.408783 -401.857909)
			(xy 338.386141 -401.808332) (xy 338.370786 -401.756037) (xy 338.36303 -401.702089) (xy 338.362544 -401.674838)
			(xy 337.925664 -401.674838) (xy 337.925178 -401.702107) (xy 337.917416 -401.756091) (xy 337.902051 -401.808421)
			(xy 337.879394 -401.858031) (xy 337.849908 -401.903912) (xy 337.814193 -401.945129) (xy 337.772976 -401.980844)
			(xy 337.727095 -402.01033) (xy 337.677485 -402.032987) (xy 337.625155 -402.048352) (xy 337.571171 -402.056114)
			(xy 337.516633 -402.056114) (xy 337.462649 -402.048352) (xy 337.410319 -402.032987) (xy 337.360709 -402.01033)
			(xy 337.314828 -401.980844) (xy 337.273611 -401.945129) (xy 337.237896 -401.903912) (xy 337.20841 -401.858031)
			(xy 337.185753 -401.808421) (xy 337.170388 -401.756091) (xy 337.162626 -401.702107) (xy 337.16214 -401.674838)
			(xy 336.725768 -401.674838) (xy 336.725282 -401.702107) (xy 336.71752 -401.756091) (xy 336.702155 -401.808421)
			(xy 336.679498 -401.858031) (xy 336.650012 -401.903912) (xy 336.614297 -401.945129) (xy 336.57308 -401.980844)
			(xy 336.527199 -402.01033) (xy 336.477589 -402.032987) (xy 336.425259 -402.048352) (xy 336.371275 -402.056114)
			(xy 336.316737 -402.056114) (xy 336.262753 -402.048352) (xy 336.210423 -402.032987) (xy 336.160813 -402.01033)
			(xy 336.114932 -401.980844) (xy 336.073715 -401.945129) (xy 336.038 -401.903912) (xy 336.008514 -401.858031)
			(xy 335.985857 -401.808421) (xy 335.970492 -401.756091) (xy 335.96273 -401.702107) (xy 335.962244 -401.674838)
			(xy 322.197984 -401.674838) (xy 322.197498 -401.702107) (xy 322.189736 -401.756091) (xy 322.174371 -401.808421)
			(xy 322.151714 -401.858031) (xy 322.122228 -401.903912) (xy 322.086513 -401.945129) (xy 322.045296 -401.980844)
			(xy 321.999415 -402.01033) (xy 321.949805 -402.032987) (xy 321.897475 -402.048352) (xy 321.843491 -402.056114)
			(xy 321.788953 -402.056114) (xy 321.734969 -402.048352) (xy 321.682639 -402.032987) (xy 321.633029 -402.01033)
			(xy 321.587148 -401.980844) (xy 321.545931 -401.945129) (xy 321.510216 -401.903912) (xy 321.48073 -401.858031)
			(xy 321.458073 -401.808421) (xy 321.442708 -401.756091) (xy 321.434946 -401.702107) (xy 321.43446 -401.674838)
			(xy 320.998088 -401.674838) (xy 320.997602 -401.702107) (xy 320.98984 -401.756091) (xy 320.974475 -401.808421)
			(xy 320.951818 -401.858031) (xy 320.922332 -401.903912) (xy 320.886617 -401.945129) (xy 320.8454 -401.980844)
			(xy 320.799519 -402.01033) (xy 320.749909 -402.032987) (xy 320.697579 -402.048352) (xy 320.643595 -402.056114)
			(xy 320.589057 -402.056114) (xy 320.535073 -402.048352) (xy 320.482743 -402.032987) (xy 320.433133 -402.01033)
			(xy 320.387252 -401.980844) (xy 320.346035 -401.945129) (xy 320.31032 -401.903912) (xy 320.280834 -401.858031)
			(xy 320.258177 -401.808421) (xy 320.242812 -401.756091) (xy 320.23505 -401.702107) (xy 320.234564 -401.674838)
			(xy 319.797684 -401.674838) (xy 319.797198 -401.702089) (xy 319.789442 -401.756037) (xy 319.774087 -401.808332)
			(xy 319.751445 -401.857909) (xy 319.721979 -401.903759) (xy 319.686288 -401.94495) (xy 319.645097 -401.980641)
			(xy 319.599247 -402.010107) (xy 319.54967 -402.032749) (xy 319.497375 -402.048104) (xy 319.443427 -402.05586)
			(xy 319.388925 -402.05586) (xy 319.334977 -402.048104) (xy 319.282682 -402.032749) (xy 319.233105 -402.010107)
			(xy 319.187255 -401.980641) (xy 319.146064 -401.94495) (xy 319.110373 -401.903759) (xy 319.080907 -401.857909)
			(xy 319.058265 -401.808332) (xy 319.04291 -401.756037) (xy 319.035154 -401.702089) (xy 319.034668 -401.674838)
			(xy 318.597788 -401.674838) (xy 318.597302 -401.702089) (xy 318.589546 -401.756037) (xy 318.574191 -401.808332)
			(xy 318.551549 -401.857909) (xy 318.522083 -401.903759) (xy 318.486392 -401.94495) (xy 318.445201 -401.980641)
			(xy 318.399351 -402.010107) (xy 318.349774 -402.032749) (xy 318.297479 -402.048104) (xy 318.243531 -402.05586)
			(xy 318.189029 -402.05586) (xy 318.135081 -402.048104) (xy 318.082786 -402.032749) (xy 318.033209 -402.010107)
			(xy 317.987359 -401.980641) (xy 317.946168 -401.94495) (xy 317.910477 -401.903759) (xy 317.881011 -401.857909)
			(xy 317.858369 -401.808332) (xy 317.843014 -401.756037) (xy 317.835258 -401.702089) (xy 317.834772 -401.674838)
			(xy 317.397892 -401.674838) (xy 317.397406 -401.702089) (xy 317.38965 -401.756037) (xy 317.374295 -401.808332)
			(xy 317.351653 -401.857909) (xy 317.322187 -401.903759) (xy 317.286496 -401.94495) (xy 317.245305 -401.980641)
			(xy 317.199455 -402.010107) (xy 317.149878 -402.032749) (xy 317.097583 -402.048104) (xy 317.043635 -402.05586)
			(xy 316.989133 -402.05586) (xy 316.935185 -402.048104) (xy 316.88289 -402.032749) (xy 316.833313 -402.010107)
			(xy 316.787463 -401.980641) (xy 316.746272 -401.94495) (xy 316.710581 -401.903759) (xy 316.681115 -401.857909)
			(xy 316.658473 -401.808332) (xy 316.643118 -401.756037) (xy 316.635362 -401.702089) (xy 316.634876 -401.674838)
			(xy 316.197996 -401.674838) (xy 316.19751 -401.702089) (xy 316.189754 -401.756037) (xy 316.174399 -401.808332)
			(xy 316.151757 -401.857909) (xy 316.122291 -401.903759) (xy 316.0866 -401.94495) (xy 316.045409 -401.980641)
			(xy 315.999559 -402.010107) (xy 315.949982 -402.032749) (xy 315.897687 -402.048104) (xy 315.843739 -402.05586)
			(xy 315.789237 -402.05586) (xy 315.735289 -402.048104) (xy 315.682994 -402.032749) (xy 315.633417 -402.010107)
			(xy 315.587567 -401.980641) (xy 315.546376 -401.94495) (xy 315.510685 -401.903759) (xy 315.481219 -401.857909)
			(xy 315.458577 -401.808332) (xy 315.443222 -401.756037) (xy 315.435466 -401.702089) (xy 315.43498 -401.674838)
			(xy 314.9981 -401.674838) (xy 314.997614 -401.702107) (xy 314.989852 -401.756091) (xy 314.974487 -401.808421)
			(xy 314.95183 -401.858031) (xy 314.922344 -401.903912) (xy 314.886629 -401.945129) (xy 314.845412 -401.980844)
			(xy 314.799531 -402.01033) (xy 314.749921 -402.032987) (xy 314.697591 -402.048352) (xy 314.643607 -402.056114)
			(xy 314.589069 -402.056114) (xy 314.535085 -402.048352) (xy 314.482755 -402.032987) (xy 314.433145 -402.01033)
			(xy 314.387264 -401.980844) (xy 314.346047 -401.945129) (xy 314.310332 -401.903912) (xy 314.280846 -401.858031)
			(xy 314.258189 -401.808421) (xy 314.242824 -401.756091) (xy 314.235062 -401.702107) (xy 314.234576 -401.674838)
			(xy 313.798204 -401.674838) (xy 313.797718 -401.702107) (xy 313.789956 -401.756091) (xy 313.774591 -401.808421)
			(xy 313.751934 -401.858031) (xy 313.722448 -401.903912) (xy 313.686733 -401.945129) (xy 313.645516 -401.980844)
			(xy 313.599635 -402.01033) (xy 313.550025 -402.032987) (xy 313.497695 -402.048352) (xy 313.443711 -402.056114)
			(xy 313.389173 -402.056114) (xy 313.335189 -402.048352) (xy 313.282859 -402.032987) (xy 313.233249 -402.01033)
			(xy 313.187368 -401.980844) (xy 313.146151 -401.945129) (xy 313.110436 -401.903912) (xy 313.08095 -401.858031)
			(xy 313.058293 -401.808421) (xy 313.042928 -401.756091) (xy 313.035166 -401.702107) (xy 313.03468 -401.674838)
			(xy 312.5978 -401.674838) (xy 312.597314 -401.702089) (xy 312.589558 -401.756037) (xy 312.574203 -401.808332)
			(xy 312.551561 -401.857909) (xy 312.522095 -401.903759) (xy 312.486404 -401.94495) (xy 312.445213 -401.980641)
			(xy 312.399363 -402.010107) (xy 312.349786 -402.032749) (xy 312.297491 -402.048104) (xy 312.243543 -402.05586)
			(xy 312.189041 -402.05586) (xy 312.135093 -402.048104) (xy 312.082798 -402.032749) (xy 312.033221 -402.010107)
			(xy 311.987371 -401.980641) (xy 311.94618 -401.94495) (xy 311.910489 -401.903759) (xy 311.881023 -401.857909)
			(xy 311.858381 -401.808332) (xy 311.843026 -401.756037) (xy 311.83527 -401.702089) (xy 311.834784 -401.674838)
			(xy 311.397904 -401.674838) (xy 311.397418 -401.702089) (xy 311.389662 -401.756037) (xy 311.374307 -401.808332)
			(xy 311.351665 -401.857909) (xy 311.322199 -401.903759) (xy 311.286508 -401.94495) (xy 311.245317 -401.980641)
			(xy 311.199467 -402.010107) (xy 311.14989 -402.032749) (xy 311.097595 -402.048104) (xy 311.043647 -402.05586)
			(xy 310.989145 -402.05586) (xy 310.935197 -402.048104) (xy 310.882902 -402.032749) (xy 310.833325 -402.010107)
			(xy 310.787475 -401.980641) (xy 310.746284 -401.94495) (xy 310.710593 -401.903759) (xy 310.681127 -401.857909)
			(xy 310.658485 -401.808332) (xy 310.64313 -401.756037) (xy 310.635374 -401.702089) (xy 310.634888 -401.674838)
			(xy 310.198008 -401.674838) (xy 310.197522 -401.702107) (xy 310.18976 -401.756091) (xy 310.174395 -401.808421)
			(xy 310.151738 -401.858031) (xy 310.122252 -401.903912) (xy 310.086537 -401.945129) (xy 310.04532 -401.980844)
			(xy 309.999439 -402.01033) (xy 309.949829 -402.032987) (xy 309.897499 -402.048352) (xy 309.843515 -402.056114)
			(xy 309.788977 -402.056114) (xy 309.734993 -402.048352) (xy 309.682663 -402.032987) (xy 309.633053 -402.01033)
			(xy 309.587172 -401.980844) (xy 309.545955 -401.945129) (xy 309.51024 -401.903912) (xy 309.480754 -401.858031)
			(xy 309.458097 -401.808421) (xy 309.442732 -401.756091) (xy 309.43497 -401.702107) (xy 309.434484 -401.674838)
			(xy 308.998112 -401.674838) (xy 308.997626 -401.702107) (xy 308.989864 -401.756091) (xy 308.974499 -401.808421)
			(xy 308.951842 -401.858031) (xy 308.922356 -401.903912) (xy 308.886641 -401.945129) (xy 308.845424 -401.980844)
			(xy 308.799543 -402.01033) (xy 308.749933 -402.032987) (xy 308.697603 -402.048352) (xy 308.643619 -402.056114)
			(xy 308.589081 -402.056114) (xy 308.535097 -402.048352) (xy 308.482767 -402.032987) (xy 308.433157 -402.01033)
			(xy 308.387276 -401.980844) (xy 308.346059 -401.945129) (xy 308.310344 -401.903912) (xy 308.280858 -401.858031)
			(xy 308.258201 -401.808421) (xy 308.242836 -401.756091) (xy 308.235074 -401.702107) (xy 308.234588 -401.674838)
			(xy 307.797708 -401.674838) (xy 307.797222 -401.702089) (xy 307.789466 -401.756037) (xy 307.774111 -401.808332)
			(xy 307.751469 -401.857909) (xy 307.722003 -401.903759) (xy 307.686312 -401.94495) (xy 307.645121 -401.980641)
			(xy 307.599271 -402.010107) (xy 307.549694 -402.032749) (xy 307.497399 -402.048104) (xy 307.443451 -402.05586)
			(xy 307.388949 -402.05586) (xy 307.335001 -402.048104) (xy 307.282706 -402.032749) (xy 307.233129 -402.010107)
			(xy 307.187279 -401.980641) (xy 307.146088 -401.94495) (xy 307.110397 -401.903759) (xy 307.080931 -401.857909)
			(xy 307.058289 -401.808332) (xy 307.042934 -401.756037) (xy 307.035178 -401.702089) (xy 307.034692 -401.674838)
			(xy 306.597812 -401.674838) (xy 306.597326 -401.702089) (xy 306.58957 -401.756037) (xy 306.574215 -401.808332)
			(xy 306.551573 -401.857909) (xy 306.522107 -401.903759) (xy 306.486416 -401.94495) (xy 306.445225 -401.980641)
			(xy 306.399375 -402.010107) (xy 306.349798 -402.032749) (xy 306.297503 -402.048104) (xy 306.243555 -402.05586)
			(xy 306.189053 -402.05586) (xy 306.135105 -402.048104) (xy 306.08281 -402.032749) (xy 306.033233 -402.010107)
			(xy 305.987383 -401.980641) (xy 305.946192 -401.94495) (xy 305.910501 -401.903759) (xy 305.881035 -401.857909)
			(xy 305.858393 -401.808332) (xy 305.843038 -401.756037) (xy 305.835282 -401.702089) (xy 305.834796 -401.674838)
			(xy 305.397916 -401.674838) (xy 305.39743 -401.702107) (xy 305.389668 -401.756091) (xy 305.374303 -401.808421)
			(xy 305.351646 -401.858031) (xy 305.32216 -401.903912) (xy 305.286445 -401.945129) (xy 305.245228 -401.980844)
			(xy 305.199347 -402.01033) (xy 305.149737 -402.032987) (xy 305.097407 -402.048352) (xy 305.043423 -402.056114)
			(xy 304.988885 -402.056114) (xy 304.934901 -402.048352) (xy 304.882571 -402.032987) (xy 304.832961 -402.01033)
			(xy 304.78708 -401.980844) (xy 304.745863 -401.945129) (xy 304.710148 -401.903912) (xy 304.680662 -401.858031)
			(xy 304.658005 -401.808421) (xy 304.64264 -401.756091) (xy 304.634878 -401.702107) (xy 304.634392 -401.674838)
			(xy 304.19802 -401.674838) (xy 304.197534 -401.702107) (xy 304.189772 -401.756091) (xy 304.174407 -401.808421)
			(xy 304.15175 -401.858031) (xy 304.122264 -401.903912) (xy 304.086549 -401.945129) (xy 304.045332 -401.980844)
			(xy 303.999451 -402.01033) (xy 303.949841 -402.032987) (xy 303.897511 -402.048352) (xy 303.843527 -402.056114)
			(xy 303.788989 -402.056114) (xy 303.735005 -402.048352) (xy 303.682675 -402.032987) (xy 303.633065 -402.01033)
			(xy 303.587184 -401.980844) (xy 303.545967 -401.945129) (xy 303.510252 -401.903912) (xy 303.480766 -401.858031)
			(xy 303.458109 -401.808421) (xy 303.442744 -401.756091) (xy 303.434982 -401.702107) (xy 303.434496 -401.674838)
			(xy 280.68524 -401.674838) (xy 280.68524 -404.215092) (xy 283.62402 -404.215092) (xy 283.62402 -403.351492)
			(xy 283.624506 -403.324223) (xy 283.632268 -403.270239) (xy 283.647633 -403.217909) (xy 283.67029 -403.168299)
			(xy 283.699776 -403.122418) (xy 283.735491 -403.081201) (xy 283.776708 -403.045486) (xy 283.822589 -403.016)
			(xy 283.872199 -402.993343) (xy 283.924529 -402.977978) (xy 283.978513 -402.970216) (xy 284.033051 -402.970216)
			(xy 284.087035 -402.977978) (xy 284.139365 -402.993343) (xy 284.188975 -403.016) (xy 284.203533 -403.025356)
			(xy 289.919156 -403.025356) (xy 289.919156 -402.161756) (xy 289.919642 -402.134487) (xy 289.927404 -402.080503)
			(xy 289.942769 -402.028173) (xy 289.965426 -401.978563) (xy 289.994912 -401.932682) (xy 290.030627 -401.891465)
			(xy 290.071844 -401.85575) (xy 290.117725 -401.826264) (xy 290.167335 -401.803607) (xy 290.219665 -401.788242)
			(xy 290.273649 -401.78048) (xy 290.328187 -401.78048) (xy 290.382171 -401.788242) (xy 290.434501 -401.803607)
			(xy 290.484111 -401.826264) (xy 290.529992 -401.85575) (xy 290.571209 -401.891465) (xy 290.606924 -401.932682)
			(xy 290.63641 -401.978563) (xy 290.659067 -402.028173) (xy 290.674432 -402.080503) (xy 290.682194 -402.134487)
			(xy 290.68268 -402.161756) (xy 290.68268 -403.025356) (xy 290.682194 -403.052625) (xy 290.674432 -403.106609)
			(xy 290.659067 -403.158939) (xy 290.63641 -403.208549) (xy 290.606924 -403.25443) (xy 290.571209 -403.295647)
			(xy 290.529992 -403.331362) (xy 290.484111 -403.360848) (xy 290.434501 -403.383505) (xy 290.382171 -403.39887)
			(xy 290.328187 -403.406632) (xy 290.273649 -403.406632) (xy 290.219665 -403.39887) (xy 290.167335 -403.383505)
			(xy 290.117725 -403.360848) (xy 290.071844 -403.331362) (xy 290.030627 -403.295647) (xy 289.994912 -403.25443)
			(xy 289.965426 -403.208549) (xy 289.942769 -403.158939) (xy 289.927404 -403.106609) (xy 289.919642 -403.052625)
			(xy 289.919156 -403.025356) (xy 284.203533 -403.025356) (xy 284.234856 -403.045486) (xy 284.276073 -403.081201)
			(xy 284.311788 -403.122418) (xy 284.341274 -403.168299) (xy 284.363931 -403.217909) (xy 284.379296 -403.270239)
			(xy 284.387058 -403.324223) (xy 284.387544 -403.351492) (xy 284.387544 -404.215092) (xy 284.387058 -404.242361)
			(xy 284.379296 -404.296345) (xy 284.363931 -404.348675) (xy 284.341274 -404.398285) (xy 284.311788 -404.444166)
			(xy 284.276073 -404.485383) (xy 284.234856 -404.521098) (xy 284.188975 -404.550584) (xy 284.139365 -404.573241)
			(xy 284.087035 -404.588606) (xy 284.033051 -404.596368) (xy 283.978513 -404.596368) (xy 283.924529 -404.588606)
			(xy 283.872199 -404.573241) (xy 283.822589 -404.550584) (xy 283.776708 -404.521098) (xy 283.735491 -404.485383)
			(xy 283.699776 -404.444166) (xy 283.67029 -404.398285) (xy 283.647633 -404.348675) (xy 283.632268 -404.296345)
			(xy 283.624506 -404.242361) (xy 283.62402 -404.215092) (xy 280.68524 -404.215092) (xy 280.68524 -407.583953)
			(xy 282.536071 -407.583953) (xy 282.536071 -407.529447) (xy 282.543829 -407.475495) (xy 282.559186 -407.423196)
			(xy 282.581831 -407.373615) (xy 282.611301 -407.327762) (xy 282.646997 -407.28657) (xy 282.688193 -407.250878)
			(xy 282.734049 -407.221412) (xy 282.783632 -407.198773) (xy 282.835932 -407.183421) (xy 282.889885 -407.175669)
			(xy 282.917138 -407.175208) (xy 283.780738 -407.175208) (xy 283.807989 -407.175664) (xy 283.861934 -407.183426)
			(xy 283.914227 -407.198785) (xy 283.963801 -407.221429) (xy 284.009649 -407.250898) (xy 284.050836 -407.286591)
			(xy 284.086525 -407.327782) (xy 284.115989 -407.373632) (xy 284.134525 -407.414222) (xy 287.101788 -407.414222)
			(xy 287.101788 -406.550622) (xy 287.102274 -406.523371) (xy 287.11003 -406.469423) (xy 287.125385 -406.417128)
			(xy 287.148027 -406.367551) (xy 287.177493 -406.321701) (xy 287.213184 -406.28051) (xy 287.254375 -406.244819)
			(xy 287.300225 -406.215353) (xy 287.349802 -406.192711) (xy 287.402097 -406.177356) (xy 287.456045 -406.1696)
			(xy 287.510547 -406.1696) (xy 287.564495 -406.177356) (xy 287.61679 -406.192711) (xy 287.666367 -406.215353)
			(xy 287.712217 -406.244819) (xy 287.753408 -406.28051) (xy 287.789099 -406.321701) (xy 287.818565 -406.367551)
			(xy 287.841207 -406.417128) (xy 287.856562 -406.469423) (xy 287.864318 -406.523371) (xy 287.864804 -406.550622)
			(xy 287.864804 -407.414222) (xy 287.864318 -407.441473) (xy 287.856562 -407.495421) (xy 287.841207 -407.547716)
			(xy 287.818565 -407.597293) (xy 287.789099 -407.643143) (xy 287.753408 -407.684334) (xy 287.712217 -407.720025)
			(xy 287.666367 -407.749491) (xy 287.61679 -407.772133) (xy 287.564495 -407.787488) (xy 287.510547 -407.795244)
			(xy 287.456045 -407.795244) (xy 287.402097 -407.787488) (xy 287.349802 -407.772133) (xy 287.300225 -407.749491)
			(xy 287.254375 -407.720025) (xy 287.213184 -407.684334) (xy 287.177493 -407.643143) (xy 287.148027 -407.597293)
			(xy 287.125385 -407.547716) (xy 287.11003 -407.495421) (xy 287.102274 -407.441473) (xy 287.101788 -407.414222)
			(xy 284.134525 -407.414222) (xy 284.138629 -407.423209) (xy 284.153982 -407.475503) (xy 284.161738 -407.529449)
			(xy 284.161738 -407.583951) (xy 284.153982 -407.637897) (xy 284.138629 -407.690191) (xy 284.115989 -407.739768)
			(xy 284.086525 -407.785619) (xy 284.050836 -407.826809) (xy 284.009649 -407.862502) (xy 283.963801 -407.891971)
			(xy 283.914227 -407.914615) (xy 283.861934 -407.929974) (xy 283.807989 -407.937736) (xy 283.780738 -407.938224)
			(xy 282.917138 -407.938224) (xy 282.889885 -407.937731) (xy 282.835932 -407.929979) (xy 282.783632 -407.914627)
			(xy 282.734049 -407.891988) (xy 282.688193 -407.862522) (xy 282.646997 -407.82683) (xy 282.611301 -407.785638)
			(xy 282.581831 -407.739785) (xy 282.559186 -407.690204) (xy 282.543829 -407.637905) (xy 282.536071 -407.583953)
			(xy 280.68524 -407.583953) (xy 280.68524 -409.10256) (xy 280.684766 -409.12751) (xy 280.676946 -409.176794)
			(xy 280.661524 -409.224251) (xy 280.638877 -409.268716) (xy 280.609563 -409.309098) (xy 280.592276 -409.327096)
			(xy 276.749256 -413.170116) (xy 293.568894 -413.170116) (xy 293.572866 -412.991873) (xy 293.584774 -412.813984)
			(xy 293.604595 -412.636802) (xy 293.632289 -412.460678) (xy 293.667801 -412.285963) (xy 293.711061 -412.113004)
			(xy 293.761983 -411.942143) (xy 293.820466 -411.773721) (xy 293.886393 -411.608071) (xy 293.959634 -411.445522)
			(xy 294.040044 -411.286397) (xy 294.127462 -411.131012) (xy 294.221715 -410.979676) (xy 294.322616 -410.832688)
			(xy 294.429965 -410.690341) (xy 294.543548 -410.552918) (xy 294.663141 -410.420691) (xy 294.788505 -410.293922)
			(xy 294.919392 -410.172864) (xy 295.055541 -410.057757) (xy 295.196683 -409.948829) (xy 295.342538 -409.846297)
			(xy 295.492815 -409.750363) (xy 295.647216 -409.66122) (xy 295.805435 -409.579043) (xy 295.967158 -409.503995)
			(xy 296.132063 -409.436227) (xy 296.299824 -409.375871) (xy 296.470107 -409.323049) (xy 296.642574 -409.277865)
			(xy 296.816882 -409.240408) (xy 296.992686 -409.210754) (xy 297.169636 -409.188961) (xy 297.347382 -409.175071)
			(xy 297.525569 -409.169114) (xy 297.703846 -409.1711) (xy 297.881857 -409.181026) (xy 298.059249 -409.198872)
			(xy 298.235669 -409.224602) (xy 298.410769 -409.258166) (xy 298.5842 -409.299496) (xy 298.755617 -409.348512)
			(xy 298.92468 -409.405114) (xy 299.091055 -409.469192) (xy 299.254409 -409.540618) (xy 299.41442 -409.61925)
			(xy 299.570769 -409.704931) (xy 299.723146 -409.797493) (xy 299.871249 -409.89675) (xy 300.014783 -410.002507)
			(xy 300.153463 -410.114552) (xy 300.287014 -410.232664) (xy 300.415171 -410.356608) (xy 300.53768 -410.486138)
			(xy 300.654297 -410.620997) (xy 300.76479 -410.760917) (xy 300.868941 -410.90562) (xy 300.966543 -411.054819)
			(xy 301.057401 -411.208218) (xy 301.141335 -411.365512) (xy 301.21818 -411.526388) (xy 301.287781 -411.690529)
			(xy 301.350002 -411.857606) (xy 301.404718 -412.02729) (xy 301.45182 -412.199243) (xy 301.491216 -412.373123)
			(xy 301.522827 -412.548586) (xy 301.546591 -412.725282) (xy 301.559858 -412.873752) (xy 303.412875 -412.873752)
			(xy 303.412875 -412.819248) (xy 303.420632 -412.7653) (xy 303.435988 -412.713004) (xy 303.458629 -412.663426)
			(xy 303.488096 -412.617575) (xy 303.523789 -412.576384) (xy 303.56498 -412.540693) (xy 303.610831 -412.511226)
			(xy 303.66041 -412.488585) (xy 303.712706 -412.473231) (xy 303.766654 -412.465475) (xy 303.793906 -412.465012)
			(xy 304.657506 -412.465012) (xy 304.684758 -412.465458) (xy 304.738708 -412.473216) (xy 304.791005 -412.488572)
			(xy 304.840584 -412.511215) (xy 304.886436 -412.540683) (xy 304.927628 -412.576376) (xy 304.963321 -412.617569)
			(xy 304.992788 -412.663421) (xy 305.01543 -412.713001) (xy 305.030785 -412.765298) (xy 305.038542 -412.819248)
			(xy 305.038542 -412.873752) (xy 305.038542 -412.873754) (xy 306.476075 -412.873754) (xy 306.476075 -412.819246)
			(xy 306.483833 -412.765294) (xy 306.499191 -412.712996) (xy 306.521835 -412.663415) (xy 306.551306 -412.617562)
			(xy 306.587003 -412.57637) (xy 306.628199 -412.540679) (xy 306.674055 -412.511213) (xy 306.723639 -412.488575)
			(xy 306.775939 -412.473223) (xy 306.829892 -412.465472) (xy 306.857146 -412.465012) (xy 307.720746 -412.465012)
			(xy 307.747997 -412.465461) (xy 307.801942 -412.473223) (xy 307.854234 -412.488583) (xy 307.903808 -412.511228)
			(xy 307.949655 -412.540697) (xy 307.990842 -412.576391) (xy 308.02653 -412.617582) (xy 308.055994 -412.663432)
			(xy 308.078633 -412.713009) (xy 308.093987 -412.765303) (xy 308.101742 -412.819249) (xy 308.101742 -412.873749)
			(xy 309.539398 -412.873749) (xy 309.539398 -412.819251) (xy 309.547154 -412.765307) (xy 309.562508 -412.713016)
			(xy 309.585146 -412.663443) (xy 309.61461 -412.617596) (xy 309.650298 -412.576408) (xy 309.691484 -412.540718)
			(xy 309.73733 -412.511253) (xy 309.786903 -412.488612) (xy 309.839194 -412.473257) (xy 309.893137 -412.465499)
			(xy 309.920386 -412.465012) (xy 310.783986 -412.465012) (xy 310.811241 -412.465434) (xy 310.865196 -412.47319)
			(xy 310.917499 -412.488545) (xy 310.967083 -412.511188) (xy 311.012941 -412.540657) (xy 311.054137 -412.576353)
			(xy 311.089834 -412.617548) (xy 311.119305 -412.663405) (xy 311.14195 -412.712988) (xy 311.157307 -412.76529)
			(xy 311.165065 -412.819245) (xy 311.165065 -412.873753) (xy 312.602575 -412.873753) (xy 312.602575 -412.819247)
			(xy 312.610333 -412.765297) (xy 312.625689 -412.713) (xy 312.648332 -412.663421) (xy 312.677801 -412.617569)
			(xy 312.713496 -412.576377) (xy 312.754689 -412.540686) (xy 312.800543 -412.51122) (xy 312.850124 -412.48858)
			(xy 312.902422 -412.473227) (xy 312.956373 -412.465474) (xy 312.983626 -412.465012) (xy 313.847226 -412.465012)
			(xy 313.874477 -412.46546) (xy 313.928425 -412.47322) (xy 313.98072 -412.488578) (xy 314.030296 -412.511222)
			(xy 314.076146 -412.54069) (xy 314.117335 -412.576383) (xy 314.153026 -412.617575) (xy 314.182491 -412.663427)
			(xy 314.205131 -412.713005) (xy 314.220486 -412.7653) (xy 314.228242 -412.819249) (xy 314.228242 -412.873748)
			(xy 315.665898 -412.873748) (xy 315.665898 -412.819252) (xy 315.673653 -412.76531) (xy 315.689006 -412.713021)
			(xy 315.711643 -412.663448) (xy 315.741105 -412.617602) (xy 315.776791 -412.576415) (xy 315.817975 -412.540725)
			(xy 315.863818 -412.51126) (xy 315.913389 -412.488618) (xy 315.965677 -412.473261) (xy 316.019618 -412.465501)
			(xy 316.046866 -412.465012) (xy 316.910466 -412.465012) (xy 316.937722 -412.465433) (xy 316.991679 -412.473186)
			(xy 317.043984 -412.48854) (xy 317.093571 -412.511182) (xy 317.139431 -412.54065) (xy 317.18063 -412.576346)
			(xy 317.216329 -412.617542) (xy 317.245802 -412.663399) (xy 317.268448 -412.712984) (xy 317.283807 -412.765287)
			(xy 317.291565 -412.819244) (xy 317.291565 -412.873752) (xy 318.729075 -412.873752) (xy 318.729075 -412.819248)
			(xy 318.736832 -412.7653) (xy 318.752188 -412.713004) (xy 318.774829 -412.663426) (xy 318.804296 -412.617575)
			(xy 318.839989 -412.576384) (xy 318.88118 -412.540693) (xy 318.927031 -412.511226) (xy 318.97661 -412.488585)
			(xy 319.028906 -412.473231) (xy 319.082854 -412.465475) (xy 319.110106 -412.465012) (xy 319.973706 -412.465012)
			(xy 320.000958 -412.465458) (xy 320.054908 -412.473216) (xy 320.107205 -412.488572) (xy 320.156784 -412.511215)
			(xy 320.202636 -412.540683) (xy 320.243828 -412.576376) (xy 320.279521 -412.617569) (xy 320.308988 -412.663421)
			(xy 320.33163 -412.713001) (xy 320.346985 -412.765298) (xy 320.354742 -412.819248) (xy 320.354742 -412.873752)
			(xy 320.354742 -412.873754) (xy 321.792275 -412.873754) (xy 321.792275 -412.819246) (xy 321.800033 -412.765294)
			(xy 321.815391 -412.712996) (xy 321.838035 -412.663415) (xy 321.867506 -412.617562) (xy 321.903203 -412.57637)
			(xy 321.944399 -412.540679) (xy 321.990255 -412.511213) (xy 322.039839 -412.488575) (xy 322.092139 -412.473223)
			(xy 322.146092 -412.465472) (xy 322.173346 -412.465012) (xy 323.036946 -412.465012) (xy 323.064197 -412.465461)
			(xy 323.118142 -412.473223) (xy 323.170434 -412.488583) (xy 323.220008 -412.511228) (xy 323.265855 -412.540697)
			(xy 323.307042 -412.576391) (xy 323.34273 -412.617582) (xy 323.372194 -412.663432) (xy 323.394833 -412.713009)
			(xy 323.410187 -412.765303) (xy 323.417942 -412.819249) (xy 323.417942 -412.873749) (xy 324.855598 -412.873749)
			(xy 324.855598 -412.819251) (xy 324.863354 -412.765307) (xy 324.878708 -412.713016) (xy 324.901346 -412.663443)
			(xy 324.93081 -412.617596) (xy 324.966498 -412.576408) (xy 325.007684 -412.540718) (xy 325.05353 -412.511253)
			(xy 325.103103 -412.488612) (xy 325.155394 -412.473257) (xy 325.209337 -412.465499) (xy 325.236586 -412.465012)
			(xy 326.100186 -412.465012) (xy 326.127441 -412.465434) (xy 326.181396 -412.47319) (xy 326.233699 -412.488545)
			(xy 326.283283 -412.511188) (xy 326.329141 -412.540657) (xy 326.370337 -412.576353) (xy 326.406034 -412.617548)
			(xy 326.435505 -412.663405) (xy 326.45815 -412.712988) (xy 326.473507 -412.76529) (xy 326.481265 -412.819245)
			(xy 326.481265 -412.873753) (xy 327.918775 -412.873753) (xy 327.918775 -412.819247) (xy 327.926533 -412.765297)
			(xy 327.941889 -412.713) (xy 327.964532 -412.663421) (xy 327.994001 -412.617569) (xy 328.029696 -412.576377)
			(xy 328.070889 -412.540686) (xy 328.116743 -412.51122) (xy 328.166324 -412.48858) (xy 328.218622 -412.473227)
			(xy 328.272573 -412.465474) (xy 328.299826 -412.465012) (xy 329.163426 -412.465012) (xy 329.190677 -412.46546)
			(xy 329.244625 -412.47322) (xy 329.29692 -412.488578) (xy 329.346496 -412.511222) (xy 329.392346 -412.54069)
			(xy 329.433535 -412.576383) (xy 329.469226 -412.617575) (xy 329.498691 -412.663427) (xy 329.521331 -412.713005)
			(xy 329.536686 -412.7653) (xy 329.544442 -412.819249) (xy 329.544442 -412.873748) (xy 330.982098 -412.873748)
			(xy 330.982098 -412.819252) (xy 330.989853 -412.76531) (xy 331.005206 -412.713021) (xy 331.027843 -412.663448)
			(xy 331.057305 -412.617602) (xy 331.092991 -412.576415) (xy 331.134175 -412.540725) (xy 331.180018 -412.51126)
			(xy 331.229589 -412.488618) (xy 331.281877 -412.473261) (xy 331.335818 -412.465501) (xy 331.363066 -412.465012)
			(xy 332.226666 -412.465012) (xy 332.253922 -412.465433) (xy 332.307879 -412.473186) (xy 332.360184 -412.48854)
			(xy 332.409771 -412.511182) (xy 332.455631 -412.54065) (xy 332.49683 -412.576346) (xy 332.532529 -412.617542)
			(xy 332.562002 -412.663399) (xy 332.584648 -412.712984) (xy 332.600007 -412.765287) (xy 332.607765 -412.819244)
			(xy 332.607765 -412.873752) (xy 334.045275 -412.873752) (xy 334.045275 -412.819248) (xy 334.053032 -412.7653)
			(xy 334.068388 -412.713004) (xy 334.091029 -412.663426) (xy 334.120496 -412.617575) (xy 334.156189 -412.576384)
			(xy 334.19738 -412.540693) (xy 334.243231 -412.511226) (xy 334.29281 -412.488585) (xy 334.345106 -412.473231)
			(xy 334.399054 -412.465475) (xy 334.426306 -412.465012) (xy 335.289906 -412.465012) (xy 335.317158 -412.465458)
			(xy 335.371108 -412.473216) (xy 335.423405 -412.488572) (xy 335.472984 -412.511215) (xy 335.518836 -412.540683)
			(xy 335.560028 -412.576376) (xy 335.595721 -412.617569) (xy 335.625188 -412.663421) (xy 335.64783 -412.713001)
			(xy 335.663185 -412.765298) (xy 335.670942 -412.819248) (xy 335.670942 -412.873752) (xy 335.670942 -412.873754)
			(xy 337.108475 -412.873754) (xy 337.108475 -412.819246) (xy 337.116233 -412.765294) (xy 337.131591 -412.712996)
			(xy 337.154235 -412.663415) (xy 337.183706 -412.617562) (xy 337.219403 -412.57637) (xy 337.260599 -412.540679)
			(xy 337.306455 -412.511213) (xy 337.356039 -412.488575) (xy 337.408339 -412.473223) (xy 337.462292 -412.465472)
			(xy 337.489546 -412.465012) (xy 338.353146 -412.465012) (xy 338.380397 -412.465461) (xy 338.434342 -412.473223)
			(xy 338.486634 -412.488583) (xy 338.536208 -412.511228) (xy 338.582055 -412.540697) (xy 338.623242 -412.576391)
			(xy 338.65893 -412.617582) (xy 338.688394 -412.663432) (xy 338.711033 -412.713009) (xy 338.726387 -412.765303)
			(xy 338.734142 -412.819249) (xy 338.734142 -412.873749) (xy 340.171798 -412.873749) (xy 340.171798 -412.819251)
			(xy 340.179554 -412.765307) (xy 340.194908 -412.713016) (xy 340.217546 -412.663443) (xy 340.24701 -412.617596)
			(xy 340.282698 -412.576408) (xy 340.323884 -412.540718) (xy 340.36973 -412.511253) (xy 340.419303 -412.488612)
			(xy 340.471594 -412.473257) (xy 340.525537 -412.465499) (xy 340.552786 -412.465012) (xy 341.416386 -412.465012)
			(xy 341.443641 -412.465434) (xy 341.497596 -412.47319) (xy 341.549899 -412.488545) (xy 341.599483 -412.511188)
			(xy 341.645341 -412.540657) (xy 341.686537 -412.576353) (xy 341.722234 -412.617548) (xy 341.751705 -412.663405)
			(xy 341.77435 -412.712988) (xy 341.789707 -412.76529) (xy 341.797465 -412.819245) (xy 341.797465 -412.873753)
			(xy 343.234975 -412.873753) (xy 343.234975 -412.819247) (xy 343.242733 -412.765297) (xy 343.258089 -412.713)
			(xy 343.280732 -412.663421) (xy 343.310201 -412.617569) (xy 343.345896 -412.576377) (xy 343.387089 -412.540686)
			(xy 343.432943 -412.51122) (xy 343.482524 -412.48858) (xy 343.534822 -412.473227) (xy 343.588773 -412.465474)
			(xy 343.616026 -412.465012) (xy 344.479626 -412.465012) (xy 344.506877 -412.46546) (xy 344.560825 -412.47322)
			(xy 344.61312 -412.488578) (xy 344.662696 -412.511222) (xy 344.708546 -412.54069) (xy 344.749735 -412.576383)
			(xy 344.785426 -412.617575) (xy 344.814891 -412.663427) (xy 344.837531 -412.713005) (xy 344.852886 -412.7653)
			(xy 344.860642 -412.819249) (xy 344.860642 -412.873748) (xy 346.298298 -412.873748) (xy 346.298298 -412.819252)
			(xy 346.306053 -412.76531) (xy 346.321406 -412.713021) (xy 346.344043 -412.663448) (xy 346.373505 -412.617602)
			(xy 346.409191 -412.576415) (xy 346.450375 -412.540725) (xy 346.496218 -412.51126) (xy 346.545789 -412.488618)
			(xy 346.598077 -412.473261) (xy 346.652018 -412.465501) (xy 346.679266 -412.465012) (xy 347.542866 -412.465012)
			(xy 347.570122 -412.465433) (xy 347.624079 -412.473186) (xy 347.676384 -412.48854) (xy 347.725971 -412.511182)
			(xy 347.771831 -412.54065) (xy 347.81303 -412.576346) (xy 347.848729 -412.617542) (xy 347.878202 -412.663399)
			(xy 347.900848 -412.712984) (xy 347.916207 -412.765287) (xy 347.923965 -412.819244) (xy 347.923965 -412.873752)
			(xy 349.361475 -412.873752) (xy 349.361475 -412.819248) (xy 349.369232 -412.7653) (xy 349.384588 -412.713004)
			(xy 349.407229 -412.663426) (xy 349.436696 -412.617575) (xy 349.472389 -412.576384) (xy 349.51358 -412.540693)
			(xy 349.559431 -412.511226) (xy 349.60901 -412.488585) (xy 349.661306 -412.473231) (xy 349.715254 -412.465475)
			(xy 349.742506 -412.465012) (xy 350.606106 -412.465012) (xy 350.633358 -412.465458) (xy 350.687308 -412.473216)
			(xy 350.739605 -412.488572) (xy 350.789184 -412.511215) (xy 350.835036 -412.540683) (xy 350.876228 -412.576376)
			(xy 350.911921 -412.617569) (xy 350.941388 -412.663421) (xy 350.96403 -412.713001) (xy 350.979385 -412.765298)
			(xy 350.987142 -412.819248) (xy 350.987142 -412.873752) (xy 370.513075 -412.873752) (xy 370.513075 -412.819248)
			(xy 370.520832 -412.7653) (xy 370.536187 -412.713005) (xy 370.558829 -412.663427) (xy 370.588295 -412.617576)
			(xy 370.623987 -412.576386) (xy 370.665178 -412.540694) (xy 370.711029 -412.511228) (xy 370.760607 -412.488587)
			(xy 370.812902 -412.473231) (xy 370.86685 -412.465475) (xy 370.894102 -412.465012) (xy 371.757702 -412.465012)
			(xy 371.784955 -412.465458) (xy 371.838905 -412.473215) (xy 371.891202 -412.488571) (xy 371.940782 -412.511214)
			(xy 371.986634 -412.540682) (xy 372.027826 -412.576375) (xy 372.06352 -412.617567) (xy 372.092987 -412.66342)
			(xy 372.115629 -412.713) (xy 372.130985 -412.765297) (xy 372.138742 -412.819247) (xy 372.138742 -412.873753)
			(xy 373.576275 -412.873753) (xy 373.576275 -412.819247) (xy 373.584033 -412.765295) (xy 373.59939 -412.712996)
			(xy 373.622035 -412.663416) (xy 373.651505 -412.617563) (xy 373.687201 -412.576372) (xy 373.728397 -412.54068)
			(xy 373.774253 -412.511215) (xy 373.823836 -412.488576) (xy 373.876136 -412.473224) (xy 373.930089 -412.465472)
			(xy 373.957342 -412.465012) (xy 374.820942 -412.465012) (xy 374.848193 -412.465461) (xy 374.902139 -412.473222)
			(xy 374.954431 -412.488582) (xy 375.004006 -412.511227) (xy 375.049853 -412.540696) (xy 375.091041 -412.576389)
			(xy 375.126729 -412.61758) (xy 375.156193 -412.663431) (xy 375.178833 -412.713008) (xy 375.194186 -412.765302)
			(xy 375.201942 -412.819249) (xy 375.201942 -412.873749) (xy 376.639598 -412.873749) (xy 376.639598 -412.819251)
			(xy 376.647354 -412.765308) (xy 376.662707 -412.713017) (xy 376.685346 -412.663444) (xy 376.714809 -412.617597)
			(xy 376.750497 -412.576409) (xy 376.791682 -412.54072) (xy 376.837528 -412.511254) (xy 376.8871 -412.488613)
			(xy 376.93939 -412.473258) (xy 376.993333 -412.465499) (xy 377.020582 -412.465012) (xy 377.884182 -412.465012)
			(xy 377.911437 -412.465434) (xy 377.965393 -412.473189) (xy 378.017696 -412.488544) (xy 378.067281 -412.511187)
			(xy 378.113139 -412.540656) (xy 378.154336 -412.576352) (xy 378.190033 -412.617547) (xy 378.219504 -412.663403)
			(xy 378.242149 -412.712987) (xy 378.257507 -412.765289) (xy 378.265265 -412.819245) (xy 378.265265 -412.873752)
			(xy 379.702775 -412.873752) (xy 379.702775 -412.819248) (xy 379.710532 -412.765298) (xy 379.725889 -412.713001)
			(xy 379.748532 -412.663422) (xy 379.778 -412.61757) (xy 379.813694 -412.576379) (xy 379.854888 -412.540687)
			(xy 379.900741 -412.511221) (xy 379.950321 -412.488581) (xy 380.002619 -412.473228) (xy 380.05657 -412.465474)
			(xy 380.083822 -412.465012) (xy 380.947422 -412.465012) (xy 380.974674 -412.465459) (xy 381.028622 -412.473219)
			(xy 381.080917 -412.488577) (xy 381.130494 -412.51122) (xy 381.176344 -412.540689) (xy 381.217534 -412.576382)
			(xy 381.253225 -412.617574) (xy 381.28269 -412.663426) (xy 381.305331 -412.713004) (xy 381.320686 -412.7653)
			(xy 381.328442 -412.819248) (xy 381.328442 -412.873748) (xy 382.766098 -412.873748) (xy 382.766098 -412.819252)
			(xy 382.773853 -412.76531) (xy 382.789206 -412.713022) (xy 382.811843 -412.663449) (xy 382.841304 -412.617603)
			(xy 382.876989 -412.576416) (xy 382.918173 -412.540727) (xy 382.964016 -412.511261) (xy 383.013586 -412.488619)
			(xy 383.065873 -412.473261) (xy 383.119814 -412.465501) (xy 383.147062 -412.465012) (xy 384.010662 -412.465012)
			(xy 384.037918 -412.465432) (xy 384.091876 -412.473185) (xy 384.144181 -412.488539) (xy 384.193769 -412.51118)
			(xy 384.239629 -412.540649) (xy 384.280829 -412.576345) (xy 384.316528 -412.61754) (xy 384.346001 -412.663398)
			(xy 384.368648 -412.712983) (xy 384.384007 -412.765287) (xy 384.391765 -412.819244) (xy 384.391765 -412.873752)
			(xy 385.829275 -412.873752) (xy 385.829275 -412.819248) (xy 385.837032 -412.7653) (xy 385.852387 -412.713005)
			(xy 385.875029 -412.663427) (xy 385.904495 -412.617576) (xy 385.940187 -412.576386) (xy 385.981378 -412.540694)
			(xy 386.027229 -412.511228) (xy 386.076807 -412.488587) (xy 386.129102 -412.473231) (xy 386.18305 -412.465475)
			(xy 386.210302 -412.465012) (xy 387.073902 -412.465012) (xy 387.101155 -412.465458) (xy 387.155105 -412.473215)
			(xy 387.207402 -412.488571) (xy 387.256982 -412.511214) (xy 387.302834 -412.540682) (xy 387.344026 -412.576375)
			(xy 387.37972 -412.617567) (xy 387.409187 -412.66342) (xy 387.431829 -412.713) (xy 387.447185 -412.765297)
			(xy 387.454942 -412.819247) (xy 387.454942 -412.873753) (xy 388.892475 -412.873753) (xy 388.892475 -412.819247)
			(xy 388.900233 -412.765295) (xy 388.91559 -412.712996) (xy 388.938235 -412.663416) (xy 388.967705 -412.617563)
			(xy 389.003401 -412.576372) (xy 389.044597 -412.54068) (xy 389.090453 -412.511215) (xy 389.140036 -412.488576)
			(xy 389.192336 -412.473224) (xy 389.246289 -412.465472) (xy 389.273542 -412.465012) (xy 390.137142 -412.465012)
			(xy 390.164393 -412.465461) (xy 390.218339 -412.473222) (xy 390.270631 -412.488582) (xy 390.320206 -412.511227)
			(xy 390.366053 -412.540696) (xy 390.407241 -412.576389) (xy 390.442929 -412.61758) (xy 390.472393 -412.663431)
			(xy 390.495033 -412.713008) (xy 390.510386 -412.765302) (xy 390.518142 -412.819249) (xy 390.518142 -412.873749)
			(xy 391.955798 -412.873749) (xy 391.955798 -412.819251) (xy 391.963554 -412.765308) (xy 391.978907 -412.713017)
			(xy 392.001546 -412.663444) (xy 392.031009 -412.617597) (xy 392.066697 -412.576409) (xy 392.107882 -412.54072)
			(xy 392.153728 -412.511254) (xy 392.2033 -412.488613) (xy 392.25559 -412.473258) (xy 392.309533 -412.465499)
			(xy 392.336782 -412.465012) (xy 393.200382 -412.465012) (xy 393.227637 -412.465434) (xy 393.281593 -412.473189)
			(xy 393.333896 -412.488544) (xy 393.383481 -412.511187) (xy 393.429339 -412.540656) (xy 393.470536 -412.576352)
			(xy 393.506233 -412.617547) (xy 393.535704 -412.663403) (xy 393.558349 -412.712987) (xy 393.573707 -412.765289)
			(xy 393.581465 -412.819245) (xy 393.581465 -412.873752) (xy 395.018975 -412.873752) (xy 395.018975 -412.819248)
			(xy 395.026732 -412.765298) (xy 395.042089 -412.713001) (xy 395.064732 -412.663422) (xy 395.0942 -412.61757)
			(xy 395.129894 -412.576379) (xy 395.171088 -412.540687) (xy 395.216941 -412.511221) (xy 395.266521 -412.488581)
			(xy 395.318819 -412.473228) (xy 395.37277 -412.465474) (xy 395.400022 -412.465012) (xy 396.263622 -412.465012)
			(xy 396.290874 -412.465459) (xy 396.344822 -412.473219) (xy 396.397117 -412.488577) (xy 396.446694 -412.51122)
			(xy 396.492544 -412.540689) (xy 396.533734 -412.576382) (xy 396.569425 -412.617574) (xy 396.59889 -412.663426)
			(xy 396.621531 -412.713004) (xy 396.636886 -412.7653) (xy 396.644642 -412.819248) (xy 396.644642 -412.873748)
			(xy 398.082298 -412.873748) (xy 398.082298 -412.819252) (xy 398.090053 -412.76531) (xy 398.105406 -412.713022)
			(xy 398.128043 -412.663449) (xy 398.157504 -412.617603) (xy 398.193189 -412.576416) (xy 398.234373 -412.540727)
			(xy 398.280216 -412.511261) (xy 398.329786 -412.488619) (xy 398.382073 -412.473261) (xy 398.436014 -412.465501)
			(xy 398.463262 -412.465012) (xy 399.326862 -412.465012) (xy 399.354118 -412.465432) (xy 399.408076 -412.473185)
			(xy 399.460381 -412.488539) (xy 399.509969 -412.51118) (xy 399.555829 -412.540649) (xy 399.597029 -412.576345)
			(xy 399.632728 -412.61754) (xy 399.662201 -412.663398) (xy 399.684848 -412.712983) (xy 399.700207 -412.765287)
			(xy 399.707965 -412.819244) (xy 399.707965 -412.873752) (xy 401.145475 -412.873752) (xy 401.145475 -412.819248)
			(xy 401.153232 -412.7653) (xy 401.168587 -412.713005) (xy 401.191229 -412.663427) (xy 401.220695 -412.617576)
			(xy 401.256387 -412.576386) (xy 401.297578 -412.540694) (xy 401.343429 -412.511228) (xy 401.393007 -412.488587)
			(xy 401.445302 -412.473231) (xy 401.49925 -412.465475) (xy 401.526502 -412.465012) (xy 402.390102 -412.465012)
			(xy 402.417355 -412.465458) (xy 402.471305 -412.473215) (xy 402.523602 -412.488571) (xy 402.573182 -412.511214)
			(xy 402.619034 -412.540682) (xy 402.660226 -412.576375) (xy 402.69592 -412.617567) (xy 402.725387 -412.66342)
			(xy 402.748029 -412.713) (xy 402.763385 -412.765297) (xy 402.771142 -412.819247) (xy 402.771142 -412.873753)
			(xy 404.208675 -412.873753) (xy 404.208675 -412.819247) (xy 404.216433 -412.765295) (xy 404.23179 -412.712996)
			(xy 404.254435 -412.663416) (xy 404.283905 -412.617563) (xy 404.319601 -412.576372) (xy 404.360797 -412.54068)
			(xy 404.406653 -412.511215) (xy 404.456236 -412.488576) (xy 404.508536 -412.473224) (xy 404.562489 -412.465472)
			(xy 404.589742 -412.465012) (xy 405.453342 -412.465012) (xy 405.480593 -412.465461) (xy 405.534539 -412.473222)
			(xy 405.586831 -412.488582) (xy 405.636406 -412.511227) (xy 405.682253 -412.540696) (xy 405.723441 -412.576389)
			(xy 405.759129 -412.61758) (xy 405.788593 -412.663431) (xy 405.811233 -412.713008) (xy 405.826586 -412.765302)
			(xy 405.834342 -412.819249) (xy 405.834342 -412.873749) (xy 407.271998 -412.873749) (xy 407.271998 -412.819251)
			(xy 407.279754 -412.765308) (xy 407.295107 -412.713017) (xy 407.317746 -412.663444) (xy 407.347209 -412.617597)
			(xy 407.382897 -412.576409) (xy 407.424082 -412.54072) (xy 407.469928 -412.511254) (xy 407.5195 -412.488613)
			(xy 407.57179 -412.473258) (xy 407.625733 -412.465499) (xy 407.652982 -412.465012) (xy 408.516582 -412.465012)
			(xy 408.543837 -412.465434) (xy 408.597793 -412.473189) (xy 408.650096 -412.488544) (xy 408.699681 -412.511187)
			(xy 408.745539 -412.540656) (xy 408.786736 -412.576352) (xy 408.822433 -412.617547) (xy 408.851904 -412.663403)
			(xy 408.874549 -412.712987) (xy 408.889907 -412.765289) (xy 408.897665 -412.819245) (xy 408.897665 -412.873752)
			(xy 410.335175 -412.873752) (xy 410.335175 -412.819248) (xy 410.342932 -412.765298) (xy 410.358289 -412.713001)
			(xy 410.380932 -412.663422) (xy 410.4104 -412.61757) (xy 410.446094 -412.576379) (xy 410.487288 -412.540687)
			(xy 410.533141 -412.511221) (xy 410.582721 -412.488581) (xy 410.635019 -412.473228) (xy 410.68897 -412.465474)
			(xy 410.716222 -412.465012) (xy 411.579822 -412.465012) (xy 411.607074 -412.465459) (xy 411.661022 -412.473219)
			(xy 411.713317 -412.488577) (xy 411.762894 -412.51122) (xy 411.808744 -412.540689) (xy 411.849934 -412.576382)
			(xy 411.885625 -412.617574) (xy 411.91509 -412.663426) (xy 411.937731 -412.713004) (xy 411.953086 -412.7653)
			(xy 411.960842 -412.819248) (xy 411.960842 -412.873748) (xy 413.398498 -412.873748) (xy 413.398498 -412.819252)
			(xy 413.406253 -412.76531) (xy 413.421606 -412.713022) (xy 413.444243 -412.663449) (xy 413.473704 -412.617603)
			(xy 413.509389 -412.576416) (xy 413.550573 -412.540727) (xy 413.596416 -412.511261) (xy 413.645986 -412.488619)
			(xy 413.698273 -412.473261) (xy 413.752214 -412.465501) (xy 413.779462 -412.465012) (xy 414.643062 -412.465012)
			(xy 414.670318 -412.465432) (xy 414.724276 -412.473185) (xy 414.776581 -412.488539) (xy 414.826169 -412.51118)
			(xy 414.872029 -412.540649) (xy 414.913229 -412.576345) (xy 414.948928 -412.61754) (xy 414.978401 -412.663398)
			(xy 415.001048 -412.712983) (xy 415.016407 -412.765287) (xy 415.024165 -412.819244) (xy 415.024165 -412.873752)
			(xy 416.461675 -412.873752) (xy 416.461675 -412.819248) (xy 416.469432 -412.7653) (xy 416.484787 -412.713005)
			(xy 416.507429 -412.663427) (xy 416.536895 -412.617576) (xy 416.572587 -412.576386) (xy 416.613778 -412.540694)
			(xy 416.659629 -412.511228) (xy 416.709207 -412.488587) (xy 416.761502 -412.473231) (xy 416.81545 -412.465475)
			(xy 416.842702 -412.465012) (xy 417.706302 -412.465012) (xy 417.733555 -412.465458) (xy 417.787505 -412.473215)
			(xy 417.839802 -412.488571) (xy 417.889382 -412.511214) (xy 417.935234 -412.540682) (xy 417.976426 -412.576375)
			(xy 418.01212 -412.617567) (xy 418.041587 -412.66342) (xy 418.064229 -412.713) (xy 418.079585 -412.765297)
			(xy 418.087342 -412.819247) (xy 418.087342 -412.873753) (xy 418.079585 -412.927703) (xy 418.064229 -412.98)
			(xy 418.041587 -413.02958) (xy 418.01212 -413.075433) (xy 417.976426 -413.116625) (xy 417.935234 -413.152318)
			(xy 417.90754 -413.170116) (xy 422.998658 -413.170116) (xy 423.00263 -412.991873) (xy 423.014538 -412.813984)
			(xy 423.034359 -412.636802) (xy 423.062053 -412.460678) (xy 423.097565 -412.285963) (xy 423.140825 -412.113004)
			(xy 423.191747 -411.942143) (xy 423.25023 -411.773721) (xy 423.316157 -411.608071) (xy 423.389398 -411.445522)
			(xy 423.469808 -411.286397) (xy 423.557226 -411.131012) (xy 423.651479 -410.979676) (xy 423.75238 -410.832688)
			(xy 423.859729 -410.690341) (xy 423.973312 -410.552918) (xy 424.092905 -410.420691) (xy 424.218269 -410.293922)
			(xy 424.349156 -410.172864) (xy 424.485305 -410.057757) (xy 424.626447 -409.948829) (xy 424.772302 -409.846297)
			(xy 424.922579 -409.750363) (xy 425.07698 -409.66122) (xy 425.235199 -409.579043) (xy 425.396922 -409.503995)
			(xy 425.561827 -409.436227) (xy 425.729588 -409.375871) (xy 425.899871 -409.323049) (xy 426.072338 -409.277865)
			(xy 426.246646 -409.240408) (xy 426.42245 -409.210754) (xy 426.5994 -409.188961) (xy 426.777146 -409.175071)
			(xy 426.955333 -409.169114) (xy 427.13361 -409.1711) (xy 427.311621 -409.181026) (xy 427.489013 -409.198872)
			(xy 427.665433 -409.224602) (xy 427.840533 -409.258166) (xy 428.013964 -409.299496) (xy 428.185381 -409.348512)
			(xy 428.354444 -409.405114) (xy 428.520819 -409.469192) (xy 428.684173 -409.540618) (xy 428.844184 -409.61925)
			(xy 429.000533 -409.704931) (xy 429.15291 -409.797493) (xy 429.301013 -409.89675) (xy 429.444547 -410.002507)
			(xy 429.583227 -410.114552) (xy 429.716778 -410.232664) (xy 429.844935 -410.356608) (xy 429.967444 -410.486138)
			(xy 430.084061 -410.620997) (xy 430.194554 -410.760917) (xy 430.298705 -410.90562) (xy 430.396307 -411.054819)
			(xy 430.487165 -411.208218) (xy 430.571099 -411.365512) (xy 430.647944 -411.526388) (xy 430.717545 -411.690529)
			(xy 430.779766 -411.857606) (xy 430.834482 -412.02729) (xy 430.881584 -412.199243) (xy 430.92098 -412.373123)
			(xy 430.952591 -412.548586) (xy 430.976355 -412.725282) (xy 430.992223 -412.902862) (xy 431.000165 -413.080972)
			(xy 431.000662 -413.170116) (xy 431.000165 -413.25926) (xy 430.992223 -413.43737) (xy 430.976355 -413.61495)
			(xy 430.952591 -413.791646) (xy 430.92098 -413.967109) (xy 430.881584 -414.140989) (xy 430.834482 -414.312942)
			(xy 430.779766 -414.482626) (xy 430.717545 -414.649703) (xy 430.647944 -414.813844) (xy 430.571099 -414.97472)
			(xy 430.487165 -415.132014) (xy 430.396307 -415.285413) (xy 430.298705 -415.434612) (xy 430.194554 -415.579315)
			(xy 430.084061 -415.719235) (xy 429.967444 -415.854094) (xy 429.844935 -415.983624) (xy 429.716778 -416.107568)
			(xy 429.583227 -416.22568) (xy 429.444547 -416.337725) (xy 429.301013 -416.443482) (xy 429.15291 -416.542739)
			(xy 429.000533 -416.635301) (xy 428.844184 -416.720982) (xy 428.684173 -416.799614) (xy 428.520819 -416.87104)
			(xy 428.354444 -416.935118) (xy 428.185381 -416.99172) (xy 428.013964 -417.040736) (xy 427.840533 -417.082066)
			(xy 427.665433 -417.11563) (xy 427.489013 -417.14136) (xy 427.311621 -417.159206) (xy 427.13361 -417.169132)
			(xy 426.955333 -417.171118) (xy 426.777146 -417.165161) (xy 426.5994 -417.151271) (xy 426.42245 -417.129478)
			(xy 426.246646 -417.099824) (xy 426.072338 -417.062367) (xy 425.899871 -417.017183) (xy 425.729588 -416.964361)
			(xy 425.561827 -416.904005) (xy 425.396922 -416.836237) (xy 425.235199 -416.761189) (xy 425.07698 -416.679012)
			(xy 424.922579 -416.589869) (xy 424.772302 -416.493935) (xy 424.626447 -416.391403) (xy 424.485305 -416.282475)
			(xy 424.349156 -416.167368) (xy 424.218269 -416.04631) (xy 424.092905 -415.919541) (xy 423.973312 -415.787314)
			(xy 423.859729 -415.649891) (xy 423.75238 -415.507544) (xy 423.651479 -415.360556) (xy 423.557226 -415.20922)
			(xy 423.469808 -415.053835) (xy 423.389398 -414.89471) (xy 423.316157 -414.732161) (xy 423.25023 -414.566511)
			(xy 423.191747 -414.398089) (xy 423.140825 -414.227228) (xy 423.097565 -414.054269) (xy 423.062053 -413.879554)
			(xy 423.034359 -413.70343) (xy 423.014538 -413.526248) (xy 423.00263 -413.348359) (xy 422.998658 -413.170116)
			(xy 417.90754 -413.170116) (xy 417.889382 -413.181786) (xy 417.839802 -413.204429) (xy 417.787505 -413.219785)
			(xy 417.733555 -413.227542) (xy 417.706302 -413.228028) (xy 416.842702 -413.228028) (xy 416.81545 -413.227525)
			(xy 416.761502 -413.219769) (xy 416.709207 -413.204413) (xy 416.659629 -413.181772) (xy 416.613778 -413.152306)
			(xy 416.572587 -413.116614) (xy 416.536895 -413.075424) (xy 416.507429 -413.029573) (xy 416.484787 -412.979995)
			(xy 416.469432 -412.9277) (xy 416.461675 -412.873752) (xy 415.024165 -412.873752) (xy 415.024165 -412.873756)
			(xy 415.016407 -412.927713) (xy 415.001048 -412.980017) (xy 414.978401 -413.029602) (xy 414.948928 -413.07546)
			(xy 414.913229 -413.116655) (xy 414.872029 -413.152351) (xy 414.826169 -413.18182) (xy 414.776581 -413.204461)
			(xy 414.724276 -413.219815) (xy 414.670318 -413.227568) (xy 414.643062 -413.228028) (xy 413.779462 -413.228028)
			(xy 413.752214 -413.227499) (xy 413.698273 -413.219739) (xy 413.645986 -413.204381) (xy 413.596416 -413.181739)
			(xy 413.550573 -413.152273) (xy 413.509389 -413.116584) (xy 413.473704 -413.075397) (xy 413.444243 -413.029551)
			(xy 413.421606 -412.979978) (xy 413.406253 -412.92769) (xy 413.398498 -412.873748) (xy 411.960842 -412.873748)
			(xy 411.960842 -412.873752) (xy 411.953086 -412.9277) (xy 411.937731 -412.979996) (xy 411.91509 -413.029574)
			(xy 411.885625 -413.075426) (xy 411.849934 -413.116618) (xy 411.808744 -413.152311) (xy 411.762894 -413.18178)
			(xy 411.713317 -413.204423) (xy 411.661022 -413.219781) (xy 411.607074 -413.227541) (xy 411.579822 -413.228028)
			(xy 410.716222 -413.228028) (xy 410.68897 -413.227526) (xy 410.635019 -413.219772) (xy 410.582721 -413.204419)
			(xy 410.533141 -413.181779) (xy 410.487288 -413.152313) (xy 410.446094 -413.116621) (xy 410.4104 -413.07543)
			(xy 410.380932 -413.029578) (xy 410.358289 -412.979999) (xy 410.342932 -412.927702) (xy 410.335175 -412.873752)
			(xy 408.897665 -412.873752) (xy 408.897665 -412.873755) (xy 408.889907 -412.927711) (xy 408.874549 -412.980013)
			(xy 408.851904 -413.029597) (xy 408.822433 -413.075453) (xy 408.786736 -413.116648) (xy 408.745539 -413.152344)
			(xy 408.699681 -413.181813) (xy 408.650096 -413.204456) (xy 408.597793 -413.219811) (xy 408.543837 -413.227566)
			(xy 408.516582 -413.228028) (xy 407.652982 -413.228028) (xy 407.625733 -413.227501) (xy 407.57179 -413.219742)
			(xy 407.5195 -413.204387) (xy 407.469928 -413.181746) (xy 407.424082 -413.15228) (xy 407.382897 -413.116591)
			(xy 407.347209 -413.075403) (xy 407.317746 -413.029556) (xy 407.295107 -412.979983) (xy 407.279754 -412.927692)
			(xy 407.271998 -412.873749) (xy 405.834342 -412.873749) (xy 405.834342 -412.873751) (xy 405.826586 -412.927698)
			(xy 405.811233 -412.979992) (xy 405.788593 -413.029569) (xy 405.759129 -413.07542) (xy 405.723441 -413.116611)
			(xy 405.682253 -413.152304) (xy 405.636406 -413.181773) (xy 405.586831 -413.204418) (xy 405.534539 -413.219778)
			(xy 405.480593 -413.227539) (xy 405.453342 -413.228028) (xy 404.589742 -413.228028) (xy 404.562489 -413.227528)
			(xy 404.508536 -413.219776) (xy 404.456236 -413.204424) (xy 404.406653 -413.181785) (xy 404.360797 -413.15232)
			(xy 404.319601 -413.116628) (xy 404.283905 -413.075437) (xy 404.254435 -413.029584) (xy 404.23179 -412.980004)
			(xy 404.216433 -412.927705) (xy 404.208675 -412.873753) (xy 402.771142 -412.873753) (xy 402.763385 -412.927703)
			(xy 402.748029 -412.98) (xy 402.725387 -413.02958) (xy 402.69592 -413.075433) (xy 402.660226 -413.116625)
			(xy 402.619034 -413.152318) (xy 402.573182 -413.181786) (xy 402.523602 -413.204429) (xy 402.471305 -413.219785)
			(xy 402.417355 -413.227542) (xy 402.390102 -413.228028) (xy 401.526502 -413.228028) (xy 401.49925 -413.227525)
			(xy 401.445302 -413.219769) (xy 401.393007 -413.204413) (xy 401.343429 -413.181772) (xy 401.297578 -413.152306)
			(xy 401.256387 -413.116614) (xy 401.220695 -413.075424) (xy 401.191229 -413.029573) (xy 401.168587 -412.979995)
			(xy 401.153232 -412.9277) (xy 401.145475 -412.873752) (xy 399.707965 -412.873752) (xy 399.707965 -412.873756)
			(xy 399.700207 -412.927713) (xy 399.684848 -412.980017) (xy 399.662201 -413.029602) (xy 399.632728 -413.07546)
			(xy 399.597029 -413.116655) (xy 399.555829 -413.152351) (xy 399.509969 -413.18182) (xy 399.460381 -413.204461)
			(xy 399.408076 -413.219815) (xy 399.354118 -413.227568) (xy 399.326862 -413.228028) (xy 398.463262 -413.228028)
			(xy 398.436014 -413.227499) (xy 398.382073 -413.219739) (xy 398.329786 -413.204381) (xy 398.280216 -413.181739)
			(xy 398.234373 -413.152273) (xy 398.193189 -413.116584) (xy 398.157504 -413.075397) (xy 398.128043 -413.029551)
			(xy 398.105406 -412.979978) (xy 398.090053 -412.92769) (xy 398.082298 -412.873748) (xy 396.644642 -412.873748)
			(xy 396.644642 -412.873752) (xy 396.636886 -412.9277) (xy 396.621531 -412.979996) (xy 396.59889 -413.029574)
			(xy 396.569425 -413.075426) (xy 396.533734 -413.116618) (xy 396.492544 -413.152311) (xy 396.446694 -413.18178)
			(xy 396.397117 -413.204423) (xy 396.344822 -413.219781) (xy 396.290874 -413.227541) (xy 396.263622 -413.228028)
			(xy 395.400022 -413.228028) (xy 395.37277 -413.227526) (xy 395.318819 -413.219772) (xy 395.266521 -413.204419)
			(xy 395.216941 -413.181779) (xy 395.171088 -413.152313) (xy 395.129894 -413.116621) (xy 395.0942 -413.07543)
			(xy 395.064732 -413.029578) (xy 395.042089 -412.979999) (xy 395.026732 -412.927702) (xy 395.018975 -412.873752)
			(xy 393.581465 -412.873752) (xy 393.581465 -412.873755) (xy 393.573707 -412.927711) (xy 393.558349 -412.980013)
			(xy 393.535704 -413.029597) (xy 393.506233 -413.075453) (xy 393.470536 -413.116648) (xy 393.429339 -413.152344)
			(xy 393.383481 -413.181813) (xy 393.333896 -413.204456) (xy 393.281593 -413.219811) (xy 393.227637 -413.227566)
			(xy 393.200382 -413.228028) (xy 392.336782 -413.228028) (xy 392.309533 -413.227501) (xy 392.25559 -413.219742)
			(xy 392.2033 -413.204387) (xy 392.153728 -413.181746) (xy 392.107882 -413.15228) (xy 392.066697 -413.116591)
			(xy 392.031009 -413.075403) (xy 392.001546 -413.029556) (xy 391.978907 -412.979983) (xy 391.963554 -412.927692)
			(xy 391.955798 -412.873749) (xy 390.518142 -412.873749) (xy 390.518142 -412.873751) (xy 390.510386 -412.927698)
			(xy 390.495033 -412.979992) (xy 390.472393 -413.029569) (xy 390.442929 -413.07542) (xy 390.407241 -413.116611)
			(xy 390.366053 -413.152304) (xy 390.320206 -413.181773) (xy 390.270631 -413.204418) (xy 390.218339 -413.219778)
			(xy 390.164393 -413.227539) (xy 390.137142 -413.228028) (xy 389.273542 -413.228028) (xy 389.246289 -413.227528)
			(xy 389.192336 -413.219776) (xy 389.140036 -413.204424) (xy 389.090453 -413.181785) (xy 389.044597 -413.15232)
			(xy 389.003401 -413.116628) (xy 388.967705 -413.075437) (xy 388.938235 -413.029584) (xy 388.91559 -412.980004)
			(xy 388.900233 -412.927705) (xy 388.892475 -412.873753) (xy 387.454942 -412.873753) (xy 387.447185 -412.927703)
			(xy 387.431829 -412.98) (xy 387.409187 -413.02958) (xy 387.37972 -413.075433) (xy 387.344026 -413.116625)
			(xy 387.302834 -413.152318) (xy 387.256982 -413.181786) (xy 387.207402 -413.204429) (xy 387.155105 -413.219785)
			(xy 387.101155 -413.227542) (xy 387.073902 -413.228028) (xy 386.210302 -413.228028) (xy 386.18305 -413.227525)
			(xy 386.129102 -413.219769) (xy 386.076807 -413.204413) (xy 386.027229 -413.181772) (xy 385.981378 -413.152306)
			(xy 385.940187 -413.116614) (xy 385.904495 -413.075424) (xy 385.875029 -413.029573) (xy 385.852387 -412.979995)
			(xy 385.837032 -412.9277) (xy 385.829275 -412.873752) (xy 384.391765 -412.873752) (xy 384.391765 -412.873756)
			(xy 384.384007 -412.927713) (xy 384.368648 -412.980017) (xy 384.346001 -413.029602) (xy 384.316528 -413.07546)
			(xy 384.280829 -413.116655) (xy 384.239629 -413.152351) (xy 384.193769 -413.18182) (xy 384.144181 -413.204461)
			(xy 384.091876 -413.219815) (xy 384.037918 -413.227568) (xy 384.010662 -413.228028) (xy 383.147062 -413.228028)
			(xy 383.119814 -413.227499) (xy 383.065873 -413.219739) (xy 383.013586 -413.204381) (xy 382.964016 -413.181739)
			(xy 382.918173 -413.152273) (xy 382.876989 -413.116584) (xy 382.841304 -413.075397) (xy 382.811843 -413.029551)
			(xy 382.789206 -412.979978) (xy 382.773853 -412.92769) (xy 382.766098 -412.873748) (xy 381.328442 -412.873748)
			(xy 381.328442 -412.873752) (xy 381.320686 -412.9277) (xy 381.305331 -412.979996) (xy 381.28269 -413.029574)
			(xy 381.253225 -413.075426) (xy 381.217534 -413.116618) (xy 381.176344 -413.152311) (xy 381.130494 -413.18178)
			(xy 381.080917 -413.204423) (xy 381.028622 -413.219781) (xy 380.974674 -413.227541) (xy 380.947422 -413.228028)
			(xy 380.083822 -413.228028) (xy 380.05657 -413.227526) (xy 380.002619 -413.219772) (xy 379.950321 -413.204419)
			(xy 379.900741 -413.181779) (xy 379.854888 -413.152313) (xy 379.813694 -413.116621) (xy 379.778 -413.07543)
			(xy 379.748532 -413.029578) (xy 379.725889 -412.979999) (xy 379.710532 -412.927702) (xy 379.702775 -412.873752)
			(xy 378.265265 -412.873752) (xy 378.265265 -412.873755) (xy 378.257507 -412.927711) (xy 378.242149 -412.980013)
			(xy 378.219504 -413.029597) (xy 378.190033 -413.075453) (xy 378.154336 -413.116648) (xy 378.113139 -413.152344)
			(xy 378.067281 -413.181813) (xy 378.017696 -413.204456) (xy 377.965393 -413.219811) (xy 377.911437 -413.227566)
			(xy 377.884182 -413.228028) (xy 377.020582 -413.228028) (xy 376.993333 -413.227501) (xy 376.93939 -413.219742)
			(xy 376.8871 -413.204387) (xy 376.837528 -413.181746) (xy 376.791682 -413.15228) (xy 376.750497 -413.116591)
			(xy 376.714809 -413.075403) (xy 376.685346 -413.029556) (xy 376.662707 -412.979983) (xy 376.647354 -412.927692)
			(xy 376.639598 -412.873749) (xy 375.201942 -412.873749) (xy 375.201942 -412.873751) (xy 375.194186 -412.927698)
			(xy 375.178833 -412.979992) (xy 375.156193 -413.029569) (xy 375.126729 -413.07542) (xy 375.091041 -413.116611)
			(xy 375.049853 -413.152304) (xy 375.004006 -413.181773) (xy 374.954431 -413.204418) (xy 374.902139 -413.219778)
			(xy 374.848193 -413.227539) (xy 374.820942 -413.228028) (xy 373.957342 -413.228028) (xy 373.930089 -413.227528)
			(xy 373.876136 -413.219776) (xy 373.823836 -413.204424) (xy 373.774253 -413.181785) (xy 373.728397 -413.15232)
			(xy 373.687201 -413.116628) (xy 373.651505 -413.075437) (xy 373.622035 -413.029584) (xy 373.59939 -412.980004)
			(xy 373.584033 -412.927705) (xy 373.576275 -412.873753) (xy 372.138742 -412.873753) (xy 372.130985 -412.927703)
			(xy 372.115629 -412.98) (xy 372.092987 -413.02958) (xy 372.06352 -413.075433) (xy 372.027826 -413.116625)
			(xy 371.986634 -413.152318) (xy 371.940782 -413.181786) (xy 371.891202 -413.204429) (xy 371.838905 -413.219785)
			(xy 371.784955 -413.227542) (xy 371.757702 -413.228028) (xy 370.894102 -413.228028) (xy 370.86685 -413.227525)
			(xy 370.812902 -413.219769) (xy 370.760607 -413.204413) (xy 370.711029 -413.181772) (xy 370.665178 -413.152306)
			(xy 370.623987 -413.116614) (xy 370.588295 -413.075424) (xy 370.558829 -413.029573) (xy 370.536187 -412.979995)
			(xy 370.520832 -412.9277) (xy 370.513075 -412.873752) (xy 350.987142 -412.873752) (xy 350.979385 -412.927702)
			(xy 350.96403 -412.979999) (xy 350.941388 -413.029579) (xy 350.911921 -413.075431) (xy 350.876228 -413.116624)
			(xy 350.835036 -413.152317) (xy 350.789184 -413.181785) (xy 350.739605 -413.204428) (xy 350.687308 -413.219784)
			(xy 350.633358 -413.227542) (xy 350.606106 -413.228028) (xy 349.742506 -413.228028) (xy 349.715254 -413.227525)
			(xy 349.661306 -413.219769) (xy 349.60901 -413.204415) (xy 349.559431 -413.181774) (xy 349.51358 -413.152307)
			(xy 349.472389 -413.116616) (xy 349.436696 -413.075425) (xy 349.407229 -413.029574) (xy 349.384588 -412.979996)
			(xy 349.369232 -412.9277) (xy 349.361475 -412.873752) (xy 347.923965 -412.873752) (xy 347.923965 -412.873756)
			(xy 347.916207 -412.927713) (xy 347.900848 -412.980016) (xy 347.878202 -413.029601) (xy 347.848729 -413.075458)
			(xy 347.81303 -413.116654) (xy 347.771831 -413.15235) (xy 347.725971 -413.181818) (xy 347.676384 -413.20446)
			(xy 347.624079 -413.219814) (xy 347.570122 -413.227567) (xy 347.542866 -413.228028) (xy 346.679266 -413.228028)
			(xy 346.652018 -413.227499) (xy 346.598077 -413.219739) (xy 346.545789 -413.204382) (xy 346.496218 -413.18174)
			(xy 346.450375 -413.152275) (xy 346.409191 -413.116585) (xy 346.373505 -413.075398) (xy 346.344043 -413.029552)
			(xy 346.321406 -412.979979) (xy 346.306053 -412.92769) (xy 346.298298 -412.873748) (xy 344.860642 -412.873748)
			(xy 344.860642 -412.873751) (xy 344.852886 -412.9277) (xy 344.837531 -412.979995) (xy 344.814891 -413.029573)
			(xy 344.785426 -413.075425) (xy 344.749735 -413.116617) (xy 344.708546 -413.15231) (xy 344.662696 -413.181778)
			(xy 344.61312 -413.204422) (xy 344.560825 -413.21978) (xy 344.506877 -413.22754) (xy 344.479626 -413.228028)
			(xy 343.616026 -413.228028) (xy 343.588773 -413.227526) (xy 343.534822 -413.219773) (xy 343.482524 -413.20442)
			(xy 343.432943 -413.18178) (xy 343.387089 -413.152314) (xy 343.345896 -413.116623) (xy 343.310201 -413.075431)
			(xy 343.280732 -413.029579) (xy 343.258089 -412.98) (xy 343.242733 -412.927703) (xy 343.234975 -412.873753)
			(xy 341.797465 -412.873753) (xy 341.797465 -412.873755) (xy 341.789707 -412.92771) (xy 341.77435 -412.980012)
			(xy 341.751705 -413.029595) (xy 341.722234 -413.075452) (xy 341.686537 -413.116647) (xy 341.645341 -413.152343)
			(xy 341.599483 -413.181812) (xy 341.549899 -413.204455) (xy 341.497596 -413.21981) (xy 341.443641 -413.227566)
			(xy 341.416386 -413.228028) (xy 340.552786 -413.228028) (xy 340.525537 -413.227501) (xy 340.471594 -413.219743)
			(xy 340.419303 -413.204388) (xy 340.36973 -413.181747) (xy 340.323884 -413.152282) (xy 340.282698 -413.116592)
			(xy 340.24701 -413.075404) (xy 340.217546 -413.029557) (xy 340.194908 -412.979984) (xy 340.179554 -412.927693)
			(xy 340.171798 -412.873749) (xy 338.734142 -412.873749) (xy 338.734142 -412.873751) (xy 338.726387 -412.927697)
			(xy 338.711033 -412.979991) (xy 338.688394 -413.029568) (xy 338.65893 -413.075418) (xy 338.623242 -413.116609)
			(xy 338.582055 -413.152303) (xy 338.536208 -413.181772) (xy 338.486634 -413.204417) (xy 338.434342 -413.219777)
			(xy 338.380397 -413.227539) (xy 338.353146 -413.228028) (xy 337.489546 -413.228028) (xy 337.462292 -413.227528)
			(xy 337.408339 -413.219777) (xy 337.356039 -413.204425) (xy 337.306455 -413.181787) (xy 337.260599 -413.152321)
			(xy 337.219403 -413.11663) (xy 337.183706 -413.075438) (xy 337.154235 -413.029585) (xy 337.131591 -412.980004)
			(xy 337.116233 -412.927706) (xy 337.108475 -412.873754) (xy 335.670942 -412.873754) (xy 335.663185 -412.927702)
			(xy 335.64783 -412.979999) (xy 335.625188 -413.029579) (xy 335.595721 -413.075431) (xy 335.560028 -413.116624)
			(xy 335.518836 -413.152317) (xy 335.472984 -413.181785) (xy 335.423405 -413.204428) (xy 335.371108 -413.219784)
			(xy 335.317158 -413.227542) (xy 335.289906 -413.228028) (xy 334.426306 -413.228028) (xy 334.399054 -413.227525)
			(xy 334.345106 -413.219769) (xy 334.29281 -413.204415) (xy 334.243231 -413.181774) (xy 334.19738 -413.152307)
			(xy 334.156189 -413.116616) (xy 334.120496 -413.075425) (xy 334.091029 -413.029574) (xy 334.068388 -412.979996)
			(xy 334.053032 -412.9277) (xy 334.045275 -412.873752) (xy 332.607765 -412.873752) (xy 332.607765 -412.873756)
			(xy 332.600007 -412.927713) (xy 332.584648 -412.980016) (xy 332.562002 -413.029601) (xy 332.532529 -413.075458)
			(xy 332.49683 -413.116654) (xy 332.455631 -413.15235) (xy 332.409771 -413.181818) (xy 332.360184 -413.20446)
			(xy 332.307879 -413.219814) (xy 332.253922 -413.227567) (xy 332.226666 -413.228028) (xy 331.363066 -413.228028)
			(xy 331.335818 -413.227499) (xy 331.281877 -413.219739) (xy 331.229589 -413.204382) (xy 331.180018 -413.18174)
			(xy 331.134175 -413.152275) (xy 331.092991 -413.116585) (xy 331.057305 -413.075398) (xy 331.027843 -413.029552)
			(xy 331.005206 -412.979979) (xy 330.989853 -412.92769) (xy 330.982098 -412.873748) (xy 329.544442 -412.873748)
			(xy 329.544442 -412.873751) (xy 329.536686 -412.9277) (xy 329.521331 -412.979995) (xy 329.498691 -413.029573)
			(xy 329.469226 -413.075425) (xy 329.433535 -413.116617) (xy 329.392346 -413.15231) (xy 329.346496 -413.181778)
			(xy 329.29692 -413.204422) (xy 329.244625 -413.21978) (xy 329.190677 -413.22754) (xy 329.163426 -413.228028)
			(xy 328.299826 -413.228028) (xy 328.272573 -413.227526) (xy 328.218622 -413.219773) (xy 328.166324 -413.20442)
			(xy 328.116743 -413.18178) (xy 328.070889 -413.152314) (xy 328.029696 -413.116623) (xy 327.994001 -413.075431)
			(xy 327.964532 -413.029579) (xy 327.941889 -412.98) (xy 327.926533 -412.927703) (xy 327.918775 -412.873753)
			(xy 326.481265 -412.873753) (xy 326.481265 -412.873755) (xy 326.473507 -412.92771) (xy 326.45815 -412.980012)
			(xy 326.435505 -413.029595) (xy 326.406034 -413.075452) (xy 326.370337 -413.116647) (xy 326.329141 -413.152343)
			(xy 326.283283 -413.181812) (xy 326.233699 -413.204455) (xy 326.181396 -413.21981) (xy 326.127441 -413.227566)
			(xy 326.100186 -413.228028) (xy 325.236586 -413.228028) (xy 325.209337 -413.227501) (xy 325.155394 -413.219743)
			(xy 325.103103 -413.204388) (xy 325.05353 -413.181747) (xy 325.007684 -413.152282) (xy 324.966498 -413.116592)
			(xy 324.93081 -413.075404) (xy 324.901346 -413.029557) (xy 324.878708 -412.979984) (xy 324.863354 -412.927693)
			(xy 324.855598 -412.873749) (xy 323.417942 -412.873749) (xy 323.417942 -412.873751) (xy 323.410187 -412.927697)
			(xy 323.394833 -412.979991) (xy 323.372194 -413.029568) (xy 323.34273 -413.075418) (xy 323.307042 -413.116609)
			(xy 323.265855 -413.152303) (xy 323.220008 -413.181772) (xy 323.170434 -413.204417) (xy 323.118142 -413.219777)
			(xy 323.064197 -413.227539) (xy 323.036946 -413.228028) (xy 322.173346 -413.228028) (xy 322.146092 -413.227528)
			(xy 322.092139 -413.219777) (xy 322.039839 -413.204425) (xy 321.990255 -413.181787) (xy 321.944399 -413.152321)
			(xy 321.903203 -413.11663) (xy 321.867506 -413.075438) (xy 321.838035 -413.029585) (xy 321.815391 -412.980004)
			(xy 321.800033 -412.927706) (xy 321.792275 -412.873754) (xy 320.354742 -412.873754) (xy 320.346985 -412.927702)
			(xy 320.33163 -412.979999) (xy 320.308988 -413.029579) (xy 320.279521 -413.075431) (xy 320.243828 -413.116624)
			(xy 320.202636 -413.152317) (xy 320.156784 -413.181785) (xy 320.107205 -413.204428) (xy 320.054908 -413.219784)
			(xy 320.000958 -413.227542) (xy 319.973706 -413.228028) (xy 319.110106 -413.228028) (xy 319.082854 -413.227525)
			(xy 319.028906 -413.219769) (xy 318.97661 -413.204415) (xy 318.927031 -413.181774) (xy 318.88118 -413.152307)
			(xy 318.839989 -413.116616) (xy 318.804296 -413.075425) (xy 318.774829 -413.029574) (xy 318.752188 -412.979996)
			(xy 318.736832 -412.9277) (xy 318.729075 -412.873752) (xy 317.291565 -412.873752) (xy 317.291565 -412.873756)
			(xy 317.283807 -412.927713) (xy 317.268448 -412.980016) (xy 317.245802 -413.029601) (xy 317.216329 -413.075458)
			(xy 317.18063 -413.116654) (xy 317.139431 -413.15235) (xy 317.093571 -413.181818) (xy 317.043984 -413.20446)
			(xy 316.991679 -413.219814) (xy 316.937722 -413.227567) (xy 316.910466 -413.228028) (xy 316.046866 -413.228028)
			(xy 316.019618 -413.227499) (xy 315.965677 -413.219739) (xy 315.913389 -413.204382) (xy 315.863818 -413.18174)
			(xy 315.817975 -413.152275) (xy 315.776791 -413.116585) (xy 315.741105 -413.075398) (xy 315.711643 -413.029552)
			(xy 315.689006 -412.979979) (xy 315.673653 -412.92769) (xy 315.665898 -412.873748) (xy 314.228242 -412.873748)
			(xy 314.228242 -412.873751) (xy 314.220486 -412.9277) (xy 314.205131 -412.979995) (xy 314.182491 -413.029573)
			(xy 314.153026 -413.075425) (xy 314.117335 -413.116617) (xy 314.076146 -413.15231) (xy 314.030296 -413.181778)
			(xy 313.98072 -413.204422) (xy 313.928425 -413.21978) (xy 313.874477 -413.22754) (xy 313.847226 -413.228028)
			(xy 312.983626 -413.228028) (xy 312.956373 -413.227526) (xy 312.902422 -413.219773) (xy 312.850124 -413.20442)
			(xy 312.800543 -413.18178) (xy 312.754689 -413.152314) (xy 312.713496 -413.116623) (xy 312.677801 -413.075431)
			(xy 312.648332 -413.029579) (xy 312.625689 -412.98) (xy 312.610333 -412.927703) (xy 312.602575 -412.873753)
			(xy 311.165065 -412.873753) (xy 311.165065 -412.873755) (xy 311.157307 -412.92771) (xy 311.14195 -412.980012)
			(xy 311.119305 -413.029595) (xy 311.089834 -413.075452) (xy 311.054137 -413.116647) (xy 311.012941 -413.152343)
			(xy 310.967083 -413.181812) (xy 310.917499 -413.204455) (xy 310.865196 -413.21981) (xy 310.811241 -413.227566)
			(xy 310.783986 -413.228028) (xy 309.920386 -413.228028) (xy 309.893137 -413.227501) (xy 309.839194 -413.219743)
			(xy 309.786903 -413.204388) (xy 309.73733 -413.181747) (xy 309.691484 -413.152282) (xy 309.650298 -413.116592)
			(xy 309.61461 -413.075404) (xy 309.585146 -413.029557) (xy 309.562508 -412.979984) (xy 309.547154 -412.927693)
			(xy 309.539398 -412.873749) (xy 308.101742 -412.873749) (xy 308.101742 -412.873751) (xy 308.093987 -412.927697)
			(xy 308.078633 -412.979991) (xy 308.055994 -413.029568) (xy 308.02653 -413.075418) (xy 307.990842 -413.116609)
			(xy 307.949655 -413.152303) (xy 307.903808 -413.181772) (xy 307.854234 -413.204417) (xy 307.801942 -413.219777)
			(xy 307.747997 -413.227539) (xy 307.720746 -413.228028) (xy 306.857146 -413.228028) (xy 306.829892 -413.227528)
			(xy 306.775939 -413.219777) (xy 306.723639 -413.204425) (xy 306.674055 -413.181787) (xy 306.628199 -413.152321)
			(xy 306.587003 -413.11663) (xy 306.551306 -413.075438) (xy 306.521835 -413.029585) (xy 306.499191 -412.980004)
			(xy 306.483833 -412.927706) (xy 306.476075 -412.873754) (xy 305.038542 -412.873754) (xy 305.030785 -412.927702)
			(xy 305.01543 -412.979999) (xy 304.992788 -413.029579) (xy 304.963321 -413.075431) (xy 304.927628 -413.116624)
			(xy 304.886436 -413.152317) (xy 304.840584 -413.181785) (xy 304.791005 -413.204428) (xy 304.738708 -413.219784)
			(xy 304.684758 -413.227542) (xy 304.657506 -413.228028) (xy 303.793906 -413.228028) (xy 303.766654 -413.227525)
			(xy 303.712706 -413.219769) (xy 303.66041 -413.204415) (xy 303.610831 -413.181774) (xy 303.56498 -413.152307)
			(xy 303.523789 -413.116616) (xy 303.488096 -413.075425) (xy 303.458629 -413.029574) (xy 303.435988 -412.979996)
			(xy 303.420632 -412.9277) (xy 303.412875 -412.873752) (xy 301.559858 -412.873752) (xy 301.562459 -412.902862)
			(xy 301.570401 -413.080972) (xy 301.570898 -413.170116) (xy 301.570401 -413.25926) (xy 301.562459 -413.43737)
			(xy 301.546591 -413.61495) (xy 301.522827 -413.791646) (xy 301.491216 -413.967109) (xy 301.45182 -414.140989)
			(xy 301.404718 -414.312942) (xy 301.350002 -414.482626) (xy 301.287781 -414.649703) (xy 301.21818 -414.813844)
			(xy 301.141335 -414.97472) (xy 301.057401 -415.132014) (xy 300.966543 -415.285413) (xy 300.882586 -415.413753)
			(xy 304.944475 -415.413753) (xy 304.944475 -415.359247) (xy 304.952233 -415.305297) (xy 304.967589 -415.253)
			(xy 304.990232 -415.203421) (xy 305.019701 -415.157569) (xy 305.055396 -415.116377) (xy 305.096589 -415.080686)
			(xy 305.142443 -415.05122) (xy 305.192024 -415.02858) (xy 305.244322 -415.013227) (xy 305.298273 -415.005474)
			(xy 305.325526 -415.005012) (xy 306.189126 -415.005012) (xy 306.216377 -415.00546) (xy 306.270325 -415.01322)
			(xy 306.32262 -415.028578) (xy 306.372196 -415.051222) (xy 306.418046 -415.08069) (xy 306.459235 -415.116383)
			(xy 306.494926 -415.157575) (xy 306.524391 -415.203427) (xy 306.547031 -415.253005) (xy 306.562386 -415.3053)
			(xy 306.570142 -415.359249) (xy 306.570142 -415.413748) (xy 308.007798 -415.413748) (xy 308.007798 -415.359252)
			(xy 308.015553 -415.30531) (xy 308.030906 -415.253021) (xy 308.053543 -415.203448) (xy 308.083005 -415.157602)
			(xy 308.118691 -415.116415) (xy 308.159875 -415.080725) (xy 308.205718 -415.05126) (xy 308.255289 -415.028618)
			(xy 308.307577 -415.013261) (xy 308.361518 -415.005501) (xy 308.388766 -415.005012) (xy 309.252366 -415.005012)
			(xy 309.279622 -415.005433) (xy 309.333579 -415.013186) (xy 309.385884 -415.02854) (xy 309.435471 -415.051182)
			(xy 309.481331 -415.08065) (xy 309.52253 -415.116346) (xy 309.558229 -415.157542) (xy 309.587702 -415.203399)
			(xy 309.610348 -415.252984) (xy 309.625707 -415.305287) (xy 309.633465 -415.359244) (xy 309.633465 -415.413752)
			(xy 311.070975 -415.413752) (xy 311.070975 -415.359248) (xy 311.078732 -415.3053) (xy 311.094088 -415.253004)
			(xy 311.116729 -415.203426) (xy 311.146196 -415.157575) (xy 311.181889 -415.116384) (xy 311.22308 -415.080693)
			(xy 311.268931 -415.051226) (xy 311.31851 -415.028585) (xy 311.370806 -415.013231) (xy 311.424754 -415.005475)
			(xy 311.452006 -415.005012) (xy 312.315606 -415.005012) (xy 312.342858 -415.005458) (xy 312.396808 -415.013216)
			(xy 312.449105 -415.028572) (xy 312.498684 -415.051215) (xy 312.544536 -415.080683) (xy 312.585728 -415.116376)
			(xy 312.621421 -415.157569) (xy 312.650888 -415.203421) (xy 312.67353 -415.253001) (xy 312.688885 -415.305298)
			(xy 312.696642 -415.359248) (xy 312.696642 -415.413752) (xy 312.696642 -415.413754) (xy 314.134175 -415.413754)
			(xy 314.134175 -415.359246) (xy 314.141933 -415.305294) (xy 314.157291 -415.252996) (xy 314.179935 -415.203415)
			(xy 314.209406 -415.157562) (xy 314.245103 -415.11637) (xy 314.286299 -415.080679) (xy 314.332155 -415.051213)
			(xy 314.381739 -415.028575) (xy 314.434039 -415.013223) (xy 314.487992 -415.005472) (xy 314.515246 -415.005012)
			(xy 315.378846 -415.005012) (xy 315.406097 -415.005461) (xy 315.460042 -415.013223) (xy 315.512334 -415.028583)
			(xy 315.561908 -415.051228) (xy 315.607755 -415.080697) (xy 315.648942 -415.116391) (xy 315.68463 -415.157582)
			(xy 315.714094 -415.203432) (xy 315.736733 -415.253009) (xy 315.752087 -415.305303) (xy 315.759842 -415.359249)
			(xy 315.759842 -415.413749) (xy 317.197498 -415.413749) (xy 317.197498 -415.359251) (xy 317.205254 -415.305307)
			(xy 317.220608 -415.253016) (xy 317.243246 -415.203443) (xy 317.27271 -415.157596) (xy 317.308398 -415.116408)
			(xy 317.349584 -415.080718) (xy 317.39543 -415.051253) (xy 317.445003 -415.028612) (xy 317.497294 -415.013257)
			(xy 317.551237 -415.005499) (xy 317.578486 -415.005012) (xy 318.442086 -415.005012) (xy 318.469341 -415.005434)
			(xy 318.523296 -415.01319) (xy 318.575599 -415.028545) (xy 318.625183 -415.051188) (xy 318.671041 -415.080657)
			(xy 318.712237 -415.116353) (xy 318.747934 -415.157548) (xy 318.777405 -415.203405) (xy 318.80005 -415.252988)
			(xy 318.815407 -415.30529) (xy 318.823165 -415.359245) (xy 318.823165 -415.413753) (xy 320.260675 -415.413753)
			(xy 320.260675 -415.359247) (xy 320.268433 -415.305297) (xy 320.283789 -415.253) (xy 320.306432 -415.203421)
			(xy 320.335901 -415.157569) (xy 320.371596 -415.116377) (xy 320.412789 -415.080686) (xy 320.458643 -415.05122)
			(xy 320.508224 -415.02858) (xy 320.560522 -415.013227) (xy 320.614473 -415.005474) (xy 320.641726 -415.005012)
			(xy 321.505326 -415.005012) (xy 321.532577 -415.00546) (xy 321.586525 -415.01322) (xy 321.63882 -415.028578)
			(xy 321.688396 -415.051222) (xy 321.734246 -415.08069) (xy 321.775435 -415.116383) (xy 321.811126 -415.157575)
			(xy 321.840591 -415.203427) (xy 321.863231 -415.253005) (xy 321.878586 -415.3053) (xy 321.886342 -415.359249)
			(xy 321.886342 -415.413748) (xy 323.323998 -415.413748) (xy 323.323998 -415.359252) (xy 323.331753 -415.30531)
			(xy 323.347106 -415.253021) (xy 323.369743 -415.203448) (xy 323.399205 -415.157602) (xy 323.434891 -415.116415)
			(xy 323.476075 -415.080725) (xy 323.521918 -415.05126) (xy 323.571489 -415.028618) (xy 323.623777 -415.013261)
			(xy 323.677718 -415.005501) (xy 323.704966 -415.005012) (xy 324.568566 -415.005012) (xy 324.595822 -415.005433)
			(xy 324.649779 -415.013186) (xy 324.702084 -415.02854) (xy 324.751671 -415.051182) (xy 324.797531 -415.08065)
			(xy 324.83873 -415.116346) (xy 324.874429 -415.157542) (xy 324.903902 -415.203399) (xy 324.926548 -415.252984)
			(xy 324.941907 -415.305287) (xy 324.949665 -415.359244) (xy 324.949665 -415.413752) (xy 326.387175 -415.413752)
			(xy 326.387175 -415.359248) (xy 326.394932 -415.3053) (xy 326.410288 -415.253004) (xy 326.432929 -415.203426)
			(xy 326.462396 -415.157575) (xy 326.498089 -415.116384) (xy 326.53928 -415.080693) (xy 326.585131 -415.051226)
			(xy 326.63471 -415.028585) (xy 326.687006 -415.013231) (xy 326.740954 -415.005475) (xy 326.768206 -415.005012)
			(xy 327.631806 -415.005012) (xy 327.659058 -415.005458) (xy 327.713008 -415.013216) (xy 327.765305 -415.028572)
			(xy 327.814884 -415.051215) (xy 327.860736 -415.080683) (xy 327.901928 -415.116376) (xy 327.937621 -415.157569)
			(xy 327.967088 -415.203421) (xy 327.98973 -415.253001) (xy 328.005085 -415.305298) (xy 328.012842 -415.359248)
			(xy 328.012842 -415.413752) (xy 328.012842 -415.413754) (xy 329.450375 -415.413754) (xy 329.450375 -415.359246)
			(xy 329.458133 -415.305294) (xy 329.473491 -415.252996) (xy 329.496135 -415.203415) (xy 329.525606 -415.157562)
			(xy 329.561303 -415.11637) (xy 329.602499 -415.080679) (xy 329.648355 -415.051213) (xy 329.697939 -415.028575)
			(xy 329.750239 -415.013223) (xy 329.804192 -415.005472) (xy 329.831446 -415.005012) (xy 330.695046 -415.005012)
			(xy 330.722297 -415.005461) (xy 330.776242 -415.013223) (xy 330.828534 -415.028583) (xy 330.878108 -415.051228)
			(xy 330.923955 -415.080697) (xy 330.965142 -415.116391) (xy 331.00083 -415.157582) (xy 331.030294 -415.203432)
			(xy 331.052933 -415.253009) (xy 331.068287 -415.305303) (xy 331.076042 -415.359249) (xy 331.076042 -415.413749)
			(xy 332.513698 -415.413749) (xy 332.513698 -415.359251) (xy 332.521454 -415.305307) (xy 332.536808 -415.253016)
			(xy 332.559446 -415.203443) (xy 332.58891 -415.157596) (xy 332.624598 -415.116408) (xy 332.665784 -415.080718)
			(xy 332.71163 -415.051253) (xy 332.761203 -415.028612) (xy 332.813494 -415.013257) (xy 332.867437 -415.005499)
			(xy 332.894686 -415.005012) (xy 333.758286 -415.005012) (xy 333.785541 -415.005434) (xy 333.839496 -415.01319)
			(xy 333.891799 -415.028545) (xy 333.941383 -415.051188) (xy 333.987241 -415.080657) (xy 334.028437 -415.116353)
			(xy 334.064134 -415.157548) (xy 334.093605 -415.203405) (xy 334.11625 -415.252988) (xy 334.131607 -415.30529)
			(xy 334.139365 -415.359245) (xy 334.139365 -415.413753) (xy 335.576875 -415.413753) (xy 335.576875 -415.359247)
			(xy 335.584633 -415.305297) (xy 335.599989 -415.253) (xy 335.622632 -415.203421) (xy 335.652101 -415.157569)
			(xy 335.687796 -415.116377) (xy 335.728989 -415.080686) (xy 335.774843 -415.05122) (xy 335.824424 -415.02858)
			(xy 335.876722 -415.013227) (xy 335.930673 -415.005474) (xy 335.957926 -415.005012) (xy 336.821526 -415.005012)
			(xy 336.848777 -415.00546) (xy 336.902725 -415.01322) (xy 336.95502 -415.028578) (xy 337.004596 -415.051222)
			(xy 337.050446 -415.08069) (xy 337.091635 -415.116383) (xy 337.127326 -415.157575) (xy 337.156791 -415.203427)
			(xy 337.179431 -415.253005) (xy 337.194786 -415.3053) (xy 337.202542 -415.359249) (xy 337.202542 -415.413748)
			(xy 338.640198 -415.413748) (xy 338.640198 -415.359252) (xy 338.647953 -415.30531) (xy 338.663306 -415.253021)
			(xy 338.685943 -415.203448) (xy 338.715405 -415.157602) (xy 338.751091 -415.116415) (xy 338.792275 -415.080725)
			(xy 338.838118 -415.05126) (xy 338.887689 -415.028618) (xy 338.939977 -415.013261) (xy 338.993918 -415.005501)
			(xy 339.021166 -415.005012) (xy 339.884766 -415.005012) (xy 339.912022 -415.005433) (xy 339.965979 -415.013186)
			(xy 340.018284 -415.02854) (xy 340.067871 -415.051182) (xy 340.113731 -415.08065) (xy 340.15493 -415.116346)
			(xy 340.190629 -415.157542) (xy 340.220102 -415.203399) (xy 340.242748 -415.252984) (xy 340.258107 -415.305287)
			(xy 340.265865 -415.359244) (xy 340.265865 -415.413752) (xy 341.703375 -415.413752) (xy 341.703375 -415.359248)
			(xy 341.711132 -415.3053) (xy 341.726488 -415.253004) (xy 341.749129 -415.203426) (xy 341.778596 -415.157575)
			(xy 341.814289 -415.116384) (xy 341.85548 -415.080693) (xy 341.901331 -415.051226) (xy 341.95091 -415.028585)
			(xy 342.003206 -415.013231) (xy 342.057154 -415.005475) (xy 342.084406 -415.005012) (xy 342.948006 -415.005012)
			(xy 342.975258 -415.005458) (xy 343.029208 -415.013216) (xy 343.081505 -415.028572) (xy 343.131084 -415.051215)
			(xy 343.176936 -415.080683) (xy 343.218128 -415.116376) (xy 343.253821 -415.157569) (xy 343.283288 -415.203421)
			(xy 343.30593 -415.253001) (xy 343.321285 -415.305298) (xy 343.329042 -415.359248) (xy 343.329042 -415.413752)
			(xy 343.329042 -415.413754) (xy 344.766575 -415.413754) (xy 344.766575 -415.359246) (xy 344.774333 -415.305294)
			(xy 344.789691 -415.252996) (xy 344.812335 -415.203415) (xy 344.841806 -415.157562) (xy 344.877503 -415.11637)
			(xy 344.918699 -415.080679) (xy 344.964555 -415.051213) (xy 345.014139 -415.028575) (xy 345.066439 -415.013223)
			(xy 345.120392 -415.005472) (xy 345.147646 -415.005012) (xy 346.011246 -415.005012) (xy 346.038497 -415.005461)
			(xy 346.092442 -415.013223) (xy 346.144734 -415.028583) (xy 346.194308 -415.051228) (xy 346.240155 -415.080697)
			(xy 346.281342 -415.116391) (xy 346.31703 -415.157582) (xy 346.346494 -415.203432) (xy 346.369133 -415.253009)
			(xy 346.384487 -415.305303) (xy 346.392242 -415.359249) (xy 346.392242 -415.413749) (xy 347.829898 -415.413749)
			(xy 347.829898 -415.359251) (xy 347.837654 -415.305307) (xy 347.853008 -415.253016) (xy 347.875646 -415.203443)
			(xy 347.90511 -415.157596) (xy 347.940798 -415.116408) (xy 347.981984 -415.080718) (xy 348.02783 -415.051253)
			(xy 348.077403 -415.028612) (xy 348.129694 -415.013257) (xy 348.183637 -415.005499) (xy 348.210886 -415.005012)
			(xy 349.074486 -415.005012) (xy 349.101741 -415.005434) (xy 349.155696 -415.01319) (xy 349.207999 -415.028545)
			(xy 349.257583 -415.051188) (xy 349.303441 -415.080657) (xy 349.344637 -415.116353) (xy 349.380334 -415.157548)
			(xy 349.409805 -415.203405) (xy 349.43245 -415.252988) (xy 349.447807 -415.30529) (xy 349.455565 -415.359245)
			(xy 349.455565 -415.413753) (xy 350.893075 -415.413753) (xy 350.893075 -415.359247) (xy 350.900833 -415.305297)
			(xy 350.916189 -415.253) (xy 350.938832 -415.203421) (xy 350.968301 -415.157569) (xy 351.003996 -415.116377)
			(xy 351.045189 -415.080686) (xy 351.091043 -415.05122) (xy 351.140624 -415.02858) (xy 351.192922 -415.013227)
			(xy 351.246873 -415.005474) (xy 351.274126 -415.005012) (xy 352.137726 -415.005012) (xy 352.164977 -415.00546)
			(xy 352.218925 -415.01322) (xy 352.27122 -415.028578) (xy 352.320796 -415.051222) (xy 352.366646 -415.08069)
			(xy 352.407835 -415.116383) (xy 352.443526 -415.157575) (xy 352.472991 -415.203427) (xy 352.495631 -415.253005)
			(xy 352.510986 -415.3053) (xy 352.518742 -415.359249) (xy 352.518742 -415.413751) (xy 352.518742 -415.413752)
			(xy 372.044675 -415.413752) (xy 372.044675 -415.359248) (xy 372.052432 -415.305298) (xy 372.067789 -415.253001)
			(xy 372.090432 -415.203422) (xy 372.1199 -415.15757) (xy 372.155594 -415.116379) (xy 372.196788 -415.080687)
			(xy 372.242641 -415.051221) (xy 372.292221 -415.028581) (xy 372.344519 -415.013228) (xy 372.39847 -415.005474)
			(xy 372.425722 -415.005012) (xy 373.289322 -415.005012) (xy 373.316574 -415.005459) (xy 373.370522 -415.013219)
			(xy 373.422817 -415.028577) (xy 373.472394 -415.05122) (xy 373.518244 -415.080689) (xy 373.559434 -415.116382)
			(xy 373.595125 -415.157574) (xy 373.62459 -415.203426) (xy 373.647231 -415.253004) (xy 373.662586 -415.3053)
			(xy 373.670342 -415.359248) (xy 373.670342 -415.413748) (xy 375.107998 -415.413748) (xy 375.107998 -415.359252)
			(xy 375.115753 -415.30531) (xy 375.131106 -415.253022) (xy 375.153743 -415.203449) (xy 375.183204 -415.157603)
			(xy 375.218889 -415.116416) (xy 375.260073 -415.080727) (xy 375.305916 -415.051261) (xy 375.355486 -415.028619)
			(xy 375.407773 -415.013261) (xy 375.461714 -415.005501) (xy 375.488962 -415.005012) (xy 376.352562 -415.005012)
			(xy 376.379818 -415.005432) (xy 376.433776 -415.013185) (xy 376.486081 -415.028539) (xy 376.535669 -415.05118)
			(xy 376.581529 -415.080649) (xy 376.622729 -415.116345) (xy 376.658428 -415.15754) (xy 376.687901 -415.203398)
			(xy 376.710548 -415.252983) (xy 376.725907 -415.305287) (xy 376.733665 -415.359244) (xy 376.733665 -415.413752)
			(xy 378.171175 -415.413752) (xy 378.171175 -415.359248) (xy 378.178932 -415.3053) (xy 378.194287 -415.253005)
			(xy 378.216929 -415.203427) (xy 378.246395 -415.157576) (xy 378.282087 -415.116386) (xy 378.323278 -415.080694)
			(xy 378.369129 -415.051228) (xy 378.418707 -415.028587) (xy 378.471002 -415.013231) (xy 378.52495 -415.005475)
			(xy 378.552202 -415.005012) (xy 379.415802 -415.005012) (xy 379.443055 -415.005458) (xy 379.497005 -415.013215)
			(xy 379.549302 -415.028571) (xy 379.598882 -415.051214) (xy 379.644734 -415.080682) (xy 379.685926 -415.116375)
			(xy 379.72162 -415.157567) (xy 379.751087 -415.20342) (xy 379.773729 -415.253) (xy 379.789085 -415.305297)
			(xy 379.796842 -415.359247) (xy 379.796842 -415.413753) (xy 381.234375 -415.413753) (xy 381.234375 -415.359247)
			(xy 381.242133 -415.305295) (xy 381.25749 -415.252996) (xy 381.280135 -415.203416) (xy 381.309605 -415.157563)
			(xy 381.345301 -415.116372) (xy 381.386497 -415.08068) (xy 381.432353 -415.051215) (xy 381.481936 -415.028576)
			(xy 381.534236 -415.013224) (xy 381.588189 -415.005472) (xy 381.615442 -415.005012) (xy 382.479042 -415.005012)
			(xy 382.506293 -415.005461) (xy 382.560239 -415.013222) (xy 382.612531 -415.028582) (xy 382.662106 -415.051227)
			(xy 382.707953 -415.080696) (xy 382.749141 -415.116389) (xy 382.784829 -415.15758) (xy 382.814293 -415.203431)
			(xy 382.836933 -415.253008) (xy 382.852286 -415.305302) (xy 382.860042 -415.359249) (xy 382.860042 -415.413749)
			(xy 384.297698 -415.413749) (xy 384.297698 -415.359251) (xy 384.305454 -415.305308) (xy 384.320807 -415.253017)
			(xy 384.343446 -415.203444) (xy 384.372909 -415.157597) (xy 384.408597 -415.116409) (xy 384.449782 -415.08072)
			(xy 384.495628 -415.051254) (xy 384.5452 -415.028613) (xy 384.59749 -415.013258) (xy 384.651433 -415.005499)
			(xy 384.678682 -415.005012) (xy 385.542282 -415.005012) (xy 385.569537 -415.005434) (xy 385.623493 -415.013189)
			(xy 385.675796 -415.028544) (xy 385.725381 -415.051187) (xy 385.771239 -415.080656) (xy 385.812436 -415.116352)
			(xy 385.848133 -415.157547) (xy 385.877604 -415.203403) (xy 385.900249 -415.252987) (xy 385.915607 -415.305289)
			(xy 385.923365 -415.359245) (xy 385.923365 -415.413752) (xy 387.360875 -415.413752) (xy 387.360875 -415.359248)
			(xy 387.368632 -415.305298) (xy 387.383989 -415.253001) (xy 387.406632 -415.203422) (xy 387.4361 -415.15757)
			(xy 387.471794 -415.116379) (xy 387.512988 -415.080687) (xy 387.558841 -415.051221) (xy 387.608421 -415.028581)
			(xy 387.660719 -415.013228) (xy 387.71467 -415.005474) (xy 387.741922 -415.005012) (xy 388.605522 -415.005012)
			(xy 388.632774 -415.005459) (xy 388.686722 -415.013219) (xy 388.739017 -415.028577) (xy 388.788594 -415.05122)
			(xy 388.834444 -415.080689) (xy 388.875634 -415.116382) (xy 388.911325 -415.157574) (xy 388.94079 -415.203426)
			(xy 388.963431 -415.253004) (xy 388.978786 -415.3053) (xy 388.986542 -415.359248) (xy 388.986542 -415.413748)
			(xy 390.424198 -415.413748) (xy 390.424198 -415.359252) (xy 390.431953 -415.30531) (xy 390.447306 -415.253022)
			(xy 390.469943 -415.203449) (xy 390.499404 -415.157603) (xy 390.535089 -415.116416) (xy 390.576273 -415.080727)
			(xy 390.622116 -415.051261) (xy 390.671686 -415.028619) (xy 390.723973 -415.013261) (xy 390.777914 -415.005501)
			(xy 390.805162 -415.005012) (xy 391.668762 -415.005012) (xy 391.696018 -415.005432) (xy 391.749976 -415.013185)
			(xy 391.802281 -415.028539) (xy 391.851869 -415.05118) (xy 391.897729 -415.080649) (xy 391.938929 -415.116345)
			(xy 391.974628 -415.15754) (xy 392.004101 -415.203398) (xy 392.026748 -415.252983) (xy 392.042107 -415.305287)
			(xy 392.049865 -415.359244) (xy 392.049865 -415.413752) (xy 393.487375 -415.413752) (xy 393.487375 -415.359248)
			(xy 393.495132 -415.3053) (xy 393.510487 -415.253005) (xy 393.533129 -415.203427) (xy 393.562595 -415.157576)
			(xy 393.598287 -415.116386) (xy 393.639478 -415.080694) (xy 393.685329 -415.051228) (xy 393.734907 -415.028587)
			(xy 393.787202 -415.013231) (xy 393.84115 -415.005475) (xy 393.868402 -415.005012) (xy 394.732002 -415.005012)
			(xy 394.759255 -415.005458) (xy 394.813205 -415.013215) (xy 394.865502 -415.028571) (xy 394.915082 -415.051214)
			(xy 394.960934 -415.080682) (xy 395.002126 -415.116375) (xy 395.03782 -415.157567) (xy 395.067287 -415.20342)
			(xy 395.089929 -415.253) (xy 395.105285 -415.305297) (xy 395.113042 -415.359247) (xy 395.113042 -415.413753)
			(xy 396.550575 -415.413753) (xy 396.550575 -415.359247) (xy 396.558333 -415.305295) (xy 396.57369 -415.252996)
			(xy 396.596335 -415.203416) (xy 396.625805 -415.157563) (xy 396.661501 -415.116372) (xy 396.702697 -415.08068)
			(xy 396.748553 -415.051215) (xy 396.798136 -415.028576) (xy 396.850436 -415.013224) (xy 396.904389 -415.005472)
			(xy 396.931642 -415.005012) (xy 397.795242 -415.005012) (xy 397.822493 -415.005461) (xy 397.876439 -415.013222)
			(xy 397.928731 -415.028582) (xy 397.978306 -415.051227) (xy 398.024153 -415.080696) (xy 398.065341 -415.116389)
			(xy 398.101029 -415.15758) (xy 398.130493 -415.203431) (xy 398.153133 -415.253008) (xy 398.168486 -415.305302)
			(xy 398.176242 -415.359249) (xy 398.176242 -415.413749) (xy 399.613898 -415.413749) (xy 399.613898 -415.359251)
			(xy 399.621654 -415.305308) (xy 399.637007 -415.253017) (xy 399.659646 -415.203444) (xy 399.689109 -415.157597)
			(xy 399.724797 -415.116409) (xy 399.765982 -415.08072) (xy 399.811828 -415.051254) (xy 399.8614 -415.028613)
			(xy 399.91369 -415.013258) (xy 399.967633 -415.005499) (xy 399.994882 -415.005012) (xy 400.858482 -415.005012)
			(xy 400.885737 -415.005434) (xy 400.939693 -415.013189) (xy 400.991996 -415.028544) (xy 401.041581 -415.051187)
			(xy 401.087439 -415.080656) (xy 401.128636 -415.116352) (xy 401.164333 -415.157547) (xy 401.193804 -415.203403)
			(xy 401.216449 -415.252987) (xy 401.231807 -415.305289) (xy 401.239565 -415.359245) (xy 401.239565 -415.413752)
			(xy 402.677075 -415.413752) (xy 402.677075 -415.359248) (xy 402.684832 -415.305298) (xy 402.700189 -415.253001)
			(xy 402.722832 -415.203422) (xy 402.7523 -415.15757) (xy 402.787994 -415.116379) (xy 402.829188 -415.080687)
			(xy 402.875041 -415.051221) (xy 402.924621 -415.028581) (xy 402.976919 -415.013228) (xy 403.03087 -415.005474)
			(xy 403.058122 -415.005012) (xy 403.921722 -415.005012) (xy 403.948974 -415.005459) (xy 404.002922 -415.013219)
			(xy 404.055217 -415.028577) (xy 404.104794 -415.05122) (xy 404.150644 -415.080689) (xy 404.191834 -415.116382)
			(xy 404.227525 -415.157574) (xy 404.25699 -415.203426) (xy 404.279631 -415.253004) (xy 404.294986 -415.3053)
			(xy 404.302742 -415.359248) (xy 404.302742 -415.413748) (xy 405.740398 -415.413748) (xy 405.740398 -415.359252)
			(xy 405.748153 -415.30531) (xy 405.763506 -415.253022) (xy 405.786143 -415.203449) (xy 405.815604 -415.157603)
			(xy 405.851289 -415.116416) (xy 405.892473 -415.080727) (xy 405.938316 -415.051261) (xy 405.987886 -415.028619)
			(xy 406.040173 -415.013261) (xy 406.094114 -415.005501) (xy 406.121362 -415.005012) (xy 406.984962 -415.005012)
			(xy 407.012218 -415.005432) (xy 407.066176 -415.013185) (xy 407.118481 -415.028539) (xy 407.168069 -415.05118)
			(xy 407.213929 -415.080649) (xy 407.255129 -415.116345) (xy 407.290828 -415.15754) (xy 407.320301 -415.203398)
			(xy 407.342948 -415.252983) (xy 407.358307 -415.305287) (xy 407.366065 -415.359244) (xy 407.366065 -415.413752)
			(xy 408.803575 -415.413752) (xy 408.803575 -415.359248) (xy 408.811332 -415.3053) (xy 408.826687 -415.253005)
			(xy 408.849329 -415.203427) (xy 408.878795 -415.157576) (xy 408.914487 -415.116386) (xy 408.955678 -415.080694)
			(xy 409.001529 -415.051228) (xy 409.051107 -415.028587) (xy 409.103402 -415.013231) (xy 409.15735 -415.005475)
			(xy 409.184602 -415.005012) (xy 410.048202 -415.005012) (xy 410.075455 -415.005458) (xy 410.129405 -415.013215)
			(xy 410.181702 -415.028571) (xy 410.231282 -415.051214) (xy 410.277134 -415.080682) (xy 410.318326 -415.116375)
			(xy 410.35402 -415.157567) (xy 410.383487 -415.20342) (xy 410.406129 -415.253) (xy 410.421485 -415.305297)
			(xy 410.429242 -415.359247) (xy 410.429242 -415.413753) (xy 411.866775 -415.413753) (xy 411.866775 -415.359247)
			(xy 411.874533 -415.305295) (xy 411.88989 -415.252996) (xy 411.912535 -415.203416) (xy 411.942005 -415.157563)
			(xy 411.977701 -415.116372) (xy 412.018897 -415.08068) (xy 412.064753 -415.051215) (xy 412.114336 -415.028576)
			(xy 412.166636 -415.013224) (xy 412.220589 -415.005472) (xy 412.247842 -415.005012) (xy 413.111442 -415.005012)
			(xy 413.138693 -415.005461) (xy 413.192639 -415.013222) (xy 413.244931 -415.028582) (xy 413.294506 -415.051227)
			(xy 413.340353 -415.080696) (xy 413.381541 -415.116389) (xy 413.417229 -415.15758) (xy 413.446693 -415.203431)
			(xy 413.469333 -415.253008) (xy 413.484686 -415.305302) (xy 413.492442 -415.359249) (xy 413.492442 -415.413749)
			(xy 414.930098 -415.413749) (xy 414.930098 -415.359251) (xy 414.937854 -415.305308) (xy 414.953207 -415.253017)
			(xy 414.975846 -415.203444) (xy 415.005309 -415.157597) (xy 415.040997 -415.116409) (xy 415.082182 -415.08072)
			(xy 415.128028 -415.051254) (xy 415.1776 -415.028613) (xy 415.22989 -415.013258) (xy 415.283833 -415.005499)
			(xy 415.311082 -415.005012) (xy 416.174682 -415.005012) (xy 416.201937 -415.005434) (xy 416.255893 -415.013189)
			(xy 416.308196 -415.028544) (xy 416.357781 -415.051187) (xy 416.403639 -415.080656) (xy 416.444836 -415.116352)
			(xy 416.480533 -415.157547) (xy 416.510004 -415.203403) (xy 416.532649 -415.252987) (xy 416.548007 -415.305289)
			(xy 416.555765 -415.359245) (xy 416.555765 -415.413752) (xy 417.993275 -415.413752) (xy 417.993275 -415.359248)
			(xy 418.001032 -415.305298) (xy 418.016389 -415.253001) (xy 418.039032 -415.203422) (xy 418.0685 -415.15757)
			(xy 418.104194 -415.116379) (xy 418.145388 -415.080687) (xy 418.191241 -415.051221) (xy 418.240821 -415.028581)
			(xy 418.293119 -415.013228) (xy 418.34707 -415.005474) (xy 418.374322 -415.005012) (xy 419.237922 -415.005012)
			(xy 419.265174 -415.005459) (xy 419.319122 -415.013219) (xy 419.371417 -415.028577) (xy 419.420994 -415.05122)
			(xy 419.466844 -415.080689) (xy 419.508034 -415.116382) (xy 419.543725 -415.157574) (xy 419.57319 -415.203426)
			(xy 419.595831 -415.253004) (xy 419.611186 -415.3053) (xy 419.618942 -415.359248) (xy 419.618942 -415.413752)
			(xy 419.611186 -415.4677) (xy 419.595831 -415.519996) (xy 419.57319 -415.569574) (xy 419.543725 -415.615426)
			(xy 419.508034 -415.656618) (xy 419.466844 -415.692311) (xy 419.420994 -415.72178) (xy 419.371417 -415.744423)
			(xy 419.319122 -415.759781) (xy 419.265174 -415.767541) (xy 419.237922 -415.768028) (xy 418.374322 -415.768028)
			(xy 418.34707 -415.767526) (xy 418.293119 -415.759772) (xy 418.240821 -415.744419) (xy 418.191241 -415.721779)
			(xy 418.145388 -415.692313) (xy 418.104194 -415.656621) (xy 418.0685 -415.61543) (xy 418.039032 -415.569578)
			(xy 418.016389 -415.519999) (xy 418.001032 -415.467702) (xy 417.993275 -415.413752) (xy 416.555765 -415.413752)
			(xy 416.555765 -415.413755) (xy 416.548007 -415.467711) (xy 416.532649 -415.520013) (xy 416.510004 -415.569597)
			(xy 416.480533 -415.615453) (xy 416.444836 -415.656648) (xy 416.403639 -415.692344) (xy 416.357781 -415.721813)
			(xy 416.308196 -415.744456) (xy 416.255893 -415.759811) (xy 416.201937 -415.767566) (xy 416.174682 -415.768028)
			(xy 415.311082 -415.768028) (xy 415.283833 -415.767501) (xy 415.22989 -415.759742) (xy 415.1776 -415.744387)
			(xy 415.128028 -415.721746) (xy 415.082182 -415.69228) (xy 415.040997 -415.656591) (xy 415.005309 -415.615403)
			(xy 414.975846 -415.569556) (xy 414.953207 -415.519983) (xy 414.937854 -415.467692) (xy 414.930098 -415.413749)
			(xy 413.492442 -415.413749) (xy 413.492442 -415.413751) (xy 413.484686 -415.467698) (xy 413.469333 -415.519992)
			(xy 413.446693 -415.569569) (xy 413.417229 -415.61542) (xy 413.381541 -415.656611) (xy 413.340353 -415.692304)
			(xy 413.294506 -415.721773) (xy 413.244931 -415.744418) (xy 413.192639 -415.759778) (xy 413.138693 -415.767539)
			(xy 413.111442 -415.768028) (xy 412.247842 -415.768028) (xy 412.220589 -415.767528) (xy 412.166636 -415.759776)
			(xy 412.114336 -415.744424) (xy 412.064753 -415.721785) (xy 412.018897 -415.69232) (xy 411.977701 -415.656628)
			(xy 411.942005 -415.615437) (xy 411.912535 -415.569584) (xy 411.88989 -415.520004) (xy 411.874533 -415.467705)
			(xy 411.866775 -415.413753) (xy 410.429242 -415.413753) (xy 410.421485 -415.467703) (xy 410.406129 -415.52)
			(xy 410.383487 -415.56958) (xy 410.35402 -415.615433) (xy 410.318326 -415.656625) (xy 410.277134 -415.692318)
			(xy 410.231282 -415.721786) (xy 410.181702 -415.744429) (xy 410.129405 -415.759785) (xy 410.075455 -415.767542)
			(xy 410.048202 -415.768028) (xy 409.184602 -415.768028) (xy 409.15735 -415.767525) (xy 409.103402 -415.759769)
			(xy 409.051107 -415.744413) (xy 409.001529 -415.721772) (xy 408.955678 -415.692306) (xy 408.914487 -415.656614)
			(xy 408.878795 -415.615424) (xy 408.849329 -415.569573) (xy 408.826687 -415.519995) (xy 408.811332 -415.4677)
			(xy 408.803575 -415.413752) (xy 407.366065 -415.413752) (xy 407.366065 -415.413756) (xy 407.358307 -415.467713)
			(xy 407.342948 -415.520017) (xy 407.320301 -415.569602) (xy 407.290828 -415.61546) (xy 407.255129 -415.656655)
			(xy 407.213929 -415.692351) (xy 407.168069 -415.72182) (xy 407.118481 -415.744461) (xy 407.066176 -415.759815)
			(xy 407.012218 -415.767568) (xy 406.984962 -415.768028) (xy 406.121362 -415.768028) (xy 406.094114 -415.767499)
			(xy 406.040173 -415.759739) (xy 405.987886 -415.744381) (xy 405.938316 -415.721739) (xy 405.892473 -415.692273)
			(xy 405.851289 -415.656584) (xy 405.815604 -415.615397) (xy 405.786143 -415.569551) (xy 405.763506 -415.519978)
			(xy 405.748153 -415.46769) (xy 405.740398 -415.413748) (xy 404.302742 -415.413748) (xy 404.302742 -415.413752)
			(xy 404.294986 -415.4677) (xy 404.279631 -415.519996) (xy 404.25699 -415.569574) (xy 404.227525 -415.615426)
			(xy 404.191834 -415.656618) (xy 404.150644 -415.692311) (xy 404.104794 -415.72178) (xy 404.055217 -415.744423)
			(xy 404.002922 -415.759781) (xy 403.948974 -415.767541) (xy 403.921722 -415.768028) (xy 403.058122 -415.768028)
			(xy 403.03087 -415.767526) (xy 402.976919 -415.759772) (xy 402.924621 -415.744419) (xy 402.875041 -415.721779)
			(xy 402.829188 -415.692313) (xy 402.787994 -415.656621) (xy 402.7523 -415.61543) (xy 402.722832 -415.569578)
			(xy 402.700189 -415.519999) (xy 402.684832 -415.467702) (xy 402.677075 -415.413752) (xy 401.239565 -415.413752)
			(xy 401.239565 -415.413755) (xy 401.231807 -415.467711) (xy 401.216449 -415.520013) (xy 401.193804 -415.569597)
			(xy 401.164333 -415.615453) (xy 401.128636 -415.656648) (xy 401.087439 -415.692344) (xy 401.041581 -415.721813)
			(xy 400.991996 -415.744456) (xy 400.939693 -415.759811) (xy 400.885737 -415.767566) (xy 400.858482 -415.768028)
			(xy 399.994882 -415.768028) (xy 399.967633 -415.767501) (xy 399.91369 -415.759742) (xy 399.8614 -415.744387)
			(xy 399.811828 -415.721746) (xy 399.765982 -415.69228) (xy 399.724797 -415.656591) (xy 399.689109 -415.615403)
			(xy 399.659646 -415.569556) (xy 399.637007 -415.519983) (xy 399.621654 -415.467692) (xy 399.613898 -415.413749)
			(xy 398.176242 -415.413749) (xy 398.176242 -415.413751) (xy 398.168486 -415.467698) (xy 398.153133 -415.519992)
			(xy 398.130493 -415.569569) (xy 398.101029 -415.61542) (xy 398.065341 -415.656611) (xy 398.024153 -415.692304)
			(xy 397.978306 -415.721773) (xy 397.928731 -415.744418) (xy 397.876439 -415.759778) (xy 397.822493 -415.767539)
			(xy 397.795242 -415.768028) (xy 396.931642 -415.768028) (xy 396.904389 -415.767528) (xy 396.850436 -415.759776)
			(xy 396.798136 -415.744424) (xy 396.748553 -415.721785) (xy 396.702697 -415.69232) (xy 396.661501 -415.656628)
			(xy 396.625805 -415.615437) (xy 396.596335 -415.569584) (xy 396.57369 -415.520004) (xy 396.558333 -415.467705)
			(xy 396.550575 -415.413753) (xy 395.113042 -415.413753) (xy 395.105285 -415.467703) (xy 395.089929 -415.52)
			(xy 395.067287 -415.56958) (xy 395.03782 -415.615433) (xy 395.002126 -415.656625) (xy 394.960934 -415.692318)
			(xy 394.915082 -415.721786) (xy 394.865502 -415.744429) (xy 394.813205 -415.759785) (xy 394.759255 -415.767542)
			(xy 394.732002 -415.768028) (xy 393.868402 -415.768028) (xy 393.84115 -415.767525) (xy 393.787202 -415.759769)
			(xy 393.734907 -415.744413) (xy 393.685329 -415.721772) (xy 393.639478 -415.692306) (xy 393.598287 -415.656614)
			(xy 393.562595 -415.615424) (xy 393.533129 -415.569573) (xy 393.510487 -415.519995) (xy 393.495132 -415.4677)
			(xy 393.487375 -415.413752) (xy 392.049865 -415.413752) (xy 392.049865 -415.413756) (xy 392.042107 -415.467713)
			(xy 392.026748 -415.520017) (xy 392.004101 -415.569602) (xy 391.974628 -415.61546) (xy 391.938929 -415.656655)
			(xy 391.897729 -415.692351) (xy 391.851869 -415.72182) (xy 391.802281 -415.744461) (xy 391.749976 -415.759815)
			(xy 391.696018 -415.767568) (xy 391.668762 -415.768028) (xy 390.805162 -415.768028) (xy 390.777914 -415.767499)
			(xy 390.723973 -415.759739) (xy 390.671686 -415.744381) (xy 390.622116 -415.721739) (xy 390.576273 -415.692273)
			(xy 390.535089 -415.656584) (xy 390.499404 -415.615397) (xy 390.469943 -415.569551) (xy 390.447306 -415.519978)
			(xy 390.431953 -415.46769) (xy 390.424198 -415.413748) (xy 388.986542 -415.413748) (xy 388.986542 -415.413752)
			(xy 388.978786 -415.4677) (xy 388.963431 -415.519996) (xy 388.94079 -415.569574) (xy 388.911325 -415.615426)
			(xy 388.875634 -415.656618) (xy 388.834444 -415.692311) (xy 388.788594 -415.72178) (xy 388.739017 -415.744423)
			(xy 388.686722 -415.759781) (xy 388.632774 -415.767541) (xy 388.605522 -415.768028) (xy 387.741922 -415.768028)
			(xy 387.71467 -415.767526) (xy 387.660719 -415.759772) (xy 387.608421 -415.744419) (xy 387.558841 -415.721779)
			(xy 387.512988 -415.692313) (xy 387.471794 -415.656621) (xy 387.4361 -415.61543) (xy 387.406632 -415.569578)
			(xy 387.383989 -415.519999) (xy 387.368632 -415.467702) (xy 387.360875 -415.413752) (xy 385.923365 -415.413752)
			(xy 385.923365 -415.413755) (xy 385.915607 -415.467711) (xy 385.900249 -415.520013) (xy 385.877604 -415.569597)
			(xy 385.848133 -415.615453) (xy 385.812436 -415.656648) (xy 385.771239 -415.692344) (xy 385.725381 -415.721813)
			(xy 385.675796 -415.744456) (xy 385.623493 -415.759811) (xy 385.569537 -415.767566) (xy 385.542282 -415.768028)
			(xy 384.678682 -415.768028) (xy 384.651433 -415.767501) (xy 384.59749 -415.759742) (xy 384.5452 -415.744387)
			(xy 384.495628 -415.721746) (xy 384.449782 -415.69228) (xy 384.408597 -415.656591) (xy 384.372909 -415.615403)
			(xy 384.343446 -415.569556) (xy 384.320807 -415.519983) (xy 384.305454 -415.467692) (xy 384.297698 -415.413749)
			(xy 382.860042 -415.413749) (xy 382.860042 -415.413751) (xy 382.852286 -415.467698) (xy 382.836933 -415.519992)
			(xy 382.814293 -415.569569) (xy 382.784829 -415.61542) (xy 382.749141 -415.656611) (xy 382.707953 -415.692304)
			(xy 382.662106 -415.721773) (xy 382.612531 -415.744418) (xy 382.560239 -415.759778) (xy 382.506293 -415.767539)
			(xy 382.479042 -415.768028) (xy 381.615442 -415.768028) (xy 381.588189 -415.767528) (xy 381.534236 -415.759776)
			(xy 381.481936 -415.744424) (xy 381.432353 -415.721785) (xy 381.386497 -415.69232) (xy 381.345301 -415.656628)
			(xy 381.309605 -415.615437) (xy 381.280135 -415.569584) (xy 381.25749 -415.520004) (xy 381.242133 -415.467705)
			(xy 381.234375 -415.413753) (xy 379.796842 -415.413753) (xy 379.789085 -415.467703) (xy 379.773729 -415.52)
			(xy 379.751087 -415.56958) (xy 379.72162 -415.615433) (xy 379.685926 -415.656625) (xy 379.644734 -415.692318)
			(xy 379.598882 -415.721786) (xy 379.549302 -415.744429) (xy 379.497005 -415.759785) (xy 379.443055 -415.767542)
			(xy 379.415802 -415.768028) (xy 378.552202 -415.768028) (xy 378.52495 -415.767525) (xy 378.471002 -415.759769)
			(xy 378.418707 -415.744413) (xy 378.369129 -415.721772) (xy 378.323278 -415.692306) (xy 378.282087 -415.656614)
			(xy 378.246395 -415.615424) (xy 378.216929 -415.569573) (xy 378.194287 -415.519995) (xy 378.178932 -415.4677)
			(xy 378.171175 -415.413752) (xy 376.733665 -415.413752) (xy 376.733665 -415.413756) (xy 376.725907 -415.467713)
			(xy 376.710548 -415.520017) (xy 376.687901 -415.569602) (xy 376.658428 -415.61546) (xy 376.622729 -415.656655)
			(xy 376.581529 -415.692351) (xy 376.535669 -415.72182) (xy 376.486081 -415.744461) (xy 376.433776 -415.759815)
			(xy 376.379818 -415.767568) (xy 376.352562 -415.768028) (xy 375.488962 -415.768028) (xy 375.461714 -415.767499)
			(xy 375.407773 -415.759739) (xy 375.355486 -415.744381) (xy 375.305916 -415.721739) (xy 375.260073 -415.692273)
			(xy 375.218889 -415.656584) (xy 375.183204 -415.615397) (xy 375.153743 -415.569551) (xy 375.131106 -415.519978)
			(xy 375.115753 -415.46769) (xy 375.107998 -415.413748) (xy 373.670342 -415.413748) (xy 373.670342 -415.413752)
			(xy 373.662586 -415.4677) (xy 373.647231 -415.519996) (xy 373.62459 -415.569574) (xy 373.595125 -415.615426)
			(xy 373.559434 -415.656618) (xy 373.518244 -415.692311) (xy 373.472394 -415.72178) (xy 373.422817 -415.744423)
			(xy 373.370522 -415.759781) (xy 373.316574 -415.767541) (xy 373.289322 -415.768028) (xy 372.425722 -415.768028)
			(xy 372.39847 -415.767526) (xy 372.344519 -415.759772) (xy 372.292221 -415.744419) (xy 372.242641 -415.721779)
			(xy 372.196788 -415.692313) (xy 372.155594 -415.656621) (xy 372.1199 -415.61543) (xy 372.090432 -415.569578)
			(xy 372.067789 -415.519999) (xy 372.052432 -415.467702) (xy 372.044675 -415.413752) (xy 352.518742 -415.413752)
			(xy 352.510986 -415.4677) (xy 352.495631 -415.519995) (xy 352.472991 -415.569573) (xy 352.443526 -415.615425)
			(xy 352.407835 -415.656617) (xy 352.366646 -415.69231) (xy 352.320796 -415.721778) (xy 352.27122 -415.744422)
			(xy 352.218925 -415.75978) (xy 352.164977 -415.76754) (xy 352.137726 -415.768028) (xy 351.274126 -415.768028)
			(xy 351.246873 -415.767526) (xy 351.192922 -415.759773) (xy 351.140624 -415.74442) (xy 351.091043 -415.72178)
			(xy 351.045189 -415.692314) (xy 351.003996 -415.656623) (xy 350.968301 -415.615431) (xy 350.938832 -415.569579)
			(xy 350.916189 -415.52) (xy 350.900833 -415.467703) (xy 350.893075 -415.413753) (xy 349.455565 -415.413753)
			(xy 349.455565 -415.413755) (xy 349.447807 -415.46771) (xy 349.43245 -415.520012) (xy 349.409805 -415.569595)
			(xy 349.380334 -415.615452) (xy 349.344637 -415.656647) (xy 349.303441 -415.692343) (xy 349.257583 -415.721812)
			(xy 349.207999 -415.744455) (xy 349.155696 -415.75981) (xy 349.101741 -415.767566) (xy 349.074486 -415.768028)
			(xy 348.210886 -415.768028) (xy 348.183637 -415.767501) (xy 348.129694 -415.759743) (xy 348.077403 -415.744388)
			(xy 348.02783 -415.721747) (xy 347.981984 -415.692282) (xy 347.940798 -415.656592) (xy 347.90511 -415.615404)
			(xy 347.875646 -415.569557) (xy 347.853008 -415.519984) (xy 347.837654 -415.467693) (xy 347.829898 -415.413749)
			(xy 346.392242 -415.413749) (xy 346.392242 -415.413751) (xy 346.384487 -415.467697) (xy 346.369133 -415.519991)
			(xy 346.346494 -415.569568) (xy 346.31703 -415.615418) (xy 346.281342 -415.656609) (xy 346.240155 -415.692303)
			(xy 346.194308 -415.721772) (xy 346.144734 -415.744417) (xy 346.092442 -415.759777) (xy 346.038497 -415.767539)
			(xy 346.011246 -415.768028) (xy 345.147646 -415.768028) (xy 345.120392 -415.767528) (xy 345.066439 -415.759777)
			(xy 345.014139 -415.744425) (xy 344.964555 -415.721787) (xy 344.918699 -415.692321) (xy 344.877503 -415.65663)
			(xy 344.841806 -415.615438) (xy 344.812335 -415.569585) (xy 344.789691 -415.520004) (xy 344.774333 -415.467706)
			(xy 344.766575 -415.413754) (xy 343.329042 -415.413754) (xy 343.321285 -415.467702) (xy 343.30593 -415.519999)
			(xy 343.283288 -415.569579) (xy 343.253821 -415.615431) (xy 343.218128 -415.656624) (xy 343.176936 -415.692317)
			(xy 343.131084 -415.721785) (xy 343.081505 -415.744428) (xy 343.029208 -415.759784) (xy 342.975258 -415.767542)
			(xy 342.948006 -415.768028) (xy 342.084406 -415.768028) (xy 342.057154 -415.767525) (xy 342.003206 -415.759769)
			(xy 341.95091 -415.744415) (xy 341.901331 -415.721774) (xy 341.85548 -415.692307) (xy 341.814289 -415.656616)
			(xy 341.778596 -415.615425) (xy 341.749129 -415.569574) (xy 341.726488 -415.519996) (xy 341.711132 -415.4677)
			(xy 341.703375 -415.413752) (xy 340.265865 -415.413752) (xy 340.265865 -415.413756) (xy 340.258107 -415.467713)
			(xy 340.242748 -415.520016) (xy 340.220102 -415.569601) (xy 340.190629 -415.615458) (xy 340.15493 -415.656654)
			(xy 340.113731 -415.69235) (xy 340.067871 -415.721818) (xy 340.018284 -415.74446) (xy 339.965979 -415.759814)
			(xy 339.912022 -415.767567) (xy 339.884766 -415.768028) (xy 339.021166 -415.768028) (xy 338.993918 -415.767499)
			(xy 338.939977 -415.759739) (xy 338.887689 -415.744382) (xy 338.838118 -415.72174) (xy 338.792275 -415.692275)
			(xy 338.751091 -415.656585) (xy 338.715405 -415.615398) (xy 338.685943 -415.569552) (xy 338.663306 -415.519979)
			(xy 338.647953 -415.46769) (xy 338.640198 -415.413748) (xy 337.202542 -415.413748) (xy 337.202542 -415.413751)
			(xy 337.194786 -415.4677) (xy 337.179431 -415.519995) (xy 337.156791 -415.569573) (xy 337.127326 -415.615425)
			(xy 337.091635 -415.656617) (xy 337.050446 -415.69231) (xy 337.004596 -415.721778) (xy 336.95502 -415.744422)
			(xy 336.902725 -415.75978) (xy 336.848777 -415.76754) (xy 336.821526 -415.768028) (xy 335.957926 -415.768028)
			(xy 335.930673 -415.767526) (xy 335.876722 -415.759773) (xy 335.824424 -415.74442) (xy 335.774843 -415.72178)
			(xy 335.728989 -415.692314) (xy 335.687796 -415.656623) (xy 335.652101 -415.615431) (xy 335.622632 -415.569579)
			(xy 335.599989 -415.52) (xy 335.584633 -415.467703) (xy 335.576875 -415.413753) (xy 334.139365 -415.413753)
			(xy 334.139365 -415.413755) (xy 334.131607 -415.46771) (xy 334.11625 -415.520012) (xy 334.093605 -415.569595)
			(xy 334.064134 -415.615452) (xy 334.028437 -415.656647) (xy 333.987241 -415.692343) (xy 333.941383 -415.721812)
			(xy 333.891799 -415.744455) (xy 333.839496 -415.75981) (xy 333.785541 -415.767566) (xy 333.758286 -415.768028)
			(xy 332.894686 -415.768028) (xy 332.867437 -415.767501) (xy 332.813494 -415.759743) (xy 332.761203 -415.744388)
			(xy 332.71163 -415.721747) (xy 332.665784 -415.692282) (xy 332.624598 -415.656592) (xy 332.58891 -415.615404)
			(xy 332.559446 -415.569557) (xy 332.536808 -415.519984) (xy 332.521454 -415.467693) (xy 332.513698 -415.413749)
			(xy 331.076042 -415.413749) (xy 331.076042 -415.413751) (xy 331.068287 -415.467697) (xy 331.052933 -415.519991)
			(xy 331.030294 -415.569568) (xy 331.00083 -415.615418) (xy 330.965142 -415.656609) (xy 330.923955 -415.692303)
			(xy 330.878108 -415.721772) (xy 330.828534 -415.744417) (xy 330.776242 -415.759777) (xy 330.722297 -415.767539)
			(xy 330.695046 -415.768028) (xy 329.831446 -415.768028) (xy 329.804192 -415.767528) (xy 329.750239 -415.759777)
			(xy 329.697939 -415.744425) (xy 329.648355 -415.721787) (xy 329.602499 -415.692321) (xy 329.561303 -415.65663)
			(xy 329.525606 -415.615438) (xy 329.496135 -415.569585) (xy 329.473491 -415.520004) (xy 329.458133 -415.467706)
			(xy 329.450375 -415.413754) (xy 328.012842 -415.413754) (xy 328.005085 -415.467702) (xy 327.98973 -415.519999)
			(xy 327.967088 -415.569579) (xy 327.937621 -415.615431) (xy 327.901928 -415.656624) (xy 327.860736 -415.692317)
			(xy 327.814884 -415.721785) (xy 327.765305 -415.744428) (xy 327.713008 -415.759784) (xy 327.659058 -415.767542)
			(xy 327.631806 -415.768028) (xy 326.768206 -415.768028) (xy 326.740954 -415.767525) (xy 326.687006 -415.759769)
			(xy 326.63471 -415.744415) (xy 326.585131 -415.721774) (xy 326.53928 -415.692307) (xy 326.498089 -415.656616)
			(xy 326.462396 -415.615425) (xy 326.432929 -415.569574) (xy 326.410288 -415.519996) (xy 326.394932 -415.4677)
			(xy 326.387175 -415.413752) (xy 324.949665 -415.413752) (xy 324.949665 -415.413756) (xy 324.941907 -415.467713)
			(xy 324.926548 -415.520016) (xy 324.903902 -415.569601) (xy 324.874429 -415.615458) (xy 324.83873 -415.656654)
			(xy 324.797531 -415.69235) (xy 324.751671 -415.721818) (xy 324.702084 -415.74446) (xy 324.649779 -415.759814)
			(xy 324.595822 -415.767567) (xy 324.568566 -415.768028) (xy 323.704966 -415.768028) (xy 323.677718 -415.767499)
			(xy 323.623777 -415.759739) (xy 323.571489 -415.744382) (xy 323.521918 -415.72174) (xy 323.476075 -415.692275)
			(xy 323.434891 -415.656585) (xy 323.399205 -415.615398) (xy 323.369743 -415.569552) (xy 323.347106 -415.519979)
			(xy 323.331753 -415.46769) (xy 323.323998 -415.413748) (xy 321.886342 -415.413748) (xy 321.886342 -415.413751)
			(xy 321.878586 -415.4677) (xy 321.863231 -415.519995) (xy 321.840591 -415.569573) (xy 321.811126 -415.615425)
			(xy 321.775435 -415.656617) (xy 321.734246 -415.69231) (xy 321.688396 -415.721778) (xy 321.63882 -415.744422)
			(xy 321.586525 -415.75978) (xy 321.532577 -415.76754) (xy 321.505326 -415.768028) (xy 320.641726 -415.768028)
			(xy 320.614473 -415.767526) (xy 320.560522 -415.759773) (xy 320.508224 -415.74442) (xy 320.458643 -415.72178)
			(xy 320.412789 -415.692314) (xy 320.371596 -415.656623) (xy 320.335901 -415.615431) (xy 320.306432 -415.569579)
			(xy 320.283789 -415.52) (xy 320.268433 -415.467703) (xy 320.260675 -415.413753) (xy 318.823165 -415.413753)
			(xy 318.823165 -415.413755) (xy 318.815407 -415.46771) (xy 318.80005 -415.520012) (xy 318.777405 -415.569595)
			(xy 318.747934 -415.615452) (xy 318.712237 -415.656647) (xy 318.671041 -415.692343) (xy 318.625183 -415.721812)
			(xy 318.575599 -415.744455) (xy 318.523296 -415.75981) (xy 318.469341 -415.767566) (xy 318.442086 -415.768028)
			(xy 317.578486 -415.768028) (xy 317.551237 -415.767501) (xy 317.497294 -415.759743) (xy 317.445003 -415.744388)
			(xy 317.39543 -415.721747) (xy 317.349584 -415.692282) (xy 317.308398 -415.656592) (xy 317.27271 -415.615404)
			(xy 317.243246 -415.569557) (xy 317.220608 -415.519984) (xy 317.205254 -415.467693) (xy 317.197498 -415.413749)
			(xy 315.759842 -415.413749) (xy 315.759842 -415.413751) (xy 315.752087 -415.467697) (xy 315.736733 -415.519991)
			(xy 315.714094 -415.569568) (xy 315.68463 -415.615418) (xy 315.648942 -415.656609) (xy 315.607755 -415.692303)
			(xy 315.561908 -415.721772) (xy 315.512334 -415.744417) (xy 315.460042 -415.759777) (xy 315.406097 -415.767539)
			(xy 315.378846 -415.768028) (xy 314.515246 -415.768028) (xy 314.487992 -415.767528) (xy 314.434039 -415.759777)
			(xy 314.381739 -415.744425) (xy 314.332155 -415.721787) (xy 314.286299 -415.692321) (xy 314.245103 -415.65663)
			(xy 314.209406 -415.615438) (xy 314.179935 -415.569585) (xy 314.157291 -415.520004) (xy 314.141933 -415.467706)
			(xy 314.134175 -415.413754) (xy 312.696642 -415.413754) (xy 312.688885 -415.467702) (xy 312.67353 -415.519999)
			(xy 312.650888 -415.569579) (xy 312.621421 -415.615431) (xy 312.585728 -415.656624) (xy 312.544536 -415.692317)
			(xy 312.498684 -415.721785) (xy 312.449105 -415.744428) (xy 312.396808 -415.759784) (xy 312.342858 -415.767542)
			(xy 312.315606 -415.768028) (xy 311.452006 -415.768028) (xy 311.424754 -415.767525) (xy 311.370806 -415.759769)
			(xy 311.31851 -415.744415) (xy 311.268931 -415.721774) (xy 311.22308 -415.692307) (xy 311.181889 -415.656616)
			(xy 311.146196 -415.615425) (xy 311.116729 -415.569574) (xy 311.094088 -415.519996) (xy 311.078732 -415.4677)
			(xy 311.070975 -415.413752) (xy 309.633465 -415.413752) (xy 309.633465 -415.413756) (xy 309.625707 -415.467713)
			(xy 309.610348 -415.520016) (xy 309.587702 -415.569601) (xy 309.558229 -415.615458) (xy 309.52253 -415.656654)
			(xy 309.481331 -415.69235) (xy 309.435471 -415.721818) (xy 309.385884 -415.74446) (xy 309.333579 -415.759814)
			(xy 309.279622 -415.767567) (xy 309.252366 -415.768028) (xy 308.388766 -415.768028) (xy 308.361518 -415.767499)
			(xy 308.307577 -415.759739) (xy 308.255289 -415.744382) (xy 308.205718 -415.72174) (xy 308.159875 -415.692275)
			(xy 308.118691 -415.656585) (xy 308.083005 -415.615398) (xy 308.053543 -415.569552) (xy 308.030906 -415.519979)
			(xy 308.015553 -415.46769) (xy 308.007798 -415.413748) (xy 306.570142 -415.413748) (xy 306.570142 -415.413751)
			(xy 306.562386 -415.4677) (xy 306.547031 -415.519995) (xy 306.524391 -415.569573) (xy 306.494926 -415.615425)
			(xy 306.459235 -415.656617) (xy 306.418046 -415.69231) (xy 306.372196 -415.721778) (xy 306.32262 -415.744422)
			(xy 306.270325 -415.75978) (xy 306.216377 -415.76754) (xy 306.189126 -415.768028) (xy 305.325526 -415.768028)
			(xy 305.298273 -415.767526) (xy 305.244322 -415.759773) (xy 305.192024 -415.74442) (xy 305.142443 -415.72178)
			(xy 305.096589 -415.692314) (xy 305.055396 -415.656623) (xy 305.019701 -415.615431) (xy 304.990232 -415.569579)
			(xy 304.967589 -415.52) (xy 304.952233 -415.467703) (xy 304.944475 -415.413753) (xy 300.882586 -415.413753)
			(xy 300.868941 -415.434612) (xy 300.76479 -415.579315) (xy 300.654297 -415.719235) (xy 300.53768 -415.854094)
			(xy 300.415171 -415.983624) (xy 300.287014 -416.107568) (xy 300.153463 -416.22568) (xy 300.014783 -416.337725)
			(xy 299.871249 -416.443482) (xy 299.723146 -416.542739) (xy 299.570769 -416.635301) (xy 299.41442 -416.720982)
			(xy 299.254409 -416.799614) (xy 299.091055 -416.87104) (xy 298.92468 -416.935118) (xy 298.755617 -416.99172)
			(xy 298.5842 -417.040736) (xy 298.410769 -417.082066) (xy 298.235669 -417.11563) (xy 298.059249 -417.14136)
			(xy 297.881857 -417.159206) (xy 297.703846 -417.169132) (xy 297.525569 -417.171118) (xy 297.347382 -417.165161)
			(xy 297.169636 -417.151271) (xy 296.992686 -417.129478) (xy 296.816882 -417.099824) (xy 296.642574 -417.062367)
			(xy 296.470107 -417.017183) (xy 296.299824 -416.964361) (xy 296.132063 -416.904005) (xy 295.967158 -416.836237)
			(xy 295.805435 -416.761189) (xy 295.647216 -416.679012) (xy 295.492815 -416.589869) (xy 295.342538 -416.493935)
			(xy 295.196683 -416.391403) (xy 295.055541 -416.282475) (xy 294.919392 -416.167368) (xy 294.788505 -416.04631)
			(xy 294.663141 -415.919541) (xy 294.543548 -415.787314) (xy 294.429965 -415.649891) (xy 294.322616 -415.507544)
			(xy 294.221715 -415.360556) (xy 294.127462 -415.20922) (xy 294.040044 -415.053835) (xy 293.959634 -414.89471)
			(xy 293.886393 -414.732161) (xy 293.820466 -414.566511) (xy 293.761983 -414.398089) (xy 293.711061 -414.227228)
			(xy 293.667801 -414.054269) (xy 293.632289 -413.879554) (xy 293.604595 -413.70343) (xy 293.584774 -413.526248)
			(xy 293.572866 -413.348359) (xy 293.568894 -413.170116) (xy 276.749256 -413.170116) (xy 272.414746 -417.504626)
			(xy 272.396783 -417.521953) (xy 272.356401 -417.55128) (xy 272.311928 -417.573928) (xy 272.264459 -417.589339)
			(xy 272.215164 -417.597133) (xy 272.19021 -417.59759) (xy 235.05033 -417.59759) (xy 235.040259 -417.598007)
			(xy 235.02166 -417.605731) (xy 235.014262 -417.612576) (xy 233.545126 -419.081712) (xy 276.721824 -419.081712)
			(xy 276.721824 -418.218112) (xy 276.72231 -418.190861) (xy 276.730066 -418.136913) (xy 276.745421 -418.084618)
			(xy 276.768063 -418.035041) (xy 276.797529 -417.989191) (xy 276.83322 -417.948) (xy 276.874411 -417.912309)
			(xy 276.920261 -417.882843) (xy 276.969838 -417.860201) (xy 277.022133 -417.844846) (xy 277.076081 -417.83709)
			(xy 277.130583 -417.83709) (xy 277.184531 -417.844846) (xy 277.236826 -417.860201) (xy 277.286403 -417.882843)
			(xy 277.332253 -417.912309) (xy 277.373444 -417.948) (xy 277.409135 -417.989191) (xy 277.438601 -418.035041)
			(xy 277.461243 -418.084618) (xy 277.476598 -418.136913) (xy 277.484354 -418.190861) (xy 277.48484 -418.218112)
			(xy 277.48484 -418.254688) (xy 289.453828 -418.254688) (xy 289.453828 -417.391088) (xy 289.454314 -417.363837)
			(xy 289.46207 -417.309889) (xy 289.477425 -417.257594) (xy 289.500067 -417.208017) (xy 289.529533 -417.162167)
			(xy 289.565224 -417.120976) (xy 289.606415 -417.085285) (xy 289.652265 -417.055819) (xy 289.701842 -417.033177)
			(xy 289.754137 -417.017822) (xy 289.808085 -417.010066) (xy 289.862587 -417.010066) (xy 289.916535 -417.017822)
			(xy 289.96883 -417.033177) (xy 290.018407 -417.055819) (xy 290.064257 -417.085285) (xy 290.105448 -417.120976)
			(xy 290.141139 -417.162167) (xy 290.170605 -417.208017) (xy 290.193247 -417.257594) (xy 290.208602 -417.309889)
			(xy 290.216358 -417.363837) (xy 290.216844 -417.391088) (xy 290.216844 -418.254688) (xy 290.216358 -418.281939)
			(xy 290.208602 -418.335887) (xy 290.193247 -418.388182) (xy 290.170605 -418.437759) (xy 290.169514 -418.439456)
			(xy 304.944423 -418.439456) (xy 304.944423 -418.384944) (xy 304.952181 -418.330986) (xy 304.96754 -418.278681)
			(xy 304.990186 -418.229095) (xy 305.019659 -418.183237) (xy 305.055359 -418.14204) (xy 305.096558 -418.106344)
			(xy 305.142418 -418.076874) (xy 305.192006 -418.054231) (xy 305.244311 -418.038876) (xy 305.29827 -418.031121)
			(xy 305.325526 -418.03066) (xy 306.189126 -418.03066) (xy 306.216374 -418.031212) (xy 306.270314 -418.038971)
			(xy 306.322601 -418.054327) (xy 306.372171 -418.076968) (xy 306.418014 -418.106432) (xy 306.459198 -418.142121)
			(xy 306.494884 -418.183307) (xy 306.524345 -418.229152) (xy 306.546982 -418.278723) (xy 306.562335 -418.331011)
			(xy 306.57009 -418.384952) (xy 306.57009 -418.439448) (xy 306.570089 -418.439452) (xy 308.007746 -418.439452)
			(xy 308.007746 -418.384948) (xy 308.015502 -418.330999) (xy 308.030857 -418.278702) (xy 308.053497 -418.229123)
			(xy 308.082963 -418.183271) (xy 308.118654 -418.142078) (xy 308.159843 -418.106383) (xy 308.205693 -418.076914)
			(xy 308.25527 -418.054269) (xy 308.307565 -418.038909) (xy 308.361514 -418.031148) (xy 308.388766 -418.03066)
			(xy 309.252366 -418.03066) (xy 309.279618 -418.031185) (xy 309.333568 -418.038937) (xy 309.385866 -418.054289)
			(xy 309.435446 -418.076928) (xy 309.4813 -418.106392) (xy 309.522493 -418.142083) (xy 309.558187 -418.183273)
			(xy 309.587656 -418.229124) (xy 309.610299 -418.278702) (xy 309.625655 -418.330999) (xy 309.633413 -418.384948)
			(xy 309.633413 -418.439452) (xy 309.633413 -418.439455) (xy 311.070923 -418.439455) (xy 311.070923 -418.384945)
			(xy 311.078681 -418.330989) (xy 311.094038 -418.278686) (xy 311.116683 -418.229101) (xy 311.146154 -418.183244)
			(xy 311.181852 -418.142047) (xy 311.223049 -418.106351) (xy 311.268906 -418.07688) (xy 311.318491 -418.054236)
			(xy 311.370794 -418.038879) (xy 311.424751 -418.031123) (xy 311.452006 -418.03066) (xy 312.315606 -418.03066)
			(xy 312.342855 -418.031211) (xy 312.396797 -418.038967) (xy 312.449087 -418.054321) (xy 312.498659 -418.076961)
			(xy 312.544505 -418.106425) (xy 312.585691 -418.142113) (xy 312.621379 -418.1833) (xy 312.650842 -418.229146)
			(xy 312.673481 -418.278719) (xy 312.688834 -418.331009) (xy 312.69659 -418.384951) (xy 312.69659 -418.439449)
			(xy 312.696589 -418.439457) (xy 314.134123 -418.439457) (xy 314.134123 -418.384943) (xy 314.141882 -418.330983)
			(xy 314.157242 -418.278677) (xy 314.179889 -418.22909) (xy 314.209364 -418.183231) (xy 314.245066 -418.142033)
			(xy 314.286267 -418.106337) (xy 314.33213 -418.076867) (xy 314.38172 -418.054225) (xy 314.434028 -418.038872)
			(xy 314.487989 -418.03112) (xy 314.515246 -418.03066) (xy 315.378846 -418.03066) (xy 315.406093 -418.031213)
			(xy 315.460031 -418.038975) (xy 315.512316 -418.054332) (xy 315.561883 -418.076974) (xy 315.607724 -418.106439)
			(xy 315.648905 -418.142128) (xy 315.684588 -418.183313) (xy 315.714048 -418.229157) (xy 315.736684 -418.278727)
			(xy 315.752035 -418.331014) (xy 315.75979 -418.384953) (xy 315.75979 -418.439447) (xy 315.759789 -418.439453)
			(xy 317.197446 -418.439453) (xy 317.197446 -418.384947) (xy 317.205203 -418.330996) (xy 317.220558 -418.278698)
			(xy 317.2432 -418.229118) (xy 317.272668 -418.183264) (xy 317.308361 -418.142071) (xy 317.349553 -418.106376)
			(xy 317.395405 -418.076907) (xy 317.444985 -418.054263) (xy 317.497282 -418.038906) (xy 317.551233 -418.031147)
			(xy 317.578486 -418.03066) (xy 318.442086 -418.03066) (xy 318.469337 -418.031186) (xy 318.523285 -418.038941)
			(xy 318.57558 -418.054295) (xy 318.625158 -418.076934) (xy 318.671009 -418.106399) (xy 318.7122 -418.14209)
			(xy 318.747892 -418.18328) (xy 318.777359 -418.22913) (xy 318.800001 -418.278707) (xy 318.815356 -418.331001)
			(xy 318.823113 -418.384949) (xy 318.823113 -418.439451) (xy 318.823112 -418.439456) (xy 320.260623 -418.439456)
			(xy 320.260623 -418.384944) (xy 320.268381 -418.330986) (xy 320.28374 -418.278681) (xy 320.306386 -418.229095)
			(xy 320.335859 -418.183237) (xy 320.371559 -418.14204) (xy 320.412758 -418.106344) (xy 320.458618 -418.076874)
			(xy 320.508206 -418.054231) (xy 320.560511 -418.038876) (xy 320.61447 -418.031121) (xy 320.641726 -418.03066)
			(xy 321.505326 -418.03066) (xy 321.532574 -418.031212) (xy 321.586514 -418.038971) (xy 321.638801 -418.054327)
			(xy 321.688371 -418.076968) (xy 321.734214 -418.106432) (xy 321.775398 -418.142121) (xy 321.811084 -418.183307)
			(xy 321.840545 -418.229152) (xy 321.863182 -418.278723) (xy 321.878535 -418.331011) (xy 321.88629 -418.384952)
			(xy 321.88629 -418.439448) (xy 321.886289 -418.439452) (xy 323.323946 -418.439452) (xy 323.323946 -418.384948)
			(xy 323.331702 -418.330999) (xy 323.347057 -418.278702) (xy 323.369697 -418.229123) (xy 323.399163 -418.183271)
			(xy 323.434854 -418.142078) (xy 323.476043 -418.106383) (xy 323.521893 -418.076914) (xy 323.57147 -418.054269)
			(xy 323.623765 -418.038909) (xy 323.677714 -418.031148) (xy 323.704966 -418.03066) (xy 324.568566 -418.03066)
			(xy 324.595818 -418.031185) (xy 324.649768 -418.038937) (xy 324.702066 -418.054289) (xy 324.751646 -418.076928)
			(xy 324.7975 -418.106392) (xy 324.838693 -418.142083) (xy 324.874387 -418.183273) (xy 324.903856 -418.229124)
			(xy 324.926499 -418.278702) (xy 324.941855 -418.330999) (xy 324.949613 -418.384948) (xy 324.949613 -418.439452)
			(xy 324.949613 -418.439455) (xy 326.387123 -418.439455) (xy 326.387123 -418.384945) (xy 326.394881 -418.330989)
			(xy 326.410238 -418.278686) (xy 326.432883 -418.229101) (xy 326.462354 -418.183244) (xy 326.498052 -418.142047)
			(xy 326.539249 -418.106351) (xy 326.585106 -418.07688) (xy 326.634691 -418.054236) (xy 326.686994 -418.038879)
			(xy 326.740951 -418.031123) (xy 326.768206 -418.03066) (xy 327.631806 -418.03066) (xy 327.659055 -418.031211)
			(xy 327.712997 -418.038967) (xy 327.765287 -418.054321) (xy 327.814859 -418.076961) (xy 327.860705 -418.106425)
			(xy 327.901891 -418.142113) (xy 327.937579 -418.1833) (xy 327.967042 -418.229146) (xy 327.989681 -418.278719)
			(xy 328.005034 -418.331009) (xy 328.01279 -418.384951) (xy 328.01279 -418.439449) (xy 328.012789 -418.439457)
			(xy 329.450323 -418.439457) (xy 329.450323 -418.384943) (xy 329.458082 -418.330983) (xy 329.473442 -418.278677)
			(xy 329.496089 -418.22909) (xy 329.525564 -418.183231) (xy 329.561266 -418.142033) (xy 329.602467 -418.106337)
			(xy 329.64833 -418.076867) (xy 329.69792 -418.054225) (xy 329.750228 -418.038872) (xy 329.804189 -418.03112)
			(xy 329.831446 -418.03066) (xy 330.695046 -418.03066) (xy 330.722293 -418.031213) (xy 330.776231 -418.038975)
			(xy 330.828516 -418.054332) (xy 330.878083 -418.076974) (xy 330.923924 -418.106439) (xy 330.965105 -418.142128)
			(xy 331.000788 -418.183313) (xy 331.030248 -418.229157) (xy 331.052884 -418.278727) (xy 331.068235 -418.331014)
			(xy 331.07599 -418.384953) (xy 331.07599 -418.439447) (xy 331.075989 -418.439453) (xy 332.513646 -418.439453)
			(xy 332.513646 -418.384947) (xy 332.521403 -418.330996) (xy 332.536758 -418.278698) (xy 332.5594 -418.229118)
			(xy 332.588868 -418.183264) (xy 332.624561 -418.142071) (xy 332.665753 -418.106376) (xy 332.711605 -418.076907)
			(xy 332.761185 -418.054263) (xy 332.813482 -418.038906) (xy 332.867433 -418.031147) (xy 332.894686 -418.03066)
			(xy 333.758286 -418.03066) (xy 333.785537 -418.031186) (xy 333.839485 -418.038941) (xy 333.89178 -418.054295)
			(xy 333.941358 -418.076934) (xy 333.987209 -418.106399) (xy 334.0284 -418.14209) (xy 334.064092 -418.18328)
			(xy 334.093559 -418.22913) (xy 334.116201 -418.278707) (xy 334.131556 -418.331001) (xy 334.139313 -418.384949)
			(xy 334.139313 -418.439451) (xy 334.139312 -418.439456) (xy 335.576823 -418.439456) (xy 335.576823 -418.384944)
			(xy 335.584581 -418.330986) (xy 335.59994 -418.278681) (xy 335.622586 -418.229095) (xy 335.652059 -418.183237)
			(xy 335.687759 -418.14204) (xy 335.728958 -418.106344) (xy 335.774818 -418.076874) (xy 335.824406 -418.054231)
			(xy 335.876711 -418.038876) (xy 335.93067 -418.031121) (xy 335.957926 -418.03066) (xy 336.821526 -418.03066)
			(xy 336.848774 -418.031212) (xy 336.902714 -418.038971) (xy 336.955001 -418.054327) (xy 337.004571 -418.076968)
			(xy 337.050414 -418.106432) (xy 337.091598 -418.142121) (xy 337.127284 -418.183307) (xy 337.156745 -418.229152)
			(xy 337.179382 -418.278723) (xy 337.194735 -418.331011) (xy 337.20249 -418.384952) (xy 337.20249 -418.439448)
			(xy 337.202489 -418.439452) (xy 338.640146 -418.439452) (xy 338.640146 -418.384948) (xy 338.647902 -418.330999)
			(xy 338.663257 -418.278702) (xy 338.685897 -418.229123) (xy 338.715363 -418.183271) (xy 338.751054 -418.142078)
			(xy 338.792243 -418.106383) (xy 338.838093 -418.076914) (xy 338.88767 -418.054269) (xy 338.939965 -418.038909)
			(xy 338.993914 -418.031148) (xy 339.021166 -418.03066) (xy 339.884766 -418.03066) (xy 339.912018 -418.031185)
			(xy 339.965968 -418.038937) (xy 340.018266 -418.054289) (xy 340.067846 -418.076928) (xy 340.1137 -418.106392)
			(xy 340.154893 -418.142083) (xy 340.190587 -418.183273) (xy 340.220056 -418.229124) (xy 340.242699 -418.278702)
			(xy 340.258055 -418.330999) (xy 340.265813 -418.384948) (xy 340.265813 -418.439452) (xy 340.265813 -418.439455)
			(xy 341.703323 -418.439455) (xy 341.703323 -418.384945) (xy 341.711081 -418.330989) (xy 341.726438 -418.278686)
			(xy 341.749083 -418.229101) (xy 341.778554 -418.183244) (xy 341.814252 -418.142047) (xy 341.855449 -418.106351)
			(xy 341.901306 -418.07688) (xy 341.950891 -418.054236) (xy 342.003194 -418.038879) (xy 342.057151 -418.031123)
			(xy 342.084406 -418.03066) (xy 342.948006 -418.03066) (xy 342.975255 -418.031211) (xy 343.029197 -418.038967)
			(xy 343.081487 -418.054321) (xy 343.131059 -418.076961) (xy 343.176905 -418.106425) (xy 343.218091 -418.142113)
			(xy 343.253779 -418.1833) (xy 343.283242 -418.229146) (xy 343.305881 -418.278719) (xy 343.321234 -418.331009)
			(xy 343.32899 -418.384951) (xy 343.32899 -418.439449) (xy 343.328989 -418.439457) (xy 344.766523 -418.439457)
			(xy 344.766523 -418.384943) (xy 344.774282 -418.330983) (xy 344.789642 -418.278677) (xy 344.812289 -418.22909)
			(xy 344.841764 -418.183231) (xy 344.877466 -418.142033) (xy 344.918667 -418.106337) (xy 344.96453 -418.076867)
			(xy 345.01412 -418.054225) (xy 345.066428 -418.038872) (xy 345.120389 -418.03112) (xy 345.147646 -418.03066)
			(xy 346.011246 -418.03066) (xy 346.038493 -418.031213) (xy 346.092431 -418.038975) (xy 346.144716 -418.054332)
			(xy 346.194283 -418.076974) (xy 346.240124 -418.106439) (xy 346.281305 -418.142128) (xy 346.316988 -418.183313)
			(xy 346.346448 -418.229157) (xy 346.369084 -418.278727) (xy 346.384435 -418.331014) (xy 346.39219 -418.384953)
			(xy 346.39219 -418.439447) (xy 346.392189 -418.439453) (xy 347.829846 -418.439453) (xy 347.829846 -418.384947)
			(xy 347.837603 -418.330996) (xy 347.852958 -418.278698) (xy 347.8756 -418.229118) (xy 347.905068 -418.183264)
			(xy 347.940761 -418.142071) (xy 347.981953 -418.106376) (xy 348.027805 -418.076907) (xy 348.077385 -418.054263)
			(xy 348.129682 -418.038906) (xy 348.183633 -418.031147) (xy 348.210886 -418.03066) (xy 349.074486 -418.03066)
			(xy 349.101737 -418.031186) (xy 349.155685 -418.038941) (xy 349.20798 -418.054295) (xy 349.257558 -418.076934)
			(xy 349.303409 -418.106399) (xy 349.3446 -418.14209) (xy 349.380292 -418.18328) (xy 349.409759 -418.22913)
			(xy 349.432401 -418.278707) (xy 349.447756 -418.331001) (xy 349.455513 -418.384949) (xy 349.455513 -418.439451)
			(xy 349.455512 -418.439456) (xy 350.893023 -418.439456) (xy 350.893023 -418.384944) (xy 350.900781 -418.330986)
			(xy 350.91614 -418.278681) (xy 350.938786 -418.229095) (xy 350.968259 -418.183237) (xy 351.003959 -418.14204)
			(xy 351.045158 -418.106344) (xy 351.091018 -418.076874) (xy 351.140606 -418.054231) (xy 351.192911 -418.038876)
			(xy 351.24687 -418.031121) (xy 351.274126 -418.03066) (xy 352.137726 -418.03066) (xy 352.164974 -418.031212)
			(xy 352.218914 -418.038971) (xy 352.271201 -418.054327) (xy 352.320771 -418.076968) (xy 352.366614 -418.106432)
			(xy 352.407798 -418.142121) (xy 352.443484 -418.183307) (xy 352.472945 -418.229152) (xy 352.495582 -418.278723)
			(xy 352.510935 -418.331011) (xy 352.51869 -418.384952) (xy 352.51869 -418.439448) (xy 352.510935 -418.493389)
			(xy 352.495582 -418.545677) (xy 352.472945 -418.595248) (xy 352.443484 -418.641093) (xy 352.407798 -418.682279)
			(xy 352.366614 -418.717968) (xy 352.320771 -418.747432) (xy 352.271201 -418.770073) (xy 352.218914 -418.785429)
			(xy 352.164974 -418.793188) (xy 352.137726 -418.793676) (xy 351.274126 -418.793676) (xy 351.24687 -418.793279)
			(xy 351.192911 -418.785524) (xy 351.140606 -418.770169) (xy 351.091018 -418.747526) (xy 351.045158 -418.718056)
			(xy 351.003959 -418.68236) (xy 350.968259 -418.641163) (xy 350.938786 -418.595305) (xy 350.91614 -418.545719)
			(xy 350.900781 -418.493414) (xy 350.893023 -418.439456) (xy 349.455512 -418.439456) (xy 349.447756 -418.493399)
			(xy 349.432401 -418.545693) (xy 349.409759 -418.59527) (xy 349.380292 -418.64112) (xy 349.3446 -418.68231)
			(xy 349.303409 -418.718001) (xy 349.257558 -418.747466) (xy 349.20798 -418.770105) (xy 349.155685 -418.785459)
			(xy 349.101737 -418.793214) (xy 349.074486 -418.793676) (xy 348.210886 -418.793676) (xy 348.183633 -418.793253)
			(xy 348.129682 -418.785494) (xy 348.077385 -418.770137) (xy 348.027805 -418.747493) (xy 347.981953 -418.718024)
			(xy 347.940761 -418.682329) (xy 347.905068 -418.641136) (xy 347.8756 -418.595282) (xy 347.852958 -418.545702)
			(xy 347.837603 -418.493404) (xy 347.829846 -418.439453) (xy 346.392189 -418.439453) (xy 346.384435 -418.493386)
			(xy 346.369084 -418.545673) (xy 346.346448 -418.595243) (xy 346.316988 -418.641087) (xy 346.281305 -418.682272)
			(xy 346.240124 -418.717961) (xy 346.194283 -418.747426) (xy 346.144716 -418.770068) (xy 346.092431 -418.785425)
			(xy 346.038493 -418.793187) (xy 346.011246 -418.793676) (xy 345.147646 -418.793676) (xy 345.120389 -418.79328)
			(xy 345.066428 -418.785528) (xy 345.01412 -418.770175) (xy 344.96453 -418.747533) (xy 344.918667 -418.718063)
			(xy 344.877466 -418.682367) (xy 344.841764 -418.641169) (xy 344.812289 -418.59531) (xy 344.789642 -418.545723)
			(xy 344.774282 -418.493417) (xy 344.766523 -418.439457) (xy 343.328989 -418.439457) (xy 343.321234 -418.493391)
			(xy 343.305881 -418.545681) (xy 343.283242 -418.595254) (xy 343.253779 -418.6411) (xy 343.218091 -418.682287)
			(xy 343.176905 -418.717975) (xy 343.131059 -418.747439) (xy 343.081487 -418.770079) (xy 343.029197 -418.785433)
			(xy 342.975255 -418.793189) (xy 342.948006 -418.793676) (xy 342.084406 -418.793676) (xy 342.057151 -418.793277)
			(xy 342.003194 -418.785521) (xy 341.950891 -418.770164) (xy 341.901306 -418.74752) (xy 341.855449 -418.718049)
			(xy 341.814252 -418.682353) (xy 341.778554 -418.641156) (xy 341.749083 -418.595299) (xy 341.726438 -418.545714)
			(xy 341.711081 -418.493411) (xy 341.703323 -418.439455) (xy 340.265813 -418.439455) (xy 340.258055 -418.493402)
			(xy 340.242699 -418.545698) (xy 340.220056 -418.595276) (xy 340.190587 -418.641127) (xy 340.154893 -418.682317)
			(xy 340.1137 -418.718008) (xy 340.067846 -418.747472) (xy 340.018266 -418.770111) (xy 339.965968 -418.785463)
			(xy 339.912018 -418.793215) (xy 339.884766 -418.793676) (xy 339.021166 -418.793676) (xy 338.993914 -418.793252)
			(xy 338.939965 -418.785491) (xy 338.88767 -418.770131) (xy 338.838093 -418.747486) (xy 338.792243 -418.718017)
			(xy 338.751054 -418.682322) (xy 338.715363 -418.641129) (xy 338.685897 -418.595277) (xy 338.663257 -418.545698)
			(xy 338.647902 -418.493401) (xy 338.640146 -418.439452) (xy 337.202489 -418.439452) (xy 337.194735 -418.493389)
			(xy 337.179382 -418.545677) (xy 337.156745 -418.595248) (xy 337.127284 -418.641093) (xy 337.091598 -418.682279)
			(xy 337.050414 -418.717968) (xy 337.004571 -418.747432) (xy 336.955001 -418.770073) (xy 336.902714 -418.785429)
			(xy 336.848774 -418.793188) (xy 336.821526 -418.793676) (xy 335.957926 -418.793676) (xy 335.93067 -418.793279)
			(xy 335.876711 -418.785524) (xy 335.824406 -418.770169) (xy 335.774818 -418.747526) (xy 335.728958 -418.718056)
			(xy 335.687759 -418.68236) (xy 335.652059 -418.641163) (xy 335.622586 -418.595305) (xy 335.59994 -418.545719)
			(xy 335.584581 -418.493414) (xy 335.576823 -418.439456) (xy 334.139312 -418.439456) (xy 334.131556 -418.493399)
			(xy 334.116201 -418.545693) (xy 334.093559 -418.59527) (xy 334.064092 -418.64112) (xy 334.0284 -418.68231)
			(xy 333.987209 -418.718001) (xy 333.941358 -418.747466) (xy 333.89178 -418.770105) (xy 333.839485 -418.785459)
			(xy 333.785537 -418.793214) (xy 333.758286 -418.793676) (xy 332.894686 -418.793676) (xy 332.867433 -418.793253)
			(xy 332.813482 -418.785494) (xy 332.761185 -418.770137) (xy 332.711605 -418.747493) (xy 332.665753 -418.718024)
			(xy 332.624561 -418.682329) (xy 332.588868 -418.641136) (xy 332.5594 -418.595282) (xy 332.536758 -418.545702)
			(xy 332.521403 -418.493404) (xy 332.513646 -418.439453) (xy 331.075989 -418.439453) (xy 331.068235 -418.493386)
			(xy 331.052884 -418.545673) (xy 331.030248 -418.595243) (xy 331.000788 -418.641087) (xy 330.965105 -418.682272)
			(xy 330.923924 -418.717961) (xy 330.878083 -418.747426) (xy 330.828516 -418.770068) (xy 330.776231 -418.785425)
			(xy 330.722293 -418.793187) (xy 330.695046 -418.793676) (xy 329.831446 -418.793676) (xy 329.804189 -418.79328)
			(xy 329.750228 -418.785528) (xy 329.69792 -418.770175) (xy 329.64833 -418.747533) (xy 329.602467 -418.718063)
			(xy 329.561266 -418.682367) (xy 329.525564 -418.641169) (xy 329.496089 -418.59531) (xy 329.473442 -418.545723)
			(xy 329.458082 -418.493417) (xy 329.450323 -418.439457) (xy 328.012789 -418.439457) (xy 328.005034 -418.493391)
			(xy 327.989681 -418.545681) (xy 327.967042 -418.595254) (xy 327.937579 -418.6411) (xy 327.901891 -418.682287)
			(xy 327.860705 -418.717975) (xy 327.814859 -418.747439) (xy 327.765287 -418.770079) (xy 327.712997 -418.785433)
			(xy 327.659055 -418.793189) (xy 327.631806 -418.793676) (xy 326.768206 -418.793676) (xy 326.740951 -418.793277)
			(xy 326.686994 -418.785521) (xy 326.634691 -418.770164) (xy 326.585106 -418.74752) (xy 326.539249 -418.718049)
			(xy 326.498052 -418.682353) (xy 326.462354 -418.641156) (xy 326.432883 -418.595299) (xy 326.410238 -418.545714)
			(xy 326.394881 -418.493411) (xy 326.387123 -418.439455) (xy 324.949613 -418.439455) (xy 324.941855 -418.493402)
			(xy 324.926499 -418.545698) (xy 324.903856 -418.595276) (xy 324.874387 -418.641127) (xy 324.838693 -418.682317)
			(xy 324.7975 -418.718008) (xy 324.751646 -418.747472) (xy 324.702066 -418.770111) (xy 324.649768 -418.785463)
			(xy 324.595818 -418.793215) (xy 324.568566 -418.793676) (xy 323.704966 -418.793676) (xy 323.677714 -418.793252)
			(xy 323.623765 -418.785491) (xy 323.57147 -418.770131) (xy 323.521893 -418.747486) (xy 323.476043 -418.718017)
			(xy 323.434854 -418.682322) (xy 323.399163 -418.641129) (xy 323.369697 -418.595277) (xy 323.347057 -418.545698)
			(xy 323.331702 -418.493401) (xy 323.323946 -418.439452) (xy 321.886289 -418.439452) (xy 321.878535 -418.493389)
			(xy 321.863182 -418.545677) (xy 321.840545 -418.595248) (xy 321.811084 -418.641093) (xy 321.775398 -418.682279)
			(xy 321.734214 -418.717968) (xy 321.688371 -418.747432) (xy 321.638801 -418.770073) (xy 321.586514 -418.785429)
			(xy 321.532574 -418.793188) (xy 321.505326 -418.793676) (xy 320.641726 -418.793676) (xy 320.61447 -418.793279)
			(xy 320.560511 -418.785524) (xy 320.508206 -418.770169) (xy 320.458618 -418.747526) (xy 320.412758 -418.718056)
			(xy 320.371559 -418.68236) (xy 320.335859 -418.641163) (xy 320.306386 -418.595305) (xy 320.28374 -418.545719)
			(xy 320.268381 -418.493414) (xy 320.260623 -418.439456) (xy 318.823112 -418.439456) (xy 318.815356 -418.493399)
			(xy 318.800001 -418.545693) (xy 318.777359 -418.59527) (xy 318.747892 -418.64112) (xy 318.7122 -418.68231)
			(xy 318.671009 -418.718001) (xy 318.625158 -418.747466) (xy 318.57558 -418.770105) (xy 318.523285 -418.785459)
			(xy 318.469337 -418.793214) (xy 318.442086 -418.793676) (xy 317.578486 -418.793676) (xy 317.551233 -418.793253)
			(xy 317.497282 -418.785494) (xy 317.444985 -418.770137) (xy 317.395405 -418.747493) (xy 317.349553 -418.718024)
			(xy 317.308361 -418.682329) (xy 317.272668 -418.641136) (xy 317.2432 -418.595282) (xy 317.220558 -418.545702)
			(xy 317.205203 -418.493404) (xy 317.197446 -418.439453) (xy 315.759789 -418.439453) (xy 315.752035 -418.493386)
			(xy 315.736684 -418.545673) (xy 315.714048 -418.595243) (xy 315.684588 -418.641087) (xy 315.648905 -418.682272)
			(xy 315.607724 -418.717961) (xy 315.561883 -418.747426) (xy 315.512316 -418.770068) (xy 315.460031 -418.785425)
			(xy 315.406093 -418.793187) (xy 315.378846 -418.793676) (xy 314.515246 -418.793676) (xy 314.487989 -418.79328)
			(xy 314.434028 -418.785528) (xy 314.38172 -418.770175) (xy 314.33213 -418.747533) (xy 314.286267 -418.718063)
			(xy 314.245066 -418.682367) (xy 314.209364 -418.641169) (xy 314.179889 -418.59531) (xy 314.157242 -418.545723)
			(xy 314.141882 -418.493417) (xy 314.134123 -418.439457) (xy 312.696589 -418.439457) (xy 312.688834 -418.493391)
			(xy 312.673481 -418.545681) (xy 312.650842 -418.595254) (xy 312.621379 -418.6411) (xy 312.585691 -418.682287)
			(xy 312.544505 -418.717975) (xy 312.498659 -418.747439) (xy 312.449087 -418.770079) (xy 312.396797 -418.785433)
			(xy 312.342855 -418.793189) (xy 312.315606 -418.793676) (xy 311.452006 -418.793676) (xy 311.424751 -418.793277)
			(xy 311.370794 -418.785521) (xy 311.318491 -418.770164) (xy 311.268906 -418.74752) (xy 311.223049 -418.718049)
			(xy 311.181852 -418.682353) (xy 311.146154 -418.641156) (xy 311.116683 -418.595299) (xy 311.094038 -418.545714)
			(xy 311.078681 -418.493411) (xy 311.070923 -418.439455) (xy 309.633413 -418.439455) (xy 309.625655 -418.493402)
			(xy 309.610299 -418.545698) (xy 309.587656 -418.595276) (xy 309.558187 -418.641127) (xy 309.522493 -418.682317)
			(xy 309.4813 -418.718008) (xy 309.435446 -418.747472) (xy 309.385866 -418.770111) (xy 309.333568 -418.785463)
			(xy 309.279618 -418.793215) (xy 309.252366 -418.793676) (xy 308.388766 -418.793676) (xy 308.361514 -418.793252)
			(xy 308.307565 -418.785491) (xy 308.25527 -418.770131) (xy 308.205693 -418.747486) (xy 308.159843 -418.718017)
			(xy 308.118654 -418.682322) (xy 308.082963 -418.641129) (xy 308.053497 -418.595277) (xy 308.030857 -418.545698)
			(xy 308.015502 -418.493401) (xy 308.007746 -418.439452) (xy 306.570089 -418.439452) (xy 306.562335 -418.493389)
			(xy 306.546982 -418.545677) (xy 306.524345 -418.595248) (xy 306.494884 -418.641093) (xy 306.459198 -418.682279)
			(xy 306.418014 -418.717968) (xy 306.372171 -418.747432) (xy 306.322601 -418.770073) (xy 306.270314 -418.785429)
			(xy 306.216374 -418.793188) (xy 306.189126 -418.793676) (xy 305.325526 -418.793676) (xy 305.29827 -418.793279)
			(xy 305.244311 -418.785524) (xy 305.192006 -418.770169) (xy 305.142418 -418.747526) (xy 305.096558 -418.718056)
			(xy 305.055359 -418.68236) (xy 305.019659 -418.641163) (xy 304.990186 -418.595305) (xy 304.96754 -418.545719)
			(xy 304.952181 -418.493414) (xy 304.944423 -418.439456) (xy 290.169514 -418.439456) (xy 290.141139 -418.483609)
			(xy 290.105448 -418.5248) (xy 290.064257 -418.560491) (xy 290.018407 -418.589957) (xy 289.96883 -418.612599)
			(xy 289.916535 -418.627954) (xy 289.862587 -418.63571) (xy 289.808085 -418.63571) (xy 289.754137 -418.627954)
			(xy 289.701842 -418.612599) (xy 289.652265 -418.589957) (xy 289.606415 -418.560491) (xy 289.565224 -418.5248)
			(xy 289.529533 -418.483609) (xy 289.500067 -418.437759) (xy 289.477425 -418.388182) (xy 289.46207 -418.335887)
			(xy 289.454314 -418.281939) (xy 289.453828 -418.254688) (xy 277.48484 -418.254688) (xy 277.48484 -419.081712)
			(xy 277.484354 -419.108963) (xy 277.476598 -419.162911) (xy 277.461243 -419.215206) (xy 277.438601 -419.264783)
			(xy 277.409135 -419.310633) (xy 277.373444 -419.351824) (xy 277.332253 -419.387515) (xy 277.286403 -419.416981)
			(xy 277.236826 -419.439623) (xy 277.184531 -419.454978) (xy 277.130583 -419.462734) (xy 277.076081 -419.462734)
			(xy 277.022133 -419.454978) (xy 276.969838 -419.439623) (xy 276.920261 -419.416981) (xy 276.874411 -419.387515)
			(xy 276.83322 -419.351824) (xy 276.797529 -419.310633) (xy 276.768063 -419.264783) (xy 276.745421 -419.215206)
			(xy 276.730066 -419.162911) (xy 276.72231 -419.108963) (xy 276.721824 -419.081712) (xy 233.545126 -419.081712)
			(xy 232.102406 -420.524432) (xy 290.829492 -420.524432) (xy 290.829492 -419.660832) (xy 290.829978 -419.633563)
			(xy 290.83774 -419.579579) (xy 290.853105 -419.527249) (xy 290.875762 -419.477639) (xy 290.905248 -419.431758)
			(xy 290.940963 -419.390541) (xy 290.98218 -419.354826) (xy 291.028061 -419.32534) (xy 291.077671 -419.302683)
			(xy 291.130001 -419.287318) (xy 291.183985 -419.279556) (xy 291.238523 -419.279556) (xy 291.292507 -419.287318)
			(xy 291.344837 -419.302683) (xy 291.394447 -419.32534) (xy 291.440328 -419.354826) (xy 291.481545 -419.390541)
			(xy 291.51726 -419.431758) (xy 291.546746 -419.477639) (xy 291.569403 -419.527249) (xy 291.584768 -419.579579)
			(xy 291.59253 -419.633563) (xy 291.593016 -419.660832) (xy 291.593016 -420.524432) (xy 291.59253 -420.551701)
			(xy 291.584768 -420.605685) (xy 291.569403 -420.658015) (xy 291.546746 -420.707625) (xy 291.51726 -420.753506)
			(xy 291.481545 -420.794723) (xy 291.440328 -420.830438) (xy 291.394447 -420.859924) (xy 291.344837 -420.882581)
			(xy 291.292507 -420.897946) (xy 291.238523 -420.905708) (xy 291.183985 -420.905708) (xy 291.130001 -420.897946)
			(xy 291.077671 -420.882581) (xy 291.028061 -420.859924) (xy 290.98218 -420.830438) (xy 290.940963 -420.794723)
			(xy 290.905248 -420.753506) (xy 290.875762 -420.707625) (xy 290.853105 -420.658015) (xy 290.83774 -420.605685)
			(xy 290.829978 -420.551701) (xy 290.829492 -420.524432) (xy 232.102406 -420.524432) (xy 231.647383 -420.979455)
			(xy 303.412823 -420.979455) (xy 303.412823 -420.924945) (xy 303.420581 -420.870989) (xy 303.435938 -420.818686)
			(xy 303.458583 -420.769101) (xy 303.488054 -420.723244) (xy 303.523752 -420.682047) (xy 303.564949 -420.646351)
			(xy 303.610806 -420.61688) (xy 303.660391 -420.594236) (xy 303.712694 -420.578879) (xy 303.766651 -420.571123)
			(xy 303.793906 -420.57066) (xy 304.657506 -420.57066) (xy 304.684755 -420.571211) (xy 304.738697 -420.578967)
			(xy 304.790987 -420.594321) (xy 304.840559 -420.616961) (xy 304.886405 -420.646425) (xy 304.927591 -420.682113)
			(xy 304.963279 -420.7233) (xy 304.992742 -420.769146) (xy 305.015381 -420.818719) (xy 305.030734 -420.871009)
			(xy 305.03849 -420.924951) (xy 305.03849 -420.979449) (xy 305.038489 -420.979457) (xy 306.476023 -420.979457)
			(xy 306.476023 -420.924943) (xy 306.483782 -420.870983) (xy 306.499142 -420.818677) (xy 306.521789 -420.76909)
			(xy 306.551264 -420.723231) (xy 306.586966 -420.682033) (xy 306.628167 -420.646337) (xy 306.67403 -420.616867)
			(xy 306.72362 -420.594225) (xy 306.775928 -420.578872) (xy 306.829889 -420.57112) (xy 306.857146 -420.57066)
			(xy 307.720746 -420.57066) (xy 307.747993 -420.571213) (xy 307.801931 -420.578975) (xy 307.854216 -420.594332)
			(xy 307.903783 -420.616974) (xy 307.949624 -420.646439) (xy 307.990805 -420.682128) (xy 308.026488 -420.723313)
			(xy 308.055948 -420.769157) (xy 308.078584 -420.818727) (xy 308.093935 -420.871014) (xy 308.10169 -420.924953)
			(xy 308.10169 -420.979447) (xy 308.101689 -420.979453) (xy 309.539346 -420.979453) (xy 309.539346 -420.924947)
			(xy 309.547103 -420.870996) (xy 309.562458 -420.818698) (xy 309.5851 -420.769118) (xy 309.614568 -420.723264)
			(xy 309.650261 -420.682071) (xy 309.691453 -420.646376) (xy 309.737305 -420.616907) (xy 309.786885 -420.594263)
			(xy 309.839182 -420.578906) (xy 309.893133 -420.571147) (xy 309.920386 -420.57066) (xy 310.783986 -420.57066)
			(xy 310.811237 -420.571186) (xy 310.865185 -420.578941) (xy 310.91748 -420.594295) (xy 310.967058 -420.616934)
			(xy 311.012909 -420.646399) (xy 311.0541 -420.68209) (xy 311.089792 -420.72328) (xy 311.119259 -420.76913)
			(xy 311.141901 -420.818707) (xy 311.157256 -420.871001) (xy 311.165013 -420.924949) (xy 311.165013 -420.979451)
			(xy 311.165012 -420.979456) (xy 312.602523 -420.979456) (xy 312.602523 -420.924944) (xy 312.610281 -420.870986)
			(xy 312.62564 -420.818681) (xy 312.648286 -420.769095) (xy 312.677759 -420.723237) (xy 312.713459 -420.68204)
			(xy 312.754658 -420.646344) (xy 312.800518 -420.616874) (xy 312.850106 -420.594231) (xy 312.902411 -420.578876)
			(xy 312.95637 -420.571121) (xy 312.983626 -420.57066) (xy 313.847226 -420.57066) (xy 313.874474 -420.571212)
			(xy 313.928414 -420.578971) (xy 313.980701 -420.594327) (xy 314.030271 -420.616968) (xy 314.076114 -420.646432)
			(xy 314.117298 -420.682121) (xy 314.152984 -420.723307) (xy 314.182445 -420.769152) (xy 314.205082 -420.818723)
			(xy 314.220435 -420.871011) (xy 314.22819 -420.924952) (xy 314.22819 -420.979448) (xy 314.228189 -420.979452)
			(xy 315.665846 -420.979452) (xy 315.665846 -420.924948) (xy 315.673602 -420.870999) (xy 315.688957 -420.818702)
			(xy 315.711597 -420.769123) (xy 315.741063 -420.723271) (xy 315.776754 -420.682078) (xy 315.817943 -420.646383)
			(xy 315.863793 -420.616914) (xy 315.91337 -420.594269) (xy 315.965665 -420.578909) (xy 316.019614 -420.571148)
			(xy 316.046866 -420.57066) (xy 316.910466 -420.57066) (xy 316.937718 -420.571185) (xy 316.991668 -420.578937)
			(xy 317.043966 -420.594289) (xy 317.093546 -420.616928) (xy 317.1394 -420.646392) (xy 317.180593 -420.682083)
			(xy 317.216287 -420.723273) (xy 317.245756 -420.769124) (xy 317.268399 -420.818702) (xy 317.283755 -420.870999)
			(xy 317.291513 -420.924948) (xy 317.291513 -420.979452) (xy 317.291513 -420.979455) (xy 318.729023 -420.979455)
			(xy 318.729023 -420.924945) (xy 318.736781 -420.870989) (xy 318.752138 -420.818686) (xy 318.774783 -420.769101)
			(xy 318.804254 -420.723244) (xy 318.839952 -420.682047) (xy 318.881149 -420.646351) (xy 318.927006 -420.61688)
			(xy 318.976591 -420.594236) (xy 319.028894 -420.578879) (xy 319.082851 -420.571123) (xy 319.110106 -420.57066)
			(xy 319.973706 -420.57066) (xy 320.000955 -420.571211) (xy 320.054897 -420.578967) (xy 320.107187 -420.594321)
			(xy 320.156759 -420.616961) (xy 320.202605 -420.646425) (xy 320.243791 -420.682113) (xy 320.279479 -420.7233)
			(xy 320.308942 -420.769146) (xy 320.331581 -420.818719) (xy 320.346934 -420.871009) (xy 320.35469 -420.924951)
			(xy 320.35469 -420.979449) (xy 320.354689 -420.979457) (xy 321.792223 -420.979457) (xy 321.792223 -420.924943)
			(xy 321.799982 -420.870983) (xy 321.815342 -420.818677) (xy 321.837989 -420.76909) (xy 321.867464 -420.723231)
			(xy 321.903166 -420.682033) (xy 321.944367 -420.646337) (xy 321.99023 -420.616867) (xy 322.03982 -420.594225)
			(xy 322.092128 -420.578872) (xy 322.146089 -420.57112) (xy 322.173346 -420.57066) (xy 323.036946 -420.57066)
			(xy 323.064193 -420.571213) (xy 323.118131 -420.578975) (xy 323.170416 -420.594332) (xy 323.219983 -420.616974)
			(xy 323.265824 -420.646439) (xy 323.307005 -420.682128) (xy 323.342688 -420.723313) (xy 323.372148 -420.769157)
			(xy 323.394784 -420.818727) (xy 323.410135 -420.871014) (xy 323.41789 -420.924953) (xy 323.41789 -420.979447)
			(xy 323.417889 -420.979453) (xy 324.855546 -420.979453) (xy 324.855546 -420.924947) (xy 324.863303 -420.870996)
			(xy 324.878658 -420.818698) (xy 324.9013 -420.769118) (xy 324.930768 -420.723264) (xy 324.966461 -420.682071)
			(xy 325.007653 -420.646376) (xy 325.053505 -420.616907) (xy 325.103085 -420.594263) (xy 325.155382 -420.578906)
			(xy 325.209333 -420.571147) (xy 325.236586 -420.57066) (xy 326.100186 -420.57066) (xy 326.127437 -420.571186)
			(xy 326.181385 -420.578941) (xy 326.23368 -420.594295) (xy 326.283258 -420.616934) (xy 326.329109 -420.646399)
			(xy 326.3703 -420.68209) (xy 326.405992 -420.72328) (xy 326.435459 -420.76913) (xy 326.458101 -420.818707)
			(xy 326.473456 -420.871001) (xy 326.481213 -420.924949) (xy 326.481213 -420.979451) (xy 326.481212 -420.979456)
			(xy 327.918723 -420.979456) (xy 327.918723 -420.924944) (xy 327.926481 -420.870986) (xy 327.94184 -420.818681)
			(xy 327.964486 -420.769095) (xy 327.993959 -420.723237) (xy 328.029659 -420.68204) (xy 328.070858 -420.646344)
			(xy 328.116718 -420.616874) (xy 328.166306 -420.594231) (xy 328.218611 -420.578876) (xy 328.27257 -420.571121)
			(xy 328.299826 -420.57066) (xy 329.163426 -420.57066) (xy 329.190674 -420.571212) (xy 329.244614 -420.578971)
			(xy 329.296901 -420.594327) (xy 329.346471 -420.616968) (xy 329.392314 -420.646432) (xy 329.433498 -420.682121)
			(xy 329.469184 -420.723307) (xy 329.498645 -420.769152) (xy 329.521282 -420.818723) (xy 329.536635 -420.871011)
			(xy 329.54439 -420.924952) (xy 329.54439 -420.979448) (xy 329.544389 -420.979452) (xy 330.982046 -420.979452)
			(xy 330.982046 -420.924948) (xy 330.989802 -420.870999) (xy 331.005157 -420.818702) (xy 331.027797 -420.769123)
			(xy 331.057263 -420.723271) (xy 331.092954 -420.682078) (xy 331.134143 -420.646383) (xy 331.179993 -420.616914)
			(xy 331.22957 -420.594269) (xy 331.281865 -420.578909) (xy 331.335814 -420.571148) (xy 331.363066 -420.57066)
			(xy 332.226666 -420.57066) (xy 332.253918 -420.571185) (xy 332.307868 -420.578937) (xy 332.360166 -420.594289)
			(xy 332.409746 -420.616928) (xy 332.4556 -420.646392) (xy 332.496793 -420.682083) (xy 332.532487 -420.723273)
			(xy 332.561956 -420.769124) (xy 332.584599 -420.818702) (xy 332.599955 -420.870999) (xy 332.607713 -420.924948)
			(xy 332.607713 -420.979452) (xy 332.607713 -420.979455) (xy 334.045223 -420.979455) (xy 334.045223 -420.924945)
			(xy 334.052981 -420.870989) (xy 334.068338 -420.818686) (xy 334.090983 -420.769101) (xy 334.120454 -420.723244)
			(xy 334.156152 -420.682047) (xy 334.197349 -420.646351) (xy 334.243206 -420.61688) (xy 334.292791 -420.594236)
			(xy 334.345094 -420.578879) (xy 334.399051 -420.571123) (xy 334.426306 -420.57066) (xy 335.289906 -420.57066)
			(xy 335.317155 -420.571211) (xy 335.371097 -420.578967) (xy 335.423387 -420.594321) (xy 335.472959 -420.616961)
			(xy 335.518805 -420.646425) (xy 335.559991 -420.682113) (xy 335.595679 -420.7233) (xy 335.625142 -420.769146)
			(xy 335.647781 -420.818719) (xy 335.663134 -420.871009) (xy 335.67089 -420.924951) (xy 335.67089 -420.979449)
			(xy 335.670889 -420.979457) (xy 337.108423 -420.979457) (xy 337.108423 -420.924943) (xy 337.116182 -420.870983)
			(xy 337.131542 -420.818677) (xy 337.154189 -420.76909) (xy 337.183664 -420.723231) (xy 337.219366 -420.682033)
			(xy 337.260567 -420.646337) (xy 337.30643 -420.616867) (xy 337.35602 -420.594225) (xy 337.408328 -420.578872)
			(xy 337.462289 -420.57112) (xy 337.489546 -420.57066) (xy 338.353146 -420.57066) (xy 338.380393 -420.571213)
			(xy 338.434331 -420.578975) (xy 338.486616 -420.594332) (xy 338.536183 -420.616974) (xy 338.582024 -420.646439)
			(xy 338.623205 -420.682128) (xy 338.658888 -420.723313) (xy 338.688348 -420.769157) (xy 338.710984 -420.818727)
			(xy 338.726335 -420.871014) (xy 338.73409 -420.924953) (xy 338.73409 -420.979447) (xy 338.734089 -420.979453)
			(xy 340.171746 -420.979453) (xy 340.171746 -420.924947) (xy 340.179503 -420.870996) (xy 340.194858 -420.818698)
			(xy 340.2175 -420.769118) (xy 340.246968 -420.723264) (xy 340.282661 -420.682071) (xy 340.323853 -420.646376)
			(xy 340.369705 -420.616907) (xy 340.419285 -420.594263) (xy 340.471582 -420.578906) (xy 340.525533 -420.571147)
			(xy 340.552786 -420.57066) (xy 341.416386 -420.57066) (xy 341.443637 -420.571186) (xy 341.497585 -420.578941)
			(xy 341.54988 -420.594295) (xy 341.599458 -420.616934) (xy 341.645309 -420.646399) (xy 341.6865 -420.68209)
			(xy 341.722192 -420.72328) (xy 341.751659 -420.76913) (xy 341.774301 -420.818707) (xy 341.789656 -420.871001)
			(xy 341.797413 -420.924949) (xy 341.797413 -420.979451) (xy 341.797412 -420.979456) (xy 343.234923 -420.979456)
			(xy 343.234923 -420.924944) (xy 343.242681 -420.870986) (xy 343.25804 -420.818681) (xy 343.280686 -420.769095)
			(xy 343.310159 -420.723237) (xy 343.345859 -420.68204) (xy 343.387058 -420.646344) (xy 343.432918 -420.616874)
			(xy 343.482506 -420.594231) (xy 343.534811 -420.578876) (xy 343.58877 -420.571121) (xy 343.616026 -420.57066)
			(xy 344.479626 -420.57066) (xy 344.506874 -420.571212) (xy 344.560814 -420.578971) (xy 344.613101 -420.594327)
			(xy 344.662671 -420.616968) (xy 344.708514 -420.646432) (xy 344.749698 -420.682121) (xy 344.785384 -420.723307)
			(xy 344.814845 -420.769152) (xy 344.837482 -420.818723) (xy 344.852835 -420.871011) (xy 344.86059 -420.924952)
			(xy 344.86059 -420.979448) (xy 344.860589 -420.979452) (xy 346.298246 -420.979452) (xy 346.298246 -420.924948)
			(xy 346.306002 -420.870999) (xy 346.321357 -420.818702) (xy 346.343997 -420.769123) (xy 346.373463 -420.723271)
			(xy 346.409154 -420.682078) (xy 346.450343 -420.646383) (xy 346.496193 -420.616914) (xy 346.54577 -420.594269)
			(xy 346.598065 -420.578909) (xy 346.652014 -420.571148) (xy 346.679266 -420.57066) (xy 347.542866 -420.57066)
			(xy 347.570118 -420.571185) (xy 347.624068 -420.578937) (xy 347.676366 -420.594289) (xy 347.725946 -420.616928)
			(xy 347.7718 -420.646392) (xy 347.812993 -420.682083) (xy 347.848687 -420.723273) (xy 347.878156 -420.769124)
			(xy 347.900799 -420.818702) (xy 347.916155 -420.870999) (xy 347.923913 -420.924948) (xy 347.923913 -420.979452)
			(xy 347.923913 -420.979455) (xy 349.361423 -420.979455) (xy 349.361423 -420.924945) (xy 349.369181 -420.870989)
			(xy 349.384538 -420.818686) (xy 349.407183 -420.769101) (xy 349.436654 -420.723244) (xy 349.472352 -420.682047)
			(xy 349.513549 -420.646351) (xy 349.559406 -420.61688) (xy 349.608991 -420.594236) (xy 349.661294 -420.578879)
			(xy 349.715251 -420.571123) (xy 349.742506 -420.57066) (xy 350.606106 -420.57066) (xy 350.633355 -420.571211)
			(xy 350.687297 -420.578967) (xy 350.739587 -420.594321) (xy 350.789159 -420.616961) (xy 350.835005 -420.646425)
			(xy 350.876191 -420.682113) (xy 350.911879 -420.7233) (xy 350.941342 -420.769146) (xy 350.963981 -420.818719)
			(xy 350.979334 -420.871009) (xy 350.98709 -420.924951) (xy 350.98709 -420.979449) (xy 350.979334 -421.033391)
			(xy 350.963981 -421.085681) (xy 350.941342 -421.135254) (xy 350.911879 -421.1811) (xy 350.876191 -421.222287)
			(xy 350.835005 -421.257975) (xy 350.789159 -421.287439) (xy 350.739587 -421.310079) (xy 350.687297 -421.325433)
			(xy 350.633355 -421.333189) (xy 350.606106 -421.333676) (xy 349.742506 -421.333676) (xy 349.715251 -421.333277)
			(xy 349.661294 -421.325521) (xy 349.608991 -421.310164) (xy 349.559406 -421.28752) (xy 349.513549 -421.258049)
			(xy 349.472352 -421.222353) (xy 349.436654 -421.181156) (xy 349.407183 -421.135299) (xy 349.384538 -421.085714)
			(xy 349.369181 -421.033411) (xy 349.361423 -420.979455) (xy 347.923913 -420.979455) (xy 347.916155 -421.033402)
			(xy 347.900799 -421.085698) (xy 347.878156 -421.135276) (xy 347.848687 -421.181127) (xy 347.812993 -421.222317)
			(xy 347.7718 -421.258008) (xy 347.725946 -421.287472) (xy 347.676366 -421.310111) (xy 347.624068 -421.325463)
			(xy 347.570118 -421.333215) (xy 347.542866 -421.333676) (xy 346.679266 -421.333676) (xy 346.652014 -421.333252)
			(xy 346.598065 -421.325491) (xy 346.54577 -421.310131) (xy 346.496193 -421.287486) (xy 346.450343 -421.258017)
			(xy 346.409154 -421.222322) (xy 346.373463 -421.181129) (xy 346.343997 -421.135277) (xy 346.321357 -421.085698)
			(xy 346.306002 -421.033401) (xy 346.298246 -420.979452) (xy 344.860589 -420.979452) (xy 344.852835 -421.033389)
			(xy 344.837482 -421.085677) (xy 344.814845 -421.135248) (xy 344.785384 -421.181093) (xy 344.749698 -421.222279)
			(xy 344.708514 -421.257968) (xy 344.662671 -421.287432) (xy 344.613101 -421.310073) (xy 344.560814 -421.325429)
			(xy 344.506874 -421.333188) (xy 344.479626 -421.333676) (xy 343.616026 -421.333676) (xy 343.58877 -421.333279)
			(xy 343.534811 -421.325524) (xy 343.482506 -421.310169) (xy 343.432918 -421.287526) (xy 343.387058 -421.258056)
			(xy 343.345859 -421.22236) (xy 343.310159 -421.181163) (xy 343.280686 -421.135305) (xy 343.25804 -421.085719)
			(xy 343.242681 -421.033414) (xy 343.234923 -420.979456) (xy 341.797412 -420.979456) (xy 341.789656 -421.033399)
			(xy 341.774301 -421.085693) (xy 341.751659 -421.13527) (xy 341.722192 -421.18112) (xy 341.6865 -421.22231)
			(xy 341.645309 -421.258001) (xy 341.599458 -421.287466) (xy 341.54988 -421.310105) (xy 341.497585 -421.325459)
			(xy 341.443637 -421.333214) (xy 341.416386 -421.333676) (xy 340.552786 -421.333676) (xy 340.525533 -421.333253)
			(xy 340.471582 -421.325494) (xy 340.419285 -421.310137) (xy 340.369705 -421.287493) (xy 340.323853 -421.258024)
			(xy 340.282661 -421.222329) (xy 340.246968 -421.181136) (xy 340.2175 -421.135282) (xy 340.194858 -421.085702)
			(xy 340.179503 -421.033404) (xy 340.171746 -420.979453) (xy 338.734089 -420.979453) (xy 338.726335 -421.033386)
			(xy 338.710984 -421.085673) (xy 338.688348 -421.135243) (xy 338.658888 -421.181087) (xy 338.623205 -421.222272)
			(xy 338.582024 -421.257961) (xy 338.536183 -421.287426) (xy 338.486616 -421.310068) (xy 338.434331 -421.325425)
			(xy 338.380393 -421.333187) (xy 338.353146 -421.333676) (xy 337.489546 -421.333676) (xy 337.462289 -421.33328)
			(xy 337.408328 -421.325528) (xy 337.35602 -421.310175) (xy 337.30643 -421.287533) (xy 337.260567 -421.258063)
			(xy 337.219366 -421.222367) (xy 337.183664 -421.181169) (xy 337.154189 -421.13531) (xy 337.131542 -421.085723)
			(xy 337.116182 -421.033417) (xy 337.108423 -420.979457) (xy 335.670889 -420.979457) (xy 335.663134 -421.033391)
			(xy 335.647781 -421.085681) (xy 335.625142 -421.135254) (xy 335.595679 -421.1811) (xy 335.559991 -421.222287)
			(xy 335.518805 -421.257975) (xy 335.472959 -421.287439) (xy 335.423387 -421.310079) (xy 335.371097 -421.325433)
			(xy 335.317155 -421.333189) (xy 335.289906 -421.333676) (xy 334.426306 -421.333676) (xy 334.399051 -421.333277)
			(xy 334.345094 -421.325521) (xy 334.292791 -421.310164) (xy 334.243206 -421.28752) (xy 334.197349 -421.258049)
			(xy 334.156152 -421.222353) (xy 334.120454 -421.181156) (xy 334.090983 -421.135299) (xy 334.068338 -421.085714)
			(xy 334.052981 -421.033411) (xy 334.045223 -420.979455) (xy 332.607713 -420.979455) (xy 332.599955 -421.033402)
			(xy 332.584599 -421.085698) (xy 332.561956 -421.135276) (xy 332.532487 -421.181127) (xy 332.496793 -421.222317)
			(xy 332.4556 -421.258008) (xy 332.409746 -421.287472) (xy 332.360166 -421.310111) (xy 332.307868 -421.325463)
			(xy 332.253918 -421.333215) (xy 332.226666 -421.333676) (xy 331.363066 -421.333676) (xy 331.335814 -421.333252)
			(xy 331.281865 -421.325491) (xy 331.22957 -421.310131) (xy 331.179993 -421.287486) (xy 331.134143 -421.258017)
			(xy 331.092954 -421.222322) (xy 331.057263 -421.181129) (xy 331.027797 -421.135277) (xy 331.005157 -421.085698)
			(xy 330.989802 -421.033401) (xy 330.982046 -420.979452) (xy 329.544389 -420.979452) (xy 329.536635 -421.033389)
			(xy 329.521282 -421.085677) (xy 329.498645 -421.135248) (xy 329.469184 -421.181093) (xy 329.433498 -421.222279)
			(xy 329.392314 -421.257968) (xy 329.346471 -421.287432) (xy 329.296901 -421.310073) (xy 329.244614 -421.325429)
			(xy 329.190674 -421.333188) (xy 329.163426 -421.333676) (xy 328.299826 -421.333676) (xy 328.27257 -421.333279)
			(xy 328.218611 -421.325524) (xy 328.166306 -421.310169) (xy 328.116718 -421.287526) (xy 328.070858 -421.258056)
			(xy 328.029659 -421.22236) (xy 327.993959 -421.181163) (xy 327.964486 -421.135305) (xy 327.94184 -421.085719)
			(xy 327.926481 -421.033414) (xy 327.918723 -420.979456) (xy 326.481212 -420.979456) (xy 326.473456 -421.033399)
			(xy 326.458101 -421.085693) (xy 326.435459 -421.13527) (xy 326.405992 -421.18112) (xy 326.3703 -421.22231)
			(xy 326.329109 -421.258001) (xy 326.283258 -421.287466) (xy 326.23368 -421.310105) (xy 326.181385 -421.325459)
			(xy 326.127437 -421.333214) (xy 326.100186 -421.333676) (xy 325.236586 -421.333676) (xy 325.209333 -421.333253)
			(xy 325.155382 -421.325494) (xy 325.103085 -421.310137) (xy 325.053505 -421.287493) (xy 325.007653 -421.258024)
			(xy 324.966461 -421.222329) (xy 324.930768 -421.181136) (xy 324.9013 -421.135282) (xy 324.878658 -421.085702)
			(xy 324.863303 -421.033404) (xy 324.855546 -420.979453) (xy 323.417889 -420.979453) (xy 323.410135 -421.033386)
			(xy 323.394784 -421.085673) (xy 323.372148 -421.135243) (xy 323.342688 -421.181087) (xy 323.307005 -421.222272)
			(xy 323.265824 -421.257961) (xy 323.219983 -421.287426) (xy 323.170416 -421.310068) (xy 323.118131 -421.325425)
			(xy 323.064193 -421.333187) (xy 323.036946 -421.333676) (xy 322.173346 -421.333676) (xy 322.146089 -421.33328)
			(xy 322.092128 -421.325528) (xy 322.03982 -421.310175) (xy 321.99023 -421.287533) (xy 321.944367 -421.258063)
			(xy 321.903166 -421.222367) (xy 321.867464 -421.181169) (xy 321.837989 -421.13531) (xy 321.815342 -421.085723)
			(xy 321.799982 -421.033417) (xy 321.792223 -420.979457) (xy 320.354689 -420.979457) (xy 320.346934 -421.033391)
			(xy 320.331581 -421.085681) (xy 320.308942 -421.135254) (xy 320.279479 -421.1811) (xy 320.243791 -421.222287)
			(xy 320.202605 -421.257975) (xy 320.156759 -421.287439) (xy 320.107187 -421.310079) (xy 320.054897 -421.325433)
			(xy 320.000955 -421.333189) (xy 319.973706 -421.333676) (xy 319.110106 -421.333676) (xy 319.082851 -421.333277)
			(xy 319.028894 -421.325521) (xy 318.976591 -421.310164) (xy 318.927006 -421.28752) (xy 318.881149 -421.258049)
			(xy 318.839952 -421.222353) (xy 318.804254 -421.181156) (xy 318.774783 -421.135299) (xy 318.752138 -421.085714)
			(xy 318.736781 -421.033411) (xy 318.729023 -420.979455) (xy 317.291513 -420.979455) (xy 317.283755 -421.033402)
			(xy 317.268399 -421.085698) (xy 317.245756 -421.135276) (xy 317.216287 -421.181127) (xy 317.180593 -421.222317)
			(xy 317.1394 -421.258008) (xy 317.093546 -421.287472) (xy 317.043966 -421.310111) (xy 316.991668 -421.325463)
			(xy 316.937718 -421.333215) (xy 316.910466 -421.333676) (xy 316.046866 -421.333676) (xy 316.019614 -421.333252)
			(xy 315.965665 -421.325491) (xy 315.91337 -421.310131) (xy 315.863793 -421.287486) (xy 315.817943 -421.258017)
			(xy 315.776754 -421.222322) (xy 315.741063 -421.181129) (xy 315.711597 -421.135277) (xy 315.688957 -421.085698)
			(xy 315.673602 -421.033401) (xy 315.665846 -420.979452) (xy 314.228189 -420.979452) (xy 314.220435 -421.033389)
			(xy 314.205082 -421.085677) (xy 314.182445 -421.135248) (xy 314.152984 -421.181093) (xy 314.117298 -421.222279)
			(xy 314.076114 -421.257968) (xy 314.030271 -421.287432) (xy 313.980701 -421.310073) (xy 313.928414 -421.325429)
			(xy 313.874474 -421.333188) (xy 313.847226 -421.333676) (xy 312.983626 -421.333676) (xy 312.95637 -421.333279)
			(xy 312.902411 -421.325524) (xy 312.850106 -421.310169) (xy 312.800518 -421.287526) (xy 312.754658 -421.258056)
			(xy 312.713459 -421.22236) (xy 312.677759 -421.181163) (xy 312.648286 -421.135305) (xy 312.62564 -421.085719)
			(xy 312.610281 -421.033414) (xy 312.602523 -420.979456) (xy 311.165012 -420.979456) (xy 311.157256 -421.033399)
			(xy 311.141901 -421.085693) (xy 311.119259 -421.13527) (xy 311.089792 -421.18112) (xy 311.0541 -421.22231)
			(xy 311.012909 -421.258001) (xy 310.967058 -421.287466) (xy 310.91748 -421.310105) (xy 310.865185 -421.325459)
			(xy 310.811237 -421.333214) (xy 310.783986 -421.333676) (xy 309.920386 -421.333676) (xy 309.893133 -421.333253)
			(xy 309.839182 -421.325494) (xy 309.786885 -421.310137) (xy 309.737305 -421.287493) (xy 309.691453 -421.258024)
			(xy 309.650261 -421.222329) (xy 309.614568 -421.181136) (xy 309.5851 -421.135282) (xy 309.562458 -421.085702)
			(xy 309.547103 -421.033404) (xy 309.539346 -420.979453) (xy 308.101689 -420.979453) (xy 308.093935 -421.033386)
			(xy 308.078584 -421.085673) (xy 308.055948 -421.135243) (xy 308.026488 -421.181087) (xy 307.990805 -421.222272)
			(xy 307.949624 -421.257961) (xy 307.903783 -421.287426) (xy 307.854216 -421.310068) (xy 307.801931 -421.325425)
			(xy 307.747993 -421.333187) (xy 307.720746 -421.333676) (xy 306.857146 -421.333676) (xy 306.829889 -421.33328)
			(xy 306.775928 -421.325528) (xy 306.72362 -421.310175) (xy 306.67403 -421.287533) (xy 306.628167 -421.258063)
			(xy 306.586966 -421.222367) (xy 306.551264 -421.181169) (xy 306.521789 -421.13531) (xy 306.499142 -421.085723)
			(xy 306.483782 -421.033417) (xy 306.476023 -420.979457) (xy 305.038489 -420.979457) (xy 305.030734 -421.033391)
			(xy 305.015381 -421.085681) (xy 304.992742 -421.135254) (xy 304.963279 -421.1811) (xy 304.927591 -421.222287)
			(xy 304.886405 -421.257975) (xy 304.840559 -421.287439) (xy 304.790987 -421.310079) (xy 304.738697 -421.325433)
			(xy 304.684755 -421.333189) (xy 304.657506 -421.333676) (xy 303.793906 -421.333676) (xy 303.766651 -421.333277)
			(xy 303.712694 -421.325521) (xy 303.660391 -421.310164) (xy 303.610806 -421.28752) (xy 303.564949 -421.258049)
			(xy 303.523752 -421.222353) (xy 303.488054 -421.181156) (xy 303.458583 -421.135299) (xy 303.435938 -421.085714)
			(xy 303.420581 -421.033411) (xy 303.412823 -420.979455) (xy 231.647383 -420.979455) (xy 230.329486 -422.297352)
			(xy 230.322673 -422.304773) (xy 230.314938 -422.323356) (xy 230.3145 -422.33342) (xy 230.3145 -422.354375)
			(xy 285.567772 -422.354375) (xy 285.567772 -422.299825) (xy 285.575535 -422.245831) (xy 285.590905 -422.193491)
			(xy 285.613567 -422.143872) (xy 285.64306 -422.097983) (xy 285.678784 -422.056759) (xy 285.720012 -422.021038)
			(xy 285.765903 -421.991549) (xy 285.815525 -421.968892) (xy 285.867866 -421.953528) (xy 285.921861 -421.945769)
			(xy 285.949136 -421.945308) (xy 286.812736 -421.945308) (xy 286.840002 -421.945857) (xy 286.893977 -421.953622)
			(xy 286.946298 -421.968989) (xy 286.9959 -421.991646) (xy 287.041773 -422.02113) (xy 287.082983 -422.056843)
			(xy 287.118691 -422.098056) (xy 287.148172 -422.143932) (xy 287.170823 -422.193536) (xy 287.186186 -422.245858)
			(xy 287.193946 -422.299834) (xy 287.193946 -422.354366) (xy 287.186186 -422.408342) (xy 287.170823 -422.460664)
			(xy 287.148172 -422.510268) (xy 287.118691 -422.556144) (xy 287.082983 -422.597357) (xy 287.041773 -422.63307)
			(xy 286.9959 -422.662554) (xy 286.946298 -422.685211) (xy 286.893977 -422.700578) (xy 286.840002 -422.708343)
			(xy 286.812736 -422.708832) (xy 285.949136 -422.708832) (xy 285.921861 -422.708431) (xy 285.867866 -422.700672)
			(xy 285.815525 -422.685308) (xy 285.765903 -422.662651) (xy 285.720012 -422.633162) (xy 285.678784 -422.597441)
			(xy 285.64306 -422.556217) (xy 285.613567 -422.510328) (xy 285.590905 -422.460709) (xy 285.575535 -422.408369)
			(xy 285.567772 -422.354375) (xy 230.3145 -422.354375) (xy 230.3145 -424.80464) (xy 357.679233 -424.80464)
			(xy 357.679233 -424.6755) (xy 357.687183 -424.546605) (xy 357.703053 -424.418445) (xy 357.726782 -424.291504)
			(xy 357.758281 -424.166265) (xy 357.79743 -424.043202) (xy 357.844081 -423.922783) (xy 357.898056 -423.805464)
			(xy 357.959151 -423.69169) (xy 358.027134 -423.581893) (xy 358.101748 -423.47649) (xy 358.182709 -423.37588)
			(xy 358.269709 -423.280445) (xy 358.36242 -423.190546) (xy 358.46049 -423.106525) (xy 358.563545 -423.028701)
			(xy 358.671196 -422.957369) (xy 358.783035 -422.892799) (xy 358.898636 -422.835237) (xy 359.017561 -422.7849)
			(xy 359.13936 -422.74198) (xy 359.26357 -422.706639) (xy 359.389719 -422.679012) (xy 359.517331 -422.659203)
			(xy 359.64592 -422.647287) (xy 359.774998 -422.643311) (xy 359.904076 -422.647287) (xy 360.032665 -422.659203)
			(xy 360.160277 -422.679012) (xy 360.222212 -422.692576) (xy 365.310928 -422.692576) (xy 365.310928 -415.898584)
			(xy 365.3113 -415.888356) (xy 365.319137 -415.86946) (xy 365.33361 -415.855003) (xy 365.352515 -415.847188)
			(xy 365.362744 -415.846768) (xy 370.261388 -415.846768) (xy 370.271593 -415.847291) (xy 370.290451 -415.855097)
			(xy 370.304887 -415.869525) (xy 370.312703 -415.888379) (xy 370.313204 -415.898584) (xy 370.313204 -418.439456)
			(xy 372.044623 -418.439456) (xy 372.044623 -418.384944) (xy 372.052381 -418.330986) (xy 372.06774 -418.278682)
			(xy 372.090386 -418.229097) (xy 372.119858 -418.183238) (xy 372.155557 -418.142042) (xy 372.196756 -418.106345)
			(xy 372.242616 -418.076875) (xy 372.292203 -418.054232) (xy 372.344508 -418.038877) (xy 372.398466 -418.031121)
			(xy 372.425722 -418.03066) (xy 373.289322 -418.03066) (xy 373.31657 -418.031212) (xy 373.370511 -418.03897)
			(xy 373.422798 -418.054326) (xy 373.472369 -418.076966) (xy 373.518212 -418.106431) (xy 373.559396 -418.142119)
			(xy 373.595083 -418.183305) (xy 373.624544 -418.229151) (xy 373.647182 -418.278722) (xy 373.662535 -418.331011)
			(xy 373.67029 -418.384952) (xy 373.67029 -418.439448) (xy 373.670289 -418.439452) (xy 375.107946 -418.439452)
			(xy 375.107946 -418.384948) (xy 375.115702 -418.330999) (xy 375.131056 -418.278703) (xy 375.153697 -418.229124)
			(xy 375.183162 -418.183272) (xy 375.218852 -418.142079) (xy 375.260041 -418.106385) (xy 375.305891 -418.076915)
			(xy 375.355468 -418.05427) (xy 375.407762 -418.03891) (xy 375.46171 -418.031148) (xy 375.488962 -418.03066)
			(xy 376.352562 -418.03066) (xy 376.379814 -418.031185) (xy 376.433765 -418.038937) (xy 376.486063 -418.054288)
			(xy 376.535644 -418.076926) (xy 376.581498 -418.106391) (xy 376.622691 -418.142082) (xy 376.658386 -418.183272)
			(xy 376.687855 -418.229123) (xy 376.710499 -418.278701) (xy 376.725855 -418.330998) (xy 376.733613 -418.384948)
			(xy 376.733613 -418.439452) (xy 376.733613 -418.439455) (xy 378.171123 -418.439455) (xy 378.171123 -418.384945)
			(xy 378.178881 -418.330989) (xy 378.194238 -418.278687) (xy 378.216883 -418.229102) (xy 378.246353 -418.183245)
			(xy 378.28205 -418.142049) (xy 378.323247 -418.106352) (xy 378.369104 -418.076882) (xy 378.418688 -418.054237)
			(xy 378.470991 -418.03888) (xy 378.524947 -418.031123) (xy 378.552202 -418.03066) (xy 379.415802 -418.03066)
			(xy 379.443051 -418.03121) (xy 379.496994 -418.038966) (xy 379.549284 -418.05432) (xy 379.598857 -418.07696)
			(xy 379.644703 -418.106424) (xy 379.685889 -418.142112) (xy 379.721578 -418.183299) (xy 379.751041 -418.229145)
			(xy 379.77368 -418.278718) (xy 379.789034 -418.331008) (xy 379.79679 -418.384951) (xy 379.79679 -418.439449)
			(xy 379.796789 -418.439457) (xy 381.234323 -418.439457) (xy 381.234323 -418.384943) (xy 381.242082 -418.330984)
			(xy 381.257441 -418.278678) (xy 381.280089 -418.229091) (xy 381.309563 -418.183232) (xy 381.345264 -418.142035)
			(xy 381.386466 -418.106338) (xy 381.432328 -418.076869) (xy 381.481917 -418.054227) (xy 381.534225 -418.038873)
			(xy 381.588185 -418.03112) (xy 381.615442 -418.03066) (xy 382.479042 -418.03066) (xy 382.506289 -418.031213)
			(xy 382.560228 -418.038974) (xy 382.612513 -418.054331) (xy 382.662081 -418.076973) (xy 382.707922 -418.106438)
			(xy 382.749103 -418.142126) (xy 382.784787 -418.183312) (xy 382.814247 -418.229156) (xy 382.836883 -418.278727)
			(xy 382.852235 -418.331014) (xy 382.85999 -418.384953) (xy 382.85999 -418.439447) (xy 382.859989 -418.439453)
			(xy 384.297646 -418.439453) (xy 384.297646 -418.384947) (xy 384.305403 -418.330997) (xy 384.320758 -418.278699)
			(xy 384.3434 -418.229119) (xy 384.372867 -418.183265) (xy 384.408559 -418.142072) (xy 384.449751 -418.106378)
			(xy 384.495603 -418.076908) (xy 384.545182 -418.054264) (xy 384.597479 -418.038906) (xy 384.651429 -418.031147)
			(xy 384.678682 -418.03066) (xy 385.542282 -418.03066) (xy 385.569533 -418.031186) (xy 385.623482 -418.03894)
			(xy 385.675777 -418.054293) (xy 385.725356 -418.076933) (xy 385.771207 -418.106398) (xy 385.812399 -418.142089)
			(xy 385.848091 -418.183278) (xy 385.877558 -418.229129) (xy 385.9002 -418.278706) (xy 385.915556 -418.331001)
			(xy 385.923313 -418.384949) (xy 385.923313 -418.439451) (xy 385.923312 -418.439456) (xy 387.360823 -418.439456)
			(xy 387.360823 -418.384944) (xy 387.368581 -418.330986) (xy 387.38394 -418.278682) (xy 387.406586 -418.229097)
			(xy 387.436058 -418.183238) (xy 387.471757 -418.142042) (xy 387.512956 -418.106345) (xy 387.558816 -418.076875)
			(xy 387.608403 -418.054232) (xy 387.660708 -418.038877) (xy 387.714666 -418.031121) (xy 387.741922 -418.03066)
			(xy 388.605522 -418.03066) (xy 388.63277 -418.031212) (xy 388.686711 -418.03897) (xy 388.738998 -418.054326)
			(xy 388.788569 -418.076966) (xy 388.834412 -418.106431) (xy 388.875596 -418.142119) (xy 388.911283 -418.183305)
			(xy 388.940744 -418.229151) (xy 388.963382 -418.278722) (xy 388.978735 -418.331011) (xy 388.98649 -418.384952)
			(xy 388.98649 -418.439448) (xy 388.986489 -418.439452) (xy 390.424146 -418.439452) (xy 390.424146 -418.384948)
			(xy 390.431902 -418.330999) (xy 390.447256 -418.278703) (xy 390.469897 -418.229124) (xy 390.499362 -418.183272)
			(xy 390.535052 -418.142079) (xy 390.576241 -418.106385) (xy 390.622091 -418.076915) (xy 390.671668 -418.05427)
			(xy 390.723962 -418.03891) (xy 390.77791 -418.031148) (xy 390.805162 -418.03066) (xy 391.668762 -418.03066)
			(xy 391.696014 -418.031185) (xy 391.749965 -418.038937) (xy 391.802263 -418.054288) (xy 391.851844 -418.076926)
			(xy 391.897698 -418.106391) (xy 391.938891 -418.142082) (xy 391.974586 -418.183272) (xy 392.004055 -418.229123)
			(xy 392.026699 -418.278701) (xy 392.042055 -418.330998) (xy 392.049813 -418.384948) (xy 392.049813 -418.439452)
			(xy 392.049813 -418.439455) (xy 393.487323 -418.439455) (xy 393.487323 -418.384945) (xy 393.495081 -418.330989)
			(xy 393.510438 -418.278687) (xy 393.533083 -418.229102) (xy 393.562553 -418.183245) (xy 393.59825 -418.142049)
			(xy 393.639447 -418.106352) (xy 393.685304 -418.076882) (xy 393.734888 -418.054237) (xy 393.787191 -418.03888)
			(xy 393.841147 -418.031123) (xy 393.868402 -418.03066) (xy 394.732002 -418.03066) (xy 394.759251 -418.03121)
			(xy 394.813194 -418.038966) (xy 394.865484 -418.05432) (xy 394.915057 -418.07696) (xy 394.960903 -418.106424)
			(xy 395.002089 -418.142112) (xy 395.037778 -418.183299) (xy 395.067241 -418.229145) (xy 395.08988 -418.278718)
			(xy 395.105234 -418.331008) (xy 395.11299 -418.384951) (xy 395.11299 -418.439449) (xy 395.112989 -418.439457)
			(xy 396.550523 -418.439457) (xy 396.550523 -418.384943) (xy 396.558282 -418.330984) (xy 396.573641 -418.278678)
			(xy 396.596289 -418.229091) (xy 396.625763 -418.183232) (xy 396.661464 -418.142035) (xy 396.702666 -418.106338)
			(xy 396.748528 -418.076869) (xy 396.798117 -418.054227) (xy 396.850425 -418.038873) (xy 396.904385 -418.03112)
			(xy 396.931642 -418.03066) (xy 397.795242 -418.03066) (xy 397.822489 -418.031213) (xy 397.876428 -418.038974)
			(xy 397.928713 -418.054331) (xy 397.978281 -418.076973) (xy 398.024122 -418.106438) (xy 398.065303 -418.142126)
			(xy 398.100987 -418.183312) (xy 398.130447 -418.229156) (xy 398.153083 -418.278727) (xy 398.168435 -418.331014)
			(xy 398.17619 -418.384953) (xy 398.17619 -418.439447) (xy 398.176189 -418.439453) (xy 399.613846 -418.439453)
			(xy 399.613846 -418.384947) (xy 399.621603 -418.330997) (xy 399.636958 -418.278699) (xy 399.6596 -418.229119)
			(xy 399.689067 -418.183265) (xy 399.724759 -418.142072) (xy 399.765951 -418.106378) (xy 399.811803 -418.076908)
			(xy 399.861382 -418.054264) (xy 399.913679 -418.038906) (xy 399.967629 -418.031147) (xy 399.994882 -418.03066)
			(xy 400.858482 -418.03066) (xy 400.885733 -418.031186) (xy 400.939682 -418.03894) (xy 400.991977 -418.054293)
			(xy 401.041556 -418.076933) (xy 401.087407 -418.106398) (xy 401.128599 -418.142089) (xy 401.164291 -418.183278)
			(xy 401.193758 -418.229129) (xy 401.2164 -418.278706) (xy 401.231756 -418.331001) (xy 401.239513 -418.384949)
			(xy 401.239513 -418.439451) (xy 401.239512 -418.439456) (xy 402.677023 -418.439456) (xy 402.677023 -418.384944)
			(xy 402.684781 -418.330986) (xy 402.70014 -418.278682) (xy 402.722786 -418.229097) (xy 402.752258 -418.183238)
			(xy 402.787957 -418.142042) (xy 402.829156 -418.106345) (xy 402.875016 -418.076875) (xy 402.924603 -418.054232)
			(xy 402.976908 -418.038877) (xy 403.030866 -418.031121) (xy 403.058122 -418.03066) (xy 403.921722 -418.03066)
			(xy 403.94897 -418.031212) (xy 404.002911 -418.03897) (xy 404.055198 -418.054326) (xy 404.104769 -418.076966)
			(xy 404.150612 -418.106431) (xy 404.191796 -418.142119) (xy 404.227483 -418.183305) (xy 404.256944 -418.229151)
			(xy 404.279582 -418.278722) (xy 404.294935 -418.331011) (xy 404.30269 -418.384952) (xy 404.30269 -418.439448)
			(xy 404.302689 -418.439452) (xy 405.740346 -418.439452) (xy 405.740346 -418.384948) (xy 405.748102 -418.330999)
			(xy 405.763456 -418.278703) (xy 405.786097 -418.229124) (xy 405.815562 -418.183272) (xy 405.851252 -418.142079)
			(xy 405.892441 -418.106385) (xy 405.938291 -418.076915) (xy 405.987868 -418.05427) (xy 406.040162 -418.03891)
			(xy 406.09411 -418.031148) (xy 406.121362 -418.03066) (xy 406.984962 -418.03066) (xy 407.012214 -418.031185)
			(xy 407.066165 -418.038937) (xy 407.118463 -418.054288) (xy 407.168044 -418.076926) (xy 407.213898 -418.106391)
			(xy 407.255091 -418.142082) (xy 407.290786 -418.183272) (xy 407.320255 -418.229123) (xy 407.342899 -418.278701)
			(xy 407.358255 -418.330998) (xy 407.366013 -418.384948) (xy 407.366013 -418.439452) (xy 407.366013 -418.439455)
			(xy 408.803523 -418.439455) (xy 408.803523 -418.384945) (xy 408.811281 -418.330989) (xy 408.826638 -418.278687)
			(xy 408.849283 -418.229102) (xy 408.878753 -418.183245) (xy 408.91445 -418.142049) (xy 408.955647 -418.106352)
			(xy 409.001504 -418.076882) (xy 409.051088 -418.054237) (xy 409.103391 -418.03888) (xy 409.157347 -418.031123)
			(xy 409.184602 -418.03066) (xy 410.048202 -418.03066) (xy 410.075451 -418.03121) (xy 410.129394 -418.038966)
			(xy 410.181684 -418.05432) (xy 410.231257 -418.07696) (xy 410.277103 -418.106424) (xy 410.318289 -418.142112)
			(xy 410.353978 -418.183299) (xy 410.383441 -418.229145) (xy 410.40608 -418.278718) (xy 410.421434 -418.331008)
			(xy 410.42919 -418.384951) (xy 410.42919 -418.439449) (xy 410.429189 -418.439457) (xy 411.866723 -418.439457)
			(xy 411.866723 -418.384943) (xy 411.874482 -418.330984) (xy 411.889841 -418.278678) (xy 411.912489 -418.229091)
			(xy 411.941963 -418.183232) (xy 411.977664 -418.142035) (xy 412.018866 -418.106338) (xy 412.064728 -418.076869)
			(xy 412.114317 -418.054227) (xy 412.166625 -418.038873) (xy 412.220585 -418.03112) (xy 412.247842 -418.03066)
			(xy 413.111442 -418.03066) (xy 413.138689 -418.031213) (xy 413.192628 -418.038974) (xy 413.244913 -418.054331)
			(xy 413.294481 -418.076973) (xy 413.340322 -418.106438) (xy 413.381503 -418.142126) (xy 413.417187 -418.183312)
			(xy 413.446647 -418.229156) (xy 413.469283 -418.278727) (xy 413.484635 -418.331014) (xy 413.49239 -418.384953)
			(xy 413.49239 -418.439447) (xy 413.492389 -418.439453) (xy 414.930046 -418.439453) (xy 414.930046 -418.384947)
			(xy 414.937803 -418.330997) (xy 414.953158 -418.278699) (xy 414.9758 -418.229119) (xy 415.005267 -418.183265)
			(xy 415.040959 -418.142072) (xy 415.082151 -418.106378) (xy 415.128003 -418.076908) (xy 415.177582 -418.054264)
			(xy 415.229879 -418.038906) (xy 415.283829 -418.031147) (xy 415.311082 -418.03066) (xy 416.174682 -418.03066)
			(xy 416.201933 -418.031186) (xy 416.255882 -418.03894) (xy 416.308177 -418.054293) (xy 416.357756 -418.076933)
			(xy 416.403607 -418.106398) (xy 416.444799 -418.142089) (xy 416.480491 -418.183278) (xy 416.509958 -418.229129)
			(xy 416.5326 -418.278706) (xy 416.547956 -418.331001) (xy 416.555713 -418.384949) (xy 416.555713 -418.439451)
			(xy 416.555712 -418.439456) (xy 417.993223 -418.439456) (xy 417.993223 -418.384944) (xy 418.000981 -418.330986)
			(xy 418.01634 -418.278682) (xy 418.038986 -418.229097) (xy 418.068458 -418.183238) (xy 418.104157 -418.142042)
			(xy 418.145356 -418.106345) (xy 418.191216 -418.076875) (xy 418.240803 -418.054232) (xy 418.293108 -418.038877)
			(xy 418.347066 -418.031121) (xy 418.374322 -418.03066) (xy 419.237922 -418.03066) (xy 419.26517 -418.031212)
			(xy 419.319111 -418.03897) (xy 419.371398 -418.054326) (xy 419.420969 -418.076966) (xy 419.466812 -418.106431)
			(xy 419.507996 -418.142119) (xy 419.543683 -418.183305) (xy 419.573144 -418.229151) (xy 419.595782 -418.278722)
			(xy 419.611135 -418.331011) (xy 419.61889 -418.384952) (xy 419.61889 -418.439448) (xy 419.611135 -418.493389)
			(xy 419.595782 -418.545678) (xy 419.573144 -418.595249) (xy 419.543683 -418.641095) (xy 419.507996 -418.682281)
			(xy 419.466812 -418.717969) (xy 419.420969 -418.747434) (xy 419.371398 -418.770074) (xy 419.319111 -418.78543)
			(xy 419.26517 -418.793188) (xy 419.237922 -418.793676) (xy 418.374322 -418.793676) (xy 418.347066 -418.793279)
			(xy 418.293108 -418.785523) (xy 418.240803 -418.770168) (xy 418.191216 -418.747525) (xy 418.145356 -418.718055)
			(xy 418.104157 -418.682358) (xy 418.068458 -418.641162) (xy 418.038986 -418.595303) (xy 418.01634 -418.545718)
			(xy 418.000981 -418.493414) (xy 417.993223 -418.439456) (xy 416.555712 -418.439456) (xy 416.547956 -418.493399)
			(xy 416.5326 -418.545694) (xy 416.509958 -418.595271) (xy 416.480491 -418.641122) (xy 416.444799 -418.682311)
			(xy 416.403607 -418.718002) (xy 416.357756 -418.747467) (xy 416.308177 -418.770107) (xy 416.255882 -418.78546)
			(xy 416.201933 -418.793214) (xy 416.174682 -418.793676) (xy 415.311082 -418.793676) (xy 415.283829 -418.793253)
			(xy 415.229879 -418.785494) (xy 415.177582 -418.770136) (xy 415.128003 -418.747492) (xy 415.082151 -418.718022)
			(xy 415.040959 -418.682328) (xy 415.005267 -418.641135) (xy 414.9758 -418.595281) (xy 414.953158 -418.545701)
			(xy 414.937803 -418.493403) (xy 414.930046 -418.439453) (xy 413.492389 -418.439453) (xy 413.484635 -418.493386)
			(xy 413.469283 -418.545673) (xy 413.446647 -418.595244) (xy 413.417187 -418.641088) (xy 413.381503 -418.682274)
			(xy 413.340322 -418.717962) (xy 413.294481 -418.747427) (xy 413.244913 -418.770069) (xy 413.192628 -418.785426)
			(xy 413.138689 -418.793187) (xy 413.111442 -418.793676) (xy 412.247842 -418.793676) (xy 412.220585 -418.79328)
			(xy 412.166625 -418.785527) (xy 412.114317 -418.770173) (xy 412.064728 -418.747531) (xy 412.018866 -418.718062)
			(xy 411.977664 -418.682365) (xy 411.941963 -418.641168) (xy 411.912489 -418.595309) (xy 411.889841 -418.545722)
			(xy 411.874482 -418.493416) (xy 411.866723 -418.439457) (xy 410.429189 -418.439457) (xy 410.421434 -418.493392)
			(xy 410.40608 -418.545682) (xy 410.383441 -418.595255) (xy 410.353978 -418.641101) (xy 410.318289 -418.682288)
			(xy 410.277103 -418.717976) (xy 410.231257 -418.74744) (xy 410.181684 -418.77008) (xy 410.129394 -418.785434)
			(xy 410.075451 -418.79319) (xy 410.048202 -418.793676) (xy 409.184602 -418.793676) (xy 409.157347 -418.793277)
			(xy 409.103391 -418.78552) (xy 409.051088 -418.770163) (xy 409.001504 -418.747518) (xy 408.955647 -418.718048)
			(xy 408.91445 -418.682351) (xy 408.878753 -418.641155) (xy 408.849283 -418.595298) (xy 408.826638 -418.545713)
			(xy 408.811281 -418.493411) (xy 408.803523 -418.439455) (xy 407.366013 -418.439455) (xy 407.358255 -418.493402)
			(xy 407.342899 -418.545699) (xy 407.320255 -418.595277) (xy 407.290786 -418.641128) (xy 407.255091 -418.682318)
			(xy 407.213898 -418.718009) (xy 407.168044 -418.747474) (xy 407.118463 -418.770112) (xy 407.066165 -418.785463)
			(xy 407.012214 -418.793215) (xy 406.984962 -418.793676) (xy 406.121362 -418.793676) (xy 406.09411 -418.793252)
			(xy 406.040162 -418.78549) (xy 405.987868 -418.77013) (xy 405.938291 -418.747485) (xy 405.892441 -418.718015)
			(xy 405.851252 -418.682321) (xy 405.815562 -418.641128) (xy 405.786097 -418.595276) (xy 405.763456 -418.545697)
			(xy 405.748102 -418.493401) (xy 405.740346 -418.439452) (xy 404.302689 -418.439452) (xy 404.294935 -418.493389)
			(xy 404.279582 -418.545678) (xy 404.256944 -418.595249) (xy 404.227483 -418.641095) (xy 404.191796 -418.682281)
			(xy 404.150612 -418.717969) (xy 404.104769 -418.747434) (xy 404.055198 -418.770074) (xy 404.002911 -418.78543)
			(xy 403.94897 -418.793188) (xy 403.921722 -418.793676) (xy 403.058122 -418.793676) (xy 403.030866 -418.793279)
			(xy 402.976908 -418.785523) (xy 402.924603 -418.770168) (xy 402.875016 -418.747525) (xy 402.829156 -418.718055)
			(xy 402.787957 -418.682358) (xy 402.752258 -418.641162) (xy 402.722786 -418.595303) (xy 402.70014 -418.545718)
			(xy 402.684781 -418.493414) (xy 402.677023 -418.439456) (xy 401.239512 -418.439456) (xy 401.231756 -418.493399)
			(xy 401.2164 -418.545694) (xy 401.193758 -418.595271) (xy 401.164291 -418.641122) (xy 401.128599 -418.682311)
			(xy 401.087407 -418.718002) (xy 401.041556 -418.747467) (xy 400.991977 -418.770107) (xy 400.939682 -418.78546)
			(xy 400.885733 -418.793214) (xy 400.858482 -418.793676) (xy 399.994882 -418.793676) (xy 399.967629 -418.793253)
			(xy 399.913679 -418.785494) (xy 399.861382 -418.770136) (xy 399.811803 -418.747492) (xy 399.765951 -418.718022)
			(xy 399.724759 -418.682328) (xy 399.689067 -418.641135) (xy 399.6596 -418.595281) (xy 399.636958 -418.545701)
			(xy 399.621603 -418.493403) (xy 399.613846 -418.439453) (xy 398.176189 -418.439453) (xy 398.168435 -418.493386)
			(xy 398.153083 -418.545673) (xy 398.130447 -418.595244) (xy 398.100987 -418.641088) (xy 398.065303 -418.682274)
			(xy 398.024122 -418.717962) (xy 397.978281 -418.747427) (xy 397.928713 -418.770069) (xy 397.876428 -418.785426)
			(xy 397.822489 -418.793187) (xy 397.795242 -418.793676) (xy 396.931642 -418.793676) (xy 396.904385 -418.79328)
			(xy 396.850425 -418.785527) (xy 396.798117 -418.770173) (xy 396.748528 -418.747531) (xy 396.702666 -418.718062)
			(xy 396.661464 -418.682365) (xy 396.625763 -418.641168) (xy 396.596289 -418.595309) (xy 396.573641 -418.545722)
			(xy 396.558282 -418.493416) (xy 396.550523 -418.439457) (xy 395.112989 -418.439457) (xy 395.105234 -418.493392)
			(xy 395.08988 -418.545682) (xy 395.067241 -418.595255) (xy 395.037778 -418.641101) (xy 395.002089 -418.682288)
			(xy 394.960903 -418.717976) (xy 394.915057 -418.74744) (xy 394.865484 -418.77008) (xy 394.813194 -418.785434)
			(xy 394.759251 -418.79319) (xy 394.732002 -418.793676) (xy 393.868402 -418.793676) (xy 393.841147 -418.793277)
			(xy 393.787191 -418.78552) (xy 393.734888 -418.770163) (xy 393.685304 -418.747518) (xy 393.639447 -418.718048)
			(xy 393.59825 -418.682351) (xy 393.562553 -418.641155) (xy 393.533083 -418.595298) (xy 393.510438 -418.545713)
			(xy 393.495081 -418.493411) (xy 393.487323 -418.439455) (xy 392.049813 -418.439455) (xy 392.042055 -418.493402)
			(xy 392.026699 -418.545699) (xy 392.004055 -418.595277) (xy 391.974586 -418.641128) (xy 391.938891 -418.682318)
			(xy 391.897698 -418.718009) (xy 391.851844 -418.747474) (xy 391.802263 -418.770112) (xy 391.749965 -418.785463)
			(xy 391.696014 -418.793215) (xy 391.668762 -418.793676) (xy 390.805162 -418.793676) (xy 390.77791 -418.793252)
			(xy 390.723962 -418.78549) (xy 390.671668 -418.77013) (xy 390.622091 -418.747485) (xy 390.576241 -418.718015)
			(xy 390.535052 -418.682321) (xy 390.499362 -418.641128) (xy 390.469897 -418.595276) (xy 390.447256 -418.545697)
			(xy 390.431902 -418.493401) (xy 390.424146 -418.439452) (xy 388.986489 -418.439452) (xy 388.978735 -418.493389)
			(xy 388.963382 -418.545678) (xy 388.940744 -418.595249) (xy 388.911283 -418.641095) (xy 388.875596 -418.682281)
			(xy 388.834412 -418.717969) (xy 388.788569 -418.747434) (xy 388.738998 -418.770074) (xy 388.686711 -418.78543)
			(xy 388.63277 -418.793188) (xy 388.605522 -418.793676) (xy 387.741922 -418.793676) (xy 387.714666 -418.793279)
			(xy 387.660708 -418.785523) (xy 387.608403 -418.770168) (xy 387.558816 -418.747525) (xy 387.512956 -418.718055)
			(xy 387.471757 -418.682358) (xy 387.436058 -418.641162) (xy 387.406586 -418.595303) (xy 387.38394 -418.545718)
			(xy 387.368581 -418.493414) (xy 387.360823 -418.439456) (xy 385.923312 -418.439456) (xy 385.915556 -418.493399)
			(xy 385.9002 -418.545694) (xy 385.877558 -418.595271) (xy 385.848091 -418.641122) (xy 385.812399 -418.682311)
			(xy 385.771207 -418.718002) (xy 385.725356 -418.747467) (xy 385.675777 -418.770107) (xy 385.623482 -418.78546)
			(xy 385.569533 -418.793214) (xy 385.542282 -418.793676) (xy 384.678682 -418.793676) (xy 384.651429 -418.793253)
			(xy 384.597479 -418.785494) (xy 384.545182 -418.770136) (xy 384.495603 -418.747492) (xy 384.449751 -418.718022)
			(xy 384.408559 -418.682328) (xy 384.372867 -418.641135) (xy 384.3434 -418.595281) (xy 384.320758 -418.545701)
			(xy 384.305403 -418.493403) (xy 384.297646 -418.439453) (xy 382.859989 -418.439453) (xy 382.852235 -418.493386)
			(xy 382.836883 -418.545673) (xy 382.814247 -418.595244) (xy 382.784787 -418.641088) (xy 382.749103 -418.682274)
			(xy 382.707922 -418.717962) (xy 382.662081 -418.747427) (xy 382.612513 -418.770069) (xy 382.560228 -418.785426)
			(xy 382.506289 -418.793187) (xy 382.479042 -418.793676) (xy 381.615442 -418.793676) (xy 381.588185 -418.79328)
			(xy 381.534225 -418.785527) (xy 381.481917 -418.770173) (xy 381.432328 -418.747531) (xy 381.386466 -418.718062)
			(xy 381.345264 -418.682365) (xy 381.309563 -418.641168) (xy 381.280089 -418.595309) (xy 381.257441 -418.545722)
			(xy 381.242082 -418.493416) (xy 381.234323 -418.439457) (xy 379.796789 -418.439457) (xy 379.789034 -418.493392)
			(xy 379.77368 -418.545682) (xy 379.751041 -418.595255) (xy 379.721578 -418.641101) (xy 379.685889 -418.682288)
			(xy 379.644703 -418.717976) (xy 379.598857 -418.74744) (xy 379.549284 -418.77008) (xy 379.496994 -418.785434)
			(xy 379.443051 -418.79319) (xy 379.415802 -418.793676) (xy 378.552202 -418.793676) (xy 378.524947 -418.793277)
			(xy 378.470991 -418.78552) (xy 378.418688 -418.770163) (xy 378.369104 -418.747518) (xy 378.323247 -418.718048)
			(xy 378.28205 -418.682351) (xy 378.246353 -418.641155) (xy 378.216883 -418.595298) (xy 378.194238 -418.545713)
			(xy 378.178881 -418.493411) (xy 378.171123 -418.439455) (xy 376.733613 -418.439455) (xy 376.725855 -418.493402)
			(xy 376.710499 -418.545699) (xy 376.687855 -418.595277) (xy 376.658386 -418.641128) (xy 376.622691 -418.682318)
			(xy 376.581498 -418.718009) (xy 376.535644 -418.747474) (xy 376.486063 -418.770112) (xy 376.433765 -418.785463)
			(xy 376.379814 -418.793215) (xy 376.352562 -418.793676) (xy 375.488962 -418.793676) (xy 375.46171 -418.793252)
			(xy 375.407762 -418.78549) (xy 375.355468 -418.77013) (xy 375.305891 -418.747485) (xy 375.260041 -418.718015)
			(xy 375.218852 -418.682321) (xy 375.183162 -418.641128) (xy 375.153697 -418.595276) (xy 375.131056 -418.545697)
			(xy 375.115702 -418.493401) (xy 375.107946 -418.439452) (xy 373.670289 -418.439452) (xy 373.662535 -418.493389)
			(xy 373.647182 -418.545678) (xy 373.624544 -418.595249) (xy 373.595083 -418.641095) (xy 373.559396 -418.682281)
			(xy 373.518212 -418.717969) (xy 373.472369 -418.747434) (xy 373.422798 -418.770074) (xy 373.370511 -418.78543)
			(xy 373.31657 -418.793188) (xy 373.289322 -418.793676) (xy 372.425722 -418.793676) (xy 372.398466 -418.793279)
			(xy 372.344508 -418.785523) (xy 372.292203 -418.770168) (xy 372.242616 -418.747525) (xy 372.196756 -418.718055)
			(xy 372.155557 -418.682358) (xy 372.119858 -418.641162) (xy 372.090386 -418.595303) (xy 372.06774 -418.545718)
			(xy 372.052381 -418.493414) (xy 372.044623 -418.439456) (xy 370.313204 -418.439456) (xy 370.313204 -420.739316)
			(xy 370.16182 -420.739316) (xy 370.150859 -420.741086) (xy 370.131853 -420.752509) (xy 370.11943 -420.770877)
			(xy 370.117116 -420.781734) (xy 370.117116 -420.979455) (xy 370.513023 -420.979455) (xy 370.513023 -420.924945)
			(xy 370.520781 -420.870989) (xy 370.536138 -420.818687) (xy 370.558783 -420.769102) (xy 370.588253 -420.723245)
			(xy 370.62395 -420.682049) (xy 370.665147 -420.646352) (xy 370.711004 -420.616882) (xy 370.760588 -420.594237)
			(xy 370.812891 -420.57888) (xy 370.866847 -420.571123) (xy 370.894102 -420.57066) (xy 371.757702 -420.57066)
			(xy 371.784951 -420.57121) (xy 371.838894 -420.578966) (xy 371.891184 -420.59432) (xy 371.940757 -420.61696)
			(xy 371.986603 -420.646424) (xy 372.027789 -420.682112) (xy 372.063478 -420.723299) (xy 372.092941 -420.769145)
			(xy 372.11558 -420.818718) (xy 372.130934 -420.871008) (xy 372.13869 -420.924951) (xy 372.13869 -420.979449)
			(xy 372.138689 -420.979457) (xy 373.576223 -420.979457) (xy 373.576223 -420.924943) (xy 373.583982 -420.870984)
			(xy 373.599341 -420.818678) (xy 373.621989 -420.769091) (xy 373.651463 -420.723232) (xy 373.687164 -420.682035)
			(xy 373.728366 -420.646338) (xy 373.774228 -420.616869) (xy 373.823817 -420.594227) (xy 373.876125 -420.578873)
			(xy 373.930085 -420.57112) (xy 373.957342 -420.57066) (xy 374.820942 -420.57066) (xy 374.848189 -420.571213)
			(xy 374.902128 -420.578974) (xy 374.954413 -420.594331) (xy 375.003981 -420.616973) (xy 375.049822 -420.646438)
			(xy 375.091003 -420.682126) (xy 375.126687 -420.723312) (xy 375.156147 -420.769156) (xy 375.178783 -420.818727)
			(xy 375.194135 -420.871014) (xy 375.20189 -420.924953) (xy 375.20189 -420.979447) (xy 375.201889 -420.979453)
			(xy 376.639546 -420.979453) (xy 376.639546 -420.924947) (xy 376.647303 -420.870997) (xy 376.662658 -420.818699)
			(xy 376.6853 -420.769119) (xy 376.714767 -420.723265) (xy 376.750459 -420.682072) (xy 376.791651 -420.646378)
			(xy 376.837503 -420.616908) (xy 376.887082 -420.594264) (xy 376.939379 -420.578906) (xy 376.993329 -420.571147)
			(xy 377.020582 -420.57066) (xy 377.884182 -420.57066) (xy 377.911433 -420.571186) (xy 377.965382 -420.57894)
			(xy 378.017677 -420.594293) (xy 378.067256 -420.616933) (xy 378.113107 -420.646398) (xy 378.154299 -420.682089)
			(xy 378.189991 -420.723278) (xy 378.219458 -420.769129) (xy 378.2421 -420.818706) (xy 378.257456 -420.871001)
			(xy 378.265213 -420.924949) (xy 378.265213 -420.979451) (xy 378.265212 -420.979456) (xy 379.702723 -420.979456)
			(xy 379.702723 -420.924944) (xy 379.710481 -420.870986) (xy 379.72584 -420.818682) (xy 379.748486 -420.769097)
			(xy 379.777958 -420.723238) (xy 379.813657 -420.682042) (xy 379.854856 -420.646345) (xy 379.900716 -420.616875)
			(xy 379.950303 -420.594232) (xy 380.002608 -420.578877) (xy 380.056566 -420.571121) (xy 380.083822 -420.57066)
			(xy 380.947422 -420.57066) (xy 380.97467 -420.571212) (xy 381.028611 -420.57897) (xy 381.080898 -420.594326)
			(xy 381.130469 -420.616966) (xy 381.176312 -420.646431) (xy 381.217496 -420.682119) (xy 381.253183 -420.723305)
			(xy 381.282644 -420.769151) (xy 381.305282 -420.818722) (xy 381.320635 -420.871011) (xy 381.32839 -420.924952)
			(xy 381.32839 -420.979448) (xy 381.328389 -420.979452) (xy 382.766046 -420.979452) (xy 382.766046 -420.924948)
			(xy 382.773802 -420.870999) (xy 382.789156 -420.818703) (xy 382.811797 -420.769124) (xy 382.841262 -420.723272)
			(xy 382.876952 -420.682079) (xy 382.918141 -420.646385) (xy 382.963991 -420.616915) (xy 383.013568 -420.59427)
			(xy 383.065862 -420.57891) (xy 383.11981 -420.571148) (xy 383.147062 -420.57066) (xy 384.010662 -420.57066)
			(xy 384.037914 -420.571185) (xy 384.091865 -420.578937) (xy 384.144163 -420.594288) (xy 384.193744 -420.616926)
			(xy 384.239598 -420.646391) (xy 384.280791 -420.682082) (xy 384.316486 -420.723272) (xy 384.345955 -420.769123)
			(xy 384.368599 -420.818701) (xy 384.383955 -420.870998) (xy 384.391713 -420.924948) (xy 384.391713 -420.979452)
			(xy 384.391713 -420.979455) (xy 385.829223 -420.979455) (xy 385.829223 -420.924945) (xy 385.836981 -420.870989)
			(xy 385.852338 -420.818687) (xy 385.874983 -420.769102) (xy 385.904453 -420.723245) (xy 385.94015 -420.682049)
			(xy 385.981347 -420.646352) (xy 386.027204 -420.616882) (xy 386.076788 -420.594237) (xy 386.129091 -420.57888)
			(xy 386.183047 -420.571123) (xy 386.210302 -420.57066) (xy 387.073902 -420.57066) (xy 387.101151 -420.57121)
			(xy 387.155094 -420.578966) (xy 387.207384 -420.59432) (xy 387.256957 -420.61696) (xy 387.302803 -420.646424)
			(xy 387.343989 -420.682112) (xy 387.379678 -420.723299) (xy 387.409141 -420.769145) (xy 387.43178 -420.818718)
			(xy 387.447134 -420.871008) (xy 387.45489 -420.924951) (xy 387.45489 -420.979449) (xy 387.454889 -420.979457)
			(xy 388.892423 -420.979457) (xy 388.892423 -420.924943) (xy 388.900182 -420.870984) (xy 388.915541 -420.818678)
			(xy 388.938189 -420.769091) (xy 388.967663 -420.723232) (xy 389.003364 -420.682035) (xy 389.044566 -420.646338)
			(xy 389.090428 -420.616869) (xy 389.140017 -420.594227) (xy 389.192325 -420.578873) (xy 389.246285 -420.57112)
			(xy 389.273542 -420.57066) (xy 390.137142 -420.57066) (xy 390.164389 -420.571213) (xy 390.218328 -420.578974)
			(xy 390.270613 -420.594331) (xy 390.320181 -420.616973) (xy 390.366022 -420.646438) (xy 390.407203 -420.682126)
			(xy 390.442887 -420.723312) (xy 390.472347 -420.769156) (xy 390.494983 -420.818727) (xy 390.510335 -420.871014)
			(xy 390.51809 -420.924953) (xy 390.51809 -420.979447) (xy 390.518089 -420.979453) (xy 391.955746 -420.979453)
			(xy 391.955746 -420.924947) (xy 391.963503 -420.870997) (xy 391.978858 -420.818699) (xy 392.0015 -420.769119)
			(xy 392.030967 -420.723265) (xy 392.066659 -420.682072) (xy 392.107851 -420.646378) (xy 392.153703 -420.616908)
			(xy 392.203282 -420.594264) (xy 392.255579 -420.578906) (xy 392.309529 -420.571147) (xy 392.336782 -420.57066)
			(xy 393.200382 -420.57066) (xy 393.227633 -420.571186) (xy 393.281582 -420.57894) (xy 393.333877 -420.594293)
			(xy 393.383456 -420.616933) (xy 393.429307 -420.646398) (xy 393.470499 -420.682089) (xy 393.506191 -420.723278)
			(xy 393.535658 -420.769129) (xy 393.5583 -420.818706) (xy 393.573656 -420.871001) (xy 393.581413 -420.924949)
			(xy 393.581413 -420.979451) (xy 393.581412 -420.979456) (xy 395.018923 -420.979456) (xy 395.018923 -420.924944)
			(xy 395.026681 -420.870986) (xy 395.04204 -420.818682) (xy 395.064686 -420.769097) (xy 395.094158 -420.723238)
			(xy 395.129857 -420.682042) (xy 395.171056 -420.646345) (xy 395.216916 -420.616875) (xy 395.266503 -420.594232)
			(xy 395.318808 -420.578877) (xy 395.372766 -420.571121) (xy 395.400022 -420.57066) (xy 396.263622 -420.57066)
			(xy 396.29087 -420.571212) (xy 396.344811 -420.57897) (xy 396.397098 -420.594326) (xy 396.446669 -420.616966)
			(xy 396.492512 -420.646431) (xy 396.533696 -420.682119) (xy 396.569383 -420.723305) (xy 396.598844 -420.769151)
			(xy 396.621482 -420.818722) (xy 396.636835 -420.871011) (xy 396.64459 -420.924952) (xy 396.64459 -420.979448)
			(xy 396.644589 -420.979452) (xy 398.082246 -420.979452) (xy 398.082246 -420.924948) (xy 398.090002 -420.870999)
			(xy 398.105356 -420.818703) (xy 398.127997 -420.769124) (xy 398.157462 -420.723272) (xy 398.193152 -420.682079)
			(xy 398.234341 -420.646385) (xy 398.280191 -420.616915) (xy 398.329768 -420.59427) (xy 398.382062 -420.57891)
			(xy 398.43601 -420.571148) (xy 398.463262 -420.57066) (xy 399.326862 -420.57066) (xy 399.354114 -420.571185)
			(xy 399.408065 -420.578937) (xy 399.460363 -420.594288) (xy 399.509944 -420.616926) (xy 399.555798 -420.646391)
			(xy 399.596991 -420.682082) (xy 399.632686 -420.723272) (xy 399.662155 -420.769123) (xy 399.684799 -420.818701)
			(xy 399.700155 -420.870998) (xy 399.707913 -420.924948) (xy 399.707913 -420.979452) (xy 399.707913 -420.979455)
			(xy 401.145423 -420.979455) (xy 401.145423 -420.924945) (xy 401.153181 -420.870989) (xy 401.168538 -420.818687)
			(xy 401.191183 -420.769102) (xy 401.220653 -420.723245) (xy 401.25635 -420.682049) (xy 401.297547 -420.646352)
			(xy 401.343404 -420.616882) (xy 401.392988 -420.594237) (xy 401.445291 -420.57888) (xy 401.499247 -420.571123)
			(xy 401.526502 -420.57066) (xy 402.390102 -420.57066) (xy 402.417351 -420.57121) (xy 402.471294 -420.578966)
			(xy 402.523584 -420.59432) (xy 402.573157 -420.61696) (xy 402.619003 -420.646424) (xy 402.660189 -420.682112)
			(xy 402.695878 -420.723299) (xy 402.725341 -420.769145) (xy 402.74798 -420.818718) (xy 402.763334 -420.871008)
			(xy 402.77109 -420.924951) (xy 402.77109 -420.979449) (xy 402.771089 -420.979457) (xy 404.208623 -420.979457)
			(xy 404.208623 -420.924943) (xy 404.216382 -420.870984) (xy 404.231741 -420.818678) (xy 404.254389 -420.769091)
			(xy 404.283863 -420.723232) (xy 404.319564 -420.682035) (xy 404.360766 -420.646338) (xy 404.406628 -420.616869)
			(xy 404.456217 -420.594227) (xy 404.508525 -420.578873) (xy 404.562485 -420.57112) (xy 404.589742 -420.57066)
			(xy 405.453342 -420.57066) (xy 405.480589 -420.571213) (xy 405.534528 -420.578974) (xy 405.586813 -420.594331)
			(xy 405.636381 -420.616973) (xy 405.682222 -420.646438) (xy 405.723403 -420.682126) (xy 405.759087 -420.723312)
			(xy 405.788547 -420.769156) (xy 405.811183 -420.818727) (xy 405.826535 -420.871014) (xy 405.83429 -420.924953)
			(xy 405.83429 -420.979447) (xy 405.834289 -420.979453) (xy 407.271946 -420.979453) (xy 407.271946 -420.924947)
			(xy 407.279703 -420.870997) (xy 407.295058 -420.818699) (xy 407.3177 -420.769119) (xy 407.347167 -420.723265)
			(xy 407.382859 -420.682072) (xy 407.424051 -420.646378) (xy 407.469903 -420.616908) (xy 407.519482 -420.594264)
			(xy 407.571779 -420.578906) (xy 407.625729 -420.571147) (xy 407.652982 -420.57066) (xy 408.516582 -420.57066)
			(xy 408.543833 -420.571186) (xy 408.597782 -420.57894) (xy 408.650077 -420.594293) (xy 408.699656 -420.616933)
			(xy 408.745507 -420.646398) (xy 408.786699 -420.682089) (xy 408.822391 -420.723278) (xy 408.851858 -420.769129)
			(xy 408.8745 -420.818706) (xy 408.889856 -420.871001) (xy 408.897613 -420.924949) (xy 408.897613 -420.979451)
			(xy 408.897612 -420.979456) (xy 410.335123 -420.979456) (xy 410.335123 -420.924944) (xy 410.342881 -420.870986)
			(xy 410.35824 -420.818682) (xy 410.380886 -420.769097) (xy 410.410358 -420.723238) (xy 410.446057 -420.682042)
			(xy 410.487256 -420.646345) (xy 410.533116 -420.616875) (xy 410.582703 -420.594232) (xy 410.635008 -420.578877)
			(xy 410.688966 -420.571121) (xy 410.716222 -420.57066) (xy 411.579822 -420.57066) (xy 411.60707 -420.571212)
			(xy 411.661011 -420.57897) (xy 411.713298 -420.594326) (xy 411.762869 -420.616966) (xy 411.808712 -420.646431)
			(xy 411.849896 -420.682119) (xy 411.885583 -420.723305) (xy 411.915044 -420.769151) (xy 411.937682 -420.818722)
			(xy 411.953035 -420.871011) (xy 411.96079 -420.924952) (xy 411.96079 -420.979448) (xy 411.960789 -420.979452)
			(xy 413.398446 -420.979452) (xy 413.398446 -420.924948) (xy 413.406202 -420.870999) (xy 413.421556 -420.818703)
			(xy 413.444197 -420.769124) (xy 413.473662 -420.723272) (xy 413.509352 -420.682079) (xy 413.550541 -420.646385)
			(xy 413.596391 -420.616915) (xy 413.645968 -420.59427) (xy 413.698262 -420.57891) (xy 413.75221 -420.571148)
			(xy 413.779462 -420.57066) (xy 414.643062 -420.57066) (xy 414.670314 -420.571185) (xy 414.724265 -420.578937)
			(xy 414.776563 -420.594288) (xy 414.826144 -420.616926) (xy 414.871998 -420.646391) (xy 414.913191 -420.682082)
			(xy 414.948886 -420.723272) (xy 414.978355 -420.769123) (xy 415.000999 -420.818701) (xy 415.016355 -420.870998)
			(xy 415.024113 -420.924948) (xy 415.024113 -420.979452) (xy 415.024113 -420.979455) (xy 416.461623 -420.979455)
			(xy 416.461623 -420.924945) (xy 416.469381 -420.870989) (xy 416.484738 -420.818687) (xy 416.507383 -420.769102)
			(xy 416.536853 -420.723245) (xy 416.57255 -420.682049) (xy 416.613747 -420.646352) (xy 416.659604 -420.616882)
			(xy 416.709188 -420.594237) (xy 416.761491 -420.57888) (xy 416.815447 -420.571123) (xy 416.842702 -420.57066)
			(xy 417.706302 -420.57066) (xy 417.733551 -420.57121) (xy 417.787494 -420.578966) (xy 417.839784 -420.59432)
			(xy 417.889357 -420.61696) (xy 417.935203 -420.646424) (xy 417.976389 -420.682112) (xy 418.012078 -420.723299)
			(xy 418.041541 -420.769145) (xy 418.06418 -420.818718) (xy 418.079534 -420.871008) (xy 418.08729 -420.924951)
			(xy 418.08729 -420.979449) (xy 418.079534 -421.033392) (xy 418.06418 -421.085682) (xy 418.041541 -421.135255)
			(xy 418.012078 -421.181101) (xy 417.976389 -421.222288) (xy 417.935203 -421.257976) (xy 417.889357 -421.28744)
			(xy 417.839784 -421.31008) (xy 417.787494 -421.325434) (xy 417.733551 -421.33319) (xy 417.706302 -421.333676)
			(xy 416.842702 -421.333676) (xy 416.815447 -421.333277) (xy 416.761491 -421.32552) (xy 416.709188 -421.310163)
			(xy 416.659604 -421.287518) (xy 416.613747 -421.258048) (xy 416.57255 -421.222351) (xy 416.536853 -421.181155)
			(xy 416.507383 -421.135298) (xy 416.484738 -421.085713) (xy 416.469381 -421.033411) (xy 416.461623 -420.979455)
			(xy 415.024113 -420.979455) (xy 415.016355 -421.033402) (xy 415.000999 -421.085699) (xy 414.978355 -421.135277)
			(xy 414.948886 -421.181128) (xy 414.913191 -421.222318) (xy 414.871998 -421.258009) (xy 414.826144 -421.287474)
			(xy 414.776563 -421.310112) (xy 414.724265 -421.325463) (xy 414.670314 -421.333215) (xy 414.643062 -421.333676)
			(xy 413.779462 -421.333676) (xy 413.75221 -421.333252) (xy 413.698262 -421.32549) (xy 413.645968 -421.31013)
			(xy 413.596391 -421.287485) (xy 413.550541 -421.258015) (xy 413.509352 -421.222321) (xy 413.473662 -421.181128)
			(xy 413.444197 -421.135276) (xy 413.421556 -421.085697) (xy 413.406202 -421.033401) (xy 413.398446 -420.979452)
			(xy 411.960789 -420.979452) (xy 411.953035 -421.033389) (xy 411.937682 -421.085678) (xy 411.915044 -421.135249)
			(xy 411.885583 -421.181095) (xy 411.849896 -421.222281) (xy 411.808712 -421.257969) (xy 411.762869 -421.287434)
			(xy 411.713298 -421.310074) (xy 411.661011 -421.32543) (xy 411.60707 -421.333188) (xy 411.579822 -421.333676)
			(xy 410.716222 -421.333676) (xy 410.688966 -421.333279) (xy 410.635008 -421.325523) (xy 410.582703 -421.310168)
			(xy 410.533116 -421.287525) (xy 410.487256 -421.258055) (xy 410.446057 -421.222358) (xy 410.410358 -421.181162)
			(xy 410.380886 -421.135303) (xy 410.35824 -421.085718) (xy 410.342881 -421.033414) (xy 410.335123 -420.979456)
			(xy 408.897612 -420.979456) (xy 408.889856 -421.033399) (xy 408.8745 -421.085694) (xy 408.851858 -421.135271)
			(xy 408.822391 -421.181122) (xy 408.786699 -421.222311) (xy 408.745507 -421.258002) (xy 408.699656 -421.287467)
			(xy 408.650077 -421.310107) (xy 408.597782 -421.32546) (xy 408.543833 -421.333214) (xy 408.516582 -421.333676)
			(xy 407.652982 -421.333676) (xy 407.625729 -421.333253) (xy 407.571779 -421.325494) (xy 407.519482 -421.310136)
			(xy 407.469903 -421.287492) (xy 407.424051 -421.258022) (xy 407.382859 -421.222328) (xy 407.347167 -421.181135)
			(xy 407.3177 -421.135281) (xy 407.295058 -421.085701) (xy 407.279703 -421.033403) (xy 407.271946 -420.979453)
			(xy 405.834289 -420.979453) (xy 405.826535 -421.033386) (xy 405.811183 -421.085673) (xy 405.788547 -421.135244)
			(xy 405.759087 -421.181088) (xy 405.723403 -421.222274) (xy 405.682222 -421.257962) (xy 405.636381 -421.287427)
			(xy 405.586813 -421.310069) (xy 405.534528 -421.325426) (xy 405.480589 -421.333187) (xy 405.453342 -421.333676)
			(xy 404.589742 -421.333676) (xy 404.562485 -421.33328) (xy 404.508525 -421.325527) (xy 404.456217 -421.310173)
			(xy 404.406628 -421.287531) (xy 404.360766 -421.258062) (xy 404.319564 -421.222365) (xy 404.283863 -421.181168)
			(xy 404.254389 -421.135309) (xy 404.231741 -421.085722) (xy 404.216382 -421.033416) (xy 404.208623 -420.979457)
			(xy 402.771089 -420.979457) (xy 402.763334 -421.033392) (xy 402.74798 -421.085682) (xy 402.725341 -421.135255)
			(xy 402.695878 -421.181101) (xy 402.660189 -421.222288) (xy 402.619003 -421.257976) (xy 402.573157 -421.28744)
			(xy 402.523584 -421.31008) (xy 402.471294 -421.325434) (xy 402.417351 -421.33319) (xy 402.390102 -421.333676)
			(xy 401.526502 -421.333676) (xy 401.499247 -421.333277) (xy 401.445291 -421.32552) (xy 401.392988 -421.310163)
			(xy 401.343404 -421.287518) (xy 401.297547 -421.258048) (xy 401.25635 -421.222351) (xy 401.220653 -421.181155)
			(xy 401.191183 -421.135298) (xy 401.168538 -421.085713) (xy 401.153181 -421.033411) (xy 401.145423 -420.979455)
			(xy 399.707913 -420.979455) (xy 399.700155 -421.033402) (xy 399.684799 -421.085699) (xy 399.662155 -421.135277)
			(xy 399.632686 -421.181128) (xy 399.596991 -421.222318) (xy 399.555798 -421.258009) (xy 399.509944 -421.287474)
			(xy 399.460363 -421.310112) (xy 399.408065 -421.325463) (xy 399.354114 -421.333215) (xy 399.326862 -421.333676)
			(xy 398.463262 -421.333676) (xy 398.43601 -421.333252) (xy 398.382062 -421.32549) (xy 398.329768 -421.31013)
			(xy 398.280191 -421.287485) (xy 398.234341 -421.258015) (xy 398.193152 -421.222321) (xy 398.157462 -421.181128)
			(xy 398.127997 -421.135276) (xy 398.105356 -421.085697) (xy 398.090002 -421.033401) (xy 398.082246 -420.979452)
			(xy 396.644589 -420.979452) (xy 396.636835 -421.033389) (xy 396.621482 -421.085678) (xy 396.598844 -421.135249)
			(xy 396.569383 -421.181095) (xy 396.533696 -421.222281) (xy 396.492512 -421.257969) (xy 396.446669 -421.287434)
			(xy 396.397098 -421.310074) (xy 396.344811 -421.32543) (xy 396.29087 -421.333188) (xy 396.263622 -421.333676)
			(xy 395.400022 -421.333676) (xy 395.372766 -421.333279) (xy 395.318808 -421.325523) (xy 395.266503 -421.310168)
			(xy 395.216916 -421.287525) (xy 395.171056 -421.258055) (xy 395.129857 -421.222358) (xy 395.094158 -421.181162)
			(xy 395.064686 -421.135303) (xy 395.04204 -421.085718) (xy 395.026681 -421.033414) (xy 395.018923 -420.979456)
			(xy 393.581412 -420.979456) (xy 393.573656 -421.033399) (xy 393.5583 -421.085694) (xy 393.535658 -421.135271)
			(xy 393.506191 -421.181122) (xy 393.470499 -421.222311) (xy 393.429307 -421.258002) (xy 393.383456 -421.287467)
			(xy 393.333877 -421.310107) (xy 393.281582 -421.32546) (xy 393.227633 -421.333214) (xy 393.200382 -421.333676)
			(xy 392.336782 -421.333676) (xy 392.309529 -421.333253) (xy 392.255579 -421.325494) (xy 392.203282 -421.310136)
			(xy 392.153703 -421.287492) (xy 392.107851 -421.258022) (xy 392.066659 -421.222328) (xy 392.030967 -421.181135)
			(xy 392.0015 -421.135281) (xy 391.978858 -421.085701) (xy 391.963503 -421.033403) (xy 391.955746 -420.979453)
			(xy 390.518089 -420.979453) (xy 390.510335 -421.033386) (xy 390.494983 -421.085673) (xy 390.472347 -421.135244)
			(xy 390.442887 -421.181088) (xy 390.407203 -421.222274) (xy 390.366022 -421.257962) (xy 390.320181 -421.287427)
			(xy 390.270613 -421.310069) (xy 390.218328 -421.325426) (xy 390.164389 -421.333187) (xy 390.137142 -421.333676)
			(xy 389.273542 -421.333676) (xy 389.246285 -421.33328) (xy 389.192325 -421.325527) (xy 389.140017 -421.310173)
			(xy 389.090428 -421.287531) (xy 389.044566 -421.258062) (xy 389.003364 -421.222365) (xy 388.967663 -421.181168)
			(xy 388.938189 -421.135309) (xy 388.915541 -421.085722) (xy 388.900182 -421.033416) (xy 388.892423 -420.979457)
			(xy 387.454889 -420.979457) (xy 387.447134 -421.033392) (xy 387.43178 -421.085682) (xy 387.409141 -421.135255)
			(xy 387.379678 -421.181101) (xy 387.343989 -421.222288) (xy 387.302803 -421.257976) (xy 387.256957 -421.28744)
			(xy 387.207384 -421.31008) (xy 387.155094 -421.325434) (xy 387.101151 -421.33319) (xy 387.073902 -421.333676)
			(xy 386.210302 -421.333676) (xy 386.183047 -421.333277) (xy 386.129091 -421.32552) (xy 386.076788 -421.310163)
			(xy 386.027204 -421.287518) (xy 385.981347 -421.258048) (xy 385.94015 -421.222351) (xy 385.904453 -421.181155)
			(xy 385.874983 -421.135298) (xy 385.852338 -421.085713) (xy 385.836981 -421.033411) (xy 385.829223 -420.979455)
			(xy 384.391713 -420.979455) (xy 384.383955 -421.033402) (xy 384.368599 -421.085699) (xy 384.345955 -421.135277)
			(xy 384.316486 -421.181128) (xy 384.280791 -421.222318) (xy 384.239598 -421.258009) (xy 384.193744 -421.287474)
			(xy 384.144163 -421.310112) (xy 384.091865 -421.325463) (xy 384.037914 -421.333215) (xy 384.010662 -421.333676)
			(xy 383.147062 -421.333676) (xy 383.11981 -421.333252) (xy 383.065862 -421.32549) (xy 383.013568 -421.31013)
			(xy 382.963991 -421.287485) (xy 382.918141 -421.258015) (xy 382.876952 -421.222321) (xy 382.841262 -421.181128)
			(xy 382.811797 -421.135276) (xy 382.789156 -421.085697) (xy 382.773802 -421.033401) (xy 382.766046 -420.979452)
			(xy 381.328389 -420.979452) (xy 381.320635 -421.033389) (xy 381.305282 -421.085678) (xy 381.282644 -421.135249)
			(xy 381.253183 -421.181095) (xy 381.217496 -421.222281) (xy 381.176312 -421.257969) (xy 381.130469 -421.287434)
			(xy 381.080898 -421.310074) (xy 381.028611 -421.32543) (xy 380.97467 -421.333188) (xy 380.947422 -421.333676)
			(xy 380.083822 -421.333676) (xy 380.056566 -421.333279) (xy 380.002608 -421.325523) (xy 379.950303 -421.310168)
			(xy 379.900716 -421.287525) (xy 379.854856 -421.258055) (xy 379.813657 -421.222358) (xy 379.777958 -421.181162)
			(xy 379.748486 -421.135303) (xy 379.72584 -421.085718) (xy 379.710481 -421.033414) (xy 379.702723 -420.979456)
			(xy 378.265212 -420.979456) (xy 378.257456 -421.033399) (xy 378.2421 -421.085694) (xy 378.219458 -421.135271)
			(xy 378.189991 -421.181122) (xy 378.154299 -421.222311) (xy 378.113107 -421.258002) (xy 378.067256 -421.287467)
			(xy 378.017677 -421.310107) (xy 377.965382 -421.32546) (xy 377.911433 -421.333214) (xy 377.884182 -421.333676)
			(xy 377.020582 -421.333676) (xy 376.993329 -421.333253) (xy 376.939379 -421.325494) (xy 376.887082 -421.310136)
			(xy 376.837503 -421.287492) (xy 376.791651 -421.258022) (xy 376.750459 -421.222328) (xy 376.714767 -421.181135)
			(xy 376.6853 -421.135281) (xy 376.662658 -421.085701) (xy 376.647303 -421.033403) (xy 376.639546 -420.979453)
			(xy 375.201889 -420.979453) (xy 375.194135 -421.033386) (xy 375.178783 -421.085673) (xy 375.156147 -421.135244)
			(xy 375.126687 -421.181088) (xy 375.091003 -421.222274) (xy 375.049822 -421.257962) (xy 375.003981 -421.287427)
			(xy 374.954413 -421.310069) (xy 374.902128 -421.325426) (xy 374.848189 -421.333187) (xy 374.820942 -421.333676)
			(xy 373.957342 -421.333676) (xy 373.930085 -421.33328) (xy 373.876125 -421.325527) (xy 373.823817 -421.310173)
			(xy 373.774228 -421.287531) (xy 373.728366 -421.258062) (xy 373.687164 -421.222365) (xy 373.651463 -421.181168)
			(xy 373.621989 -421.135309) (xy 373.599341 -421.085722) (xy 373.583982 -421.033416) (xy 373.576223 -420.979457)
			(xy 372.138689 -420.979457) (xy 372.130934 -421.033392) (xy 372.11558 -421.085682) (xy 372.092941 -421.135255)
			(xy 372.063478 -421.181101) (xy 372.027789 -421.222288) (xy 371.986603 -421.257976) (xy 371.940757 -421.28744)
			(xy 371.891184 -421.31008) (xy 371.838894 -421.325434) (xy 371.784951 -421.33319) (xy 371.757702 -421.333676)
			(xy 370.894102 -421.333676) (xy 370.866847 -421.333277) (xy 370.812891 -421.32552) (xy 370.760588 -421.310163)
			(xy 370.711004 -421.287518) (xy 370.665147 -421.258048) (xy 370.62395 -421.222351) (xy 370.588253 -421.181155)
			(xy 370.558783 -421.135298) (xy 370.536138 -421.085713) (xy 370.520781 -421.033411) (xy 370.513023 -420.979455)
			(xy 370.117116 -420.979455) (xy 370.117116 -421.136826) (xy 370.119466 -421.147668) (xy 370.131899 -421.166013)
			(xy 370.150869 -421.17747) (xy 370.16182 -421.179244) (xy 370.313204 -421.179244) (xy 370.313204 -422.692576)
			(xy 370.312768 -422.702798) (xy 370.30495 -422.721687) (xy 370.290497 -422.736144) (xy 370.27161 -422.743966)
			(xy 370.261388 -422.744392) (xy 365.362744 -422.744392) (xy 365.352522 -422.743952) (xy 365.333631 -422.736138)
			(xy 365.319173 -422.721686) (xy 365.311352 -422.702798) (xy 365.310928 -422.692576) (xy 360.222212 -422.692576)
			(xy 360.286426 -422.706639) (xy 360.410636 -422.74198) (xy 360.532435 -422.7849) (xy 360.65136 -422.835237)
			(xy 360.766961 -422.892799) (xy 360.8788 -422.957369) (xy 360.986451 -423.028701) (xy 361.089506 -423.106525)
			(xy 361.187576 -423.190546) (xy 361.280287 -423.280445) (xy 361.367287 -423.37588) (xy 361.448248 -423.47649)
			(xy 361.505055 -423.556738) (xy 456.285335 -423.556738) (xy 456.285335 -423.427598) (xy 456.293285 -423.298703)
			(xy 456.309155 -423.170543) (xy 456.332884 -423.043602) (xy 456.364383 -422.918363) (xy 456.403532 -422.7953)
			(xy 456.450183 -422.674881) (xy 456.504158 -422.557562) (xy 456.565253 -422.443788) (xy 456.633236 -422.333991)
			(xy 456.70785 -422.228588) (xy 456.788811 -422.127978) (xy 456.875811 -422.032543) (xy 456.968522 -421.942644)
			(xy 457.066592 -421.858623) (xy 457.169647 -421.780799) (xy 457.277298 -421.709467) (xy 457.389137 -421.644897)
			(xy 457.504738 -421.587335) (xy 457.623663 -421.536998) (xy 457.745462 -421.494078) (xy 457.869672 -421.458737)
			(xy 457.995821 -421.43111) (xy 458.123433 -421.411301) (xy 458.252022 -421.399385) (xy 458.3811 -421.395409)
			(xy 458.510178 -421.399385) (xy 458.638767 -421.411301) (xy 458.766379 -421.43111) (xy 458.892528 -421.458737)
			(xy 459.016738 -421.494078) (xy 459.138537 -421.536998) (xy 459.257462 -421.587335) (xy 459.373063 -421.644897)
			(xy 459.484902 -421.709467) (xy 459.592553 -421.780799) (xy 459.695608 -421.858623) (xy 459.793678 -421.942644)
			(xy 459.886389 -422.032543) (xy 459.973389 -422.127978) (xy 460.05435 -422.228588) (xy 460.128964 -422.333991)
			(xy 460.196947 -422.443788) (xy 460.258042 -422.557562) (xy 460.312017 -422.674881) (xy 460.358668 -422.7953)
			(xy 460.397817 -422.918363) (xy 460.429316 -423.043602) (xy 460.453045 -423.170543) (xy 460.468915 -423.298703)
			(xy 460.476865 -423.427598) (xy 460.477362 -423.492168) (xy 460.476865 -423.556738) (xy 460.468915 -423.685633)
			(xy 460.453045 -423.813793) (xy 460.429316 -423.940734) (xy 460.397817 -424.065973) (xy 460.358668 -424.189036)
			(xy 460.312017 -424.309455) (xy 460.258042 -424.426774) (xy 460.196947 -424.540548) (xy 460.128964 -424.650345)
			(xy 460.05435 -424.755748) (xy 459.973389 -424.856358) (xy 459.886389 -424.951793) (xy 459.793678 -425.041692)
			(xy 459.695608 -425.125713) (xy 459.592553 -425.203537) (xy 459.484902 -425.274869) (xy 459.373063 -425.339439)
			(xy 459.257462 -425.397001) (xy 459.138537 -425.447338) (xy 459.016738 -425.490258) (xy 458.892528 -425.525599)
			(xy 458.766379 -425.553226) (xy 458.638767 -425.573035) (xy 458.510178 -425.584951) (xy 458.3811 -425.588928)
			(xy 458.252022 -425.584951) (xy 458.123433 -425.573035) (xy 457.995821 -425.553226) (xy 457.869672 -425.525599)
			(xy 457.745462 -425.490258) (xy 457.623663 -425.447338) (xy 457.504738 -425.397001) (xy 457.389137 -425.339439)
			(xy 457.277298 -425.274869) (xy 457.169647 -425.203537) (xy 457.066592 -425.125713) (xy 456.968522 -425.041692)
			(xy 456.875811 -424.951793) (xy 456.788811 -424.856358) (xy 456.70785 -424.755748) (xy 456.633236 -424.650345)
			(xy 456.565253 -424.540548) (xy 456.504158 -424.426774) (xy 456.450183 -424.309455) (xy 456.403532 -424.189036)
			(xy 456.364383 -424.065973) (xy 456.332884 -423.940734) (xy 456.309155 -423.813793) (xy 456.293285 -423.685633)
			(xy 456.285335 -423.556738) (xy 361.505055 -423.556738) (xy 361.522862 -423.581893) (xy 361.590845 -423.69169)
			(xy 361.65194 -423.805464) (xy 361.705915 -423.922783) (xy 361.752566 -424.043202) (xy 361.791715 -424.166265)
			(xy 361.823214 -424.291504) (xy 361.846943 -424.418445) (xy 361.862813 -424.546605) (xy 361.870763 -424.6755)
			(xy 361.87126 -424.74007) (xy 361.870763 -424.80464) (xy 361.862813 -424.933535) (xy 361.846943 -425.061695)
			(xy 361.823214 -425.188636) (xy 361.791715 -425.313875) (xy 361.752566 -425.436938) (xy 361.705915 -425.557357)
			(xy 361.65194 -425.674676) (xy 361.590845 -425.78845) (xy 361.522862 -425.898247) (xy 361.448248 -426.00365)
			(xy 361.367287 -426.10426) (xy 361.280287 -426.199695) (xy 361.187576 -426.289594) (xy 361.089506 -426.373615)
			(xy 360.986451 -426.451439) (xy 360.8788 -426.522771) (xy 360.766961 -426.587341) (xy 360.65136 -426.644903)
			(xy 360.532435 -426.69524) (xy 360.410636 -426.73816) (xy 360.286426 -426.773501) (xy 360.160277 -426.801128)
			(xy 360.032665 -426.820937) (xy 359.904076 -426.832853) (xy 359.774998 -426.83683) (xy 359.64592 -426.832853)
			(xy 359.517331 -426.820937) (xy 359.389719 -426.801128) (xy 359.26357 -426.773501) (xy 359.13936 -426.73816)
			(xy 359.017561 -426.69524) (xy 358.898636 -426.644903) (xy 358.783035 -426.587341) (xy 358.671196 -426.522771)
			(xy 358.563545 -426.451439) (xy 358.46049 -426.373615) (xy 358.36242 -426.289594) (xy 358.269709 -426.199695)
			(xy 358.182709 -426.10426) (xy 358.101748 -426.00365) (xy 358.027134 -425.898247) (xy 357.959151 -425.78845)
			(xy 357.898056 -425.674676) (xy 357.844081 -425.557357) (xy 357.79743 -425.436938) (xy 357.758281 -425.313875)
			(xy 357.726782 -425.188636) (xy 357.703053 -425.061695) (xy 357.687183 -424.933535) (xy 357.679233 -424.80464)
			(xy 230.3145 -424.80464) (xy 230.3145 -427.960536) (xy 314.141104 -427.960536) (xy 314.141104 -425.419012)
			(xy 314.14157 -425.406962) (xy 314.149 -425.384036) (xy 314.163139 -425.36452) (xy 314.182609 -425.350316)
			(xy 314.20551 -425.342811) (xy 314.217558 -425.342304) (xy 315.157866 -425.342304) (xy 315.16995 -425.342836)
			(xy 315.192944 -425.350279) (xy 315.212521 -425.36445) (xy 315.226774 -425.383968) (xy 315.234313 -425.40693)
			(xy 315.234828 -425.419012) (xy 315.234828 -427.960536) (xy 315.234371 -427.972585) (xy 315.226932 -427.995507)
			(xy 315.21279 -428.01502) (xy 315.193321 -428.029223) (xy 315.170422 -428.036734) (xy 315.158374 -428.037244)
			(xy 314.218066 -428.037244) (xy 314.205973 -428.036821) (xy 314.182969 -428.029353) (xy 314.163388 -428.015156)
			(xy 314.149139 -427.995612) (xy 314.141611 -427.972628) (xy 314.141104 -427.960536) (xy 230.3145 -427.960536)
			(xy 230.3145 -433.130695) (xy 266.885917 -433.130695) (xy 266.885917 -432.953425) (xy 266.89387 -432.776334)
			(xy 266.909761 -432.599778) (xy 266.933556 -432.424113) (xy 266.965209 -432.249692) (xy 267.004655 -432.076867)
			(xy 267.051815 -431.905986) (xy 267.106594 -431.737392) (xy 267.168882 -431.571427) (xy 267.238554 -431.408422)
			(xy 267.315468 -431.248708) (xy 267.399471 -431.092605) (xy 267.490392 -430.940428) (xy 267.588049 -430.792484)
			(xy 267.692246 -430.64907) (xy 267.802772 -430.510475) (xy 267.919404 -430.376978) (xy 268.041909 -430.248849)
			(xy 268.170038 -430.126344) (xy 268.303535 -430.009712) (xy 268.44213 -429.899186) (xy 268.585544 -429.794989)
			(xy 268.733488 -429.697332) (xy 268.885665 -429.606411) (xy 269.041768 -429.522408) (xy 269.201482 -429.445494)
			(xy 269.364487 -429.375822) (xy 269.530452 -429.313534) (xy 269.699046 -429.258755) (xy 269.869927 -429.211595)
			(xy 270.042752 -429.172149) (xy 270.217173 -429.140496) (xy 270.392838 -429.116701) (xy 270.569394 -429.10081)
			(xy 270.746485 -429.092857) (xy 270.923755 -429.092857) (xy 271.100846 -429.10081) (xy 271.277402 -429.116701)
			(xy 271.453067 -429.140496) (xy 271.627488 -429.172149) (xy 271.800313 -429.211595) (xy 271.971194 -429.258755)
			(xy 272.139788 -429.313534) (xy 272.305753 -429.375822) (xy 272.468758 -429.445494) (xy 272.628472 -429.522408)
			(xy 272.784575 -429.606411) (xy 272.936752 -429.697332) (xy 273.084696 -429.794989) (xy 273.22811 -429.899186)
			(xy 273.366705 -430.009712) (xy 273.500202 -430.126344) (xy 273.628331 -430.248849) (xy 273.750836 -430.376978)
			(xy 273.867468 -430.510475) (xy 273.977994 -430.64907) (xy 274.082191 -430.792484) (xy 274.179848 -430.940428)
			(xy 274.270769 -431.092605) (xy 274.354772 -431.248708) (xy 274.431686 -431.408422) (xy 274.496678 -431.560478)
			(xy 314.141104 -431.560478) (xy 314.141104 -430.833276) (xy 314.141355 -430.824519) (xy 314.145335 -430.807461)
			(xy 314.148978 -430.799494) (xy 314.382404 -430.323244) (xy 314.387132 -430.312738) (xy 314.390613 -430.289973)
			(xy 314.387116 -430.26721) (xy 314.382404 -430.256696) (xy 314.148978 -429.780446) (xy 314.145329 -429.77248)
			(xy 314.141345 -429.755422) (xy 314.141104 -429.746664) (xy 314.141104 -429.018954) (xy 314.141567 -429.006866)
			(xy 314.149032 -428.98387) (xy 314.163221 -428.964293) (xy 314.182753 -428.950043) (xy 314.205725 -428.942506)
			(xy 314.217812 -428.941992) (xy 315.157612 -428.941992) (xy 315.169721 -428.942406) (xy 315.192747 -428.949908)
			(xy 315.207329 -428.960534) (xy 316.1411 -428.960534) (xy 316.1411 -426.41901) (xy 316.14162 -426.4069)
			(xy 316.1491 -426.383863) (xy 316.163331 -426.364265) (xy 316.18292 -426.350022) (xy 316.205952 -426.342527)
			(xy 316.218062 -426.342048) (xy 317.157862 -426.342048) (xy 317.169984 -426.342492) (xy 317.193043 -426.349975)
			(xy 317.21266 -426.36422) (xy 317.226912 -426.383832) (xy 317.234403 -426.406888) (xy 317.234824 -426.41901)
			(xy 317.234824 -427.960536) (xy 318.141096 -427.960536) (xy 318.141096 -425.419012) (xy 318.14157 -425.406963)
			(xy 318.148999 -425.384038) (xy 318.163136 -425.364523) (xy 318.182604 -425.350319) (xy 318.205503 -425.342812)
			(xy 318.21755 -425.342304) (xy 319.157858 -425.342304) (xy 319.169942 -425.342842) (xy 319.192935 -425.350283)
			(xy 319.212513 -425.364453) (xy 319.226766 -425.383969) (xy 319.234305 -425.40693) (xy 319.23482 -425.419012)
			(xy 319.23482 -427.960536) (xy 319.234371 -427.972586) (xy 319.226931 -427.99551) (xy 319.212787 -428.015023)
			(xy 319.193316 -428.029226) (xy 319.170415 -428.036735) (xy 319.158366 -428.037244) (xy 318.218058 -428.037244)
			(xy 318.205965 -428.036828) (xy 318.18296 -428.029358) (xy 318.163379 -428.015159) (xy 318.149131 -427.995614)
			(xy 318.141603 -427.972628) (xy 318.141096 -427.960536) (xy 317.234824 -427.960536) (xy 317.234824 -428.960534)
			(xy 317.234469 -428.972662) (xy 317.226962 -428.995729) (xy 317.212695 -429.015347) (xy 317.193064 -429.029595)
			(xy 317.169991 -429.03708) (xy 317.157862 -429.037496) (xy 316.218062 -429.037496) (xy 316.205949 -429.037021)
			(xy 316.18291 -429.029528) (xy 316.163312 -429.015285) (xy 316.14907 -428.995686) (xy 316.141578 -428.972647)
			(xy 316.1411 -428.960534) (xy 315.207329 -428.960534) (xy 315.212319 -428.96417) (xy 315.226514 -428.983792)
			(xy 315.233936 -429.006844) (xy 315.23432 -429.018954) (xy 315.23432 -431.560478) (xy 315.233873 -431.57257)
			(xy 315.226418 -431.595577) (xy 315.212227 -431.615161) (xy 315.192687 -431.629411) (xy 315.169703 -431.636936)
			(xy 315.157612 -431.63744) (xy 314.217812 -431.63744) (xy 314.205708 -431.636974) (xy 314.182688 -431.629483)
			(xy 314.163118 -431.615232) (xy 314.148922 -431.595624) (xy 314.141493 -431.572583) (xy 314.141104 -431.560478)
			(xy 274.496678 -431.560478) (xy 274.501358 -431.571427) (xy 274.563646 -431.737392) (xy 274.618425 -431.905986)
			(xy 274.665585 -432.076867) (xy 274.705031 -432.249692) (xy 274.736684 -432.424113) (xy 274.760479 -432.599778)
			(xy 274.77637 -432.776334) (xy 274.784323 -432.953425) (xy 274.78482 -433.04206) (xy 274.784323 -433.130695)
			(xy 274.77637 -433.307786) (xy 274.760479 -433.484342) (xy 274.736684 -433.660007) (xy 274.705031 -433.834428)
			(xy 274.665585 -434.007253) (xy 274.618425 -434.178134) (xy 274.563646 -434.346728) (xy 274.501358 -434.512693)
			(xy 274.431686 -434.675698) (xy 274.354772 -434.835412) (xy 274.270769 -434.991515) (xy 274.179848 -435.143692)
			(xy 274.168806 -435.16042) (xy 314.141104 -435.16042) (xy 314.141104 -434.433472) (xy 314.141431 -434.424703)
			(xy 314.145529 -434.407645) (xy 314.149232 -434.39969) (xy 314.149232 -434.399182) (xy 314.382658 -433.923186)
			(xy 314.387354 -433.912668) (xy 314.390843 -433.889911) (xy 314.387361 -433.867153) (xy 314.382658 -433.856638)
			(xy 314.149232 -433.380642) (xy 314.149232 -433.380134) (xy 314.145516 -433.372182) (xy 314.141404 -433.355124)
			(xy 314.141104 -433.346352) (xy 314.141104 -432.618896) (xy 314.141557 -432.606845) (xy 314.148991 -432.583919)
			(xy 314.163134 -432.564403) (xy 314.182606 -432.5502) (xy 314.205509 -432.542694) (xy 314.217558 -432.542188)
			(xy 315.157866 -432.542188) (xy 315.169959 -432.542637) (xy 315.192966 -432.55009) (xy 315.207301 -432.560476)
			(xy 316.1411 -432.560476) (xy 316.1411 -431.833274) (xy 316.141351 -431.824517) (xy 316.145331 -431.807459)
			(xy 316.148974 -431.799492) (xy 316.3824 -431.323242) (xy 316.38713 -431.312736) (xy 316.39061 -431.289971)
			(xy 316.387112 -431.267208) (xy 316.3824 -431.256694) (xy 316.148974 -430.780444) (xy 316.145324 -430.772478)
			(xy 316.141341 -430.75542) (xy 316.1411 -430.746662) (xy 316.1411 -430.018952) (xy 316.141523 -430.006874)
			(xy 316.149 -429.983904) (xy 316.163207 -429.964367) (xy 316.182754 -429.950174) (xy 316.20573 -429.942714)
			(xy 316.217808 -429.942244) (xy 317.157608 -429.942244) (xy 317.169678 -429.942757) (xy 317.192637 -429.950216)
			(xy 317.21217 -429.964401) (xy 317.226366 -429.983927) (xy 317.233837 -430.006882) (xy 317.234316 -430.018952)
			(xy 317.234316 -431.560478) (xy 318.141096 -431.560478) (xy 318.141096 -430.833276) (xy 318.141348 -430.824519)
			(xy 318.145327 -430.807461) (xy 318.14897 -430.799494) (xy 318.382396 -430.323244) (xy 318.387125 -430.312738)
			(xy 318.390605 -430.289973) (xy 318.387108 -430.26721) (xy 318.382396 -430.256696) (xy 318.14897 -429.780446)
			(xy 318.14532 -429.77248) (xy 318.141337 -429.755422) (xy 318.141096 -429.746664) (xy 318.141096 -429.018954)
			(xy 318.141567 -429.006866) (xy 318.149031 -428.983872) (xy 318.163218 -428.964296) (xy 318.182748 -428.950046)
			(xy 318.205718 -428.942507) (xy 318.217804 -428.941992) (xy 319.157604 -428.941992) (xy 319.169712 -428.942413)
			(xy 319.192738 -428.949912) (xy 319.207317 -428.960534) (xy 320.141092 -428.960534) (xy 320.141092 -426.41901)
			(xy 320.14162 -426.406901) (xy 320.149099 -426.383865) (xy 320.163328 -426.364268) (xy 320.182915 -426.350024)
			(xy 320.205945 -426.342528) (xy 320.218054 -426.342048) (xy 321.157854 -426.342048) (xy 321.169975 -426.342499)
			(xy 321.193034 -426.34998) (xy 321.212651 -426.364223) (xy 321.226904 -426.383833) (xy 321.234395 -426.406889)
			(xy 321.234816 -426.41901) (xy 321.234816 -427.960536) (xy 322.141088 -427.960536) (xy 322.141088 -425.419012)
			(xy 322.14157 -425.406964) (xy 322.148998 -425.38404) (xy 322.163133 -425.364526) (xy 322.182598 -425.350321)
			(xy 322.205495 -425.342813) (xy 322.217542 -425.342304) (xy 323.15785 -425.342304) (xy 323.169933 -425.342849)
			(xy 323.192926 -425.350288) (xy 323.212504 -425.364455) (xy 323.226758 -425.383971) (xy 323.234297 -425.406931)
			(xy 323.234812 -425.419012) (xy 323.234812 -427.960536) (xy 323.234371 -427.972587) (xy 323.22693 -427.995512)
			(xy 323.212784 -428.015026) (xy 323.193311 -428.029228) (xy 323.170407 -428.036736) (xy 323.158358 -428.037244)
			(xy 322.21805 -428.037244) (xy 322.205961 -428.03675) (xy 322.18296 -428.029305) (xy 322.163378 -428.015126)
			(xy 322.149126 -427.995597) (xy 322.141595 -427.972623) (xy 322.141088 -427.960536) (xy 321.234816 -427.960536)
			(xy 321.234816 -428.960534) (xy 321.234468 -428.972663) (xy 321.226961 -428.995731) (xy 321.212692 -429.015349)
			(xy 321.193059 -429.029598) (xy 321.169984 -429.037081) (xy 321.157854 -429.037496) (xy 320.218054 -429.037496)
			(xy 320.20594 -429.037028) (xy 320.182901 -429.029532) (xy 320.163303 -429.015288) (xy 320.149062 -428.995688)
			(xy 320.14157 -428.972648) (xy 320.141092 -428.960534) (xy 319.207317 -428.960534) (xy 319.212311 -428.964173)
			(xy 319.226506 -428.983793) (xy 319.233928 -429.006844) (xy 319.234312 -429.018954) (xy 319.234312 -431.560478)
			(xy 319.233873 -431.572571) (xy 319.226416 -431.595579) (xy 319.212224 -431.615164) (xy 319.192682 -431.629413)
			(xy 319.169696 -431.636937) (xy 319.157604 -431.63744) (xy 318.217804 -431.63744) (xy 318.205699 -431.636981)
			(xy 318.182679 -431.629488) (xy 318.163109 -431.615236) (xy 318.148913 -431.595625) (xy 318.141485 -431.572584)
			(xy 318.141096 -431.560478) (xy 317.234316 -431.560478) (xy 317.234316 -432.560476) (xy 317.233867 -432.572557)
			(xy 317.226407 -432.595537) (xy 317.21221 -432.615087) (xy 317.192666 -432.629292) (xy 317.169688 -432.636762)
			(xy 317.157608 -432.637184) (xy 316.217808 -432.637184) (xy 316.205723 -432.63678) (xy 316.182737 -432.629312)
			(xy 316.163184 -432.615105) (xy 316.148981 -432.595549) (xy 316.141517 -432.572561) (xy 316.1411 -432.560476)
			(xy 315.207301 -432.560476) (xy 315.212551 -432.56428) (xy 315.226801 -432.583821) (xy 315.234325 -432.606805)
			(xy 315.234828 -432.618896) (xy 315.234828 -435.16042) (xy 315.234357 -435.172468) (xy 315.226923 -435.19539)
			(xy 315.212784 -435.214903) (xy 315.193317 -435.229106) (xy 315.170421 -435.236617) (xy 315.158374 -435.237128)
			(xy 314.218066 -435.237128) (xy 314.205971 -435.236721) (xy 314.182964 -435.229251) (xy 314.163382 -435.21505)
			(xy 314.149134 -435.195502) (xy 314.141608 -435.172513) (xy 314.141104 -435.16042) (xy 274.168806 -435.16042)
			(xy 274.082191 -435.291636) (xy 273.977994 -435.43505) (xy 273.867468 -435.573645) (xy 273.750836 -435.707142)
			(xy 273.628331 -435.835271) (xy 273.500202 -435.957776) (xy 273.366705 -436.074408) (xy 273.22811 -436.184934)
			(xy 273.084696 -436.289131) (xy 272.936752 -436.386788) (xy 272.784575 -436.477709) (xy 272.628472 -436.561712)
			(xy 272.468758 -436.638626) (xy 272.305753 -436.708298) (xy 272.139788 -436.770586) (xy 271.971194 -436.825365)
			(xy 271.800313 -436.872525) (xy 271.627488 -436.911971) (xy 271.453067 -436.943624) (xy 271.277402 -436.967419)
			(xy 271.100846 -436.98331) (xy 270.923755 -436.991263) (xy 270.746485 -436.991263) (xy 270.569394 -436.98331)
			(xy 270.392838 -436.967419) (xy 270.217173 -436.943624) (xy 270.042752 -436.911971) (xy 269.869927 -436.872525)
			(xy 269.699046 -436.825365) (xy 269.530452 -436.770586) (xy 269.364487 -436.708298) (xy 269.201482 -436.638626)
			(xy 269.041768 -436.561712) (xy 268.885665 -436.477709) (xy 268.733488 -436.386788) (xy 268.585544 -436.289131)
			(xy 268.44213 -436.184934) (xy 268.303535 -436.074408) (xy 268.170038 -435.957776) (xy 268.041909 -435.835271)
			(xy 267.919404 -435.707142) (xy 267.802772 -435.573645) (xy 267.692246 -435.43505) (xy 267.588049 -435.291636)
			(xy 267.490392 -435.143692) (xy 267.399471 -434.991515) (xy 267.315468 -434.835412) (xy 267.238554 -434.675698)
			(xy 267.168882 -434.512693) (xy 267.106594 -434.346728) (xy 267.051815 -434.178134) (xy 267.004655 -434.007253)
			(xy 266.965209 -433.834428) (xy 266.933556 -433.660007) (xy 266.909761 -433.484342) (xy 266.89387 -433.307786)
			(xy 266.885917 -433.130695) (xy 230.3145 -433.130695) (xy 230.3145 -435.873652) (xy 230.314033 -435.898602)
			(xy 230.306213 -435.947887) (xy 230.29079 -435.995345) (xy 230.268141 -436.03981) (xy 230.238824 -436.080191)
			(xy 230.221536 -436.098188) (xy 229.299008 -437.020716) (xy 229.281016 -437.03801) (xy 229.240639 -437.067332)
			(xy 229.196172 -437.089979) (xy 229.148711 -437.105393) (xy 229.099423 -437.113193) (xy 229.074472 -437.11368)
			(xy 207.302608 -437.11368) (xy 207.27766 -437.113152) (xy 207.22838 -437.105344) (xy 207.180923 -437.089933)
			(xy 207.136457 -437.067299) (xy 207.096072 -437.037997) (xy 207.078072 -437.020716) (xy 205.512924 -435.455568)
			(xy 205.495618 -435.437587) (xy 205.466295 -435.397208) (xy 205.44365 -435.352738) (xy 205.42824 -435.305274)
			(xy 205.420444 -435.255984) (xy 205.41996 -435.231032) (xy 205.41996 -431.836068) (xy 205.419562 -431.825996)
			(xy 205.411823 -431.807397) (xy 205.404974 -431.8) (xy 204.586586 -430.981612) (xy 204.579871 -430.975414)
			(xy 204.563254 -430.96784) (xy 204.545036 -430.96659) (xy 204.52754 -430.971821) (xy 204.520038 -430.97704)
			(xy 204.424534 -431.04943) (xy 204.416914 -431.086514) (xy 204.426312 -431.103278) (xy 204.471058 -431.183788)
			(xy 204.553904 -431.348323) (xy 204.628987 -431.516542) (xy 204.696145 -431.688079) (xy 204.75523 -431.862561)
			(xy 204.806115 -432.039609) (xy 204.848688 -432.218837) (xy 204.882858 -432.399855) (xy 204.908549 -432.58227)
			(xy 204.925705 -432.765684) (xy 204.934291 -432.949699) (xy 204.93482 -433.041806) (xy 204.93482 -433.04206)
			(xy 204.934323 -433.130695) (xy 204.92637 -433.307786) (xy 204.910479 -433.484342) (xy 204.886684 -433.660007)
			(xy 204.855031 -433.834428) (xy 204.815585 -434.007253) (xy 204.768425 -434.178134) (xy 204.713646 -434.346728)
			(xy 204.651358 -434.512693) (xy 204.581686 -434.675698) (xy 204.504772 -434.835412) (xy 204.420769 -434.991515)
			(xy 204.329848 -435.143692) (xy 204.232191 -435.291636) (xy 204.127994 -435.43505) (xy 204.017468 -435.573645)
			(xy 203.900836 -435.707142) (xy 203.778331 -435.835271) (xy 203.650202 -435.957776) (xy 203.516705 -436.074408)
			(xy 203.37811 -436.184934) (xy 203.234696 -436.289131) (xy 203.086752 -436.386788) (xy 202.934575 -436.477709)
			(xy 202.778472 -436.561712) (xy 202.618758 -436.638626) (xy 202.455753 -436.708298) (xy 202.289788 -436.770586)
			(xy 202.121194 -436.825365) (xy 201.950313 -436.872525) (xy 201.777488 -436.911971) (xy 201.603067 -436.943624)
			(xy 201.427402 -436.967419) (xy 201.250846 -436.98331) (xy 201.073755 -436.991263) (xy 200.896485 -436.991263)
			(xy 200.719394 -436.98331) (xy 200.542838 -436.967419) (xy 200.367173 -436.943624) (xy 200.192752 -436.911971)
			(xy 200.019927 -436.872525) (xy 199.849046 -436.825365) (xy 199.680452 -436.770586) (xy 199.514487 -436.708298)
			(xy 199.351482 -436.638626) (xy 199.191768 -436.561712) (xy 199.035665 -436.477709) (xy 198.883488 -436.386788)
			(xy 198.735544 -436.289131) (xy 198.59213 -436.184934) (xy 198.453535 -436.074408) (xy 198.320038 -435.957776)
			(xy 198.191909 -435.835271) (xy 198.069404 -435.707142) (xy 197.952772 -435.573645) (xy 197.842246 -435.43505)
			(xy 197.738049 -435.291636) (xy 197.640392 -435.143692) (xy 197.549471 -434.991515) (xy 197.465468 -434.835412)
			(xy 197.388554 -434.675698) (xy 197.318882 -434.512693) (xy 197.256594 -434.346728) (xy 197.201815 -434.178134)
			(xy 197.154655 -434.007253) (xy 197.115209 -433.834428) (xy 197.083556 -433.660007) (xy 197.059761 -433.484342)
			(xy 197.04387 -433.307786) (xy 197.035917 -433.130695) (xy 197.035917 -432.953425) (xy 197.04387 -432.776334)
			(xy 197.059761 -432.599778) (xy 197.083556 -432.424113) (xy 197.115209 -432.249692) (xy 197.154655 -432.076867)
			(xy 197.201815 -431.905986) (xy 197.256594 -431.737392) (xy 197.318882 -431.571427) (xy 197.388554 -431.408422)
			(xy 197.465468 -431.248708) (xy 197.549471 -431.092605) (xy 197.640392 -430.940428) (xy 197.738049 -430.792484)
			(xy 197.842246 -430.64907) (xy 197.952772 -430.510475) (xy 198.069404 -430.376978) (xy 198.191909 -430.248849)
			(xy 198.320038 -430.126344) (xy 198.453535 -430.009712) (xy 198.59213 -429.899186) (xy 198.735544 -429.794989)
			(xy 198.883488 -429.697332) (xy 199.035665 -429.606411) (xy 199.191768 -429.522408) (xy 199.351482 -429.445494)
			(xy 199.514487 -429.375822) (xy 199.680452 -429.313534) (xy 199.849046 -429.258755) (xy 200.019927 -429.211595)
			(xy 200.192752 -429.172149) (xy 200.367173 -429.140496) (xy 200.542838 -429.116701) (xy 200.719394 -429.10081)
			(xy 200.896485 -429.092857) (xy 200.98512 -429.09236) (xy 200.985374 -429.09236) (xy 201.07748 -429.092926)
			(xy 201.261492 -429.101525) (xy 201.444903 -429.118692) (xy 201.627315 -429.144389) (xy 201.80833 -429.17856)
			(xy 201.987556 -429.221132) (xy 202.164603 -429.272011) (xy 202.339086 -429.331088) (xy 202.510625 -429.398233)
			(xy 202.678849 -429.4733) (xy 202.84339 -429.556127) (xy 202.923902 -429.600868) (xy 202.932044 -429.605072)
			(xy 202.950138 -429.607899) (xy 202.968075 -429.604204) (xy 202.983579 -429.594457) (xy 202.989434 -429.587406)
			(xy 203.05014 -429.507396) (xy 203.055391 -429.49992) (xy 203.060685 -429.482447) (xy 203.059501 -429.464229)
			(xy 203.05199 -429.447588) (xy 203.045822 -429.440848) (xy 194.790822 -421.185594) (xy 194.763915 -421.158053)
			(xy 194.715832 -421.097913) (xy 194.674792 -421.032763) (xy 194.641312 -420.963424) (xy 194.615814 -420.89077)
			(xy 194.598619 -420.815716) (xy 194.589944 -420.739207) (xy 194.5894 -420.700708) (xy 102.15118 -420.700708)
			(xy 102.15118 -421.122094) (xy 102.150662 -421.132249) (xy 102.142893 -421.151015) (xy 102.128535 -421.16538)
			(xy 102.109773 -421.173157) (xy 102.099618 -421.173656) (xy 97.200974 -421.173656) (xy 97.190814 -421.173188)
			(xy 97.172043 -421.165404) (xy 97.157678 -421.15103) (xy 97.149906 -421.132255) (xy 97.149412 -421.122094)
			(xy 75.844472 -421.122094) (xy 75.826048 -421.150762) (xy 75.790333 -421.191979) (xy 75.749116 -421.227694)
			(xy 75.703235 -421.25718) (xy 75.653625 -421.279837) (xy 75.601295 -421.295202) (xy 75.547311 -421.302964)
			(xy 75.492773 -421.302964) (xy 75.438789 -421.295202) (xy 75.386459 -421.279837) (xy 75.336849 -421.25718)
			(xy 75.290968 -421.227694) (xy 75.249751 -421.191979) (xy 75.214036 -421.150762) (xy 75.18455 -421.104881)
			(xy 75.161893 -421.055271) (xy 75.146528 -421.002941) (xy 75.138766 -420.948957) (xy 75.13828 -420.921688)
			(xy 73.234804 -420.921688) (xy 73.234804 -421.760396) (xy 73.234337 -421.772446) (xy 73.226906 -421.79537)
			(xy 73.212766 -421.814886) (xy 73.193298 -421.829089) (xy 73.170398 -421.836596) (xy 73.15835 -421.837104)
			(xy 72.218042 -421.837104) (xy 72.205959 -421.836558) (xy 72.182967 -421.829118) (xy 72.16339 -421.81495)
			(xy 72.149137 -421.795436) (xy 72.141596 -421.772477) (xy 72.14108 -421.760396) (xy 71.207209 -421.760396)
			(xy 71.212598 -421.764313) (xy 71.226839 -421.783915) (xy 71.23433 -421.806956) (xy 71.234808 -421.81907)
			(xy 71.234808 -424.360594) (xy 71.234284 -424.372704) (xy 71.226804 -424.395739) (xy 71.212574 -424.415337)
			(xy 71.192985 -424.42958) (xy 71.169955 -424.437076) (xy 71.157846 -424.437556) (xy 70.218046 -424.437556)
			(xy 70.205925 -424.437101) (xy 70.182867 -424.429621) (xy 70.16325 -424.415378) (xy 70.148998 -424.395769)
			(xy 70.141505 -424.372715) (xy 70.141084 -424.360594) (xy 69.234812 -424.360594) (xy 69.234812 -425.360592)
			(xy 69.234333 -425.372641) (xy 69.226904 -425.395564) (xy 69.212768 -425.415079) (xy 69.193302 -425.429283)
			(xy 69.170405 -425.436791) (xy 69.158358 -425.4373) (xy 68.21805 -425.4373) (xy 68.205967 -425.436751)
			(xy 68.182975 -425.429313) (xy 68.163397 -425.415146) (xy 68.149144 -425.395632) (xy 68.141603 -425.372673)
			(xy 68.141088 -425.360592) (xy 67.207172 -425.360592) (xy 67.212508 -425.364454) (xy 67.226762 -425.38397)
			(xy 67.234301 -425.40693) (xy 67.234816 -425.419012) (xy 67.234816 -427.960536) (xy 67.234371 -427.972587)
			(xy 67.226931 -427.995511) (xy 67.212785 -428.015024) (xy 67.193313 -428.029227) (xy 67.170411 -428.036735)
			(xy 67.158362 -428.037244) (xy 66.218054 -428.037244) (xy 66.20596 -428.036832) (xy 66.182956 -428.02936)
			(xy 66.163375 -428.01516) (xy 66.149127 -427.995615) (xy 66.141599 -427.972628) (xy 66.141092 -427.960536)
			(xy 65.23482 -427.960536) (xy 65.23482 -428.960534) (xy 65.234469 -428.972663) (xy 65.226962 -428.99573)
			(xy 65.212694 -429.015348) (xy 65.193062 -429.029597) (xy 65.169987 -429.03708) (xy 65.157858 -429.037496)
			(xy 64.218058 -429.037496) (xy 64.205945 -429.037025) (xy 64.182906 -429.02953) (xy 64.163308 -429.015287)
			(xy 64.149066 -428.995687) (xy 64.141574 -428.972647) (xy 64.141096 -428.960534) (xy 63.207499 -428.960534)
			(xy 63.212603 -428.964238) (xy 63.226847 -428.98382) (xy 63.234343 -429.006847) (xy 63.234824 -429.018954)
			(xy 63.234824 -431.560478) (xy 63.234421 -431.572603) (xy 63.22693 -431.595668) (xy 63.212675 -431.615287)
			(xy 63.193054 -431.629537) (xy 63.169987 -431.637023) (xy 63.157862 -431.63744) (xy 62.218062 -431.63744)
			(xy 62.205943 -431.63702) (xy 62.182895 -431.62952) (xy 62.163292 -431.615265) (xy 62.149053 -431.595651)
			(xy 62.14157 -431.572597) (xy 62.1411 -431.560478) (xy 61.234828 -431.560478) (xy 61.234828 -432.560476)
			(xy 61.23432 -432.572522) (xy 61.226897 -432.595442) (xy 61.212768 -432.614956) (xy 61.193309 -432.629161)
			(xy 61.170418 -432.636673) (xy 61.158374 -432.637184) (xy 60.218066 -432.637184) (xy 60.205977 -432.636722)
			(xy 60.182979 -432.629259) (xy 60.163402 -432.61507) (xy 60.149152 -432.595538) (xy 60.141616 -432.572563)
			(xy 60.141104 -432.560476) (xy 59.207307 -432.560476) (xy 59.212555 -432.564278) (xy 59.226805 -432.58382)
			(xy 59.234329 -432.606805) (xy 59.234832 -432.618896) (xy 59.234832 -435.16042) (xy 59.234358 -435.172468)
			(xy 59.226923 -435.195389) (xy 59.212785 -435.214901) (xy 59.19332 -435.229105) (xy 59.170424 -435.236616)
			(xy 59.158378 -435.237128) (xy 58.21807 -435.237128) (xy 58.205976 -435.236718) (xy 58.182969 -435.229249)
			(xy 58.163386 -435.215049) (xy 58.149138 -435.195502) (xy 58.141612 -435.172513) (xy 58.141108 -435.16042)
			(xy 7.00913 -435.16042) (xy 7.00913 -438.760616) (xy 58.141108 -438.760616) (xy 58.141108 -436.219092)
			(xy 58.141553 -436.207041) (xy 58.148989 -436.184113) (xy 58.163134 -436.164597) (xy 58.182607 -436.150394)
			(xy 58.205512 -436.14289) (xy 58.217562 -436.142384) (xy 59.15787 -436.142384) (xy 59.169962 -436.142834)
			(xy 59.192969 -436.150288) (xy 59.206951 -436.160418) (xy 60.141104 -436.160418) (xy 60.141104 -435.43347)
			(xy 60.14143 -435.424701) (xy 60.145529 -435.407643) (xy 60.149232 -435.399688) (xy 60.149232 -435.39918)
			(xy 60.382658 -434.923184) (xy 60.387356 -434.912666) (xy 60.390843 -434.889909) (xy 60.387361 -434.867151)
			(xy 60.382658 -434.856636) (xy 60.149232 -434.38064) (xy 60.149232 -434.380132) (xy 60.145516 -434.37218)
			(xy 60.141404 -434.355122) (xy 60.141104 -434.34635) (xy 60.141104 -433.618894) (xy 60.141606 -433.606783)
			(xy 60.149091 -433.583745) (xy 60.163326 -433.564146) (xy 60.18292 -433.549904) (xy 60.205955 -433.542411)
			(xy 60.218066 -433.541932) (xy 61.157866 -433.541932) (xy 61.169986 -433.542389) (xy 61.193043 -433.549871)
			(xy 61.212658 -433.564113) (xy 61.226911 -433.583721) (xy 61.234405 -433.606774) (xy 61.234828 -433.618894)
			(xy 61.234828 -435.16042) (xy 62.1411 -435.16042) (xy 62.1411 -434.433472) (xy 62.141418 -434.424702)
			(xy 62.145522 -434.407644) (xy 62.149228 -434.39969) (xy 62.149228 -434.399182) (xy 62.382654 -433.923186)
			(xy 62.38735 -433.912668) (xy 62.390839 -433.889911) (xy 62.387357 -433.867153) (xy 62.382654 -433.856638)
			(xy 62.149228 -433.380642) (xy 62.149228 -433.380134) (xy 62.145512 -433.372182) (xy 62.1414 -433.355124)
			(xy 62.1411 -433.346352) (xy 62.1411 -432.618896) (xy 62.141557 -432.606846) (xy 62.14899 -432.58392)
			(xy 62.163132 -432.564404) (xy 62.182603 -432.550201) (xy 62.205505 -432.542695) (xy 62.217554 -432.542188)
			(xy 63.157862 -432.542188) (xy 63.169954 -432.542641) (xy 63.192962 -432.550093) (xy 63.207295 -432.560476)
			(xy 64.141096 -432.560476) (xy 64.141096 -431.833528) (xy 64.1414 -431.824757) (xy 64.145513 -431.807699)
			(xy 64.149224 -431.799746) (xy 64.149224 -431.799238) (xy 64.38265 -431.323242) (xy 64.387377 -431.312736)
			(xy 64.390855 -431.289971) (xy 64.38736 -431.267209) (xy 64.38265 -431.256694) (xy 64.149224 -430.780698)
			(xy 64.149224 -430.78019) (xy 64.145494 -430.772244) (xy 64.141391 -430.755181) (xy 64.141096 -430.746408)
			(xy 64.141096 -430.018952) (xy 64.141519 -430.0069) (xy 64.148964 -429.983973) (xy 64.163115 -429.964459)
			(xy 64.182592 -429.950257) (xy 64.205499 -429.942751) (xy 64.21755 -429.942244) (xy 65.157858 -429.942244)
			(xy 65.169946 -429.942743) (xy 65.192946 -429.950189) (xy 65.212527 -429.964367) (xy 65.226779 -429.983894)
			(xy 65.234311 -430.006866) (xy 65.23482 -430.018952) (xy 65.23482 -431.560478) (xy 66.141092 -431.560478)
			(xy 66.141092 -430.83353) (xy 66.141397 -430.824759) (xy 66.14551 -430.807702) (xy 66.14922 -430.799748)
			(xy 66.14922 -430.79924) (xy 66.382646 -430.323244) (xy 66.387372 -430.312737) (xy 66.39085 -430.289973)
			(xy 66.387356 -430.267211) (xy 66.382646 -430.256696) (xy 66.14922 -429.7807) (xy 66.14922 -429.780192)
			(xy 66.145491 -429.772246) (xy 66.141387 -429.755183) (xy 66.141092 -429.74641) (xy 66.141092 -429.018954)
			(xy 66.141572 -429.006842) (xy 66.149066 -428.983805) (xy 66.163308 -428.964208) (xy 66.182905 -428.949966)
			(xy 66.205942 -428.942472) (xy 66.218054 -428.941992) (xy 67.157854 -428.941992) (xy 67.169962 -428.94255)
			(xy 67.192996 -428.950019) (xy 67.207487 -428.960534) (xy 68.141088 -428.960534) (xy 68.141088 -426.41901)
			(xy 68.14162 -426.406901) (xy 68.149098 -426.383867) (xy 68.163326 -426.364269) (xy 68.182913 -426.350025)
			(xy 68.205941 -426.342529) (xy 68.21805 -426.342048) (xy 69.15785 -426.342048) (xy 69.169968 -426.342469)
			(xy 69.193015 -426.349972) (xy 69.212616 -426.364226) (xy 69.226856 -426.383839) (xy 69.23434 -426.406891)
			(xy 69.234812 -426.41901) (xy 69.234812 -427.960536) (xy 70.141084 -427.960536) (xy 70.141084 -425.419012)
			(xy 70.14157 -425.406964) (xy 70.148997 -425.384042) (xy 70.163132 -425.364527) (xy 70.182596 -425.350323)
			(xy 70.205492 -425.342813) (xy 70.217538 -425.342304) (xy 71.157846 -425.342304) (xy 71.169934 -425.342767)
			(xy 71.19293 -425.350232) (xy 71.207224 -425.360592) (xy 72.14108 -425.360592) (xy 72.14108 -422.819068)
			(xy 72.141532 -422.807018) (xy 72.148971 -422.784095) (xy 72.163115 -422.764581) (xy 72.182585 -422.750378)
			(xy 72.205486 -422.742869) (xy 72.217534 -422.74236) (xy 73.157842 -422.74236) (xy 73.169936 -422.742772)
			(xy 73.192941 -422.750243) (xy 73.212522 -422.764443) (xy 73.226771 -422.783989) (xy 73.234298 -422.806975)
			(xy 73.234804 -422.819068) (xy 73.234804 -424.80464) (xy 109.929157 -424.80464) (xy 109.929157 -424.6755)
			(xy 109.937107 -424.546605) (xy 109.952977 -424.418445) (xy 109.976706 -424.291504) (xy 110.008205 -424.166265)
			(xy 110.047354 -424.043202) (xy 110.094005 -423.922783) (xy 110.14798 -423.805464) (xy 110.209075 -423.69169)
			(xy 110.277058 -423.581893) (xy 110.351672 -423.47649) (xy 110.432633 -423.37588) (xy 110.519633 -423.280445)
			(xy 110.612344 -423.190546) (xy 110.710414 -423.106525) (xy 110.813469 -423.028701) (xy 110.92112 -422.957369)
			(xy 111.032959 -422.892799) (xy 111.14856 -422.835237) (xy 111.267485 -422.7849) (xy 111.389284 -422.74198)
			(xy 111.513494 -422.706639) (xy 111.639643 -422.679012) (xy 111.767255 -422.659203) (xy 111.895844 -422.647287)
			(xy 112.024922 -422.643311) (xy 112.154 -422.647287) (xy 112.282589 -422.659203) (xy 112.410201 -422.679012)
			(xy 112.53635 -422.706639) (xy 112.66056 -422.74198) (xy 112.782359 -422.7849) (xy 112.901284 -422.835237)
			(xy 113.016885 -422.892799) (xy 113.128724 -422.957369) (xy 113.236375 -423.028701) (xy 113.33943 -423.106525)
			(xy 113.4375 -423.190546) (xy 113.530211 -423.280445) (xy 113.617211 -423.37588) (xy 113.698172 -423.47649)
			(xy 113.772786 -423.581893) (xy 113.840769 -423.69169) (xy 113.901864 -423.805464) (xy 113.955839 -423.922783)
			(xy 114.00249 -424.043202) (xy 114.041639 -424.166265) (xy 114.073138 -424.291504) (xy 114.096867 -424.418445)
			(xy 114.112737 -424.546605) (xy 114.120687 -424.6755) (xy 114.121184 -424.74007) (xy 114.120687 -424.80464)
			(xy 114.112737 -424.933535) (xy 114.096867 -425.061695) (xy 114.073138 -425.188636) (xy 114.041639 -425.313875)
			(xy 114.00249 -425.436938) (xy 113.955839 -425.557357) (xy 113.901864 -425.674676) (xy 113.840769 -425.78845)
			(xy 113.772786 -425.898247) (xy 113.698172 -426.00365) (xy 113.617211 -426.10426) (xy 113.530211 -426.199695)
			(xy 113.4375 -426.289594) (xy 113.33943 -426.373615) (xy 113.236375 -426.451439) (xy 113.128724 -426.522771)
			(xy 113.016885 -426.587341) (xy 112.901284 -426.644903) (xy 112.782359 -426.69524) (xy 112.66056 -426.73816)
			(xy 112.53635 -426.773501) (xy 112.410201 -426.801128) (xy 112.282589 -426.820937) (xy 112.154 -426.832853)
			(xy 112.024922 -426.83683) (xy 111.895844 -426.832853) (xy 111.767255 -426.820937) (xy 111.639643 -426.801128)
			(xy 111.513494 -426.773501) (xy 111.389284 -426.73816) (xy 111.267485 -426.69524) (xy 111.14856 -426.644903)
			(xy 111.032959 -426.587341) (xy 110.92112 -426.522771) (xy 110.813469 -426.451439) (xy 110.710414 -426.373615)
			(xy 110.612344 -426.289594) (xy 110.519633 -426.199695) (xy 110.432633 -426.10426) (xy 110.351672 -426.00365)
			(xy 110.277058 -425.898247) (xy 110.209075 -425.78845) (xy 110.14798 -425.674676) (xy 110.094005 -425.557357)
			(xy 110.047354 -425.436938) (xy 110.008205 -425.313875) (xy 109.976706 -425.188636) (xy 109.952977 -425.061695)
			(xy 109.937107 -424.933535) (xy 109.929157 -424.80464) (xy 73.234804 -424.80464) (xy 73.234804 -425.360592)
			(xy 73.234333 -425.372641) (xy 73.226903 -425.395566) (xy 73.212765 -425.415082) (xy 73.193297 -425.429285)
			(xy 73.170398 -425.436792) (xy 73.15835 -425.4373) (xy 72.218042 -425.4373) (xy 72.205959 -425.436758)
			(xy 72.182966 -425.429317) (xy 72.163389 -425.415149) (xy 72.149135 -425.395633) (xy 72.141595 -425.372673)
			(xy 72.14108 -425.360592) (xy 71.207224 -425.360592) (xy 71.212507 -425.364421) (xy 71.226757 -425.383953)
			(xy 71.234294 -425.406925) (xy 71.234808 -425.419012) (xy 71.234808 -427.960536) (xy 71.234371 -427.972587)
			(xy 71.226929 -427.995513) (xy 71.212782 -428.015027) (xy 71.193308 -428.02923) (xy 71.170404 -428.036736)
			(xy 71.158354 -428.037244) (xy 70.218046 -428.037244) (xy 70.205957 -428.036753) (xy 70.182955 -428.029307)
			(xy 70.163373 -428.015127) (xy 70.149122 -427.995597) (xy 70.141591 -427.972623) (xy 70.141084 -427.960536)
			(xy 69.234812 -427.960536) (xy 69.234812 -428.960534) (xy 69.234318 -428.972645) (xy 69.226828 -428.995681)
			(xy 69.21259 -429.015278) (xy 69.192996 -429.02952) (xy 69.169961 -429.037016) (xy 69.15785 -429.037496)
			(xy 68.21805 -429.037496) (xy 68.205936 -429.037031) (xy 68.182897 -429.029535) (xy 68.163299 -429.015289)
			(xy 68.149058 -428.995689) (xy 68.141566 -428.972648) (xy 68.141088 -428.960534) (xy 67.207487 -428.960534)
			(xy 67.212594 -428.96424) (xy 67.226839 -428.983822) (xy 67.234335 -429.006847) (xy 67.234816 -429.018954)
			(xy 67.234816 -431.560478) (xy 67.234421 -431.572604) (xy 67.226929 -431.59567) (xy 67.212672 -431.61529)
			(xy 67.193049 -431.62954) (xy 67.16998 -431.637024) (xy 67.157854 -431.63744) (xy 66.218054 -431.63744)
			(xy 66.205935 -431.637027) (xy 66.182886 -431.629525) (xy 66.163284 -431.615268) (xy 66.149044 -431.595653)
			(xy 66.141562 -431.572598) (xy 66.141092 -431.560478) (xy 65.23482 -431.560478) (xy 65.23482 -432.560476)
			(xy 65.23432 -432.572523) (xy 65.226896 -432.595444) (xy 65.212765 -432.614959) (xy 65.193304 -432.629164)
			(xy 65.170411 -432.636674) (xy 65.158366 -432.637184) (xy 64.218058 -432.637184) (xy 64.205969 -432.636729)
			(xy 64.182971 -432.629264) (xy 64.163393 -432.615073) (xy 64.149143 -432.595539) (xy 64.141608 -432.572564)
			(xy 64.141096 -432.560476) (xy 63.207295 -432.560476) (xy 63.212547 -432.564281) (xy 63.226797 -432.583821)
			(xy 63.234321 -432.606805) (xy 63.234824 -432.618896) (xy 63.234824 -435.16042) (xy 63.234357 -435.172469)
			(xy 63.226922 -435.195391) (xy 63.212782 -435.214904) (xy 63.193315 -435.229108) (xy 63.170417 -435.236618)
			(xy 63.15837 -435.237128) (xy 62.218062 -435.237128) (xy 62.205967 -435.236724) (xy 62.18296 -435.229253)
			(xy 62.163378 -435.215052) (xy 62.14913 -435.195503) (xy 62.141604 -435.172514) (xy 62.1411 -435.16042)
			(xy 61.234828 -435.16042) (xy 61.234828 -436.160418) (xy 61.234455 -436.172545) (xy 61.226953 -436.19561)
			(xy 61.212691 -436.215228) (xy 61.193064 -436.229477) (xy 61.169993 -436.236963) (xy 61.157866 -436.23738)
			(xy 60.218066 -436.23738) (xy 60.205951 -436.236918) (xy 60.18291 -436.229423) (xy 60.16331 -436.215178)
			(xy 60.149069 -436.195576) (xy 60.14158 -436.172533) (xy 60.141104 -436.160418) (xy 59.206951 -436.160418)
			(xy 59.212554 -436.164477) (xy 59.226804 -436.184017) (xy 59.234329 -436.207001) (xy 59.234832 -436.219092)
			(xy 59.234832 -438.760616) (xy 59.234354 -438.772664) (xy 59.226921 -438.795584) (xy 59.212784 -438.815097)
			(xy 59.193319 -438.829301) (xy 59.170424 -438.836812) (xy 59.158378 -438.837324) (xy 58.21807 -438.837324)
			(xy 58.205975 -438.836918) (xy 58.182968 -438.829448) (xy 58.163385 -438.815247) (xy 58.149137 -438.795699)
			(xy 58.141612 -438.77271) (xy 58.141108 -438.760616) (xy 7.00913 -438.760616) (xy 7.00913 -439.760614)
			(xy 60.141104 -439.760614) (xy 60.141104 -437.21909) (xy 60.141603 -437.206978) (xy 60.149089 -437.183941)
			(xy 60.163325 -437.164342) (xy 60.182919 -437.1501) (xy 60.205954 -437.142607) (xy 60.218066 -437.142128)
			(xy 61.157866 -437.142128) (xy 61.169986 -437.142589) (xy 61.193042 -437.15007) (xy 61.212657 -437.164312)
			(xy 61.22691 -437.183918) (xy 61.234404 -437.20697) (xy 61.234828 -437.21909) (xy 61.234828 -438.760616)
			(xy 62.1411 -438.760616) (xy 62.1411 -436.219092) (xy 62.141553 -436.207041) (xy 62.148988 -436.184116)
			(xy 62.163131 -436.1646) (xy 62.182602 -436.150397) (xy 62.205505 -436.142891) (xy 62.217554 -436.142384)
			(xy 63.157862 -436.142384) (xy 63.169954 -436.142841) (xy 63.192961 -436.150292) (xy 63.206938 -436.160418)
			(xy 64.141096 -436.160418) (xy 64.141096 -435.43347) (xy 64.141414 -435.4247) (xy 64.145518 -435.407642)
			(xy 64.149224 -435.399688) (xy 64.149224 -435.39918) (xy 64.38265 -434.923184) (xy 64.387348 -434.912666)
			(xy 64.390836 -434.889909) (xy 64.387353 -434.867151) (xy 64.38265 -434.856636) (xy 64.149224 -434.38064)
			(xy 64.149224 -434.380132) (xy 64.145507 -434.37218) (xy 64.141396 -434.355122) (xy 64.141096 -434.34635)
			(xy 64.141096 -433.618894) (xy 64.141606 -433.606783) (xy 64.14909 -433.583747) (xy 64.163324 -433.564149)
			(xy 64.182915 -433.549906) (xy 64.205948 -433.542412) (xy 64.218058 -433.541932) (xy 65.157858 -433.541932)
			(xy 65.169978 -433.542396) (xy 65.193034 -433.549876) (xy 65.21265 -433.564116) (xy 65.226903 -433.583722)
			(xy 65.234397 -433.606774) (xy 65.23482 -433.618894) (xy 65.23482 -435.16042) (xy 66.141092 -435.16042)
			(xy 66.141092 -434.433472) (xy 66.141411 -434.424702) (xy 66.145514 -434.407644) (xy 66.14922 -434.39969)
			(xy 66.14922 -434.399182) (xy 66.382646 -433.923186) (xy 66.387343 -433.912668) (xy 66.390832 -433.889911)
			(xy 66.387349 -433.867153) (xy 66.382646 -433.856638) (xy 66.14922 -433.380642) (xy 66.14922 -433.380134)
			(xy 66.145504 -433.372182) (xy 66.141392 -433.355124) (xy 66.141092 -433.346352) (xy 66.141092 -432.618896)
			(xy 66.141556 -432.606846) (xy 66.148989 -432.583922) (xy 66.163129 -432.564407) (xy 66.182598 -432.550204)
			(xy 66.205498 -432.542696) (xy 66.217546 -432.542188) (xy 67.157854 -432.542188) (xy 67.169946 -432.542647)
			(xy 67.192953 -432.550097) (xy 67.207281 -432.560476) (xy 68.141088 -432.560476) (xy 68.141088 -431.833528)
			(xy 68.141393 -431.824757) (xy 68.145506 -431.8077) (xy 68.149216 -431.799746) (xy 68.149216 -431.799238)
			(xy 68.382642 -431.323242) (xy 68.387369 -431.312736) (xy 68.390848 -431.289971) (xy 68.387352 -431.267209)
			(xy 68.382642 -431.256694) (xy 68.149216 -430.780698) (xy 68.149216 -430.78019) (xy 68.145486 -430.772244)
			(xy 68.141383 -430.755181) (xy 68.141088 -430.746408) (xy 68.141088 -430.018952) (xy 68.141519 -430.0069)
			(xy 68.148963 -429.983975) (xy 68.163112 -429.964461) (xy 68.182587 -429.950259) (xy 68.205492 -429.942752)
			(xy 68.217542 -429.942244) (xy 69.15785 -429.942244) (xy 69.169937 -429.94275) (xy 69.192937 -429.950193)
			(xy 69.212518 -429.96437) (xy 69.22677 -429.983896) (xy 69.234303 -430.006866) (xy 69.234812 -430.018952)
			(xy 69.234812 -431.560478) (xy 70.141084 -431.560478) (xy 70.141084 -430.83353) (xy 70.14139 -430.824759)
			(xy 70.145502 -430.807702) (xy 70.149212 -430.799748) (xy 70.149212 -430.79924) (xy 70.382638 -430.323244)
			(xy 70.387364 -430.312737) (xy 70.390843 -430.289973) (xy 70.387348 -430.267211) (xy 70.382638 -430.256696)
			(xy 70.149212 -429.7807) (xy 70.149212 -429.780192) (xy 70.145482 -429.772246) (xy 70.141379 -429.755183)
			(xy 70.141084 -429.74641) (xy 70.141084 -429.018954) (xy 70.141473 -429.006832) (xy 70.148979 -428.98378)
			(xy 70.16324 -428.964175) (xy 70.182862 -428.949937) (xy 70.205924 -428.942459) (xy 70.218046 -428.941992)
			(xy 71.157846 -428.941992) (xy 71.169958 -428.942472) (xy 71.192995 -428.949966) (xy 71.207537 -428.960534)
			(xy 72.14108 -428.960534) (xy 72.14108 -426.41901) (xy 72.141469 -426.406884) (xy 72.148964 -426.383818)
			(xy 72.163222 -426.364199) (xy 72.182847 -426.349949) (xy 72.205915 -426.342464) (xy 72.218042 -426.342048)
			(xy 73.157842 -426.342048) (xy 73.16996 -426.342476) (xy 73.193006 -426.349976) (xy 73.212608 -426.364229)
			(xy 73.226848 -426.383841) (xy 73.234332 -426.406892) (xy 73.234804 -426.41901) (xy 73.234804 -427.960536)
			(xy 75.141328 -427.960536) (xy 75.141328 -425.419012) (xy 75.141724 -425.406926) (xy 75.149192 -425.383938)
			(xy 75.163402 -425.364384) (xy 75.18296 -425.350181) (xy 75.20595 -425.34272) (xy 75.218036 -425.342304)
			(xy 76.157836 -425.342304) (xy 76.169914 -425.342734) (xy 76.192884 -425.350207) (xy 76.212422 -425.364413)
			(xy 76.226615 -425.383959) (xy 76.234074 -425.406934) (xy 76.234544 -425.419012) (xy 76.234544 -427.960536)
			(xy 76.234067 -427.972609) (xy 76.226599 -427.995571) (xy 76.212405 -428.015105) (xy 76.192871 -428.029299)
			(xy 76.169909 -428.036767) (xy 76.157836 -428.037244) (xy 75.218036 -428.037244) (xy 75.205967 -428.036706)
			(xy 75.183007 -428.029258) (xy 75.163472 -428.015079) (xy 75.149275 -427.995558) (xy 75.141806 -427.972605)
			(xy 75.141328 -427.960536) (xy 73.234804 -427.960536) (xy 73.234804 -428.960534) (xy 73.234318 -428.972646)
			(xy 73.226827 -428.995683) (xy 73.212587 -429.015281) (xy 73.192991 -429.029523) (xy 73.169954 -429.037017)
			(xy 73.157842 -429.037496) (xy 72.218042 -429.037496) (xy 72.205925 -429.037005) (xy 72.182873 -429.029528)
			(xy 72.16326 -429.015294) (xy 72.149006 -428.995695) (xy 72.141507 -428.972651) (xy 72.14108 -428.960534)
			(xy 71.207537 -428.960534) (xy 71.212592 -428.964208) (xy 71.226834 -428.983805) (xy 71.234328 -429.006842)
			(xy 71.234808 -429.018954) (xy 71.234808 -431.560478) (xy 71.23427 -431.572587) (xy 71.226795 -431.595622)
			(xy 71.212568 -431.61522) (xy 71.192983 -431.629464) (xy 71.169954 -431.636959) (xy 71.157846 -431.63744)
			(xy 70.218046 -431.63744) (xy 70.205923 -431.637001) (xy 70.182862 -431.629518) (xy 70.163245 -431.615273)
			(xy 70.148993 -431.595659) (xy 70.141503 -431.5726) (xy 70.141084 -431.560478) (xy 69.234812 -431.560478)
			(xy 69.234812 -432.560476) (xy 69.23432 -432.572524) (xy 69.226895 -432.595447) (xy 69.212762 -432.614962)
			(xy 69.193299 -432.629166) (xy 69.170404 -432.636675) (xy 69.158358 -432.637184) (xy 68.21805 -432.637184)
			(xy 68.205965 -432.636651) (xy 68.18297 -432.62921) (xy 68.163392 -432.61504) (xy 68.149139 -432.595522)
			(xy 68.141601 -432.572559) (xy 68.141088 -432.560476) (xy 67.207281 -432.560476) (xy 67.212538 -432.564284)
			(xy 67.226788 -432.583823) (xy 67.234313 -432.606806) (xy 67.234816 -432.618896) (xy 67.234816 -435.16042)
			(xy 67.234357 -435.17247) (xy 67.226921 -435.195393) (xy 67.212779 -435.214907) (xy 67.19331 -435.22911)
			(xy 67.17041 -435.236619) (xy 67.158362 -435.237128) (xy 66.218054 -435.237128) (xy 66.205959 -435.236731)
			(xy 66.182951 -435.229258) (xy 66.163369 -435.215054) (xy 66.149122 -435.195505) (xy 66.141596 -435.172514)
			(xy 66.141092 -435.16042) (xy 65.23482 -435.16042) (xy 65.23482 -436.160418) (xy 65.234454 -436.172546)
			(xy 65.226952 -436.195612) (xy 65.212688 -436.215231) (xy 65.193058 -436.22948) (xy 65.169986 -436.236964)
			(xy 65.157858 -436.23738) (xy 64.218058 -436.23738) (xy 64.205943 -436.236924) (xy 64.182901 -436.229428)
			(xy 64.163302 -436.215181) (xy 64.149061 -436.195577) (xy 64.141572 -436.172533) (xy 64.141096 -436.160418)
			(xy 63.206938 -436.160418) (xy 63.212545 -436.16448) (xy 63.226795 -436.184019) (xy 63.234321 -436.207002)
			(xy 63.234824 -436.219092) (xy 63.234824 -438.760616) (xy 63.234354 -438.772665) (xy 63.22692 -438.795587)
			(xy 63.212781 -438.8151) (xy 63.193314 -438.829304) (xy 63.170417 -438.836814) (xy 63.15837 -438.837324)
			(xy 62.218062 -438.837324) (xy 62.205967 -438.836924) (xy 62.182959 -438.829453) (xy 62.163377 -438.81525)
			(xy 62.149129 -438.795701) (xy 62.141604 -438.77271) (xy 62.1411 -438.760616) (xy 61.234828 -438.760616)
			(xy 61.234828 -439.760614) (xy 64.141096 -439.760614) (xy 64.141096 -437.21909) (xy 64.141603 -437.206979)
			(xy 64.149088 -437.183943) (xy 64.163322 -437.164345) (xy 64.182914 -437.150102) (xy 64.205947 -437.142608)
			(xy 64.218058 -437.142128) (xy 65.157858 -437.142128) (xy 65.169978 -437.142595) (xy 65.193033 -437.150075)
			(xy 65.212648 -437.164315) (xy 65.226901 -437.18392) (xy 65.234396 -437.206971) (xy 65.23482 -437.21909)
			(xy 65.23482 -438.760616) (xy 66.141092 -438.760616) (xy 66.141092 -436.219092) (xy 66.141553 -436.207042)
			(xy 66.148987 -436.184118) (xy 66.163128 -436.164603) (xy 66.182597 -436.1504) (xy 66.205498 -436.142892)
			(xy 66.217546 -436.142384) (xy 67.157854 -436.142384) (xy 67.169946 -436.142847) (xy 67.192952 -436.150297)
			(xy 67.206925 -436.160418) (xy 68.141088 -436.160418) (xy 68.141088 -435.43347) (xy 68.141407 -435.4247)
			(xy 68.14551 -435.407642) (xy 68.149216 -435.399688) (xy 68.149216 -435.39918) (xy 68.382642 -434.923184)
			(xy 68.38734 -434.912667) (xy 68.390829 -434.889909) (xy 68.387346 -434.867151) (xy 68.382642 -434.856636)
			(xy 68.149216 -434.38064) (xy 68.149216 -434.380132) (xy 68.145499 -434.372181) (xy 68.141388 -434.355122)
			(xy 68.141088 -434.34635) (xy 68.141088 -433.618894) (xy 68.141606 -433.606784) (xy 68.149089 -433.583749)
			(xy 68.163321 -433.564152) (xy 68.18291 -433.549909) (xy 68.20594 -433.542413) (xy 68.21805 -433.541932)
			(xy 69.15785 -433.541932) (xy 69.169967 -433.542369) (xy 69.19301 -433.549869) (xy 69.212611 -433.564121)
			(xy 69.226851 -433.583729) (xy 69.234338 -433.606777) (xy 69.234812 -433.618894) (xy 69.234812 -435.16042)
			(xy 70.141084 -435.16042) (xy 70.141084 -434.433472) (xy 70.141404 -434.424702) (xy 70.145506 -434.407645)
			(xy 70.149212 -434.39969) (xy 70.149212 -434.399182) (xy 70.382638 -433.923186) (xy 70.387335 -433.912668)
			(xy 70.390825 -433.889911) (xy 70.387342 -433.867153) (xy 70.382638 -433.856638) (xy 70.149212 -433.380642)
			(xy 70.149212 -433.380134) (xy 70.145495 -433.372182) (xy 70.141384 -433.355124) (xy 70.141084 -433.346352)
			(xy 70.141084 -432.618896) (xy 70.141556 -432.606847) (xy 70.148988 -432.583924) (xy 70.163126 -432.56441)
			(xy 70.182593 -432.550206) (xy 70.205491 -432.542697) (xy 70.217538 -432.542188) (xy 71.157846 -432.542188)
			(xy 71.169943 -432.542569) (xy 71.192953 -432.550044) (xy 71.207333 -432.560476) (xy 72.14108 -432.560476)
			(xy 72.14108 -431.833528) (xy 72.141385 -431.824757) (xy 72.145498 -431.8077) (xy 72.149208 -431.799746)
			(xy 72.149208 -431.799238) (xy 72.382634 -431.323242) (xy 72.387362 -431.312736) (xy 72.39084 -431.289971)
			(xy 72.387345 -431.267209) (xy 72.382634 -431.256694) (xy 72.149208 -430.780698) (xy 72.149208 -430.78019)
			(xy 72.145477 -430.772244) (xy 72.141374 -430.755181) (xy 72.14108 -430.746408) (xy 72.14108 -430.018952)
			(xy 72.141519 -430.006901) (xy 72.148962 -429.983977) (xy 72.163109 -429.964464) (xy 72.182582 -429.950262)
			(xy 72.205485 -429.942753) (xy 72.217534 -429.942244) (xy 73.157842 -429.942244) (xy 73.169934 -429.942672)
			(xy 73.192937 -429.95014) (xy 73.212516 -429.964337) (xy 73.226765 -429.983879) (xy 73.234296 -430.006861)
			(xy 73.234804 -430.018952) (xy 73.234804 -431.560478) (xy 75.141328 -431.560478) (xy 75.141328 -430.833276)
			(xy 75.141577 -430.824519) (xy 75.145558 -430.807461) (xy 75.149202 -430.799494) (xy 75.382628 -430.323244)
			(xy 75.387355 -430.312738) (xy 75.390834 -430.289973) (xy 75.387339 -430.267211) (xy 75.382628 -430.256696)
			(xy 75.149202 -429.780446) (xy 75.145554 -429.772479) (xy 75.141569 -429.755422) (xy 75.141328 -429.746664)
			(xy 75.141328 -429.018954) (xy 75.141768 -429.006863) (xy 75.149236 -428.983863) (xy 75.16343 -428.964285)
			(xy 75.182968 -428.950036) (xy 75.205947 -428.942503) (xy 75.218036 -428.941992) (xy 76.157836 -428.941992)
			(xy 76.169946 -428.942386) (xy 76.192973 -428.949894) (xy 76.207568 -428.960534) (xy 77.141324 -428.960534)
			(xy 77.141324 -426.41901) (xy 77.141816 -426.406923) (xy 77.149268 -426.383925) (xy 77.163449 -426.364346)
			(xy 77.182976 -426.350095) (xy 77.205946 -426.34256) (xy 77.218032 -426.342048) (xy 78.157832 -426.342048)
			(xy 78.169937 -426.342488) (xy 78.192957 -426.34999) (xy 78.212525 -426.364248) (xy 78.22672 -426.38386)
			(xy 78.234149 -426.406903) (xy 78.23454 -426.41901) (xy 78.23454 -427.960536) (xy 79.14132 -427.960536)
			(xy 79.14132 -425.419012) (xy 79.141724 -425.406927) (xy 79.149191 -425.38394) (xy 79.163399 -425.364387)
			(xy 79.182954 -425.350184) (xy 79.205943 -425.342721) (xy 79.218028 -425.342304) (xy 80.157828 -425.342304)
			(xy 80.169905 -425.34274) (xy 80.192875 -425.350212) (xy 80.212413 -425.364415) (xy 80.226606 -425.38396)
			(xy 80.234066 -425.406935) (xy 80.234536 -425.419012) (xy 80.234536 -427.960536) (xy 80.234067 -427.97261)
			(xy 80.226598 -427.995573) (xy 80.212402 -428.015107) (xy 80.192866 -428.029302) (xy 80.169902 -428.036768)
			(xy 80.157828 -428.037244) (xy 79.218028 -428.037244) (xy 79.205958 -428.036713) (xy 79.182998 -428.029262)
			(xy 79.163464 -428.015082) (xy 79.149267 -427.995559) (xy 79.141797 -427.972605) (xy 79.14132 -427.960536)
			(xy 78.23454 -427.960536) (xy 78.23454 -428.960534) (xy 78.234121 -428.972627) (xy 78.226653 -428.995632)
			(xy 78.212454 -429.015214) (xy 78.19291 -429.029462) (xy 78.169924 -429.03699) (xy 78.157832 -429.037496)
			(xy 77.218032 -429.037496) (xy 77.205924 -429.037056) (xy 77.182898 -429.029565) (xy 77.163324 -429.01531)
			(xy 77.149128 -428.995692) (xy 77.141707 -428.972643) (xy 77.141324 -428.960534) (xy 76.207568 -428.960534)
			(xy 76.212545 -428.964162) (xy 76.226738 -428.983787) (xy 76.23416 -429.006843) (xy 76.234544 -429.018954)
			(xy 76.234544 -431.560478) (xy 76.234074 -431.572568) (xy 76.226621 -431.595571) (xy 76.212436 -431.615152)
			(xy 76.192902 -431.629403) (xy 76.169924 -431.636933) (xy 76.157836 -431.63744) (xy 75.218036 -431.63744)
			(xy 75.205933 -431.636953) (xy 75.182914 -431.629469) (xy 75.163344 -431.615224) (xy 75.149146 -431.595619)
			(xy 75.141718 -431.572582) (xy 75.141328 -431.560478) (xy 73.234804 -431.560478) (xy 73.234804 -432.560476)
			(xy 73.23432 -432.572525) (xy 73.226894 -432.595449) (xy 73.212759 -432.614964) (xy 73.193294 -432.629169)
			(xy 73.170397 -432.636676) (xy 73.15835 -432.637184) (xy 72.218042 -432.637184) (xy 72.205957 -432.636657)
			(xy 72.182962 -432.629215) (xy 72.163383 -432.615043) (xy 72.14913 -432.595523) (xy 72.141593 -432.572559)
			(xy 72.14108 -432.560476) (xy 71.207333 -432.560476) (xy 71.212536 -432.564251) (xy 71.226784 -432.583805)
			(xy 71.234306 -432.6068) (xy 71.234808 -432.618896) (xy 71.234808 -435.16042) (xy 71.234357 -435.17247)
			(xy 71.22692 -435.195395) (xy 71.212776 -435.21491) (xy 71.193305 -435.229113) (xy 71.170403 -435.23662)
			(xy 71.158354 -435.237128) (xy 70.218046 -435.237128) (xy 70.205956 -435.236653) (xy 70.182951 -435.229205)
			(xy 70.163368 -435.215022) (xy 70.149117 -435.195487) (xy 70.141589 -435.172509) (xy 70.141084 -435.16042)
			(xy 69.234812 -435.16042) (xy 69.234812 -436.160418) (xy 69.234305 -436.172529) (xy 69.226818 -436.195564)
			(xy 69.212584 -436.215161) (xy 69.192993 -436.229404) (xy 69.16996 -436.2369) (xy 69.15785 -436.23738)
			(xy 68.21805 -436.23738) (xy 68.205935 -436.236931) (xy 68.182893 -436.229432) (xy 68.163293 -436.215184)
			(xy 68.149053 -436.195578) (xy 68.141564 -436.172534) (xy 68.141088 -436.160418) (xy 67.206925 -436.160418)
			(xy 67.212537 -436.164483) (xy 67.226787 -436.18402) (xy 67.234312 -436.207002) (xy 67.234816 -436.219092)
			(xy 67.234816 -438.760616) (xy 67.234354 -438.772665) (xy 67.226919 -438.795589) (xy 67.212778 -438.815103)
			(xy 67.193309 -438.829306) (xy 67.17041 -438.836815) (xy 67.158362 -438.837324) (xy 66.218054 -438.837324)
			(xy 66.205958 -438.836931) (xy 66.18295 -438.829457) (xy 66.163368 -438.815253) (xy 66.14912 -438.795702)
			(xy 66.141596 -438.77271) (xy 66.141092 -438.760616) (xy 65.23482 -438.760616) (xy 65.23482 -439.760614)
			(xy 68.141088 -439.760614) (xy 68.141088 -437.21909) (xy 68.141603 -437.20698) (xy 68.149087 -437.183945)
			(xy 68.163319 -437.164348) (xy 68.182909 -437.150105) (xy 68.20594 -437.142609) (xy 68.21805 -437.142128)
			(xy 69.15785 -437.142128) (xy 69.169966 -437.142569) (xy 69.193009 -437.150069) (xy 69.212609 -437.164319)
			(xy 69.22685 -437.183927) (xy 69.234337 -437.206974) (xy 69.234812 -437.21909) (xy 69.234812 -438.760616)
			(xy 70.141084 -438.760616) (xy 70.141084 -436.219092) (xy 70.141553 -436.207043) (xy 70.148986 -436.18412)
			(xy 70.163125 -436.164606) (xy 70.182592 -436.150402) (xy 70.205491 -436.142893) (xy 70.217538 -436.142384)
			(xy 71.157846 -436.142384) (xy 71.169942 -436.142769) (xy 71.192952 -436.150244) (xy 71.206977 -436.160418)
			(xy 72.14108 -436.160418) (xy 72.14108 -435.43347) (xy 72.141399 -435.4247) (xy 72.145502 -435.407643)
			(xy 72.149208 -435.399688) (xy 72.149208 -435.39918) (xy 72.382634 -434.923184) (xy 72.387333 -434.912667)
			(xy 72.390822 -434.889909) (xy 72.387338 -434.867151) (xy 72.382634 -434.856636) (xy 72.149208 -434.38064)
			(xy 72.149208 -434.380132) (xy 72.14549 -434.372181) (xy 72.141379 -434.355122) (xy 72.14108 -434.34635)
			(xy 72.14108 -433.618894) (xy 72.141456 -433.606767) (xy 72.148955 -433.583701) (xy 72.163216 -433.564082)
			(xy 72.182844 -433.549833) (xy 72.205915 -433.542348) (xy 72.218042 -433.541932) (xy 73.157842 -433.541932)
			(xy 73.169958 -433.542376) (xy 73.193002 -433.549874) (xy 73.212602 -433.564123) (xy 73.226843 -433.583731)
			(xy 73.23433 -433.606778) (xy 73.234804 -433.618894) (xy 73.234804 -435.16042) (xy 75.141328 -435.16042)
			(xy 75.141328 -434.433218) (xy 75.141591 -434.424462) (xy 75.145562 -434.407404) (xy 75.149202 -434.399436)
			(xy 75.382628 -433.923186) (xy 75.387326 -433.912668) (xy 75.390816 -433.889911) (xy 75.387332 -433.867152)
			(xy 75.382628 -433.856638) (xy 75.149202 -433.380388) (xy 75.145536 -433.372429) (xy 75.141562 -433.355366)
			(xy 75.141328 -433.346606) (xy 75.141328 -432.618896) (xy 75.14171 -432.606809) (xy 75.149183 -432.58382)
			(xy 75.163396 -432.564267) (xy 75.182956 -432.550064) (xy 75.205949 -432.542603) (xy 75.218036 -432.542188)
			(xy 76.157836 -432.542188) (xy 76.169912 -432.542633) (xy 76.19288 -432.550105) (xy 76.207146 -432.560476)
			(xy 77.141324 -432.560476) (xy 77.141324 -431.833274) (xy 77.141573 -431.824517) (xy 77.145554 -431.807459)
			(xy 77.149198 -431.799492) (xy 77.382624 -431.323242) (xy 77.387352 -431.312736) (xy 77.390831 -431.289971)
			(xy 77.387335 -431.267209) (xy 77.382624 -431.256694) (xy 77.149198 -430.780444) (xy 77.145549 -430.772478)
			(xy 77.141565 -430.75542) (xy 77.141324 -430.746662) (xy 77.141324 -430.018952) (xy 77.141724 -430.006872)
			(xy 77.149203 -429.983898) (xy 77.163415 -429.964358) (xy 77.182969 -429.950167) (xy 77.205951 -429.942711)
			(xy 77.218032 -429.942244) (xy 78.157832 -429.942244) (xy 78.169903 -429.942736) (xy 78.192864 -429.950201)
			(xy 78.212396 -429.964393) (xy 78.226591 -429.983922) (xy 78.234062 -430.006881) (xy 78.23454 -430.018952)
			(xy 78.23454 -431.560478) (xy 79.14132 -431.560478) (xy 79.14132 -430.833276) (xy 79.14157 -430.824519)
			(xy 79.14555 -430.807461) (xy 79.149194 -430.799494) (xy 79.38262 -430.323244) (xy 79.387347 -430.312738)
			(xy 79.390827 -430.289973) (xy 79.387331 -430.267211) (xy 79.38262 -430.256696) (xy 79.149194 -429.780446)
			(xy 79.145546 -429.77248) (xy 79.141561 -429.755422) (xy 79.14132 -429.746664) (xy 79.14132 -429.018954)
			(xy 79.141768 -429.006864) (xy 79.149235 -428.983865) (xy 79.163427 -428.964288) (xy 79.182963 -428.950038)
			(xy 79.205939 -428.942504) (xy 79.218028 -428.941992) (xy 80.157828 -428.941992) (xy 80.169938 -428.942392)
			(xy 80.192964 -428.949899) (xy 80.207555 -428.960534) (xy 81.141316 -428.960534) (xy 81.141316 -426.41901)
			(xy 81.141816 -426.406923) (xy 81.149267 -426.383927) (xy 81.163446 -426.364349) (xy 81.182971 -426.350097)
			(xy 81.205939 -426.342561) (xy 81.218024 -426.342048) (xy 82.157824 -426.342048) (xy 82.169929 -426.342495)
			(xy 82.192948 -426.349995) (xy 82.212516 -426.36425) (xy 82.226712 -426.383862) (xy 82.234141 -426.406904)
			(xy 82.234532 -426.41901) (xy 82.234532 -427.960536) (xy 83.141312 -427.960536) (xy 83.141312 -425.419012)
			(xy 83.141723 -425.406928) (xy 83.14919 -425.383942) (xy 83.163396 -425.36439) (xy 83.182949 -425.350186)
			(xy 83.205936 -425.342722) (xy 83.21802 -425.342304) (xy 84.15782 -425.342304) (xy 84.169897 -425.342748)
			(xy 84.192867 -425.350217) (xy 84.212404 -425.364419) (xy 84.226598 -425.383962) (xy 84.234057 -425.406935)
			(xy 84.234528 -425.419012) (xy 84.234528 -427.960536) (xy 84.234067 -427.97261) (xy 84.226597 -427.995576)
			(xy 84.212399 -428.01511) (xy 84.192861 -428.029304) (xy 84.169895 -428.036769) (xy 84.15782 -428.037244)
			(xy 83.21802 -428.037244) (xy 83.20595 -428.036719) (xy 83.18299 -428.029267) (xy 83.163455 -428.015085)
			(xy 83.149259 -427.995561) (xy 83.141789 -427.972606) (xy 83.141312 -427.960536) (xy 82.234532 -427.960536)
			(xy 82.234532 -428.960534) (xy 82.234121 -428.972628) (xy 82.226652 -428.995635) (xy 82.212452 -429.015216)
			(xy 82.192905 -429.029465) (xy 82.169917 -429.036991) (xy 82.157824 -429.037496) (xy 81.218024 -429.037496)
			(xy 81.205916 -429.037063) (xy 81.182889 -429.02957) (xy 81.163315 -429.015313) (xy 81.14912 -428.995694)
			(xy 81.141699 -428.972643) (xy 81.141316 -428.960534) (xy 80.207555 -428.960534) (xy 80.212536 -428.964165)
			(xy 80.22673 -428.983789) (xy 80.234152 -429.006843) (xy 80.234536 -429.018954) (xy 80.234536 -431.560478)
			(xy 80.234073 -431.572569) (xy 80.22662 -431.595573) (xy 80.212433 -431.615155) (xy 80.192897 -431.629405)
			(xy 80.169917 -431.636934) (xy 80.157828 -431.63744) (xy 79.218028 -431.63744) (xy 79.205925 -431.63696)
			(xy 79.182905 -431.629473) (xy 79.163335 -431.615227) (xy 79.149138 -431.595621) (xy 79.141709 -431.572582)
			(xy 79.14132 -431.560478) (xy 78.23454 -431.560478) (xy 78.23454 -432.560476) (xy 78.234016 -432.572546)
			(xy 78.226564 -432.595507) (xy 78.212382 -432.615042) (xy 78.192857 -432.629238) (xy 78.169902 -432.636707)
			(xy 78.157832 -432.637184) (xy 77.218032 -432.637184) (xy 77.205949 -432.63676) (xy 77.182963 -432.629298)
			(xy 77.16341 -432.615096) (xy 77.149206 -432.595544) (xy 77.141742 -432.572559) (xy 77.141324 -432.560476)
			(xy 76.207146 -432.560476) (xy 76.212416 -432.564307) (xy 76.226609 -432.583849) (xy 76.234072 -432.60682)
			(xy 76.234544 -432.618896) (xy 76.234544 -435.16042) (xy 76.234053 -435.172492) (xy 76.22659 -435.195454)
			(xy 76.212399 -435.214987) (xy 76.192868 -435.229182) (xy 76.169908 -435.236651) (xy 76.157836 -435.237128)
			(xy 75.218036 -435.237128) (xy 75.205957 -435.236657) (xy 75.182979 -435.229202) (xy 75.16343 -435.21501)
			(xy 75.149224 -435.195471) (xy 75.141752 -435.172499) (xy 75.141328 -435.16042) (xy 73.234804 -435.16042)
			(xy 73.234804 -436.160418) (xy 73.234304 -436.172529) (xy 73.226817 -436.195566) (xy 73.212581 -436.215164)
			(xy 73.192988 -436.229406) (xy 73.169953 -436.236901) (xy 73.157842 -436.23738) (xy 72.218042 -436.23738)
			(xy 72.205923 -436.236905) (xy 72.182869 -436.229426) (xy 72.163255 -436.215188) (xy 72.149001 -436.195585)
			(xy 72.141505 -436.172536) (xy 72.14108 -436.160418) (xy 71.206977 -436.160418) (xy 71.212535 -436.16445)
			(xy 71.226782 -436.184003) (xy 71.234305 -436.206997) (xy 71.234808 -436.219092) (xy 71.234808 -438.760616)
			(xy 71.234354 -438.772666) (xy 71.226918 -438.795591) (xy 71.212775 -438.815106) (xy 71.193304 -438.829309)
			(xy 71.170403 -438.836816) (xy 71.158354 -438.837324) (xy 70.218046 -438.837324) (xy 70.205955 -438.836853)
			(xy 70.18295 -438.829404) (xy 70.163366 -438.81522) (xy 70.149115 -438.795685) (xy 70.141589 -438.772705)
			(xy 70.141084 -438.760616) (xy 69.234812 -438.760616) (xy 69.234812 -439.760614) (xy 72.14108 -439.760614)
			(xy 72.14108 -437.21909) (xy 72.141452 -437.206963) (xy 72.148952 -437.183896) (xy 72.163215 -437.164278)
			(xy 72.182843 -437.150029) (xy 72.205914 -437.142544) (xy 72.218042 -437.142128) (xy 73.157842 -437.142128)
			(xy 73.169958 -437.142576) (xy 73.193001 -437.150073) (xy 73.212601 -437.164322) (xy 73.226841 -437.183928)
			(xy 73.234329 -437.206974) (xy 73.234804 -437.21909) (xy 73.234804 -438.760616) (xy 75.141328 -438.760616)
			(xy 75.141328 -436.219092) (xy 75.141706 -436.207005) (xy 75.14918 -436.184016) (xy 75.163394 -436.164463)
			(xy 75.182956 -436.15026) (xy 75.205949 -436.142799) (xy 75.218036 -436.142384) (xy 76.157836 -436.142384)
			(xy 76.169912 -436.142833) (xy 76.192879 -436.150305) (xy 76.206792 -436.160418) (xy 77.141324 -436.160418)
			(xy 77.141324 -435.433216) (xy 77.141586 -435.42446) (xy 77.145558 -435.407402) (xy 77.149198 -435.399434)
			(xy 77.382624 -434.923184) (xy 77.387323 -434.912667) (xy 77.390813 -434.889909) (xy 77.387329 -434.86715)
			(xy 77.382624 -434.856636) (xy 77.149198 -434.380386) (xy 77.145531 -434.372427) (xy 77.141558 -434.355364)
			(xy 77.141324 -434.346604) (xy 77.141324 -433.618894) (xy 77.141802 -433.606806) (xy 77.149259 -433.583808)
			(xy 77.163443 -433.564229) (xy 77.182973 -433.549978) (xy 77.205945 -433.542444) (xy 77.218032 -433.541932)
			(xy 78.157832 -433.541932) (xy 78.169946 -433.542289) (xy 78.19298 -433.549802) (xy 78.212555 -433.564077)
			(xy 78.226747 -433.583713) (xy 78.234161 -433.606779) (xy 78.23454 -433.618894) (xy 78.23454 -435.16042)
			(xy 79.14132 -435.16042) (xy 79.14132 -434.433218) (xy 79.141583 -434.424462) (xy 79.145554 -434.407404)
			(xy 79.149194 -434.399436) (xy 79.38262 -433.923186) (xy 79.387318 -433.912668) (xy 79.390808 -433.889911)
			(xy 79.387325 -433.867152) (xy 79.38262 -433.856638) (xy 79.149194 -433.380388) (xy 79.145527 -433.372429)
			(xy 79.141554 -433.355366) (xy 79.14132 -433.346606) (xy 79.14132 -432.618896) (xy 79.141709 -432.60681)
			(xy 79.149182 -432.583823) (xy 79.163393 -432.56427) (xy 79.182951 -432.550067) (xy 79.205942 -432.542604)
			(xy 79.218028 -432.542188) (xy 80.157828 -432.542188) (xy 80.169904 -432.54264) (xy 80.192871 -432.55011)
			(xy 80.207132 -432.560476) (xy 81.141316 -432.560476) (xy 81.141316 -431.833274) (xy 81.141565 -431.824517)
			(xy 81.145546 -431.807459) (xy 81.14919 -431.799492) (xy 81.382616 -431.323242) (xy 81.387345 -431.312736)
			(xy 81.390824 -431.289971) (xy 81.387328 -431.267209) (xy 81.382616 -431.256694) (xy 81.14919 -430.780444)
			(xy 81.145541 -430.772478) (xy 81.141557 -430.75542) (xy 81.141316 -430.746662) (xy 81.141316 -430.018952)
			(xy 81.141724 -430.006873) (xy 81.149202 -429.9839) (xy 81.163413 -429.964361) (xy 81.182964 -429.950169)
			(xy 81.205944 -429.942712) (xy 81.218024 -429.942244) (xy 82.157824 -429.942244) (xy 82.169895 -429.942743)
			(xy 82.192855 -429.950206) (xy 82.212387 -429.964396) (xy 82.226583 -429.983924) (xy 82.234053 -430.006881)
			(xy 82.234532 -430.018952) (xy 82.234532 -431.560478) (xy 83.141312 -431.560478) (xy 83.141312 -430.833276)
			(xy 83.141562 -430.824519) (xy 83.145542 -430.807461) (xy 83.149186 -430.799494) (xy 83.382612 -430.323244)
			(xy 83.38734 -430.312738) (xy 83.39082 -430.289973) (xy 83.387323 -430.267211) (xy 83.382612 -430.256696)
			(xy 83.149186 -429.780446) (xy 83.145537 -429.77248) (xy 83.141553 -429.755422) (xy 83.141312 -429.746664)
			(xy 83.141312 -429.018954) (xy 83.141768 -429.006865) (xy 83.149234 -428.983867) (xy 83.163424 -428.964291)
			(xy 83.182958 -428.950041) (xy 83.205932 -428.942505) (xy 83.21802 -428.941992) (xy 84.15782 -428.941992)
			(xy 84.169929 -428.942399) (xy 84.192956 -428.949903) (xy 84.207543 -428.960534) (xy 85.141308 -428.960534)
			(xy 85.141308 -426.41901) (xy 85.141815 -426.406924) (xy 85.149265 -426.383929) (xy 85.163443 -426.364352)
			(xy 85.182966 -426.3501) (xy 85.205932 -426.342562) (xy 85.218016 -426.342048) (xy 86.157816 -426.342048)
			(xy 86.169921 -426.342502) (xy 86.192939 -426.349999) (xy 86.212508 -426.364253) (xy 86.226704 -426.383863)
			(xy 86.234133 -426.406904) (xy 86.234524 -426.41901) (xy 86.234524 -427.960536) (xy 87.141304 -427.960536)
			(xy 87.141304 -425.419012) (xy 87.141723 -425.406929) (xy 87.149189 -425.383944) (xy 87.163393 -425.364393)
			(xy 87.182944 -425.350189) (xy 87.205929 -425.342723) (xy 87.218012 -425.342304) (xy 88.157812 -425.342304)
			(xy 88.169888 -425.342754) (xy 88.192858 -425.350222) (xy 88.212396 -425.364421) (xy 88.226589 -425.383964)
			(xy 88.234049 -425.406935) (xy 88.23452 -425.419012) (xy 88.23452 -427.960536) (xy 88.234067 -427.972611)
			(xy 88.226596 -427.995578) (xy 88.212396 -428.015113) (xy 88.192856 -428.029307) (xy 88.169887 -428.036771)
			(xy 88.157812 -428.037244) (xy 87.218012 -428.037244) (xy 87.205942 -428.036726) (xy 87.182981 -428.029271)
			(xy 87.163447 -428.015087) (xy 87.149251 -427.995562) (xy 87.141781 -427.972606) (xy 87.141304 -427.960536)
			(xy 86.234524 -427.960536) (xy 86.234524 -428.960534) (xy 86.234121 -428.972629) (xy 86.226651 -428.995637)
			(xy 86.212449 -429.015219) (xy 86.1929 -429.029467) (xy 86.16991 -429.036992) (xy 86.157816 -429.037496)
			(xy 85.218016 -429.037496) (xy 85.205908 -429.03707) (xy 85.18288 -429.029574) (xy 85.163307 -429.015315)
			(xy 85.149112 -428.995695) (xy 85.141691 -428.972644) (xy 85.141308 -428.960534) (xy 84.207543 -428.960534)
			(xy 84.212528 -428.964167) (xy 84.226722 -428.98379) (xy 84.234144 -429.006843) (xy 84.234528 -429.018954)
			(xy 84.234528 -431.560478) (xy 84.234073 -431.57257) (xy 84.226619 -431.595575) (xy 84.21243 -431.615158)
			(xy 84.192892 -431.629408) (xy 84.16991 -431.636935) (xy 84.15782 -431.63744) (xy 83.21802 -431.63744)
			(xy 83.205916 -431.636967) (xy 83.182896 -431.629478) (xy 83.163327 -431.61523) (xy 83.14913 -431.595622)
			(xy 83.141701 -431.572583) (xy 83.141312 -431.560478) (xy 82.234532 -431.560478) (xy 82.234532 -432.560476)
			(xy 82.234016 -432.572547) (xy 82.226563 -432.595509) (xy 82.212379 -432.615045) (xy 82.192852 -432.629241)
			(xy 82.169895 -432.636708) (xy 82.157824 -432.637184) (xy 81.218024 -432.637184) (xy 81.20594 -432.636766)
			(xy 81.182954 -432.629303) (xy 81.163401 -432.615099) (xy 81.149197 -432.595546) (xy 81.141734 -432.57256)
			(xy 81.141316 -432.560476) (xy 80.207132 -432.560476) (xy 80.212407 -432.56431) (xy 80.226601 -432.58385)
			(xy 80.234064 -432.60682) (xy 80.234536 -432.618896) (xy 80.234536 -435.16042) (xy 80.234053 -435.172493)
			(xy 80.226588 -435.195456) (xy 80.212396 -435.21499) (xy 80.192863 -435.229185) (xy 80.169901 -435.236652)
			(xy 80.157828 -435.237128) (xy 79.218028 -435.237128) (xy 79.205949 -435.236664) (xy 79.18297 -435.229206)
			(xy 79.163421 -435.215013) (xy 79.149216 -435.195473) (xy 79.141744 -435.172499) (xy 79.14132 -435.16042)
			(xy 78.23454 -435.16042) (xy 78.23454 -436.160418) (xy 78.234108 -436.172511) (xy 78.226644 -436.195515)
			(xy 78.212449 -436.215097) (xy 78.192907 -436.229346) (xy 78.169923 -436.236874) (xy 78.157832 -436.23738)
			(xy 77.218032 -436.23738) (xy 77.205923 -436.236956) (xy 77.182893 -436.229463) (xy 77.163318 -436.215204)
			(xy 77.149123 -436.195582) (xy 77.141705 -436.172528) (xy 77.141324 -436.160418) (xy 76.206792 -436.160418)
			(xy 76.212415 -436.164505) (xy 76.226608 -436.184046) (xy 76.234071 -436.207016) (xy 76.234544 -436.219092)
			(xy 76.234544 -438.760616) (xy 76.23405 -438.772688) (xy 76.226587 -438.795649) (xy 76.212397 -438.815183)
			(xy 76.192867 -438.829378) (xy 76.169908 -438.836847) (xy 76.157836 -438.837324) (xy 75.218036 -438.837324)
			(xy 75.205957 -438.836857) (xy 75.182978 -438.829401) (xy 75.163428 -438.815209) (xy 75.149223 -438.795669)
			(xy 75.141751 -438.772695) (xy 75.141328 -438.760616) (xy 73.234804 -438.760616) (xy 73.234804 -439.760614)
			(xy 77.141324 -439.760614) (xy 77.141324 -437.21909) (xy 77.141799 -437.207002) (xy 77.149256 -437.184003)
			(xy 77.163441 -437.164425) (xy 77.182972 -437.150174) (xy 77.205945 -437.14264) (xy 77.218032 -437.142128)
			(xy 78.157832 -437.142128) (xy 78.169945 -437.142489) (xy 78.192978 -437.150001) (xy 78.212553 -437.164276)
			(xy 78.226746 -437.183911) (xy 78.234161 -437.206975) (xy 78.23454 -437.21909) (xy 78.23454 -438.760616)
			(xy 79.14132 -438.760616) (xy 79.14132 -436.219092) (xy 79.141706 -436.207006) (xy 79.149179 -436.184018)
			(xy 79.163391 -436.164466) (xy 79.182951 -436.150263) (xy 79.205942 -436.1428) (xy 79.218028 -436.142384)
			(xy 80.157828 -436.142384) (xy 80.169903 -436.14284) (xy 80.19287 -436.150309) (xy 80.206779 -436.160418)
			(xy 81.141316 -436.160418) (xy 81.141316 -435.433216) (xy 81.141579 -435.42446) (xy 81.14555 -435.407402)
			(xy 81.14919 -435.399434) (xy 81.382616 -434.923184) (xy 81.387316 -434.912667) (xy 81.390806 -434.889909)
			(xy 81.387321 -434.86715) (xy 81.382616 -434.856636) (xy 81.14919 -434.380386) (xy 81.145523 -434.372427)
			(xy 81.14155 -434.355364) (xy 81.141316 -434.346604) (xy 81.141316 -433.618894) (xy 81.141802 -433.606807)
			(xy 81.149257 -433.58381) (xy 81.16344 -433.564232) (xy 81.182968 -433.549981) (xy 81.205938 -433.542445)
			(xy 81.218024 -433.541932) (xy 82.157824 -433.541932) (xy 82.169937 -433.542296) (xy 82.192971 -433.549806)
			(xy 82.212546 -433.56408) (xy 82.226739 -433.583715) (xy 82.234153 -433.606779) (xy 82.234532 -433.618894)
			(xy 82.234532 -435.16042) (xy 83.141312 -435.16042) (xy 83.141312 -434.433218) (xy 83.141576 -434.424462)
			(xy 83.145547 -434.407404) (xy 83.149186 -434.399436) (xy 83.382612 -433.923186) (xy 83.38731 -433.912668)
			(xy 83.390801 -433.889911) (xy 83.387317 -433.867152) (xy 83.382612 -433.856638) (xy 83.149186 -433.380388)
			(xy 83.145519 -433.372429) (xy 83.141546 -433.355366) (xy 83.141312 -433.346606) (xy 83.141312 -432.618896)
			(xy 83.141709 -432.606811) (xy 83.14918 -432.583825) (xy 83.16339 -432.564273) (xy 83.182946 -432.550069)
			(xy 83.205935 -432.542606) (xy 83.21802 -432.542188) (xy 84.15782 -432.542188) (xy 84.169895 -432.542647)
			(xy 84.192862 -432.550115) (xy 84.207119 -432.560476) (xy 85.141308 -432.560476) (xy 85.141308 -431.833274)
			(xy 85.141558 -431.824517) (xy 85.145538 -431.807459) (xy 85.149182 -431.799492) (xy 85.382608 -431.323242)
			(xy 85.387337 -431.312736) (xy 85.390817 -431.289971) (xy 85.38732 -431.267208) (xy 85.382608 -431.256694)
			(xy 85.149182 -430.780444) (xy 85.145532 -430.772478) (xy 85.141549 -430.75542) (xy 85.141308 -430.746662)
			(xy 85.141308 -430.018952) (xy 85.141723 -430.006873) (xy 85.149201 -429.983902) (xy 85.16341 -429.964364)
			(xy 85.182959 -429.950172) (xy 85.205937 -429.942713) (xy 85.218016 -429.942244) (xy 86.157816 -429.942244)
			(xy 86.169887 -429.94275) (xy 86.192846 -429.950211) (xy 86.212379 -429.964399) (xy 86.226574 -429.983925)
			(xy 86.234045 -430.006882) (xy 86.234524 -430.018952) (xy 86.234524 -431.560478) (xy 87.141304 -431.560478)
			(xy 87.141304 -430.833276) (xy 87.141555 -430.824519) (xy 87.145535 -430.807461) (xy 87.149178 -430.799494)
			(xy 87.382604 -430.323244) (xy 87.387332 -430.312738) (xy 87.390813 -430.289973) (xy 87.387316 -430.26721)
			(xy 87.382604 -430.256696) (xy 87.149178 -429.780446) (xy 87.145529 -429.77248) (xy 87.141545 -429.755422)
			(xy 87.141304 -429.746664) (xy 87.141304 -429.018954) (xy 87.141767 -429.006866) (xy 87.149232 -428.98387)
			(xy 87.163421 -428.964293) (xy 87.182953 -428.950043) (xy 87.205925 -428.942506) (xy 87.218012 -428.941992)
			(xy 88.157812 -428.941992) (xy 88.169921 -428.942406) (xy 88.192947 -428.949908) (xy 88.207529 -428.960534)
			(xy 89.1413 -428.960534) (xy 89.1413 -426.41901) (xy 89.141815 -426.406925) (xy 89.149264 -426.383931)
			(xy 89.16344 -426.364355) (xy 89.182961 -426.350103) (xy 89.205925 -426.342563) (xy 89.218008 -426.342048)
			(xy 90.157808 -426.342048) (xy 90.169912 -426.342509) (xy 90.192931 -426.350004) (xy 90.212499 -426.364256)
			(xy 90.226696 -426.383865) (xy 90.234125 -426.406905) (xy 90.234516 -426.41901) (xy 90.234516 -428.960534)
			(xy 90.234121 -428.97263) (xy 90.226649 -428.995639) (xy 90.212446 -429.015222) (xy 90.192895 -429.02947)
			(xy 90.169903 -429.036993) (xy 90.157808 -429.037496) (xy 89.218008 -429.037496) (xy 89.205899 -429.037077)
			(xy 89.182871 -429.029579) (xy 89.163298 -429.015319) (xy 89.149103 -428.995697) (xy 89.141683 -428.972644)
			(xy 89.1413 -428.960534) (xy 88.207529 -428.960534) (xy 88.212519 -428.96417) (xy 88.226714 -428.983792)
			(xy 88.234136 -429.006844) (xy 88.23452 -429.018954) (xy 88.23452 -431.560478) (xy 88.234073 -431.57257)
			(xy 88.226618 -431.595577) (xy 88.212427 -431.615161) (xy 88.192887 -431.629411) (xy 88.169903 -431.636936)
			(xy 88.157812 -431.63744) (xy 87.218012 -431.63744) (xy 87.205908 -431.636974) (xy 87.182888 -431.629483)
			(xy 87.163318 -431.615232) (xy 87.149122 -431.595624) (xy 87.141693 -431.572583) (xy 87.141304 -431.560478)
			(xy 86.234524 -431.560478) (xy 86.234524 -432.560476) (xy 86.234067 -432.572556) (xy 86.226608 -432.595535)
			(xy 86.212413 -432.615084) (xy 86.192871 -432.62929) (xy 86.169896 -432.636761) (xy 86.157816 -432.637184)
			(xy 85.218016 -432.637184) (xy 85.205932 -432.636773) (xy 85.182946 -432.629307) (xy 85.163393 -432.615101)
			(xy 85.149189 -432.595547) (xy 85.141726 -432.57256) (xy 85.141308 -432.560476) (xy 84.207119 -432.560476)
			(xy 84.212399 -432.564313) (xy 84.226593 -432.583852) (xy 84.234055 -432.606821) (xy 84.234528 -432.618896)
			(xy 84.234528 -435.16042) (xy 84.234053 -435.172494) (xy 84.226587 -435.195458) (xy 84.212393 -435.214993)
			(xy 84.192858 -435.229187) (xy 84.169894 -435.236653) (xy 84.15782 -435.237128) (xy 83.21802 -435.237128)
			(xy 83.205948 -435.236619) (xy 83.182985 -435.229165) (xy 83.16345 -435.214979) (xy 83.149254 -435.195451)
			(xy 83.141787 -435.172491) (xy 83.141312 -435.16042) (xy 82.234532 -435.16042) (xy 82.234532 -436.160418)
			(xy 82.234108 -436.172511) (xy 82.226643 -436.195517) (xy 82.212446 -436.215099) (xy 82.192902 -436.229348)
			(xy 82.169916 -436.236875) (xy 82.157824 -436.23738) (xy 81.218024 -436.23738) (xy 81.205914 -436.236963)
			(xy 81.182885 -436.229468) (xy 81.163309 -436.215207) (xy 81.149115 -436.195584) (xy 81.141697 -436.172529)
			(xy 81.141316 -436.160418) (xy 80.206779 -436.160418) (xy 80.212406 -436.164508) (xy 80.2266 -436.184048)
			(xy 80.234063 -436.207017) (xy 80.234536 -436.219092) (xy 80.234536 -438.760616) (xy 80.23405 -438.772689)
			(xy 80.226586 -438.795651) (xy 80.212394 -438.815186) (xy 80.192862 -438.829381) (xy 80.169901 -438.836848)
			(xy 80.157828 -438.837324) (xy 79.218028 -438.837324) (xy 79.205948 -438.836864) (xy 79.182969 -438.829406)
			(xy 79.16342 -438.815211) (xy 79.149214 -438.79567) (xy 79.141743 -438.772695) (xy 79.14132 -438.760616)
			(xy 78.23454 -438.760616) (xy 78.23454 -439.760614) (xy 81.141316 -439.760614) (xy 81.141316 -437.21909)
			(xy 81.141799 -437.207002) (xy 81.149255 -437.184006) (xy 81.163439 -437.164428) (xy 81.182967 -437.150177)
			(xy 81.205938 -437.142641) (xy 81.218024 -437.142128) (xy 82.157824 -437.142128) (xy 82.169937 -437.142496)
			(xy 82.19297 -437.150006) (xy 82.212545 -437.164279) (xy 82.226738 -437.183912) (xy 82.234153 -437.206975)
			(xy 82.234532 -437.21909) (xy 82.234532 -438.760616) (xy 83.141312 -438.760616) (xy 83.141312 -436.219092)
			(xy 83.141706 -436.207007) (xy 83.149178 -436.18402) (xy 83.163388 -436.164469) (xy 83.182946 -436.150265)
			(xy 83.205935 -436.142802) (xy 83.21802 -436.142384) (xy 84.15782 -436.142384) (xy 84.169895 -436.142847)
			(xy 84.192861 -436.150314) (xy 84.206765 -436.160418) (xy 85.141308 -436.160418) (xy 85.141308 -435.433216)
			(xy 85.141572 -435.42446) (xy 85.145543 -435.407402) (xy 85.149182 -435.399434) (xy 85.382608 -434.923184)
			(xy 85.387308 -434.912667) (xy 85.390798 -434.889909) (xy 85.387313 -434.86715) (xy 85.382608 -434.856636)
			(xy 85.149182 -434.380386) (xy 85.145514 -434.372428) (xy 85.141542 -434.355364) (xy 85.141308 -434.346604)
			(xy 85.141308 -433.618894) (xy 85.141802 -433.606807) (xy 85.149256 -433.583812) (xy 85.163437 -433.564235)
			(xy 85.182963 -433.549984) (xy 85.205931 -433.542446) (xy 85.218016 -433.541932) (xy 86.157816 -433.541932)
			(xy 86.169929 -433.542303) (xy 86.192962 -433.549811) (xy 86.212538 -433.564083) (xy 86.226731 -433.583716)
			(xy 86.234145 -433.606779) (xy 86.234524 -433.618894) (xy 86.234524 -435.16042) (xy 87.141304 -435.16042)
			(xy 87.141304 -434.433218) (xy 87.141569 -434.424462) (xy 87.145539 -434.407404) (xy 87.149178 -434.399436)
			(xy 87.382604 -433.923186) (xy 87.387303 -433.912668) (xy 87.390794 -433.889911) (xy 87.387309 -433.867152)
			(xy 87.382604 -433.856638) (xy 87.149178 -433.380388) (xy 87.145511 -433.372429) (xy 87.141538 -433.355366)
			(xy 87.141304 -433.346606) (xy 87.141304 -432.618896) (xy 87.141709 -432.606812) (xy 87.149179 -432.583827)
			(xy 87.163387 -432.564276) (xy 87.182941 -432.550072) (xy 87.205928 -432.542607) (xy 87.218012 -432.542188)
			(xy 88.157812 -432.542188) (xy 88.169887 -432.542654) (xy 88.192854 -432.550119) (xy 88.207106 -432.560476)
			(xy 89.1413 -432.560476) (xy 89.1413 -431.833274) (xy 89.141551 -431.824517) (xy 89.145531 -431.807459)
			(xy 89.149174 -431.799492) (xy 89.3826 -431.323242) (xy 89.38733 -431.312736) (xy 89.39081 -431.289971)
			(xy 89.387312 -431.267208) (xy 89.3826 -431.256694) (xy 89.149174 -430.780444) (xy 89.145524 -430.772478)
			(xy 89.141541 -430.75542) (xy 89.1413 -430.746662) (xy 89.1413 -430.018952) (xy 89.141723 -430.006874)
			(xy 89.1492 -429.983904) (xy 89.163407 -429.964367) (xy 89.182954 -429.950174) (xy 89.20593 -429.942714)
			(xy 89.218008 -429.942244) (xy 90.157808 -429.942244) (xy 90.169878 -429.942757) (xy 90.192837 -429.950216)
			(xy 90.21237 -429.964401) (xy 90.226566 -429.983927) (xy 90.234037 -430.006882) (xy 90.234516 -430.018952)
			(xy 90.234516 -431.360072) (xy 108.40466 -431.360072) (xy 108.405158 -431.275192) (xy 108.413115 -431.105619)
			(xy 108.429011 -430.936605) (xy 108.452812 -430.768522) (xy 108.484466 -430.601739) (xy 108.523902 -430.436623)
			(xy 108.571034 -430.273538) (xy 108.625758 -430.11284) (xy 108.687955 -429.954885) (xy 108.757487 -429.800018)
			(xy 108.834202 -429.648581) (xy 108.91793 -429.500905) (xy 109.008488 -429.357317) (xy 109.105677 -429.218131)
			(xy 109.209284 -429.083654) (xy 109.319079 -428.954181) (xy 109.434823 -428.829996) (xy 109.55626 -428.711373)
			(xy 109.683124 -428.598572) (xy 109.815135 -428.491842) (xy 109.952005 -428.391417) (xy 110.09343 -428.297518)
			(xy 110.239102 -428.21035) (xy 110.3887 -428.130107) (xy 110.541894 -428.056963) (xy 110.698348 -427.991081)
			(xy 110.857718 -427.932604) (xy 111.019654 -427.881662) (xy 111.1838 -427.838366) (xy 111.349795 -427.802811)
			(xy 111.517274 -427.775076) (xy 111.685869 -427.755222) (xy 111.855209 -427.743292) (xy 112.024922 -427.739313)
			(xy 112.194635 -427.743292) (xy 112.363975 -427.755222) (xy 112.53257 -427.775076) (xy 112.700049 -427.802811)
			(xy 112.866044 -427.838366) (xy 113.03019 -427.881662) (xy 113.192126 -427.932604) (xy 113.26825 -427.960536)
			(xy 125.241304 -427.960536) (xy 125.241304 -425.419012) (xy 125.241723 -425.406929) (xy 125.249189 -425.383944)
			(xy 125.263393 -425.364393) (xy 125.282944 -425.350189) (xy 125.305929 -425.342723) (xy 125.318012 -425.342304)
			(xy 126.257812 -425.342304) (xy 126.269888 -425.342754) (xy 126.292858 -425.350222) (xy 126.312396 -425.364421)
			(xy 126.326589 -425.383964) (xy 126.334049 -425.406935) (xy 126.33452 -425.419012) (xy 126.33452 -427.960536)
			(xy 126.334067 -427.972611) (xy 126.326596 -427.995578) (xy 126.312396 -428.015113) (xy 126.292856 -428.029307)
			(xy 126.269887 -428.036771) (xy 126.257812 -428.037244) (xy 125.318012 -428.037244) (xy 125.305942 -428.036726)
			(xy 125.282981 -428.029271) (xy 125.263447 -428.015087) (xy 125.249251 -427.995562) (xy 125.241781 -427.972606)
			(xy 125.241304 -427.960536) (xy 113.26825 -427.960536) (xy 113.351496 -427.991081) (xy 113.50795 -428.056963)
			(xy 113.661144 -428.130107) (xy 113.810742 -428.21035) (xy 113.956414 -428.297518) (xy 114.097839 -428.391417)
			(xy 114.234709 -428.491842) (xy 114.36672 -428.598572) (xy 114.493584 -428.711373) (xy 114.615021 -428.829996)
			(xy 114.730765 -428.954181) (xy 114.84056 -429.083654) (xy 114.944167 -429.218131) (xy 115.041356 -429.357317)
			(xy 115.131914 -429.500905) (xy 115.215642 -429.648581) (xy 115.292357 -429.800018) (xy 115.361889 -429.954885)
			(xy 115.424086 -430.11284) (xy 115.47881 -430.273538) (xy 115.525942 -430.436623) (xy 115.565378 -430.601739)
			(xy 115.597032 -430.768522) (xy 115.620833 -430.936605) (xy 115.636729 -431.105619) (xy 115.644686 -431.275192)
			(xy 115.645184 -431.360072) (xy 115.644698 -431.445674) (xy 115.639268 -431.560478) (xy 125.241304 -431.560478)
			(xy 125.241304 -430.833276) (xy 125.241555 -430.824519) (xy 125.245535 -430.807461) (xy 125.249178 -430.799494)
			(xy 125.482604 -430.323244) (xy 125.487332 -430.312738) (xy 125.490813 -430.289973) (xy 125.487316 -430.26721)
			(xy 125.482604 -430.256696) (xy 125.249178 -429.780446) (xy 125.245529 -429.77248) (xy 125.241545 -429.755422)
			(xy 125.241304 -429.746664) (xy 125.241304 -429.018954) (xy 125.241767 -429.006866) (xy 125.249232 -428.98387)
			(xy 125.263421 -428.964293) (xy 125.282953 -428.950043) (xy 125.305925 -428.942506) (xy 125.318012 -428.941992)
			(xy 126.257812 -428.941992) (xy 126.269921 -428.942406) (xy 126.292947 -428.949908) (xy 126.307529 -428.960534)
			(xy 127.2413 -428.960534) (xy 127.2413 -426.41901) (xy 127.241815 -426.406925) (xy 127.249264 -426.383931)
			(xy 127.26344 -426.364355) (xy 127.282961 -426.350103) (xy 127.305925 -426.342563) (xy 127.318008 -426.342048)
			(xy 128.257808 -426.342048) (xy 128.269912 -426.342509) (xy 128.292931 -426.350004) (xy 128.312499 -426.364256)
			(xy 128.326696 -426.383865) (xy 128.334125 -426.406905) (xy 128.334516 -426.41901) (xy 128.334516 -427.960536)
			(xy 129.241296 -427.960536) (xy 129.241296 -425.419012) (xy 129.241723 -425.40693) (xy 129.249188 -425.383947)
			(xy 129.26339 -425.364396) (xy 129.282939 -425.350191) (xy 129.305922 -425.342724) (xy 129.318004 -425.342304)
			(xy 130.257804 -425.342304) (xy 130.269888 -425.342709) (xy 130.292873 -425.350179) (xy 130.312424 -425.364387)
			(xy 130.326628 -425.383941) (xy 130.334093 -425.406928) (xy 130.334512 -425.419012) (xy 130.334512 -427.960536)
			(xy 130.334067 -427.972612) (xy 130.326595 -427.99558) (xy 130.312393 -428.015116) (xy 130.292851 -428.029309)
			(xy 130.26988 -428.036772) (xy 130.257804 -428.037244) (xy 129.318004 -428.037244) (xy 129.305933 -428.036733)
			(xy 129.282972 -428.029276) (xy 129.263438 -428.01509) (xy 129.249242 -427.995564) (xy 129.241773 -427.972607)
			(xy 129.241296 -427.960536) (xy 128.334516 -427.960536) (xy 128.334516 -428.960534) (xy 128.334121 -428.97263)
			(xy 128.326649 -428.995639) (xy 128.312446 -429.015222) (xy 128.292895 -429.02947) (xy 128.269903 -429.036993)
			(xy 128.257808 -429.037496) (xy 127.318008 -429.037496) (xy 127.305899 -429.037077) (xy 127.282871 -429.029579)
			(xy 127.263298 -429.015319) (xy 127.249103 -428.995697) (xy 127.241683 -428.972644) (xy 127.2413 -428.960534)
			(xy 126.307529 -428.960534) (xy 126.312519 -428.96417) (xy 126.326714 -428.983792) (xy 126.334136 -429.006844)
			(xy 126.33452 -429.018954) (xy 126.33452 -431.560478) (xy 126.334073 -431.57257) (xy 126.326618 -431.595577)
			(xy 126.312427 -431.615161) (xy 126.292887 -431.629411) (xy 126.269903 -431.636936) (xy 126.257812 -431.63744)
			(xy 125.318012 -431.63744) (xy 125.305908 -431.636974) (xy 125.282888 -431.629483) (xy 125.263318 -431.615232)
			(xy 125.249122 -431.595624) (xy 125.241693 -431.572583) (xy 125.241304 -431.560478) (xy 115.639268 -431.560478)
			(xy 115.63661 -431.616688) (xy 115.620446 -431.787128) (xy 115.596243 -431.956613) (xy 115.564055 -432.124765)
			(xy 115.523953 -432.291207) (xy 115.476027 -432.455567) (xy 115.420385 -432.617477) (xy 115.35715 -432.776576)
			(xy 115.286464 -432.932508) (xy 115.208486 -433.084923) (xy 115.12339 -433.233482) (xy 115.031365 -433.377851)
			(xy 114.932619 -433.517709) (xy 114.82737 -433.652742) (xy 114.715856 -433.782648) (xy 114.598325 -433.907137)
			(xy 114.47504 -434.02593) (xy 114.346277 -434.138763) (xy 114.212324 -434.245381) (xy 114.07348 -434.345548)
			(xy 113.930056 -434.439039) (xy 113.782372 -434.525645) (xy 113.630759 -434.605172) (xy 113.475556 -434.677443)
			(xy 113.396522 -434.710332) (xy 113.388621 -434.713964) (xy 113.375731 -434.725623) (xy 113.367472 -434.740915)
			(xy 113.365788 -434.749448) (xy 113.35004 -434.849016) (xy 113.359438 -434.873654) (xy 113.369852 -434.88229)
			(xy 113.419298 -434.924299) (xy 113.513487 -435.013553) (xy 113.601975 -435.108462) (xy 113.644727 -435.16042)
			(xy 125.241304 -435.16042) (xy 125.241304 -434.433218) (xy 125.241569 -434.424462) (xy 125.245539 -434.407404)
			(xy 125.249178 -434.399436) (xy 125.482604 -433.923186) (xy 125.487303 -433.912668) (xy 125.490794 -433.889911)
			(xy 125.487309 -433.867152) (xy 125.482604 -433.856638) (xy 125.249178 -433.380388) (xy 125.245511 -433.372429)
			(xy 125.241538 -433.355366) (xy 125.241304 -433.346606) (xy 125.241304 -432.618896) (xy 125.241709 -432.606812)
			(xy 125.249179 -432.583827) (xy 125.263387 -432.564276) (xy 125.282941 -432.550072) (xy 125.305928 -432.542607)
			(xy 125.318012 -432.542188) (xy 126.257812 -432.542188) (xy 126.269887 -432.542654) (xy 126.292854 -432.550119)
			(xy 126.307106 -432.560476) (xy 127.2413 -432.560476) (xy 127.2413 -431.833274) (xy 127.241551 -431.824517)
			(xy 127.245531 -431.807459) (xy 127.249174 -431.799492) (xy 127.4826 -431.323242) (xy 127.48733 -431.312736)
			(xy 127.49081 -431.289971) (xy 127.487312 -431.267208) (xy 127.4826 -431.256694) (xy 127.249174 -430.780444)
			(xy 127.245524 -430.772478) (xy 127.241541 -430.75542) (xy 127.2413 -430.746662) (xy 127.2413 -430.018952)
			(xy 127.241723 -430.006874) (xy 127.2492 -429.983904) (xy 127.263407 -429.964367) (xy 127.282954 -429.950174)
			(xy 127.30593 -429.942714) (xy 127.318008 -429.942244) (xy 128.257808 -429.942244) (xy 128.269878 -429.942757)
			(xy 128.292837 -429.950216) (xy 128.31237 -429.964401) (xy 128.326566 -429.983927) (xy 128.334037 -430.006882)
			(xy 128.334516 -430.018952) (xy 128.334516 -431.560478) (xy 129.241296 -431.560478) (xy 129.241296 -430.833276)
			(xy 129.241548 -430.824519) (xy 129.245527 -430.807461) (xy 129.24917 -430.799494) (xy 129.482596 -430.323244)
			(xy 129.487325 -430.312738) (xy 129.490805 -430.289973) (xy 129.487308 -430.26721) (xy 129.482596 -430.256696)
			(xy 129.24917 -429.780446) (xy 129.24552 -429.77248) (xy 129.241537 -429.755422) (xy 129.241296 -429.746664)
			(xy 129.241296 -429.018954) (xy 129.241767 -429.006866) (xy 129.249231 -428.983872) (xy 129.263418 -428.964296)
			(xy 129.282948 -428.950046) (xy 129.305918 -428.942507) (xy 129.318004 -428.941992) (xy 130.257804 -428.941992)
			(xy 130.269912 -428.942413) (xy 130.292938 -428.949912) (xy 130.307517 -428.960534) (xy 131.241292 -428.960534)
			(xy 131.241292 -426.41901) (xy 131.241815 -426.406926) (xy 131.249263 -426.383934) (xy 131.263437 -426.364358)
			(xy 131.282956 -426.350105) (xy 131.305918 -426.342564) (xy 131.318 -426.342048) (xy 132.2578 -426.342048)
			(xy 132.269904 -426.342515) (xy 132.292922 -426.350009) (xy 132.312491 -426.364259) (xy 132.326687 -426.383866)
			(xy 132.334117 -426.406905) (xy 132.334508 -426.41901) (xy 132.334508 -427.960536) (xy 133.241288 -427.960536)
			(xy 133.241288 -425.419012) (xy 133.241723 -425.40693) (xy 133.249187 -425.383949) (xy 133.263387 -425.364399)
			(xy 133.282934 -425.350194) (xy 133.305914 -425.342726) (xy 133.317996 -425.342304) (xy 134.257796 -425.342304)
			(xy 134.26988 -425.342716) (xy 134.292864 -425.350184) (xy 134.312416 -425.36439) (xy 134.32662 -425.383943)
			(xy 134.334085 -425.406928) (xy 134.334504 -425.419012) (xy 134.334504 -427.960536) (xy 134.334067 -427.972613)
			(xy 134.326594 -427.995582) (xy 134.31239 -428.015119) (xy 134.292846 -428.029312) (xy 134.269873 -428.036773)
			(xy 134.257796 -428.037244) (xy 133.317996 -428.037244) (xy 133.305925 -428.03674) (xy 133.282964 -428.02928)
			(xy 133.26343 -428.015093) (xy 133.249234 -427.995565) (xy 133.241765 -427.972607) (xy 133.241288 -427.960536)
			(xy 132.334508 -427.960536) (xy 132.334508 -428.960534) (xy 132.334023 -428.972621) (xy 132.326562 -428.995614)
			(xy 132.312379 -429.01519) (xy 132.292853 -429.029441) (xy 132.269885 -429.03698) (xy 132.2578 -429.037496)
			(xy 131.318 -429.037496) (xy 131.305891 -429.037084) (xy 131.282863 -429.029584) (xy 131.263289 -429.015321)
			(xy 131.249095 -428.995699) (xy 131.241675 -428.972645) (xy 131.241292 -428.960534) (xy 130.307517 -428.960534)
			(xy 130.312511 -428.964173) (xy 130.326706 -428.983793) (xy 130.334128 -429.006844) (xy 130.334512 -429.018954)
			(xy 130.334512 -431.560478) (xy 130.334073 -431.572571) (xy 130.326616 -431.595579) (xy 130.312424 -431.615164)
			(xy 130.292882 -431.629413) (xy 130.269896 -431.636937) (xy 130.257804 -431.63744) (xy 129.318004 -431.63744)
			(xy 129.305899 -431.636981) (xy 129.282879 -431.629488) (xy 129.263309 -431.615236) (xy 129.249113 -431.595625)
			(xy 129.241685 -431.572584) (xy 129.241296 -431.560478) (xy 128.334516 -431.560478) (xy 128.334516 -432.560476)
			(xy 128.334067 -432.572557) (xy 128.326607 -432.595537) (xy 128.31241 -432.615087) (xy 128.292866 -432.629292)
			(xy 128.269888 -432.636762) (xy 128.257808 -432.637184) (xy 127.318008 -432.637184) (xy 127.305923 -432.63678)
			(xy 127.282937 -432.629312) (xy 127.263384 -432.615105) (xy 127.249181 -432.595549) (xy 127.241717 -432.572561)
			(xy 127.2413 -432.560476) (xy 126.307106 -432.560476) (xy 126.31239 -432.564316) (xy 126.326584 -432.583854)
			(xy 126.334047 -432.606821) (xy 126.33452 -432.618896) (xy 126.33452 -435.16042) (xy 126.334053 -435.172494)
			(xy 126.326586 -435.19546) (xy 126.31239 -435.214996) (xy 126.292853 -435.22919) (xy 126.269886 -435.236654)
			(xy 126.257812 -435.237128) (xy 125.318012 -435.237128) (xy 125.30594 -435.236626) (xy 125.282977 -435.229169)
			(xy 125.263441 -435.214982) (xy 125.249246 -435.195452) (xy 125.241779 -435.172492) (xy 125.241304 -435.16042)
			(xy 113.644727 -435.16042) (xy 113.684422 -435.208663) (xy 113.760513 -435.313772) (xy 113.829956 -435.423387)
			(xy 113.892486 -435.537087) (xy 113.947862 -435.654438) (xy 113.995874 -435.77499) (xy 114.036336 -435.89828)
			(xy 114.069094 -436.023838) (xy 114.094022 -436.151181) (xy 114.111025 -436.279823) (xy 114.120038 -436.40927)
			(xy 114.121027 -436.539027) (xy 114.113986 -436.668596) (xy 114.098945 -436.797482) (xy 114.075959 -436.92519)
			(xy 114.045118 -437.051232) (xy 114.006538 -437.175125) (xy 113.960369 -437.296394) (xy 113.906786 -437.414574)
			(xy 113.845996 -437.529214) (xy 113.77823 -437.639874) (xy 113.703749 -437.74613) (xy 113.622838 -437.847575)
			(xy 113.535806 -437.943821) (xy 113.442988 -438.034499) (xy 113.344738 -438.119261) (xy 113.241432 -438.197784)
			(xy 113.133467 -438.269766) (xy 113.021257 -438.334931) (xy 112.90523 -438.39303) (xy 112.785831 -438.443841)
			(xy 112.663518 -438.487169) (xy 112.538759 -438.522847) (xy 112.412032 -438.550739) (xy 112.283822 -438.570739)
			(xy 112.15462 -438.58277) (xy 112.024922 -438.586785) (xy 111.895224 -438.58277) (xy 111.766022 -438.570739)
			(xy 111.637812 -438.550739) (xy 111.511085 -438.522847) (xy 111.386326 -438.487169) (xy 111.264013 -438.443841)
			(xy 111.144614 -438.39303) (xy 111.028587 -438.334931) (xy 110.916377 -438.269766) (xy 110.808412 -438.197784)
			(xy 110.705106 -438.119261) (xy 110.606856 -438.034499) (xy 110.514038 -437.943821) (xy 110.427006 -437.847575)
			(xy 110.346095 -437.74613) (xy 110.271614 -437.639874) (xy 110.203848 -437.529214) (xy 110.143058 -437.414574)
			(xy 110.089475 -437.296394) (xy 110.043306 -437.175125) (xy 110.004726 -437.051232) (xy 109.973885 -436.92519)
			(xy 109.950899 -436.797482) (xy 109.935858 -436.668596) (xy 109.928817 -436.539027) (xy 109.929806 -436.40927)
			(xy 109.938819 -436.279823) (xy 109.955822 -436.151181) (xy 109.98075 -436.023838) (xy 110.013508 -435.89828)
			(xy 110.05397 -435.77499) (xy 110.101982 -435.654438) (xy 110.157358 -435.537087) (xy 110.219888 -435.423387)
			(xy 110.289331 -435.313772) (xy 110.365422 -435.208663) (xy 110.447869 -435.108462) (xy 110.536357 -435.013553)
			(xy 110.630546 -434.924299) (xy 110.679992 -434.88229) (xy 110.690406 -434.873654) (xy 110.699804 -434.849016)
			(xy 110.682024 -434.73624) (xy 110.665768 -434.715412) (xy 110.653322 -434.710332) (xy 110.574304 -434.677407)
			(xy 110.419107 -434.605131) (xy 110.267499 -434.5256) (xy 110.119821 -434.438991) (xy 109.976402 -434.345497)
			(xy 109.837562 -434.245328) (xy 109.703613 -434.138709) (xy 109.574854 -434.025876) (xy 109.451573 -433.907083)
			(xy 109.334045 -433.782595) (xy 109.222533 -433.65269) (xy 109.117287 -433.517659) (xy 109.018541 -433.377804)
			(xy 108.926517 -433.233438) (xy 108.84142 -433.084883) (xy 108.763441 -432.932471) (xy 108.692754 -432.776543)
			(xy 108.629516 -432.617449) (xy 108.57387 -432.455542) (xy 108.52594 -432.291187) (xy 108.485833 -432.124749)
			(xy 108.453638 -431.956601) (xy 108.429428 -431.78712) (xy 108.413257 -431.616683) (xy 108.405161 -431.445673)
			(xy 108.40466 -431.360072) (xy 90.234516 -431.360072) (xy 90.234516 -432.560476) (xy 90.234067 -432.572557)
			(xy 90.226607 -432.595537) (xy 90.21241 -432.615087) (xy 90.192866 -432.629292) (xy 90.169888 -432.636762)
			(xy 90.157808 -432.637184) (xy 89.218008 -432.637184) (xy 89.205923 -432.63678) (xy 89.182937 -432.629312)
			(xy 89.163384 -432.615105) (xy 89.149181 -432.595549) (xy 89.141717 -432.572561) (xy 89.1413 -432.560476)
			(xy 88.207106 -432.560476) (xy 88.21239 -432.564316) (xy 88.226584 -432.583854) (xy 88.234047 -432.606821)
			(xy 88.23452 -432.618896) (xy 88.23452 -435.16042) (xy 88.234053 -435.172494) (xy 88.226586 -435.19546)
			(xy 88.21239 -435.214996) (xy 88.192853 -435.22919) (xy 88.169886 -435.236654) (xy 88.157812 -435.237128)
			(xy 87.218012 -435.237128) (xy 87.20594 -435.236626) (xy 87.182977 -435.229169) (xy 87.163441 -435.214982)
			(xy 87.149246 -435.195452) (xy 87.141779 -435.172492) (xy 87.141304 -435.16042) (xy 86.234524 -435.16042)
			(xy 86.234524 -436.160418) (xy 86.234107 -436.172512) (xy 86.226641 -436.195519) (xy 86.212443 -436.215102)
			(xy 86.192897 -436.229351) (xy 86.169909 -436.236876) (xy 86.157816 -436.23738) (xy 85.218016 -436.23738)
			(xy 85.205906 -436.23697) (xy 85.182876 -436.229472) (xy 85.163301 -436.21521) (xy 85.149106 -436.195585)
			(xy 85.141689 -436.172529) (xy 85.141308 -436.160418) (xy 84.206765 -436.160418) (xy 84.212397 -436.164511)
			(xy 84.226591 -436.18405) (xy 84.234055 -436.207017) (xy 84.234528 -436.219092) (xy 84.234528 -438.760616)
			(xy 84.23405 -438.772689) (xy 84.226585 -438.795654) (xy 84.212391 -438.815189) (xy 84.192857 -438.829383)
			(xy 84.169893 -438.836849) (xy 84.15782 -438.837324) (xy 83.21802 -438.837324) (xy 83.20594 -438.83687)
			(xy 83.182961 -438.82941) (xy 83.163411 -438.815214) (xy 83.149206 -438.795672) (xy 83.141735 -438.772696)
			(xy 83.141312 -438.760616) (xy 82.234532 -438.760616) (xy 82.234532 -439.760614) (xy 85.141308 -439.760614)
			(xy 85.141308 -437.21909) (xy 85.141798 -437.207003) (xy 85.149254 -437.184008) (xy 85.163436 -437.164431)
			(xy 85.182962 -437.150179) (xy 85.205931 -437.142642) (xy 85.218016 -437.142128) (xy 86.157816 -437.142128)
			(xy 86.169929 -437.142503) (xy 86.192961 -437.15001) (xy 86.212536 -437.164281) (xy 86.226729 -437.183914)
			(xy 86.234145 -437.206976) (xy 86.234524 -437.21909) (xy 86.234524 -438.760616) (xy 87.141304 -438.760616)
			(xy 87.141304 -436.219092) (xy 87.141706 -436.207008) (xy 87.149177 -436.184023) (xy 87.163386 -436.164471)
			(xy 87.182941 -436.150268) (xy 87.205928 -436.142803) (xy 87.218012 -436.142384) (xy 88.157812 -436.142384)
			(xy 88.169886 -436.142854) (xy 88.192853 -436.150319) (xy 88.206752 -436.160418) (xy 89.1413 -436.160418)
			(xy 89.1413 -435.433216) (xy 89.141565 -435.42446) (xy 89.145535 -435.407402) (xy 89.149174 -435.399434)
			(xy 89.3826 -434.923184) (xy 89.3873 -434.912667) (xy 89.390791 -434.889909) (xy 89.387306 -434.86715)
			(xy 89.3826 -434.856636) (xy 89.149174 -434.380386) (xy 89.145506 -434.372428) (xy 89.141534 -434.355364)
			(xy 89.1413 -434.346604) (xy 89.1413 -433.618894) (xy 89.141802 -433.606808) (xy 89.149255 -433.583814)
			(xy 89.163434 -433.564238) (xy 89.182958 -433.549986) (xy 89.205924 -433.542447) (xy 89.218008 -433.541932)
			(xy 90.157808 -433.541932) (xy 90.169921 -433.54231) (xy 90.192954 -433.549815) (xy 90.212529 -433.564086)
			(xy 90.226723 -433.583717) (xy 90.234137 -433.60678) (xy 90.234516 -433.618894) (xy 90.234516 -436.160418)
			(xy 90.234107 -436.172513) (xy 90.22664 -436.195522) (xy 90.21244 -436.215105) (xy 90.192892 -436.229353)
			(xy 90.169902 -436.236877) (xy 90.157808 -436.23738) (xy 89.218008 -436.23738) (xy 89.205898 -436.236977)
			(xy 89.182867 -436.229477) (xy 89.163292 -436.215213) (xy 89.149098 -436.195587) (xy 89.14168 -436.17253)
			(xy 89.1413 -436.160418) (xy 88.206752 -436.160418) (xy 88.212389 -436.164514) (xy 88.226583 -436.184051)
			(xy 88.234047 -436.207018) (xy 88.23452 -436.219092) (xy 88.23452 -438.760616) (xy 88.234049 -438.77269)
			(xy 88.226584 -438.795656) (xy 88.212389 -438.815191) (xy 88.192852 -438.829386) (xy 88.169886 -438.83685)
			(xy 88.157812 -438.837324) (xy 87.218012 -438.837324) (xy 87.20594 -438.836826) (xy 87.182976 -438.829369)
			(xy 87.16344 -438.81518) (xy 87.149244 -438.79565) (xy 87.141779 -438.772688) (xy 87.141304 -438.760616)
			(xy 86.234524 -438.760616) (xy 86.234524 -439.760614) (xy 89.1413 -439.760614) (xy 89.1413 -437.21909)
			(xy 89.141798 -437.207004) (xy 89.149253 -437.18401) (xy 89.163433 -437.164434) (xy 89.182957 -437.150182)
			(xy 89.205924 -437.142643) (xy 89.218008 -437.142128) (xy 90.157808 -437.142128) (xy 90.16992 -437.14251)
			(xy 90.192952 -437.150015) (xy 90.212528 -437.164284) (xy 90.226721 -437.183915) (xy 90.234137 -437.206976)
			(xy 90.234516 -437.21909) (xy 90.234516 -438.76087) (xy 125.240796 -438.76087) (xy 125.240796 -436.219346)
			(xy 125.241298 -436.20723) (xy 125.248773 -436.18418) (xy 125.263005 -436.164567) (xy 125.282601 -436.150313)
			(xy 125.305642 -436.142812) (xy 125.317758 -436.142384) (xy 126.257558 -436.142384) (xy 126.269683 -436.142796)
			(xy 126.292748 -436.150283) (xy 126.3067 -436.160418) (xy 127.2413 -436.160418) (xy 127.2413 -435.433216)
			(xy 127.241565 -435.42446) (xy 127.245535 -435.407402) (xy 127.249174 -435.399434) (xy 127.4826 -434.923184)
			(xy 127.4873 -434.912667) (xy 127.490791 -434.889909) (xy 127.487306 -434.86715) (xy 127.4826 -434.856636)
			(xy 127.249174 -434.380386) (xy 127.245506 -434.372428) (xy 127.241534 -434.355364) (xy 127.2413 -434.346604)
			(xy 127.2413 -433.618894) (xy 127.241802 -433.606808) (xy 127.249255 -433.583814) (xy 127.263434 -433.564238)
			(xy 127.282958 -433.549986) (xy 127.305924 -433.542447) (xy 127.318008 -433.541932) (xy 128.257808 -433.541932)
			(xy 128.269921 -433.54231) (xy 128.292954 -433.549815) (xy 128.312529 -433.564086) (xy 128.326723 -433.583717)
			(xy 128.334137 -433.60678) (xy 128.334516 -433.618894) (xy 128.334516 -435.16042) (xy 129.241296 -435.16042)
			(xy 129.241296 -434.433218) (xy 129.241562 -434.424462) (xy 129.245531 -434.407404) (xy 129.24917 -434.399436)
			(xy 129.482596 -433.923186) (xy 129.487295 -433.912668) (xy 129.490786 -433.889911) (xy 129.487302 -433.867152)
			(xy 129.482596 -433.856638) (xy 129.24917 -433.380388) (xy 129.245502 -433.37243) (xy 129.24153 -433.355366)
			(xy 129.241296 -433.346606) (xy 129.241296 -432.618896) (xy 129.241761 -432.606821) (xy 129.249225 -432.583853)
			(xy 129.263421 -432.564316) (xy 129.28296 -432.550121) (xy 129.305929 -432.54266) (xy 129.318004 -432.542188)
			(xy 130.257804 -432.542188) (xy 130.269878 -432.542661) (xy 130.292845 -432.550124) (xy 130.307094 -432.560476)
			(xy 131.241292 -432.560476) (xy 131.241292 -431.833274) (xy 131.241544 -431.824517) (xy 131.245523 -431.807459)
			(xy 131.249166 -431.799492) (xy 131.482592 -431.323242) (xy 131.487322 -431.312737) (xy 131.490803 -431.289971)
			(xy 131.487305 -431.267208) (xy 131.482592 -431.256694) (xy 131.249166 -430.780444) (xy 131.245515 -430.772478)
			(xy 131.241533 -430.755421) (xy 131.241292 -430.746662) (xy 131.241292 -430.018952) (xy 131.241723 -430.006875)
			(xy 131.249199 -429.983906) (xy 131.263404 -429.96437) (xy 131.282949 -429.950177) (xy 131.305923 -429.942716)
			(xy 131.318 -429.942244) (xy 132.2578 -429.942244) (xy 132.26987 -429.942764) (xy 132.292829 -429.95022)
			(xy 132.312362 -429.964404) (xy 132.326558 -429.983928) (xy 132.334029 -430.006883) (xy 132.334508 -430.018952)
			(xy 132.334508 -431.560478) (xy 133.241288 -431.560478) (xy 133.241288 -430.833276) (xy 133.241541 -430.824519)
			(xy 133.245519 -430.807462) (xy 133.249162 -430.799494) (xy 133.482588 -430.323244) (xy 133.487317 -430.312738)
			(xy 133.490798 -430.289973) (xy 133.4873 -430.26721) (xy 133.482588 -430.256696) (xy 133.249162 -429.780446)
			(xy 133.245512 -429.77248) (xy 133.241529 -429.755422) (xy 133.241288 -429.746664) (xy 133.241288 -429.018954)
			(xy 133.241669 -429.006857) (xy 133.249144 -428.983847) (xy 133.263351 -428.964264) (xy 133.282905 -428.950016)
			(xy 133.3059 -428.942494) (xy 133.317996 -428.941992) (xy 134.257796 -428.941992) (xy 134.269904 -428.942419)
			(xy 134.29293 -428.949917) (xy 134.307503 -428.960534) (xy 135.241284 -428.960534) (xy 135.241284 -426.41901)
			(xy 135.241717 -426.406917) (xy 135.249176 -426.383909) (xy 135.26337 -426.364325) (xy 135.282914 -426.350076)
			(xy 135.3059 -426.342551) (xy 135.317992 -426.342048) (xy 136.257792 -426.342048) (xy 136.269895 -426.342522)
			(xy 136.292914 -426.350013) (xy 136.312482 -426.364262) (xy 136.326679 -426.383868) (xy 136.334109 -426.406906)
			(xy 136.3345 -426.41901) (xy 136.3345 -427.960536) (xy 137.24128 -427.960536) (xy 137.24128 -425.419012)
			(xy 137.241774 -425.406939) (xy 137.249232 -425.383974) (xy 137.263421 -425.364438) (xy 137.282953 -425.350243)
			(xy 137.305915 -425.342778) (xy 137.317988 -425.342304) (xy 138.257788 -425.342304) (xy 138.269871 -425.342723)
			(xy 138.292856 -425.350189) (xy 138.312407 -425.364393) (xy 138.326611 -425.383944) (xy 138.334077 -425.406929)
			(xy 138.334496 -425.419012) (xy 138.334496 -427.960536) (xy 138.334066 -427.972614) (xy 138.326593 -427.995584)
			(xy 138.312387 -428.015122) (xy 138.292841 -428.029315) (xy 138.269866 -428.036774) (xy 138.257788 -428.037244)
			(xy 137.317988 -428.037244) (xy 137.305916 -428.036746) (xy 137.282955 -428.029285) (xy 137.263421 -428.015096)
			(xy 137.249226 -427.995567) (xy 137.241757 -427.972607) (xy 137.24128 -427.960536) (xy 136.3345 -427.960536)
			(xy 136.3345 -428.960534) (xy 136.334022 -428.972621) (xy 136.326561 -428.995616) (xy 136.312376 -429.015192)
			(xy 136.292848 -429.029443) (xy 136.269878 -429.036981) (xy 136.257792 -429.037496) (xy 135.317992 -429.037496)
			(xy 135.305882 -429.037091) (xy 135.282854 -429.029588) (xy 135.263281 -429.015324) (xy 135.249086 -428.9957)
			(xy 135.241667 -428.972645) (xy 135.241284 -428.960534) (xy 134.307503 -428.960534) (xy 134.312502 -428.964176)
			(xy 134.326697 -428.983795) (xy 134.33412 -429.006845) (xy 134.334504 -429.018954) (xy 134.334504 -431.560478)
			(xy 134.333975 -431.572562) (xy 134.326529 -431.595555) (xy 134.312357 -431.615131) (xy 134.29284 -431.629384)
			(xy 134.269878 -431.636924) (xy 134.257796 -431.63744) (xy 133.317996 -431.63744) (xy 133.305891 -431.636988)
			(xy 133.28287 -431.629492) (xy 133.263301 -431.615238) (xy 133.249105 -431.595627) (xy 133.241677 -431.572584)
			(xy 133.241288 -431.560478) (xy 132.334508 -431.560478) (xy 132.334508 -432.560476) (xy 132.334067 -432.572557)
			(xy 132.326606 -432.595539) (xy 132.312407 -432.61509) (xy 132.292861 -432.629295) (xy 132.269881 -432.636763)
			(xy 132.2578 -432.637184) (xy 131.318 -432.637184) (xy 131.305915 -432.636787) (xy 131.282928 -432.629317)
			(xy 131.263376 -432.615107) (xy 131.249172 -432.59555) (xy 131.241709 -432.572561) (xy 131.241292 -432.560476)
			(xy 130.307094 -432.560476) (xy 130.312382 -432.564318) (xy 130.326576 -432.583855) (xy 130.334039 -432.606822)
			(xy 130.334512 -432.618896) (xy 130.334512 -435.16042) (xy 130.334053 -435.172495) (xy 130.326585 -435.195462)
			(xy 130.312387 -435.214999) (xy 130.292848 -435.229193) (xy 130.269879 -435.236655) (xy 130.257804 -435.237128)
			(xy 129.318004 -435.237128) (xy 129.305932 -435.236633) (xy 129.282968 -435.229174) (xy 129.263433 -435.214984)
			(xy 129.249237 -435.195454) (xy 129.241771 -435.172492) (xy 129.241296 -435.16042) (xy 128.334516 -435.16042)
			(xy 128.334516 -436.160418) (xy 128.334107 -436.172513) (xy 128.32664 -436.195522) (xy 128.31244 -436.215105)
			(xy 128.292892 -436.229353) (xy 128.269902 -436.236877) (xy 128.257808 -436.23738) (xy 127.318008 -436.23738)
			(xy 127.305898 -436.236977) (xy 127.282867 -436.229477) (xy 127.263292 -436.215213) (xy 127.249098 -436.195587)
			(xy 127.24168 -436.17253) (xy 127.2413 -436.160418) (xy 126.3067 -436.160418) (xy 126.312368 -436.164535)
			(xy 126.326619 -436.184155) (xy 126.334104 -436.207221) (xy 126.33452 -436.219346) (xy 126.33452 -438.76087)
			(xy 126.334114 -438.772995) (xy 126.326625 -438.79606) (xy 126.312371 -438.81568) (xy 126.29275 -438.82993)
			(xy 126.269683 -438.837416) (xy 126.257558 -438.837832) (xy 125.317758 -438.837832) (xy 125.305638 -438.837424)
			(xy 125.282589 -438.829921) (xy 125.262985 -438.815664) (xy 125.248746 -438.796047) (xy 125.241265 -438.77299)
			(xy 125.240796 -438.76087) (xy 90.234516 -438.76087) (xy 90.234516 -439.760614) (xy 90.234507 -439.760868)
			(xy 127.240792 -439.760868) (xy 127.240792 -437.219344) (xy 127.241297 -437.207297) (xy 127.248717 -437.184374)
			(xy 127.262846 -437.164858) (xy 127.282307 -437.150653) (xy 127.305201 -437.143144) (xy 127.317246 -437.142636)
			(xy 128.257554 -437.142636) (xy 128.269641 -437.143146) (xy 128.292639 -437.15059) (xy 128.31222 -437.164765)
			(xy 128.326472 -437.18429) (xy 128.334006 -437.207259) (xy 128.334516 -437.219344) (xy 128.334516 -438.76087)
			(xy 129.240788 -438.76087) (xy 129.240788 -436.219346) (xy 129.24135 -436.207239) (xy 129.248819 -436.184205)
			(xy 129.263039 -436.164607) (xy 129.282619 -436.150362) (xy 129.305643 -436.142865) (xy 129.31775 -436.142384)
			(xy 130.25755 -436.142384) (xy 130.269672 -436.14277) (xy 130.292724 -436.150276) (xy 130.306665 -436.160418)
			(xy 131.241292 -436.160418) (xy 131.241292 -435.433216) (xy 131.241557 -435.42446) (xy 131.245527 -435.407402)
			(xy 131.249166 -435.399434) (xy 131.482592 -434.923184) (xy 131.487293 -434.912667) (xy 131.490784 -434.889909)
			(xy 131.487298 -434.86715) (xy 131.482592 -434.856636) (xy 131.249166 -434.380386) (xy 131.245497 -434.372428)
			(xy 131.241526 -434.355364) (xy 131.241292 -434.346604) (xy 131.241292 -433.618894) (xy 131.241802 -433.606809)
			(xy 131.249254 -433.583816) (xy 131.263431 -433.564241) (xy 131.282953 -433.549989) (xy 131.305917 -433.542448)
			(xy 131.318 -433.541932) (xy 132.2578 -433.541932) (xy 132.269912 -433.542317) (xy 132.292945 -433.54982)
			(xy 132.312521 -433.564088) (xy 132.326714 -433.583719) (xy 132.334129 -433.60678) (xy 132.334508 -433.618894)
			(xy 132.334508 -435.16042) (xy 133.241288 -435.16042) (xy 133.241288 -434.433218) (xy 133.241554 -434.424462)
			(xy 133.245524 -434.407404) (xy 133.249162 -434.399436) (xy 133.482588 -433.923186) (xy 133.487288 -433.912669)
			(xy 133.490779 -433.889911) (xy 133.487294 -433.867152) (xy 133.482588 -433.856638) (xy 133.249162 -433.380388)
			(xy 133.245494 -433.37243) (xy 133.241522 -433.355366) (xy 133.241288 -433.346606) (xy 133.241288 -432.618896)
			(xy 133.241761 -432.606822) (xy 133.249224 -432.583855) (xy 133.263418 -432.564318) (xy 133.282955 -432.550124)
			(xy 133.305922 -432.542661) (xy 133.317996 -432.542188) (xy 134.257796 -432.542188) (xy 134.26987 -432.542668)
			(xy 134.292836 -432.550129) (xy 134.30708 -432.560476) (xy 135.241284 -432.560476) (xy 135.241284 -431.833274)
			(xy 135.241537 -431.824517) (xy 135.245515 -431.80746) (xy 135.249158 -431.799492) (xy 135.482584 -431.323242)
			(xy 135.487314 -431.312737) (xy 135.490795 -431.289971) (xy 135.487297 -431.267208) (xy 135.482584 -431.256694)
			(xy 135.249158 -430.780444) (xy 135.245507 -430.772479) (xy 135.241524 -430.755421) (xy 135.241284 -430.746662)
			(xy 135.241284 -430.018952) (xy 135.241723 -430.006876) (xy 135.249198 -429.983908) (xy 135.263401 -429.964373)
			(xy 135.282944 -429.95018) (xy 135.305915 -429.942717) (xy 135.317992 -429.942244) (xy 136.257792 -429.942244)
			(xy 136.269861 -429.94277) (xy 136.29282 -429.950225) (xy 136.312353 -429.964407) (xy 136.32655 -429.98393)
			(xy 136.334021 -430.006883) (xy 136.3345 -430.018952) (xy 136.3345 -431.560478) (xy 137.24128 -431.560478)
			(xy 137.24128 -430.833276) (xy 137.241534 -430.824519) (xy 137.245512 -430.807462) (xy 137.249154 -430.799494)
			(xy 137.48258 -430.323244) (xy 137.487309 -430.312738) (xy 137.490791 -430.289973) (xy 137.487293 -430.26721)
			(xy 137.48258 -430.256696) (xy 137.249154 -429.780446) (xy 137.245503 -429.77248) (xy 137.241521 -429.755423)
			(xy 137.24128 -429.746664) (xy 137.24128 -429.018954) (xy 137.241669 -429.006858) (xy 137.249143 -428.983849)
			(xy 137.263348 -428.964267) (xy 137.2829 -428.950019) (xy 137.305893 -428.942495) (xy 137.317988 -428.941992)
			(xy 138.257788 -428.941992) (xy 138.269895 -428.942427) (xy 138.292921 -428.949922) (xy 138.307489 -428.960534)
			(xy 139.241276 -428.960534) (xy 139.241276 -426.41901) (xy 139.241717 -426.406917) (xy 139.249175 -426.383911)
			(xy 139.263367 -426.364328) (xy 139.282909 -426.350078) (xy 139.305893 -426.342553) (xy 139.317984 -426.342048)
			(xy 140.257784 -426.342048) (xy 140.269887 -426.342529) (xy 140.292905 -426.350018) (xy 140.312473 -426.364265)
			(xy 140.32667 -426.383869) (xy 140.334101 -426.406906) (xy 140.334492 -426.41901) (xy 140.334492 -427.960536)
			(xy 142.241016 -427.960536) (xy 142.241016 -425.419012) (xy 142.24147 -425.406961) (xy 142.248902 -425.384033)
			(xy 142.263043 -425.364516) (xy 142.282516 -425.350313) (xy 142.30542 -425.342809) (xy 142.31747 -425.342304)
			(xy 143.257778 -425.342304) (xy 143.269863 -425.342825) (xy 143.292857 -425.350272) (xy 143.312434 -425.364446)
			(xy 143.326686 -425.383966) (xy 143.334225 -425.406929) (xy 143.33474 -425.419012) (xy 143.33474 -427.960536)
			(xy 143.334272 -427.972584) (xy 143.326834 -427.995504) (xy 143.312694 -428.015016) (xy 143.293228 -428.029219)
			(xy 143.270333 -428.036732) (xy 143.258286 -428.037244) (xy 142.317978 -428.037244) (xy 142.305886 -428.036811)
			(xy 142.282882 -428.029347) (xy 142.263301 -428.015152) (xy 142.249051 -427.99561) (xy 142.241523 -427.972627)
			(xy 142.241016 -427.960536) (xy 140.334492 -427.960536) (xy 140.334492 -428.960534) (xy 140.334022 -428.972622)
			(xy 140.32656 -428.995619) (xy 140.312373 -429.015195) (xy 140.292843 -429.029446) (xy 140.269871 -429.036983)
			(xy 140.257784 -429.037496) (xy 139.317984 -429.037496) (xy 139.305874 -429.037097) (xy 139.282845 -429.029593)
			(xy 139.263272 -429.015327) (xy 139.249078 -428.995702) (xy 139.241659 -428.972646) (xy 139.241276 -428.960534)
			(xy 138.307489 -428.960534) (xy 138.312493 -428.964179) (xy 138.326689 -428.983796) (xy 138.334111 -429.006845)
			(xy 138.334496 -429.018954) (xy 138.334496 -431.560478) (xy 138.333975 -431.572563) (xy 138.326528 -431.595557)
			(xy 138.312354 -431.615134) (xy 138.292834 -431.629386) (xy 138.269871 -431.636925) (xy 138.257788 -431.63744)
			(xy 137.317988 -431.63744) (xy 137.305882 -431.636995) (xy 137.282862 -431.629497) (xy 137.263292 -431.615241)
			(xy 137.249096 -431.595628) (xy 137.241669 -431.572585) (xy 137.24128 -431.560478) (xy 136.3345 -431.560478)
			(xy 136.3345 -432.560476) (xy 136.334067 -432.572558) (xy 136.326605 -432.595542) (xy 136.312404 -432.615093)
			(xy 136.292856 -432.629297) (xy 136.269874 -432.636764) (xy 136.257792 -432.637184) (xy 135.317992 -432.637184)
			(xy 135.305906 -432.636794) (xy 135.282919 -432.629321) (xy 135.263367 -432.61511) (xy 135.249164 -432.595552)
			(xy 135.241701 -432.572562) (xy 135.241284 -432.560476) (xy 134.30708 -432.560476) (xy 134.312373 -432.564321)
			(xy 134.326568 -432.583857) (xy 134.334031 -432.606822) (xy 134.334504 -432.618896) (xy 134.334504 -435.16042)
			(xy 134.334053 -435.172496) (xy 134.326584 -435.195464) (xy 134.312384 -435.215001) (xy 134.292843 -435.229195)
			(xy 134.269872 -435.236656) (xy 134.257796 -435.237128) (xy 133.317996 -435.237128) (xy 133.305923 -435.236639)
			(xy 133.282959 -435.229178) (xy 133.263424 -435.214987) (xy 133.249229 -435.195455) (xy 133.241763 -435.172493)
			(xy 133.241288 -435.16042) (xy 132.334508 -435.16042) (xy 132.334508 -436.160418) (xy 132.334009 -436.172504)
			(xy 132.326553 -436.195497) (xy 132.312373 -436.215072) (xy 132.29285 -436.229324) (xy 132.269884 -436.236864)
			(xy 132.2578 -436.23738) (xy 131.318 -436.23738) (xy 131.305889 -436.236984) (xy 131.282858 -436.229482)
			(xy 131.263283 -436.215216) (xy 131.24909 -436.195589) (xy 131.241672 -436.17253) (xy 131.241292 -436.160418)
			(xy 130.306665 -436.160418) (xy 130.312329 -436.164539) (xy 130.326567 -436.184162) (xy 130.334045 -436.207224)
			(xy 130.334512 -436.219346) (xy 130.334512 -438.76087) (xy 130.333963 -438.772978) (xy 130.326491 -438.796012)
			(xy 130.312267 -438.81561) (xy 130.292684 -438.829854) (xy 130.269658 -438.837351) (xy 130.25755 -438.837832)
			(xy 129.31775 -438.837832) (xy 129.30563 -438.83743) (xy 129.28258 -438.829926) (xy 129.262976 -438.815667)
			(xy 129.248738 -438.796048) (xy 129.241257 -438.772991) (xy 129.240788 -438.76087) (xy 128.334516 -438.76087)
			(xy 128.334516 -439.760868) (xy 131.240784 -439.760868) (xy 131.240784 -437.219344) (xy 131.241297 -437.207298)
			(xy 131.248716 -437.184376) (xy 131.262843 -437.164861) (xy 131.282302 -437.150656) (xy 131.305194 -437.143145)
			(xy 131.317238 -437.142636) (xy 132.257546 -437.142636) (xy 132.269638 -437.143068) (xy 132.292639 -437.150537)
			(xy 132.312218 -437.164733) (xy 132.326467 -437.184273) (xy 132.333999 -437.207254) (xy 132.334508 -437.219344)
			(xy 132.334508 -438.76087) (xy 133.24078 -438.76087) (xy 133.24078 -436.219346) (xy 133.2412 -436.207221)
			(xy 133.248684 -436.184157) (xy 133.262935 -436.164537) (xy 133.282553 -436.150286) (xy 133.305617 -436.1428)
			(xy 133.317742 -436.142384) (xy 134.257542 -436.142384) (xy 134.269672 -436.142725) (xy 134.29274 -436.150234)
			(xy 134.30674 -436.160418) (xy 135.241284 -436.160418) (xy 135.241284 -435.433216) (xy 135.24155 -435.42446)
			(xy 135.24552 -435.407402) (xy 135.249158 -435.399434) (xy 135.482584 -434.923184) (xy 135.487285 -434.912667)
			(xy 135.490777 -434.889909) (xy 135.487291 -434.86715) (xy 135.482584 -434.856636) (xy 135.249158 -434.380386)
			(xy 135.245489 -434.372428) (xy 135.241518 -434.355364) (xy 135.241284 -434.346604) (xy 135.241284 -433.618894)
			(xy 135.241703 -433.6068) (xy 135.249167 -433.583792) (xy 135.263364 -433.564208) (xy 135.282911 -433.549959)
			(xy 135.305899 -433.542435) (xy 135.317992 -433.541932) (xy 136.257792 -433.541932) (xy 136.269904 -433.542323)
			(xy 136.292936 -433.549824) (xy 136.312512 -433.564091) (xy 136.326706 -433.58372) (xy 136.334121 -433.606781)
			(xy 136.3345 -433.618894) (xy 136.3345 -435.16042) (xy 137.24128 -435.16042) (xy 137.24128 -434.433218)
			(xy 137.241547 -434.424462) (xy 137.245516 -434.407405) (xy 137.249154 -434.399436) (xy 137.48258 -433.923186)
			(xy 137.48728 -433.912669) (xy 137.490772 -433.889911) (xy 137.487286 -433.867152) (xy 137.48258 -433.856638)
			(xy 137.249154 -433.380388) (xy 137.245485 -433.37243) (xy 137.241514 -433.355366) (xy 137.24128 -433.346606)
			(xy 137.24128 -432.618896) (xy 137.241761 -432.606822) (xy 137.249223 -432.583857) (xy 137.263416 -432.564321)
			(xy 137.28295 -432.550126) (xy 137.305914 -432.542662) (xy 137.317988 -432.542188) (xy 138.257788 -432.542188)
			(xy 138.26987 -432.542623) (xy 138.292851 -432.550087) (xy 138.307154 -432.560476) (xy 139.241276 -432.560476)
			(xy 139.241276 -431.833274) (xy 139.241529 -431.824517) (xy 139.245508 -431.80746) (xy 139.24915 -431.799492)
			(xy 139.482576 -431.323242) (xy 139.487307 -431.312737) (xy 139.490788 -431.289971) (xy 139.487289 -431.267208)
			(xy 139.482576 -431.256694) (xy 139.24915 -430.780444) (xy 139.245499 -430.772479) (xy 139.241516 -430.755421)
			(xy 139.241276 -430.746662) (xy 139.241276 -430.018952) (xy 139.241723 -430.006877) (xy 139.249197 -429.98391)
			(xy 139.263398 -429.964376) (xy 139.282939 -429.950182) (xy 139.305908 -429.942718) (xy 139.317984 -429.942244)
			(xy 140.257784 -429.942244) (xy 140.269853 -429.942777) (xy 140.292812 -429.950229) (xy 140.312345 -429.96441)
			(xy 140.326541 -429.983931) (xy 140.334013 -430.006883) (xy 140.334492 -430.018952) (xy 140.334492 -431.560478)
			(xy 142.241524 -431.560478) (xy 142.241524 -430.833276) (xy 142.241773 -430.824519) (xy 142.245754 -430.807461)
			(xy 142.249398 -430.799494) (xy 142.482824 -430.323244) (xy 142.487551 -430.312738) (xy 142.491031 -430.289973)
			(xy 142.487535 -430.267211) (xy 142.482824 -430.256696) (xy 142.249398 -429.780446) (xy 142.24575 -429.772479)
			(xy 142.241765 -429.755422) (xy 142.241524 -429.746664) (xy 142.241524 -429.018954) (xy 142.241968 -429.006864)
			(xy 142.249435 -428.983864) (xy 142.263628 -428.964286) (xy 142.283165 -428.950037) (xy 142.306143 -428.942503)
			(xy 142.318232 -428.941992) (xy 143.258032 -428.941992) (xy 143.270142 -428.942389) (xy 143.293169 -428.949896)
			(xy 143.307763 -428.960534) (xy 144.241012 -428.960534) (xy 144.241012 -426.41901) (xy 144.24152 -426.406899)
			(xy 144.249001 -426.38386) (xy 144.263235 -426.36426) (xy 144.282828 -426.350018) (xy 144.305863 -426.342526)
			(xy 144.317974 -426.342048) (xy 145.257774 -426.342048) (xy 145.269896 -426.342482) (xy 145.292956 -426.349969)
			(xy 145.312572 -426.364216) (xy 145.326824 -426.38383) (xy 145.334315 -426.406888) (xy 145.334736 -426.41901)
			(xy 145.334736 -427.960536) (xy 146.241008 -427.960536) (xy 146.241008 -425.419012) (xy 146.24147 -425.406962)
			(xy 146.248901 -425.384035) (xy 146.263041 -425.364518) (xy 146.282511 -425.350315) (xy 146.305413 -425.34281)
			(xy 146.317462 -425.342304) (xy 147.25777 -425.342304) (xy 147.269854 -425.342832) (xy 147.292848 -425.350276)
			(xy 147.312425 -425.364448) (xy 147.326678 -425.383967) (xy 147.334217 -425.40693) (xy 147.334732 -425.419012)
			(xy 147.334732 -427.960536) (xy 147.334272 -427.972585) (xy 147.326833 -427.995506) (xy 147.312691 -428.015019)
			(xy 147.293223 -428.029222) (xy 147.270325 -428.036733) (xy 147.258278 -428.037244) (xy 146.31797 -428.037244)
			(xy 146.305877 -428.036818) (xy 146.282873 -428.029351) (xy 146.263292 -428.015154) (xy 146.249043 -427.995612)
			(xy 146.241515 -427.972627) (xy 146.241008 -427.960536) (xy 145.334736 -427.960536) (xy 145.334736 -428.960534)
			(xy 145.334317 -428.972653) (xy 145.326817 -428.995702) (xy 145.312562 -429.015305) (xy 145.292948 -429.029545)
			(xy 145.269893 -429.037026) (xy 145.257774 -429.037496) (xy 144.317974 -429.037496) (xy 144.305861 -429.037011)
			(xy 144.282823 -429.029521) (xy 144.263225 -429.015281) (xy 144.248983 -428.995684) (xy 144.24149 -428.972646)
			(xy 144.241012 -428.960534) (xy 143.307763 -428.960534) (xy 143.312741 -428.964163) (xy 143.326934 -428.983788)
			(xy 143.334356 -429.006843) (xy 143.33474 -429.018954) (xy 143.33474 -431.560478) (xy 143.334273 -431.572568)
			(xy 143.32682 -431.595572) (xy 143.312634 -431.615154) (xy 143.293099 -431.629404) (xy 143.270121 -431.636933)
			(xy 143.258032 -431.63744) (xy 142.318232 -431.63744) (xy 142.306129 -431.636957) (xy 142.283109 -431.629471)
			(xy 142.263539 -431.615225) (xy 142.249342 -431.59562) (xy 142.241913 -431.572582) (xy 142.241524 -431.560478)
			(xy 140.334492 -431.560478) (xy 140.334492 -432.560476) (xy 140.334067 -432.572559) (xy 140.326604 -432.595544)
			(xy 140.312401 -432.615096) (xy 140.292851 -432.6293) (xy 140.269867 -432.636765) (xy 140.257784 -432.637184)
			(xy 139.317984 -432.637184) (xy 139.305898 -432.636801) (xy 139.282911 -432.629326) (xy 139.263359 -432.615113)
			(xy 139.249156 -432.595553) (xy 139.241693 -432.572562) (xy 139.241276 -432.560476) (xy 138.307154 -432.560476)
			(xy 138.312401 -432.564287) (xy 138.326606 -432.583834) (xy 138.334074 -432.606814) (xy 138.334496 -432.618896)
			(xy 138.334496 -435.16042) (xy 138.334052 -435.172497) (xy 138.326583 -435.195467) (xy 138.312381 -435.215004)
			(xy 138.292838 -435.229198) (xy 138.269865 -435.236657) (xy 138.257788 -435.237128) (xy 137.317988 -435.237128)
			(xy 137.305915 -435.236646) (xy 137.282951 -435.229183) (xy 137.263416 -435.21499) (xy 137.249221 -435.195456)
			(xy 137.241755 -435.172493) (xy 137.24128 -435.16042) (xy 136.3345 -435.16042) (xy 136.3345 -436.160418)
			(xy 136.334009 -436.172505) (xy 136.326552 -436.195499) (xy 136.31237 -436.215075) (xy 136.292845 -436.229327)
			(xy 136.269877 -436.236865) (xy 136.257792 -436.23738) (xy 135.317992 -436.23738) (xy 135.305881 -436.23699)
			(xy 135.28285 -436.229486) (xy 135.263275 -436.215219) (xy 135.249081 -436.19559) (xy 135.241664 -436.172531)
			(xy 135.241284 -436.160418) (xy 134.30674 -436.160418) (xy 134.312358 -436.164505) (xy 134.326606 -436.184139)
			(xy 134.334089 -436.207216) (xy 134.334504 -436.219346) (xy 134.334504 -438.76087) (xy 134.333963 -438.772979)
			(xy 134.326489 -438.796014) (xy 134.312264 -438.815613) (xy 134.292679 -438.829857) (xy 134.26965 -438.837352)
			(xy 134.257542 -438.837832) (xy 133.317742 -438.837832) (xy 133.305618 -438.837404) (xy 133.282556 -438.82992)
			(xy 133.262937 -438.815671) (xy 133.248686 -438.796055) (xy 133.241198 -438.772993) (xy 133.24078 -438.76087)
			(xy 132.334508 -438.76087) (xy 132.334508 -439.760868) (xy 135.240776 -439.760868) (xy 135.240776 -437.219344)
			(xy 135.241297 -437.207298) (xy 135.248715 -437.184378) (xy 135.26284 -437.164864) (xy 135.282297 -437.150658)
			(xy 135.305186 -437.143147) (xy 135.31723 -437.142636) (xy 136.257538 -437.142636) (xy 136.269629 -437.143075)
			(xy 136.29263 -437.150542) (xy 136.312209 -437.164736) (xy 136.326459 -437.184274) (xy 136.333991 -437.207254)
			(xy 136.3345 -437.219344) (xy 136.3345 -438.76087) (xy 137.240772 -438.76087) (xy 137.240772 -436.219346)
			(xy 137.2412 -436.207222) (xy 137.248683 -436.184159) (xy 137.262932 -436.16454) (xy 137.282548 -436.150289)
			(xy 137.30561 -436.142801) (xy 137.317734 -436.142384) (xy 138.257534 -436.142384) (xy 138.269663 -436.142732)
			(xy 138.292731 -436.150239) (xy 138.306726 -436.160418) (xy 139.241276 -436.160418) (xy 139.241276 -435.433216)
			(xy 139.241543 -435.42446) (xy 139.245512 -435.407403) (xy 139.24915 -435.399434) (xy 139.482576 -434.923184)
			(xy 139.487278 -434.912667) (xy 139.490769 -434.889909) (xy 139.487283 -434.86715) (xy 139.482576 -434.856636)
			(xy 139.24915 -434.380386) (xy 139.24548 -434.372428) (xy 139.24151 -434.355364) (xy 139.241276 -434.346604)
			(xy 139.241276 -433.618894) (xy 139.241703 -433.606801) (xy 139.249166 -433.583794) (xy 139.263361 -433.564211)
			(xy 139.282906 -433.549962) (xy 139.305892 -433.542436) (xy 139.317984 -433.541932) (xy 140.257784 -433.541932)
			(xy 140.269895 -433.542331) (xy 140.292927 -433.549829) (xy 140.312503 -433.564094) (xy 140.326697 -433.583722)
			(xy 140.334113 -433.606781) (xy 140.334492 -433.618894) (xy 140.334492 -435.16042) (xy 142.241016 -435.16042)
			(xy 142.241016 -434.433472) (xy 142.241342 -434.424703) (xy 142.245441 -434.407645) (xy 142.249144 -434.39969)
			(xy 142.249144 -434.399182) (xy 142.48257 -433.923186) (xy 142.487271 -433.912669) (xy 142.490763 -433.889911)
			(xy 142.487277 -433.867152) (xy 142.48257 -433.856638) (xy 142.249144 -433.380642) (xy 142.249144 -433.380134)
			(xy 142.245423 -433.372184) (xy 142.241315 -433.355124) (xy 142.241016 -433.346352) (xy 142.241016 -432.618896)
			(xy 142.241457 -432.606844) (xy 142.248893 -432.583916) (xy 142.263038 -432.564399) (xy 142.282513 -432.550196)
			(xy 142.305419 -432.542693) (xy 142.31747 -432.542188) (xy 143.257778 -432.542188) (xy 143.269871 -432.542627)
			(xy 143.292879 -432.550084) (xy 143.30722 -432.560476) (xy 144.24152 -432.560476) (xy 144.24152 -431.833274)
			(xy 144.241769 -431.824517) (xy 144.24575 -431.807459) (xy 144.249394 -431.799492) (xy 144.48282 -431.323242)
			(xy 144.487549 -431.312736) (xy 144.491028 -431.289971) (xy 144.487531 -431.267209) (xy 144.48282 -431.256694)
			(xy 144.249394 -430.780444) (xy 144.245745 -430.772478) (xy 144.241761 -430.75542) (xy 144.24152 -430.746662)
			(xy 144.24152 -430.018952) (xy 144.241924 -430.006872) (xy 144.249403 -429.983899) (xy 144.263614 -429.96436)
			(xy 144.283167 -429.950168) (xy 144.306148 -429.942712) (xy 144.318228 -429.942244) (xy 145.258028 -429.942244)
			(xy 145.270099 -429.942739) (xy 145.293059 -429.950204) (xy 145.312592 -429.964394) (xy 145.326787 -429.983923)
			(xy 145.334258 -430.006881) (xy 145.334736 -430.018952) (xy 145.334736 -431.560478) (xy 146.241516 -431.560478)
			(xy 146.241516 -430.833276) (xy 146.241766 -430.824519) (xy 146.245746 -430.807461) (xy 146.24939 -430.799494)
			(xy 146.482816 -430.323244) (xy 146.487543 -430.312738) (xy 146.491023 -430.289973) (xy 146.487527 -430.267211)
			(xy 146.482816 -430.256696) (xy 146.24939 -429.780446) (xy 146.245741 -429.77248) (xy 146.241757 -429.755422)
			(xy 146.241516 -429.746664) (xy 146.241516 -429.018954) (xy 146.241968 -429.006864) (xy 146.249434 -428.983866)
			(xy 146.263626 -428.964289) (xy 146.28316 -428.950039) (xy 146.306136 -428.942504) (xy 146.318224 -428.941992)
			(xy 147.258024 -428.941992) (xy 147.270133 -428.942396) (xy 147.29316 -428.949901) (xy 147.307749 -428.960534)
			(xy 148.241004 -428.960534) (xy 148.241004 -426.41901) (xy 148.24152 -426.406899) (xy 148.249 -426.383862)
			(xy 148.263232 -426.364263) (xy 148.282823 -426.35002) (xy 148.305856 -426.342527) (xy 148.317966 -426.342048)
			(xy 149.257766 -426.342048) (xy 149.269888 -426.342489) (xy 149.292947 -426.349973) (xy 149.312564 -426.364219)
			(xy 149.326816 -426.383831) (xy 149.334307 -426.406888) (xy 149.334728 -426.41901) (xy 149.334728 -427.960536)
			(xy 150.241 -427.960536) (xy 150.241 -425.419012) (xy 150.24147 -425.406962) (xy 150.2489 -425.384037)
			(xy 150.263038 -425.364521) (xy 150.282506 -425.350318) (xy 150.305406 -425.342811) (xy 150.317454 -425.342304)
			(xy 151.257762 -425.342304) (xy 151.269846 -425.342839) (xy 151.292839 -425.350281) (xy 151.312417 -425.364451)
			(xy 151.32667 -425.383968) (xy 151.334209 -425.40693) (xy 151.334724 -425.419012) (xy 151.334724 -427.960536)
			(xy 151.334271 -427.972586) (xy 151.326832 -427.995508) (xy 151.312688 -428.015022) (xy 151.293218 -428.029225)
			(xy 151.270318 -428.036734) (xy 151.25827 -428.037244) (xy 150.317962 -428.037244) (xy 150.305869 -428.036825)
			(xy 150.282864 -428.029356) (xy 150.263284 -428.015157) (xy 150.249035 -427.995613) (xy 150.241507 -427.972628)
			(xy 150.241 -427.960536) (xy 149.334728 -427.960536) (xy 149.334728 -428.960534) (xy 149.334317 -428.972654)
			(xy 149.326816 -428.995704) (xy 149.31256 -429.015308) (xy 149.292943 -429.029547) (xy 149.269886 -429.037027)
			(xy 149.257766 -429.037496) (xy 148.317966 -429.037496) (xy 148.305853 -429.037018) (xy 148.282814 -429.029525)
			(xy 148.263216 -429.015284) (xy 148.248975 -428.995686) (xy 148.241482 -428.972647) (xy 148.241004 -428.960534)
			(xy 147.307749 -428.960534) (xy 147.312732 -428.964166) (xy 147.326926 -428.983789) (xy 147.334348 -429.006843)
			(xy 147.334732 -429.018954) (xy 147.334732 -431.560478) (xy 147.334273 -431.572569) (xy 147.326819 -431.595574)
			(xy 147.312632 -431.615156) (xy 147.293094 -431.629407) (xy 147.270114 -431.636934) (xy 147.258024 -431.63744)
			(xy 146.318224 -431.63744) (xy 146.30612 -431.636964) (xy 146.283101 -431.629476) (xy 146.263531 -431.615228)
			(xy 146.249334 -431.595622) (xy 146.241905 -431.572583) (xy 146.241516 -431.560478) (xy 145.334736 -431.560478)
			(xy 145.334736 -432.560476) (xy 145.334216 -432.572547) (xy 145.326763 -432.595508) (xy 145.31258 -432.615043)
			(xy 145.293055 -432.62924) (xy 145.270098 -432.636708) (xy 145.258028 -432.637184) (xy 144.318228 -432.637184)
			(xy 144.306144 -432.636763) (xy 144.283159 -432.6293) (xy 144.263606 -432.615097) (xy 144.249402 -432.595545)
			(xy 144.241938 -432.57256) (xy 144.24152 -432.560476) (xy 143.30722 -432.560476) (xy 143.312464 -432.564276)
			(xy 143.326713 -432.583818) (xy 143.334237 -432.606804) (xy 143.33474 -432.618896) (xy 143.33474 -435.16042)
			(xy 143.334258 -435.172467) (xy 143.326824 -435.195387) (xy 143.312688 -435.214899) (xy 143.293225 -435.229103)
			(xy 143.270332 -435.236615) (xy 143.258286 -435.237128) (xy 142.317978 -435.237128) (xy 142.305884 -435.236711)
			(xy 142.282877 -435.229244) (xy 142.263295 -435.215046) (xy 142.249046 -435.1955) (xy 142.24152 -435.172513)
			(xy 142.241016 -435.16042) (xy 140.334492 -435.16042) (xy 140.334492 -436.160418) (xy 140.334009 -436.172505)
			(xy 140.326551 -436.195501) (xy 140.312367 -436.215078) (xy 140.29284 -436.229329) (xy 140.26987 -436.236866)
			(xy 140.257784 -436.23738) (xy 139.317984 -436.23738) (xy 139.305872 -436.236997) (xy 139.282841 -436.229491)
			(xy 139.263266 -436.215221) (xy 139.249073 -436.195592) (xy 139.241656 -436.172531) (xy 139.241276 -436.160418)
			(xy 138.306726 -436.160418) (xy 138.312349 -436.164508) (xy 138.326598 -436.184141) (xy 138.334081 -436.207216)
			(xy 138.334496 -436.219346) (xy 138.334496 -438.76087) (xy 138.333963 -438.77298) (xy 138.326488 -438.796016)
			(xy 138.312261 -438.815615) (xy 138.292673 -438.829859) (xy 138.269643 -438.837353) (xy 138.257534 -438.837832)
			(xy 137.317734 -438.837832) (xy 137.30561 -438.837411) (xy 137.282547 -438.829924) (xy 137.262929 -438.815674)
			(xy 137.248678 -438.796056) (xy 137.24119 -438.772994) (xy 137.240772 -438.76087) (xy 136.3345 -438.76087)
			(xy 136.3345 -439.760868) (xy 139.240768 -439.760868) (xy 139.240768 -437.219344) (xy 139.241297 -437.207299)
			(xy 139.248713 -437.18438) (xy 139.262838 -437.164867) (xy 139.282292 -437.150661) (xy 139.305179 -437.143148)
			(xy 139.317222 -437.142636) (xy 140.25753 -437.142636) (xy 140.269621 -437.143082) (xy 140.292622 -437.150546)
			(xy 140.312201 -437.164738) (xy 140.326451 -437.184276) (xy 140.333982 -437.207255) (xy 140.334492 -437.219344)
			(xy 140.334492 -438.76087) (xy 142.241016 -438.76087) (xy 142.241016 -436.219346) (xy 142.241499 -436.207228)
			(xy 142.248976 -436.184174) (xy 142.263212 -436.16456) (xy 142.282813 -436.150307) (xy 142.30586 -436.142809)
			(xy 142.317978 -436.142384) (xy 143.257778 -436.142384) (xy 143.269904 -436.142779) (xy 143.29297 -436.150271)
			(xy 143.306934 -436.160418) (xy 144.241012 -436.160418) (xy 144.241012 -435.43347) (xy 144.241337 -435.424701)
			(xy 144.245437 -435.407643) (xy 144.24914 -435.399688) (xy 144.24914 -435.39918) (xy 144.482566 -434.923184)
			(xy 144.487263 -434.912666) (xy 144.490751 -434.889909) (xy 144.487268 -434.867151) (xy 144.482566 -434.856636)
			(xy 144.24914 -434.38064) (xy 144.24914 -434.380132) (xy 144.245418 -434.372183) (xy 144.241311 -434.355122)
			(xy 144.241012 -434.34635) (xy 144.241012 -433.618894) (xy 144.241506 -433.606782) (xy 144.248992 -433.583743)
			(xy 144.263229 -433.564143) (xy 144.282825 -433.549901) (xy 144.305862 -433.54241) (xy 144.317974 -433.541932)
			(xy 145.257774 -433.541932) (xy 145.269895 -433.542382) (xy 145.292952 -433.549866) (xy 145.312567 -433.56411)
			(xy 145.326819 -433.58372) (xy 145.334313 -433.606773) (xy 145.334736 -433.618894) (xy 145.334736 -435.16042)
			(xy 146.241008 -435.16042) (xy 146.241008 -434.433472) (xy 146.241334 -434.424703) (xy 146.245433 -434.407645)
			(xy 146.249136 -434.39969) (xy 146.249136 -434.399182) (xy 146.482562 -433.923186) (xy 146.487258 -433.912668)
			(xy 146.490746 -433.889911) (xy 146.487264 -433.867153) (xy 146.482562 -433.856638) (xy 146.249136 -433.380642)
			(xy 146.249136 -433.380134) (xy 146.245421 -433.372182) (xy 146.241308 -433.355124) (xy 146.241008 -433.346352)
			(xy 146.241008 -432.618896) (xy 146.241457 -432.606845) (xy 146.248892 -432.583918) (xy 146.263035 -432.564401)
			(xy 146.282508 -432.550199) (xy 146.305412 -432.542694) (xy 146.317462 -432.542188) (xy 147.25777 -432.542188)
			(xy 147.269863 -432.542634) (xy 147.29287 -432.550088) (xy 147.307207 -432.560476) (xy 148.241512 -432.560476)
			(xy 148.241512 -431.833274) (xy 148.241762 -431.824517) (xy 148.245742 -431.807459) (xy 148.249386 -431.799492)
			(xy 148.482812 -431.323242) (xy 148.487541 -431.312736) (xy 148.491021 -431.289971) (xy 148.487524 -431.267209)
			(xy 148.482812 -431.256694) (xy 148.249386 -430.780444) (xy 148.245737 -430.772478) (xy 148.241753 -430.75542)
			(xy 148.241512 -430.746662) (xy 148.241512 -430.018952) (xy 148.241924 -430.006873) (xy 148.249402 -429.983901)
			(xy 148.263611 -429.964363) (xy 148.283162 -429.950171) (xy 148.306141 -429.942713) (xy 148.31822 -429.942244)
			(xy 149.25802 -429.942244) (xy 149.270091 -429.942747) (xy 149.29305 -429.950209) (xy 149.312583 -429.964397)
			(xy 149.326778 -429.983924) (xy 149.334249 -430.006881) (xy 149.334728 -430.018952) (xy 149.334728 -431.560478)
			(xy 150.241508 -431.560478) (xy 150.241508 -430.833276) (xy 150.241759 -430.824519) (xy 150.245738 -430.807461)
			(xy 150.249382 -430.799494) (xy 150.482808 -430.323244) (xy 150.487536 -430.312738) (xy 150.491016 -430.289973)
			(xy 150.48752 -430.26721) (xy 150.482808 -430.256696) (xy 150.249382 -429.780446) (xy 150.245733 -429.77248)
			(xy 150.241749 -429.755422) (xy 150.241508 -429.746664) (xy 150.241508 -429.018954) (xy 150.241968 -429.006865)
			(xy 150.249433 -428.983868) (xy 150.263623 -428.964292) (xy 150.283155 -428.950042) (xy 150.306129 -428.942505)
			(xy 150.318216 -428.941992) (xy 151.258016 -428.941992) (xy 151.270125 -428.942402) (xy 151.293151 -428.949905)
			(xy 151.307736 -428.960534) (xy 152.240996 -428.960534) (xy 152.240996 -426.41901) (xy 152.24152 -426.4069)
			(xy 152.248999 -426.383864) (xy 152.263229 -426.364266) (xy 152.282818 -426.350023) (xy 152.305848 -426.342528)
			(xy 152.317958 -426.342048) (xy 153.257758 -426.342048) (xy 153.26988 -426.342496) (xy 153.292939 -426.349978)
			(xy 153.312555 -426.364222) (xy 153.326808 -426.383833) (xy 153.334299 -426.406889) (xy 153.33472 -426.41901)
			(xy 153.33472 -427.960536) (xy 154.240992 -427.960536) (xy 154.240992 -425.419012) (xy 154.24147 -425.406963)
			(xy 154.248898 -425.384039) (xy 154.263035 -425.364524) (xy 154.282501 -425.35032) (xy 154.305399 -425.342812)
			(xy 154.317446 -425.342304) (xy 155.257754 -425.342304) (xy 155.269838 -425.342846) (xy 155.292831 -425.350286)
			(xy 155.312408 -425.364454) (xy 155.326662 -425.38397) (xy 155.334201 -425.40693) (xy 155.334716 -425.419012)
			(xy 155.334716 -427.960536) (xy 155.334271 -427.972587) (xy 155.326831 -427.995511) (xy 155.312685 -428.015024)
			(xy 155.293213 -428.029227) (xy 155.270311 -428.036735) (xy 155.258262 -428.037244) (xy 154.317954 -428.037244)
			(xy 154.30586 -428.036832) (xy 154.282856 -428.02936) (xy 154.263275 -428.01516) (xy 154.249027 -427.995615)
			(xy 154.241499 -427.972628) (xy 154.240992 -427.960536) (xy 153.33472 -427.960536) (xy 153.33472 -428.960534)
			(xy 153.334369 -428.972663) (xy 153.326862 -428.99573) (xy 153.312594 -429.015348) (xy 153.292962 -429.029597)
			(xy 153.269887 -429.03708) (xy 153.257758 -429.037496) (xy 152.317958 -429.037496) (xy 152.305845 -429.037025)
			(xy 152.282806 -429.02953) (xy 152.263208 -429.015287) (xy 152.248966 -428.995687) (xy 152.241474 -428.972647)
			(xy 152.240996 -428.960534) (xy 151.307736 -428.960534) (xy 151.312724 -428.964169) (xy 151.326918 -428.983791)
			(xy 151.33434 -429.006844) (xy 151.334724 -429.018954) (xy 151.334724 -431.560478) (xy 151.334273 -431.57257)
			(xy 151.326818 -431.595576) (xy 151.312629 -431.615159) (xy 151.293089 -431.629409) (xy 151.270106 -431.636935)
			(xy 151.258016 -431.63744) (xy 150.318216 -431.63744) (xy 150.306112 -431.63697) (xy 150.283092 -431.62948)
			(xy 150.263522 -431.615231) (xy 150.249326 -431.595623) (xy 150.241897 -431.572583) (xy 150.241508 -431.560478)
			(xy 149.334728 -431.560478) (xy 149.334728 -432.560476) (xy 149.334267 -432.572555) (xy 149.326809 -432.595534)
			(xy 149.312614 -432.615083) (xy 149.293073 -432.629288) (xy 149.270099 -432.63676) (xy 149.25802 -432.637184)
			(xy 148.31822 -432.637184) (xy 148.306136 -432.63677) (xy 148.28315 -432.629305) (xy 148.263597 -432.6151)
			(xy 148.249393 -432.595547) (xy 148.24193 -432.57256) (xy 148.241512 -432.560476) (xy 147.307207 -432.560476)
			(xy 147.312455 -432.564278) (xy 147.326705 -432.58382) (xy 147.334229 -432.606805) (xy 147.334732 -432.618896)
			(xy 147.334732 -435.16042) (xy 147.334258 -435.172468) (xy 147.326823 -435.195389) (xy 147.312685 -435.214901)
			(xy 147.29322 -435.229105) (xy 147.270324 -435.236616) (xy 147.258278 -435.237128) (xy 146.31797 -435.237128)
			(xy 146.305876 -435.236718) (xy 146.282869 -435.229249) (xy 146.263286 -435.215049) (xy 146.249038 -435.195502)
			(xy 146.241512 -435.172513) (xy 146.241008 -435.16042) (xy 145.334736 -435.16042) (xy 145.334736 -436.160418)
			(xy 145.334355 -436.172544) (xy 145.326854 -436.195608) (xy 145.312594 -436.215225) (xy 145.292969 -436.229474)
			(xy 145.2699 -436.236962) (xy 145.257774 -436.23738) (xy 144.317974 -436.23738) (xy 144.30586 -436.236911)
			(xy 144.282819 -436.229419) (xy 144.263219 -436.215175) (xy 144.248978 -436.195574) (xy 144.241488 -436.172532)
			(xy 144.241012 -436.160418) (xy 143.306934 -436.160418) (xy 143.31259 -436.164528) (xy 143.32684 -436.184151)
			(xy 143.334324 -436.20722) (xy 143.33474 -436.219346) (xy 143.33474 -438.76087) (xy 143.334314 -438.772993)
			(xy 143.326828 -438.796055) (xy 143.312578 -438.815672) (xy 143.292962 -438.829924) (xy 143.269901 -438.837413)
			(xy 143.257778 -438.837832) (xy 142.317978 -438.837832) (xy 142.305851 -438.837458) (xy 142.282787 -438.829956)
			(xy 142.263169 -438.815694) (xy 142.24892 -438.796067) (xy 142.241434 -438.772997) (xy 142.241016 -438.76087)
			(xy 140.334492 -438.76087) (xy 140.334492 -439.760868) (xy 144.241012 -439.760868) (xy 144.241012 -437.219344)
			(xy 144.241498 -437.207295) (xy 144.24892 -437.184369) (xy 144.263053 -437.164851) (xy 144.28252 -437.150647)
			(xy 144.305419 -437.143142) (xy 144.317466 -437.142636) (xy 145.257774 -437.142636) (xy 145.269862 -437.143129)
			(xy 145.292861 -437.150579) (xy 145.312441 -437.164758) (xy 145.326692 -437.184286) (xy 145.334226 -437.207258)
			(xy 145.334736 -437.219344) (xy 145.334736 -438.76087) (xy 146.241008 -438.76087) (xy 146.241008 -436.219346)
			(xy 146.241499 -436.207229) (xy 146.248975 -436.184176) (xy 146.263209 -436.164563) (xy 146.282808 -436.150309)
			(xy 146.305853 -436.14281) (xy 146.31797 -436.142384) (xy 147.25777 -436.142384) (xy 147.269896 -436.142786)
			(xy 147.292961 -436.150276) (xy 147.306921 -436.160418) (xy 148.241004 -436.160418) (xy 148.241004 -435.43347)
			(xy 148.24133 -435.424701) (xy 148.245429 -435.407643) (xy 148.249132 -435.399688) (xy 148.249132 -435.39918)
			(xy 148.482558 -434.923184) (xy 148.487256 -434.912666) (xy 148.490743 -434.889909) (xy 148.487261 -434.867151)
			(xy 148.482558 -434.856636) (xy 148.249132 -434.38064) (xy 148.249132 -434.380132) (xy 148.245416 -434.37218)
			(xy 148.241304 -434.355122) (xy 148.241004 -434.34635) (xy 148.241004 -433.618894) (xy 148.241506 -433.606783)
			(xy 148.248991 -433.583745) (xy 148.263226 -433.564146) (xy 148.28282 -433.549904) (xy 148.305855 -433.542411)
			(xy 148.317966 -433.541932) (xy 149.257766 -433.541932) (xy 149.269886 -433.542389) (xy 149.292943 -433.549871)
			(xy 149.312558 -433.564113) (xy 149.326811 -433.583721) (xy 149.334305 -433.606774) (xy 149.334728 -433.618894)
			(xy 149.334728 -435.16042) (xy 150.241 -435.16042) (xy 150.241 -434.433472) (xy 150.241318 -434.424702)
			(xy 150.245422 -434.407644) (xy 150.249128 -434.39969) (xy 150.249128 -434.399182) (xy 150.482554 -433.923186)
			(xy 150.48725 -433.912668) (xy 150.490739 -433.889911) (xy 150.487257 -433.867153) (xy 150.482554 -433.856638)
			(xy 150.249128 -433.380642) (xy 150.249128 -433.380134) (xy 150.245412 -433.372182) (xy 150.2413 -433.355124)
			(xy 150.241 -433.346352) (xy 150.241 -432.618896) (xy 150.241457 -432.606846) (xy 150.24889 -432.58392)
			(xy 150.263032 -432.564404) (xy 150.282503 -432.550201) (xy 150.305405 -432.542695) (xy 150.317454 -432.542188)
			(xy 151.257762 -432.542188) (xy 151.269854 -432.542641) (xy 151.292862 -432.550093) (xy 151.307195 -432.560476)
			(xy 152.241504 -432.560476) (xy 152.241504 -431.833274) (xy 152.241755 -431.824517) (xy 152.245734 -431.807459)
			(xy 152.249378 -431.799492) (xy 152.482804 -431.323242) (xy 152.487534 -431.312736) (xy 152.491014 -431.289971)
			(xy 152.487516 -431.267208) (xy 152.482804 -431.256694) (xy 152.249378 -430.780444) (xy 152.245728 -430.772478)
			(xy 152.241745 -430.75542) (xy 152.241504 -430.746662) (xy 152.241504 -430.018952) (xy 152.241923 -430.006874)
			(xy 152.249401 -429.983903) (xy 152.263608 -429.964366) (xy 152.283157 -429.950173) (xy 152.306133 -429.942714)
			(xy 152.318212 -429.942244) (xy 153.258012 -429.942244) (xy 153.270082 -429.942753) (xy 153.293042 -429.950213)
			(xy 153.312574 -429.9644) (xy 153.32677 -429.983926) (xy 153.334241 -430.006882) (xy 153.33472 -430.018952)
			(xy 153.33472 -431.560478) (xy 154.2415 -431.560478) (xy 154.2415 -430.833276) (xy 154.241752 -430.824519)
			(xy 154.245731 -430.807461) (xy 154.249374 -430.799494) (xy 154.4828 -430.323244) (xy 154.487528 -430.312738)
			(xy 154.491009 -430.289973) (xy 154.487512 -430.26721) (xy 154.4828 -430.256696) (xy 154.249374 -429.780446)
			(xy 154.245724 -429.77248) (xy 154.241741 -429.755422) (xy 154.2415 -429.746664) (xy 154.2415 -429.018954)
			(xy 154.241967 -429.006866) (xy 154.249432 -428.983871) (xy 154.26362 -428.964295) (xy 154.28315 -428.950044)
			(xy 154.306122 -428.942507) (xy 154.318208 -428.941992) (xy 155.258008 -428.941992) (xy 155.270117 -428.942409)
			(xy 155.293143 -428.94991) (xy 155.307723 -428.960534) (xy 156.240988 -428.960534) (xy 156.240988 -426.41901)
			(xy 156.24152 -426.406901) (xy 156.248998 -426.383867) (xy 156.263226 -426.364269) (xy 156.282813 -426.350025)
			(xy 156.305841 -426.342529) (xy 156.31795 -426.342048) (xy 157.25775 -426.342048) (xy 157.269868 -426.342469)
			(xy 157.292915 -426.349972) (xy 157.312516 -426.364226) (xy 157.326756 -426.383839) (xy 157.33424 -426.406891)
			(xy 157.334712 -426.41901) (xy 157.334712 -428.960534) (xy 157.334218 -428.972645) (xy 157.326728 -428.995681)
			(xy 157.31249 -429.015278) (xy 157.292896 -429.02952) (xy 157.269861 -429.037016) (xy 157.25775 -429.037496)
			(xy 156.31795 -429.037496) (xy 156.305836 -429.037031) (xy 156.282797 -429.029535) (xy 156.263199 -429.015289)
			(xy 156.248958 -428.995689) (xy 156.241466 -428.972648) (xy 156.240988 -428.960534) (xy 155.307723 -428.960534)
			(xy 155.312715 -428.964172) (xy 155.32691 -428.983792) (xy 155.334332 -429.006844) (xy 155.334716 -429.018954)
			(xy 155.334716 -431.560478) (xy 155.334273 -431.572571) (xy 155.326817 -431.595578) (xy 155.312626 -431.615162)
			(xy 155.293084 -431.629412) (xy 155.270099 -431.636937) (xy 155.258008 -431.63744) (xy 154.318208 -431.63744)
			(xy 154.306104 -431.636978) (xy 154.283083 -431.629485) (xy 154.263513 -431.615234) (xy 154.249317 -431.595625)
			(xy 154.241889 -431.572584) (xy 154.2415 -431.560478) (xy 153.33472 -431.560478) (xy 153.33472 -432.560476)
			(xy 153.334267 -432.572556) (xy 153.326807 -432.595536) (xy 153.312611 -432.615086) (xy 153.293068 -432.629291)
			(xy 153.270092 -432.636761) (xy 153.258012 -432.637184) (xy 152.318212 -432.637184) (xy 152.306128 -432.636777)
			(xy 152.283141 -432.629309) (xy 152.263589 -432.615103) (xy 152.249385 -432.595548) (xy 152.241922 -432.572561)
			(xy 152.241504 -432.560476) (xy 151.307195 -432.560476) (xy 151.312447 -432.564281) (xy 151.326697 -432.583821)
			(xy 151.334221 -432.606805) (xy 151.334724 -432.618896) (xy 151.334724 -435.16042) (xy 151.334257 -435.172469)
			(xy 151.326822 -435.195391) (xy 151.312682 -435.214904) (xy 151.293215 -435.229108) (xy 151.270317 -435.236618)
			(xy 151.25827 -435.237128) (xy 150.317962 -435.237128) (xy 150.305867 -435.236724) (xy 150.28286 -435.229253)
			(xy 150.263278 -435.215052) (xy 150.24903 -435.195503) (xy 150.241504 -435.172514) (xy 150.241 -435.16042)
			(xy 149.334728 -435.16042) (xy 149.334728 -436.160418) (xy 149.334355 -436.172545) (xy 149.326853 -436.19561)
			(xy 149.312591 -436.215228) (xy 149.292964 -436.229477) (xy 149.269893 -436.236963) (xy 149.257766 -436.23738)
			(xy 148.317966 -436.23738) (xy 148.305851 -436.236918) (xy 148.28281 -436.229423) (xy 148.26321 -436.215178)
			(xy 148.248969 -436.195576) (xy 148.24148 -436.172533) (xy 148.241004 -436.160418) (xy 147.306921 -436.160418)
			(xy 147.312581 -436.16453) (xy 147.326832 -436.184153) (xy 147.334316 -436.20722) (xy 147.334732 -436.219346)
			(xy 147.334732 -438.76087) (xy 147.334314 -438.772994) (xy 147.326826 -438.796057) (xy 147.312575 -438.815675)
			(xy 147.292957 -438.829926) (xy 147.269894 -438.837414) (xy 147.25777 -438.837832) (xy 146.31797 -438.837832)
			(xy 146.305851 -438.837413) (xy 146.282802 -438.829914) (xy 146.263198 -438.81566) (xy 146.248958 -438.796045)
			(xy 146.241477 -438.772989) (xy 146.241008 -438.76087) (xy 145.334736 -438.76087) (xy 145.334736 -439.760868)
			(xy 148.241004 -439.760868) (xy 148.241004 -437.219344) (xy 148.241497 -437.207296) (xy 148.248918 -437.184371)
			(xy 148.26305 -437.164854) (xy 148.282514 -437.150649) (xy 148.305411 -437.143143) (xy 148.317458 -437.142636)
			(xy 149.257766 -437.142636) (xy 149.269853 -437.143136) (xy 149.292852 -437.150583) (xy 149.312432 -437.164761)
			(xy 149.326684 -437.184288) (xy 149.334218 -437.207258) (xy 149.334728 -437.219344) (xy 149.334728 -438.76087)
			(xy 150.241 -438.76087) (xy 150.241 -436.219346) (xy 150.241498 -436.207229) (xy 150.248973 -436.184178)
			(xy 150.263206 -436.164566) (xy 150.282803 -436.150312) (xy 150.305846 -436.142812) (xy 150.317962 -436.142384)
			(xy 151.257762 -436.142384) (xy 151.269887 -436.142793) (xy 151.292953 -436.15028) (xy 151.306908 -436.160418)
			(xy 152.240996 -436.160418) (xy 152.240996 -435.43347) (xy 152.241314 -435.4247) (xy 152.245418 -435.407642)
			(xy 152.249124 -435.399688) (xy 152.249124 -435.39918) (xy 152.48255 -434.923184) (xy 152.487248 -434.912666)
			(xy 152.490736 -434.889909) (xy 152.487253 -434.867151) (xy 152.48255 -434.856636) (xy 152.249124 -434.38064)
			(xy 152.249124 -434.380132) (xy 152.245407 -434.37218) (xy 152.241296 -434.355122) (xy 152.240996 -434.34635)
			(xy 152.240996 -433.618894) (xy 152.241506 -433.606783) (xy 152.24899 -433.583747) (xy 152.263224 -433.564149)
			(xy 152.282815 -433.549906) (xy 152.305848 -433.542412) (xy 152.317958 -433.541932) (xy 153.257758 -433.541932)
			(xy 153.269878 -433.542396) (xy 153.292934 -433.549876) (xy 153.31255 -433.564116) (xy 153.326803 -433.583722)
			(xy 153.334297 -433.606774) (xy 153.33472 -433.618894) (xy 153.33472 -435.16042) (xy 154.240992 -435.16042)
			(xy 154.240992 -434.433472) (xy 154.241311 -434.424702) (xy 154.245414 -434.407644) (xy 154.24912 -434.39969)
			(xy 154.24912 -434.399182) (xy 154.482546 -433.923186) (xy 154.487243 -433.912668) (xy 154.490732 -433.889911)
			(xy 154.487249 -433.867153) (xy 154.482546 -433.856638) (xy 154.24912 -433.380642) (xy 154.24912 -433.380134)
			(xy 154.245404 -433.372182) (xy 154.241292 -433.355124) (xy 154.240992 -433.346352) (xy 154.240992 -432.618896)
			(xy 154.241456 -432.606846) (xy 154.248889 -432.583922) (xy 154.263029 -432.564407) (xy 154.282498 -432.550204)
			(xy 154.305398 -432.542696) (xy 154.317446 -432.542188) (xy 155.257754 -432.542188) (xy 155.269846 -432.542647)
			(xy 155.292853 -432.550097) (xy 155.307181 -432.560476) (xy 156.241496 -432.560476) (xy 156.241496 -431.833274)
			(xy 156.241747 -431.824517) (xy 156.245727 -431.807459) (xy 156.24937 -431.799492) (xy 156.482796 -431.323242)
			(xy 156.487526 -431.312737) (xy 156.491006 -431.289971) (xy 156.487509 -431.267208) (xy 156.482796 -431.256694)
			(xy 156.24937 -430.780444) (xy 156.24572 -430.772478) (xy 156.241737 -430.75542) (xy 156.241496 -430.746662)
			(xy 156.241496 -430.018952) (xy 156.241923 -430.006875) (xy 156.249399 -429.983905) (xy 156.263605 -429.964368)
			(xy 156.283152 -429.950176) (xy 156.306126 -429.942715) (xy 156.318204 -429.942244) (xy 157.258004 -429.942244)
			(xy 157.270074 -429.94276) (xy 157.293033 -429.950218) (xy 157.312566 -429.964403) (xy 157.326762 -429.983927)
			(xy 157.334233 -430.006882) (xy 157.334712 -430.018952) (xy 157.334712 -432.560476) (xy 157.334267 -432.572557)
			(xy 157.326806 -432.595538) (xy 157.312609 -432.615089) (xy 157.293063 -432.629294) (xy 157.270085 -432.636762)
			(xy 157.258004 -432.637184) (xy 156.318204 -432.637184) (xy 156.306119 -432.636784) (xy 156.283132 -432.629314)
			(xy 156.26358 -432.615106) (xy 156.249376 -432.59555) (xy 156.241913 -432.572561) (xy 156.241496 -432.560476)
			(xy 155.307181 -432.560476) (xy 155.312438 -432.564284) (xy 155.326688 -432.583823) (xy 155.334213 -432.606806)
			(xy 155.334716 -432.618896) (xy 155.334716 -435.16042) (xy 155.334257 -435.17247) (xy 155.326821 -435.195393)
			(xy 155.312679 -435.214907) (xy 155.29321 -435.22911) (xy 155.27031 -435.236619) (xy 155.258262 -435.237128)
			(xy 154.317954 -435.237128) (xy 154.305859 -435.236731) (xy 154.282851 -435.229258) (xy 154.263269 -435.215054)
			(xy 154.249022 -435.195505) (xy 154.241496 -435.172514) (xy 154.240992 -435.16042) (xy 153.33472 -435.16042)
			(xy 153.33472 -436.160418) (xy 153.334354 -436.172546) (xy 153.326852 -436.195612) (xy 153.312588 -436.215231)
			(xy 153.292958 -436.22948) (xy 153.269886 -436.236964) (xy 153.257758 -436.23738) (xy 152.317958 -436.23738)
			(xy 152.305843 -436.236924) (xy 152.282801 -436.229428) (xy 152.263202 -436.215181) (xy 152.248961 -436.195577)
			(xy 152.241472 -436.172533) (xy 152.240996 -436.160418) (xy 151.306908 -436.160418) (xy 151.312573 -436.164533)
			(xy 151.326823 -436.184154) (xy 151.334308 -436.207221) (xy 151.334724 -436.219346) (xy 151.334724 -438.76087)
			(xy 151.334314 -438.772995) (xy 151.326825 -438.796059) (xy 151.312572 -438.815678) (xy 151.292952 -438.829929)
			(xy 151.269887 -438.837415) (xy 151.257762 -438.837832) (xy 150.317962 -438.837832) (xy 150.305842 -438.83742)
			(xy 150.282793 -438.829919) (xy 150.263189 -438.815662) (xy 150.24895 -438.796046) (xy 150.241469 -438.77299)
			(xy 150.241 -438.76087) (xy 149.334728 -438.76087) (xy 149.334728 -439.760868) (xy 152.240996 -439.760868)
			(xy 152.240996 -437.219344) (xy 152.241497 -437.207296) (xy 152.248917 -437.184373) (xy 152.263048 -437.164857)
			(xy 152.282509 -437.150652) (xy 152.305404 -437.143144) (xy 152.31745 -437.142636) (xy 153.257758 -437.142636)
			(xy 153.269845 -437.143143) (xy 153.292844 -437.150588) (xy 153.312424 -437.164764) (xy 153.326676 -437.184289)
			(xy 153.33421 -437.207259) (xy 153.33472 -437.219344) (xy 153.33472 -438.76087) (xy 154.240992 -438.76087)
			(xy 154.240992 -436.219346) (xy 154.24155 -436.207238) (xy 154.249019 -436.184204) (xy 154.26324 -436.164606)
			(xy 154.282822 -436.150361) (xy 154.305847 -436.142865) (xy 154.317954 -436.142384) (xy 155.257754 -436.142384)
			(xy 155.269879 -436.1428) (xy 155.292944 -436.150285) (xy 155.306895 -436.160418) (xy 156.240988 -436.160418)
			(xy 156.240988 -435.43347) (xy 156.241307 -435.4247) (xy 156.24541 -435.407642) (xy 156.249116 -435.399688)
			(xy 156.249116 -435.39918) (xy 156.482542 -434.923184) (xy 156.48724 -434.912667) (xy 156.490729 -434.889909)
			(xy 156.487246 -434.867151) (xy 156.482542 -434.856636) (xy 156.249116 -434.38064) (xy 156.249116 -434.380132)
			(xy 156.245399 -434.372181) (xy 156.241288 -434.355122) (xy 156.240988 -434.34635) (xy 156.240988 -433.618894)
			(xy 156.241506 -433.606784) (xy 156.248989 -433.583749) (xy 156.263221 -433.564152) (xy 156.28281 -433.549909)
			(xy 156.30584 -433.542413) (xy 156.31795 -433.541932) (xy 157.25775 -433.541932) (xy 157.269867 -433.542369)
			(xy 157.29291 -433.549869) (xy 157.312511 -433.564121) (xy 157.326751 -433.583729) (xy 157.334238 -433.606777)
			(xy 157.334712 -433.618894) (xy 157.334712 -436.160418) (xy 157.334205 -436.172529) (xy 157.326718 -436.195564)
			(xy 157.312484 -436.215161) (xy 157.292893 -436.229404) (xy 157.26986 -436.2369) (xy 157.25775 -436.23738)
			(xy 156.31795 -436.23738) (xy 156.305835 -436.236931) (xy 156.282793 -436.229432) (xy 156.263193 -436.215184)
			(xy 156.248953 -436.195578) (xy 156.241464 -436.172534) (xy 156.240988 -436.160418) (xy 155.306895 -436.160418)
			(xy 155.312564 -436.164536) (xy 155.326815 -436.184156) (xy 155.3343 -436.207221) (xy 155.334716 -436.219346)
			(xy 155.334716 -438.76087) (xy 155.334314 -438.772996) (xy 155.326824 -438.796061) (xy 155.31257 -438.815681)
			(xy 155.292947 -438.829932) (xy 155.26988 -438.837416) (xy 155.257754 -438.837832) (xy 154.317954 -438.837832)
			(xy 154.305834 -438.837427) (xy 154.282784 -438.829923) (xy 154.263181 -438.815665) (xy 154.248942 -438.796048)
			(xy 154.241461 -438.77299) (xy 154.240992 -438.76087) (xy 153.33472 -438.76087) (xy 153.33472 -439.760868)
			(xy 156.240988 -439.760868) (xy 156.240988 -437.219344) (xy 156.241497 -437.207297) (xy 156.248916 -437.184375)
			(xy 156.263045 -437.16486) (xy 156.282504 -437.150654) (xy 156.305397 -437.143145) (xy 156.317442 -437.142636)
			(xy 157.25775 -437.142636) (xy 157.269837 -437.14315) (xy 157.292835 -437.150592) (xy 157.312415 -437.164767)
			(xy 157.326668 -437.184291) (xy 157.334202 -437.207259) (xy 157.334712 -437.219344) (xy 157.334712 -438.76087)
			(xy 314.140596 -438.76087) (xy 314.140596 -436.219346) (xy 314.141098 -436.20723) (xy 314.148573 -436.18418)
			(xy 314.162805 -436.164567) (xy 314.182401 -436.150313) (xy 314.205442 -436.142812) (xy 314.217558 -436.142384)
			(xy 315.157358 -436.142384) (xy 315.169483 -436.142796) (xy 315.192548 -436.150283) (xy 315.2065 -436.160418)
			(xy 316.1411 -436.160418) (xy 316.1411 -435.43347) (xy 316.141417 -435.4247) (xy 316.145522 -435.407642)
			(xy 316.149228 -435.399688) (xy 316.149228 -435.39918) (xy 316.382654 -434.923184) (xy 316.387352 -434.912666)
			(xy 316.39084 -434.889909) (xy 316.387357 -434.867151) (xy 316.382654 -434.856636) (xy 316.149228 -434.38064)
			(xy 316.149228 -434.380132) (xy 316.145512 -434.37218) (xy 316.1414 -434.355122) (xy 316.1411 -434.34635)
			(xy 316.1411 -433.618894) (xy 316.141606 -433.606783) (xy 316.14909 -433.583746) (xy 316.163325 -433.564148)
			(xy 316.182917 -433.549905) (xy 316.205951 -433.542411) (xy 316.218062 -433.541932) (xy 317.157862 -433.541932)
			(xy 317.169982 -433.542392) (xy 317.193039 -433.549873) (xy 317.212654 -433.564115) (xy 317.226907 -433.583722)
			(xy 317.234401 -433.606774) (xy 317.234824 -433.618894) (xy 317.234824 -435.16042) (xy 318.141096 -435.16042)
			(xy 318.141096 -434.433472) (xy 318.141414 -434.424702) (xy 318.145518 -434.407644) (xy 318.149224 -434.39969)
			(xy 318.149224 -434.399182) (xy 318.38265 -433.923186) (xy 318.387347 -433.912668) (xy 318.390835 -433.889911)
			(xy 318.387353 -433.867153) (xy 318.38265 -433.856638) (xy 318.149224 -433.380642) (xy 318.149224 -433.380134)
			(xy 318.145508 -433.372182) (xy 318.141396 -433.355124) (xy 318.141096 -433.346352) (xy 318.141096 -432.618896)
			(xy 318.141557 -432.606846) (xy 318.14899 -432.583921) (xy 318.163131 -432.564406) (xy 318.182601 -432.550202)
			(xy 318.205502 -432.542696) (xy 318.21755 -432.542188) (xy 319.157858 -432.542188) (xy 319.16995 -432.542644)
			(xy 319.192958 -432.550095) (xy 319.207287 -432.560476) (xy 320.141092 -432.560476) (xy 320.141092 -431.833274)
			(xy 320.141344 -431.824517) (xy 320.145323 -431.807459) (xy 320.148966 -431.799492) (xy 320.382392 -431.323242)
			(xy 320.387122 -431.312737) (xy 320.390603 -431.289971) (xy 320.387105 -431.267208) (xy 320.382392 -431.256694)
			(xy 320.148966 -430.780444) (xy 320.145315 -430.772478) (xy 320.141333 -430.755421) (xy 320.141092 -430.746662)
			(xy 320.141092 -430.018952) (xy 320.141523 -430.006875) (xy 320.148999 -429.983906) (xy 320.163204 -429.96437)
			(xy 320.182749 -429.950177) (xy 320.205723 -429.942716) (xy 320.2178 -429.942244) (xy 321.1576 -429.942244)
			(xy 321.16967 -429.942764) (xy 321.192629 -429.95022) (xy 321.212162 -429.964404) (xy 321.226358 -429.983928)
			(xy 321.233829 -430.006883) (xy 321.234308 -430.018952) (xy 321.234308 -431.560478) (xy 322.141088 -431.560478)
			(xy 322.141088 -430.833276) (xy 322.141341 -430.824519) (xy 322.145319 -430.807462) (xy 322.148962 -430.799494)
			(xy 322.382388 -430.323244) (xy 322.387117 -430.312738) (xy 322.390598 -430.289973) (xy 322.3871 -430.26721)
			(xy 322.382388 -430.256696) (xy 322.148962 -429.780446) (xy 322.145312 -429.77248) (xy 322.141329 -429.755422)
			(xy 322.141088 -429.746664) (xy 322.141088 -429.018954) (xy 322.141469 -429.006857) (xy 322.148944 -428.983847)
			(xy 322.163151 -428.964264) (xy 322.182705 -428.950016) (xy 322.2057 -428.942494) (xy 322.217796 -428.941992)
			(xy 323.157596 -428.941992) (xy 323.169704 -428.942419) (xy 323.19273 -428.949917) (xy 323.207303 -428.960534)
			(xy 324.141084 -428.960534) (xy 324.141084 -426.41901) (xy 324.141469 -426.406883) (xy 324.148964 -426.383817)
			(xy 324.163223 -426.364198) (xy 324.182849 -426.349948) (xy 324.205919 -426.342464) (xy 324.218046 -426.342048)
			(xy 325.157846 -426.342048) (xy 325.169964 -426.342473) (xy 325.19301 -426.349974) (xy 325.212612 -426.364228)
			(xy 325.226852 -426.38384) (xy 325.234336 -426.406892) (xy 325.234808 -426.41901) (xy 325.234808 -427.960536)
			(xy 326.14108 -427.960536) (xy 326.14108 -425.419012) (xy 326.14157 -425.406964) (xy 326.148997 -425.384043)
			(xy 326.163131 -425.364528) (xy 326.182593 -425.350324) (xy 326.205488 -425.342814) (xy 326.217534 -425.342304)
			(xy 327.157842 -425.342304) (xy 327.16993 -425.342771) (xy 327.192926 -425.350235) (xy 327.212502 -425.364423)
			(xy 327.226753 -425.383953) (xy 327.23429 -425.406925) (xy 327.234804 -425.419012) (xy 327.234804 -427.960536)
			(xy 327.234371 -427.972588) (xy 327.226929 -427.995514) (xy 327.212781 -428.015029) (xy 327.193306 -428.029231)
			(xy 327.1704 -428.036737) (xy 327.15835 -428.037244) (xy 326.218042 -428.037244) (xy 326.205953 -428.036757)
			(xy 326.182951 -428.029309) (xy 326.163369 -428.015129) (xy 326.149118 -427.995598) (xy 326.141587 -427.972623)
			(xy 326.14108 -427.960536) (xy 325.234808 -427.960536) (xy 325.234808 -428.960534) (xy 325.234318 -428.972646)
			(xy 325.226827 -428.995682) (xy 325.212588 -429.01528) (xy 325.192993 -429.029522) (xy 325.169958 -429.037016)
			(xy 325.157846 -429.037496) (xy 324.218046 -429.037496) (xy 324.205929 -429.037002) (xy 324.182877 -429.029526)
			(xy 324.163264 -429.015292) (xy 324.149011 -428.995694) (xy 324.141511 -428.972651) (xy 324.141084 -428.960534)
			(xy 323.207303 -428.960534) (xy 323.212302 -428.964176) (xy 323.226497 -428.983795) (xy 323.23392 -429.006845)
			(xy 323.234304 -429.018954) (xy 323.234304 -431.560478) (xy 323.233775 -431.572562) (xy 323.226329 -431.595555)
			(xy 323.212157 -431.615131) (xy 323.19264 -431.629384) (xy 323.169678 -431.636924) (xy 323.157596 -431.63744)
			(xy 322.217796 -431.63744) (xy 322.205691 -431.636988) (xy 322.18267 -431.629492) (xy 322.163101 -431.615238)
			(xy 322.148905 -431.595627) (xy 322.141477 -431.572584) (xy 322.141088 -431.560478) (xy 321.234308 -431.560478)
			(xy 321.234308 -432.560476) (xy 321.233867 -432.572557) (xy 321.226406 -432.595539) (xy 321.212207 -432.61509)
			(xy 321.192661 -432.629295) (xy 321.169681 -432.636763) (xy 321.1576 -432.637184) (xy 320.2178 -432.637184)
			(xy 320.205715 -432.636787) (xy 320.182728 -432.629317) (xy 320.163176 -432.615107) (xy 320.148972 -432.59555)
			(xy 320.141509 -432.572561) (xy 320.141092 -432.560476) (xy 319.207287 -432.560476) (xy 319.212542 -432.564283)
			(xy 319.226793 -432.583822) (xy 319.234317 -432.606805) (xy 319.23482 -432.618896) (xy 319.23482 -435.16042)
			(xy 319.234357 -435.172469) (xy 319.226921 -435.195392) (xy 319.212781 -435.214906) (xy 319.193312 -435.229109)
			(xy 319.170414 -435.236618) (xy 319.158366 -435.237128) (xy 318.218058 -435.237128) (xy 318.205963 -435.236728)
			(xy 318.182956 -435.229256) (xy 318.163374 -435.215053) (xy 318.149126 -435.195504) (xy 318.1416 -435.172514)
			(xy 318.141096 -435.16042) (xy 317.234824 -435.16042) (xy 317.234824 -436.160418) (xy 317.234455 -436.172545)
			(xy 317.226953 -436.195611) (xy 317.212689 -436.215229) (xy 317.193061 -436.229478) (xy 317.16999 -436.236963)
			(xy 317.157862 -436.23738) (xy 316.218062 -436.23738) (xy 316.205947 -436.236921) (xy 316.182906 -436.229425)
			(xy 316.163306 -436.21518) (xy 316.149065 -436.195576) (xy 316.141576 -436.172533) (xy 316.1411 -436.160418)
			(xy 315.2065 -436.160418) (xy 315.212168 -436.164535) (xy 315.226419 -436.184155) (xy 315.233904 -436.207221)
			(xy 315.23432 -436.219346) (xy 315.23432 -438.76087) (xy 315.233914 -438.772995) (xy 315.226425 -438.79606)
			(xy 315.212171 -438.81568) (xy 315.19255 -438.82993) (xy 315.169483 -438.837416) (xy 315.157358 -438.837832)
			(xy 314.217558 -438.837832) (xy 314.205438 -438.837424) (xy 314.182389 -438.829921) (xy 314.162785 -438.815664)
			(xy 314.148546 -438.796047) (xy 314.141065 -438.77299) (xy 314.140596 -438.76087) (xy 157.334712 -438.76087)
			(xy 157.334712 -439.760868) (xy 316.140592 -439.760868) (xy 316.140592 -437.219344) (xy 316.141097 -437.207297)
			(xy 316.148517 -437.184374) (xy 316.162646 -437.164858) (xy 316.182107 -437.150653) (xy 316.205001 -437.143144)
			(xy 316.217046 -437.142636) (xy 317.157354 -437.142636) (xy 317.169441 -437.143146) (xy 317.192439 -437.15059)
			(xy 317.21202 -437.164765) (xy 317.226272 -437.18429) (xy 317.233806 -437.207259) (xy 317.234316 -437.219344)
			(xy 317.234316 -438.76087) (xy 318.140588 -438.76087) (xy 318.140588 -436.219346) (xy 318.14115 -436.207239)
			(xy 318.148619 -436.184205) (xy 318.162839 -436.164607) (xy 318.182419 -436.150362) (xy 318.205443 -436.142865)
			(xy 318.21755 -436.142384) (xy 319.15735 -436.142384) (xy 319.169472 -436.14277) (xy 319.192524 -436.150276)
			(xy 319.206465 -436.160418) (xy 320.141092 -436.160418) (xy 320.141092 -435.43347) (xy 320.14141 -435.4247)
			(xy 320.145514 -435.407642) (xy 320.14922 -435.399688) (xy 320.14922 -435.39918) (xy 320.382646 -434.923184)
			(xy 320.387344 -434.912667) (xy 320.390833 -434.889909) (xy 320.38735 -434.867151) (xy 320.382646 -434.856636)
			(xy 320.14922 -434.38064) (xy 320.14922 -434.380132) (xy 320.145503 -434.37218) (xy 320.141392 -434.355122)
			(xy 320.141092 -434.34635) (xy 320.141092 -433.618894) (xy 320.141606 -433.606784) (xy 320.149089 -433.583748)
			(xy 320.163322 -433.564151) (xy 320.182912 -433.549908) (xy 320.205944 -433.542412) (xy 320.218054 -433.541932)
			(xy 321.157854 -433.541932) (xy 321.169974 -433.542399) (xy 321.19303 -433.549878) (xy 321.212646 -433.564117)
			(xy 321.226898 -433.583723) (xy 321.234393 -433.606775) (xy 321.234816 -433.618894) (xy 321.234816 -435.16042)
			(xy 322.141088 -435.16042) (xy 322.141088 -434.433472) (xy 322.141407 -434.424702) (xy 322.14551 -434.407645)
			(xy 322.149216 -434.39969) (xy 322.149216 -434.399182) (xy 322.382642 -433.923186) (xy 322.387339 -433.912668)
			(xy 322.390828 -433.889911) (xy 322.387346 -433.867153) (xy 322.382642 -433.856638) (xy 322.149216 -433.380642)
			(xy 322.149216 -433.380134) (xy 322.145499 -433.372182) (xy 322.141388 -433.355124) (xy 322.141088 -433.346352)
			(xy 322.141088 -432.618896) (xy 322.141556 -432.606847) (xy 322.148989 -432.583923) (xy 322.163128 -432.564409)
			(xy 322.182596 -432.550205) (xy 322.205494 -432.542697) (xy 322.217542 -432.542188) (xy 323.15785 -432.542188)
			(xy 323.169942 -432.542651) (xy 323.192949 -432.5501) (xy 323.207275 -432.560476) (xy 324.141084 -432.560476)
			(xy 324.141084 -431.833274) (xy 324.141337 -431.824517) (xy 324.145315 -431.80746) (xy 324.148958 -431.799492)
			(xy 324.382384 -431.323242) (xy 324.387114 -431.312737) (xy 324.390595 -431.289971) (xy 324.387097 -431.267208)
			(xy 324.382384 -431.256694) (xy 324.148958 -430.780444) (xy 324.145307 -430.772479) (xy 324.141324 -430.755421)
			(xy 324.141084 -430.746662) (xy 324.141084 -430.018952) (xy 324.141523 -430.006876) (xy 324.148998 -429.983908)
			(xy 324.163201 -429.964373) (xy 324.182744 -429.95018) (xy 324.205715 -429.942717) (xy 324.217792 -429.942244)
			(xy 325.157592 -429.942244) (xy 325.169661 -429.94277) (xy 325.19262 -429.950225) (xy 325.212153 -429.964407)
			(xy 325.22635 -429.98393) (xy 325.233821 -430.006883) (xy 325.2343 -430.018952) (xy 325.2343 -431.560478)
			(xy 326.14108 -431.560478) (xy 326.14108 -430.833276) (xy 326.141334 -430.824519) (xy 326.145312 -430.807462)
			(xy 326.148954 -430.799494) (xy 326.38238 -430.323244) (xy 326.387109 -430.312738) (xy 326.390591 -430.289973)
			(xy 326.387093 -430.26721) (xy 326.38238 -430.256696) (xy 326.148954 -429.780446) (xy 326.145303 -429.77248)
			(xy 326.141321 -429.755423) (xy 326.14108 -429.746664) (xy 326.14108 -429.018954) (xy 326.141469 -429.006858)
			(xy 326.148943 -428.983849) (xy 326.163148 -428.964267) (xy 326.1827 -428.950019) (xy 326.205693 -428.942495)
			(xy 326.217788 -428.941992) (xy 327.157588 -428.941992) (xy 327.169695 -428.942427) (xy 327.192721 -428.949922)
			(xy 327.207289 -428.960534) (xy 328.141076 -428.960534) (xy 328.141076 -426.41901) (xy 328.141469 -426.406884)
			(xy 328.148963 -426.383819) (xy 328.16322 -426.364201) (xy 328.182844 -426.34995) (xy 328.205912 -426.342465)
			(xy 328.218038 -426.342048) (xy 329.157838 -426.342048) (xy 329.169956 -426.342479) (xy 329.193002 -426.349978)
			(xy 329.212604 -426.36423) (xy 329.226844 -426.383841) (xy 329.234328 -426.406892) (xy 329.2348 -426.41901)
			(xy 329.2348 -427.960536) (xy 331.141324 -427.960536) (xy 331.141324 -425.419012) (xy 331.141724 -425.406927)
			(xy 331.149192 -425.383939) (xy 331.1634 -425.364386) (xy 331.182957 -425.350183) (xy 331.205947 -425.34272)
			(xy 331.218032 -425.342304) (xy 332.157832 -425.342304) (xy 332.169909 -425.342737) (xy 332.19288 -425.35021)
			(xy 332.212417 -425.364414) (xy 332.22661 -425.38396) (xy 332.23407 -425.406934) (xy 332.23454 -425.419012)
			(xy 332.23454 -427.960536) (xy 332.234067 -427.972609) (xy 332.226599 -427.995572) (xy 332.212403 -428.015106)
			(xy 332.192869 -428.0293) (xy 332.169905 -428.036768) (xy 332.157832 -428.037244) (xy 331.218032 -428.037244)
			(xy 331.205963 -428.036709) (xy 331.183003 -428.02926) (xy 331.163468 -428.01508) (xy 331.149271 -427.995558)
			(xy 331.141801 -427.972605) (xy 331.141324 -427.960536) (xy 329.2348 -427.960536) (xy 329.2348 -428.960534)
			(xy 329.234318 -428.972647) (xy 329.226826 -428.995684) (xy 329.212585 -429.015282) (xy 329.192988 -429.029524)
			(xy 329.169951 -429.037017) (xy 329.157838 -429.037496) (xy 328.218038 -429.037496) (xy 328.205921 -429.037008)
			(xy 328.182869 -429.029531) (xy 328.163256 -429.015295) (xy 328.149002 -428.995696) (xy 328.141503 -428.972651)
			(xy 328.141076 -428.960534) (xy 327.207289 -428.960534) (xy 327.212293 -428.964179) (xy 327.226489 -428.983796)
			(xy 327.233911 -429.006845) (xy 327.234296 -429.018954) (xy 327.234296 -431.560478) (xy 327.233775 -431.572563)
			(xy 327.226328 -431.595557) (xy 327.212154 -431.615134) (xy 327.192634 -431.629386) (xy 327.169671 -431.636925)
			(xy 327.157588 -431.63744) (xy 326.217788 -431.63744) (xy 326.205682 -431.636995) (xy 326.182662 -431.629497)
			(xy 326.163092 -431.615241) (xy 326.148896 -431.595628) (xy 326.141469 -431.572585) (xy 326.14108 -431.560478)
			(xy 325.2343 -431.560478) (xy 325.2343 -432.560476) (xy 325.233867 -432.572558) (xy 325.226405 -432.595542)
			(xy 325.212204 -432.615093) (xy 325.192656 -432.629297) (xy 325.169674 -432.636764) (xy 325.157592 -432.637184)
			(xy 324.217792 -432.637184) (xy 324.205706 -432.636794) (xy 324.182719 -432.629321) (xy 324.163167 -432.61511)
			(xy 324.148964 -432.595552) (xy 324.141501 -432.572562) (xy 324.141084 -432.560476) (xy 323.207275 -432.560476)
			(xy 323.212534 -432.564285) (xy 323.226784 -432.583823) (xy 323.234309 -432.606806) (xy 323.234812 -432.618896)
			(xy 323.234812 -435.16042) (xy 323.234357 -435.17247) (xy 323.22692 -435.195394) (xy 323.212778 -435.214908)
			(xy 323.193307 -435.229111) (xy 323.170406 -435.236619) (xy 323.158358 -435.237128) (xy 322.21805 -435.237128)
			(xy 322.20596 -435.23665) (xy 322.182955 -435.229203) (xy 322.163372 -435.21502) (xy 322.149121 -435.195487)
			(xy 322.141593 -435.172508) (xy 322.141088 -435.16042) (xy 321.234816 -435.16042) (xy 321.234816 -436.160418)
			(xy 321.234454 -436.172546) (xy 321.226952 -436.195613) (xy 321.212686 -436.215232) (xy 321.193056 -436.229481)
			(xy 321.169983 -436.236965) (xy 321.157854 -436.23738) (xy 320.218054 -436.23738) (xy 320.205939 -436.236928)
			(xy 320.182897 -436.22943) (xy 320.163298 -436.215182) (xy 320.149057 -436.195578) (xy 320.141568 -436.172533)
			(xy 320.141092 -436.160418) (xy 319.206465 -436.160418) (xy 319.212129 -436.164539) (xy 319.226367 -436.184162)
			(xy 319.233845 -436.207224) (xy 319.234312 -436.219346) (xy 319.234312 -438.76087) (xy 319.233763 -438.772978)
			(xy 319.226291 -438.796012) (xy 319.212067 -438.81561) (xy 319.192484 -438.829854) (xy 319.169458 -438.837351)
			(xy 319.15735 -438.837832) (xy 318.21755 -438.837832) (xy 318.20543 -438.83743) (xy 318.18238 -438.829926)
			(xy 318.162776 -438.815667) (xy 318.148538 -438.796048) (xy 318.141057 -438.772991) (xy 318.140588 -438.76087)
			(xy 317.234316 -438.76087) (xy 317.234316 -439.760868) (xy 320.140584 -439.760868) (xy 320.140584 -437.219344)
			(xy 320.141097 -437.207298) (xy 320.148516 -437.184376) (xy 320.162643 -437.164861) (xy 320.182102 -437.150656)
			(xy 320.204994 -437.143145) (xy 320.217038 -437.142636) (xy 321.157346 -437.142636) (xy 321.169438 -437.143068)
			(xy 321.192439 -437.150537) (xy 321.212018 -437.164733) (xy 321.226267 -437.184273) (xy 321.233799 -437.207254)
			(xy 321.234308 -437.219344) (xy 321.234308 -438.76087) (xy 322.14058 -438.76087) (xy 322.14058 -436.219346)
			(xy 322.141 -436.207221) (xy 322.148484 -436.184157) (xy 322.162735 -436.164537) (xy 322.182353 -436.150286)
			(xy 322.205417 -436.1428) (xy 322.217542 -436.142384) (xy 323.157342 -436.142384) (xy 323.169472 -436.142725)
			(xy 323.19254 -436.150234) (xy 323.212158 -436.164505) (xy 323.226406 -436.184139) (xy 323.233889 -436.207216)
			(xy 323.234304 -436.219346) (xy 323.234304 -436.724694) (xy 324.069317 -436.724694) (xy 324.069322 -436.654824)
			(xy 324.07771 -436.585459) (xy 324.094358 -436.517602) (xy 324.119028 -436.452232) (xy 324.134734 -436.421022)
			(xy 324.137407 -436.41555) (xy 324.140365 -436.40374) (xy 324.140576 -436.397654) (xy 324.140576 -436.019448)
			(xy 324.141084 -436.01259) (xy 324.141084 -435.43347) (xy 324.141403 -435.4247) (xy 324.145506 -435.407643)
			(xy 324.149212 -435.399688) (xy 324.149212 -435.39918) (xy 324.382638 -434.923184) (xy 324.387337 -434.912667)
			(xy 324.390826 -434.889909) (xy 324.387342 -434.867151) (xy 324.382638 -434.856636) (xy 324.149212 -434.38064)
			(xy 324.149212 -434.380132) (xy 324.145495 -434.372181) (xy 324.141384 -434.355122) (xy 324.141084 -434.34635)
			(xy 324.141084 -433.618894) (xy 324.141456 -433.606766) (xy 324.148955 -433.5837) (xy 324.163218 -433.564081)
			(xy 324.182846 -433.549831) (xy 324.205918 -433.542348) (xy 324.218046 -433.541932) (xy 325.157846 -433.541932)
			(xy 325.169962 -433.542372) (xy 325.193006 -433.549872) (xy 325.212607 -433.564122) (xy 325.226847 -433.58373)
			(xy 325.234334 -433.606777) (xy 325.234808 -433.618894) (xy 325.234808 -435.16042) (xy 326.14108 -435.16042)
			(xy 326.14108 -434.433472) (xy 326.1414 -434.424702) (xy 326.145503 -434.407645) (xy 326.149208 -434.39969)
			(xy 326.149208 -434.399182) (xy 326.382634 -433.923186) (xy 326.387331 -433.912668) (xy 326.390821 -433.889911)
			(xy 326.387338 -433.867153) (xy 326.382634 -433.856638) (xy 326.149208 -433.380642) (xy 326.149208 -433.380134)
			(xy 326.145491 -433.372183) (xy 326.141379 -433.355124) (xy 326.14108 -433.346352) (xy 326.14108 -432.618896)
			(xy 326.141556 -432.606848) (xy 326.148988 -432.583925) (xy 326.163125 -432.564411) (xy 326.182591 -432.550208)
			(xy 326.205487 -432.542698) (xy 326.217534 -432.542188) (xy 327.157842 -432.542188) (xy 327.169939 -432.542572)
			(xy 327.192949 -432.550047) (xy 327.207325 -432.560476) (xy 328.141076 -432.560476) (xy 328.141076 -431.833274)
			(xy 328.141329 -431.824517) (xy 328.145308 -431.80746) (xy 328.14895 -431.799492) (xy 328.382376 -431.323242)
			(xy 328.387107 -431.312737) (xy 328.390588 -431.289971) (xy 328.387089 -431.267208) (xy 328.382376 -431.256694)
			(xy 328.14895 -430.780444) (xy 328.145299 -430.772479) (xy 328.141316 -430.755421) (xy 328.141076 -430.746662)
			(xy 328.141076 -430.018952) (xy 328.141523 -430.006877) (xy 328.148997 -429.98391) (xy 328.163198 -429.964376)
			(xy 328.182739 -429.950182) (xy 328.205708 -429.942718) (xy 328.217784 -429.942244) (xy 329.157584 -429.942244)
			(xy 329.169653 -429.942777) (xy 329.192612 -429.950229) (xy 329.212145 -429.96441) (xy 329.226341 -429.983931)
			(xy 329.233813 -430.006883) (xy 329.234292 -430.018952) (xy 329.234292 -431.560478) (xy 331.141324 -431.560478)
			(xy 331.141324 -430.833276) (xy 331.141573 -430.824519) (xy 331.145554 -430.807461) (xy 331.149198 -430.799494)
			(xy 331.382624 -430.323244) (xy 331.387351 -430.312738) (xy 331.390831 -430.289973) (xy 331.387335 -430.267211)
			(xy 331.382624 -430.256696) (xy 331.149198 -429.780446) (xy 331.14555 -429.772479) (xy 331.141565 -429.755422)
			(xy 331.141324 -429.746664) (xy 331.141324 -429.018954) (xy 331.141768 -429.006864) (xy 331.149235 -428.983864)
			(xy 331.163428 -428.964286) (xy 331.182965 -428.950037) (xy 331.205943 -428.942503) (xy 331.218032 -428.941992)
			(xy 332.157832 -428.941992) (xy 332.169942 -428.942389) (xy 332.192969 -428.949896) (xy 332.207563 -428.960534)
			(xy 333.14132 -428.960534) (xy 333.14132 -426.41901) (xy 333.141816 -426.406923) (xy 333.149267 -426.383926)
			(xy 333.163447 -426.364348) (xy 333.182973 -426.350096) (xy 333.205943 -426.34256) (xy 333.218028 -426.342048)
			(xy 334.157828 -426.342048) (xy 334.169933 -426.342492) (xy 334.192952 -426.349993) (xy 334.212521 -426.364249)
			(xy 334.226716 -426.383861) (xy 334.234145 -426.406904) (xy 334.234536 -426.41901) (xy 334.234536 -427.960536)
			(xy 335.141316 -427.960536) (xy 335.141316 -425.419012) (xy 335.141723 -425.406928) (xy 335.149191 -425.383941)
			(xy 335.163397 -425.364389) (xy 335.182952 -425.350185) (xy 335.205939 -425.342722) (xy 335.218024 -425.342304)
			(xy 336.157824 -425.342304) (xy 336.169901 -425.342744) (xy 336.192871 -425.350215) (xy 336.212409 -425.364417)
			(xy 336.226602 -425.383961) (xy 336.234061 -425.406935) (xy 336.234532 -425.419012) (xy 336.234532 -427.960536)
			(xy 336.234067 -427.97261) (xy 336.226598 -427.995574) (xy 336.2124 -428.015109) (xy 336.192864 -428.029303)
			(xy 336.169898 -428.036769) (xy 336.157824 -428.037244) (xy 335.218024 -428.037244) (xy 335.205954 -428.036716)
			(xy 335.182994 -428.029264) (xy 335.16346 -428.015083) (xy 335.149263 -427.99556) (xy 335.141793 -427.972605)
			(xy 335.141316 -427.960536) (xy 334.234536 -427.960536) (xy 334.234536 -428.960534) (xy 334.234121 -428.972628)
			(xy 334.226652 -428.995634) (xy 334.212453 -429.015215) (xy 334.192907 -429.029464) (xy 334.16992 -429.03699)
			(xy 334.157828 -429.037496) (xy 333.218028 -429.037496) (xy 333.20592 -429.03706) (xy 333.182893 -429.029567)
			(xy 333.163319 -429.015311) (xy 333.149124 -428.995693) (xy 333.141703 -428.972643) (xy 333.14132 -428.960534)
			(xy 332.207563 -428.960534) (xy 332.212541 -428.964163) (xy 332.226734 -428.983788) (xy 332.234156 -429.006843)
			(xy 332.23454 -429.018954) (xy 332.23454 -431.560478) (xy 332.234073 -431.572568) (xy 332.22662 -431.595572)
			(xy 332.212434 -431.615154) (xy 332.192899 -431.629404) (xy 332.169921 -431.636933) (xy 332.157832 -431.63744)
			(xy 331.218032 -431.63744) (xy 331.205929 -431.636957) (xy 331.182909 -431.629471) (xy 331.163339 -431.615225)
			(xy 331.149142 -431.59562) (xy 331.141713 -431.572582) (xy 331.141324 -431.560478) (xy 329.234292 -431.560478)
			(xy 329.234292 -432.560476) (xy 329.233867 -432.572559) (xy 329.226404 -432.595544) (xy 329.212201 -432.615096)
			(xy 329.192651 -432.6293) (xy 329.169667 -432.636765) (xy 329.157584 -432.637184) (xy 328.217784 -432.637184)
			(xy 328.205698 -432.636801) (xy 328.182711 -432.629326) (xy 328.163159 -432.615113) (xy 328.148956 -432.595553)
			(xy 328.141493 -432.572562) (xy 328.141076 -432.560476) (xy 327.207325 -432.560476) (xy 327.212532 -432.564253)
			(xy 327.226779 -432.583806) (xy 327.234302 -432.606801) (xy 327.234804 -432.618896) (xy 327.234804 -435.16042)
			(xy 327.234357 -435.172471) (xy 327.226919 -435.195396) (xy 327.212775 -435.214911) (xy 327.193302 -435.229114)
			(xy 327.170399 -435.23662) (xy 327.15835 -435.237128) (xy 326.218042 -435.237128) (xy 326.205951 -435.236656)
			(xy 326.182947 -435.229207) (xy 326.163363 -435.215023) (xy 326.149113 -435.195488) (xy 326.141585 -435.172509)
			(xy 326.14108 -435.16042) (xy 325.234808 -435.16042) (xy 325.234808 -436.160418) (xy 325.2343 -436.167276)
			(xy 325.2343 -438.76087) (xy 326.140572 -438.76087) (xy 326.140572 -436.219346) (xy 326.141 -436.207222)
			(xy 326.148483 -436.184159) (xy 326.162732 -436.16454) (xy 326.182348 -436.150289) (xy 326.20541 -436.142801)
			(xy 326.217534 -436.142384) (xy 327.157334 -436.142384) (xy 327.169463 -436.142732) (xy 327.192531 -436.150239)
			(xy 327.206526 -436.160418) (xy 328.141076 -436.160418) (xy 328.141076 -435.43347) (xy 328.141396 -435.4247)
			(xy 328.145499 -435.407643) (xy 328.149204 -435.399688) (xy 328.149204 -435.39918) (xy 328.38263 -434.923184)
			(xy 328.387329 -434.912667) (xy 328.390818 -434.889909) (xy 328.387334 -434.86715) (xy 328.38263 -434.856636)
			(xy 328.149204 -434.38064) (xy 328.149204 -434.380132) (xy 328.145486 -434.372181) (xy 328.141375 -434.355122)
			(xy 328.141076 -434.34635) (xy 328.141076 -433.618894) (xy 328.141456 -433.606767) (xy 328.148954 -433.583702)
			(xy 328.163215 -433.564084) (xy 328.182841 -433.549834) (xy 328.205911 -433.542349) (xy 328.218038 -433.541932)
			(xy 329.157838 -433.541932) (xy 329.169954 -433.542379) (xy 329.192997 -433.549876) (xy 329.212598 -433.564125)
			(xy 329.226838 -433.583731) (xy 329.234326 -433.606778) (xy 329.2348 -433.618894) (xy 329.2348 -435.16042)
			(xy 331.141324 -435.16042) (xy 331.141324 -434.433218) (xy 331.141587 -434.424462) (xy 331.145558 -434.407404)
			(xy 331.149198 -434.399436) (xy 331.382624 -433.923186) (xy 331.387322 -433.912668) (xy 331.390812 -433.889911)
			(xy 331.387329 -433.867152) (xy 331.382624 -433.856638) (xy 331.149198 -433.380388) (xy 331.145532 -433.372429)
			(xy 331.141558 -433.355366) (xy 331.141324 -433.346606) (xy 331.141324 -432.618896) (xy 331.14171 -432.60681)
			(xy 331.149182 -432.583822) (xy 331.163394 -432.564268) (xy 331.182954 -432.550066) (xy 331.205946 -432.542604)
			(xy 331.218032 -432.542188) (xy 332.157832 -432.542188) (xy 332.169908 -432.542637) (xy 332.192875 -432.550108)
			(xy 332.20714 -432.560476) (xy 333.14132 -432.560476) (xy 333.14132 -431.833274) (xy 333.141569 -431.824517)
			(xy 333.14555 -431.807459) (xy 333.149194 -431.799492) (xy 333.38262 -431.323242) (xy 333.387349 -431.312736)
			(xy 333.390828 -431.289971) (xy 333.387331 -431.267209) (xy 333.38262 -431.256694) (xy 333.149194 -430.780444)
			(xy 333.145545 -430.772478) (xy 333.141561 -430.75542) (xy 333.14132 -430.746662) (xy 333.14132 -430.018952)
			(xy 333.141724 -430.006872) (xy 333.149203 -429.983899) (xy 333.163414 -429.96436) (xy 333.182967 -429.950168)
			(xy 333.205948 -429.942712) (xy 333.218028 -429.942244) (xy 334.157828 -429.942244) (xy 334.169899 -429.942739)
			(xy 334.192859 -429.950204) (xy 334.212392 -429.964394) (xy 334.226587 -429.983923) (xy 334.234058 -430.006881)
			(xy 334.234536 -430.018952) (xy 334.234536 -431.560478) (xy 335.141316 -431.560478) (xy 335.141316 -430.833276)
			(xy 335.141566 -430.824519) (xy 335.145546 -430.807461) (xy 335.14919 -430.799494) (xy 335.382616 -430.323244)
			(xy 335.387343 -430.312738) (xy 335.390823 -430.289973) (xy 335.387327 -430.267211) (xy 335.382616 -430.256696)
			(xy 335.14919 -429.780446) (xy 335.145541 -429.77248) (xy 335.141557 -429.755422) (xy 335.141316 -429.746664)
			(xy 335.141316 -429.018954) (xy 335.141768 -429.006864) (xy 335.149234 -428.983866) (xy 335.163426 -428.964289)
			(xy 335.18296 -428.950039) (xy 335.205936 -428.942504) (xy 335.218024 -428.941992) (xy 336.157824 -428.941992)
			(xy 336.169933 -428.942396) (xy 336.19296 -428.949901) (xy 336.207549 -428.960534) (xy 337.141312 -428.960534)
			(xy 337.141312 -426.41901) (xy 337.141815 -426.406924) (xy 337.149266 -426.383928) (xy 337.163444 -426.364351)
			(xy 337.182968 -426.350099) (xy 337.205936 -426.342562) (xy 337.21802 -426.342048) (xy 338.15782 -426.342048)
			(xy 338.169925 -426.342499) (xy 338.192944 -426.349997) (xy 338.212512 -426.364252) (xy 338.226708 -426.383863)
			(xy 338.234137 -426.406904) (xy 338.234528 -426.41901) (xy 338.234528 -427.960536) (xy 339.141308 -427.960536)
			(xy 339.141308 -425.419012) (xy 339.141723 -425.406928) (xy 339.149189 -425.383943) (xy 339.163394 -425.364392)
			(xy 339.182947 -425.350188) (xy 339.205932 -425.342723) (xy 339.218016 -425.342304) (xy 340.157816 -425.342304)
			(xy 340.169893 -425.342751) (xy 340.192862 -425.350219) (xy 340.2124 -425.36442) (xy 340.226594 -425.383963)
			(xy 340.234053 -425.406935) (xy 340.234524 -425.419012) (xy 340.234524 -427.960536) (xy 340.234067 -427.972611)
			(xy 340.226596 -427.995577) (xy 340.212397 -428.015112) (xy 340.192859 -428.029306) (xy 340.169891 -428.03677)
			(xy 340.157816 -428.037244) (xy 339.218016 -428.037244) (xy 339.205946 -428.036723) (xy 339.182985 -428.029269)
			(xy 339.163451 -428.015086) (xy 339.149255 -427.995561) (xy 339.141785 -427.972606) (xy 339.141308 -427.960536)
			(xy 338.234528 -427.960536) (xy 338.234528 -428.960534) (xy 338.234121 -428.972629) (xy 338.226651 -428.995636)
			(xy 338.21245 -429.015218) (xy 338.192902 -429.029466) (xy 338.169913 -429.036992) (xy 338.15782 -429.037496)
			(xy 337.21802 -429.037496) (xy 337.205912 -429.037066) (xy 337.182885 -429.029572) (xy 337.163311 -429.015314)
			(xy 337.149116 -428.995695) (xy 337.141695 -428.972643) (xy 337.141312 -428.960534) (xy 336.207549 -428.960534)
			(xy 336.212532 -428.964166) (xy 336.226726 -428.983789) (xy 336.234148 -429.006843) (xy 336.234532 -429.018954)
			(xy 336.234532 -431.560478) (xy 336.234073 -431.572569) (xy 336.226619 -431.595574) (xy 336.212432 -431.615156)
			(xy 336.192894 -431.629407) (xy 336.169914 -431.636934) (xy 336.157824 -431.63744) (xy 335.218024 -431.63744)
			(xy 335.20592 -431.636964) (xy 335.182901 -431.629476) (xy 335.163331 -431.615228) (xy 335.149134 -431.595622)
			(xy 335.141705 -431.572583) (xy 335.141316 -431.560478) (xy 334.234536 -431.560478) (xy 334.234536 -432.560476)
			(xy 334.234016 -432.572547) (xy 334.226563 -432.595508) (xy 334.21238 -432.615043) (xy 334.192855 -432.62924)
			(xy 334.169898 -432.636708) (xy 334.157828 -432.637184) (xy 333.218028 -432.637184) (xy 333.205944 -432.636763)
			(xy 333.182959 -432.6293) (xy 333.163406 -432.615097) (xy 333.149202 -432.595545) (xy 333.141738 -432.57256)
			(xy 333.14132 -432.560476) (xy 332.20714 -432.560476) (xy 332.212412 -432.564308) (xy 332.226605 -432.58385)
			(xy 332.234068 -432.60682) (xy 332.23454 -432.618896) (xy 332.23454 -435.16042) (xy 332.234053 -435.172492)
			(xy 332.226589 -435.195455) (xy 332.212397 -435.214989) (xy 332.192865 -435.229184) (xy 332.169904 -435.236651)
			(xy 332.157832 -435.237128) (xy 331.218032 -435.237128) (xy 331.205953 -435.23666) (xy 331.182975 -435.229204)
			(xy 331.163426 -435.215011) (xy 331.14922 -435.195472) (xy 331.141748 -435.172499) (xy 331.141324 -435.16042)
			(xy 329.2348 -435.16042) (xy 329.2348 -436.160418) (xy 329.234304 -436.17253) (xy 329.226817 -436.195567)
			(xy 329.21258 -436.215165) (xy 329.192985 -436.229408) (xy 329.16995 -436.236901) (xy 329.157838 -436.23738)
			(xy 328.218038 -436.23738) (xy 328.205919 -436.236908) (xy 328.182864 -436.229428) (xy 328.16325 -436.21519)
			(xy 328.148997 -436.195586) (xy 328.141501 -436.172537) (xy 328.141076 -436.160418) (xy 327.206526 -436.160418)
			(xy 327.212149 -436.164508) (xy 327.226398 -436.184141) (xy 327.233881 -436.207216) (xy 327.234296 -436.219346)
			(xy 327.234296 -438.76087) (xy 327.233763 -438.77298) (xy 327.226288 -438.796016) (xy 327.212061 -438.815615)
			(xy 327.192473 -438.829859) (xy 327.169443 -438.837353) (xy 327.157334 -438.837832) (xy 326.217534 -438.837832)
			(xy 326.20541 -438.837411) (xy 326.182347 -438.829924) (xy 326.162729 -438.815674) (xy 326.148478 -438.796056)
			(xy 326.14099 -438.772994) (xy 326.140572 -438.76087) (xy 325.2343 -438.76087) (xy 325.2343 -439.760868)
			(xy 328.140568 -439.760868) (xy 328.140568 -437.219344) (xy 328.141097 -437.207299) (xy 328.148513 -437.18438)
			(xy 328.162638 -437.164867) (xy 328.182092 -437.150661) (xy 328.204979 -437.143148) (xy 328.217022 -437.142636)
			(xy 329.15733 -437.142636) (xy 329.169421 -437.143082) (xy 329.192422 -437.150546) (xy 329.212001 -437.164738)
			(xy 329.226251 -437.184276) (xy 329.233782 -437.207255) (xy 329.234292 -437.219344) (xy 329.234292 -438.76087)
			(xy 331.140816 -438.76087) (xy 331.140816 -436.219346) (xy 331.141299 -436.207228) (xy 331.148776 -436.184174)
			(xy 331.163012 -436.16456) (xy 331.182613 -436.150307) (xy 331.20566 -436.142809) (xy 331.217778 -436.142384)
			(xy 332.157578 -436.142384) (xy 332.169704 -436.142779) (xy 332.19277 -436.150271) (xy 332.206734 -436.160418)
			(xy 333.14132 -436.160418) (xy 333.14132 -435.433216) (xy 333.141583 -435.42446) (xy 333.145554 -435.407402)
			(xy 333.149194 -435.399434) (xy 333.38262 -434.923184) (xy 333.38732 -434.912667) (xy 333.390809 -434.889909)
			(xy 333.387325 -434.86715) (xy 333.38262 -434.856636) (xy 333.149194 -434.380386) (xy 333.145527 -434.372427)
			(xy 333.141554 -434.355364) (xy 333.14132 -434.346604) (xy 333.14132 -433.618894) (xy 333.141802 -433.606806)
			(xy 333.149258 -433.583809) (xy 333.163441 -433.564231) (xy 333.18297 -433.54998) (xy 333.205942 -433.542444)
			(xy 333.218028 -433.541932) (xy 334.157828 -433.541932) (xy 334.169942 -433.542293) (xy 334.192975 -433.549804)
			(xy 334.212551 -433.564079) (xy 334.226743 -433.583714) (xy 334.234157 -433.606779) (xy 334.234536 -433.618894)
			(xy 334.234536 -435.16042) (xy 335.141316 -435.16042) (xy 335.141316 -434.433218) (xy 335.14158 -434.424462)
			(xy 335.14555 -434.407404) (xy 335.14919 -434.399436) (xy 335.382616 -433.923186) (xy 335.387314 -433.912668)
			(xy 335.390805 -433.889911) (xy 335.387321 -433.867152) (xy 335.382616 -433.856638) (xy 335.14919 -433.380388)
			(xy 335.145523 -433.372429) (xy 335.14155 -433.355366) (xy 335.141316 -433.346606) (xy 335.141316 -432.618896)
			(xy 335.141709 -432.606811) (xy 335.149181 -432.583824) (xy 335.163391 -432.564271) (xy 335.182949 -432.550068)
			(xy 335.205938 -432.542605) (xy 335.218024 -432.542188) (xy 336.157824 -432.542188) (xy 336.169899 -432.542644)
			(xy 336.192867 -432.550113) (xy 336.207126 -432.560476) (xy 337.141312 -432.560476) (xy 337.141312 -431.833274)
			(xy 337.141562 -431.824517) (xy 337.145542 -431.807459) (xy 337.149186 -431.799492) (xy 337.382612 -431.323242)
			(xy 337.387341 -431.312736) (xy 337.390821 -431.289971) (xy 337.387324 -431.267209) (xy 337.382612 -431.256694)
			(xy 337.149186 -430.780444) (xy 337.145537 -430.772478) (xy 337.141553 -430.75542) (xy 337.141312 -430.746662)
			(xy 337.141312 -430.018952) (xy 337.141724 -430.006873) (xy 337.149202 -429.983901) (xy 337.163411 -429.964363)
			(xy 337.182962 -429.950171) (xy 337.205941 -429.942713) (xy 337.21802 -429.942244) (xy 338.15782 -429.942244)
			(xy 338.169891 -429.942747) (xy 338.19285 -429.950209) (xy 338.212383 -429.964397) (xy 338.226578 -429.983924)
			(xy 338.234049 -430.006881) (xy 338.234528 -430.018952) (xy 338.234528 -431.560478) (xy 339.141308 -431.560478)
			(xy 339.141308 -430.833276) (xy 339.141559 -430.824519) (xy 339.145538 -430.807461) (xy 339.149182 -430.799494)
			(xy 339.382608 -430.323244) (xy 339.387336 -430.312738) (xy 339.390816 -430.289973) (xy 339.38732 -430.26721)
			(xy 339.382608 -430.256696) (xy 339.149182 -429.780446) (xy 339.145533 -429.77248) (xy 339.141549 -429.755422)
			(xy 339.141308 -429.746664) (xy 339.141308 -429.018954) (xy 339.141768 -429.006865) (xy 339.149233 -428.983868)
			(xy 339.163423 -428.964292) (xy 339.182955 -428.950042) (xy 339.205929 -428.942505) (xy 339.218016 -428.941992)
			(xy 340.157816 -428.941992) (xy 340.169925 -428.942402) (xy 340.192951 -428.949905) (xy 340.207536 -428.960534)
			(xy 341.141304 -428.960534) (xy 341.141304 -426.41901) (xy 341.141815 -426.406925) (xy 341.149265 -426.38393)
			(xy 341.163441 -426.364353) (xy 341.182963 -426.350101) (xy 341.205928 -426.342563) (xy 341.218012 -426.342048)
			(xy 342.157812 -426.342048) (xy 342.169916 -426.342505) (xy 342.192935 -426.350002) (xy 342.212504 -426.364255)
			(xy 342.2267 -426.383864) (xy 342.234129 -426.406905) (xy 342.23452 -426.41901) (xy 342.23452 -427.960536)
			(xy 343.1413 -427.960536) (xy 343.1413 -425.419012) (xy 343.141723 -425.406929) (xy 343.149188 -425.383946)
			(xy 343.163392 -425.364394) (xy 343.182942 -425.35019) (xy 343.205925 -425.342724) (xy 343.218008 -425.342304)
			(xy 344.157808 -425.342304) (xy 344.169892 -425.342706) (xy 344.192877 -425.350177) (xy 344.212429 -425.364386)
			(xy 344.226632 -425.383941) (xy 344.234097 -425.406928) (xy 344.234516 -425.419012) (xy 344.234516 -427.960536)
			(xy 344.234067 -427.972612) (xy 344.226595 -427.995579) (xy 344.212395 -428.015115) (xy 344.192854 -428.029308)
			(xy 344.169884 -428.036771) (xy 344.157808 -428.037244) (xy 343.218008 -428.037244) (xy 343.205937 -428.03673)
			(xy 343.182977 -428.029274) (xy 343.163443 -428.015089) (xy 343.149247 -427.995563) (xy 343.141777 -427.972606)
			(xy 343.1413 -427.960536) (xy 342.23452 -427.960536) (xy 342.23452 -428.960534) (xy 342.234121 -428.972629)
			(xy 342.22665 -428.995638) (xy 342.212447 -429.015221) (xy 342.192897 -429.029469) (xy 342.169906 -429.036993)
			(xy 342.157812 -429.037496) (xy 341.218012 -429.037496) (xy 341.205903 -429.037073) (xy 341.182876 -429.029577)
			(xy 341.163302 -429.015317) (xy 341.149107 -428.995696) (xy 341.141687 -428.972644) (xy 341.141304 -428.960534)
			(xy 340.207536 -428.960534) (xy 340.212524 -428.964169) (xy 340.226718 -428.983791) (xy 340.23414 -429.006844)
			(xy 340.234524 -429.018954) (xy 340.234524 -431.560478) (xy 340.234073 -431.57257) (xy 340.226618 -431.595576)
			(xy 340.212429 -431.615159) (xy 340.192889 -431.629409) (xy 340.169906 -431.636935) (xy 340.157816 -431.63744)
			(xy 339.218016 -431.63744) (xy 339.205912 -431.63697) (xy 339.182892 -431.62948) (xy 339.163322 -431.615231)
			(xy 339.149126 -431.595623) (xy 339.141697 -431.572583) (xy 339.141308 -431.560478) (xy 338.234528 -431.560478)
			(xy 338.234528 -432.560476) (xy 338.234067 -432.572555) (xy 338.226609 -432.595534) (xy 338.212414 -432.615083)
			(xy 338.192873 -432.629288) (xy 338.169899 -432.63676) (xy 338.15782 -432.637184) (xy 337.21802 -432.637184)
			(xy 337.205936 -432.63677) (xy 337.18295 -432.629305) (xy 337.163397 -432.6151) (xy 337.149193 -432.595547)
			(xy 337.14173 -432.57256) (xy 337.141312 -432.560476) (xy 336.207126 -432.560476) (xy 336.212403 -432.564311)
			(xy 336.226597 -432.583851) (xy 336.234059 -432.606821) (xy 336.234532 -432.618896) (xy 336.234532 -435.16042)
			(xy 336.234053 -435.172493) (xy 336.226588 -435.195457) (xy 336.212394 -435.214991) (xy 336.19286 -435.229186)
			(xy 336.169897 -435.236652) (xy 336.157824 -435.237128) (xy 335.218024 -435.237128) (xy 335.205945 -435.236667)
			(xy 335.182966 -435.229209) (xy 335.163417 -435.215014) (xy 335.149212 -435.195473) (xy 335.14174 -435.172499)
			(xy 335.141316 -435.16042) (xy 334.234536 -435.16042) (xy 334.234536 -436.160418) (xy 334.234108 -436.172511)
			(xy 334.226643 -436.195516) (xy 334.212447 -436.215098) (xy 334.192904 -436.229347) (xy 334.16992 -436.236874)
			(xy 334.157828 -436.23738) (xy 333.218028 -436.23738) (xy 333.205919 -436.236959) (xy 333.182889 -436.229465)
			(xy 333.163314 -436.215206) (xy 333.149119 -436.195583) (xy 333.141701 -436.172529) (xy 333.14132 -436.160418)
			(xy 332.206734 -436.160418) (xy 332.21239 -436.164528) (xy 332.22664 -436.184151) (xy 332.234124 -436.20722)
			(xy 332.23454 -436.219346) (xy 332.23454 -438.76087) (xy 332.234114 -438.772993) (xy 332.226628 -438.796055)
			(xy 332.212378 -438.815672) (xy 332.192762 -438.829924) (xy 332.169701 -438.837413) (xy 332.157578 -438.837832)
			(xy 331.217778 -438.837832) (xy 331.205651 -438.837458) (xy 331.182587 -438.829956) (xy 331.162969 -438.815694)
			(xy 331.14872 -438.796067) (xy 331.141234 -438.772997) (xy 331.140816 -438.76087) (xy 329.234292 -438.76087)
			(xy 329.234292 -439.760868) (xy 333.140812 -439.760868) (xy 333.140812 -437.219344) (xy 333.141298 -437.207295)
			(xy 333.14872 -437.184369) (xy 333.162853 -437.164851) (xy 333.18232 -437.150647) (xy 333.205219 -437.143142)
			(xy 333.217266 -437.142636) (xy 334.157574 -437.142636) (xy 334.169662 -437.143129) (xy 334.192661 -437.150579)
			(xy 334.212241 -437.164758) (xy 334.226492 -437.184286) (xy 334.234026 -437.207258) (xy 334.234536 -437.219344)
			(xy 334.234536 -438.76087) (xy 335.140808 -438.76087) (xy 335.140808 -436.219346) (xy 335.141299 -436.207229)
			(xy 335.148775 -436.184176) (xy 335.163009 -436.164563) (xy 335.182608 -436.150309) (xy 335.205653 -436.14281)
			(xy 335.21777 -436.142384) (xy 336.15757 -436.142384) (xy 336.169696 -436.142786) (xy 336.192761 -436.150276)
			(xy 336.206721 -436.160418) (xy 337.141312 -436.160418) (xy 337.141312 -435.433216) (xy 337.141575 -435.42446)
			(xy 337.145546 -435.407402) (xy 337.149186 -435.399434) (xy 337.382612 -434.923184) (xy 337.387312 -434.912667)
			(xy 337.390802 -434.889909) (xy 337.387317 -434.86715) (xy 337.382612 -434.856636) (xy 337.149186 -434.380386)
			(xy 337.145518 -434.372427) (xy 337.141546 -434.355364) (xy 337.141312 -434.346604) (xy 337.141312 -433.618894)
			(xy 337.141802 -433.606807) (xy 337.149257 -433.583811) (xy 337.163439 -433.564234) (xy 337.182965 -433.549982)
			(xy 337.205935 -433.542445) (xy 337.21802 -433.541932) (xy 338.15782 -433.541932) (xy 338.169933 -433.5423)
			(xy 338.192967 -433.549808) (xy 338.212542 -433.564081) (xy 338.226735 -433.583715) (xy 338.234149 -433.606779)
			(xy 338.234528 -433.618894) (xy 338.234528 -435.16042) (xy 339.141308 -435.16042) (xy 339.141308 -434.433218)
			(xy 339.141572 -434.424462) (xy 339.145543 -434.407404) (xy 339.149182 -434.399436) (xy 339.382608 -433.923186)
			(xy 339.387306 -433.912668) (xy 339.390797 -433.889911) (xy 339.387313 -433.867152) (xy 339.382608 -433.856638)
			(xy 339.149182 -433.380388) (xy 339.145515 -433.372429) (xy 339.141542 -433.355366) (xy 339.141308 -433.346606)
			(xy 339.141308 -432.618896) (xy 339.141709 -432.606811) (xy 339.14918 -432.583826) (xy 339.163388 -432.564274)
			(xy 339.182944 -432.550071) (xy 339.205931 -432.542606) (xy 339.218016 -432.542188) (xy 340.157816 -432.542188)
			(xy 340.169891 -432.542651) (xy 340.192858 -432.550117) (xy 340.207113 -432.560476) (xy 341.141304 -432.560476)
			(xy 341.141304 -431.833274) (xy 341.141555 -431.824517) (xy 341.145534 -431.807459) (xy 341.149178 -431.799492)
			(xy 341.382604 -431.323242) (xy 341.387334 -431.312736) (xy 341.390814 -431.289971) (xy 341.387316 -431.267208)
			(xy 341.382604 -431.256694) (xy 341.149178 -430.780444) (xy 341.145528 -430.772478) (xy 341.141545 -430.75542)
			(xy 341.141304 -430.746662) (xy 341.141304 -430.018952) (xy 341.141723 -430.006874) (xy 341.149201 -429.983903)
			(xy 341.163408 -429.964366) (xy 341.182957 -429.950173) (xy 341.205933 -429.942714) (xy 341.218012 -429.942244)
			(xy 342.157812 -429.942244) (xy 342.169882 -429.942753) (xy 342.192842 -429.950213) (xy 342.212374 -429.9644)
			(xy 342.22657 -429.983926) (xy 342.234041 -430.006882) (xy 342.23452 -430.018952) (xy 342.23452 -431.560478)
			(xy 343.1413 -431.560478) (xy 343.1413 -430.833276) (xy 343.141552 -430.824519) (xy 343.145531 -430.807461)
			(xy 343.149174 -430.799494) (xy 343.3826 -430.323244) (xy 343.387328 -430.312738) (xy 343.390809 -430.289973)
			(xy 343.387312 -430.26721) (xy 343.3826 -430.256696) (xy 343.149174 -429.780446) (xy 343.145524 -429.77248)
			(xy 343.141541 -429.755422) (xy 343.1413 -429.746664) (xy 343.1413 -429.018954) (xy 343.141767 -429.006866)
			(xy 343.149232 -428.983871) (xy 343.16342 -428.964295) (xy 343.18295 -428.950044) (xy 343.205922 -428.942507)
			(xy 343.218008 -428.941992) (xy 344.157808 -428.941992) (xy 344.169917 -428.942409) (xy 344.192943 -428.94991)
			(xy 344.207523 -428.960534) (xy 345.141296 -428.960534) (xy 345.141296 -426.41901) (xy 345.141815 -426.406925)
			(xy 345.149264 -426.383932) (xy 345.163439 -426.364356) (xy 345.182958 -426.350104) (xy 345.205921 -426.342564)
			(xy 345.218004 -426.342048) (xy 346.157804 -426.342048) (xy 346.169908 -426.342512) (xy 346.192927 -426.350006)
			(xy 346.212495 -426.364257) (xy 346.226691 -426.383866) (xy 346.234121 -426.406905) (xy 346.234512 -426.41901)
			(xy 346.234512 -428.960534) (xy 346.234121 -428.97263) (xy 346.226649 -428.99564) (xy 346.212444 -429.015223)
			(xy 346.192892 -429.029471) (xy 346.169899 -429.036994) (xy 346.157804 -429.037496) (xy 345.218004 -429.037496)
			(xy 345.205895 -429.03708) (xy 345.182867 -429.029582) (xy 345.163293 -429.01532) (xy 345.149099 -428.995698)
			(xy 345.141679 -428.972644) (xy 345.141296 -428.960534) (xy 344.207523 -428.960534) (xy 344.212515 -428.964172)
			(xy 344.22671 -428.983792) (xy 344.234132 -429.006844) (xy 344.234516 -429.018954) (xy 344.234516 -431.560478)
			(xy 344.234073 -431.572571) (xy 344.226617 -431.595578) (xy 344.212426 -431.615162) (xy 344.192884 -431.629412)
			(xy 344.169899 -431.636937) (xy 344.157808 -431.63744) (xy 343.218008 -431.63744) (xy 343.205904 -431.636978)
			(xy 343.182883 -431.629485) (xy 343.163313 -431.615234) (xy 343.149117 -431.595625) (xy 343.141689 -431.572584)
			(xy 343.1413 -431.560478) (xy 342.23452 -431.560478) (xy 342.23452 -432.560476) (xy 342.234067 -432.572556)
			(xy 342.226607 -432.595536) (xy 342.212411 -432.615086) (xy 342.192868 -432.629291) (xy 342.169892 -432.636761)
			(xy 342.157812 -432.637184) (xy 341.218012 -432.637184) (xy 341.205928 -432.636777) (xy 341.182941 -432.629309)
			(xy 341.163389 -432.615103) (xy 341.149185 -432.595548) (xy 341.141722 -432.572561) (xy 341.141304 -432.560476)
			(xy 340.207113 -432.560476) (xy 340.212394 -432.564314) (xy 340.226588 -432.583853) (xy 340.234051 -432.606821)
			(xy 340.234524 -432.618896) (xy 340.234524 -435.16042) (xy 340.234053 -435.172494) (xy 340.226587 -435.195459)
			(xy 340.212391 -435.214994) (xy 340.192855 -435.229189) (xy 340.16989 -435.236654) (xy 340.157816 -435.237128)
			(xy 339.218016 -435.237128) (xy 339.205944 -435.236622) (xy 339.182981 -435.229167) (xy 339.163445 -435.21498)
			(xy 339.14925 -435.195451) (xy 339.141783 -435.172492) (xy 339.141308 -435.16042) (xy 338.234528 -435.16042)
			(xy 338.234528 -436.160418) (xy 338.234108 -436.172512) (xy 338.226642 -436.195518) (xy 338.212445 -436.215101)
			(xy 338.192899 -436.22935) (xy 338.169912 -436.236876) (xy 338.15782 -436.23738) (xy 337.21802 -436.23738)
			(xy 337.20591 -436.236966) (xy 337.18288 -436.22947) (xy 337.163305 -436.215208) (xy 337.149111 -436.195585)
			(xy 337.141693 -436.172529) (xy 337.141312 -436.160418) (xy 336.206721 -436.160418) (xy 336.212381 -436.16453)
			(xy 336.226632 -436.184153) (xy 336.234116 -436.20722) (xy 336.234532 -436.219346) (xy 336.234532 -438.76087)
			(xy 336.234114 -438.772994) (xy 336.226626 -438.796057) (xy 336.212375 -438.815675) (xy 336.192757 -438.829926)
			(xy 336.169694 -438.837414) (xy 336.15757 -438.837832) (xy 335.21777 -438.837832) (xy 335.205651 -438.837413)
			(xy 335.182602 -438.829914) (xy 335.162998 -438.81566) (xy 335.148758 -438.796045) (xy 335.141277 -438.772989)
			(xy 335.140808 -438.76087) (xy 334.234536 -438.76087) (xy 334.234536 -439.760868) (xy 337.140804 -439.760868)
			(xy 337.140804 -437.219344) (xy 337.141297 -437.207296) (xy 337.148718 -437.184371) (xy 337.16285 -437.164854)
			(xy 337.182314 -437.150649) (xy 337.205211 -437.143143) (xy 337.217258 -437.142636) (xy 338.157566 -437.142636)
			(xy 338.169653 -437.143136) (xy 338.192652 -437.150583) (xy 338.212232 -437.164761) (xy 338.226484 -437.184288)
			(xy 338.234018 -437.207258) (xy 338.234528 -437.219344) (xy 338.234528 -438.76087) (xy 339.1408 -438.76087)
			(xy 339.1408 -436.219346) (xy 339.141298 -436.207229) (xy 339.148773 -436.184178) (xy 339.163006 -436.164566)
			(xy 339.182603 -436.150312) (xy 339.205646 -436.142812) (xy 339.217762 -436.142384) (xy 340.157562 -436.142384)
			(xy 340.169687 -436.142793) (xy 340.192753 -436.15028) (xy 340.206708 -436.160418) (xy 341.141304 -436.160418)
			(xy 341.141304 -435.433216) (xy 341.141568 -435.42446) (xy 341.145539 -435.407402) (xy 341.149178 -435.399434)
			(xy 341.382604 -434.923184) (xy 341.387304 -434.912667) (xy 341.390795 -434.889909) (xy 341.387309 -434.86715)
			(xy 341.382604 -434.856636) (xy 341.149178 -434.380386) (xy 341.14551 -434.372428) (xy 341.141538 -434.355364)
			(xy 341.141304 -434.346604) (xy 341.141304 -433.618894) (xy 341.141802 -433.606808) (xy 341.149256 -433.583813)
			(xy 341.163436 -433.564236) (xy 341.18296 -433.549985) (xy 341.205928 -433.542447) (xy 341.218012 -433.541932)
			(xy 342.157812 -433.541932) (xy 342.169925 -433.542306) (xy 342.192958 -433.549813) (xy 342.212534 -433.564084)
			(xy 342.226727 -433.583717) (xy 342.234141 -433.60678) (xy 342.23452 -433.618894) (xy 342.23452 -435.16042)
			(xy 343.1413 -435.16042) (xy 343.1413 -434.433218) (xy 343.141565 -434.424462) (xy 343.145535 -434.407404)
			(xy 343.149174 -434.399436) (xy 343.3826 -433.923186) (xy 343.387299 -433.912668) (xy 343.39079 -433.889911)
			(xy 343.387305 -433.867152) (xy 343.3826 -433.856638) (xy 343.149174 -433.380388) (xy 343.145506 -433.37243)
			(xy 343.141534 -433.355366) (xy 343.1413 -433.346606) (xy 343.1413 -432.618896) (xy 343.141709 -432.606812)
			(xy 343.149179 -432.583828) (xy 343.163386 -432.564277) (xy 343.182939 -432.550073) (xy 343.205924 -432.542607)
			(xy 343.218008 -432.542188) (xy 344.157808 -432.542188) (xy 344.169883 -432.542657) (xy 344.192849 -432.550122)
			(xy 344.2071 -432.560476) (xy 345.141296 -432.560476) (xy 345.141296 -431.833274) (xy 345.141547 -431.824517)
			(xy 345.145527 -431.807459) (xy 345.14917 -431.799492) (xy 345.382596 -431.323242) (xy 345.387326 -431.312737)
			(xy 345.390806 -431.289971) (xy 345.387309 -431.267208) (xy 345.382596 -431.256694) (xy 345.14917 -430.780444)
			(xy 345.14552 -430.772478) (xy 345.141537 -430.75542) (xy 345.141296 -430.746662) (xy 345.141296 -430.018952)
			(xy 345.141723 -430.006875) (xy 345.149199 -429.983905) (xy 345.163405 -429.964368) (xy 345.182952 -429.950176)
			(xy 345.205926 -429.942715) (xy 345.218004 -429.942244) (xy 346.157804 -429.942244) (xy 346.169874 -429.94276)
			(xy 346.192833 -429.950218) (xy 346.212366 -429.964403) (xy 346.226562 -429.983927) (xy 346.234033 -430.006882)
			(xy 346.234512 -430.018952) (xy 346.234512 -431.360072) (xy 356.154736 -431.360072) (xy 356.155234 -431.275192)
			(xy 356.163191 -431.105619) (xy 356.179087 -430.936605) (xy 356.202888 -430.768522) (xy 356.234542 -430.601739)
			(xy 356.273978 -430.436623) (xy 356.32111 -430.273538) (xy 356.375834 -430.11284) (xy 356.438031 -429.954885)
			(xy 356.507563 -429.800018) (xy 356.584278 -429.648581) (xy 356.668006 -429.500905) (xy 356.758564 -429.357317)
			(xy 356.855753 -429.218131) (xy 356.95936 -429.083654) (xy 357.069155 -428.954181) (xy 357.184899 -428.829996)
			(xy 357.306336 -428.711373) (xy 357.4332 -428.598572) (xy 357.565211 -428.491842) (xy 357.702081 -428.391417)
			(xy 357.843506 -428.297518) (xy 357.989178 -428.21035) (xy 358.138776 -428.130107) (xy 358.29197 -428.056963)
			(xy 358.448424 -427.991081) (xy 358.607794 -427.932604) (xy 358.76973 -427.881662) (xy 358.933876 -427.838366)
			(xy 359.099871 -427.802811) (xy 359.26735 -427.775076) (xy 359.435945 -427.755222) (xy 359.605285 -427.743292)
			(xy 359.774998 -427.739313) (xy 359.944711 -427.743292) (xy 360.114051 -427.755222) (xy 360.282646 -427.775076)
			(xy 360.450125 -427.802811) (xy 360.61612 -427.838366) (xy 360.780266 -427.881662) (xy 360.942202 -427.932604)
			(xy 361.019019 -427.96079) (xy 381.2413 -427.96079) (xy 381.2413 -425.419266) (xy 381.241778 -425.407179)
			(xy 381.249239 -425.384184) (xy 381.263424 -425.364608) (xy 381.282952 -425.350357) (xy 381.305922 -425.342819)
			(xy 381.318008 -425.342304) (xy 382.257808 -425.342304) (xy 382.269918 -425.342709) (xy 382.292946 -425.350212)
			(xy 382.312519 -425.364476) (xy 382.326714 -425.3841) (xy 382.334133 -425.407155) (xy 382.334516 -425.419266)
			(xy 382.334516 -427.96079) (xy 382.334083 -427.972883) (xy 382.326624 -427.995891) (xy 382.31243 -428.015475)
			(xy 382.292886 -428.029724) (xy 382.2699 -428.037249) (xy 382.257808 -428.037752) (xy 381.318008 -428.037752)
			(xy 381.305905 -428.037278) (xy 381.282886 -428.029787) (xy 381.263318 -428.015538) (xy 381.249121 -427.995932)
			(xy 381.241691 -427.972894) (xy 381.2413 -427.96079) (xy 361.019019 -427.96079) (xy 361.101572 -427.991081)
			(xy 361.258026 -428.056963) (xy 361.41122 -428.130107) (xy 361.560818 -428.21035) (xy 361.70649 -428.297518)
			(xy 361.847915 -428.391417) (xy 361.984785 -428.491842) (xy 362.116796 -428.598572) (xy 362.24366 -428.711373)
			(xy 362.365097 -428.829996) (xy 362.480841 -428.954181) (xy 362.590636 -429.083654) (xy 362.694243 -429.218131)
			(xy 362.791432 -429.357317) (xy 362.88199 -429.500905) (xy 362.965718 -429.648581) (xy 363.042433 -429.800018)
			(xy 363.111965 -429.954885) (xy 363.174162 -430.11284) (xy 363.228886 -430.273538) (xy 363.276018 -430.436623)
			(xy 363.315454 -430.601739) (xy 363.347108 -430.768522) (xy 363.370909 -430.936605) (xy 363.386805 -431.105619)
			(xy 363.394762 -431.275192) (xy 363.39526 -431.360072) (xy 363.394788 -431.445675) (xy 363.389359 -431.560478)
			(xy 381.2413 -431.560478) (xy 381.2413 -430.833276) (xy 381.241552 -430.824519) (xy 381.245531 -430.807461)
			(xy 381.249174 -430.799494) (xy 381.4826 -430.323244) (xy 381.487328 -430.312738) (xy 381.490809 -430.289973)
			(xy 381.487312 -430.26721) (xy 381.4826 -430.256696) (xy 381.249174 -429.780446) (xy 381.245524 -429.77248)
			(xy 381.241541 -429.755422) (xy 381.2413 -429.746664) (xy 381.2413 -429.018954) (xy 381.241767 -429.006866)
			(xy 381.249232 -428.983871) (xy 381.26342 -428.964295) (xy 381.28295 -428.950044) (xy 381.305922 -428.942507)
			(xy 381.318008 -428.941992) (xy 382.257808 -428.941992) (xy 382.269917 -428.942409) (xy 382.292943 -428.94991)
			(xy 382.307871 -428.960788) (xy 383.241296 -428.960788) (xy 383.241296 -426.419264) (xy 383.241733 -426.407187)
			(xy 383.249206 -426.384218) (xy 383.26341 -426.364681) (xy 383.282954 -426.350488) (xy 383.305927 -426.343027)
			(xy 383.318004 -426.342556) (xy 384.257804 -426.342556) (xy 384.269875 -426.34306) (xy 384.292836 -426.35052)
			(xy 384.31237 -426.364707) (xy 384.326566 -426.384235) (xy 384.334035 -426.407193) (xy 384.334512 -426.419264)
			(xy 384.334512 -427.96079) (xy 385.241292 -427.96079) (xy 385.241292 -425.419266) (xy 385.241777 -425.407179)
			(xy 385.249238 -425.384186) (xy 385.263421 -425.36461) (xy 385.282947 -425.350359) (xy 385.305915 -425.34282)
			(xy 385.318 -425.342304) (xy 386.2578 -425.342304) (xy 386.269909 -425.342716) (xy 386.292937 -425.350216)
			(xy 386.312511 -425.364479) (xy 386.326705 -425.384101) (xy 386.334125 -425.407155) (xy 386.334508 -425.419266)
			(xy 386.334508 -427.96079) (xy 386.333985 -427.972874) (xy 386.326537 -427.995866) (xy 386.312363 -428.015442)
			(xy 386.292844 -428.029695) (xy 386.269882 -428.037236) (xy 386.2578 -428.037752) (xy 385.318 -428.037752)
			(xy 385.305896 -428.037285) (xy 385.282878 -428.029791) (xy 385.263309 -428.015541) (xy 385.249113 -427.995934)
			(xy 385.241683 -427.972895) (xy 385.241292 -427.96079) (xy 384.334512 -427.96079) (xy 384.334512 -428.960788)
			(xy 384.334077 -428.97287) (xy 384.326613 -428.995851) (xy 384.312413 -429.015401) (xy 384.292866 -429.029606)
			(xy 384.269886 -429.037074) (xy 384.257804 -429.037496) (xy 383.318004 -429.037496) (xy 383.30592 -429.037084)
			(xy 383.282936 -429.029616) (xy 383.263384 -429.01541) (xy 383.24918 -428.995857) (xy 383.241715 -428.972872)
			(xy 383.241296 -428.960788) (xy 382.307871 -428.960788) (xy 382.312515 -428.964172) (xy 382.32671 -428.983792)
			(xy 382.334132 -429.006844) (xy 382.334516 -429.018954) (xy 382.334516 -431.560478) (xy 382.334073 -431.572571)
			(xy 382.326617 -431.595578) (xy 382.312426 -431.615162) (xy 382.292884 -431.629412) (xy 382.269899 -431.636937)
			(xy 382.257808 -431.63744) (xy 381.318008 -431.63744) (xy 381.305904 -431.636978) (xy 381.282883 -431.629485)
			(xy 381.263313 -431.615234) (xy 381.249117 -431.595625) (xy 381.241689 -431.572584) (xy 381.2413 -431.560478)
			(xy 363.389359 -431.560478) (xy 363.386701 -431.616689) (xy 363.370537 -431.787129) (xy 363.346334 -431.956615)
			(xy 363.314145 -432.124767) (xy 363.274043 -432.291209) (xy 363.226117 -432.455569) (xy 363.170474 -432.61748)
			(xy 363.107239 -432.776579) (xy 363.036553 -432.932511) (xy 362.958574 -433.084927) (xy 362.873477 -433.233486)
			(xy 362.781452 -433.377855) (xy 362.682704 -433.517713) (xy 362.577455 -433.652746) (xy 362.46594 -433.782652)
			(xy 362.348408 -433.907141) (xy 362.225123 -434.025934) (xy 362.096359 -434.138766) (xy 361.962404 -434.245385)
			(xy 361.82356 -434.345551) (xy 361.680135 -434.439042) (xy 361.53245 -434.525647) (xy 361.380836 -434.605174)
			(xy 361.225632 -434.677444) (xy 361.146598 -434.710332) (xy 361.138713 -434.713995) (xy 361.125816 -434.725637)
			(xy 361.117551 -434.740919) (xy 361.115864 -434.749448) (xy 361.100116 -434.849016) (xy 361.109514 -434.873654)
			(xy 361.119928 -434.88229) (xy 361.169374 -434.924299) (xy 361.263563 -435.013553) (xy 361.352051 -435.108462)
			(xy 361.394803 -435.16042) (xy 381.2413 -435.16042) (xy 381.2413 -434.433218) (xy 381.241565 -434.424462)
			(xy 381.245535 -434.407404) (xy 381.249174 -434.399436) (xy 381.4826 -433.923186) (xy 381.487299 -433.912668)
			(xy 381.49079 -433.889911) (xy 381.487305 -433.867152) (xy 381.4826 -433.856638) (xy 381.249174 -433.380388)
			(xy 381.245506 -433.37243) (xy 381.241534 -433.355366) (xy 381.2413 -433.346606) (xy 381.2413 -432.618896)
			(xy 381.241709 -432.606812) (xy 381.249179 -432.583828) (xy 381.263386 -432.564277) (xy 381.282939 -432.550073)
			(xy 381.305924 -432.542607) (xy 381.318008 -432.542188) (xy 382.257808 -432.542188) (xy 382.269883 -432.542657)
			(xy 382.292849 -432.550122) (xy 382.3071 -432.560476) (xy 383.241296 -432.560476) (xy 383.241296 -431.833274)
			(xy 383.241547 -431.824517) (xy 383.245527 -431.807459) (xy 383.24917 -431.799492) (xy 383.482596 -431.323242)
			(xy 383.487326 -431.312737) (xy 383.490806 -431.289971) (xy 383.487309 -431.267208) (xy 383.482596 -431.256694)
			(xy 383.24917 -430.780444) (xy 383.24552 -430.772478) (xy 383.241537 -430.75542) (xy 383.241296 -430.746662)
			(xy 383.241296 -430.018952) (xy 383.241723 -430.006875) (xy 383.249199 -429.983905) (xy 383.263405 -429.964368)
			(xy 383.282952 -429.950176) (xy 383.305926 -429.942715) (xy 383.318004 -429.942244) (xy 384.257804 -429.942244)
			(xy 384.269874 -429.94276) (xy 384.292833 -429.950218) (xy 384.312366 -429.964403) (xy 384.326562 -429.983927)
			(xy 384.334033 -430.006882) (xy 384.334512 -430.018952) (xy 384.334512 -431.560478) (xy 385.241292 -431.560478)
			(xy 385.241292 -430.833276) (xy 385.241544 -430.824519) (xy 385.245523 -430.807462) (xy 385.249166 -430.799494)
			(xy 385.482592 -430.323244) (xy 385.48732 -430.312738) (xy 385.490801 -430.289973) (xy 385.487304 -430.26721)
			(xy 385.482592 -430.256696) (xy 385.249166 -429.780446) (xy 385.245516 -429.77248) (xy 385.241533 -429.755422)
			(xy 385.241292 -429.746664) (xy 385.241292 -429.018954) (xy 385.241767 -429.006867) (xy 385.249231 -428.983873)
			(xy 385.263417 -428.964298) (xy 385.282945 -428.950047) (xy 385.305914 -428.942508) (xy 385.318 -428.941992)
			(xy 386.2578 -428.941992) (xy 386.269908 -428.942416) (xy 386.292934 -428.949914) (xy 386.307859 -428.960788)
			(xy 387.241288 -428.960788) (xy 387.241288 -426.419264) (xy 387.241733 -426.407188) (xy 387.249205 -426.38422)
			(xy 387.263407 -426.364684) (xy 387.282949 -426.350491) (xy 387.30592 -426.343028) (xy 387.317996 -426.342556)
			(xy 388.257796 -426.342556) (xy 388.269867 -426.343067) (xy 388.292828 -426.350524) (xy 388.312362 -426.36471)
			(xy 388.326558 -426.384236) (xy 388.334027 -426.407193) (xy 388.334504 -426.419264) (xy 388.334504 -427.96079)
			(xy 389.241284 -427.96079) (xy 389.241284 -425.419266) (xy 389.241679 -425.40717) (xy 389.249151 -425.384161)
			(xy 389.263354 -425.364578) (xy 389.282905 -425.35033) (xy 389.305897 -425.342807) (xy 389.317992 -425.342304)
			(xy 390.257792 -425.342304) (xy 390.269901 -425.342723) (xy 390.292929 -425.350221) (xy 390.312502 -425.364481)
			(xy 390.326697 -425.384103) (xy 390.334117 -425.407156) (xy 390.3345 -425.419266) (xy 390.3345 -427.96079)
			(xy 390.333985 -427.972875) (xy 390.326536 -427.995869) (xy 390.31236 -428.015445) (xy 390.292839 -428.029697)
			(xy 390.269875 -428.037237) (xy 390.257792 -428.037752) (xy 389.317992 -428.037752) (xy 389.305888 -428.037291)
			(xy 389.282869 -428.029796) (xy 389.263301 -428.015544) (xy 389.249104 -427.995935) (xy 389.241675 -427.972895)
			(xy 389.241284 -427.96079) (xy 388.334504 -427.96079) (xy 388.334504 -428.960788) (xy 388.334077 -428.97287)
			(xy 388.326612 -428.995853) (xy 388.31241 -429.015404) (xy 388.292861 -429.029609) (xy 388.269878 -429.037076)
			(xy 388.257796 -429.037496) (xy 387.317996 -429.037496) (xy 387.305912 -429.037091) (xy 387.282927 -429.029621)
			(xy 387.263376 -429.015413) (xy 387.249172 -428.995859) (xy 387.241707 -428.972872) (xy 387.241288 -428.960788)
			(xy 386.307859 -428.960788) (xy 386.312507 -428.964174) (xy 386.326701 -428.983794) (xy 386.334124 -429.006845)
			(xy 386.334508 -429.018954) (xy 386.334508 -431.560478) (xy 386.333975 -431.572562) (xy 386.32653 -431.595553)
			(xy 386.312359 -431.61513) (xy 386.292842 -431.629383) (xy 386.269882 -431.636924) (xy 386.2578 -431.63744)
			(xy 385.318 -431.63744) (xy 385.305895 -431.636984) (xy 385.282875 -431.62949) (xy 385.263305 -431.615237)
			(xy 385.249109 -431.595626) (xy 385.241681 -431.572584) (xy 385.241292 -431.560478) (xy 384.334512 -431.560478)
			(xy 384.334512 -432.560476) (xy 384.334067 -432.572557) (xy 384.326606 -432.595538) (xy 384.312409 -432.615089)
			(xy 384.292863 -432.629294) (xy 384.269885 -432.636762) (xy 384.257804 -432.637184) (xy 383.318004 -432.637184)
			(xy 383.305919 -432.636784) (xy 383.282932 -432.629314) (xy 383.26338 -432.615106) (xy 383.249176 -432.59555)
			(xy 383.241713 -432.572561) (xy 383.241296 -432.560476) (xy 382.3071 -432.560476) (xy 382.312386 -432.564317)
			(xy 382.32658 -432.583854) (xy 382.334043 -432.606821) (xy 382.334516 -432.618896) (xy 382.334516 -435.16042)
			(xy 382.334053 -435.172495) (xy 382.326586 -435.195461) (xy 382.312389 -435.214997) (xy 382.29285 -435.229191)
			(xy 382.269883 -435.236655) (xy 382.257808 -435.237128) (xy 381.318008 -435.237128) (xy 381.305936 -435.236629)
			(xy 381.282972 -435.229171) (xy 381.263437 -435.214983) (xy 381.249241 -435.195453) (xy 381.241775 -435.172492)
			(xy 381.2413 -435.16042) (xy 361.394803 -435.16042) (xy 361.434498 -435.208663) (xy 361.510589 -435.313772)
			(xy 361.580032 -435.423387) (xy 361.642562 -435.537087) (xy 361.697938 -435.654438) (xy 361.74595 -435.77499)
			(xy 361.786412 -435.89828) (xy 361.81917 -436.023838) (xy 361.844098 -436.151181) (xy 361.861101 -436.279823)
			(xy 361.870114 -436.40927) (xy 361.871103 -436.539027) (xy 361.864062 -436.668596) (xy 361.849021 -436.797482)
			(xy 361.826035 -436.92519) (xy 361.795194 -437.051232) (xy 361.756614 -437.175125) (xy 361.710445 -437.296394)
			(xy 361.656862 -437.414574) (xy 361.596072 -437.529214) (xy 361.528306 -437.639874) (xy 361.453825 -437.74613)
			(xy 361.372914 -437.847575) (xy 361.285882 -437.943821) (xy 361.193064 -438.034499) (xy 361.094814 -438.119261)
			(xy 360.991508 -438.197784) (xy 360.883543 -438.269766) (xy 360.771333 -438.334931) (xy 360.655306 -438.39303)
			(xy 360.535907 -438.443841) (xy 360.413594 -438.487169) (xy 360.288835 -438.522847) (xy 360.162108 -438.550739)
			(xy 360.033898 -438.570739) (xy 359.904696 -438.58277) (xy 359.774998 -438.586785) (xy 359.6453 -438.58277)
			(xy 359.516098 -438.570739) (xy 359.387888 -438.550739) (xy 359.261161 -438.522847) (xy 359.136402 -438.487169)
			(xy 359.014089 -438.443841) (xy 358.89469 -438.39303) (xy 358.778663 -438.334931) (xy 358.666453 -438.269766)
			(xy 358.558488 -438.197784) (xy 358.455182 -438.119261) (xy 358.356932 -438.034499) (xy 358.264114 -437.943821)
			(xy 358.177082 -437.847575) (xy 358.096171 -437.74613) (xy 358.02169 -437.639874) (xy 357.953924 -437.529214)
			(xy 357.893134 -437.414574) (xy 357.839551 -437.296394) (xy 357.793382 -437.175125) (xy 357.754802 -437.051232)
			(xy 357.723961 -436.92519) (xy 357.700975 -436.797482) (xy 357.685934 -436.668596) (xy 357.678893 -436.539027)
			(xy 357.679882 -436.40927) (xy 357.688895 -436.279823) (xy 357.705898 -436.151181) (xy 357.730826 -436.023838)
			(xy 357.763584 -435.89828) (xy 357.804046 -435.77499) (xy 357.852058 -435.654438) (xy 357.907434 -435.537087)
			(xy 357.969964 -435.423387) (xy 358.039407 -435.313772) (xy 358.115498 -435.208663) (xy 358.197945 -435.108462)
			(xy 358.286433 -435.013553) (xy 358.380622 -434.924299) (xy 358.430068 -434.88229) (xy 358.440228 -434.873908)
			(xy 358.449626 -434.849016) (xy 358.4321 -434.73624) (xy 358.415844 -434.715412) (xy 358.403398 -434.710332)
			(xy 358.325295 -434.677853) (xy 358.1719 -434.606515) (xy 358.022004 -434.52809) (xy 357.875935 -434.44275)
			(xy 357.734012 -434.350681) (xy 357.596544 -434.252083) (xy 357.463831 -434.147172) (xy 357.336162 -434.036176)
			(xy 357.213818 -433.919339) (xy 357.097064 -433.796915) (xy 356.986156 -433.669172) (xy 356.881335 -433.536387)
			(xy 356.782831 -433.398852) (xy 356.690858 -433.256866) (xy 356.605617 -433.110739) (xy 356.527295 -432.96079)
			(xy 356.456061 -432.807346) (xy 356.392073 -432.650743) (xy 356.335468 -432.491322) (xy 356.286372 -432.329431)
			(xy 356.244891 -432.165424) (xy 356.211115 -431.999658) (xy 356.185119 -431.832496) (xy 356.166958 -431.664301)
			(xy 356.156674 -431.495443) (xy 356.15499 -431.410872) (xy 356.155244 -431.410872) (xy 356.154736 -431.360072)
			(xy 346.234512 -431.360072) (xy 346.234512 -432.560476) (xy 346.234067 -432.572557) (xy 346.226606 -432.595538)
			(xy 346.212409 -432.615089) (xy 346.192863 -432.629294) (xy 346.169885 -432.636762) (xy 346.157804 -432.637184)
			(xy 345.218004 -432.637184) (xy 345.205919 -432.636784) (xy 345.182932 -432.629314) (xy 345.16338 -432.615106)
			(xy 345.149176 -432.59555) (xy 345.141713 -432.572561) (xy 345.141296 -432.560476) (xy 344.2071 -432.560476)
			(xy 344.212386 -432.564317) (xy 344.22658 -432.583854) (xy 344.234043 -432.606821) (xy 344.234516 -432.618896)
			(xy 344.234516 -435.16042) (xy 344.234053 -435.172495) (xy 344.226586 -435.195461) (xy 344.212389 -435.214997)
			(xy 344.19285 -435.229191) (xy 344.169883 -435.236655) (xy 344.157808 -435.237128) (xy 343.218008 -435.237128)
			(xy 343.205936 -435.236629) (xy 343.182972 -435.229171) (xy 343.163437 -435.214983) (xy 343.149241 -435.195453)
			(xy 343.141775 -435.172492) (xy 343.1413 -435.16042) (xy 342.23452 -435.16042) (xy 342.23452 -436.160418)
			(xy 342.234107 -436.172513) (xy 342.226641 -436.195521) (xy 342.212442 -436.215104) (xy 342.192894 -436.229352)
			(xy 342.169905 -436.236877) (xy 342.157812 -436.23738) (xy 341.218012 -436.23738) (xy 341.205902 -436.236973)
			(xy 341.182872 -436.229474) (xy 341.163297 -436.215211) (xy 341.149102 -436.195586) (xy 341.141685 -436.17253)
			(xy 341.141304 -436.160418) (xy 340.206708 -436.160418) (xy 340.212373 -436.164533) (xy 340.226623 -436.184154)
			(xy 340.234108 -436.207221) (xy 340.234524 -436.219346) (xy 340.234524 -438.76087) (xy 340.234114 -438.772995)
			(xy 340.226625 -438.796059) (xy 340.212372 -438.815678) (xy 340.192752 -438.829929) (xy 340.169687 -438.837415)
			(xy 340.157562 -438.837832) (xy 339.217762 -438.837832) (xy 339.205642 -438.83742) (xy 339.182593 -438.829919)
			(xy 339.162989 -438.815662) (xy 339.14875 -438.796046) (xy 339.141269 -438.77299) (xy 339.1408 -438.76087)
			(xy 338.234528 -438.76087) (xy 338.234528 -439.760868) (xy 341.140796 -439.760868) (xy 341.140796 -437.219344)
			(xy 341.141297 -437.207296) (xy 341.148717 -437.184373) (xy 341.162848 -437.164857) (xy 341.182309 -437.150652)
			(xy 341.205204 -437.143144) (xy 341.21725 -437.142636) (xy 342.157558 -437.142636) (xy 342.169645 -437.143143)
			(xy 342.192644 -437.150588) (xy 342.212224 -437.164764) (xy 342.226476 -437.184289) (xy 342.23401 -437.207259)
			(xy 342.23452 -437.219344) (xy 342.23452 -438.76087) (xy 343.140792 -438.76087) (xy 343.140792 -436.219346)
			(xy 343.14135 -436.207238) (xy 343.148819 -436.184204) (xy 343.16304 -436.164606) (xy 343.182622 -436.150361)
			(xy 343.205647 -436.142865) (xy 343.217754 -436.142384) (xy 344.157554 -436.142384) (xy 344.169679 -436.1428)
			(xy 344.192744 -436.150285) (xy 344.206695 -436.160418) (xy 345.141296 -436.160418) (xy 345.141296 -435.433216)
			(xy 345.141561 -435.42446) (xy 345.145531 -435.407402) (xy 345.14917 -435.399434) (xy 345.382596 -434.923184)
			(xy 345.387296 -434.912667) (xy 345.390787 -434.889909) (xy 345.387302 -434.86715) (xy 345.382596 -434.856636)
			(xy 345.14917 -434.380386) (xy 345.145501 -434.372428) (xy 345.14153 -434.355364) (xy 345.141296 -434.346604)
			(xy 345.141296 -433.618894) (xy 345.141802 -433.606809) (xy 345.149255 -433.583815) (xy 345.163433 -433.564239)
			(xy 345.182955 -433.549987) (xy 345.20592 -433.542448) (xy 345.218004 -433.541932) (xy 346.157804 -433.541932)
			(xy 346.169916 -433.542313) (xy 346.192949 -433.549818) (xy 346.212525 -433.564087) (xy 346.226718 -433.583718)
			(xy 346.234133 -433.60678) (xy 346.234512 -433.618894) (xy 346.234512 -436.160418) (xy 346.234107 -436.172513)
			(xy 346.22664 -436.195523) (xy 346.212439 -436.215106) (xy 346.192889 -436.229355) (xy 346.169898 -436.236878)
			(xy 346.157804 -436.23738) (xy 345.218004 -436.23738) (xy 345.205893 -436.23698) (xy 345.182863 -436.229479)
			(xy 345.163288 -436.215214) (xy 345.149094 -436.195588) (xy 345.141676 -436.17253) (xy 345.141296 -436.160418)
			(xy 344.206695 -436.160418) (xy 344.212364 -436.164536) (xy 344.226615 -436.184156) (xy 344.2341 -436.207221)
			(xy 344.234516 -436.219346) (xy 344.234516 -438.76087) (xy 344.234114 -438.772996) (xy 344.226624 -438.796061)
			(xy 344.21237 -438.815681) (xy 344.192747 -438.829932) (xy 344.16968 -438.837416) (xy 344.157554 -438.837832)
			(xy 343.217754 -438.837832) (xy 343.205634 -438.837427) (xy 343.182584 -438.829923) (xy 343.162981 -438.815665)
			(xy 343.148742 -438.796048) (xy 343.141261 -438.77299) (xy 343.140792 -438.76087) (xy 342.23452 -438.76087)
			(xy 342.23452 -439.760868) (xy 345.140788 -439.760868) (xy 345.140788 -437.219344) (xy 345.141297 -437.207297)
			(xy 345.148716 -437.184375) (xy 345.162845 -437.16486) (xy 345.182304 -437.150654) (xy 345.205197 -437.143145)
			(xy 345.217242 -437.142636) (xy 346.15755 -437.142636) (xy 346.169637 -437.14315) (xy 346.192635 -437.150592)
			(xy 346.212215 -437.164767) (xy 346.226468 -437.184291) (xy 346.234002 -437.207259) (xy 346.234512 -437.219344)
			(xy 346.234512 -438.76087) (xy 381.240792 -438.76087) (xy 381.240792 -436.219346) (xy 381.24135 -436.207238)
			(xy 381.248819 -436.184204) (xy 381.26304 -436.164606) (xy 381.282622 -436.150361) (xy 381.305647 -436.142865)
			(xy 381.317754 -436.142384) (xy 382.257554 -436.142384) (xy 382.269679 -436.1428) (xy 382.292744 -436.150285)
			(xy 382.306695 -436.160418) (xy 383.241296 -436.160418) (xy 383.241296 -435.433216) (xy 383.241561 -435.42446)
			(xy 383.245531 -435.407402) (xy 383.24917 -435.399434) (xy 383.482596 -434.923184) (xy 383.487296 -434.912667)
			(xy 383.490787 -434.889909) (xy 383.487302 -434.86715) (xy 383.482596 -434.856636) (xy 383.24917 -434.380386)
			(xy 383.245501 -434.372428) (xy 383.24153 -434.355364) (xy 383.241296 -434.346604) (xy 383.241296 -433.618894)
			(xy 383.241802 -433.606809) (xy 383.249255 -433.583815) (xy 383.263433 -433.564239) (xy 383.282955 -433.549987)
			(xy 383.30592 -433.542448) (xy 383.318004 -433.541932) (xy 384.257804 -433.541932) (xy 384.269916 -433.542313)
			(xy 384.292949 -433.549818) (xy 384.312525 -433.564087) (xy 384.326718 -433.583718) (xy 384.334133 -433.60678)
			(xy 384.334512 -433.618894) (xy 384.334512 -435.16042) (xy 385.241292 -435.16042) (xy 385.241292 -434.433218)
			(xy 385.241558 -434.424462) (xy 385.245528 -434.407404) (xy 385.249166 -434.399436) (xy 385.482592 -433.923186)
			(xy 385.487291 -433.912669) (xy 385.490783 -433.889911) (xy 385.487298 -433.867152) (xy 385.482592 -433.856638)
			(xy 385.249166 -433.380388) (xy 385.245498 -433.37243) (xy 385.241526 -433.355366) (xy 385.241292 -433.346606)
			(xy 385.241292 -432.618896) (xy 385.241761 -432.606821) (xy 385.249224 -432.583854) (xy 385.26342 -432.564317)
			(xy 385.282958 -432.550123) (xy 385.305925 -432.54266) (xy 385.318 -432.542188) (xy 386.2578 -432.542188)
			(xy 386.269874 -432.542664) (xy 386.292841 -432.550126) (xy 386.307086 -432.560476) (xy 387.241288 -432.560476)
			(xy 387.241288 -431.833274) (xy 387.24154 -431.824517) (xy 387.245519 -431.80746) (xy 387.249162 -431.799492)
			(xy 387.482588 -431.323242) (xy 387.487318 -431.312736) (xy 387.490799 -431.289971) (xy 387.487301 -431.267208)
			(xy 387.482588 -431.256694) (xy 387.249162 -430.780444) (xy 387.245511 -430.772479) (xy 387.241529 -430.755421)
			(xy 387.241288 -430.746662) (xy 387.241288 -430.018952) (xy 387.241723 -430.006875) (xy 387.249198 -429.983907)
			(xy 387.263403 -429.964371) (xy 387.282947 -429.950178) (xy 387.305919 -429.942716) (xy 387.317996 -429.942244)
			(xy 388.257796 -429.942244) (xy 388.269866 -429.942767) (xy 388.292824 -429.950222) (xy 388.312357 -429.964406)
			(xy 388.326554 -429.983929) (xy 388.334025 -430.006883) (xy 388.334504 -430.018952) (xy 388.334504 -431.560478)
			(xy 389.241284 -431.560478) (xy 389.241284 -430.833276) (xy 389.241537 -430.824519) (xy 389.245516 -430.807462)
			(xy 389.249158 -430.799494) (xy 389.482584 -430.323244) (xy 389.487313 -430.312738) (xy 389.490794 -430.289973)
			(xy 389.487297 -430.26721) (xy 389.482584 -430.256696) (xy 389.249158 -429.780446) (xy 389.245508 -429.77248)
			(xy 389.241525 -429.755422) (xy 389.241284 -429.746664) (xy 389.241284 -429.018954) (xy 389.241669 -429.006858)
			(xy 389.249144 -428.983848) (xy 389.26335 -428.964265) (xy 389.282903 -428.950018) (xy 389.305897 -428.942495)
			(xy 389.317992 -428.941992) (xy 390.257792 -428.941992) (xy 390.2699 -428.942423) (xy 390.292925 -428.949919)
			(xy 390.307846 -428.960788) (xy 391.24128 -428.960788) (xy 391.24128 -426.419264) (xy 391.241733 -426.407189)
			(xy 391.249204 -426.384222) (xy 391.263404 -426.364687) (xy 391.282944 -426.350493) (xy 391.305913 -426.343029)
			(xy 391.317988 -426.342556) (xy 392.257788 -426.342556) (xy 392.269858 -426.343074) (xy 392.292819 -426.350529)
			(xy 392.312353 -426.364713) (xy 392.326549 -426.384238) (xy 392.334019 -426.407194) (xy 392.334496 -426.419264)
			(xy 392.334496 -427.96079) (xy 393.241276 -427.96079) (xy 393.241276 -425.419266) (xy 393.241679 -425.407171)
			(xy 393.249149 -425.384163) (xy 393.263351 -425.364581) (xy 393.2829 -425.350333) (xy 393.30589 -425.342808)
			(xy 393.317984 -425.342304) (xy 394.257784 -425.342304) (xy 394.269892 -425.34273) (xy 394.29292 -425.350226)
			(xy 394.312493 -425.364485) (xy 394.326688 -425.384105) (xy 394.334109 -425.407156) (xy 394.334492 -425.419266)
			(xy 394.334492 -427.96079) (xy 394.333985 -427.972876) (xy 394.326535 -427.995871) (xy 394.312357 -428.015448)
			(xy 394.292834 -428.0297) (xy 394.269868 -428.037238) (xy 394.257784 -428.037752) (xy 393.317984 -428.037752)
			(xy 393.305879 -428.037298) (xy 393.282861 -428.029801) (xy 393.263292 -428.015547) (xy 393.249096 -427.995937)
			(xy 393.241667 -427.972896) (xy 393.241276 -427.96079) (xy 392.334496 -427.96079) (xy 392.334496 -428.960788)
			(xy 392.334077 -428.972871) (xy 392.326611 -428.995856) (xy 392.312407 -429.015407) (xy 392.292856 -429.029611)
			(xy 392.269871 -429.037077) (xy 392.257788 -429.037496) (xy 391.317988 -429.037496) (xy 391.305912 -429.037046)
			(xy 391.282942 -429.029578) (xy 391.263404 -429.015379) (xy 391.249211 -428.995836) (xy 391.241751 -428.972865)
			(xy 391.24128 -428.960788) (xy 390.307846 -428.960788) (xy 390.312498 -428.964177) (xy 390.326693 -428.983795)
			(xy 390.334116 -429.006845) (xy 390.3345 -429.018954) (xy 390.3345 -431.560478) (xy 390.333975 -431.572562)
			(xy 390.326529 -431.595556) (xy 390.312356 -431.615132) (xy 390.292837 -431.629385) (xy 390.269874 -431.636925)
			(xy 390.257792 -431.63744) (xy 389.317992 -431.63744) (xy 389.305887 -431.636991) (xy 389.282866 -431.629494)
			(xy 389.263296 -431.61524) (xy 389.249101 -431.595628) (xy 389.241673 -431.572585) (xy 389.241284 -431.560478)
			(xy 388.334504 -431.560478) (xy 388.334504 -432.560476) (xy 388.334067 -432.572558) (xy 388.326605 -432.59554)
			(xy 388.312406 -432.615091) (xy 388.292858 -432.629296) (xy 388.269878 -432.636764) (xy 388.257796 -432.637184)
			(xy 387.317996 -432.637184) (xy 387.305911 -432.636791) (xy 387.282924 -432.629319) (xy 387.263371 -432.615109)
			(xy 387.249168 -432.595551) (xy 387.241705 -432.572562) (xy 387.241288 -432.560476) (xy 386.307086 -432.560476)
			(xy 386.312377 -432.56432) (xy 386.326572 -432.583856) (xy 386.334035 -432.606822) (xy 386.334508 -432.618896)
			(xy 386.334508 -435.16042) (xy 386.334053 -435.172496) (xy 386.326585 -435.195463) (xy 386.312386 -435.215)
			(xy 386.292845 -435.229194) (xy 386.269876 -435.236656) (xy 386.2578 -435.237128) (xy 385.318 -435.237128)
			(xy 385.305927 -435.236636) (xy 385.282964 -435.229176) (xy 385.263428 -435.214986) (xy 385.249233 -435.195454)
			(xy 385.241767 -435.172492) (xy 385.241292 -435.16042) (xy 384.334512 -435.16042) (xy 384.334512 -436.160418)
			(xy 384.334107 -436.172513) (xy 384.32664 -436.195523) (xy 384.312439 -436.215106) (xy 384.292889 -436.229355)
			(xy 384.269898 -436.236878) (xy 384.257804 -436.23738) (xy 383.318004 -436.23738) (xy 383.305893 -436.23698)
			(xy 383.282863 -436.229479) (xy 383.263288 -436.215214) (xy 383.249094 -436.195588) (xy 383.241676 -436.17253)
			(xy 383.241296 -436.160418) (xy 382.306695 -436.160418) (xy 382.312364 -436.164536) (xy 382.326615 -436.184156)
			(xy 382.3341 -436.207221) (xy 382.334516 -436.219346) (xy 382.334516 -438.76087) (xy 382.334114 -438.772996)
			(xy 382.326624 -438.796061) (xy 382.31237 -438.815681) (xy 382.292747 -438.829932) (xy 382.26968 -438.837416)
			(xy 382.257554 -438.837832) (xy 381.317754 -438.837832) (xy 381.305634 -438.837427) (xy 381.282584 -438.829923)
			(xy 381.262981 -438.815665) (xy 381.248742 -438.796048) (xy 381.241261 -438.77299) (xy 381.240792 -438.76087)
			(xy 346.234512 -438.76087) (xy 346.234512 -439.760868) (xy 383.240788 -439.760868) (xy 383.240788 -437.219344)
			(xy 383.241297 -437.207297) (xy 383.248716 -437.184375) (xy 383.262845 -437.16486) (xy 383.282304 -437.150654)
			(xy 383.305197 -437.143145) (xy 383.317242 -437.142636) (xy 384.25755 -437.142636) (xy 384.269637 -437.14315)
			(xy 384.292635 -437.150592) (xy 384.312215 -437.164767) (xy 384.326468 -437.184291) (xy 384.334002 -437.207259)
			(xy 384.334512 -437.219344) (xy 384.334512 -438.76087) (xy 385.240784 -438.76087) (xy 385.240784 -436.219346)
			(xy 385.2412 -436.207221) (xy 385.248685 -436.184156) (xy 385.262936 -436.164536) (xy 385.282556 -436.150285)
			(xy 385.305621 -436.1428) (xy 385.317746 -436.142384) (xy 386.257546 -436.142384) (xy 386.269668 -436.142773)
			(xy 386.29272 -436.150279) (xy 386.306658 -436.160418) (xy 387.241288 -436.160418) (xy 387.241288 -435.433216)
			(xy 387.241554 -435.42446) (xy 387.245523 -435.407402) (xy 387.249162 -435.399434) (xy 387.482588 -434.923184)
			(xy 387.487289 -434.912667) (xy 387.49078 -434.889909) (xy 387.487294 -434.86715) (xy 387.482588 -434.856636)
			(xy 387.249162 -434.380386) (xy 387.245493 -434.372428) (xy 387.241522 -434.355364) (xy 387.241288 -434.346604)
			(xy 387.241288 -433.618894) (xy 387.241703 -433.606799) (xy 387.249168 -433.583791) (xy 387.263366 -433.564207)
			(xy 387.282913 -433.549958) (xy 387.305903 -433.542435) (xy 387.317996 -433.541932) (xy 388.257796 -433.541932)
			(xy 388.269908 -433.54232) (xy 388.292941 -433.549822) (xy 388.312517 -433.56409) (xy 388.32671 -433.58372)
			(xy 388.334125 -433.606781) (xy 388.334504 -433.618894) (xy 388.334504 -435.16042) (xy 389.241284 -435.16042)
			(xy 389.241284 -434.433218) (xy 389.241551 -434.424462) (xy 389.24552 -434.407404) (xy 389.249158 -434.399436)
			(xy 389.482584 -433.923186) (xy 389.487284 -433.912669) (xy 389.490776 -433.889911) (xy 389.48729 -433.867152)
			(xy 389.482584 -433.856638) (xy 389.249158 -433.380388) (xy 389.245489 -433.37243) (xy 389.241518 -433.355366)
			(xy 389.241284 -433.346606) (xy 389.241284 -432.618896) (xy 389.241761 -432.606822) (xy 389.249223 -432.583856)
			(xy 389.263417 -432.56432) (xy 389.282953 -432.550125) (xy 389.305918 -432.542661) (xy 389.317992 -432.542188)
			(xy 390.257792 -432.542188) (xy 390.269874 -432.542619) (xy 390.292856 -432.550084) (xy 390.307161 -432.560476)
			(xy 391.24128 -432.560476) (xy 391.24128 -431.833274) (xy 391.241533 -431.824517) (xy 391.245511 -431.80746)
			(xy 391.249154 -431.799492) (xy 391.48258 -431.323242) (xy 391.48731 -431.312737) (xy 391.490791 -431.289971)
			(xy 391.487293 -431.267208) (xy 391.48258 -431.256694) (xy 391.249154 -430.780444) (xy 391.245503 -430.772479)
			(xy 391.24152 -430.755421) (xy 391.24128 -430.746662) (xy 391.24128 -430.018952) (xy 391.241723 -430.006876)
			(xy 391.249197 -429.983909) (xy 391.2634 -429.964374) (xy 391.282942 -429.950181) (xy 391.305912 -429.942717)
			(xy 391.317988 -429.942244) (xy 392.257788 -429.942244) (xy 392.269857 -429.942774) (xy 392.292816 -429.950227)
			(xy 392.312349 -429.964408) (xy 392.326546 -429.98393) (xy 392.334017 -430.006883) (xy 392.334496 -430.018952)
			(xy 392.334496 -431.560478) (xy 393.241276 -431.560478) (xy 393.241276 -430.833276) (xy 393.24153 -430.824519)
			(xy 393.245508 -430.807462) (xy 393.24915 -430.799494) (xy 393.482576 -430.323244) (xy 393.487305 -430.312738)
			(xy 393.490787 -430.289973) (xy 393.487289 -430.26721) (xy 393.482576 -430.256696) (xy 393.24915 -429.780446)
			(xy 393.245499 -429.772481) (xy 393.241517 -429.755423) (xy 393.241276 -429.746664) (xy 393.241276 -429.018954)
			(xy 393.241669 -429.006858) (xy 393.249143 -428.98385) (xy 393.263347 -428.964268) (xy 393.282898 -428.95002)
			(xy 393.30589 -428.942496) (xy 393.317984 -428.941992) (xy 394.257784 -428.941992) (xy 394.269891 -428.94243)
			(xy 394.292917 -428.949924) (xy 394.307832 -428.960788) (xy 395.241272 -428.960788) (xy 395.241272 -426.419264)
			(xy 395.241733 -426.40719) (xy 395.249203 -426.384224) (xy 395.263401 -426.36469) (xy 395.282939 -426.350496)
			(xy 395.305905 -426.343031) (xy 395.31798 -426.342556) (xy 396.25778 -426.342556) (xy 396.26985 -426.343081)
			(xy 396.29281 -426.350533) (xy 396.312345 -426.364715) (xy 396.326541 -426.384239) (xy 396.334011 -426.407194)
			(xy 396.334488 -426.419264) (xy 396.334488 -427.96079) (xy 398.241012 -427.96079) (xy 398.241012 -425.419266)
			(xy 398.241482 -425.407152) (xy 398.248976 -425.384112) (xy 398.263219 -425.364513) (xy 398.282819 -425.350272)
			(xy 398.30586 -425.342781) (xy 398.317974 -425.342304) (xy 399.257774 -425.342304) (xy 399.269884 -425.342833)
			(xy 399.29292 -425.350309) (xy 399.31252 -425.364538) (xy 399.326763 -425.384126) (xy 399.334257 -425.407157)
			(xy 399.334736 -425.419266) (xy 399.334736 -427.96079) (xy 399.334331 -427.972915) (xy 399.326838 -427.995978)
			(xy 399.312584 -428.015595) (xy 399.292963 -428.029846) (xy 399.269899 -428.037334) (xy 399.257774 -428.037752)
			(xy 398.317974 -428.037752) (xy 398.305857 -428.03731) (xy 398.282811 -428.029815) (xy 398.263209 -428.015565)
			(xy 398.248969 -427.995956) (xy 398.241484 -427.972907) (xy 398.241012 -427.96079) (xy 396.334488 -427.96079)
			(xy 396.334488 -428.960788) (xy 396.334077 -428.972872) (xy 396.32661 -428.995858) (xy 396.312404 -429.01541)
			(xy 396.292851 -429.029614) (xy 396.269864 -429.037078) (xy 396.25778 -429.037496) (xy 395.31798 -429.037496)
			(xy 395.305903 -429.037052) (xy 395.282933 -429.029583) (xy 395.263396 -429.015381) (xy 395.249202 -428.995838)
			(xy 395.241743 -428.972865) (xy 395.241272 -428.960788) (xy 394.307832 -428.960788) (xy 394.312489 -428.96418)
			(xy 394.326685 -428.983797) (xy 394.334107 -429.006846) (xy 394.334492 -429.018954) (xy 394.334492 -431.560478)
			(xy 394.333974 -431.572563) (xy 394.326528 -431.595558) (xy 394.312353 -431.615135) (xy 394.292832 -431.629388)
			(xy 394.269867 -431.636926) (xy 394.257784 -431.63744) (xy 393.317984 -431.63744) (xy 393.305878 -431.636998)
			(xy 393.282857 -431.629499) (xy 393.263288 -431.615243) (xy 393.249092 -431.595629) (xy 393.241665 -431.572585)
			(xy 393.241276 -431.560478) (xy 392.334496 -431.560478) (xy 392.334496 -432.560476) (xy 392.334067 -432.572559)
			(xy 392.326604 -432.595543) (xy 392.312403 -432.615094) (xy 392.292853 -432.629299) (xy 392.269871 -432.636765)
			(xy 392.257788 -432.637184) (xy 391.317988 -432.637184) (xy 391.305902 -432.636797) (xy 391.282915 -432.629324)
			(xy 391.263363 -432.615112) (xy 391.24916 -432.595553) (xy 391.241697 -432.572562) (xy 391.24128 -432.560476)
			(xy 390.307161 -432.560476) (xy 390.312406 -432.564286) (xy 390.326611 -432.583833) (xy 390.334079 -432.606814)
			(xy 390.3345 -432.618896) (xy 390.3345 -435.16042) (xy 390.334053 -435.172496) (xy 390.326584 -435.195465)
			(xy 390.312383 -435.215003) (xy 390.29284 -435.229196) (xy 390.269869 -435.236657) (xy 390.257792 -435.237128)
			(xy 389.317992 -435.237128) (xy 389.305919 -435.236643) (xy 389.282955 -435.229181) (xy 389.26342 -435.214989)
			(xy 389.249225 -435.195456) (xy 389.241759 -435.172493) (xy 389.241284 -435.16042) (xy 388.334504 -435.16042)
			(xy 388.334504 -436.160418) (xy 388.334009 -436.172504) (xy 388.326553 -436.195498) (xy 388.312372 -436.215074)
			(xy 388.292847 -436.229325) (xy 388.26988 -436.236865) (xy 388.257796 -436.23738) (xy 387.317996 -436.23738)
			(xy 387.305885 -436.236987) (xy 387.282854 -436.229484) (xy 387.263279 -436.215217) (xy 387.249085 -436.195589)
			(xy 387.241668 -436.172531) (xy 387.241288 -436.160418) (xy 386.306658 -436.160418) (xy 386.312325 -436.16454)
			(xy 386.326563 -436.184162) (xy 386.334041 -436.207224) (xy 386.334508 -436.219346) (xy 386.334508 -438.76087)
			(xy 386.333963 -438.772978) (xy 386.32649 -438.796013) (xy 386.312265 -438.815611) (xy 386.292681 -438.829855)
			(xy 386.269654 -438.837351) (xy 386.257546 -438.837832) (xy 385.317746 -438.837832) (xy 385.305623 -438.837401)
			(xy 385.28256 -438.829917) (xy 385.262942 -438.81567) (xy 385.24869 -438.796054) (xy 385.241202 -438.772993)
			(xy 385.240784 -438.76087) (xy 384.334512 -438.76087) (xy 384.334512 -439.760868) (xy 387.24078 -439.760868)
			(xy 387.24078 -437.219344) (xy 387.241297 -437.207298) (xy 387.248715 -437.184377) (xy 387.262842 -437.164862)
			(xy 387.282299 -437.150657) (xy 387.30519 -437.143146) (xy 387.317234 -437.142636) (xy 388.257542 -437.142636)
			(xy 388.269633 -437.143071) (xy 388.292635 -437.150539) (xy 388.312214 -437.164734) (xy 388.326463 -437.184274)
			(xy 388.333995 -437.207254) (xy 388.334504 -437.219344) (xy 388.334504 -438.76087) (xy 389.240776 -438.76087)
			(xy 389.240776 -436.219346) (xy 389.2412 -436.207222) (xy 389.248684 -436.184158) (xy 389.262933 -436.164539)
			(xy 389.282551 -436.150287) (xy 389.305614 -436.142801) (xy 389.317738 -436.142384) (xy 390.257538 -436.142384)
			(xy 390.269667 -436.142728) (xy 390.292735 -436.150237) (xy 390.306733 -436.160418) (xy 391.24128 -436.160418)
			(xy 391.24128 -435.433216) (xy 391.241546 -435.42446) (xy 391.245516 -435.407402) (xy 391.249154 -435.399434)
			(xy 391.48258 -434.923184) (xy 391.487281 -434.912667) (xy 391.490773 -434.889909) (xy 391.487287 -434.86715)
			(xy 391.48258 -434.856636) (xy 391.249154 -434.380386) (xy 391.245485 -434.372428) (xy 391.241514 -434.355364)
			(xy 391.24128 -434.346604) (xy 391.24128 -433.618894) (xy 391.241703 -433.6068) (xy 391.249166 -433.583793)
			(xy 391.263363 -433.564209) (xy 391.282908 -433.549961) (xy 391.305896 -433.542436) (xy 391.317988 -433.541932)
			(xy 392.257788 -433.541932) (xy 392.269899 -433.542327) (xy 392.292932 -433.549827) (xy 392.312508 -433.564093)
			(xy 392.326702 -433.583721) (xy 392.334117 -433.606781) (xy 392.334496 -433.618894) (xy 392.334496 -435.16042)
			(xy 393.241276 -435.16042) (xy 393.241276 -434.433218) (xy 393.241544 -434.424462) (xy 393.245512 -434.407405)
			(xy 393.24915 -434.399436) (xy 393.482576 -433.923186) (xy 393.487276 -433.912669) (xy 393.490768 -433.889911)
			(xy 393.487283 -433.867152) (xy 393.482576 -433.856638) (xy 393.24915 -433.380388) (xy 393.245481 -433.37243)
			(xy 393.24151 -433.355366) (xy 393.241276 -433.346606) (xy 393.241276 -432.618896) (xy 393.241761 -432.606823)
			(xy 393.249222 -432.583858) (xy 393.263414 -432.564323) (xy 393.282948 -432.550128) (xy 393.305911 -432.542663)
			(xy 393.317984 -432.542188) (xy 394.257784 -432.542188) (xy 394.269865 -432.542626) (xy 394.292847 -432.550089)
			(xy 394.307147 -432.560476) (xy 395.241272 -432.560476) (xy 395.241272 -431.833274) (xy 395.241526 -431.824517)
			(xy 395.245504 -431.80746) (xy 395.249146 -431.799492) (xy 395.482572 -431.323242) (xy 395.487303 -431.312737)
			(xy 395.490784 -431.289971) (xy 395.487285 -431.267208) (xy 395.482572 -431.256694) (xy 395.249146 -430.780444)
			(xy 395.245494 -430.772479) (xy 395.241512 -430.755421) (xy 395.241272 -430.746662) (xy 395.241272 -430.018952)
			(xy 395.241723 -430.006877) (xy 395.249196 -429.983912) (xy 395.263397 -429.964377) (xy 395.282937 -429.950183)
			(xy 395.305905 -429.942718) (xy 395.31798 -429.942244) (xy 396.25778 -429.942244) (xy 396.269849 -429.94278)
			(xy 396.292807 -429.950232) (xy 396.31234 -429.964411) (xy 396.326537 -429.983932) (xy 396.334009 -430.006884)
			(xy 396.334488 -430.018952) (xy 396.334488 -431.560478) (xy 398.24152 -431.560478) (xy 398.24152 -430.833276)
			(xy 398.24177 -430.824519) (xy 398.24575 -430.807461) (xy 398.249394 -430.799494) (xy 398.48282 -430.323244)
			(xy 398.487547 -430.312738) (xy 398.491027 -430.289973) (xy 398.487531 -430.267211) (xy 398.48282 -430.256696)
			(xy 398.249394 -429.780446) (xy 398.245746 -429.77248) (xy 398.241761 -429.755422) (xy 398.24152 -429.746664)
			(xy 398.24152 -429.018954) (xy 398.241968 -429.006864) (xy 398.249435 -428.983865) (xy 398.263627 -428.964288)
			(xy 398.283163 -428.950038) (xy 398.306139 -428.942504) (xy 398.318228 -428.941992) (xy 399.258028 -428.941992)
			(xy 399.270138 -428.942392) (xy 399.293164 -428.949899) (xy 399.308103 -428.960788) (xy 400.241008 -428.960788)
			(xy 400.241008 -426.419264) (xy 400.241429 -426.407211) (xy 400.248873 -426.384283) (xy 400.263023 -426.364767)
			(xy 400.282502 -426.350565) (xy 400.30541 -426.343061) (xy 400.317462 -426.342556) (xy 401.25777 -426.342556)
			(xy 401.26986 -426.343033) (xy 401.292862 -426.350484) (xy 401.312444 -426.364667) (xy 401.326695 -426.3842)
			(xy 401.334225 -426.407176) (xy 401.334732 -426.419264) (xy 401.334732 -427.96079) (xy 402.241004 -427.96079)
			(xy 402.241004 -425.419266) (xy 402.241482 -425.407153) (xy 402.248975 -425.384114) (xy 402.263216 -425.364516)
			(xy 402.282814 -425.350275) (xy 402.305853 -425.342782) (xy 402.317966 -425.342304) (xy 403.257766 -425.342304)
			(xy 403.269875 -425.34284) (xy 403.292912 -425.350314) (xy 403.312511 -425.36454) (xy 403.326755 -425.384127)
			(xy 403.334249 -425.407157) (xy 403.334728 -425.419266) (xy 403.334728 -427.96079) (xy 403.334331 -427.972916)
			(xy 403.326837 -427.99598) (xy 403.312581 -428.015598) (xy 403.292958 -428.029848) (xy 403.269892 -428.037335)
			(xy 403.257766 -428.037752) (xy 402.317966 -428.037752) (xy 402.305849 -428.037317) (xy 402.282803 -428.029819)
			(xy 402.263201 -428.015568) (xy 402.248961 -427.995958) (xy 402.241476 -427.972908) (xy 402.241004 -427.96079)
			(xy 401.334732 -427.96079) (xy 401.334732 -428.960788) (xy 401.33423 -428.972834) (xy 401.326805 -428.995754)
			(xy 401.312674 -429.015267) (xy 401.293214 -429.029472) (xy 401.270323 -429.036984) (xy 401.258278 -429.037496)
			(xy 400.31797 -429.037496) (xy 400.305882 -429.037019) (xy 400.282887 -429.029558) (xy 400.263311 -429.015373)
			(xy 400.24906 -428.995844) (xy 400.241522 -428.972874) (xy 400.241008 -428.960788) (xy 399.308103 -428.960788)
			(xy 399.312736 -428.964165) (xy 399.32693 -428.983789) (xy 399.334352 -429.006843) (xy 399.334736 -429.018954)
			(xy 399.334736 -431.560478) (xy 399.334273 -431.572569) (xy 399.32682 -431.595573) (xy 399.312633 -431.615155)
			(xy 399.293097 -431.629405) (xy 399.270117 -431.636934) (xy 399.258028 -431.63744) (xy 398.318228 -431.63744)
			(xy 398.306125 -431.63696) (xy 398.283105 -431.629473) (xy 398.263535 -431.615227) (xy 398.249338 -431.595621)
			(xy 398.241909 -431.572582) (xy 398.24152 -431.560478) (xy 396.334488 -431.560478) (xy 396.334488 -432.560476)
			(xy 396.334066 -432.572559) (xy 396.326603 -432.595545) (xy 396.3124 -432.615097) (xy 396.292848 -432.629301)
			(xy 396.269863 -432.636766) (xy 396.25778 -432.637184) (xy 395.31798 -432.637184) (xy 395.305894 -432.636804)
			(xy 395.282906 -432.629328) (xy 395.263354 -432.615114) (xy 395.249152 -432.595554) (xy 395.241689 -432.572562)
			(xy 395.241272 -432.560476) (xy 394.307147 -432.560476) (xy 394.312397 -432.564289) (xy 394.326602 -432.583835)
			(xy 394.33407 -432.606815) (xy 394.334492 -432.618896) (xy 394.334492 -435.16042) (xy 394.334052 -435.172497)
			(xy 394.326582 -435.195468) (xy 394.31238 -435.215006) (xy 394.292835 -435.229199) (xy 394.269861 -435.236658)
			(xy 394.257784 -435.237128) (xy 393.317984 -435.237128) (xy 393.305911 -435.23665) (xy 393.282946 -435.229185)
			(xy 393.263411 -435.214991) (xy 393.249217 -435.195457) (xy 393.241751 -435.172493) (xy 393.241276 -435.16042)
			(xy 392.334496 -435.16042) (xy 392.334496 -436.160418) (xy 392.334009 -436.172505) (xy 392.326552 -436.1955)
			(xy 392.312369 -436.215077) (xy 392.292842 -436.229328) (xy 392.269873 -436.236866) (xy 392.257788 -436.23738)
			(xy 391.317988 -436.23738) (xy 391.305876 -436.236994) (xy 391.282845 -436.229489) (xy 391.263271 -436.21522)
			(xy 391.249077 -436.195591) (xy 391.24166 -436.172531) (xy 391.24128 -436.160418) (xy 390.306733 -436.160418)
			(xy 390.312354 -436.164506) (xy 390.326602 -436.18414) (xy 390.334085 -436.207216) (xy 390.3345 -436.219346)
			(xy 390.3345 -438.76087) (xy 390.333963 -438.772979) (xy 390.326489 -438.796015) (xy 390.312262 -438.815614)
			(xy 390.292676 -438.829858) (xy 390.269647 -438.837353) (xy 390.257538 -438.837832) (xy 389.317738 -438.837832)
			(xy 389.305614 -438.837407) (xy 389.282551 -438.829922) (xy 389.262933 -438.815673) (xy 389.248682 -438.796056)
			(xy 389.241194 -438.772994) (xy 389.240776 -438.76087) (xy 388.334504 -438.76087) (xy 388.334504 -439.760868)
			(xy 391.240772 -439.760868) (xy 391.240772 -437.219344) (xy 391.241297 -437.207299) (xy 391.248714 -437.184379)
			(xy 391.262839 -437.164865) (xy 391.282294 -437.150659) (xy 391.305183 -437.143147) (xy 391.317226 -437.142636)
			(xy 392.257534 -437.142636) (xy 392.269625 -437.143078) (xy 392.292626 -437.150544) (xy 392.312205 -437.164737)
			(xy 392.326455 -437.184275) (xy 392.333986 -437.207254) (xy 392.334496 -437.219344) (xy 392.334496 -438.76087)
			(xy 393.240768 -438.76087) (xy 393.240768 -436.219346) (xy 393.241199 -436.207223) (xy 393.248683 -436.18416)
			(xy 393.26293 -436.164542) (xy 393.282546 -436.15029) (xy 393.305607 -436.142802) (xy 393.31773 -436.142384)
			(xy 394.25753 -436.142384) (xy 394.269659 -436.142735) (xy 394.292727 -436.150241) (xy 394.30672 -436.160418)
			(xy 395.241272 -436.160418) (xy 395.241272 -435.433216) (xy 395.241539 -435.42446) (xy 395.245508 -435.407403)
			(xy 395.249146 -435.399434) (xy 395.482572 -434.923184) (xy 395.487274 -434.912667) (xy 395.490766 -434.889909)
			(xy 395.487279 -434.86715) (xy 395.482572 -434.856636) (xy 395.249146 -434.380386) (xy 395.245476 -434.372428)
			(xy 395.241506 -434.355364) (xy 395.241272 -434.346604) (xy 395.241272 -433.618894) (xy 395.241703 -433.606801)
			(xy 395.249165 -433.583795) (xy 395.26336 -433.564212) (xy 395.282903 -433.549963) (xy 395.305888 -433.542437)
			(xy 395.31798 -433.541932) (xy 396.25778 -433.541932) (xy 396.269891 -433.542334) (xy 396.292923 -433.549832)
			(xy 396.312499 -433.564096) (xy 396.326693 -433.583723) (xy 396.334109 -433.606782) (xy 396.334488 -433.618894)
			(xy 396.334488 -435.16042) (xy 398.241012 -435.16042) (xy 398.241012 -434.433472) (xy 398.241338 -434.424703)
			(xy 398.245437 -434.407645) (xy 398.24914 -434.39969) (xy 398.24914 -434.399182) (xy 398.482566 -433.923186)
			(xy 398.487262 -433.912668) (xy 398.49075 -433.889911) (xy 398.487268 -433.867153) (xy 398.482566 -433.856638)
			(xy 398.24914 -433.380642) (xy 398.24914 -433.380134) (xy 398.245419 -433.372184) (xy 398.241311 -433.355124)
			(xy 398.241012 -433.346352) (xy 398.241012 -432.618896) (xy 398.241457 -432.606844) (xy 398.248892 -432.583917)
			(xy 398.263036 -432.5644) (xy 398.282511 -432.550197) (xy 398.305416 -432.542693) (xy 398.317466 -432.542188)
			(xy 399.257774 -432.542188) (xy 399.269867 -432.54263) (xy 399.292875 -432.550086) (xy 399.307214 -432.560476)
			(xy 400.241516 -432.560476) (xy 400.241516 -431.833274) (xy 400.241765 -431.824517) (xy 400.245746 -431.807459)
			(xy 400.24939 -431.799492) (xy 400.482816 -431.323242) (xy 400.487545 -431.312736) (xy 400.491024 -431.289971)
			(xy 400.487528 -431.267209) (xy 400.482816 -431.256694) (xy 400.24939 -430.780444) (xy 400.245741 -430.772478)
			(xy 400.241757 -430.75542) (xy 400.241516 -430.746662) (xy 400.241516 -430.018952) (xy 400.241924 -430.006873)
			(xy 400.249402 -429.9839) (xy 400.263613 -429.964361) (xy 400.283164 -429.950169) (xy 400.306144 -429.942712)
			(xy 400.318224 -429.942244) (xy 401.258024 -429.942244) (xy 401.270095 -429.942743) (xy 401.293055 -429.950206)
			(xy 401.312587 -429.964396) (xy 401.326783 -429.983924) (xy 401.334253 -430.006881) (xy 401.334732 -430.018952)
			(xy 401.334732 -431.560478) (xy 402.241512 -431.560478) (xy 402.241512 -430.833276) (xy 402.241762 -430.824519)
			(xy 402.245742 -430.807461) (xy 402.249386 -430.799494) (xy 402.482812 -430.323244) (xy 402.48754 -430.312738)
			(xy 402.49102 -430.289973) (xy 402.487523 -430.267211) (xy 402.482812 -430.256696) (xy 402.249386 -429.780446)
			(xy 402.245737 -429.77248) (xy 402.241753 -429.755422) (xy 402.241512 -429.746664) (xy 402.241512 -429.018954)
			(xy 402.241968 -429.006865) (xy 402.249434 -428.983867) (xy 402.263624 -428.964291) (xy 402.283158 -428.950041)
			(xy 402.306132 -428.942505) (xy 402.31822 -428.941992) (xy 403.25802 -428.941992) (xy 403.270129 -428.942399)
			(xy 403.293156 -428.949903) (xy 403.308092 -428.960788) (xy 404.241 -428.960788) (xy 404.241 -426.419264)
			(xy 404.241429 -426.407212) (xy 404.248872 -426.384285) (xy 404.263021 -426.36477) (xy 404.282497 -426.350568)
			(xy 404.305403 -426.343062) (xy 404.317454 -426.342556) (xy 405.257762 -426.342556) (xy 405.269851 -426.34304)
			(xy 405.292853 -426.350488) (xy 405.312435 -426.36467) (xy 405.326686 -426.384201) (xy 405.334217 -426.407177)
			(xy 405.334724 -426.419264) (xy 405.334724 -427.96079) (xy 406.240996 -427.96079) (xy 406.240996 -425.419266)
			(xy 406.241482 -425.407154) (xy 406.248973 -425.384117) (xy 406.263213 -425.364519) (xy 406.282809 -425.350277)
			(xy 406.305846 -425.342783) (xy 406.317958 -425.342304) (xy 407.257758 -425.342304) (xy 407.269875 -425.342795)
			(xy 407.292927 -425.350272) (xy 407.31254 -425.364506) (xy 407.326794 -425.384105) (xy 407.334293 -425.407149)
			(xy 407.33472 -425.419266) (xy 407.33472 -427.96079) (xy 407.334331 -427.972916) (xy 407.326836 -427.995982)
			(xy 407.312578 -428.015601) (xy 407.292953 -428.029851) (xy 407.269885 -428.037336) (xy 407.257758 -428.037752)
			(xy 406.317958 -428.037752) (xy 406.30584 -428.037324) (xy 406.282794 -428.029824) (xy 406.263192 -428.015571)
			(xy 406.248952 -427.995959) (xy 406.241468 -427.972908) (xy 406.240996 -427.96079) (xy 405.334724 -427.96079)
			(xy 405.334724 -428.960788) (xy 405.33423 -428.972835) (xy 405.326804 -428.995756) (xy 405.312671 -429.01527)
			(xy 405.293209 -429.029475) (xy 405.270315 -429.036986) (xy 405.25827 -429.037496) (xy 404.317962 -429.037496)
			(xy 404.305874 -429.037026) (xy 404.282878 -429.029563) (xy 404.263302 -429.015376) (xy 404.249051 -428.995846)
			(xy 404.241514 -428.972874) (xy 404.241 -428.960788) (xy 403.308092 -428.960788) (xy 403.312728 -428.964167)
			(xy 403.326922 -428.98379) (xy 403.334344 -429.006843) (xy 403.334728 -429.018954) (xy 403.334728 -431.560478)
			(xy 403.334273 -431.57257) (xy 403.326819 -431.595575) (xy 403.31263 -431.615158) (xy 403.293092 -431.629408)
			(xy 403.27011 -431.636935) (xy 403.25802 -431.63744) (xy 402.31822 -431.63744) (xy 402.306116 -431.636967)
			(xy 402.283096 -431.629478) (xy 402.263527 -431.61523) (xy 402.24933 -431.595622) (xy 402.241901 -431.572583)
			(xy 402.241512 -431.560478) (xy 401.334732 -431.560478) (xy 401.334732 -432.560476) (xy 401.334216 -432.572547)
			(xy 401.326763 -432.595509) (xy 401.312579 -432.615045) (xy 401.293052 -432.629241) (xy 401.270095 -432.636708)
			(xy 401.258024 -432.637184) (xy 400.318224 -432.637184) (xy 400.30614 -432.636766) (xy 400.283154 -432.629303)
			(xy 400.263601 -432.615099) (xy 400.249397 -432.595546) (xy 400.241934 -432.57256) (xy 400.241516 -432.560476)
			(xy 399.307214 -432.560476) (xy 399.312459 -432.564277) (xy 399.326709 -432.583819) (xy 399.334233 -432.606804)
			(xy 399.334736 -432.618896) (xy 399.334736 -435.16042) (xy 399.334258 -435.172468) (xy 399.326824 -435.195388)
			(xy 399.312686 -435.2149) (xy 399.293223 -435.229104) (xy 399.270328 -435.236616) (xy 399.258282 -435.237128)
			(xy 398.317974 -435.237128) (xy 398.30588 -435.236714) (xy 398.282873 -435.229247) (xy 398.263291 -435.215047)
			(xy 398.249042 -435.195501) (xy 398.241516 -435.172513) (xy 398.241012 -435.16042) (xy 396.334488 -435.16042)
			(xy 396.334488 -436.160418) (xy 396.334009 -436.172506) (xy 396.32655 -436.195502) (xy 396.312366 -436.21508)
			(xy 396.292837 -436.229331) (xy 396.269866 -436.236867) (xy 396.25778 -436.23738) (xy 395.31798 -436.23738)
			(xy 395.305868 -436.237001) (xy 395.282837 -436.229493) (xy 395.263262 -436.215223) (xy 395.249069 -436.195592)
			(xy 395.241652 -436.172532) (xy 395.241272 -436.160418) (xy 394.30672 -436.160418) (xy 394.312345 -436.164509)
			(xy 394.326594 -436.184142) (xy 394.334077 -436.207217) (xy 394.334492 -436.219346) (xy 394.334492 -438.76087)
			(xy 394.333963 -438.77298) (xy 394.326488 -438.796017) (xy 394.31226 -438.815617) (xy 394.292671 -438.82986)
			(xy 394.26964 -438.837354) (xy 394.25753 -438.837832) (xy 393.31773 -438.837832) (xy 393.305606 -438.837414)
			(xy 393.282543 -438.829926) (xy 393.262925 -438.815675) (xy 393.248674 -438.796057) (xy 393.241186 -438.772994)
			(xy 393.240768 -438.76087) (xy 392.334496 -438.76087) (xy 392.334496 -439.760868) (xy 395.240764 -439.760868)
			(xy 395.240764 -437.219344) (xy 395.241297 -437.2073) (xy 395.248713 -437.184382) (xy 395.262836 -437.164868)
			(xy 395.282289 -437.150662) (xy 395.305176 -437.143148) (xy 395.317218 -437.142636) (xy 396.257526 -437.142636)
			(xy 396.269617 -437.143085) (xy 396.292617 -437.150548) (xy 396.312197 -437.16474) (xy 396.326446 -437.184276)
			(xy 396.333978 -437.207255) (xy 396.334488 -437.219344) (xy 396.334488 -438.76087) (xy 398.241012 -438.76087)
			(xy 398.241012 -436.219346) (xy 398.241499 -436.207228) (xy 398.248975 -436.184175) (xy 398.26321 -436.164562)
			(xy 398.282811 -436.150308) (xy 398.305857 -436.14281) (xy 398.317974 -436.142384) (xy 399.257774 -436.142384)
			(xy 399.2699 -436.142783) (xy 399.292966 -436.150273) (xy 399.306927 -436.160418) (xy 400.241008 -436.160418)
			(xy 400.241008 -435.43347) (xy 400.241334 -435.424701) (xy 400.245433 -435.407643) (xy 400.249136 -435.399688)
			(xy 400.249136 -435.39918) (xy 400.482562 -434.923184) (xy 400.487259 -434.912666) (xy 400.490747 -434.889909)
			(xy 400.487265 -434.867151) (xy 400.482562 -434.856636) (xy 400.249136 -434.38064) (xy 400.249136 -434.380132)
			(xy 400.24542 -434.37218) (xy 400.241308 -434.355122) (xy 400.241008 -434.34635) (xy 400.241008 -433.618894)
			(xy 400.241506 -433.606782) (xy 400.248992 -433.583744) (xy 400.263228 -433.564145) (xy 400.282822 -433.549903)
			(xy 400.305858 -433.54241) (xy 400.31797 -433.541932) (xy 401.25777 -433.541932) (xy 401.269891 -433.542385)
			(xy 401.292947 -433.549869) (xy 401.312563 -433.564112) (xy 401.326815 -433.58372) (xy 401.334309 -433.606774)
			(xy 401.334732 -433.618894) (xy 401.334732 -435.16042) (xy 402.241004 -435.16042) (xy 402.241004 -434.433472)
			(xy 402.241331 -434.424703) (xy 402.245429 -434.407645) (xy 402.249132 -434.39969) (xy 402.249132 -434.399182)
			(xy 402.482558 -433.923186) (xy 402.487254 -433.912668) (xy 402.490743 -433.889911) (xy 402.487261 -433.867153)
			(xy 402.482558 -433.856638) (xy 402.249132 -433.380642) (xy 402.249132 -433.380134) (xy 402.245416 -433.372182)
			(xy 402.241304 -433.355124) (xy 402.241004 -433.346352) (xy 402.241004 -432.618896) (xy 402.241457 -432.606845)
			(xy 402.248891 -432.583919) (xy 402.263034 -432.564403) (xy 402.282506 -432.5502) (xy 402.305409 -432.542694)
			(xy 402.317458 -432.542188) (xy 403.257766 -432.542188) (xy 403.269859 -432.542637) (xy 403.292866 -432.55009)
			(xy 403.307201 -432.560476) (xy 404.241508 -432.560476) (xy 404.241508 -431.833274) (xy 404.241758 -431.824517)
			(xy 404.245738 -431.807459) (xy 404.249382 -431.799492) (xy 404.482808 -431.323242) (xy 404.487537 -431.312736)
			(xy 404.491017 -431.289971) (xy 404.48752 -431.267208) (xy 404.482808 -431.256694) (xy 404.249382 -430.780444)
			(xy 404.245732 -430.772478) (xy 404.241749 -430.75542) (xy 404.241508 -430.746662) (xy 404.241508 -430.018952)
			(xy 404.241923 -430.006873) (xy 404.249401 -429.983902) (xy 404.26361 -429.964364) (xy 404.283159 -429.950172)
			(xy 404.306137 -429.942713) (xy 404.318216 -429.942244) (xy 405.258016 -429.942244) (xy 405.270087 -429.94275)
			(xy 405.293046 -429.950211) (xy 405.312579 -429.964399) (xy 405.326774 -429.983925) (xy 405.334245 -430.006882)
			(xy 405.334724 -430.018952) (xy 405.334724 -431.560478) (xy 406.241504 -431.560478) (xy 406.241504 -430.833276)
			(xy 406.241755 -430.824519) (xy 406.245735 -430.807461) (xy 406.249378 -430.799494) (xy 406.482804 -430.323244)
			(xy 406.487532 -430.312738) (xy 406.491013 -430.289973) (xy 406.487516 -430.26721) (xy 406.482804 -430.256696)
			(xy 406.249378 -429.780446) (xy 406.245729 -429.77248) (xy 406.241745 -429.755422) (xy 406.241504 -429.746664)
			(xy 406.241504 -429.018954) (xy 406.241967 -429.006866) (xy 406.249432 -428.98387) (xy 406.263621 -428.964293)
			(xy 406.283153 -428.950043) (xy 406.306125 -428.942506) (xy 406.318212 -428.941992) (xy 407.258012 -428.941992)
			(xy 407.270121 -428.942406) (xy 407.293147 -428.949908) (xy 407.308078 -428.960788) (xy 408.240992 -428.960788)
			(xy 408.240992 -426.419264) (xy 408.241429 -426.407213) (xy 408.248871 -426.384287) (xy 408.263018 -426.364773)
			(xy 408.282492 -426.35057) (xy 408.305396 -426.343064) (xy 408.317446 -426.342556) (xy 409.257754 -426.342556)
			(xy 409.269843 -426.343047) (xy 409.292845 -426.350493) (xy 409.312427 -426.364673) (xy 409.326678 -426.384203)
			(xy 409.334209 -426.407177) (xy 409.334716 -426.419264) (xy 409.334716 -427.96079) (xy 410.240988 -427.96079)
			(xy 410.240988 -425.419266) (xy 410.241482 -425.407155) (xy 410.248972 -425.384119) (xy 410.26321 -425.364522)
			(xy 410.282804 -425.35028) (xy 410.305839 -425.342784) (xy 410.31795 -425.342304) (xy 411.25775 -425.342304)
			(xy 411.269864 -425.342769) (xy 411.292903 -425.350265) (xy 411.312501 -425.364511) (xy 411.326742 -425.384111)
			(xy 411.334234 -425.407152) (xy 411.334712 -425.419266) (xy 411.334712 -427.96079) (xy 411.33418 -427.972899)
			(xy 411.326702 -427.995933) (xy 411.312474 -428.015531) (xy 411.292887 -428.029775) (xy 411.269859 -428.037271)
			(xy 411.25775 -428.037752) (xy 410.31795 -428.037752) (xy 410.305832 -428.037331) (xy 410.282785 -428.029828)
			(xy 410.263184 -428.015574) (xy 410.248944 -427.995961) (xy 410.24146 -427.972909) (xy 410.240988 -427.96079)
			(xy 409.334716 -427.96079) (xy 409.334716 -428.960788) (xy 409.33423 -428.972836) (xy 409.326803 -428.995758)
			(xy 409.312668 -429.015273) (xy 409.293204 -429.029477) (xy 409.270308 -429.036987) (xy 409.258262 -429.037496)
			(xy 408.317954 -429.037496) (xy 408.305866 -429.037033) (xy 408.28287 -429.029568) (xy 408.263293 -429.015379)
			(xy 408.249043 -428.995847) (xy 408.241506 -428.972875) (xy 408.240992 -428.960788) (xy 407.308078 -428.960788)
			(xy 407.312719 -428.96417) (xy 407.326914 -428.983792) (xy 407.334336 -429.006844) (xy 407.33472 -429.018954)
			(xy 407.33472 -431.560478) (xy 407.334273 -431.57257) (xy 407.326818 -431.595577) (xy 407.312627 -431.615161)
			(xy 407.293087 -431.629411) (xy 407.270103 -431.636936) (xy 407.258012 -431.63744) (xy 406.318212 -431.63744)
			(xy 406.306108 -431.636974) (xy 406.283088 -431.629483) (xy 406.263518 -431.615232) (xy 406.249322 -431.595624)
			(xy 406.241893 -431.572583) (xy 406.241504 -431.560478) (xy 405.334724 -431.560478) (xy 405.334724 -432.560476)
			(xy 405.334267 -432.572556) (xy 405.326808 -432.595535) (xy 405.312613 -432.615084) (xy 405.293071 -432.62929)
			(xy 405.270096 -432.636761) (xy 405.258016 -432.637184) (xy 404.318216 -432.637184) (xy 404.306132 -432.636773)
			(xy 404.283146 -432.629307) (xy 404.263593 -432.615101) (xy 404.249389 -432.595547) (xy 404.241926 -432.57256)
			(xy 404.241508 -432.560476) (xy 403.307201 -432.560476) (xy 403.312451 -432.56428) (xy 403.326701 -432.583821)
			(xy 403.334225 -432.606805) (xy 403.334728 -432.618896) (xy 403.334728 -435.16042) (xy 403.334257 -435.172468)
			(xy 403.326823 -435.19539) (xy 403.312684 -435.214903) (xy 403.293217 -435.229106) (xy 403.270321 -435.236617)
			(xy 403.258274 -435.237128) (xy 402.317966 -435.237128) (xy 402.305871 -435.236721) (xy 402.282864 -435.229251)
			(xy 402.263282 -435.21505) (xy 402.249034 -435.195502) (xy 402.241508 -435.172513) (xy 402.241004 -435.16042)
			(xy 401.334732 -435.16042) (xy 401.334732 -436.160418) (xy 401.334355 -436.172545) (xy 401.326854 -436.195609)
			(xy 401.312592 -436.215226) (xy 401.292966 -436.229476) (xy 401.269897 -436.236962) (xy 401.25777 -436.23738)
			(xy 400.31797 -436.23738) (xy 400.305856 -436.236914) (xy 400.282814 -436.229421) (xy 400.263215 -436.215177)
			(xy 400.248974 -436.195575) (xy 400.241484 -436.172532) (xy 400.241008 -436.160418) (xy 399.306927 -436.160418)
			(xy 399.312585 -436.164529) (xy 399.326836 -436.184152) (xy 399.33432 -436.20722) (xy 399.334736 -436.219346)
			(xy 399.334736 -438.76087) (xy 399.334314 -438.772994) (xy 399.326827 -438.796056) (xy 399.312577 -438.815674)
			(xy 399.29296 -438.829925) (xy 399.269898 -438.837414) (xy 399.257774 -438.837832) (xy 398.317974 -438.837832)
			(xy 398.305847 -438.837462) (xy 398.282782 -438.829959) (xy 398.263165 -438.815695) (xy 398.248916 -438.796068)
			(xy 398.241429 -438.772997) (xy 398.241012 -438.76087) (xy 396.334488 -438.76087) (xy 396.334488 -439.760868)
			(xy 400.241008 -439.760868) (xy 400.241008 -437.219344) (xy 400.241497 -437.207295) (xy 400.248919 -437.18437)
			(xy 400.263052 -437.164853) (xy 400.282517 -437.150648) (xy 400.305415 -437.143142) (xy 400.317462 -437.142636)
			(xy 401.25777 -437.142636) (xy 401.269858 -437.143133) (xy 401.292857 -437.150581) (xy 401.312437 -437.16476)
			(xy 401.326688 -437.184287) (xy 401.334222 -437.207258) (xy 401.334732 -437.219344) (xy 401.334732 -438.76087)
			(xy 402.241004 -438.76087) (xy 402.241004 -436.219346) (xy 402.241498 -436.207229) (xy 402.248974 -436.184177)
			(xy 402.263208 -436.164564) (xy 402.282806 -436.150311) (xy 402.305849 -436.142811) (xy 402.317966 -436.142384)
			(xy 403.257766 -436.142384) (xy 403.269892 -436.14279) (xy 403.292957 -436.150278) (xy 403.306914 -436.160418)
			(xy 404.241 -436.160418) (xy 404.241 -435.43347) (xy 404.241317 -435.4247) (xy 404.245422 -435.407642)
			(xy 404.249128 -435.399688) (xy 404.249128 -435.39918) (xy 404.482554 -434.923184) (xy 404.487252 -434.912666)
			(xy 404.49074 -434.889909) (xy 404.487257 -434.867151) (xy 404.482554 -434.856636) (xy 404.249128 -434.38064)
			(xy 404.249128 -434.380132) (xy 404.245412 -434.37218) (xy 404.2413 -434.355122) (xy 404.241 -434.34635)
			(xy 404.241 -433.618894) (xy 404.241506 -433.606783) (xy 404.24899 -433.583746) (xy 404.263225 -433.564148)
			(xy 404.282817 -433.549905) (xy 404.305851 -433.542411) (xy 404.317962 -433.541932) (xy 405.257762 -433.541932)
			(xy 405.269882 -433.542392) (xy 405.292939 -433.549873) (xy 405.312554 -433.564115) (xy 405.326807 -433.583722)
			(xy 405.334301 -433.606774) (xy 405.334724 -433.618894) (xy 405.334724 -435.16042) (xy 406.240996 -435.16042)
			(xy 406.240996 -434.433472) (xy 406.241314 -434.424702) (xy 406.245418 -434.407644) (xy 406.249124 -434.39969)
			(xy 406.249124 -434.399182) (xy 406.48255 -433.923186) (xy 406.487247 -433.912668) (xy 406.490735 -433.889911)
			(xy 406.487253 -433.867153) (xy 406.48255 -433.856638) (xy 406.249124 -433.380642) (xy 406.249124 -433.380134)
			(xy 406.245408 -433.372182) (xy 406.241296 -433.355124) (xy 406.240996 -433.346352) (xy 406.240996 -432.618896)
			(xy 406.241457 -432.606846) (xy 406.24889 -432.583921) (xy 406.263031 -432.564406) (xy 406.282501 -432.550202)
			(xy 406.305402 -432.542696) (xy 406.31745 -432.542188) (xy 407.257758 -432.542188) (xy 407.26985 -432.542644)
			(xy 407.292858 -432.550095) (xy 407.307187 -432.560476) (xy 408.2415 -432.560476) (xy 408.2415 -431.833274)
			(xy 408.241751 -431.824517) (xy 408.245731 -431.807459) (xy 408.249374 -431.799492) (xy 408.4828 -431.323242)
			(xy 408.48753 -431.312736) (xy 408.49101 -431.289971) (xy 408.487512 -431.267208) (xy 408.4828 -431.256694)
			(xy 408.249374 -430.780444) (xy 408.245724 -430.772478) (xy 408.241741 -430.75542) (xy 408.2415 -430.746662)
			(xy 408.2415 -430.018952) (xy 408.241923 -430.006874) (xy 408.2494 -429.983904) (xy 408.263607 -429.964367)
			(xy 408.283154 -429.950174) (xy 408.30613 -429.942714) (xy 408.318208 -429.942244) (xy 409.258008 -429.942244)
			(xy 409.270078 -429.942757) (xy 409.293037 -429.950216) (xy 409.31257 -429.964401) (xy 409.326766 -429.983927)
			(xy 409.334237 -430.006882) (xy 409.334716 -430.018952) (xy 409.334716 -431.560478) (xy 410.241496 -431.560478)
			(xy 410.241496 -430.833276) (xy 410.241748 -430.824519) (xy 410.245727 -430.807461) (xy 410.24937 -430.799494)
			(xy 410.482796 -430.323244) (xy 410.487525 -430.312738) (xy 410.491005 -430.289973) (xy 410.487508 -430.26721)
			(xy 410.482796 -430.256696) (xy 410.24937 -429.780446) (xy 410.24572 -429.77248) (xy 410.241737 -429.755422)
			(xy 410.241496 -429.746664) (xy 410.241496 -429.018954) (xy 410.241967 -429.006866) (xy 410.249431 -428.983872)
			(xy 410.263618 -428.964296) (xy 410.283148 -428.950046) (xy 410.306118 -428.942507) (xy 410.318204 -428.941992)
			(xy 411.258004 -428.941992) (xy 411.270112 -428.942413) (xy 411.293138 -428.949912) (xy 411.308065 -428.960788)
			(xy 412.240984 -428.960788) (xy 412.240984 -426.419264) (xy 412.241429 -426.407213) (xy 412.248869 -426.384289)
			(xy 412.263015 -426.364776) (xy 412.282487 -426.350573) (xy 412.305389 -426.343065) (xy 412.317438 -426.342556)
			(xy 413.257746 -426.342556) (xy 413.26984 -426.342968) (xy 413.292844 -426.35044) (xy 413.312425 -426.36464)
			(xy 413.326673 -426.384185) (xy 413.334201 -426.407172) (xy 413.334708 -426.419264) (xy 413.334708 -428.960788)
			(xy 413.33423 -428.972837) (xy 413.326802 -428.995761) (xy 413.312665 -429.015276) (xy 413.293199 -429.02948)
			(xy 413.270301 -429.036988) (xy 413.258254 -429.037496) (xy 412.317946 -429.037496) (xy 412.305862 -429.036954)
			(xy 412.282869 -429.029514) (xy 412.263292 -429.015346) (xy 412.249038 -428.99583) (xy 412.241499 -428.97287)
			(xy 412.240984 -428.960788) (xy 411.308065 -428.960788) (xy 411.312711 -428.964173) (xy 411.326906 -428.983793)
			(xy 411.334328 -429.006844) (xy 411.334712 -429.018954) (xy 411.334712 -431.560478) (xy 411.334273 -431.572571)
			(xy 411.326816 -431.595579) (xy 411.312624 -431.615164) (xy 411.293082 -431.629413) (xy 411.270096 -431.636937)
			(xy 411.258004 -431.63744) (xy 410.318204 -431.63744) (xy 410.306099 -431.636981) (xy 410.283079 -431.629488)
			(xy 410.263509 -431.615236) (xy 410.249313 -431.595625) (xy 410.241885 -431.572584) (xy 410.241496 -431.560478)
			(xy 409.334716 -431.560478) (xy 409.334716 -432.560476) (xy 409.334267 -432.572557) (xy 409.326807 -432.595537)
			(xy 409.31261 -432.615087) (xy 409.293066 -432.629292) (xy 409.270088 -432.636762) (xy 409.258008 -432.637184)
			(xy 408.318208 -432.637184) (xy 408.306123 -432.63678) (xy 408.283137 -432.629312) (xy 408.263584 -432.615105)
			(xy 408.249381 -432.595549) (xy 408.241917 -432.572561) (xy 408.2415 -432.560476) (xy 407.307187 -432.560476)
			(xy 407.312442 -432.564283) (xy 407.326693 -432.583822) (xy 407.334217 -432.606805) (xy 407.33472 -432.618896)
			(xy 407.33472 -435.16042) (xy 407.334257 -435.172469) (xy 407.326821 -435.195392) (xy 407.312681 -435.214906)
			(xy 407.293212 -435.229109) (xy 407.270314 -435.236618) (xy 407.258266 -435.237128) (xy 406.317958 -435.237128)
			(xy 406.305863 -435.236728) (xy 406.282856 -435.229256) (xy 406.263274 -435.215053) (xy 406.249026 -435.195504)
			(xy 406.2415 -435.172514) (xy 406.240996 -435.16042) (xy 405.334724 -435.16042) (xy 405.334724 -436.160418)
			(xy 405.334355 -436.172545) (xy 405.326853 -436.195611) (xy 405.312589 -436.215229) (xy 405.292961 -436.229478)
			(xy 405.26989 -436.236963) (xy 405.257762 -436.23738) (xy 404.317962 -436.23738) (xy 404.305847 -436.236921)
			(xy 404.282806 -436.229425) (xy 404.263206 -436.21518) (xy 404.248965 -436.195576) (xy 404.241476 -436.172533)
			(xy 404.241 -436.160418) (xy 403.306914 -436.160418) (xy 403.312577 -436.164532) (xy 403.326827 -436.184154)
			(xy 403.334312 -436.20722) (xy 403.334728 -436.219346) (xy 403.334728 -438.76087) (xy 403.334314 -438.772995)
			(xy 403.326826 -438.796058) (xy 403.312574 -438.815677) (xy 403.292955 -438.829928) (xy 403.269891 -438.837415)
			(xy 403.257766 -438.837832) (xy 402.317966 -438.837832) (xy 402.305847 -438.837417) (xy 402.282797 -438.829917)
			(xy 402.263193 -438.815661) (xy 402.248954 -438.796045) (xy 402.241473 -438.77299) (xy 402.241004 -438.76087)
			(xy 401.334732 -438.76087) (xy 401.334732 -439.760868) (xy 404.241 -439.760868) (xy 404.241 -437.219344)
			(xy 404.241497 -437.207296) (xy 404.248918 -437.184372) (xy 404.263049 -437.164855) (xy 404.282512 -437.150651)
			(xy 404.305408 -437.143143) (xy 404.317454 -437.142636) (xy 405.257762 -437.142636) (xy 405.269849 -437.14314)
			(xy 405.292848 -437.150585) (xy 405.312428 -437.164763) (xy 405.32668 -437.184289) (xy 405.334214 -437.207259)
			(xy 405.334724 -437.219344) (xy 405.334724 -438.76087) (xy 406.240996 -438.76087) (xy 406.240996 -436.219346)
			(xy 406.241498 -436.20723) (xy 406.248973 -436.18418) (xy 406.263205 -436.164567) (xy 406.282801 -436.150313)
			(xy 406.305842 -436.142812) (xy 406.317958 -436.142384) (xy 407.257758 -436.142384) (xy 407.269883 -436.142796)
			(xy 407.292948 -436.150283) (xy 407.3069 -436.160418) (xy 408.240992 -436.160418) (xy 408.240992 -435.43347)
			(xy 408.24131 -435.4247) (xy 408.245414 -435.407642) (xy 408.24912 -435.399688) (xy 408.24912 -435.39918)
			(xy 408.482546 -434.923184) (xy 408.487244 -434.912667) (xy 408.490733 -434.889909) (xy 408.48725 -434.867151)
			(xy 408.482546 -434.856636) (xy 408.24912 -434.38064) (xy 408.24912 -434.380132) (xy 408.245403 -434.37218)
			(xy 408.241292 -434.355122) (xy 408.240992 -434.34635) (xy 408.240992 -433.618894) (xy 408.241506 -433.606784)
			(xy 408.248989 -433.583748) (xy 408.263222 -433.564151) (xy 408.282812 -433.549908) (xy 408.305844 -433.542412)
			(xy 408.317954 -433.541932) (xy 409.257754 -433.541932) (xy 409.269874 -433.542399) (xy 409.29293 -433.549878)
			(xy 409.312546 -433.564117) (xy 409.326798 -433.583723) (xy 409.334293 -433.606775) (xy 409.334716 -433.618894)
			(xy 409.334716 -435.16042) (xy 410.240988 -435.16042) (xy 410.240988 -434.433472) (xy 410.241307 -434.424702)
			(xy 410.24541 -434.407645) (xy 410.249116 -434.39969) (xy 410.249116 -434.399182) (xy 410.482542 -433.923186)
			(xy 410.487239 -433.912668) (xy 410.490728 -433.889911) (xy 410.487246 -433.867153) (xy 410.482542 -433.856638)
			(xy 410.249116 -433.380642) (xy 410.249116 -433.380134) (xy 410.245399 -433.372182) (xy 410.241288 -433.355124)
			(xy 410.240988 -433.346352) (xy 410.240988 -432.618896) (xy 410.241456 -432.606847) (xy 410.248889 -432.583923)
			(xy 410.263028 -432.564409) (xy 410.282496 -432.550205) (xy 410.305394 -432.542697) (xy 410.317442 -432.542188)
			(xy 411.25775 -432.542188) (xy 411.269842 -432.542651) (xy 411.292849 -432.5501) (xy 411.307175 -432.560476)
			(xy 412.241492 -432.560476) (xy 412.241492 -431.833274) (xy 412.241744 -431.824517) (xy 412.245723 -431.807459)
			(xy 412.249366 -431.799492) (xy 412.482792 -431.323242) (xy 412.487522 -431.312737) (xy 412.491003 -431.289971)
			(xy 412.487505 -431.267208) (xy 412.482792 -431.256694) (xy 412.249366 -430.780444) (xy 412.245715 -430.772478)
			(xy 412.241733 -430.755421) (xy 412.241492 -430.746662) (xy 412.241492 -430.018952) (xy 412.241923 -430.006875)
			(xy 412.249399 -429.983906) (xy 412.263604 -429.96437) (xy 412.283149 -429.950177) (xy 412.306123 -429.942716)
			(xy 412.3182 -429.942244) (xy 413.258 -429.942244) (xy 413.27007 -429.942764) (xy 413.293029 -429.95022)
			(xy 413.312562 -429.964404) (xy 413.326758 -429.983928) (xy 413.334229 -430.006883) (xy 413.334708 -430.018952)
			(xy 413.334708 -432.560476) (xy 413.334267 -432.572557) (xy 413.326806 -432.595539) (xy 413.312607 -432.61509)
			(xy 413.293061 -432.629295) (xy 413.270081 -432.636763) (xy 413.258 -432.637184) (xy 412.3182 -432.637184)
			(xy 412.306115 -432.636787) (xy 412.283128 -432.629317) (xy 412.263576 -432.615107) (xy 412.249372 -432.59555)
			(xy 412.241909 -432.572561) (xy 412.241492 -432.560476) (xy 411.307175 -432.560476) (xy 411.312434 -432.564285)
			(xy 411.326684 -432.583823) (xy 411.334209 -432.606806) (xy 411.334712 -432.618896) (xy 411.334712 -435.16042)
			(xy 411.334257 -435.17247) (xy 411.32682 -435.195394) (xy 411.312678 -435.214908) (xy 411.293207 -435.229111)
			(xy 411.270306 -435.236619) (xy 411.258258 -435.237128) (xy 410.31795 -435.237128) (xy 410.30586 -435.23665)
			(xy 410.282855 -435.229203) (xy 410.263272 -435.21502) (xy 410.249021 -435.195487) (xy 410.241493 -435.172508)
			(xy 410.240988 -435.16042) (xy 409.334716 -435.16042) (xy 409.334716 -436.160418) (xy 409.334354 -436.172546)
			(xy 409.326852 -436.195613) (xy 409.312586 -436.215232) (xy 409.292956 -436.229481) (xy 409.269883 -436.236965)
			(xy 409.257754 -436.23738) (xy 408.317954 -436.23738) (xy 408.305839 -436.236928) (xy 408.282797 -436.22943)
			(xy 408.263198 -436.215182) (xy 408.248957 -436.195578) (xy 408.241468 -436.172533) (xy 408.240992 -436.160418)
			(xy 407.3069 -436.160418) (xy 407.312568 -436.164535) (xy 407.326819 -436.184155) (xy 407.334304 -436.207221)
			(xy 407.33472 -436.219346) (xy 407.33472 -438.76087) (xy 407.334314 -438.772995) (xy 407.326825 -438.79606)
			(xy 407.312571 -438.81568) (xy 407.29295 -438.82993) (xy 407.269883 -438.837416) (xy 407.257758 -438.837832)
			(xy 406.317958 -438.837832) (xy 406.305838 -438.837424) (xy 406.282789 -438.829921) (xy 406.263185 -438.815664)
			(xy 406.248946 -438.796047) (xy 406.241465 -438.77299) (xy 406.240996 -438.76087) (xy 405.334724 -438.76087)
			(xy 405.334724 -439.760868) (xy 408.240992 -439.760868) (xy 408.240992 -437.219344) (xy 408.241497 -437.207297)
			(xy 408.248917 -437.184374) (xy 408.263046 -437.164858) (xy 408.282507 -437.150653) (xy 408.305401 -437.143144)
			(xy 408.317446 -437.142636) (xy 409.257754 -437.142636) (xy 409.269841 -437.143146) (xy 409.292839 -437.15059)
			(xy 409.31242 -437.164765) (xy 409.326672 -437.18429) (xy 409.334206 -437.207259) (xy 409.334716 -437.219344)
			(xy 409.334716 -438.76087) (xy 410.240988 -438.76087) (xy 410.240988 -436.219346) (xy 410.24155 -436.207239)
			(xy 410.249019 -436.184205) (xy 410.263239 -436.164607) (xy 410.282819 -436.150362) (xy 410.305843 -436.142865)
			(xy 410.31795 -436.142384) (xy 411.25775 -436.142384) (xy 411.269872 -436.14277) (xy 411.292924 -436.150276)
			(xy 411.306865 -436.160418) (xy 412.240984 -436.160418) (xy 412.240984 -435.43347) (xy 412.241303 -435.4247)
			(xy 412.245406 -435.407643) (xy 412.249112 -435.399688) (xy 412.249112 -435.39918) (xy 412.482538 -434.923184)
			(xy 412.487237 -434.912667) (xy 412.490726 -434.889909) (xy 412.487242 -434.867151) (xy 412.482538 -434.856636)
			(xy 412.249112 -434.38064) (xy 412.249112 -434.380132) (xy 412.245395 -434.372181) (xy 412.241284 -434.355122)
			(xy 412.240984 -434.34635) (xy 412.240984 -433.618894) (xy 412.241356 -433.606766) (xy 412.248855 -433.5837)
			(xy 412.263118 -433.564081) (xy 412.282746 -433.549831) (xy 412.305818 -433.542348) (xy 412.317946 -433.541932)
			(xy 413.257746 -433.541932) (xy 413.269862 -433.542372) (xy 413.292906 -433.549872) (xy 413.312507 -433.564122)
			(xy 413.326747 -433.58373) (xy 413.334234 -433.606777) (xy 413.334708 -433.618894) (xy 413.334708 -435.59984)
			(xy 446.741306 -435.59984) (xy 446.745288 -435.471854) (xy 446.75722 -435.344363) (xy 446.777054 -435.21786)
			(xy 446.804715 -435.092835) (xy 446.840095 -434.969772) (xy 446.883057 -434.849146) (xy 446.933435 -434.731425)
			(xy 446.991035 -434.617063) (xy 447.055633 -434.506504) (xy 447.12698 -434.400174) (xy 447.204799 -434.298486)
			(xy 447.288789 -434.201832) (xy 447.378626 -434.110587) (xy 447.473962 -434.025104) (xy 447.574427 -433.945713)
			(xy 447.679635 -433.872721) (xy 447.789176 -433.806412) (xy 447.902628 -433.747041) (xy 448.019552 -433.694837)
			(xy 448.139495 -433.650004) (xy 448.261993 -433.612715) (xy 448.386573 -433.583113) (xy 448.512751 -433.561314)
			(xy 448.640041 -433.547401) (xy 448.76795 -433.541429) (xy 448.895983 -433.54342) (xy 449.023644 -433.553368)
			(xy 449.15044 -433.571232) (xy 449.275879 -433.596945) (xy 449.399478 -433.630407) (xy 449.520757 -433.671488)
			(xy 449.639248 -433.72003) (xy 449.754492 -433.775844) (xy 449.866042 -433.838715) (xy 449.973469 -433.908399)
			(xy 450.076355 -433.984627) (xy 450.174303 -434.067104) (xy 450.266934 -434.155511) (xy 450.35389 -434.249506)
			(xy 450.434834 -434.348725) (xy 450.509453 -434.452784) (xy 450.577458 -434.561281) (xy 450.638586 -434.673796)
			(xy 450.692601 -434.789894) (xy 450.739294 -434.909125) (xy 450.778484 -435.031029) (xy 450.81002 -435.155133)
			(xy 450.833779 -435.280957) (xy 450.849669 -435.408016) (xy 450.85763 -435.535816) (xy 450.858128 -435.59984)
			(xy 450.85763 -435.663864) (xy 450.849669 -435.791664) (xy 450.833779 -435.918723) (xy 450.81002 -436.044547)
			(xy 450.778484 -436.168651) (xy 450.739294 -436.290555) (xy 450.692601 -436.409786) (xy 450.638586 -436.525884)
			(xy 450.577458 -436.638399) (xy 450.509453 -436.746896) (xy 450.434834 -436.850955) (xy 450.35389 -436.950174)
			(xy 450.266934 -437.044169) (xy 450.174303 -437.132576) (xy 450.076355 -437.215053) (xy 449.973469 -437.291281)
			(xy 449.866042 -437.360965) (xy 449.754492 -437.423836) (xy 449.639248 -437.47965) (xy 449.520757 -437.528192)
			(xy 449.399478 -437.569273) (xy 449.275879 -437.602735) (xy 449.15044 -437.628448) (xy 449.023644 -437.646312)
			(xy 448.895983 -437.65626) (xy 448.76795 -437.658251) (xy 448.640041 -437.652279) (xy 448.512751 -437.638366)
			(xy 448.386573 -437.616567) (xy 448.261993 -437.586965) (xy 448.139495 -437.549676) (xy 448.019552 -437.504843)
			(xy 447.902628 -437.452639) (xy 447.789176 -437.393268) (xy 447.679635 -437.326959) (xy 447.574427 -437.253967)
			(xy 447.473962 -437.174576) (xy 447.378626 -437.089093) (xy 447.288789 -436.997848) (xy 447.204799 -436.901194)
			(xy 447.12698 -436.799506) (xy 447.055633 -436.693176) (xy 446.991035 -436.582617) (xy 446.933435 -436.468255)
			(xy 446.883057 -436.350534) (xy 446.840095 -436.229908) (xy 446.804715 -436.106845) (xy 446.777054 -435.98182)
			(xy 446.75722 -435.855317) (xy 446.745288 -435.727826) (xy 446.741306 -435.59984) (xy 413.334708 -435.59984)
			(xy 413.334708 -436.160418) (xy 413.334205 -436.172529) (xy 413.326718 -436.195565) (xy 413.312482 -436.215163)
			(xy 413.29289 -436.229405) (xy 413.269857 -436.2369) (xy 413.257746 -436.23738) (xy 412.317946 -436.23738)
			(xy 412.305827 -436.236901) (xy 412.282773 -436.229424) (xy 412.263159 -436.215187) (xy 412.248905 -436.195584)
			(xy 412.241409 -436.172536) (xy 412.240984 -436.160418) (xy 411.306865 -436.160418) (xy 411.312529 -436.164539)
			(xy 411.326767 -436.184162) (xy 411.334245 -436.207224) (xy 411.334712 -436.219346) (xy 411.334712 -438.76087)
			(xy 411.334163 -438.772978) (xy 411.326691 -438.796012) (xy 411.312467 -438.81561) (xy 411.292884 -438.829854)
			(xy 411.269858 -438.837351) (xy 411.25775 -438.837832) (xy 410.31795 -438.837832) (xy 410.30583 -438.83743)
			(xy 410.28278 -438.829926) (xy 410.263176 -438.815667) (xy 410.248938 -438.796048) (xy 410.241457 -438.772991)
			(xy 410.240988 -438.76087) (xy 409.334716 -438.76087) (xy 409.334716 -439.760868) (xy 412.240984 -439.760868)
			(xy 412.240984 -437.219344) (xy 412.241497 -437.207298) (xy 412.248916 -437.184376) (xy 412.263043 -437.164861)
			(xy 412.282502 -437.150656) (xy 412.305394 -437.143145) (xy 412.317438 -437.142636) (xy 413.257746 -437.142636)
			(xy 413.269838 -437.143068) (xy 413.292839 -437.150537) (xy 413.312418 -437.164733) (xy 413.326667 -437.184273)
			(xy 413.334199 -437.207254) (xy 413.334708 -437.219344) (xy 413.334708 -439.760868) (xy 413.334213 -439.772916)
			(xy 413.32679 -439.795839) (xy 413.312658 -439.815355) (xy 413.293195 -439.829559) (xy 413.2703 -439.837068)
			(xy 413.258254 -439.837576) (xy 412.317946 -439.837576) (xy 412.30586 -439.837054) (xy 412.282864 -439.829612)
			(xy 412.263285 -439.815439) (xy 412.249032 -439.795917) (xy 412.241496 -439.772952) (xy 412.240984 -439.760868)
			(xy 409.334716 -439.760868) (xy 409.334213 -439.772915) (xy 409.326791 -439.795837) (xy 409.312661 -439.815352)
			(xy 409.2932 -439.829557) (xy 409.270307 -439.837067) (xy 409.258262 -439.837576) (xy 408.317954 -439.837576)
			(xy 408.305864 -439.837132) (xy 408.282864 -439.829665) (xy 408.263286 -439.815472) (xy 408.249037 -439.795935)
			(xy 408.241503 -439.772957) (xy 408.240992 -439.760868) (xy 405.334724 -439.760868) (xy 405.334213 -439.772914)
			(xy 405.326792 -439.795835) (xy 405.312664 -439.815349) (xy 405.293205 -439.829554) (xy 405.270314 -439.837065)
			(xy 405.25827 -439.837576) (xy 404.317962 -439.837576) (xy 404.305872 -439.837125) (xy 404.282873 -439.82966)
			(xy 404.263295 -439.815469) (xy 404.249045 -439.795933) (xy 404.241511 -439.772956) (xy 404.241 -439.760868)
			(xy 401.334732 -439.760868) (xy 401.334213 -439.772913) (xy 401.326793 -439.795833) (xy 401.312667 -439.815346)
			(xy 401.29321 -439.829552) (xy 401.270321 -439.837064) (xy 401.258278 -439.837576) (xy 400.31797 -439.837576)
			(xy 400.30588 -439.837119) (xy 400.282881 -439.829656) (xy 400.263303 -439.815466) (xy 400.249053 -439.795932)
			(xy 400.241519 -439.772956) (xy 400.241008 -439.760868) (xy 396.334488 -439.760868) (xy 396.334013 -439.772918)
			(xy 396.326587 -439.795844) (xy 396.312451 -439.815362) (xy 396.292983 -439.829566) (xy 396.270082 -439.837071)
			(xy 396.258034 -439.837576) (xy 395.317726 -439.837576) (xy 395.305639 -439.837071) (xy 395.282642 -439.829623)
			(xy 395.263063 -439.815446) (xy 395.248811 -439.795921) (xy 395.241276 -439.772953) (xy 395.240764 -439.760868)
			(xy 392.334496 -439.760868) (xy 392.334013 -439.772917) (xy 392.326588 -439.795842) (xy 392.312454 -439.815359)
			(xy 392.292988 -439.829563) (xy 392.270089 -439.837069) (xy 392.258042 -439.837576) (xy 391.317734 -439.837576)
			(xy 391.305648 -439.837064) (xy 391.282651 -439.829619) (xy 391.263072 -439.815443) (xy 391.24882 -439.79592)
			(xy 391.241284 -439.772952) (xy 391.240772 -439.760868) (xy 388.334504 -439.760868) (xy 388.334013 -439.772916)
			(xy 388.32659 -439.79584) (xy 388.312457 -439.815356) (xy 388.292993 -439.829561) (xy 388.270096 -439.837068)
			(xy 388.25805 -439.837576) (xy 387.317742 -439.837576) (xy 387.305656 -439.837057) (xy 387.28266 -439.829614)
			(xy 387.26308 -439.81544) (xy 387.248828 -439.795918) (xy 387.241292 -439.772952) (xy 387.24078 -439.760868)
			(xy 384.334512 -439.760868) (xy 384.334013 -439.772915) (xy 384.326591 -439.795838) (xy 384.312459 -439.815353)
			(xy 384.292998 -439.829558) (xy 384.270104 -439.837067) (xy 384.258058 -439.837576) (xy 383.31775 -439.837576)
			(xy 383.305665 -439.83705) (xy 383.282668 -439.829609) (xy 383.263089 -439.815437) (xy 383.248836 -439.795917)
			(xy 383.2413 -439.772951) (xy 383.240788 -439.760868) (xy 346.234512 -439.760868) (xy 346.234013 -439.772915)
			(xy 346.226591 -439.795838) (xy 346.212459 -439.815353) (xy 346.192998 -439.829558) (xy 346.170104 -439.837067)
			(xy 346.158058 -439.837576) (xy 345.21775 -439.837576) (xy 345.205665 -439.83705) (xy 345.182668 -439.829609)
			(xy 345.163089 -439.815437) (xy 345.148836 -439.795917) (xy 345.1413 -439.772951) (xy 345.140788 -439.760868)
			(xy 342.23452 -439.760868) (xy 342.234013 -439.772915) (xy 342.226592 -439.795836) (xy 342.212462 -439.81535)
			(xy 342.193003 -439.829555) (xy 342.170111 -439.837066) (xy 342.158066 -439.837576) (xy 341.217758 -439.837576)
			(xy 341.205668 -439.837129) (xy 341.182669 -439.829662) (xy 341.163091 -439.81547) (xy 341.148841 -439.795934)
			(xy 341.141307 -439.772957) (xy 341.140796 -439.760868) (xy 338.234528 -439.760868) (xy 338.234013 -439.772914)
			(xy 338.226593 -439.795834) (xy 338.212465 -439.815347) (xy 338.193008 -439.829553) (xy 338.170118 -439.837065)
			(xy 338.158074 -439.837576) (xy 337.217766 -439.837576) (xy 337.205676 -439.837122) (xy 337.182677 -439.829658)
			(xy 337.163099 -439.815467) (xy 337.148849 -439.795933) (xy 337.141315 -439.772956) (xy 337.140804 -439.760868)
			(xy 334.234536 -439.760868) (xy 334.234014 -439.772913) (xy 334.226594 -439.795831) (xy 334.212468 -439.815345)
			(xy 334.193013 -439.82955) (xy 334.170125 -439.837064) (xy 334.158082 -439.837576) (xy 333.217774 -439.837576)
			(xy 333.205685 -439.837115) (xy 333.182686 -439.829653) (xy 333.163108 -439.815465) (xy 333.148857 -439.795931)
			(xy 333.141323 -439.772956) (xy 333.140812 -439.760868) (xy 329.234292 -439.760868) (xy 329.233813 -439.772917)
			(xy 329.226388 -439.795843) (xy 329.212252 -439.81536) (xy 329.192785 -439.829564) (xy 329.169886 -439.83707)
			(xy 329.157838 -439.837576) (xy 328.21753 -439.837576) (xy 328.205444 -439.837067) (xy 328.182447 -439.829621)
			(xy 328.162868 -439.815444) (xy 328.148615 -439.79592) (xy 328.14108 -439.772953) (xy 328.140568 -439.760868)
			(xy 325.2343 -439.760868) (xy 325.233813 -439.772917) (xy 325.226389 -439.795841) (xy 325.212255 -439.815357)
			(xy 325.19279 -439.829562) (xy 325.169893 -439.837069) (xy 325.157846 -439.837576) (xy 324.217538 -439.837576)
			(xy 324.205452 -439.837061) (xy 324.182455 -439.829616) (xy 324.162876 -439.815442) (xy 324.148624 -439.795919)
			(xy 324.141088 -439.772952) (xy 324.140576 -439.760868) (xy 324.140576 -436.981854) (xy 324.140356 -436.975769)
			(xy 324.137405 -436.963958) (xy 324.134734 -436.958486) (xy 324.118994 -436.927294) (xy 324.094334 -436.86192)
			(xy 324.077695 -436.79406) (xy 324.069317 -436.724694) (xy 323.234304 -436.724694) (xy 323.234304 -438.76087)
			(xy 323.233763 -438.772979) (xy 323.226289 -438.796014) (xy 323.212064 -438.815613) (xy 323.192479 -438.829857)
			(xy 323.16945 -438.837352) (xy 323.157342 -438.837832) (xy 322.217542 -438.837832) (xy 322.205418 -438.837404)
			(xy 322.182356 -438.82992) (xy 322.162737 -438.815671) (xy 322.148486 -438.796055) (xy 322.140998 -438.772993)
			(xy 322.14058 -438.76087) (xy 321.234308 -438.76087) (xy 321.234308 -439.760868) (xy 321.233813 -439.772916)
			(xy 321.22639 -439.795839) (xy 321.212258 -439.815355) (xy 321.192795 -439.829559) (xy 321.1699 -439.837068)
			(xy 321.157854 -439.837576) (xy 320.217546 -439.837576) (xy 320.20546 -439.837054) (xy 320.182464 -439.829612)
			(xy 320.162885 -439.815439) (xy 320.148632 -439.795917) (xy 320.141096 -439.772952) (xy 320.140584 -439.760868)
			(xy 317.234316 -439.760868) (xy 317.233813 -439.772915) (xy 317.226391 -439.795837) (xy 317.212261 -439.815352)
			(xy 317.1928 -439.829557) (xy 317.169907 -439.837067) (xy 317.157862 -439.837576) (xy 316.217554 -439.837576)
			(xy 316.205464 -439.837132) (xy 316.182464 -439.829665) (xy 316.162886 -439.815472) (xy 316.148637 -439.795935)
			(xy 316.141103 -439.772957) (xy 316.140592 -439.760868) (xy 157.334712 -439.760868) (xy 157.334213 -439.772915)
			(xy 157.326791 -439.795838) (xy 157.312659 -439.815353) (xy 157.293198 -439.829558) (xy 157.270304 -439.837067)
			(xy 157.258258 -439.837576) (xy 156.31795 -439.837576) (xy 156.305865 -439.83705) (xy 156.282868 -439.829609)
			(xy 156.263289 -439.815437) (xy 156.249036 -439.795917) (xy 156.2415 -439.772951) (xy 156.240988 -439.760868)
			(xy 153.33472 -439.760868) (xy 153.334213 -439.772915) (xy 153.326792 -439.795836) (xy 153.312662 -439.81535)
			(xy 153.293203 -439.829555) (xy 153.270311 -439.837066) (xy 153.258266 -439.837576) (xy 152.317958 -439.837576)
			(xy 152.305868 -439.837129) (xy 152.282869 -439.829662) (xy 152.263291 -439.81547) (xy 152.249041 -439.795934)
			(xy 152.241507 -439.772957) (xy 152.240996 -439.760868) (xy 149.334728 -439.760868) (xy 149.334213 -439.772914)
			(xy 149.326793 -439.795834) (xy 149.312665 -439.815347) (xy 149.293208 -439.829553) (xy 149.270318 -439.837065)
			(xy 149.258274 -439.837576) (xy 148.317966 -439.837576) (xy 148.305876 -439.837122) (xy 148.282877 -439.829658)
			(xy 148.263299 -439.815467) (xy 148.249049 -439.795933) (xy 148.241515 -439.772956) (xy 148.241004 -439.760868)
			(xy 145.334736 -439.760868) (xy 145.334214 -439.772913) (xy 145.326794 -439.795831) (xy 145.312668 -439.815345)
			(xy 145.293213 -439.82955) (xy 145.270325 -439.837064) (xy 145.258282 -439.837576) (xy 144.317974 -439.837576)
			(xy 144.305885 -439.837115) (xy 144.282886 -439.829653) (xy 144.263308 -439.815465) (xy 144.249057 -439.795931)
			(xy 144.241523 -439.772956) (xy 144.241012 -439.760868) (xy 140.334492 -439.760868) (xy 140.334013 -439.772917)
			(xy 140.326588 -439.795843) (xy 140.312452 -439.81536) (xy 140.292985 -439.829564) (xy 140.270086 -439.83707)
			(xy 140.258038 -439.837576) (xy 139.31773 -439.837576) (xy 139.305644 -439.837067) (xy 139.282647 -439.829621)
			(xy 139.263068 -439.815444) (xy 139.248815 -439.79592) (xy 139.24128 -439.772953) (xy 139.240768 -439.760868)
			(xy 136.3345 -439.760868) (xy 136.334013 -439.772917) (xy 136.326589 -439.795841) (xy 136.312455 -439.815357)
			(xy 136.29299 -439.829562) (xy 136.270093 -439.837069) (xy 136.258046 -439.837576) (xy 135.317738 -439.837576)
			(xy 135.305652 -439.837061) (xy 135.282655 -439.829616) (xy 135.263076 -439.815442) (xy 135.248824 -439.795919)
			(xy 135.241288 -439.772952) (xy 135.240776 -439.760868) (xy 132.334508 -439.760868) (xy 132.334013 -439.772916)
			(xy 132.32659 -439.795839) (xy 132.312458 -439.815355) (xy 132.292995 -439.829559) (xy 132.2701 -439.837068)
			(xy 132.258054 -439.837576) (xy 131.317746 -439.837576) (xy 131.30566 -439.837054) (xy 131.282664 -439.829612)
			(xy 131.263085 -439.815439) (xy 131.248832 -439.795917) (xy 131.241296 -439.772952) (xy 131.240784 -439.760868)
			(xy 128.334516 -439.760868) (xy 128.334013 -439.772915) (xy 128.326591 -439.795837) (xy 128.312461 -439.815352)
			(xy 128.293 -439.829557) (xy 128.270107 -439.837067) (xy 128.258062 -439.837576) (xy 127.317754 -439.837576)
			(xy 127.305664 -439.837132) (xy 127.282664 -439.829665) (xy 127.263086 -439.815472) (xy 127.248837 -439.795935)
			(xy 127.241303 -439.772957) (xy 127.240792 -439.760868) (xy 90.234507 -439.760868) (xy 90.234104 -439.772709)
			(xy 90.226638 -439.795717) (xy 90.212439 -439.815301) (xy 90.192891 -439.829549) (xy 90.169901 -439.837073)
			(xy 90.157808 -439.837576) (xy 89.218008 -439.837576) (xy 89.205897 -439.837177) (xy 89.182866 -439.829677)
			(xy 89.163291 -439.815412) (xy 89.149096 -439.795785) (xy 89.14168 -439.772726) (xy 89.1413 -439.760614)
			(xy 86.234524 -439.760614) (xy 86.234104 -439.772708) (xy 86.226639 -439.795715) (xy 86.212442 -439.815298)
			(xy 86.192896 -439.829547) (xy 86.169909 -439.837072) (xy 86.157816 -439.837576) (xy 85.218016 -439.837576)
			(xy 85.205906 -439.83717) (xy 85.182875 -439.829672) (xy 85.163299 -439.815408) (xy 85.149105 -439.795783)
			(xy 85.141688 -439.772726) (xy 85.141308 -439.760614) (xy 82.234532 -439.760614) (xy 82.234104 -439.772707)
			(xy 82.22664 -439.795713) (xy 82.212445 -439.815295) (xy 82.192901 -439.829544) (xy 82.169916 -439.837071)
			(xy 82.157824 -439.837576) (xy 81.218024 -439.837576) (xy 81.205914 -439.837163) (xy 81.182883 -439.829667)
			(xy 81.163308 -439.815406) (xy 81.149113 -439.795781) (xy 81.141696 -439.772725) (xy 81.141316 -439.760614)
			(xy 78.23454 -439.760614) (xy 78.234104 -439.772706) (xy 78.226641 -439.795711) (xy 78.212447 -439.815292)
			(xy 78.192906 -439.829542) (xy 78.169923 -439.83707) (xy 78.157832 -439.837576) (xy 77.218032 -439.837576)
			(xy 77.205922 -439.837156) (xy 77.182892 -439.829663) (xy 77.163316 -439.815403) (xy 77.149122 -439.79578)
			(xy 77.141704 -439.772725) (xy 77.141324 -439.760614) (xy 73.234804 -439.760614) (xy 73.234301 -439.772725)
			(xy 73.226815 -439.795762) (xy 73.21258 -439.81536) (xy 73.192987 -439.829602) (xy 73.169953 -439.837097)
			(xy 73.157842 -439.837576) (xy 72.218042 -439.837576) (xy 72.205923 -439.837105) (xy 72.182868 -439.829626)
			(xy 72.163253 -439.815387) (xy 72.149 -439.795783) (xy 72.141504 -439.772733) (xy 72.14108 -439.760614)
			(xy 69.234812 -439.760614) (xy 69.234301 -439.772724) (xy 69.226816 -439.79576) (xy 69.212582 -439.815357)
			(xy 69.192992 -439.8296) (xy 69.16996 -439.837096) (xy 69.15785 -439.837576) (xy 68.21805 -439.837576)
			(xy 68.205934 -439.837131) (xy 68.182892 -439.829632) (xy 68.163292 -439.815382) (xy 68.149052 -439.795776)
			(xy 68.141563 -439.77273) (xy 68.141088 -439.760614) (xy 65.23482 -439.760614) (xy 65.234451 -439.772742)
			(xy 65.22695 -439.795808) (xy 65.212686 -439.815426) (xy 65.193058 -439.829675) (xy 65.169986 -439.83716)
			(xy 65.157858 -439.837576) (xy 64.218058 -439.837576) (xy 64.205943 -439.837124) (xy 64.1829 -439.829627)
			(xy 64.163301 -439.815379) (xy 64.14906 -439.795774) (xy 64.141571 -439.77273) (xy 64.141096 -439.760614)
			(xy 61.234828 -439.760614) (xy 61.234451 -439.772741) (xy 61.226951 -439.795806) (xy 61.212689 -439.815424)
			(xy 61.193063 -439.829673) (xy 61.169993 -439.837159) (xy 61.157866 -439.837576) (xy 60.218066 -439.837576)
			(xy 60.205951 -439.837118) (xy 60.182909 -439.829623) (xy 60.163309 -439.815377) (xy 60.149068 -439.795773)
			(xy 60.141579 -439.772729) (xy 60.141104 -439.760614) (xy 7.00913 -439.760614) (xy 7.00913 -439.989976)
			(xy 7.009638 -440.045746) (xy 7.017973 -440.156973) (xy 7.034597 -440.267266) (xy 7.059417 -440.376009)
			(xy 7.092293 -440.482593) (xy 7.133043 -440.586422) (xy 7.181438 -440.686915) (xy 7.237207 -440.783511)
			(xy 7.300039 -440.87567) (xy 7.369583 -440.962874) (xy 7.445449 -441.044639) (xy 7.527212 -441.120505)
			(xy 7.614417 -441.190048) (xy 7.706575 -441.252881) (xy 7.803171 -441.30865) (xy 7.903664 -441.357045)
			(xy 8.007493 -441.397795) (xy 8.114077 -441.430672) (xy 8.22282 -441.455492) (xy 8.333113 -441.472116)
			(xy 8.44434 -441.480451) (xy 8.50011 -441.480956)
		)
		(stroke
			(width 0)
			(type solid)
		)
		(fill yes)
		(layer "In12.Cu")
		(net "GND")
	)
	(gr_arc
		(start 0.508 -77.67193)
		(mid 0.621601 -78.242658)
		(end 0.94488 -78.726538)
		(stroke
			(width 0.2)
			(type default)
		)
		(layer "In12.Cu")
	)
	(gr_line
		(start 0.508 -13.780008)
		(end 0.508 -77.67193)
		(stroke
			(width 0.2)
			(type default)
		)
		(layer "In12.Cu")
	)
	(gr_line
		(start 0.94488 -78.726538)
		(end 1.773428 -79.555086)
		(stroke
			(width 0.2)
			(type default)
		)
		(layer "In12.Cu")
	)
	(gr_line
		(start 1.414272 -79.914242)
		(end 0.585724 -79.085694)
		(stroke
			(width 1.016)
			(type default)
		)
		(layer "In12.Cu")
	)
	(gr_line
		(start 1.999996 -403.371558)
		(end 1.999996 -81.328514)
		(stroke
			(width 1.016)
			(type default)
		)
		(layer "In12.Cu")
	)
	(gr_arc
		(start 1.999996 -403.371558)
		(mid 2.152159 -404.136965)
		(end 2.58572 -404.78583)
		(stroke
			(width 1.016)
			(type default)
		)
		(layer "In12.Cu")
	)
	(gr_arc
		(start 1.999996 -81.328514)
		(mid 1.847755 -80.563149)
		(end 1.414272 -79.914242)
		(stroke
			(width 1.016)
			(type default)
		)
		(layer "In12.Cu")
	)
	(gr_arc
		(start 1.999996 -12.288012)
		(mid 0.944996 -12.725008)
		(end 0.508 -13.780008)
		(stroke
			(width 0.2)
			(type default)
		)
		(layer "In12.Cu")
	)
	(gr_arc
		(start 1.999996 -11.780012)
		(mid 0.585785 -12.365797)
		(end 0 -13.780008)
		(stroke
			(width 1.016)
			(type default)
		)
		(layer "In12.Cu")
	)
	(gr_line
		(start 1.999996 -11.780012)
		(end 11.102086 -11.780012)
		(stroke
			(width 1.016)
			(type default)
		)
		(layer "In12.Cu")
	)
	(gr_arc
		(start 2.507996 -403.371812)
		(mid 2.621533 -403.942691)
		(end 2.944876 -404.426674)
		(stroke
			(width 0.2)
			(type default)
		)
		(layer "In12.Cu")
	)
	(gr_arc
		(start 2.507996 -81.32826)
		(mid 2.317045 -80.368624)
		(end 1.773428 -79.555086)
		(stroke
			(width 0.2)
			(type default)
		)
		(layer "In12.Cu")
	)
	(gr_line
		(start 2.507996 -81.32826)
		(end 2.507996 -403.371812)
		(stroke
			(width 0.2)
			(type default)
		)
		(layer "In12.Cu")
	)
	(gr_line
		(start 2.944876 -404.426674)
		(end 6.273292 -407.75509)
		(stroke
			(width 0.2)
			(type default)
		)
		(layer "In12.Cu")
	)
	(gr_line
		(start 5.914136 -408.114246)
		(end 2.58572 -404.78583)
		(stroke
			(width 1.016)
			(type default)
		)
		(layer "In12.Cu")
	)
	(gr_line
		(start 6.500114 -439.989976)
		(end 6.500114 -409.528518)
		(stroke
			(width 1.016)
			(type default)
		)
		(layer "In12.Cu")
	)
	(gr_arc
		(start 6.500114 -439.989976)
		(mid 7.085891 -441.404199)
		(end 8.50011 -441.989972)
		(stroke
			(width 1.016)
			(type default)
		)
		(layer "In12.Cu")
	)
	(gr_arc
		(start 6.500114 -409.528518)
		(mid 6.347771 -408.763109)
		(end 5.914136 -408.114246)
		(stroke
			(width 1.016)
			(type default)
		)
		(layer "In12.Cu")
	)
	(gr_arc
		(start 7.008114 -439.989976)
		(mid 7.44511 -441.044976)
		(end 8.50011 -441.481972)
		(stroke
			(width 0.2)
			(type default)
		)
		(layer "In12.Cu")
	)
	(gr_arc
		(start 7.008114 -409.528518)
		(mid 6.817049 -408.568734)
		(end 6.273292 -407.75509)
		(stroke
			(width 0.2)
			(type default)
		)
		(layer "In12.Cu")
	)
	(gr_line
		(start 7.008114 -409.528518)
		(end 7.008114 -439.989976)
		(stroke
			(width 0.2)
			(type default)
		)
		(layer "In12.Cu")
	)
	(gr_line
		(start 8.50011 -441.481972)
		(end 194.496944 -441.481972)
		(stroke
			(width 0.2)
			(type default)
		)
		(layer "In12.Cu")
	)
	(gr_line
		(start 11.102086 -12.288012)
		(end 1.999996 -12.288012)
		(stroke
			(width 0.2)
			(type default)
		)
		(layer "In12.Cu")
	)
	(gr_arc
		(start 11.102086 -12.288012)
		(mid 12.875508 -11.553438)
		(end 13.610082 -9.780016)
		(stroke
			(width 0.2)
			(type default)
		)
		(layer "In12.Cu")
	)
	(gr_arc
		(start 11.102086 -11.780012)
		(mid 12.516297 -11.194227)
		(end 13.102082 -9.780016)
		(stroke
			(width 1.016)
			(type default)
		)
		(layer "In12.Cu")
	)
	(gr_line
		(start 13.102082 -9.780016)
		(end 13.102082 -0.500126)
		(stroke
			(width 1.016)
			(type default)
		)
		(layer "In12.Cu")
	)
	(gr_arc
		(start 13.601954 0)
		(mid 13.24848 -0.146572)
		(end 13.102082 -0.500126)
		(stroke
			(width 1.016)
			(type default)
		)
		(layer "In12.Cu")
	)
	(gr_line
		(start 13.601954 0)
		(end 81.202022 0)
		(stroke
			(width 1.016)
			(type default)
		)
		(layer "In12.Cu")
	)
	(gr_line
		(start 13.610082 -0.508)
		(end 13.610082 -9.780016)
		(stroke
			(width 0.2)
			(type default)
		)
		(layer "In12.Cu")
	)
	(gr_line
		(start 16.841724 -22.027896)
		(end 18.130774 -23.759668)
		(stroke
			(width 0.1016)
			(type default)
		)
		(layer "In12.Cu")
	)
	(gr_line
		(start 17.427194 -21.592032)
		(end 16.841724 -22.027896)
		(stroke
			(width 0.1016)
			(type default)
		)
		(layer "In12.Cu")
	)
	(gr_line
		(start 18.716244 -23.323804)
		(end 17.427194 -21.592032)
		(stroke
			(width 0.1016)
			(type default)
		)
		(layer "In12.Cu")
	)
	(gr_line
		(start 20.584922 -23.448518)
		(end 21.832824 -25.210516)
		(stroke
			(width 0.1016)
			(type default)
		)
		(layer "In12.Cu")
	)
	(gr_line
		(start 21.180552 -23.026624)
		(end 20.584922 -23.448518)
		(stroke
			(width 0.1016)
			(type default)
		)
		(layer "In12.Cu")
	)
	(gr_line
		(start 21.613622 -20.981162)
		(end 22.814534 -22.775164)
		(stroke
			(width 0.1016)
			(type default)
		)
		(layer "In12.Cu")
	)
	(gr_line
		(start 22.220174 -20.575016)
		(end 21.613622 -20.981162)
		(stroke
			(width 0.1016)
			(type default)
		)
		(layer "In12.Cu")
	)
	(gr_line
		(start 22.428454 -24.788622)
		(end 21.180552 -23.026624)
		(stroke
			(width 0.1016)
			(type default)
		)
		(layer "In12.Cu")
	)
	(gr_line
		(start 23.421086 -22.369018)
		(end 22.220174 -20.575016)
		(stroke
			(width 0.1016)
			(type default)
		)
		(layer "In12.Cu")
	)
	(gr_line
		(start 25.775666 -23.20163)
		(end 26.921206 -25.0317)
		(stroke
			(width 0.1016)
			(type default)
		)
		(layer "In12.Cu")
	)
	(gr_circle
		(center 25.82545 -40.816276)
		(end 26.71445 -40.816276)
		(stroke
			(width 0.2)
			(type default)
		)
		(fill no)
		(layer "In12.Cu")
	)
	(gr_line
		(start 26.39441 -22.81428)
		(end 25.775666 -23.20163)
		(stroke
			(width 0.1016)
			(type default)
		)
		(layer "In12.Cu")
	)
	(gr_line
		(start 27.430222 -21.446236)
		(end 28.521406 -23.309072)
		(stroke
			(width 0.1016)
			(type default)
		)
		(layer "In12.Cu")
	)
	(gr_line
		(start 27.53995 -24.64435)
		(end 26.39441 -22.81428)
		(stroke
			(width 0.1016)
			(type default)
		)
		(layer "In12.Cu")
	)
	(gr_line
		(start 28.060142 -21.077428)
		(end 27.430222 -21.446236)
		(stroke
			(width 0.1016)
			(type default)
		)
		(layer "In12.Cu")
	)
	(gr_line
		(start 29.151326 -22.940264)
		(end 28.060142 -21.077428)
		(stroke
			(width 0.1016)
			(type default)
		)
		(layer "In12.Cu")
	)
	(gr_circle
		(center 29.291534 -348.709488)
		(end 30.171644 -348.709488)
		(stroke
			(width 0.2)
			(type default)
		)
		(fill no)
		(layer "In12.Cu")
	)
	(gr_circle
		(center 29.908754 -348.709488)
		(end 30.788864 -348.709488)
		(stroke
			(width 0.2)
			(type default)
		)
		(fill no)
		(layer "In12.Cu")
	)
	(gr_circle
		(center 30.525974 -348.709488)
		(end 31.406084 -348.709488)
		(stroke
			(width 0.2)
			(type default)
		)
		(fill no)
		(layer "In12.Cu")
	)
	(gr_circle
		(center 30.795214 -347.966538)
		(end 31.684214 -347.966538)
		(stroke
			(width 0.2)
			(type default)
		)
		(fill no)
		(layer "In12.Cu")
	)
	(gr_circle
		(center 30.795214 -347.229938)
		(end 31.684214 -347.229938)
		(stroke
			(width 0.2)
			(type default)
		)
		(fill no)
		(layer "In12.Cu")
	)
	(gr_line
		(start 31.157926 -23.254208)
		(end 32.185864 -25.152858)
		(stroke
			(width 0.1016)
			(type default)
		)
		(layer "In12.Cu")
	)
	(gr_circle
		(center 31.22803 -350.318578)
		(end 32.11703 -350.318578)
		(stroke
			(width 0.2)
			(type default)
		)
		(fill no)
		(layer "In12.Cu")
	)
	(gr_circle
		(center 31.22803 -349.581978)
		(end 32.11703 -349.581978)
		(stroke
			(width 0.2)
			(type default)
		)
		(fill no)
		(layer "In12.Cu")
	)
	(gr_circle
		(center 31.752794 -349.142558)
		(end 32.641794 -349.142558)
		(stroke
			(width 0.2)
			(type default)
		)
		(fill no)
		(layer "In12.Cu")
	)
	(gr_circle
		(center 31.778194 -349.904558)
		(end 32.667194 -349.904558)
		(stroke
			(width 0.2)
			(type default)
		)
		(fill no)
		(layer "In12.Cu")
	)
	(gr_line
		(start 31.799784 -22.906482)
		(end 31.157926 -23.254208)
		(stroke
			(width 0.1016)
			(type default)
		)
		(layer "In12.Cu")
	)
	(gr_circle
		(center 32.311594 -350.260158)
		(end 33.200594 -350.260158)
		(stroke
			(width 0.2)
			(type default)
		)
		(fill no)
		(layer "In12.Cu")
	)
	(gr_circle
		(center 32.311594 -349.523558)
		(end 33.200594 -349.523558)
		(stroke
			(width 0.2)
			(type default)
		)
		(fill no)
		(layer "In12.Cu")
	)
	(gr_circle
		(center 32.311594 -348.786958)
		(end 33.200594 -348.786958)
		(stroke
			(width 0.2)
			(type default)
		)
		(fill no)
		(layer "In12.Cu")
	)
	(gr_line
		(start 32.827722 -24.805132)
		(end 31.799784 -22.906482)
		(stroke
			(width 0.1016)
			(type default)
		)
		(layer "In12.Cu")
	)
	(gr_line
		(start 34.583116 -24.72309)
		(end 35.235134 -24.394922)
		(stroke
			(width 0.1016)
			(type default)
		)
		(layer "In12.Cu")
	)
	(gr_line
		(start 35.235134 -24.394922)
		(end 36.205668 -26.32329)
		(stroke
			(width 0.1016)
			(type default)
		)
		(layer "In12.Cu")
	)
	(gr_line
		(start 35.428682 -20.88261)
		(end 36.089844 -20.573238)
		(stroke
			(width 0.1016)
			(type default)
		)
		(layer "In12.Cu")
	)
	(gr_line
		(start 35.55365 -26.651458)
		(end 34.583116 -24.72309)
		(stroke
			(width 0.1016)
			(type default)
		)
		(layer "In12.Cu")
	)
	(gr_line
		(start 36.089844 -20.573238)
		(end 37.005006 -22.52853)
		(stroke
			(width 0.1016)
			(type default)
		)
		(layer "In12.Cu")
	)
	(gr_line
		(start 36.343844 -22.837902)
		(end 35.428682 -20.88261)
		(stroke
			(width 0.1016)
			(type default)
		)
		(layer "In12.Cu")
	)
	(gr_circle
		(center 37.571934 -348.709488)
		(end 38.452044 -348.709488)
		(stroke
			(width 0.2)
			(type default)
		)
		(fill no)
		(layer "In12.Cu")
	)
	(gr_circle
		(center 38.189154 -348.709488)
		(end 39.069264 -348.709488)
		(stroke
			(width 0.2)
			(type default)
		)
		(fill no)
		(layer "In12.Cu")
	)
	(gr_circle
		(center 38.806374 -348.709488)
		(end 39.686484 -348.709488)
		(stroke
			(width 0.2)
			(type default)
		)
		(fill no)
		(layer "In12.Cu")
	)
	(gr_circle
		(center 39.050214 -347.974158)
		(end 39.939214 -347.974158)
		(stroke
			(width 0.2)
			(type default)
		)
		(fill no)
		(layer "In12.Cu")
	)
	(gr_circle
		(center 39.050214 -347.237558)
		(end 39.939214 -347.237558)
		(stroke
			(width 0.2)
			(type default)
		)
		(fill no)
		(layer "In12.Cu")
	)
	(gr_circle
		(center 39.50843 -350.318578)
		(end 40.39743 -350.318578)
		(stroke
			(width 0.2)
			(type default)
		)
		(fill no)
		(layer "In12.Cu")
	)
	(gr_circle
		(center 39.50843 -349.581978)
		(end 40.39743 -349.581978)
		(stroke
			(width 0.2)
			(type default)
		)
		(fill no)
		(layer "In12.Cu")
	)
	(gr_circle
		(center 40.033194 -349.142558)
		(end 40.922194 -349.142558)
		(stroke
			(width 0.2)
			(type default)
		)
		(fill no)
		(layer "In12.Cu")
	)
	(gr_circle
		(center 40.058594 -349.904558)
		(end 40.947594 -349.904558)
		(stroke
			(width 0.2)
			(type default)
		)
		(fill no)
		(layer "In12.Cu")
	)
	(gr_circle
		(center 40.591994 -350.260158)
		(end 41.480994 -350.260158)
		(stroke
			(width 0.2)
			(type default)
		)
		(fill no)
		(layer "In12.Cu")
	)
	(gr_circle
		(center 40.591994 -349.523558)
		(end 41.480994 -349.523558)
		(stroke
			(width 0.2)
			(type default)
		)
		(fill no)
		(layer "In12.Cu")
	)
	(gr_circle
		(center 40.591994 -348.786958)
		(end 41.480994 -348.786958)
		(stroke
			(width 0.2)
			(type default)
		)
		(fill no)
		(layer "In12.Cu")
	)
	(gr_circle
		(center 41.369742 -358.549194)
		(end 42.258742 -358.549194)
		(stroke
			(width 0.2)
			(type default)
		)
		(fill no)
		(layer "In12.Cu")
	)
	(gr_circle
		(center 41.417494 -357.898192)
		(end 42.306494 -357.898192)
		(stroke
			(width 0.2)
			(type default)
		)
		(fill no)
		(layer "In12.Cu")
	)
	(gr_circle
		(center 41.417494 -357.263192)
		(end 42.306494 -357.263192)
		(stroke
			(width 0.2)
			(type default)
		)
		(fill no)
		(layer "In12.Cu")
	)
	(gr_circle
		(center 41.427146 -359.2576)
		(end 42.316146 -359.2576)
		(stroke
			(width 0.2)
			(type default)
		)
		(fill no)
		(layer "In12.Cu")
	)
	(gr_line
		(start 43.105832 -32.449516)
		(end 43.777916 -32.164274)
		(stroke
			(width 0.1016)
			(type default)
		)
		(layer "In12.Cu")
	)
	(gr_line
		(start 43.777916 -32.164274)
		(end 44.621196 -34.151824)
		(stroke
			(width 0.1016)
			(type default)
		)
		(layer "In12.Cu")
	)
	(gr_circle
		(center 43.935904 -358.51084)
		(end 44.824904 -358.51084)
		(stroke
			(width 0.2)
			(type default)
		)
		(fill no)
		(layer "In12.Cu")
	)
	(gr_line
		(start 43.949112 -34.437066)
		(end 43.105832 -32.449516)
		(stroke
			(width 0.1016)
			(type default)
		)
		(layer "In12.Cu")
	)
	(gr_circle
		(center 43.983656 -357.859838)
		(end 44.872656 -357.859838)
		(stroke
			(width 0.2)
			(type default)
		)
		(fill no)
		(layer "In12.Cu")
	)
	(gr_circle
		(center 43.983656 -357.224838)
		(end 44.872656 -357.224838)
		(stroke
			(width 0.2)
			(type default)
		)
		(fill no)
		(layer "In12.Cu")
	)
	(gr_circle
		(center 43.993308 -359.219246)
		(end 44.882308 -359.219246)
		(stroke
			(width 0.2)
			(type default)
		)
		(fill no)
		(layer "In12.Cu")
	)
	(gr_line
		(start 44.017692 -28.41625)
		(end 44.703492 -28.16606)
		(stroke
			(width 0.1016)
			(type default)
		)
		(layer "In12.Cu")
	)
	(gr_line
		(start 44.154598 -21.248116)
		(end 44.850812 -21.02866)
		(stroke
			(width 0.1016)
			(type default)
		)
		(layer "In12.Cu")
	)
	(gr_line
		(start 44.703492 -28.16606)
		(end 45.44314 -30.19425)
		(stroke
			(width 0.1016)
			(type default)
		)
		(layer "In12.Cu")
	)
	(gr_line
		(start 44.75734 -30.44444)
		(end 44.017692 -28.41625)
		(stroke
			(width 0.1016)
			(type default)
		)
		(layer "In12.Cu")
	)
	(gr_line
		(start 44.804076 -23.30704)
		(end 44.154598 -21.248116)
		(stroke
			(width 0.1016)
			(type default)
		)
		(layer "In12.Cu")
	)
	(gr_line
		(start 44.850812 -21.02866)
		(end 45.50029 -23.087584)
		(stroke
			(width 0.1016)
			(type default)
		)
		(layer "In12.Cu")
	)
	(gr_circle
		(center 45.877734 -348.709488)
		(end 46.757844 -348.709488)
		(stroke
			(width 0.2)
			(type default)
		)
		(fill no)
		(layer "In12.Cu")
	)
	(gr_circle
		(center 46.494954 -348.709488)
		(end 47.375064 -348.709488)
		(stroke
			(width 0.2)
			(type default)
		)
		(fill no)
		(layer "In12.Cu")
	)
	(gr_circle
		(center 47.112174 -348.709488)
		(end 47.992284 -348.709488)
		(stroke
			(width 0.2)
			(type default)
		)
		(fill no)
		(layer "In12.Cu")
	)
	(gr_circle
		(center 47.366174 -348.017338)
		(end 48.255174 -348.017338)
		(stroke
			(width 0.2)
			(type default)
		)
		(fill no)
		(layer "In12.Cu")
	)
	(gr_circle
		(center 47.366174 -347.280738)
		(end 48.255174 -347.280738)
		(stroke
			(width 0.2)
			(type default)
		)
		(fill no)
		(layer "In12.Cu")
	)
	(gr_line
		(start 47.747428 -24.443436)
		(end 48.300132 -26.530554)
		(stroke
			(width 0.1016)
			(type default)
		)
		(layer "In12.Cu")
	)
	(gr_circle
		(center 47.81423 -350.318578)
		(end 48.70323 -350.318578)
		(stroke
			(width 0.2)
			(type default)
		)
		(fill no)
		(layer "In12.Cu")
	)
	(gr_circle
		(center 47.81423 -349.581978)
		(end 48.70323 -349.581978)
		(stroke
			(width 0.2)
			(type default)
		)
		(fill no)
		(layer "In12.Cu")
	)
	(gr_circle
		(center 47.880778 -358.108504)
		(end 48.769778 -358.108504)
		(stroke
			(width 0.2)
			(type default)
		)
		(fill no)
		(layer "In12.Cu")
	)
	(gr_circle
		(center 47.92853 -357.457502)
		(end 48.81753 -357.457502)
		(stroke
			(width 0.2)
			(type default)
		)
		(fill no)
		(layer "In12.Cu")
	)
	(gr_circle
		(center 47.92853 -356.822502)
		(end 48.81753 -356.822502)
		(stroke
			(width 0.2)
			(type default)
		)
		(fill no)
		(layer "In12.Cu")
	)
	(gr_circle
		(center 48.338994 -349.142558)
		(end 49.227994 -349.142558)
		(stroke
			(width 0.2)
			(type default)
		)
		(fill no)
		(layer "In12.Cu")
	)
	(gr_circle
		(center 48.364394 -349.904558)
		(end 49.253394 -349.904558)
		(stroke
			(width 0.2)
			(type default)
		)
		(fill no)
		(layer "In12.Cu")
	)
	(gr_line
		(start 48.45304 -24.256746)
		(end 47.747428 -24.443436)
		(stroke
			(width 0.1016)
			(type default)
		)
		(layer "In12.Cu")
	)
	(gr_circle
		(center 48.718978 -358.108504)
		(end 49.607978 -358.108504)
		(stroke
			(width 0.2)
			(type default)
		)
		(fill no)
		(layer "In12.Cu")
	)
	(gr_circle
		(center 48.76673 -357.457502)
		(end 49.65573 -357.457502)
		(stroke
			(width 0.2)
			(type default)
		)
		(fill no)
		(layer "In12.Cu")
	)
	(gr_circle
		(center 48.76673 -356.822502)
		(end 49.65573 -356.822502)
		(stroke
			(width 0.2)
			(type default)
		)
		(fill no)
		(layer "In12.Cu")
	)
	(gr_circle
		(center 48.897794 -350.260158)
		(end 49.786794 -350.260158)
		(stroke
			(width 0.2)
			(type default)
		)
		(fill no)
		(layer "In12.Cu")
	)
	(gr_circle
		(center 48.897794 -349.523558)
		(end 49.786794 -349.523558)
		(stroke
			(width 0.2)
			(type default)
		)
		(fill no)
		(layer "In12.Cu")
	)
	(gr_circle
		(center 48.897794 -348.786958)
		(end 49.786794 -348.786958)
		(stroke
			(width 0.2)
			(type default)
		)
		(fill no)
		(layer "In12.Cu")
	)
	(gr_line
		(start 49.005744 -26.343864)
		(end 48.45304 -24.256746)
		(stroke
			(width 0.1016)
			(type default)
		)
		(layer "In12.Cu")
	)
	(gr_circle
		(center 49.353978 -358.108504)
		(end 50.242978 -358.108504)
		(stroke
			(width 0.2)
			(type default)
		)
		(fill no)
		(layer "In12.Cu")
	)
	(gr_circle
		(center 49.40173 -357.457502)
		(end 50.29073 -357.457502)
		(stroke
			(width 0.2)
			(type default)
		)
		(fill no)
		(layer "In12.Cu")
	)
	(gr_circle
		(center 49.40173 -356.822502)
		(end 50.29073 -356.822502)
		(stroke
			(width 0.2)
			(type default)
		)
		(fill no)
		(layer "In12.Cu")
	)
	(gr_line
		(start 49.65192 -21.27123)
		(end 50.365914 -21.119846)
		(stroke
			(width 0.1016)
			(type default)
		)
		(layer "In12.Cu")
	)
	(gr_circle
		(center 49.988978 -358.108504)
		(end 50.877978 -358.108504)
		(stroke
			(width 0.2)
			(type default)
		)
		(fill no)
		(layer "In12.Cu")
	)
	(gr_circle
		(center 50.03673 -357.457502)
		(end 50.92573 -357.457502)
		(stroke
			(width 0.2)
			(type default)
		)
		(fill no)
		(layer "In12.Cu")
	)
	(gr_circle
		(center 50.03673 -356.822502)
		(end 50.92573 -356.822502)
		(stroke
			(width 0.2)
			(type default)
		)
		(fill no)
		(layer "In12.Cu")
	)
	(gr_line
		(start 50.099722 -23.383494)
		(end 49.65192 -21.27123)
		(stroke
			(width 0.1016)
			(type default)
		)
		(layer "In12.Cu")
	)
	(gr_line
		(start 50.365914 -21.119846)
		(end 50.813716 -23.23211)
		(stroke
			(width 0.1016)
			(type default)
		)
		(layer "In12.Cu")
	)
	(gr_circle
		(center 50.623978 -358.108504)
		(end 51.512978 -358.108504)
		(stroke
			(width 0.2)
			(type default)
		)
		(fill no)
		(layer "In12.Cu")
	)
	(gr_circle
		(center 50.67173 -357.457502)
		(end 51.56073 -357.457502)
		(stroke
			(width 0.2)
			(type default)
		)
		(fill no)
		(layer "In12.Cu")
	)
	(gr_circle
		(center 50.67173 -356.822502)
		(end 51.56073 -356.822502)
		(stroke
			(width 0.2)
			(type default)
		)
		(fill no)
		(layer "In12.Cu")
	)
	(gr_line
		(start 52.64785 -24.094948)
		(end 53.368956 -23.980648)
		(stroke
			(width 0.1016)
			(type default)
		)
		(layer "In12.Cu")
	)
	(gr_line
		(start 52.985924 -26.227532)
		(end 52.64785 -24.094948)
		(stroke
			(width 0.1016)
			(type default)
		)
		(layer "In12.Cu")
	)
	(gr_line
		(start 53.368956 -23.980648)
		(end 53.70703 -26.113232)
		(stroke
			(width 0.1016)
			(type default)
		)
		(layer "In12.Cu")
	)
	(gr_circle
		(center 54.234334 -348.709488)
		(end 55.114444 -348.709488)
		(stroke
			(width 0.2)
			(type default)
		)
		(fill no)
		(layer "In12.Cu")
	)
	(gr_circle
		(center 54.851554 -348.709488)
		(end 55.731664 -348.709488)
		(stroke
			(width 0.2)
			(type default)
		)
		(fill no)
		(layer "In12.Cu")
	)
	(gr_line
		(start 55.056024 -22.9997)
		(end 55.056024 -20.8407)
		(stroke
			(width 0.1016)
			(type default)
		)
		(layer "In12.Cu")
	)
	(gr_line
		(start 55.056024 -20.8407)
		(end 55.785004 -20.8407)
		(stroke
			(width 0.1016)
			(type default)
		)
		(layer "In12.Cu")
	)
	(gr_circle
		(center 55.468774 -348.709488)
		(end 56.348884 -348.709488)
		(stroke
			(width 0.2)
			(type default)
		)
		(fill no)
		(layer "In12.Cu")
	)
	(gr_circle
		(center 55.727854 -347.997018)
		(end 56.616854 -347.997018)
		(stroke
			(width 0.2)
			(type default)
		)
		(fill no)
		(layer "In12.Cu")
	)
	(gr_circle
		(center 55.727854 -347.260418)
		(end 56.616854 -347.260418)
		(stroke
			(width 0.2)
			(type default)
		)
		(fill no)
		(layer "In12.Cu")
	)
	(gr_line
		(start 55.785004 -20.8407)
		(end 55.785004 -22.9997)
		(stroke
			(width 0.1016)
			(type default)
		)
		(layer "In12.Cu")
	)
	(gr_circle
		(center 56.17083 -350.318578)
		(end 57.05983 -350.318578)
		(stroke
			(width 0.2)
			(type default)
		)
		(fill no)
		(layer "In12.Cu")
	)
	(gr_circle
		(center 56.17083 -349.581978)
		(end 57.05983 -349.581978)
		(stroke
			(width 0.2)
			(type default)
		)
		(fill no)
		(layer "In12.Cu")
	)
	(gr_circle
		(center 56.695594 -349.142558)
		(end 57.584594 -349.142558)
		(stroke
			(width 0.2)
			(type default)
		)
		(fill no)
		(layer "In12.Cu")
	)
	(gr_circle
		(center 56.720994 -349.904558)
		(end 57.609994 -349.904558)
		(stroke
			(width 0.2)
			(type default)
		)
		(fill no)
		(layer "In12.Cu")
	)
	(gr_circle
		(center 57.254394 -350.260158)
		(end 58.143394 -350.260158)
		(stroke
			(width 0.2)
			(type default)
		)
		(fill no)
		(layer "In12.Cu")
	)
	(gr_circle
		(center 57.254394 -349.523558)
		(end 58.143394 -349.523558)
		(stroke
			(width 0.2)
			(type default)
		)
		(fill no)
		(layer "In12.Cu")
	)
	(gr_circle
		(center 57.254394 -348.786958)
		(end 58.143394 -348.786958)
		(stroke
			(width 0.2)
			(type default)
		)
		(fill no)
		(layer "In12.Cu")
	)
	(gr_line
		(start 57.85104 -23.63978)
		(end 57.85104 -21.48078)
		(stroke
			(width 0.1016)
			(type default)
		)
		(layer "In12.Cu")
	)
	(gr_line
		(start 57.85104 -21.48078)
		(end 58.58002 -21.48078)
		(stroke
			(width 0.1016)
			(type default)
		)
		(layer "In12.Cu")
	)
	(gr_line
		(start 58.58002 -21.48078)
		(end 58.58002 -23.63978)
		(stroke
			(width 0.1016)
			(type default)
		)
		(layer "In12.Cu")
	)
	(gr_circle
		(center 61.93663 -166.86276)
		(end 62.82563 -166.86276)
		(stroke
			(width 0.2)
			(type default)
		)
		(fill no)
		(layer "In12.Cu")
	)
	(gr_circle
		(center 61.93663 -166.12616)
		(end 62.82563 -166.12616)
		(stroke
			(width 0.2)
			(type default)
		)
		(fill no)
		(layer "In12.Cu")
	)
	(gr_circle
		(center 61.93663 -165.38956)
		(end 62.82563 -165.38956)
		(stroke
			(width 0.2)
			(type default)
		)
		(fill no)
		(layer "In12.Cu")
	)
	(gr_circle
		(center 62.47003 -165.74516)
		(end 63.35903 -165.74516)
		(stroke
			(width 0.2)
			(type default)
		)
		(fill no)
		(layer "In12.Cu")
	)
	(gr_circle
		(center 62.49543 -166.50716)
		(end 63.38443 -166.50716)
		(stroke
			(width 0.2)
			(type default)
		)
		(fill no)
		(layer "In12.Cu")
	)
	(gr_circle
		(center 62.565534 -348.709488)
		(end 63.445644 -348.709488)
		(stroke
			(width 0.2)
			(type default)
		)
		(fill no)
		(layer "In12.Cu")
	)
	(gr_circle
		(center 63.020194 -166.06774)
		(end 63.909194 -166.06774)
		(stroke
			(width 0.2)
			(type default)
		)
		(fill no)
		(layer "In12.Cu")
	)
	(gr_circle
		(center 63.020194 -165.33114)
		(end 63.909194 -165.33114)
		(stroke
			(width 0.2)
			(type default)
		)
		(fill no)
		(layer "In12.Cu")
	)
	(gr_circle
		(center 63.182754 -348.709488)
		(end 64.062864 -348.709488)
		(stroke
			(width 0.2)
			(type default)
		)
		(fill no)
		(layer "In12.Cu")
	)
	(gr_circle
		(center 63.199264 -12.43711)
		(end 64.088264 -12.43711)
		(stroke
			(width 0.2)
			(type default)
		)
		(fill no)
		(layer "In12.Cu")
	)
	(gr_circle
		(center 63.579248 -168.42232)
		(end 64.468248 -168.42232)
		(stroke
			(width 0.2)
			(type default)
		)
		(fill no)
		(layer "In12.Cu")
	)
	(gr_circle
		(center 63.579248 -167.68572)
		(end 64.468248 -167.68572)
		(stroke
			(width 0.2)
			(type default)
		)
		(fill no)
		(layer "In12.Cu")
	)
	(gr_circle
		(center 63.631064 -13.09751)
		(end 64.520064 -13.09751)
		(stroke
			(width 0.2)
			(type default)
		)
		(fill no)
		(layer "In12.Cu")
	)
	(gr_circle
		(center 63.72225 -166.94023)
		(end 64.60236 -166.94023)
		(stroke
			(width 0.2)
			(type default)
		)
		(fill no)
		(layer "In12.Cu")
	)
	(gr_circle
		(center 63.799974 -348.709488)
		(end 64.680084 -348.709488)
		(stroke
			(width 0.2)
			(type default)
		)
		(fill no)
		(layer "In12.Cu")
	)
	(gr_circle
		(center 64.061594 -348.038928)
		(end 64.941704 -348.038928)
		(stroke
			(width 0.2)
			(type default)
		)
		(fill no)
		(layer "In12.Cu")
	)
	(gr_circle
		(center 64.061594 -347.302328)
		(end 64.941704 -347.302328)
		(stroke
			(width 0.2)
			(type default)
		)
		(fill no)
		(layer "In12.Cu")
	)
	(gr_circle
		(center 64.088264 -12.43711)
		(end 64.977264 -12.43711)
		(stroke
			(width 0.2)
			(type default)
		)
		(fill no)
		(layer "In12.Cu")
	)
	(gr_circle
		(center 64.33947 -166.94023)
		(end 65.21958 -166.94023)
		(stroke
			(width 0.2)
			(type default)
		)
		(fill no)
		(layer "In12.Cu")
	)
	(gr_circle
		(center 64.50203 -350.318578)
		(end 65.39103 -350.318578)
		(stroke
			(width 0.2)
			(type default)
		)
		(fill no)
		(layer "In12.Cu")
	)
	(gr_circle
		(center 64.50203 -349.581978)
		(end 65.39103 -349.581978)
		(stroke
			(width 0.2)
			(type default)
		)
		(fill no)
		(layer "In12.Cu")
	)
	(gr_circle
		(center 64.520064 -13.09751)
		(end 65.409064 -13.09751)
		(stroke
			(width 0.2)
			(type default)
		)
		(fill no)
		(layer "In12.Cu")
	)
	(gr_circle
		(center 64.95669 -166.94023)
		(end 65.8368 -166.94023)
		(stroke
			(width 0.2)
			(type default)
		)
		(fill no)
		(layer "In12.Cu")
	)
	(gr_circle
		(center 64.977264 -12.43711)
		(end 65.866264 -12.43711)
		(stroke
			(width 0.2)
			(type default)
		)
		(fill no)
		(layer "In12.Cu")
	)
	(gr_circle
		(center 65.026794 -349.142558)
		(end 65.915794 -349.142558)
		(stroke
			(width 0.2)
			(type default)
		)
		(fill no)
		(layer "In12.Cu")
	)
	(gr_circle
		(center 65.052194 -349.904558)
		(end 65.941194 -349.904558)
		(stroke
			(width 0.2)
			(type default)
		)
		(fill no)
		(layer "In12.Cu")
	)
	(gr_circle
		(center 65.409064 -13.09751)
		(end 66.298064 -13.09751)
		(stroke
			(width 0.2)
			(type default)
		)
		(fill no)
		(layer "In12.Cu")
	)
	(gr_circle
		(center 65.585594 -350.260158)
		(end 66.474594 -350.260158)
		(stroke
			(width 0.2)
			(type default)
		)
		(fill no)
		(layer "In12.Cu")
	)
	(gr_circle
		(center 65.585594 -349.523558)
		(end 66.474594 -349.523558)
		(stroke
			(width 0.2)
			(type default)
		)
		(fill no)
		(layer "In12.Cu")
	)
	(gr_circle
		(center 65.585594 -348.786958)
		(end 66.474594 -348.786958)
		(stroke
			(width 0.2)
			(type default)
		)
		(fill no)
		(layer "In12.Cu")
	)
	(gr_circle
		(center 65.866264 -12.43711)
		(end 66.755264 -12.43711)
		(stroke
			(width 0.2)
			(type default)
		)
		(fill no)
		(layer "In12.Cu")
	)
	(gr_circle
		(center 66.298064 -13.09751)
		(end 67.187064 -13.09751)
		(stroke
			(width 0.2)
			(type default)
		)
		(fill no)
		(layer "In12.Cu")
	)
	(gr_circle
		(center 66.399664 -25.56891)
		(end 67.288664 -25.56891)
		(stroke
			(width 0.2)
			(type default)
		)
		(fill no)
		(layer "In12.Cu")
	)
	(gr_circle
		(center 66.501264 -12.43711)
		(end 67.390264 -12.43711)
		(stroke
			(width 0.2)
			(type default)
		)
		(fill no)
		(layer "In12.Cu")
	)
	(gr_circle
		(center 66.774822 -20.327366)
		(end 67.663822 -20.327366)
		(stroke
			(width 0.2)
			(type default)
		)
		(fill no)
		(layer "In12.Cu")
	)
	(gr_circle
		(center 66.774822 -19.692366)
		(end 67.663822 -19.692366)
		(stroke
			(width 0.2)
			(type default)
		)
		(fill no)
		(layer "In12.Cu")
	)
	(gr_circle
		(center 66.780664 -24.88311)
		(end 67.669664 -24.88311)
		(stroke
			(width 0.2)
			(type default)
		)
		(fill no)
		(layer "In12.Cu")
	)
	(gr_circle
		(center 66.848228 -18.642584)
		(end 67.737228 -18.642584)
		(stroke
			(width 0.2)
			(type default)
		)
		(fill no)
		(layer "In12.Cu")
	)
	(gr_circle
		(center 66.882264 -22.26691)
		(end 67.771264 -22.26691)
		(stroke
			(width 0.2)
			(type default)
		)
		(fill no)
		(layer "In12.Cu")
	)
	(gr_circle
		(center 66.933064 -13.09751)
		(end 67.822064 -13.09751)
		(stroke
			(width 0.2)
			(type default)
		)
		(fill no)
		(layer "In12.Cu")
	)
	(gr_circle
		(center 67.288664 -25.56891)
		(end 68.177664 -25.56891)
		(stroke
			(width 0.2)
			(type default)
		)
		(fill no)
		(layer "In12.Cu")
	)
	(gr_circle
		(center 67.40271 -12.489434)
		(end 68.29171 -12.489434)
		(stroke
			(width 0.2)
			(type default)
		)
		(fill no)
		(layer "In12.Cu")
	)
	(gr_circle
		(center 67.669664 -24.88311)
		(end 68.558664 -24.88311)
		(stroke
			(width 0.2)
			(type default)
		)
		(fill no)
		(layer "In12.Cu")
	)
	(gr_circle
		(center 68.177664 -25.56891)
		(end 69.066664 -25.56891)
		(stroke
			(width 0.2)
			(type default)
		)
		(fill no)
		(layer "In12.Cu")
	)
	(gr_circle
		(center 68.54444 -18.476214)
		(end 69.43344 -18.476214)
		(stroke
			(width 0.2)
			(type default)
		)
		(fill no)
		(layer "In12.Cu")
	)
	(gr_circle
		(center 68.558664 -24.88311)
		(end 69.447664 -24.88311)
		(stroke
			(width 0.2)
			(type default)
		)
		(fill no)
		(layer "In12.Cu")
	)
	(gr_circle
		(center 69.498464 -24.55291)
		(end 70.387464 -24.55291)
		(stroke
			(width 0.2)
			(type default)
		)
		(fill no)
		(layer "In12.Cu")
	)
	(gr_circle
		(center 70.25005 -175.559974)
		(end 71.13905 -175.559974)
		(stroke
			(width 0.2)
			(type default)
		)
		(fill no)
		(layer "In12.Cu")
	)
	(gr_circle
		(center 70.25005 -174.823374)
		(end 71.13905 -174.823374)
		(stroke
			(width 0.2)
			(type default)
		)
		(fill no)
		(layer "In12.Cu")
	)
	(gr_circle
		(center 70.25005 -174.086774)
		(end 71.13905 -174.086774)
		(stroke
			(width 0.2)
			(type default)
		)
		(fill no)
		(layer "In12.Cu")
	)
	(gr_circle
		(center 70.78345 -174.442374)
		(end 71.67245 -174.442374)
		(stroke
			(width 0.2)
			(type default)
		)
		(fill no)
		(layer "In12.Cu")
	)
	(gr_circle
		(center 70.80885 -175.204374)
		(end 71.69785 -175.204374)
		(stroke
			(width 0.2)
			(type default)
		)
		(fill no)
		(layer "In12.Cu")
	)
	(gr_circle
		(center 71.099934 -336.988404)
		(end 71.980044 -336.988404)
		(stroke
			(width 0.2)
			(type default)
		)
		(fill no)
		(layer "In12.Cu")
	)
	(gr_circle
		(center 71.333614 -174.764954)
		(end 72.222614 -174.764954)
		(stroke
			(width 0.2)
			(type default)
		)
		(fill no)
		(layer "In12.Cu")
	)
	(gr_circle
		(center 71.333614 -174.028354)
		(end 72.222614 -174.028354)
		(stroke
			(width 0.2)
			(type default)
		)
		(fill no)
		(layer "In12.Cu")
	)
	(gr_circle
		(center 71.717154 -336.988404)
		(end 72.597264 -336.988404)
		(stroke
			(width 0.2)
			(type default)
		)
		(fill no)
		(layer "In12.Cu")
	)
	(gr_circle
		(center 71.892668 -177.10912)
		(end 72.781668 -177.10912)
		(stroke
			(width 0.2)
			(type default)
		)
		(fill no)
		(layer "In12.Cu")
	)
	(gr_circle
		(center 71.892668 -176.37252)
		(end 72.781668 -176.37252)
		(stroke
			(width 0.2)
			(type default)
		)
		(fill no)
		(layer "In12.Cu")
	)
	(gr_circle
		(center 72.03567 -175.639222)
		(end 72.91578 -175.639222)
		(stroke
			(width 0.2)
			(type default)
		)
		(fill no)
		(layer "In12.Cu")
	)
	(gr_circle
		(center 72.334374 -336.988404)
		(end 73.214484 -336.988404)
		(stroke
			(width 0.2)
			(type default)
		)
		(fill no)
		(layer "In12.Cu")
	)
	(gr_circle
		(center 72.616314 -336.255868)
		(end 73.496424 -336.255868)
		(stroke
			(width 0.2)
			(type default)
		)
		(fill no)
		(layer "In12.Cu")
	)
	(gr_circle
		(center 72.616314 -335.519268)
		(end 73.496424 -335.519268)
		(stroke
			(width 0.2)
			(type default)
		)
		(fill no)
		(layer "In12.Cu")
	)
	(gr_circle
		(center 72.65289 -175.639222)
		(end 73.533 -175.639222)
		(stroke
			(width 0.2)
			(type default)
		)
		(fill no)
		(layer "In12.Cu")
	)
	(gr_circle
		(center 73.03643 -338.597494)
		(end 73.92543 -338.597494)
		(stroke
			(width 0.2)
			(type default)
		)
		(fill no)
		(layer "In12.Cu")
	)
	(gr_circle
		(center 73.03643 -337.860894)
		(end 73.92543 -337.860894)
		(stroke
			(width 0.2)
			(type default)
		)
		(fill no)
		(layer "In12.Cu")
	)
	(gr_circle
		(center 73.27011 -175.639222)
		(end 74.15022 -175.639222)
		(stroke
			(width 0.2)
			(type default)
		)
		(fill no)
		(layer "In12.Cu")
	)
	(gr_circle
		(center 73.561194 -337.421474)
		(end 74.450194 -337.421474)
		(stroke
			(width 0.2)
			(type default)
		)
		(fill no)
		(layer "In12.Cu")
	)
	(gr_circle
		(center 73.586594 -338.183474)
		(end 74.475594 -338.183474)
		(stroke
			(width 0.2)
			(type default)
		)
		(fill no)
		(layer "In12.Cu")
	)
	(gr_circle
		(center 74.119994 -338.539074)
		(end 75.008994 -338.539074)
		(stroke
			(width 0.2)
			(type default)
		)
		(fill no)
		(layer "In12.Cu")
	)
	(gr_circle
		(center 74.119994 -337.802474)
		(end 75.008994 -337.802474)
		(stroke
			(width 0.2)
			(type default)
		)
		(fill no)
		(layer "In12.Cu")
	)
	(gr_circle
		(center 74.119994 -337.065874)
		(end 75.008994 -337.065874)
		(stroke
			(width 0.2)
			(type default)
		)
		(fill no)
		(layer "In12.Cu")
	)
	(gr_circle
		(center 74.811382 -351.637854)
		(end 75.700382 -351.637854)
		(stroke
			(width 0.2)
			(type default)
		)
		(fill no)
		(layer "In12.Cu")
	)
	(gr_circle
		(center 74.849482 -353.131374)
		(end 75.738482 -353.131374)
		(stroke
			(width 0.2)
			(type default)
		)
		(fill no)
		(layer "In12.Cu")
	)
	(gr_circle
		(center 74.849736 -352.30816)
		(end 75.738736 -352.30816)
		(stroke
			(width 0.2)
			(type default)
		)
		(fill no)
		(layer "In12.Cu")
	)
	(gr_circle
		(center 74.86015 -350.929448)
		(end 75.74915 -350.929448)
		(stroke
			(width 0.2)
			(type default)
		)
		(fill no)
		(layer "In12.Cu")
	)
	(gr_circle
		(center 77.178408 -16.520668)
		(end 78.067408 -16.520668)
		(stroke
			(width 0.2)
			(type default)
		)
		(fill no)
		(layer "In12.Cu")
	)
	(gr_circle
		(center 77.473048 -351.5995)
		(end 78.362048 -351.5995)
		(stroke
			(width 0.2)
			(type default)
		)
		(fill no)
		(layer "In12.Cu")
	)
	(gr_circle
		(center 77.511402 -352.978212)
		(end 78.400402 -352.978212)
		(stroke
			(width 0.2)
			(type default)
		)
		(fill no)
		(layer "In12.Cu")
	)
	(gr_circle
		(center 77.511402 -352.269806)
		(end 78.400402 -352.269806)
		(stroke
			(width 0.2)
			(type default)
		)
		(fill no)
		(layer "In12.Cu")
	)
	(gr_circle
		(center 77.521816 -350.891094)
		(end 78.410816 -350.891094)
		(stroke
			(width 0.2)
			(type default)
		)
		(fill no)
		(layer "In12.Cu")
	)
	(gr_circle
		(center 77.84338 -16.55064)
		(end 78.73238 -16.55064)
		(stroke
			(width 0.2)
			(type default)
		)
		(fill no)
		(layer "In12.Cu")
	)
	(gr_circle
		(center 78.85303 -178.798474)
		(end 79.74203 -178.798474)
		(stroke
			(width 0.2)
			(type default)
		)
		(fill no)
		(layer "In12.Cu")
	)
	(gr_circle
		(center 78.85303 -178.036474)
		(end 79.74203 -178.036474)
		(stroke
			(width 0.2)
			(type default)
		)
		(fill no)
		(layer "In12.Cu")
	)
	(gr_circle
		(center 79.10703 -179.560474)
		(end 79.99603 -179.560474)
		(stroke
			(width 0.2)
			(type default)
		)
		(fill no)
		(layer "In12.Cu")
	)
	(gr_circle
		(center 79.13243 -180.322474)
		(end 80.02143 -180.322474)
		(stroke
			(width 0.2)
			(type default)
		)
		(fill no)
		(layer "In12.Cu")
	)
	(gr_circle
		(center 79.403194 -178.384454)
		(end 80.292194 -178.384454)
		(stroke
			(width 0.2)
			(type default)
		)
		(fill no)
		(layer "In12.Cu")
	)
	(gr_circle
		(center 79.455518 -336.981292)
		(end 80.335628 -336.981292)
		(stroke
			(width 0.2)
			(type default)
		)
		(fill no)
		(layer "In12.Cu")
	)
	(gr_circle
		(center 79.657194 -179.883054)
		(end 80.546194 -179.883054)
		(stroke
			(width 0.2)
			(type default)
		)
		(fill no)
		(layer "In12.Cu")
	)
	(gr_circle
		(center 79.657194 -179.146454)
		(end 80.546194 -179.146454)
		(stroke
			(width 0.2)
			(type default)
		)
		(fill no)
		(layer "In12.Cu")
	)
	(gr_circle
		(center 79.921862 -18.238724)
		(end 80.810862 -18.238724)
		(stroke
			(width 0.2)
			(type default)
		)
		(fill no)
		(layer "In12.Cu")
	)
	(gr_circle
		(center 79.921862 -17.502124)
		(end 80.810862 -17.502124)
		(stroke
			(width 0.2)
			(type default)
		)
		(fill no)
		(layer "In12.Cu")
	)
	(gr_circle
		(center 80.072738 -336.981292)
		(end 80.952848 -336.981292)
		(stroke
			(width 0.2)
			(type default)
		)
		(fill no)
		(layer "In12.Cu")
	)
	(gr_circle
		(center 80.241648 -182.2196)
		(end 81.130648 -182.2196)
		(stroke
			(width 0.2)
			(type default)
		)
		(fill no)
		(layer "In12.Cu")
	)
	(gr_circle
		(center 80.241648 -181.483)
		(end 81.130648 -181.483)
		(stroke
			(width 0.2)
			(type default)
		)
		(fill no)
		(layer "In12.Cu")
	)
	(gr_circle
		(center 80.35925 -180.755544)
		(end 81.23936 -180.755544)
		(stroke
			(width 0.2)
			(type default)
		)
		(fill no)
		(layer "In12.Cu")
	)
	(gr_circle
		(center 80.689958 -336.981292)
		(end 81.570068 -336.981292)
		(stroke
			(width 0.2)
			(type default)
		)
		(fill no)
		(layer "In12.Cu")
	)
	(gr_circle
		(center 80.97647 -180.755544)
		(end 81.85658 -180.755544)
		(stroke
			(width 0.2)
			(type default)
		)
		(fill no)
		(layer "In12.Cu")
	)
	(gr_circle
		(center 80.977994 -336.245708)
		(end 81.858104 -336.245708)
		(stroke
			(width 0.2)
			(type default)
		)
		(fill no)
		(layer "In12.Cu")
	)
	(gr_circle
		(center 80.977994 -335.509108)
		(end 81.858104 -335.509108)
		(stroke
			(width 0.2)
			(type default)
		)
		(fill no)
		(layer "In12.Cu")
	)
	(gr_line
		(start 81.193894 -9.780016)
		(end 81.193894 -0.508)
		(stroke
			(width 0.2)
			(type default)
		)
		(layer "In12.Cu")
	)
	(gr_arc
		(start 81.193894 -9.780016)
		(mid 81.928474 -11.55343)
		(end 83.70189 -12.288012)
		(stroke
			(width 0.2)
			(type default)
		)
		(layer "In12.Cu")
	)
	(gr_line
		(start 81.193894 -0.508)
		(end 13.610082 -0.508)
		(stroke
			(width 0.2)
			(type default)
		)
		(layer "In12.Cu")
	)
	(gr_circle
		(center 81.392014 -338.590382)
		(end 82.281014 -338.590382)
		(stroke
			(width 0.2)
			(type default)
		)
		(fill no)
		(layer "In12.Cu")
	)
	(gr_circle
		(center 81.392014 -337.853782)
		(end 82.281014 -337.853782)
		(stroke
			(width 0.2)
			(type default)
		)
		(fill no)
		(layer "In12.Cu")
	)
	(gr_circle
		(center 81.59369 -180.755544)
		(end 82.4738 -180.755544)
		(stroke
			(width 0.2)
			(type default)
		)
		(fill no)
		(layer "In12.Cu")
	)
	(gr_arc
		(start 81.701894 -9.780016)
		(mid 82.287679 -11.194227)
		(end 83.70189 -11.780012)
		(stroke
			(width 1.016)
			(type default)
		)
		(layer "In12.Cu")
	)
	(gr_arc
		(start 81.701894 -0.500126)
		(mid 81.555625 -0.146451)
		(end 81.202022 0)
		(stroke
			(width 1.016)
			(type default)
		)
		(layer "In12.Cu")
	)
	(gr_line
		(start 81.701894 -0.500126)
		(end 81.701894 -9.780016)
		(stroke
			(width 1.016)
			(type default)
		)
		(layer "In12.Cu")
	)
	(gr_circle
		(center 81.916778 -337.414362)
		(end 82.805778 -337.414362)
		(stroke
			(width 0.2)
			(type default)
		)
		(fill no)
		(layer "In12.Cu")
	)
	(gr_circle
		(center 81.942178 -338.176362)
		(end 82.831178 -338.176362)
		(stroke
			(width 0.2)
			(type default)
		)
		(fill no)
		(layer "In12.Cu")
	)
	(gr_circle
		(center 82.183986 -348.89948)
		(end 83.072986 -348.89948)
		(stroke
			(width 0.2)
			(type default)
		)
		(fill no)
		(layer "In12.Cu")
	)
	(gr_circle
		(center 82.222086 -350.393)
		(end 83.111086 -350.393)
		(stroke
			(width 0.2)
			(type default)
		)
		(fill no)
		(layer "In12.Cu")
	)
	(gr_circle
		(center 82.22234 -349.569786)
		(end 83.11134 -349.569786)
		(stroke
			(width 0.2)
			(type default)
		)
		(fill no)
		(layer "In12.Cu")
	)
	(gr_circle
		(center 82.232754 -348.191074)
		(end 83.121754 -348.191074)
		(stroke
			(width 0.2)
			(type default)
		)
		(fill no)
		(layer "In12.Cu")
	)
	(gr_circle
		(center 82.475578 -338.531962)
		(end 83.364578 -338.531962)
		(stroke
			(width 0.2)
			(type default)
		)
		(fill no)
		(layer "In12.Cu")
	)
	(gr_circle
		(center 82.475578 -337.795362)
		(end 83.364578 -337.795362)
		(stroke
			(width 0.2)
			(type default)
		)
		(fill no)
		(layer "In12.Cu")
	)
	(gr_circle
		(center 82.475578 -337.058762)
		(end 83.364578 -337.058762)
		(stroke
			(width 0.2)
			(type default)
		)
		(fill no)
		(layer "In12.Cu")
	)
	(gr_circle
		(center 82.989674 -165.962076)
		(end 84.386674 -165.962076)
		(stroke
			(width 0.2)
			(type default)
		)
		(fill no)
		(layer "In12.Cu")
	)
	(gr_line
		(start 83.70189 -11.780012)
		(end 124.102114 -11.780012)
		(stroke
			(width 1.016)
			(type default)
		)
		(layer "In12.Cu")
	)
	(gr_circle
		(center 84.845652 -348.861126)
		(end 85.734652 -348.861126)
		(stroke
			(width 0.2)
			(type default)
		)
		(fill no)
		(layer "In12.Cu")
	)
	(gr_circle
		(center 84.884006 -350.239838)
		(end 85.773006 -350.239838)
		(stroke
			(width 0.2)
			(type default)
		)
		(fill no)
		(layer "In12.Cu")
	)
	(gr_circle
		(center 84.884006 -349.531432)
		(end 85.773006 -349.531432)
		(stroke
			(width 0.2)
			(type default)
		)
		(fill no)
		(layer "In12.Cu")
	)
	(gr_circle
		(center 84.89442 -348.15272)
		(end 85.78342 -348.15272)
		(stroke
			(width 0.2)
			(type default)
		)
		(fill no)
		(layer "In12.Cu")
	)
	(gr_circle
		(center 86.97087 -180.610002)
		(end 87.85987 -180.610002)
		(stroke
			(width 0.2)
			(type default)
		)
		(fill no)
		(layer "In12.Cu")
	)
	(gr_circle
		(center 86.97087 -179.873402)
		(end 87.85987 -179.873402)
		(stroke
			(width 0.2)
			(type default)
		)
		(fill no)
		(layer "In12.Cu")
	)
	(gr_circle
		(center 86.97087 -179.136802)
		(end 87.85987 -179.136802)
		(stroke
			(width 0.2)
			(type default)
		)
		(fill no)
		(layer "In12.Cu")
	)
	(gr_circle
		(center 87.01913 -164.097716)
		(end 87.90813 -164.097716)
		(stroke
			(width 0.2)
			(type default)
		)
		(fill no)
		(layer "In12.Cu")
	)
	(gr_circle
		(center 87.03945 -163.447476)
		(end 87.92845 -163.447476)
		(stroke
			(width 0.2)
			(type default)
		)
		(fill no)
		(layer "In12.Cu")
	)
	(gr_circle
		(center 87.03945 -162.812476)
		(end 87.92845 -162.812476)
		(stroke
			(width 0.2)
			(type default)
		)
		(fill no)
		(layer "In12.Cu")
	)
	(gr_circle
		(center 87.50427 -179.492402)
		(end 88.39327 -179.492402)
		(stroke
			(width 0.2)
			(type default)
		)
		(fill no)
		(layer "In12.Cu")
	)
	(gr_circle
		(center 87.52967 -180.254402)
		(end 88.41867 -180.254402)
		(stroke
			(width 0.2)
			(type default)
		)
		(fill no)
		(layer "In12.Cu")
	)
	(gr_circle
		(center 87.65413 -164.097716)
		(end 88.54313 -164.097716)
		(stroke
			(width 0.2)
			(type default)
		)
		(fill no)
		(layer "In12.Cu")
	)
	(gr_circle
		(center 87.67445 -163.447476)
		(end 88.56345 -163.447476)
		(stroke
			(width 0.2)
			(type default)
		)
		(fill no)
		(layer "In12.Cu")
	)
	(gr_circle
		(center 87.67445 -162.812476)
		(end 88.56345 -162.812476)
		(stroke
			(width 0.2)
			(type default)
		)
		(fill no)
		(layer "In12.Cu")
	)
	(gr_circle
		(center 87.813134 -336.966814)
		(end 88.693244 -336.966814)
		(stroke
			(width 0.2)
			(type default)
		)
		(fill no)
		(layer "In12.Cu")
	)
	(gr_circle
		(center 88.054434 -179.814982)
		(end 88.943434 -179.814982)
		(stroke
			(width 0.2)
			(type default)
		)
		(fill no)
		(layer "In12.Cu")
	)
	(gr_circle
		(center 88.054434 -179.078382)
		(end 88.943434 -179.078382)
		(stroke
			(width 0.2)
			(type default)
		)
		(fill no)
		(layer "In12.Cu")
	)
	(gr_circle
		(center 88.28913 -164.097716)
		(end 89.17813 -164.097716)
		(stroke
			(width 0.2)
			(type default)
		)
		(fill no)
		(layer "In12.Cu")
	)
	(gr_circle
		(center 88.30945 -163.447476)
		(end 89.19845 -163.447476)
		(stroke
			(width 0.2)
			(type default)
		)
		(fill no)
		(layer "In12.Cu")
	)
	(gr_circle
		(center 88.30945 -162.812476)
		(end 89.19845 -162.812476)
		(stroke
			(width 0.2)
			(type default)
		)
		(fill no)
		(layer "In12.Cu")
	)
	(gr_circle
		(center 88.430354 -336.966814)
		(end 89.310464 -336.966814)
		(stroke
			(width 0.2)
			(type default)
		)
		(fill no)
		(layer "In12.Cu")
	)
	(gr_circle
		(center 88.49233 -182.13324)
		(end 89.38133 -182.13324)
		(stroke
			(width 0.2)
			(type default)
		)
		(fill no)
		(layer "In12.Cu")
	)
	(gr_circle
		(center 88.49233 -181.39664)
		(end 89.38133 -181.39664)
		(stroke
			(width 0.2)
			(type default)
		)
		(fill no)
		(layer "In12.Cu")
	)
	(gr_circle
		(center 88.75649 -180.687472)
		(end 89.6366 -180.687472)
		(stroke
			(width 0.2)
			(type default)
		)
		(fill no)
		(layer "In12.Cu")
	)
	(gr_circle
		(center 88.92413 -164.097716)
		(end 89.81313 -164.097716)
		(stroke
			(width 0.2)
			(type default)
		)
		(fill no)
		(layer "In12.Cu")
	)
	(gr_circle
		(center 88.94445 -163.447476)
		(end 89.83345 -163.447476)
		(stroke
			(width 0.2)
			(type default)
		)
		(fill no)
		(layer "In12.Cu")
	)
	(gr_circle
		(center 88.94445 -162.812476)
		(end 89.83345 -162.812476)
		(stroke
			(width 0.2)
			(type default)
		)
		(fill no)
		(layer "In12.Cu")
	)
	(gr_circle
		(center 89.047574 -336.966814)
		(end 89.927684 -336.966814)
		(stroke
			(width 0.2)
			(type default)
		)
		(fill no)
		(layer "In12.Cu")
	)
	(gr_circle
		(center 89.314528 -345.237562)
		(end 90.203528 -345.237562)
		(stroke
			(width 0.2)
			(type default)
		)
		(fill no)
		(layer "In12.Cu")
	)
	(gr_circle
		(center 89.319354 -336.255868)
		(end 90.199464 -336.255868)
		(stroke
			(width 0.2)
			(type default)
		)
		(fill no)
		(layer "In12.Cu")
	)
	(gr_circle
		(center 89.319354 -335.519268)
		(end 90.199464 -335.519268)
		(stroke
			(width 0.2)
			(type default)
		)
		(fill no)
		(layer "In12.Cu")
	)
	(gr_circle
		(center 89.350088 -345.96959)
		(end 90.239088 -345.96959)
		(stroke
			(width 0.2)
			(type default)
		)
		(fill no)
		(layer "In12.Cu")
	)
	(gr_circle
		(center 89.37371 -180.687472)
		(end 90.25382 -180.687472)
		(stroke
			(width 0.2)
			(type default)
		)
		(fill no)
		(layer "In12.Cu")
	)
	(gr_circle
		(center 89.388442 -346.639896)
		(end 90.277442 -346.639896)
		(stroke
			(width 0.2)
			(type default)
		)
		(fill no)
		(layer "In12.Cu")
	)
	(gr_circle
		(center 89.55913 -164.097716)
		(end 90.44813 -164.097716)
		(stroke
			(width 0.2)
			(type default)
		)
		(fill no)
		(layer "In12.Cu")
	)
	(gr_circle
		(center 89.57945 -163.447476)
		(end 90.46845 -163.447476)
		(stroke
			(width 0.2)
			(type default)
		)
		(fill no)
		(layer "In12.Cu")
	)
	(gr_circle
		(center 89.57945 -162.812476)
		(end 90.46845 -162.812476)
		(stroke
			(width 0.2)
			(type default)
		)
		(fill no)
		(layer "In12.Cu")
	)
	(gr_circle
		(center 89.74963 -338.575904)
		(end 90.63863 -338.575904)
		(stroke
			(width 0.2)
			(type default)
		)
		(fill no)
		(layer "In12.Cu")
	)
	(gr_circle
		(center 89.74963 -337.839304)
		(end 90.63863 -337.839304)
		(stroke
			(width 0.2)
			(type default)
		)
		(fill no)
		(layer "In12.Cu")
	)
	(gr_circle
		(center 89.983056 -345.261184)
		(end 90.872056 -345.261184)
		(stroke
			(width 0.2)
			(type default)
		)
		(fill no)
		(layer "In12.Cu")
	)
	(gr_circle
		(center 89.985088 -345.96959)
		(end 90.874088 -345.96959)
		(stroke
			(width 0.2)
			(type default)
		)
		(fill no)
		(layer "In12.Cu")
	)
	(gr_circle
		(center 89.99093 -180.687472)
		(end 90.87104 -180.687472)
		(stroke
			(width 0.2)
			(type default)
		)
		(fill no)
		(layer "In12.Cu")
	)
	(gr_circle
		(center 90.023442 -346.639896)
		(end 90.912442 -346.639896)
		(stroke
			(width 0.2)
			(type default)
		)
		(fill no)
		(layer "In12.Cu")
	)
	(gr_circle
		(center 90.21953 -164.107876)
		(end 91.10853 -164.107876)
		(stroke
			(width 0.2)
			(type default)
		)
		(fill no)
		(layer "In12.Cu")
	)
	(gr_circle
		(center 90.23985 -163.457636)
		(end 91.12885 -163.457636)
		(stroke
			(width 0.2)
			(type default)
		)
		(fill no)
		(layer "In12.Cu")
	)
	(gr_circle
		(center 90.23985 -162.822636)
		(end 91.12885 -162.822636)
		(stroke
			(width 0.2)
			(type default)
		)
		(fill no)
		(layer "In12.Cu")
	)
	(gr_circle
		(center 90.274394 -337.399884)
		(end 91.163394 -337.399884)
		(stroke
			(width 0.2)
			(type default)
		)
		(fill no)
		(layer "In12.Cu")
	)
	(gr_circle
		(center 90.299794 -338.161884)
		(end 91.188794 -338.161884)
		(stroke
			(width 0.2)
			(type default)
		)
		(fill no)
		(layer "In12.Cu")
	)
	(gr_circle
		(center 90.618056 -345.261184)
		(end 91.507056 -345.261184)
		(stroke
			(width 0.2)
			(type default)
		)
		(fill no)
		(layer "In12.Cu")
	)
	(gr_circle
		(center 90.620088 -345.96959)
		(end 91.509088 -345.96959)
		(stroke
			(width 0.2)
			(type default)
		)
		(fill no)
		(layer "In12.Cu")
	)
	(gr_circle
		(center 90.658442 -346.639896)
		(end 91.547442 -346.639896)
		(stroke
			(width 0.2)
			(type default)
		)
		(fill no)
		(layer "In12.Cu")
	)
	(gr_circle
		(center 90.833194 -338.517484)
		(end 91.722194 -338.517484)
		(stroke
			(width 0.2)
			(type default)
		)
		(fill no)
		(layer "In12.Cu")
	)
	(gr_circle
		(center 90.833194 -337.780884)
		(end 91.722194 -337.780884)
		(stroke
			(width 0.2)
			(type default)
		)
		(fill no)
		(layer "In12.Cu")
	)
	(gr_circle
		(center 90.833194 -337.044284)
		(end 91.722194 -337.044284)
		(stroke
			(width 0.2)
			(type default)
		)
		(fill no)
		(layer "In12.Cu")
	)
	(gr_circle
		(center 91.255088 -345.96959)
		(end 92.144088 -345.96959)
		(stroke
			(width 0.2)
			(type default)
		)
		(fill no)
		(layer "In12.Cu")
	)
	(gr_circle
		(center 91.293442 -346.639896)
		(end 92.182442 -346.639896)
		(stroke
			(width 0.2)
			(type default)
		)
		(fill no)
		(layer "In12.Cu")
	)
	(gr_circle
		(center 91.380056 -345.261184)
		(end 92.269056 -345.261184)
		(stroke
			(width 0.2)
			(type default)
		)
		(fill no)
		(layer "In12.Cu")
	)
	(gr_circle
		(center 91.966288 -345.96959)
		(end 92.855288 -345.96959)
		(stroke
			(width 0.2)
			(type default)
		)
		(fill no)
		(layer "In12.Cu")
	)
	(gr_circle
		(center 92.004642 -346.639896)
		(end 92.893642 -346.639896)
		(stroke
			(width 0.2)
			(type default)
		)
		(fill no)
		(layer "In12.Cu")
	)
	(gr_circle
		(center 92.015056 -345.261184)
		(end 92.904056 -345.261184)
		(stroke
			(width 0.2)
			(type default)
		)
		(fill no)
		(layer "In12.Cu")
	)
	(gr_circle
		(center 92.387674 -165.962076)
		(end 93.784674 -165.962076)
		(stroke
			(width 0.2)
			(type default)
		)
		(fill no)
		(layer "In12.Cu")
	)
	(gr_circle
		(center 92.601288 -345.96959)
		(end 93.490288 -345.96959)
		(stroke
			(width 0.2)
			(type default)
		)
		(fill no)
		(layer "In12.Cu")
	)
	(gr_circle
		(center 92.639642 -346.639896)
		(end 93.528642 -346.639896)
		(stroke
			(width 0.2)
			(type default)
		)
		(fill no)
		(layer "In12.Cu")
	)
	(gr_circle
		(center 92.650056 -345.261184)
		(end 93.539056 -345.261184)
		(stroke
			(width 0.2)
			(type default)
		)
		(fill no)
		(layer "In12.Cu")
	)
	(gr_circle
		(center 95.36303 -180.627274)
		(end 96.25203 -180.627274)
		(stroke
			(width 0.2)
			(type default)
		)
		(fill no)
		(layer "In12.Cu")
	)
	(gr_circle
		(center 95.36303 -179.890674)
		(end 96.25203 -179.890674)
		(stroke
			(width 0.2)
			(type default)
		)
		(fill no)
		(layer "In12.Cu")
	)
	(gr_circle
		(center 95.36303 -179.154074)
		(end 96.25203 -179.154074)
		(stroke
			(width 0.2)
			(type default)
		)
		(fill no)
		(layer "In12.Cu")
	)
	(gr_circle
		(center 95.89643 -179.509674)
		(end 96.78543 -179.509674)
		(stroke
			(width 0.2)
			(type default)
		)
		(fill no)
		(layer "In12.Cu")
	)
	(gr_circle
		(center 95.92183 -180.271674)
		(end 96.81083 -180.271674)
		(stroke
			(width 0.2)
			(type default)
		)
		(fill no)
		(layer "In12.Cu")
	)
	(gr_circle
		(center 96.144334 -337.017614)
		(end 97.024444 -337.017614)
		(stroke
			(width 0.2)
			(type default)
		)
		(fill no)
		(layer "In12.Cu")
	)
	(gr_circle
		(center 96.446594 -179.832254)
		(end 97.335594 -179.832254)
		(stroke
			(width 0.2)
			(type default)
		)
		(fill no)
		(layer "In12.Cu")
	)
	(gr_circle
		(center 96.446594 -179.095654)
		(end 97.335594 -179.095654)
		(stroke
			(width 0.2)
			(type default)
		)
		(fill no)
		(layer "In12.Cu")
	)
	(gr_circle
		(center 96.761554 -337.017614)
		(end 97.641664 -337.017614)
		(stroke
			(width 0.2)
			(type default)
		)
		(fill no)
		(layer "In12.Cu")
	)
	(gr_circle
		(center 96.980248 -182.13324)
		(end 97.869248 -182.13324)
		(stroke
			(width 0.2)
			(type default)
		)
		(fill no)
		(layer "In12.Cu")
	)
	(gr_circle
		(center 96.980248 -181.39664)
		(end 97.869248 -181.39664)
		(stroke
			(width 0.2)
			(type default)
		)
		(fill no)
		(layer "In12.Cu")
	)
	(gr_circle
		(center 97.14865 -180.704744)
		(end 98.02876 -180.704744)
		(stroke
			(width 0.2)
			(type default)
		)
		(fill no)
		(layer "In12.Cu")
	)
	(gr_circle
		(center 97.378774 -337.017614)
		(end 98.258884 -337.017614)
		(stroke
			(width 0.2)
			(type default)
		)
		(fill no)
		(layer "In12.Cu")
	)
	(gr_circle
		(center 97.658174 -336.319368)
		(end 98.538284 -336.319368)
		(stroke
			(width 0.2)
			(type default)
		)
		(fill no)
		(layer "In12.Cu")
	)
	(gr_circle
		(center 97.658174 -335.582768)
		(end 98.538284 -335.582768)
		(stroke
			(width 0.2)
			(type default)
		)
		(fill no)
		(layer "In12.Cu")
	)
	(gr_circle
		(center 97.76587 -180.704744)
		(end 98.64598 -180.704744)
		(stroke
			(width 0.2)
			(type default)
		)
		(fill no)
		(layer "In12.Cu")
	)
	(gr_circle
		(center 97.981008 -273.276314)
		(end 98.235008 -273.276314)
		(stroke
			(width 0.1016)
			(type default)
		)
		(fill no)
		(layer "In12.Cu")
	)
	(gr_circle
		(center 97.981008 -271.656302)
		(end 98.235008 -271.656302)
		(stroke
			(width 0.1016)
			(type default)
		)
		(fill no)
		(layer "In12.Cu")
	)
	(gr_circle
		(center 97.981008 -270.03629)
		(end 98.235008 -270.03629)
		(stroke
			(width 0.1016)
			(type default)
		)
		(fill no)
		(layer "In12.Cu")
	)
	(gr_circle
		(center 98.08083 -338.626704)
		(end 98.96983 -338.626704)
		(stroke
			(width 0.2)
			(type default)
		)
		(fill no)
		(layer "In12.Cu")
	)
	(gr_circle
		(center 98.08083 -337.890104)
		(end 98.96983 -337.890104)
		(stroke
			(width 0.2)
			(type default)
		)
		(fill no)
		(layer "In12.Cu")
	)
	(gr_circle
		(center 98.199194 -339.358224)
		(end 99.088194 -339.358224)
		(stroke
			(width 0.2)
			(type default)
		)
		(fill no)
		(layer "In12.Cu")
	)
	(gr_circle
		(center 98.38309 -180.704744)
		(end 99.2632 -180.704744)
		(stroke
			(width 0.2)
			(type default)
		)
		(fill no)
		(layer "In12.Cu")
	)
	(gr_circle
		(center 98.605594 -337.450684)
		(end 99.494594 -337.450684)
		(stroke
			(width 0.2)
			(type default)
		)
		(fill no)
		(layer "In12.Cu")
	)
	(gr_circle
		(center 98.630994 -338.212684)
		(end 99.519994 -338.212684)
		(stroke
			(width 0.2)
			(type default)
		)
		(fill no)
		(layer "In12.Cu")
	)
	(gr_circle
		(center 98.747834 -339.736684)
		(end 99.636834 -339.736684)
		(stroke
			(width 0.2)
			(type default)
		)
		(fill no)
		(layer "In12.Cu")
	)
	(gr_circle
		(center 98.747834 -338.974684)
		(end 99.636834 -338.974684)
		(stroke
			(width 0.2)
			(type default)
		)
		(fill no)
		(layer "In12.Cu")
	)
	(gr_circle
		(center 98.921062 -273.276314)
		(end 99.175062 -273.276314)
		(stroke
			(width 0.1016)
			(type default)
		)
		(fill no)
		(layer "In12.Cu")
	)
	(gr_circle
		(center 98.921062 -271.656302)
		(end 99.175062 -271.656302)
		(stroke
			(width 0.1016)
			(type default)
		)
		(fill no)
		(layer "In12.Cu")
	)
	(gr_circle
		(center 98.921062 -270.03629)
		(end 99.175062 -270.03629)
		(stroke
			(width 0.1016)
			(type default)
		)
		(fill no)
		(layer "In12.Cu")
	)
	(gr_circle
		(center 100.800916 -273.276314)
		(end 101.054916 -273.276314)
		(stroke
			(width 0.1016)
			(type default)
		)
		(fill no)
		(layer "In12.Cu")
	)
	(gr_circle
		(center 100.800916 -271.656302)
		(end 101.054916 -271.656302)
		(stroke
			(width 0.1016)
			(type default)
		)
		(fill no)
		(layer "In12.Cu")
	)
	(gr_circle
		(center 100.800916 -270.03629)
		(end 101.054916 -270.03629)
		(stroke
			(width 0.1016)
			(type default)
		)
		(fill no)
		(layer "In12.Cu")
	)
	(gr_circle
		(center 101.74097 -273.276314)
		(end 101.99497 -273.276314)
		(stroke
			(width 0.1016)
			(type default)
		)
		(fill no)
		(layer "In12.Cu")
	)
	(gr_circle
		(center 101.74097 -271.656302)
		(end 101.99497 -271.656302)
		(stroke
			(width 0.1016)
			(type default)
		)
		(fill no)
		(layer "In12.Cu")
	)
	(gr_circle
		(center 101.74097 -270.03629)
		(end 101.99497 -270.03629)
		(stroke
			(width 0.1016)
			(type default)
		)
		(fill no)
		(layer "In12.Cu")
	)
	(gr_circle
		(center 103.621078 -273.276314)
		(end 103.875078 -273.276314)
		(stroke
			(width 0.1016)
			(type default)
		)
		(fill no)
		(layer "In12.Cu")
	)
	(gr_circle
		(center 103.621078 -271.656302)
		(end 103.875078 -271.656302)
		(stroke
			(width 0.1016)
			(type default)
		)
		(fill no)
		(layer "In12.Cu")
	)
	(gr_circle
		(center 103.621078 -270.03629)
		(end 103.875078 -270.03629)
		(stroke
			(width 0.1016)
			(type default)
		)
		(fill no)
		(layer "In12.Cu")
	)
	(gr_circle
		(center 103.74503 -176.106074)
		(end 104.63403 -176.106074)
		(stroke
			(width 0.2)
			(type default)
		)
		(fill no)
		(layer "In12.Cu")
	)
	(gr_circle
		(center 103.74503 -175.369474)
		(end 104.63403 -175.369474)
		(stroke
			(width 0.2)
			(type default)
		)
		(fill no)
		(layer "In12.Cu")
	)
	(gr_circle
		(center 103.74503 -174.632874)
		(end 104.63403 -174.632874)
		(stroke
			(width 0.2)
			(type default)
		)
		(fill no)
		(layer "In12.Cu")
	)
	(gr_circle
		(center 104.27843 -174.988474)
		(end 105.16743 -174.988474)
		(stroke
			(width 0.2)
			(type default)
		)
		(fill no)
		(layer "In12.Cu")
	)
	(gr_circle
		(center 104.30383 -175.750474)
		(end 105.19283 -175.750474)
		(stroke
			(width 0.2)
			(type default)
		)
		(fill no)
		(layer "In12.Cu")
	)
	(gr_circle
		(center 104.420162 -341.927688)
		(end 105.300272 -341.927688)
		(stroke
			(width 0.2)
			(type default)
		)
		(fill no)
		(layer "In12.Cu")
	)
	(gr_circle
		(center 104.561132 -273.276314)
		(end 104.815132 -273.276314)
		(stroke
			(width 0.1016)
			(type default)
		)
		(fill no)
		(layer "In12.Cu")
	)
	(gr_circle
		(center 104.561132 -271.656302)
		(end 104.815132 -271.656302)
		(stroke
			(width 0.1016)
			(type default)
		)
		(fill no)
		(layer "In12.Cu")
	)
	(gr_circle
		(center 104.561132 -270.03629)
		(end 104.815132 -270.03629)
		(stroke
			(width 0.1016)
			(type default)
		)
		(fill no)
		(layer "In12.Cu")
	)
	(gr_circle
		(center 104.828594 -175.311054)
		(end 105.717594 -175.311054)
		(stroke
			(width 0.2)
			(type default)
		)
		(fill no)
		(layer "In12.Cu")
	)
	(gr_circle
		(center 104.828594 -174.574454)
		(end 105.717594 -174.574454)
		(stroke
			(width 0.2)
			(type default)
		)
		(fill no)
		(layer "In12.Cu")
	)
	(gr_circle
		(center 105.037382 -341.927688)
		(end 105.917492 -341.927688)
		(stroke
			(width 0.2)
			(type default)
		)
		(fill no)
		(layer "In12.Cu")
	)
	(gr_circle
		(center 105.336848 -177.65776)
		(end 106.225848 -177.65776)
		(stroke
			(width 0.2)
			(type default)
		)
		(fill no)
		(layer "In12.Cu")
	)
	(gr_circle
		(center 105.336848 -176.92116)
		(end 106.225848 -176.92116)
		(stroke
			(width 0.2)
			(type default)
		)
		(fill no)
		(layer "In12.Cu")
	)
	(gr_circle
		(center 105.53065 -176.183544)
		(end 106.41076 -176.183544)
		(stroke
			(width 0.2)
			(type default)
		)
		(fill no)
		(layer "In12.Cu")
	)
	(gr_circle
		(center 105.654602 -341.927688)
		(end 106.534712 -341.927688)
		(stroke
			(width 0.2)
			(type default)
		)
		(fill no)
		(layer "In12.Cu")
	)
	(gr_circle
		(center 105.934002 -341.229442)
		(end 106.814112 -341.229442)
		(stroke
			(width 0.2)
			(type default)
		)
		(fill no)
		(layer "In12.Cu")
	)
	(gr_circle
		(center 105.934002 -340.492842)
		(end 106.814112 -340.492842)
		(stroke
			(width 0.2)
			(type default)
		)
		(fill no)
		(layer "In12.Cu")
	)
	(gr_circle
		(center 106.14787 -176.183544)
		(end 107.02798 -176.183544)
		(stroke
			(width 0.2)
			(type default)
		)
		(fill no)
		(layer "In12.Cu")
	)
	(gr_circle
		(center 106.34345 -343.450164)
		(end 107.23245 -343.450164)
		(stroke
			(width 0.2)
			(type default)
		)
		(fill no)
		(layer "In12.Cu")
	)
	(gr_circle
		(center 106.34345 -342.713564)
		(end 107.23245 -342.713564)
		(stroke
			(width 0.2)
			(type default)
		)
		(fill no)
		(layer "In12.Cu")
	)
	(gr_circle
		(center 106.440986 -273.276314)
		(end 106.694986 -273.276314)
		(stroke
			(width 0.1016)
			(type default)
		)
		(fill no)
		(layer "In12.Cu")
	)
	(gr_circle
		(center 106.440986 -271.656302)
		(end 106.694986 -271.656302)
		(stroke
			(width 0.1016)
			(type default)
		)
		(fill no)
		(layer "In12.Cu")
	)
	(gr_circle
		(center 106.440986 -270.03629)
		(end 106.694986 -270.03629)
		(stroke
			(width 0.1016)
			(type default)
		)
		(fill no)
		(layer "In12.Cu")
	)
	(gr_circle
		(center 106.76509 -176.183544)
		(end 107.6452 -176.183544)
		(stroke
			(width 0.2)
			(type default)
		)
		(fill no)
		(layer "In12.Cu")
	)
	(gr_circle
		(center 106.98607 -342.540844)
		(end 107.87507 -342.540844)
		(stroke
			(width 0.2)
			(type default)
		)
		(fill no)
		(layer "In12.Cu")
	)
	(gr_circle
		(center 106.98607 -341.804244)
		(end 107.87507 -341.804244)
		(stroke
			(width 0.2)
			(type default)
		)
		(fill no)
		(layer "In12.Cu")
	)
	(gr_circle
		(center 107.01401 -343.986104)
		(end 107.90301 -343.986104)
		(stroke
			(width 0.2)
			(type default)
		)
		(fill no)
		(layer "In12.Cu")
	)
	(gr_circle
		(center 107.01401 -343.249504)
		(end 107.90301 -343.249504)
		(stroke
			(width 0.2)
			(type default)
		)
		(fill no)
		(layer "In12.Cu")
	)
	(gr_circle
		(center 107.38104 -273.276314)
		(end 107.63504 -273.276314)
		(stroke
			(width 0.1016)
			(type default)
		)
		(fill no)
		(layer "In12.Cu")
	)
	(gr_circle
		(center 107.38104 -271.656302)
		(end 107.63504 -271.656302)
		(stroke
			(width 0.1016)
			(type default)
		)
		(fill no)
		(layer "In12.Cu")
	)
	(gr_circle
		(center 107.38104 -270.03629)
		(end 107.63504 -270.03629)
		(stroke
			(width 0.1016)
			(type default)
		)
		(fill no)
		(layer "In12.Cu")
	)
	(gr_circle
		(center 108.790994 -274.08632)
		(end 109.044994 -274.08632)
		(stroke
			(width 0.1016)
			(type default)
		)
		(fill no)
		(layer "In12.Cu")
	)
	(gr_circle
		(center 108.790994 -272.466308)
		(end 109.044994 -272.466308)
		(stroke
			(width 0.1016)
			(type default)
		)
		(fill no)
		(layer "In12.Cu")
	)
	(gr_circle
		(center 108.790994 -270.846296)
		(end 109.044994 -270.846296)
		(stroke
			(width 0.1016)
			(type default)
		)
		(fill no)
		(layer "In12.Cu")
	)
	(gr_circle
		(center 108.790994 -269.226284)
		(end 109.044994 -269.226284)
		(stroke
			(width 0.1016)
			(type default)
		)
		(fill no)
		(layer "In12.Cu")
	)
	(gr_circle
		(center 109.731048 -274.08632)
		(end 109.985048 -274.08632)
		(stroke
			(width 0.1016)
			(type default)
		)
		(fill no)
		(layer "In12.Cu")
	)
	(gr_circle
		(center 109.731048 -272.466308)
		(end 109.985048 -272.466308)
		(stroke
			(width 0.1016)
			(type default)
		)
		(fill no)
		(layer "In12.Cu")
	)
	(gr_circle
		(center 109.731048 -270.846296)
		(end 109.985048 -270.846296)
		(stroke
			(width 0.1016)
			(type default)
		)
		(fill no)
		(layer "In12.Cu")
	)
	(gr_circle
		(center 109.731048 -269.226284)
		(end 109.985048 -269.226284)
		(stroke
			(width 0.1016)
			(type default)
		)
		(fill no)
		(layer "In12.Cu")
	)
	(gr_circle
		(center 110.140496 -150.941786)
		(end 111.537496 -150.941786)
		(stroke
			(width 0.2)
			(type default)
		)
		(fill no)
		(layer "In12.Cu")
	)
	(gr_circle
		(center 111.97463 -169.857674)
		(end 112.86363 -169.857674)
		(stroke
			(width 0.2)
			(type default)
		)
		(fill no)
		(layer "In12.Cu")
	)
	(gr_circle
		(center 111.97463 -169.121074)
		(end 112.86363 -169.121074)
		(stroke
			(width 0.2)
			(type default)
		)
		(fill no)
		(layer "In12.Cu")
	)
	(gr_circle
		(center 111.97463 -168.384474)
		(end 112.86363 -168.384474)
		(stroke
			(width 0.2)
			(type default)
		)
		(fill no)
		(layer "In12.Cu")
	)
	(gr_circle
		(center 112.50803 -168.740074)
		(end 113.39703 -168.740074)
		(stroke
			(width 0.2)
			(type default)
		)
		(fill no)
		(layer "In12.Cu")
	)
	(gr_circle
		(center 112.53343 -169.502074)
		(end 113.42243 -169.502074)
		(stroke
			(width 0.2)
			(type default)
		)
		(fill no)
		(layer "In12.Cu")
	)
	(gr_circle
		(center 113.058194 -169.062654)
		(end 113.947194 -169.062654)
		(stroke
			(width 0.2)
			(type default)
		)
		(fill no)
		(layer "In12.Cu")
	)
	(gr_circle
		(center 113.058194 -168.326054)
		(end 113.947194 -168.326054)
		(stroke
			(width 0.2)
			(type default)
		)
		(fill no)
		(layer "In12.Cu")
	)
	(gr_circle
		(center 113.591848 -171.33316)
		(end 114.480848 -171.33316)
		(stroke
			(width 0.2)
			(type default)
		)
		(fill no)
		(layer "In12.Cu")
	)
	(gr_circle
		(center 113.591848 -170.59656)
		(end 114.480848 -170.59656)
		(stroke
			(width 0.2)
			(type default)
		)
		(fill no)
		(layer "In12.Cu")
	)
	(gr_circle
		(center 113.76025 -169.935144)
		(end 114.64036 -169.935144)
		(stroke
			(width 0.2)
			(type default)
		)
		(fill no)
		(layer "In12.Cu")
	)
	(gr_circle
		(center 114.37747 -169.935144)
		(end 115.25758 -169.935144)
		(stroke
			(width 0.2)
			(type default)
		)
		(fill no)
		(layer "In12.Cu")
	)
	(gr_circle
		(center 114.424714 -274.08632)
		(end 114.678714 -274.08632)
		(stroke
			(width 0.1016)
			(type default)
		)
		(fill no)
		(layer "In12.Cu")
	)
	(gr_circle
		(center 114.424714 -272.466308)
		(end 114.678714 -272.466308)
		(stroke
			(width 0.1016)
			(type default)
		)
		(fill no)
		(layer "In12.Cu")
	)
	(gr_circle
		(center 114.424714 -270.846296)
		(end 114.678714 -270.846296)
		(stroke
			(width 0.1016)
			(type default)
		)
		(fill no)
		(layer "In12.Cu")
	)
	(gr_circle
		(center 114.424714 -269.226284)
		(end 114.678714 -269.226284)
		(stroke
			(width 0.1016)
			(type default)
		)
		(fill no)
		(layer "In12.Cu")
	)
	(gr_circle
		(center 114.99469 -169.935144)
		(end 115.8748 -169.935144)
		(stroke
			(width 0.2)
			(type default)
		)
		(fill no)
		(layer "In12.Cu")
	)
	(gr_circle
		(center 115.364768 -274.08632)
		(end 115.618768 -274.08632)
		(stroke
			(width 0.1016)
			(type default)
		)
		(fill no)
		(layer "In12.Cu")
	)
	(gr_circle
		(center 115.364768 -272.466308)
		(end 115.618768 -272.466308)
		(stroke
			(width 0.1016)
			(type default)
		)
		(fill no)
		(layer "In12.Cu")
	)
	(gr_circle
		(center 115.364768 -270.846296)
		(end 115.618768 -270.846296)
		(stroke
			(width 0.1016)
			(type default)
		)
		(fill no)
		(layer "In12.Cu")
	)
	(gr_circle
		(center 115.364768 -269.226284)
		(end 115.618768 -269.226284)
		(stroke
			(width 0.1016)
			(type default)
		)
		(fill no)
		(layer "In12.Cu")
	)
	(gr_circle
		(center 116.258594 -152.657556)
		(end 117.147594 -152.657556)
		(stroke
			(width 0.2)
			(type default)
		)
		(fill no)
		(layer "In12.Cu")
	)
	(gr_circle
		(center 116.258594 -152.022556)
		(end 117.147594 -152.022556)
		(stroke
			(width 0.2)
			(type default)
		)
		(fill no)
		(layer "In12.Cu")
	)
	(gr_circle
		(center 116.774722 -273.276314)
		(end 117.028722 -273.276314)
		(stroke
			(width 0.1016)
			(type default)
		)
		(fill no)
		(layer "In12.Cu")
	)
	(gr_circle
		(center 116.774722 -271.656302)
		(end 117.028722 -271.656302)
		(stroke
			(width 0.1016)
			(type default)
		)
		(fill no)
		(layer "In12.Cu")
	)
	(gr_circle
		(center 116.774722 -270.03629)
		(end 117.028722 -270.03629)
		(stroke
			(width 0.1016)
			(type default)
		)
		(fill no)
		(layer "In12.Cu")
	)
	(gr_circle
		(center 116.893594 -152.657556)
		(end 117.782594 -152.657556)
		(stroke
			(width 0.2)
			(type default)
		)
		(fill no)
		(layer "In12.Cu")
	)
	(gr_circle
		(center 116.893594 -152.022556)
		(end 117.782594 -152.022556)
		(stroke
			(width 0.2)
			(type default)
		)
		(fill no)
		(layer "In12.Cu")
	)
	(gr_circle
		(center 117.559074 -152.657556)
		(end 118.448074 -152.657556)
		(stroke
			(width 0.2)
			(type default)
		)
		(fill no)
		(layer "In12.Cu")
	)
	(gr_circle
		(center 117.559074 -152.022556)
		(end 118.448074 -152.022556)
		(stroke
			(width 0.2)
			(type default)
		)
		(fill no)
		(layer "In12.Cu")
	)
	(gr_circle
		(center 117.714776 -273.276314)
		(end 117.968776 -273.276314)
		(stroke
			(width 0.1016)
			(type default)
		)
		(fill no)
		(layer "In12.Cu")
	)
	(gr_circle
		(center 117.714776 -271.656302)
		(end 117.968776 -271.656302)
		(stroke
			(width 0.1016)
			(type default)
		)
		(fill no)
		(layer "In12.Cu")
	)
	(gr_circle
		(center 117.714776 -270.03629)
		(end 117.968776 -270.03629)
		(stroke
			(width 0.1016)
			(type default)
		)
		(fill no)
		(layer "In12.Cu")
	)
	(gr_circle
		(center 118.194074 -152.657556)
		(end 119.083074 -152.657556)
		(stroke
			(width 0.2)
			(type default)
		)
		(fill no)
		(layer "In12.Cu")
	)
	(gr_circle
		(center 118.194074 -152.022556)
		(end 119.083074 -152.022556)
		(stroke
			(width 0.2)
			(type default)
		)
		(fill no)
		(layer "In12.Cu")
	)
	(gr_circle
		(center 118.829074 -152.657556)
		(end 119.718074 -152.657556)
		(stroke
			(width 0.2)
			(type default)
		)
		(fill no)
		(layer "In12.Cu")
	)
	(gr_circle
		(center 118.829074 -152.022556)
		(end 119.718074 -152.022556)
		(stroke
			(width 0.2)
			(type default)
		)
		(fill no)
		(layer "In12.Cu")
	)
	(gr_circle
		(center 119.464074 -152.657556)
		(end 120.353074 -152.657556)
		(stroke
			(width 0.2)
			(type default)
		)
		(fill no)
		(layer "In12.Cu")
	)
	(gr_circle
		(center 119.464074 -152.022556)
		(end 120.353074 -152.022556)
		(stroke
			(width 0.2)
			(type default)
		)
		(fill no)
		(layer "In12.Cu")
	)
	(gr_circle
		(center 119.59463 -273.276314)
		(end 119.84863 -273.276314)
		(stroke
			(width 0.1016)
			(type default)
		)
		(fill no)
		(layer "In12.Cu")
	)
	(gr_circle
		(center 119.59463 -271.656302)
		(end 119.84863 -271.656302)
		(stroke
			(width 0.1016)
			(type default)
		)
		(fill no)
		(layer "In12.Cu")
	)
	(gr_circle
		(center 119.59463 -270.03629)
		(end 119.84863 -270.03629)
		(stroke
			(width 0.1016)
			(type default)
		)
		(fill no)
		(layer "In12.Cu")
	)
	(gr_circle
		(center 120.25503 -163.126674)
		(end 121.14403 -163.126674)
		(stroke
			(width 0.2)
			(type default)
		)
		(fill no)
		(layer "In12.Cu")
	)
	(gr_circle
		(center 120.25503 -162.390074)
		(end 121.14403 -162.390074)
		(stroke
			(width 0.2)
			(type default)
		)
		(fill no)
		(layer "In12.Cu")
	)
	(gr_circle
		(center 120.25503 -161.653474)
		(end 121.14403 -161.653474)
		(stroke
			(width 0.2)
			(type default)
		)
		(fill no)
		(layer "In12.Cu")
	)
	(gr_circle
		(center 120.534684 -273.276314)
		(end 120.788684 -273.276314)
		(stroke
			(width 0.1016)
			(type default)
		)
		(fill no)
		(layer "In12.Cu")
	)
	(gr_circle
		(center 120.534684 -271.656302)
		(end 120.788684 -271.656302)
		(stroke
			(width 0.1016)
			(type default)
		)
		(fill no)
		(layer "In12.Cu")
	)
	(gr_circle
		(center 120.534684 -270.03629)
		(end 120.788684 -270.03629)
		(stroke
			(width 0.1016)
			(type default)
		)
		(fill no)
		(layer "In12.Cu")
	)
	(gr_circle
		(center 120.78843 -162.009074)
		(end 121.67743 -162.009074)
		(stroke
			(width 0.2)
			(type default)
		)
		(fill no)
		(layer "In12.Cu")
	)
	(gr_circle
		(center 120.81383 -162.771074)
		(end 121.70283 -162.771074)
		(stroke
			(width 0.2)
			(type default)
		)
		(fill no)
		(layer "In12.Cu")
	)
	(gr_circle
		(center 121.338594 -162.331654)
		(end 122.227594 -162.331654)
		(stroke
			(width 0.2)
			(type default)
		)
		(fill no)
		(layer "In12.Cu")
	)
	(gr_circle
		(center 121.338594 -161.595054)
		(end 122.227594 -161.595054)
		(stroke
			(width 0.2)
			(type default)
		)
		(fill no)
		(layer "In12.Cu")
	)
	(gr_circle
		(center 121.872248 -164.62756)
		(end 122.761248 -164.62756)
		(stroke
			(width 0.2)
			(type default)
		)
		(fill no)
		(layer "In12.Cu")
	)
	(gr_circle
		(center 121.872248 -163.89096)
		(end 122.761248 -163.89096)
		(stroke
			(width 0.2)
			(type default)
		)
		(fill no)
		(layer "In12.Cu")
	)
	(gr_circle
		(center 122.04065 -163.204144)
		(end 122.92076 -163.204144)
		(stroke
			(width 0.2)
			(type default)
		)
		(fill no)
		(layer "In12.Cu")
	)
	(gr_circle
		(center 122.414792 -273.276314)
		(end 122.668792 -273.276314)
		(stroke
			(width 0.1016)
			(type default)
		)
		(fill no)
		(layer "In12.Cu")
	)
	(gr_circle
		(center 122.414792 -271.656302)
		(end 122.668792 -271.656302)
		(stroke
			(width 0.1016)
			(type default)
		)
		(fill no)
		(layer "In12.Cu")
	)
	(gr_circle
		(center 122.414792 -270.03629)
		(end 122.668792 -270.03629)
		(stroke
			(width 0.1016)
			(type default)
		)
		(fill no)
		(layer "In12.Cu")
	)
	(gr_circle
		(center 122.65787 -163.204144)
		(end 123.53798 -163.204144)
		(stroke
			(width 0.2)
			(type default)
		)
		(fill no)
		(layer "In12.Cu")
	)
	(gr_circle
		(center 123.27509 -163.204144)
		(end 124.1552 -163.204144)
		(stroke
			(width 0.2)
			(type default)
		)
		(fill no)
		(layer "In12.Cu")
	)
	(gr_circle
		(center 123.354846 -273.276314)
		(end 123.608846 -273.276314)
		(stroke
			(width 0.1016)
			(type default)
		)
		(fill no)
		(layer "In12.Cu")
	)
	(gr_circle
		(center 123.354846 -271.656302)
		(end 123.608846 -271.656302)
		(stroke
			(width 0.1016)
			(type default)
		)
		(fill no)
		(layer "In12.Cu")
	)
	(gr_circle
		(center 123.354846 -270.03629)
		(end 123.608846 -270.03629)
		(stroke
			(width 0.1016)
			(type default)
		)
		(fill no)
		(layer "In12.Cu")
	)
	(gr_line
		(start 124.102114 -12.288012)
		(end 83.70189 -12.288012)
		(stroke
			(width 0.2)
			(type default)
		)
		(layer "In12.Cu")
	)
	(gr_arc
		(start 124.102114 -12.288012)
		(mid 125.875532 -11.553433)
		(end 126.61011 -9.780016)
		(stroke
			(width 0.2)
			(type default)
		)
		(layer "In12.Cu")
	)
	(gr_arc
		(start 124.102114 -11.780012)
		(mid 125.516325 -11.194227)
		(end 126.10211 -9.780016)
		(stroke
			(width 1.016)
			(type default)
		)
		(layer "In12.Cu")
	)
	(gr_circle
		(center 125.2347 -273.276314)
		(end 125.4887 -273.276314)
		(stroke
			(width 0.1016)
			(type default)
		)
		(fill no)
		(layer "In12.Cu")
	)
	(gr_circle
		(center 125.2347 -271.656302)
		(end 125.4887 -271.656302)
		(stroke
			(width 0.1016)
			(type default)
		)
		(fill no)
		(layer "In12.Cu")
	)
	(gr_circle
		(center 125.2347 -270.03629)
		(end 125.4887 -270.03629)
		(stroke
			(width 0.1016)
			(type default)
		)
		(fill no)
		(layer "In12.Cu")
	)
	(gr_line
		(start 126.10211 -9.780016)
		(end 126.10211 -5.780024)
		(stroke
			(width 1.016)
			(type default)
		)
		(layer "In12.Cu")
	)
	(gr_circle
		(center 126.174754 -273.276314)
		(end 126.428754 -273.276314)
		(stroke
			(width 0.1016)
			(type default)
		)
		(fill no)
		(layer "In12.Cu")
	)
	(gr_circle
		(center 126.174754 -271.656302)
		(end 126.428754 -271.656302)
		(stroke
			(width 0.1016)
			(type default)
		)
		(fill no)
		(layer "In12.Cu")
	)
	(gr_circle
		(center 126.174754 -270.03629)
		(end 126.428754 -270.03629)
		(stroke
			(width 0.1016)
			(type default)
		)
		(fill no)
		(layer "In12.Cu")
	)
	(gr_arc
		(start 126.601982 -5.279898)
		(mid 126.248489 -5.42646)
		(end 126.10211 -5.780024)
		(stroke
			(width 1.016)
			(type default)
		)
		(layer "In12.Cu")
	)
	(gr_line
		(start 126.601982 -5.279898)
		(end 194.20205 -5.279898)
		(stroke
			(width 1.016)
			(type default)
		)
		(layer "In12.Cu")
	)
	(gr_line
		(start 126.61011 -5.787898)
		(end 126.61011 -9.780016)
		(stroke
			(width 0.2)
			(type default)
		)
		(layer "In12.Cu")
	)
	(gr_circle
		(center 128.71323 -154.465274)
		(end 129.60223 -154.465274)
		(stroke
			(width 0.2)
			(type default)
		)
		(fill no)
		(layer "In12.Cu")
	)
	(gr_circle
		(center 128.71323 -153.728674)
		(end 129.60223 -153.728674)
		(stroke
			(width 0.2)
			(type default)
		)
		(fill no)
		(layer "In12.Cu")
	)
	(gr_circle
		(center 128.71323 -152.992074)
		(end 129.60223 -152.992074)
		(stroke
			(width 0.2)
			(type default)
		)
		(fill no)
		(layer "In12.Cu")
	)
	(gr_circle
		(center 129.24663 -153.347674)
		(end 130.13563 -153.347674)
		(stroke
			(width 0.2)
			(type default)
		)
		(fill no)
		(layer "In12.Cu")
	)
	(gr_circle
		(center 129.27203 -154.109674)
		(end 130.16103 -154.109674)
		(stroke
			(width 0.2)
			(type default)
		)
		(fill no)
		(layer "In12.Cu")
	)
	(gr_circle
		(center 129.796794 -153.670254)
		(end 130.685794 -153.670254)
		(stroke
			(width 0.2)
			(type default)
		)
		(fill no)
		(layer "In12.Cu")
	)
	(gr_circle
		(center 129.796794 -152.933654)
		(end 130.685794 -152.933654)
		(stroke
			(width 0.2)
			(type default)
		)
		(fill no)
		(layer "In12.Cu")
	)
	(gr_circle
		(center 130.305048 -155.94076)
		(end 131.194048 -155.94076)
		(stroke
			(width 0.2)
			(type default)
		)
		(fill no)
		(layer "In12.Cu")
	)
	(gr_circle
		(center 130.305048 -155.20416)
		(end 131.194048 -155.20416)
		(stroke
			(width 0.2)
			(type default)
		)
		(fill no)
		(layer "In12.Cu")
	)
	(gr_circle
		(center 130.49885 -154.542744)
		(end 131.37896 -154.542744)
		(stroke
			(width 0.2)
			(type default)
		)
		(fill no)
		(layer "In12.Cu")
	)
	(gr_circle
		(center 131.11607 -154.542744)
		(end 131.99618 -154.542744)
		(stroke
			(width 0.2)
			(type default)
		)
		(fill no)
		(layer "In12.Cu")
	)
	(gr_circle
		(center 131.73329 -154.542744)
		(end 132.6134 -154.542744)
		(stroke
			(width 0.2)
			(type default)
		)
		(fill no)
		(layer "In12.Cu")
	)
	(gr_circle
		(center 176.332134 -26.634948)
		(end 177.221134 -26.634948)
		(stroke
			(width 0.2)
			(type default)
		)
		(fill no)
		(layer "In12.Cu")
	)
	(gr_circle
		(center 176.713134 -25.949148)
		(end 177.602134 -25.949148)
		(stroke
			(width 0.2)
			(type default)
		)
		(fill no)
		(layer "In12.Cu")
	)
	(gr_circle
		(center 176.878234 -19.942048)
		(end 177.767234 -19.942048)
		(stroke
			(width 0.2)
			(type default)
		)
		(fill no)
		(layer "In12.Cu")
	)
	(gr_circle
		(center 176.968912 -21.349208)
		(end 177.857912 -21.349208)
		(stroke
			(width 0.2)
			(type default)
		)
		(fill no)
		(layer "In12.Cu")
	)
	(gr_circle
		(center 176.968912 -20.714208)
		(end 177.857912 -20.714208)
		(stroke
			(width 0.2)
			(type default)
		)
		(fill no)
		(layer "In12.Cu")
	)
	(gr_circle
		(center 177.221134 -26.634948)
		(end 178.110134 -26.634948)
		(stroke
			(width 0.2)
			(type default)
		)
		(fill no)
		(layer "In12.Cu")
	)
	(gr_circle
		(center 177.472594 -21.85289)
		(end 178.361594 -21.85289)
		(stroke
			(width 0.2)
			(type default)
		)
		(fill no)
		(layer "In12.Cu")
	)
	(gr_circle
		(center 177.602134 -25.949148)
		(end 178.491134 -25.949148)
		(stroke
			(width 0.2)
			(type default)
		)
		(fill no)
		(layer "In12.Cu")
	)
	(gr_circle
		(center 178.110134 -26.634948)
		(end 178.999134 -26.634948)
		(stroke
			(width 0.2)
			(type default)
		)
		(fill no)
		(layer "In12.Cu")
	)
	(gr_circle
		(center 178.491134 -25.949148)
		(end 179.380134 -25.949148)
		(stroke
			(width 0.2)
			(type default)
		)
		(fill no)
		(layer "In12.Cu")
	)
	(gr_circle
		(center 179.507134 -25.517348)
		(end 180.396134 -25.517348)
		(stroke
			(width 0.2)
			(type default)
		)
		(fill no)
		(layer "In12.Cu")
	)
	(gr_circle
		(center 180.921914 -27.107388)
		(end 181.810914 -27.107388)
		(stroke
			(width 0.2)
			(type default)
		)
		(fill no)
		(layer "In12.Cu")
	)
	(gr_circle
		(center 183.610758 -353.283774)
		(end 184.490868 -353.283774)
		(stroke
			(width 0.2)
			(type default)
		)
		(fill no)
		(layer "In12.Cu")
	)
	(gr_circle
		(center 184.227978 -353.283774)
		(end 185.108088 -353.283774)
		(stroke
			(width 0.2)
			(type default)
		)
		(fill no)
		(layer "In12.Cu")
	)
	(gr_circle
		(center 184.845198 -353.283774)
		(end 185.725308 -353.283774)
		(stroke
			(width 0.2)
			(type default)
		)
		(fill no)
		(layer "In12.Cu")
	)
	(gr_circle
		(center 184.85612 -403.222714)
		(end 185.74512 -403.222714)
		(stroke
			(width 0.2)
			(type default)
		)
		(fill no)
		(layer "In12.Cu")
	)
	(gr_circle
		(center 184.85612 -401.919694)
		(end 185.74512 -401.919694)
		(stroke
			(width 0.2)
			(type default)
		)
		(fill no)
		(layer "In12.Cu")
	)
	(gr_circle
		(center 184.85612 -400.616674)
		(end 185.74512 -400.616674)
		(stroke
			(width 0.2)
			(type default)
		)
		(fill no)
		(layer "In12.Cu")
	)
	(gr_circle
		(center 184.962292 -352.558604)
		(end 185.851292 -352.558604)
		(stroke
			(width 0.2)
			(type default)
		)
		(fill no)
		(layer "In12.Cu")
	)
	(gr_circle
		(center 184.962292 -351.822004)
		(end 185.851292 -351.822004)
		(stroke
			(width 0.2)
			(type default)
		)
		(fill no)
		(layer "In12.Cu")
	)
	(gr_circle
		(center 185.547254 -354.892864)
		(end 186.436254 -354.892864)
		(stroke
			(width 0.2)
			(type default)
		)
		(fill no)
		(layer "In12.Cu")
	)
	(gr_circle
		(center 185.547254 -354.156264)
		(end 186.436254 -354.156264)
		(stroke
			(width 0.2)
			(type default)
		)
		(fill no)
		(layer "In12.Cu")
	)
	(gr_circle
		(center 185.673492 -408.092402)
		(end 186.562492 -408.092402)
		(stroke
			(width 0.2)
			(type default)
		)
		(fill no)
		(layer "In12.Cu")
	)
	(gr_circle
		(center 185.673492 -407.330402)
		(end 186.562492 -407.330402)
		(stroke
			(width 0.2)
			(type default)
		)
		(fill no)
		(layer "In12.Cu")
	)
	(gr_circle
		(center 185.673492 -406.517602)
		(end 186.562492 -406.517602)
		(stroke
			(width 0.2)
			(type default)
		)
		(fill no)
		(layer "In12.Cu")
	)
	(gr_circle
		(center 185.673492 -405.755602)
		(end 186.562492 -405.755602)
		(stroke
			(width 0.2)
			(type default)
		)
		(fill no)
		(layer "In12.Cu")
	)
	(gr_circle
		(center 185.673492 -404.993602)
		(end 186.562492 -404.993602)
		(stroke
			(width 0.2)
			(type default)
		)
		(fill no)
		(layer "In12.Cu")
	)
	(gr_circle
		(center 186.034172 -362.234988)
		(end 186.923172 -362.234988)
		(stroke
			(width 0.2)
			(type default)
		)
		(fill no)
		(layer "In12.Cu")
	)
	(gr_circle
		(center 186.034172 -361.472988)
		(end 186.923172 -361.472988)
		(stroke
			(width 0.2)
			(type default)
		)
		(fill no)
		(layer "In12.Cu")
	)
	(gr_circle
		(center 186.034172 -360.710988)
		(end 186.923172 -360.710988)
		(stroke
			(width 0.2)
			(type default)
		)
		(fill no)
		(layer "In12.Cu")
	)
	(gr_circle
		(center 186.072018 -353.716844)
		(end 186.961018 -353.716844)
		(stroke
			(width 0.2)
			(type default)
		)
		(fill no)
		(layer "In12.Cu")
	)
	(gr_circle
		(center 186.097418 -354.478844)
		(end 186.986418 -354.478844)
		(stroke
			(width 0.2)
			(type default)
		)
		(fill no)
		(layer "In12.Cu")
	)
	(gr_circle
		(center 186.27852 -403.222714)
		(end 187.16752 -403.222714)
		(stroke
			(width 0.2)
			(type default)
		)
		(fill no)
		(layer "In12.Cu")
	)
	(gr_circle
		(center 186.27852 -400.616674)
		(end 187.16752 -400.616674)
		(stroke
			(width 0.2)
			(type default)
		)
		(fill no)
		(layer "In12.Cu")
	)
	(gr_circle
		(center 186.435492 -408.092402)
		(end 187.324492 -408.092402)
		(stroke
			(width 0.2)
			(type default)
		)
		(fill no)
		(layer "In12.Cu")
	)
	(gr_circle
		(center 186.435492 -407.330402)
		(end 187.324492 -407.330402)
		(stroke
			(width 0.2)
			(type default)
		)
		(fill no)
		(layer "In12.Cu")
	)
	(gr_circle
		(center 186.435492 -406.517602)
		(end 187.324492 -406.517602)
		(stroke
			(width 0.2)
			(type default)
		)
		(fill no)
		(layer "In12.Cu")
	)
	(gr_circle
		(center 186.435492 -405.755602)
		(end 187.324492 -405.755602)
		(stroke
			(width 0.2)
			(type default)
		)
		(fill no)
		(layer "In12.Cu")
	)
	(gr_circle
		(center 186.435492 -404.993602)
		(end 187.324492 -404.993602)
		(stroke
			(width 0.2)
			(type default)
		)
		(fill no)
		(layer "In12.Cu")
	)
	(gr_circle
		(center 186.630818 -354.834444)
		(end 187.519818 -354.834444)
		(stroke
			(width 0.2)
			(type default)
		)
		(fill no)
		(layer "In12.Cu")
	)
	(gr_circle
		(center 186.630818 -354.097844)
		(end 187.519818 -354.097844)
		(stroke
			(width 0.2)
			(type default)
		)
		(fill no)
		(layer "In12.Cu")
	)
	(gr_circle
		(center 186.630818 -353.361244)
		(end 187.519818 -353.361244)
		(stroke
			(width 0.2)
			(type default)
		)
		(fill no)
		(layer "In12.Cu")
	)
	(gr_circle
		(center 186.796172 -362.234988)
		(end 187.685172 -362.234988)
		(stroke
			(width 0.2)
			(type default)
		)
		(fill no)
		(layer "In12.Cu")
	)
	(gr_circle
		(center 186.796172 -361.472988)
		(end 187.685172 -361.472988)
		(stroke
			(width 0.2)
			(type default)
		)
		(fill no)
		(layer "In12.Cu")
	)
	(gr_circle
		(center 186.796172 -360.710988)
		(end 187.685172 -360.710988)
		(stroke
			(width 0.2)
			(type default)
		)
		(fill no)
		(layer "In12.Cu")
	)
	(gr_circle
		(center 187.197492 -408.092402)
		(end 188.086492 -408.092402)
		(stroke
			(width 0.2)
			(type default)
		)
		(fill no)
		(layer "In12.Cu")
	)
	(gr_circle
		(center 187.197492 -407.330402)
		(end 188.086492 -407.330402)
		(stroke
			(width 0.2)
			(type default)
		)
		(fill no)
		(layer "In12.Cu")
	)
	(gr_circle
		(center 187.197492 -406.517602)
		(end 188.086492 -406.517602)
		(stroke
			(width 0.2)
			(type default)
		)
		(fill no)
		(layer "In12.Cu")
	)
	(gr_circle
		(center 187.197492 -405.755602)
		(end 188.086492 -405.755602)
		(stroke
			(width 0.2)
			(type default)
		)
		(fill no)
		(layer "In12.Cu")
	)
	(gr_circle
		(center 187.197492 -404.993602)
		(end 188.086492 -404.993602)
		(stroke
			(width 0.2)
			(type default)
		)
		(fill no)
		(layer "In12.Cu")
	)
	(gr_circle
		(center 187.67552 -403.222714)
		(end 188.56452 -403.222714)
		(stroke
			(width 0.2)
			(type default)
		)
		(fill no)
		(layer "In12.Cu")
	)
	(gr_circle
		(center 187.67552 -401.919694)
		(end 188.56452 -401.919694)
		(stroke
			(width 0.2)
			(type default)
		)
		(fill no)
		(layer "In12.Cu")
	)
	(gr_circle
		(center 187.67552 -400.616674)
		(end 188.56452 -400.616674)
		(stroke
			(width 0.2)
			(type default)
		)
		(fill no)
		(layer "In12.Cu")
	)
	(gr_circle
		(center 187.959492 -408.092402)
		(end 188.848492 -408.092402)
		(stroke
			(width 0.2)
			(type default)
		)
		(fill no)
		(layer "In12.Cu")
	)
	(gr_circle
		(center 187.959492 -407.330402)
		(end 188.848492 -407.330402)
		(stroke
			(width 0.2)
			(type default)
		)
		(fill no)
		(layer "In12.Cu")
	)
	(gr_circle
		(center 187.959492 -406.517602)
		(end 188.848492 -406.517602)
		(stroke
			(width 0.2)
			(type default)
		)
		(fill no)
		(layer "In12.Cu")
	)
	(gr_circle
		(center 187.959492 -405.755602)
		(end 188.848492 -405.755602)
		(stroke
			(width 0.2)
			(type default)
		)
		(fill no)
		(layer "In12.Cu")
	)
	(gr_circle
		(center 187.959492 -404.993602)
		(end 188.848492 -404.993602)
		(stroke
			(width 0.2)
			(type default)
		)
		(fill no)
		(layer "In12.Cu")
	)
	(gr_circle
		(center 188.721492 -408.092402)
		(end 189.610492 -408.092402)
		(stroke
			(width 0.2)
			(type default)
		)
		(fill no)
		(layer "In12.Cu")
	)
	(gr_circle
		(center 188.721492 -407.330402)
		(end 189.610492 -407.330402)
		(stroke
			(width 0.2)
			(type default)
		)
		(fill no)
		(layer "In12.Cu")
	)
	(gr_circle
		(center 188.721492 -406.517602)
		(end 189.610492 -406.517602)
		(stroke
			(width 0.2)
			(type default)
		)
		(fill no)
		(layer "In12.Cu")
	)
	(gr_circle
		(center 188.721492 -405.755602)
		(end 189.610492 -405.755602)
		(stroke
			(width 0.2)
			(type default)
		)
		(fill no)
		(layer "In12.Cu")
	)
	(gr_circle
		(center 188.721492 -404.993602)
		(end 189.610492 -404.993602)
		(stroke
			(width 0.2)
			(type default)
		)
		(fill no)
		(layer "In12.Cu")
	)
	(gr_circle
		(center 189.483492 -408.092402)
		(end 190.372492 -408.092402)
		(stroke
			(width 0.2)
			(type default)
		)
		(fill no)
		(layer "In12.Cu")
	)
	(gr_circle
		(center 189.483492 -407.330402)
		(end 190.372492 -407.330402)
		(stroke
			(width 0.2)
			(type default)
		)
		(fill no)
		(layer "In12.Cu")
	)
	(gr_circle
		(center 189.483492 -406.517602)
		(end 190.372492 -406.517602)
		(stroke
			(width 0.2)
			(type default)
		)
		(fill no)
		(layer "In12.Cu")
	)
	(gr_circle
		(center 189.483492 -405.755602)
		(end 190.372492 -405.755602)
		(stroke
			(width 0.2)
			(type default)
		)
		(fill no)
		(layer "In12.Cu")
	)
	(gr_circle
		(center 189.483492 -404.993602)
		(end 190.372492 -404.993602)
		(stroke
			(width 0.2)
			(type default)
		)
		(fill no)
		(layer "In12.Cu")
	)
	(gr_circle
		(center 190.508636 -23.593552)
		(end 191.397636 -23.593552)
		(stroke
			(width 0.2)
			(type default)
		)
		(fill no)
		(layer "In12.Cu")
	)
	(gr_circle
		(center 190.508636 -22.856952)
		(end 191.397636 -22.856952)
		(stroke
			(width 0.2)
			(type default)
		)
		(fill no)
		(layer "In12.Cu")
	)
	(gr_circle
		(center 191.67983 -362.430568)
		(end 193.07683 -362.430568)
		(stroke
			(width 0.2)
			(type default)
		)
		(fill no)
		(layer "In12.Cu")
	)
	(gr_circle
		(center 191.927734 -13.106908)
		(end 192.816734 -13.106908)
		(stroke
			(width 0.2)
			(type default)
		)
		(fill no)
		(layer "In12.Cu")
	)
	(gr_circle
		(center 191.937386 -353.309174)
		(end 192.817496 -353.309174)
		(stroke
			(width 0.2)
			(type default)
		)
		(fill no)
		(layer "In12.Cu")
	)
	(gr_circle
		(center 192.461134 -16.416528)
		(end 193.350134 -16.416528)
		(stroke
			(width 0.2)
			(type default)
		)
		(fill no)
		(layer "In12.Cu")
	)
	(gr_circle
		(center 192.461134 -15.781528)
		(end 193.350134 -15.781528)
		(stroke
			(width 0.2)
			(type default)
		)
		(fill no)
		(layer "In12.Cu")
	)
	(gr_circle
		(center 192.554606 -353.309174)
		(end 193.434716 -353.309174)
		(stroke
			(width 0.2)
			(type default)
		)
		(fill no)
		(layer "In12.Cu")
	)
	(gr_circle
		(center 192.689734 -13.106908)
		(end 193.578734 -13.106908)
		(stroke
			(width 0.2)
			(type default)
		)
		(fill no)
		(layer "In12.Cu")
	)
	(gr_circle
		(center 193.096134 -16.416528)
		(end 193.985134 -16.416528)
		(stroke
			(width 0.2)
			(type default)
		)
		(fill no)
		(layer "In12.Cu")
	)
	(gr_circle
		(center 193.096134 -15.781528)
		(end 193.985134 -15.781528)
		(stroke
			(width 0.2)
			(type default)
		)
		(fill no)
		(layer "In12.Cu")
	)
	(gr_circle
		(center 193.171826 -353.309174)
		(end 194.051936 -353.309174)
		(stroke
			(width 0.2)
			(type default)
		)
		(fill no)
		(layer "In12.Cu")
	)
	(gr_circle
		(center 193.28892 -352.563684)
		(end 194.17792 -352.563684)
		(stroke
			(width 0.2)
			(type default)
		)
		(fill no)
		(layer "In12.Cu")
	)
	(gr_circle
		(center 193.28892 -351.827084)
		(end 194.17792 -351.827084)
		(stroke
			(width 0.2)
			(type default)
		)
		(fill no)
		(layer "In12.Cu")
	)
	(gr_circle
		(center 193.731134 -15.781528)
		(end 194.620134 -15.781528)
		(stroke
			(width 0.2)
			(type default)
		)
		(fill no)
		(layer "In12.Cu")
	)
	(gr_circle
		(center 193.858134 -16.543528)
		(end 194.747134 -16.543528)
		(stroke
			(width 0.2)
			(type default)
		)
		(fill no)
		(layer "In12.Cu")
	)
	(gr_circle
		(center 193.873882 -354.918264)
		(end 194.762882 -354.918264)
		(stroke
			(width 0.2)
			(type default)
		)
		(fill no)
		(layer "In12.Cu")
	)
	(gr_circle
		(center 193.873882 -354.181664)
		(end 194.762882 -354.181664)
		(stroke
			(width 0.2)
			(type default)
		)
		(fill no)
		(layer "In12.Cu")
	)
	(gr_line
		(start 194.193922 -9.780016)
		(end 194.193922 -5.787898)
		(stroke
			(width 0.2)
			(type default)
		)
		(layer "In12.Cu")
	)
	(gr_arc
		(start 194.193922 -9.780016)
		(mid 194.928504 -11.55342)
		(end 196.701918 -12.288012)
		(stroke
			(width 0.2)
			(type default)
		)
		(layer "In12.Cu")
	)
	(gr_line
		(start 194.193922 -5.787898)
		(end 126.61011 -5.787898)
		(stroke
			(width 0.2)
			(type default)
		)
		(layer "In12.Cu")
	)
	(gr_circle
		(center 194.398646 -353.742244)
		(end 195.287646 -353.742244)
		(stroke
			(width 0.2)
			(type default)
		)
		(fill no)
		(layer "In12.Cu")
	)
	(gr_circle
		(center 194.424046 -354.504244)
		(end 195.313046 -354.504244)
		(stroke
			(width 0.2)
			(type default)
		)
		(fill no)
		(layer "In12.Cu")
	)
	(gr_line
		(start 194.496944 -441.481972)
		(end 194.496944 -441.17006)
		(stroke
			(width 0.2)
			(type default)
		)
		(layer "In12.Cu")
	)
	(gr_line
		(start 194.505072 -441.989972)
		(end 8.50011 -441.989972)
		(stroke
			(width 1.016)
			(type default)
		)
		(layer "In12.Cu")
	)
	(gr_arc
		(start 194.505072 -441.989972)
		(mid 194.858553 -441.843573)
		(end 195.004944 -441.4901)
		(stroke
			(width 1.016)
			(type default)
		)
		(layer "In12.Cu")
	)
	(gr_arc
		(start 194.701922 -9.780016)
		(mid 195.287707 -11.194227)
		(end 196.701918 -11.780012)
		(stroke
			(width 1.016)
			(type default)
		)
		(layer "In12.Cu")
	)
	(gr_arc
		(start 194.701922 -5.780024)
		(mid 194.555654 -5.42634)
		(end 194.20205 -5.279898)
		(stroke
			(width 1.016)
			(type default)
		)
		(layer "In12.Cu")
	)
	(gr_line
		(start 194.701922 -5.780024)
		(end 194.701922 -9.780016)
		(stroke
			(width 1.016)
			(type default)
		)
		(layer "In12.Cu")
	)
	(gr_line
		(start 194.9069 -420.700454)
		(end 194.9069 -413.816038)
		(stroke
			(width 0.635)
			(type default)
		)
		(layer "In12.Cu")
	)
	(gr_arc
		(start 194.9069 -420.700454)
		(mid 194.935087 -420.841508)
		(end 195.015104 -420.961058)
		(stroke
			(width 0.635)
			(type default)
		)
		(layer "In12.Cu")
	)
	(gr_line
		(start 194.9069 -413.816038)
		(end 195.792344 -412.930594)
		(stroke
			(width 0.635)
			(type default)
		)
		(layer "In12.Cu")
	)
	(gr_circle
		(center 194.957446 -354.859844)
		(end 195.846446 -354.859844)
		(stroke
			(width 0.2)
			(type default)
		)
		(fill no)
		(layer "In12.Cu")
	)
	(gr_circle
		(center 194.957446 -354.123244)
		(end 195.846446 -354.123244)
		(stroke
			(width 0.2)
			(type default)
		)
		(fill no)
		(layer "In12.Cu")
	)
	(gr_circle
		(center 194.957446 -353.386644)
		(end 195.846446 -353.386644)
		(stroke
			(width 0.2)
			(type default)
		)
		(fill no)
		(layer "In12.Cu")
	)
	(gr_line
		(start 195.004944 -441.17006)
		(end 195.004944 -441.4901)
		(stroke
			(width 1.016)
			(type default)
		)
		(layer "In12.Cu")
	)
	(gr_line
		(start 195.015104 -420.961058)
		(end 205.73746 -431.683414)
		(stroke
			(width 0.635)
			(type default)
		)
		(layer "In12.Cu")
	)
	(gr_arc
		(start 195.50507 -440.669934)
		(mid 195.151428 -440.816418)
		(end 195.004944 -441.17006)
		(stroke
			(width 1.016)
			(type default)
		)
		(layer "In12.Cu")
	)
	(gr_arc
		(start 195.50507 -440.161934)
		(mid 194.792223 -440.457215)
		(end 194.496944 -441.17006)
		(stroke
			(width 0.2)
			(type default)
		)
		(layer "In12.Cu")
	)
	(gr_line
		(start 195.50507 -440.161934)
		(end 276.314916 -440.161934)
		(stroke
			(width 0.2)
			(type default)
		)
		(layer "In12.Cu")
	)
	(gr_line
		(start 195.792344 -412.930594)
		(end 226.92741 -412.930594)
		(stroke
			(width 0.635)
			(type default)
		)
		(layer "In12.Cu")
	)
	(gr_line
		(start 196.701918 -11.780012)
		(end 221.30004 -11.780012)
		(stroke
			(width 1.016)
			(type default)
		)
		(layer "In12.Cu")
	)
	(gr_circle
		(center 197.2437 -408.059382)
		(end 198.1327 -408.059382)
		(stroke
			(width 0.2)
			(type default)
		)
		(fill no)
		(layer "In12.Cu")
	)
	(gr_circle
		(center 197.2437 -407.297382)
		(end 198.1327 -407.297382)
		(stroke
			(width 0.2)
			(type default)
		)
		(fill no)
		(layer "In12.Cu")
	)
	(gr_circle
		(center 197.2437 -406.535382)
		(end 198.1327 -406.535382)
		(stroke
			(width 0.2)
			(type default)
		)
		(fill no)
		(layer "In12.Cu")
	)
	(gr_circle
		(center 197.2437 -405.773382)
		(end 198.1327 -405.773382)
		(stroke
			(width 0.2)
			(type default)
		)
		(fill no)
		(layer "In12.Cu")
	)
	(gr_circle
		(center 197.2437 -405.011382)
		(end 198.1327 -405.011382)
		(stroke
			(width 0.2)
			(type default)
		)
		(fill no)
		(layer "In12.Cu")
	)
	(gr_circle
		(center 198.0057 -408.059382)
		(end 198.8947 -408.059382)
		(stroke
			(width 0.2)
			(type default)
		)
		(fill no)
		(layer "In12.Cu")
	)
	(gr_circle
		(center 198.0057 -407.297382)
		(end 198.8947 -407.297382)
		(stroke
			(width 0.2)
			(type default)
		)
		(fill no)
		(layer "In12.Cu")
	)
	(gr_circle
		(center 198.0057 -406.535382)
		(end 198.8947 -406.535382)
		(stroke
			(width 0.2)
			(type default)
		)
		(fill no)
		(layer "In12.Cu")
	)
	(gr_circle
		(center 198.0057 -405.773382)
		(end 198.8947 -405.773382)
		(stroke
			(width 0.2)
			(type default)
		)
		(fill no)
		(layer "In12.Cu")
	)
	(gr_circle
		(center 198.0057 -405.011382)
		(end 198.8947 -405.011382)
		(stroke
			(width 0.2)
			(type default)
		)
		(fill no)
		(layer "In12.Cu")
	)
	(gr_circle
		(center 198.114158 -403.223222)
		(end 199.003158 -403.223222)
		(stroke
			(width 0.2)
			(type default)
		)
		(fill no)
		(layer "In12.Cu")
	)
	(gr_circle
		(center 198.114158 -401.920202)
		(end 199.003158 -401.920202)
		(stroke
			(width 0.2)
			(type default)
		)
		(fill no)
		(layer "In12.Cu")
	)
	(gr_circle
		(center 198.114158 -400.617182)
		(end 199.003158 -400.617182)
		(stroke
			(width 0.2)
			(type default)
		)
		(fill no)
		(layer "In12.Cu")
	)
	(gr_circle
		(center 198.160386 -37.328094)
		(end 199.049386 -37.328094)
		(stroke
			(width 0.2)
			(type default)
		)
		(fill no)
		(layer "In12.Cu")
	)
	(gr_circle
		(center 198.486014 -30.133798)
		(end 199.375014 -30.133798)
		(stroke
			(width 0.2)
			(type default)
		)
		(fill no)
		(layer "In12.Cu")
	)
	(gr_circle
		(center 198.7677 -408.059382)
		(end 199.6567 -408.059382)
		(stroke
			(width 0.2)
			(type default)
		)
		(fill no)
		(layer "In12.Cu")
	)
	(gr_circle
		(center 198.7677 -407.297382)
		(end 199.6567 -407.297382)
		(stroke
			(width 0.2)
			(type default)
		)
		(fill no)
		(layer "In12.Cu")
	)
	(gr_circle
		(center 198.7677 -406.535382)
		(end 199.6567 -406.535382)
		(stroke
			(width 0.2)
			(type default)
		)
		(fill no)
		(layer "In12.Cu")
	)
	(gr_circle
		(center 198.7677 -405.773382)
		(end 199.6567 -405.773382)
		(stroke
			(width 0.2)
			(type default)
		)
		(fill no)
		(layer "In12.Cu")
	)
	(gr_circle
		(center 198.7677 -405.011382)
		(end 199.6567 -405.011382)
		(stroke
			(width 0.2)
			(type default)
		)
		(fill no)
		(layer "In12.Cu")
	)
	(gr_circle
		(center 198.836026 -37.965634)
		(end 199.725026 -37.965634)
		(stroke
			(width 0.2)
			(type default)
		)
		(fill no)
		(layer "In12.Cu")
	)
	(gr_circle
		(center 199.121014 -30.133798)
		(end 200.010014 -30.133798)
		(stroke
			(width 0.2)
			(type default)
		)
		(fill no)
		(layer "In12.Cu")
	)
	(gr_circle
		(center 199.435974 -30.720538)
		(end 200.324974 -30.720538)
		(stroke
			(width 0.2)
			(type default)
		)
		(fill no)
		(layer "In12.Cu")
	)
	(gr_circle
		(center 199.5297 -408.059382)
		(end 200.4187 -408.059382)
		(stroke
			(width 0.2)
			(type default)
		)
		(fill no)
		(layer "In12.Cu")
	)
	(gr_circle
		(center 199.5297 -407.297382)
		(end 200.4187 -407.297382)
		(stroke
			(width 0.2)
			(type default)
		)
		(fill no)
		(layer "In12.Cu")
	)
	(gr_circle
		(center 199.5297 -406.535382)
		(end 200.4187 -406.535382)
		(stroke
			(width 0.2)
			(type default)
		)
		(fill no)
		(layer "In12.Cu")
	)
	(gr_circle
		(center 199.5297 -405.773382)
		(end 200.4187 -405.773382)
		(stroke
			(width 0.2)
			(type default)
		)
		(fill no)
		(layer "In12.Cu")
	)
	(gr_circle
		(center 199.5297 -405.011382)
		(end 200.4187 -405.011382)
		(stroke
			(width 0.2)
			(type default)
		)
		(fill no)
		(layer "In12.Cu")
	)
	(gr_circle
		(center 199.536558 -403.223222)
		(end 200.425558 -403.223222)
		(stroke
			(width 0.2)
			(type default)
		)
		(fill no)
		(layer "In12.Cu")
	)
	(gr_circle
		(center 199.536558 -400.617182)
		(end 200.425558 -400.617182)
		(stroke
			(width 0.2)
			(type default)
		)
		(fill no)
		(layer "In12.Cu")
	)
	(gr_circle
		(center 199.756014 -30.133798)
		(end 200.645014 -30.133798)
		(stroke
			(width 0.2)
			(type default)
		)
		(fill no)
		(layer "In12.Cu")
	)
	(gr_circle
		(center 200.070974 -30.720538)
		(end 200.959974 -30.720538)
		(stroke
			(width 0.2)
			(type default)
		)
		(fill no)
		(layer "In12.Cu")
	)
	(gr_circle
		(center 200.2917 -408.059382)
		(end 201.1807 -408.059382)
		(stroke
			(width 0.2)
			(type default)
		)
		(fill no)
		(layer "In12.Cu")
	)
	(gr_circle
		(center 200.2917 -407.297382)
		(end 201.1807 -407.297382)
		(stroke
			(width 0.2)
			(type default)
		)
		(fill no)
		(layer "In12.Cu")
	)
	(gr_circle
		(center 200.2917 -406.535382)
		(end 201.1807 -406.535382)
		(stroke
			(width 0.2)
			(type default)
		)
		(fill no)
		(layer "In12.Cu")
	)
	(gr_circle
		(center 200.2917 -405.773382)
		(end 201.1807 -405.773382)
		(stroke
			(width 0.2)
			(type default)
		)
		(fill no)
		(layer "In12.Cu")
	)
	(gr_circle
		(center 200.2917 -405.011382)
		(end 201.1807 -405.011382)
		(stroke
			(width 0.2)
			(type default)
		)
		(fill no)
		(layer "In12.Cu")
	)
	(gr_circle
		(center 200.33234 -378.160534)
		(end 201.22134 -378.160534)
		(stroke
			(width 0.2)
			(type default)
		)
		(fill no)
		(layer "In12.Cu")
	)
	(gr_circle
		(center 200.391014 -30.133798)
		(end 201.280014 -30.133798)
		(stroke
			(width 0.2)
			(type default)
		)
		(fill no)
		(layer "In12.Cu")
	)
	(gr_circle
		(center 200.705974 -30.720538)
		(end 201.594974 -30.720538)
		(stroke
			(width 0.2)
			(type default)
		)
		(fill no)
		(layer "In12.Cu")
	)
	(gr_circle
		(center 200.933558 -403.223222)
		(end 201.822558 -403.223222)
		(stroke
			(width 0.2)
			(type default)
		)
		(fill no)
		(layer "In12.Cu")
	)
	(gr_circle
		(center 200.933558 -401.920202)
		(end 201.822558 -401.920202)
		(stroke
			(width 0.2)
			(type default)
		)
		(fill no)
		(layer "In12.Cu")
	)
	(gr_circle
		(center 200.933558 -400.617182)
		(end 201.822558 -400.617182)
		(stroke
			(width 0.2)
			(type default)
		)
		(fill no)
		(layer "In12.Cu")
	)
	(gr_circle
		(center 201.0537 -408.059382)
		(end 201.9427 -408.059382)
		(stroke
			(width 0.2)
			(type default)
		)
		(fill no)
		(layer "In12.Cu")
	)
	(gr_circle
		(center 201.0537 -407.297382)
		(end 201.9427 -407.297382)
		(stroke
			(width 0.2)
			(type default)
		)
		(fill no)
		(layer "In12.Cu")
	)
	(gr_circle
		(center 201.0537 -406.535382)
		(end 201.9427 -406.535382)
		(stroke
			(width 0.2)
			(type default)
		)
		(fill no)
		(layer "In12.Cu")
	)
	(gr_circle
		(center 201.0537 -405.773382)
		(end 201.9427 -405.773382)
		(stroke
			(width 0.2)
			(type default)
		)
		(fill no)
		(layer "In12.Cu")
	)
	(gr_circle
		(center 201.0537 -405.011382)
		(end 201.9427 -405.011382)
		(stroke
			(width 0.2)
			(type default)
		)
		(fill no)
		(layer "In12.Cu")
	)
	(gr_circle
		(center 201.340974 -30.720538)
		(end 202.229974 -30.720538)
		(stroke
			(width 0.2)
			(type default)
		)
		(fill no)
		(layer "In12.Cu")
	)
	(gr_circle
		(center 201.745342 -346.583)
		(end 202.634342 -346.583)
		(stroke
			(width 0.2)
			(type default)
		)
		(fill no)
		(layer "In12.Cu")
	)
	(gr_circle
		(center 201.745342 -345.821)
		(end 202.634342 -345.821)
		(stroke
			(width 0.2)
			(type default)
		)
		(fill no)
		(layer "In12.Cu")
	)
	(gr_circle
		(center 201.745342 -344.8304)
		(end 202.634342 -344.8304)
		(stroke
			(width 0.2)
			(type default)
		)
		(fill no)
		(layer "In12.Cu")
	)
	(gr_circle
		(center 201.745342 -344.0684)
		(end 202.634342 -344.0684)
		(stroke
			(width 0.2)
			(type default)
		)
		(fill no)
		(layer "In12.Cu")
	)
	(gr_line
		(start 205.73746 -435.231032)
		(end 207.302608 -436.79618)
		(stroke
			(width 0.635)
			(type default)
		)
		(layer "In12.Cu")
	)
	(gr_line
		(start 205.73746 -431.683414)
		(end 205.73746 -435.231032)
		(stroke
			(width 0.635)
			(type default)
		)
		(layer "In12.Cu")
	)
	(gr_circle
		(center 207.1497 -408.059382)
		(end 208.0387 -408.059382)
		(stroke
			(width 0.2)
			(type default)
		)
		(fill no)
		(layer "In12.Cu")
	)
	(gr_line
		(start 207.302608 -436.79618)
		(end 229.074472 -436.79618)
		(stroke
			(width 0.635)
			(type default)
		)
		(layer "In12.Cu")
	)
	(gr_circle
		(center 207.9117 -408.059382)
		(end 208.8007 -408.059382)
		(stroke
			(width 0.2)
			(type default)
		)
		(fill no)
		(layer "In12.Cu")
	)
	(gr_circle
		(center 207.9117 -407.297382)
		(end 208.8007 -407.297382)
		(stroke
			(width 0.2)
			(type default)
		)
		(fill no)
		(layer "In12.Cu")
	)
	(gr_circle
		(center 208.508854 -37.366448)
		(end 209.397854 -37.366448)
		(stroke
			(width 0.2)
			(type default)
		)
		(fill no)
		(layer "In12.Cu")
	)
	(gr_circle
		(center 208.6737 -408.059382)
		(end 209.5627 -408.059382)
		(stroke
			(width 0.2)
			(type default)
		)
		(fill no)
		(layer "In12.Cu")
	)
	(gr_circle
		(center 208.6737 -407.297382)
		(end 209.5627 -407.297382)
		(stroke
			(width 0.2)
			(type default)
		)
		(fill no)
		(layer "In12.Cu")
	)
	(gr_circle
		(center 208.6737 -406.535382)
		(end 209.5627 -406.535382)
		(stroke
			(width 0.2)
			(type default)
		)
		(fill no)
		(layer "In12.Cu")
	)
	(gr_circle
		(center 208.6737 -405.773382)
		(end 209.5627 -405.773382)
		(stroke
			(width 0.2)
			(type default)
		)
		(fill no)
		(layer "In12.Cu")
	)
	(gr_circle
		(center 208.6737 -405.011382)
		(end 209.5627 -405.011382)
		(stroke
			(width 0.2)
			(type default)
		)
		(fill no)
		(layer "In12.Cu")
	)
	(gr_circle
		(center 208.782158 -403.223222)
		(end 209.671158 -403.223222)
		(stroke
			(width 0.2)
			(type default)
		)
		(fill no)
		(layer "In12.Cu")
	)
	(gr_circle
		(center 208.782158 -401.920202)
		(end 209.671158 -401.920202)
		(stroke
			(width 0.2)
			(type default)
		)
		(fill no)
		(layer "In12.Cu")
	)
	(gr_circle
		(center 208.782158 -400.617182)
		(end 209.671158 -400.617182)
		(stroke
			(width 0.2)
			(type default)
		)
		(fill no)
		(layer "In12.Cu")
	)
	(gr_circle
		(center 209.4357 -408.059382)
		(end 210.3247 -408.059382)
		(stroke
			(width 0.2)
			(type default)
		)
		(fill no)
		(layer "In12.Cu")
	)
	(gr_circle
		(center 209.4357 -407.297382)
		(end 210.3247 -407.297382)
		(stroke
			(width 0.2)
			(type default)
		)
		(fill no)
		(layer "In12.Cu")
	)
	(gr_circle
		(center 209.4357 -406.535382)
		(end 210.3247 -406.535382)
		(stroke
			(width 0.2)
			(type default)
		)
		(fill no)
		(layer "In12.Cu")
	)
	(gr_circle
		(center 209.4357 -405.773382)
		(end 210.3247 -405.773382)
		(stroke
			(width 0.2)
			(type default)
		)
		(fill no)
		(layer "In12.Cu")
	)
	(gr_circle
		(center 209.4357 -405.011382)
		(end 210.3247 -405.011382)
		(stroke
			(width 0.2)
			(type default)
		)
		(fill no)
		(layer "In12.Cu")
	)
	(gr_circle
		(center 210.1977 -408.059382)
		(end 211.0867 -408.059382)
		(stroke
			(width 0.2)
			(type default)
		)
		(fill no)
		(layer "In12.Cu")
	)
	(gr_circle
		(center 210.1977 -407.297382)
		(end 211.0867 -407.297382)
		(stroke
			(width 0.2)
			(type default)
		)
		(fill no)
		(layer "In12.Cu")
	)
	(gr_circle
		(center 210.1977 -406.535382)
		(end 211.0867 -406.535382)
		(stroke
			(width 0.2)
			(type default)
		)
		(fill no)
		(layer "In12.Cu")
	)
	(gr_circle
		(center 210.1977 -405.773382)
		(end 211.0867 -405.773382)
		(stroke
			(width 0.2)
			(type default)
		)
		(fill no)
		(layer "In12.Cu")
	)
	(gr_circle
		(center 210.1977 -405.011382)
		(end 211.0867 -405.011382)
		(stroke
			(width 0.2)
			(type default)
		)
		(fill no)
		(layer "In12.Cu")
	)
	(gr_circle
		(center 210.204558 -403.223222)
		(end 211.093558 -403.223222)
		(stroke
			(width 0.2)
			(type default)
		)
		(fill no)
		(layer "In12.Cu")
	)
	(gr_circle
		(center 210.204558 -400.617182)
		(end 211.093558 -400.617182)
		(stroke
			(width 0.2)
			(type default)
		)
		(fill no)
		(layer "In12.Cu")
	)
	(gr_circle
		(center 210.9597 -408.059382)
		(end 211.8487 -408.059382)
		(stroke
			(width 0.2)
			(type default)
		)
		(fill no)
		(layer "In12.Cu")
	)
	(gr_circle
		(center 210.9597 -407.297382)
		(end 211.8487 -407.297382)
		(stroke
			(width 0.2)
			(type default)
		)
		(fill no)
		(layer "In12.Cu")
	)
	(gr_circle
		(center 210.9597 -406.535382)
		(end 211.8487 -406.535382)
		(stroke
			(width 0.2)
			(type default)
		)
		(fill no)
		(layer "In12.Cu")
	)
	(gr_circle
		(center 210.9597 -405.773382)
		(end 211.8487 -405.773382)
		(stroke
			(width 0.2)
			(type default)
		)
		(fill no)
		(layer "In12.Cu")
	)
	(gr_circle
		(center 210.9597 -405.011382)
		(end 211.8487 -405.011382)
		(stroke
			(width 0.2)
			(type default)
		)
		(fill no)
		(layer "In12.Cu")
	)
	(gr_circle
		(center 211.601558 -403.223222)
		(end 212.490558 -403.223222)
		(stroke
			(width 0.2)
			(type default)
		)
		(fill no)
		(layer "In12.Cu")
	)
	(gr_circle
		(center 211.601558 -401.920202)
		(end 212.490558 -401.920202)
		(stroke
			(width 0.2)
			(type default)
		)
		(fill no)
		(layer "In12.Cu")
	)
	(gr_circle
		(center 211.601558 -400.617182)
		(end 212.490558 -400.617182)
		(stroke
			(width 0.2)
			(type default)
		)
		(fill no)
		(layer "In12.Cu")
	)
	(gr_circle
		(center 211.7217 -408.059382)
		(end 212.6107 -408.059382)
		(stroke
			(width 0.2)
			(type default)
		)
		(fill no)
		(layer "In12.Cu")
	)
	(gr_circle
		(center 211.7217 -407.297382)
		(end 212.6107 -407.297382)
		(stroke
			(width 0.2)
			(type default)
		)
		(fill no)
		(layer "In12.Cu")
	)
	(gr_circle
		(center 211.7217 -406.535382)
		(end 212.6107 -406.535382)
		(stroke
			(width 0.2)
			(type default)
		)
		(fill no)
		(layer "In12.Cu")
	)
	(gr_circle
		(center 211.7217 -405.773382)
		(end 212.6107 -405.773382)
		(stroke
			(width 0.2)
			(type default)
		)
		(fill no)
		(layer "In12.Cu")
	)
	(gr_circle
		(center 211.7217 -405.011382)
		(end 212.6107 -405.011382)
		(stroke
			(width 0.2)
			(type default)
		)
		(fill no)
		(layer "In12.Cu")
	)
	(gr_circle
		(center 212.4837 -408.059382)
		(end 213.3727 -408.059382)
		(stroke
			(width 0.2)
			(type default)
		)
		(fill no)
		(layer "In12.Cu")
	)
	(gr_circle
		(center 212.4837 -407.297382)
		(end 213.3727 -407.297382)
		(stroke
			(width 0.2)
			(type default)
		)
		(fill no)
		(layer "In12.Cu")
	)
	(gr_circle
		(center 217.8177 -408.059382)
		(end 218.7067 -408.059382)
		(stroke
			(width 0.2)
			(type default)
		)
		(fill no)
		(layer "In12.Cu")
	)
	(gr_circle
		(center 218.5797 -408.059382)
		(end 219.4687 -408.059382)
		(stroke
			(width 0.2)
			(type default)
		)
		(fill no)
		(layer "In12.Cu")
	)
	(gr_circle
		(center 218.5797 -407.297382)
		(end 219.4687 -407.297382)
		(stroke
			(width 0.2)
			(type default)
		)
		(fill no)
		(layer "In12.Cu")
	)
	(gr_circle
		(center 219.3417 -408.059382)
		(end 220.2307 -408.059382)
		(stroke
			(width 0.2)
			(type default)
		)
		(fill no)
		(layer "In12.Cu")
	)
	(gr_circle
		(center 219.3417 -407.297382)
		(end 220.2307 -407.297382)
		(stroke
			(width 0.2)
			(type default)
		)
		(fill no)
		(layer "In12.Cu")
	)
	(gr_circle
		(center 219.3417 -406.535382)
		(end 220.2307 -406.535382)
		(stroke
			(width 0.2)
			(type default)
		)
		(fill no)
		(layer "In12.Cu")
	)
	(gr_circle
		(center 219.3417 -405.773382)
		(end 220.2307 -405.773382)
		(stroke
			(width 0.2)
			(type default)
		)
		(fill no)
		(layer "In12.Cu")
	)
	(gr_circle
		(center 219.3417 -405.011382)
		(end 220.2307 -405.011382)
		(stroke
			(width 0.2)
			(type default)
		)
		(fill no)
		(layer "In12.Cu")
	)
	(gr_circle
		(center 219.450158 -403.223222)
		(end 220.339158 -403.223222)
		(stroke
			(width 0.2)
			(type default)
		)
		(fill no)
		(layer "In12.Cu")
	)
	(gr_circle
		(center 219.450158 -401.920202)
		(end 220.339158 -401.920202)
		(stroke
			(width 0.2)
			(type default)
		)
		(fill no)
		(layer "In12.Cu")
	)
	(gr_circle
		(center 219.450158 -400.617182)
		(end 220.339158 -400.617182)
		(stroke
			(width 0.2)
			(type default)
		)
		(fill no)
		(layer "In12.Cu")
	)
	(gr_circle
		(center 220.1037 -408.059382)
		(end 220.9927 -408.059382)
		(stroke
			(width 0.2)
			(type default)
		)
		(fill no)
		(layer "In12.Cu")
	)
	(gr_circle
		(center 220.1037 -407.297382)
		(end 220.9927 -407.297382)
		(stroke
			(width 0.2)
			(type default)
		)
		(fill no)
		(layer "In12.Cu")
	)
	(gr_circle
		(center 220.1037 -406.535382)
		(end 220.9927 -406.535382)
		(stroke
			(width 0.2)
			(type default)
		)
		(fill no)
		(layer "In12.Cu")
	)
	(gr_circle
		(center 220.1037 -405.773382)
		(end 220.9927 -405.773382)
		(stroke
			(width 0.2)
			(type default)
		)
		(fill no)
		(layer "In12.Cu")
	)
	(gr_circle
		(center 220.1037 -405.011382)
		(end 220.9927 -405.011382)
		(stroke
			(width 0.2)
			(type default)
		)
		(fill no)
		(layer "In12.Cu")
	)
	(gr_circle
		(center 220.8657 -408.059382)
		(end 221.7547 -408.059382)
		(stroke
			(width 0.2)
			(type default)
		)
		(fill no)
		(layer "In12.Cu")
	)
	(gr_circle
		(center 220.8657 -407.297382)
		(end 221.7547 -407.297382)
		(stroke
			(width 0.2)
			(type default)
		)
		(fill no)
		(layer "In12.Cu")
	)
	(gr_circle
		(center 220.8657 -406.535382)
		(end 221.7547 -406.535382)
		(stroke
			(width 0.2)
			(type default)
		)
		(fill no)
		(layer "In12.Cu")
	)
	(gr_circle
		(center 220.8657 -405.773382)
		(end 221.7547 -405.773382)
		(stroke
			(width 0.2)
			(type default)
		)
		(fill no)
		(layer "In12.Cu")
	)
	(gr_circle
		(center 220.8657 -405.011382)
		(end 221.7547 -405.011382)
		(stroke
			(width 0.2)
			(type default)
		)
		(fill no)
		(layer "In12.Cu")
	)
	(gr_circle
		(center 220.872558 -403.223222)
		(end 221.761558 -403.223222)
		(stroke
			(width 0.2)
			(type default)
		)
		(fill no)
		(layer "In12.Cu")
	)
	(gr_circle
		(center 220.872558 -400.617182)
		(end 221.761558 -400.617182)
		(stroke
			(width 0.2)
			(type default)
		)
		(fill no)
		(layer "In12.Cu")
	)
	(gr_line
		(start 221.30004 -12.288012)
		(end 196.701918 -12.288012)
		(stroke
			(width 0.2)
			(type default)
		)
		(layer "In12.Cu")
	)
	(gr_circle
		(center 221.6277 -408.059382)
		(end 222.5167 -408.059382)
		(stroke
			(width 0.2)
			(type default)
		)
		(fill no)
		(layer "In12.Cu")
	)
	(gr_circle
		(center 221.6277 -407.297382)
		(end 222.5167 -407.297382)
		(stroke
			(width 0.2)
			(type default)
		)
		(fill no)
		(layer "In12.Cu")
	)
	(gr_circle
		(center 221.6277 -406.535382)
		(end 222.5167 -406.535382)
		(stroke
			(width 0.2)
			(type default)
		)
		(fill no)
		(layer "In12.Cu")
	)
	(gr_circle
		(center 221.6277 -405.773382)
		(end 222.5167 -405.773382)
		(stroke
			(width 0.2)
			(type default)
		)
		(fill no)
		(layer "In12.Cu")
	)
	(gr_circle
		(center 221.6277 -405.011382)
		(end 222.5167 -405.011382)
		(stroke
			(width 0.2)
			(type default)
		)
		(fill no)
		(layer "In12.Cu")
	)
	(gr_circle
		(center 222.269558 -403.223222)
		(end 223.158558 -403.223222)
		(stroke
			(width 0.2)
			(type default)
		)
		(fill no)
		(layer "In12.Cu")
	)
	(gr_circle
		(center 222.269558 -401.920202)
		(end 223.158558 -401.920202)
		(stroke
			(width 0.2)
			(type default)
		)
		(fill no)
		(layer "In12.Cu")
	)
	(gr_circle
		(center 222.269558 -400.617182)
		(end 223.158558 -400.617182)
		(stroke
			(width 0.2)
			(type default)
		)
		(fill no)
		(layer "In12.Cu")
	)
	(gr_circle
		(center 222.3897 -408.059382)
		(end 223.2787 -408.059382)
		(stroke
			(width 0.2)
			(type default)
		)
		(fill no)
		(layer "In12.Cu")
	)
	(gr_circle
		(center 222.3897 -407.297382)
		(end 223.2787 -407.297382)
		(stroke
			(width 0.2)
			(type default)
		)
		(fill no)
		(layer "In12.Cu")
	)
	(gr_circle
		(center 222.3897 -406.535382)
		(end 223.2787 -406.535382)
		(stroke
			(width 0.2)
			(type default)
		)
		(fill no)
		(layer "In12.Cu")
	)
	(gr_circle
		(center 222.3897 -405.773382)
		(end 223.2787 -405.773382)
		(stroke
			(width 0.2)
			(type default)
		)
		(fill no)
		(layer "In12.Cu")
	)
	(gr_circle
		(center 222.3897 -405.011382)
		(end 223.2787 -405.011382)
		(stroke
			(width 0.2)
			(type default)
		)
		(fill no)
		(layer "In12.Cu")
	)
	(gr_line
		(start 222.792036 -34.120074)
		(end 222.792036 -13.780008)
		(stroke
			(width 0.2)
			(type default)
		)
		(layer "In12.Cu")
	)
	(gr_arc
		(start 222.792036 -34.120074)
		(mid 223.526604 -35.8935)
		(end 225.300032 -36.62807)
		(stroke
			(width 0.2)
			(type default)
		)
		(layer "In12.Cu")
	)
	(gr_arc
		(start 222.792036 -13.780008)
		(mid 222.35504 -12.725008)
		(end 221.30004 -12.288012)
		(stroke
			(width 0.2)
			(type default)
		)
		(layer "In12.Cu")
	)
	(gr_circle
		(center 223.1517 -408.059382)
		(end 224.0407 -408.059382)
		(stroke
			(width 0.2)
			(type default)
		)
		(fill no)
		(layer "In12.Cu")
	)
	(gr_circle
		(center 223.1517 -407.297382)
		(end 224.0407 -407.297382)
		(stroke
			(width 0.2)
			(type default)
		)
		(fill no)
		(layer "In12.Cu")
	)
	(gr_arc
		(start 223.300036 -34.120074)
		(mid 223.885821 -35.534285)
		(end 225.300032 -36.12007)
		(stroke
			(width 1.016)
			(type default)
		)
		(layer "In12.Cu")
	)
	(gr_arc
		(start 223.300036 -13.780008)
		(mid 222.714256 -12.365778)
		(end 221.30004 -11.780012)
		(stroke
			(width 1.016)
			(type default)
		)
		(layer "In12.Cu")
	)
	(gr_line
		(start 223.300036 -13.780008)
		(end 223.300036 -34.120074)
		(stroke
			(width 1.016)
			(type default)
		)
		(layer "In12.Cu")
	)
	(gr_line
		(start 225.300032 -36.12007)
		(end 256.800096 -36.12007)
		(stroke
			(width 1.016)
			(type default)
		)
		(layer "In12.Cu")
	)
	(gr_line
		(start 226.92741 -412.930594)
		(end 229.545388 -410.312616)
		(stroke
			(width 0.635)
			(type default)
		)
		(layer "In12.Cu")
	)
	(gr_circle
		(center 228.4857 -408.059382)
		(end 229.3747 -408.059382)
		(stroke
			(width 0.2)
			(type default)
		)
		(fill no)
		(layer "In12.Cu")
	)
	(gr_line
		(start 229.074472 -436.79618)
		(end 229.997 -435.873652)
		(stroke
			(width 0.635)
			(type default)
		)
		(layer "In12.Cu")
	)
	(gr_circle
		(center 229.2477 -408.059382)
		(end 230.1367 -408.059382)
		(stroke
			(width 0.2)
			(type default)
		)
		(fill no)
		(layer "In12.Cu")
	)
	(gr_circle
		(center 229.2477 -407.297382)
		(end 230.1367 -407.297382)
		(stroke
			(width 0.2)
			(type default)
		)
		(fill no)
		(layer "In12.Cu")
	)
	(gr_line
		(start 229.545388 -410.312616)
		(end 234.717844 -410.312616)
		(stroke
			(width 0.635)
			(type default)
		)
		(layer "In12.Cu")
	)
	(gr_line
		(start 229.997 -435.873652)
		(end 229.997 -422.180766)
		(stroke
			(width 0.635)
			(type default)
		)
		(layer "In12.Cu")
	)
	(gr_circle
		(center 230.0097 -408.059382)
		(end 230.8987 -408.059382)
		(stroke
			(width 0.2)
			(type default)
		)
		(fill no)
		(layer "In12.Cu")
	)
	(gr_circle
		(center 230.0097 -407.297382)
		(end 230.8987 -407.297382)
		(stroke
			(width 0.2)
			(type default)
		)
		(fill no)
		(layer "In12.Cu")
	)
	(gr_circle
		(center 230.0097 -406.535382)
		(end 230.8987 -406.535382)
		(stroke
			(width 0.2)
			(type default)
		)
		(fill no)
		(layer "In12.Cu")
	)
	(gr_circle
		(center 230.0097 -405.773382)
		(end 230.8987 -405.773382)
		(stroke
			(width 0.2)
			(type default)
		)
		(fill no)
		(layer "In12.Cu")
	)
	(gr_circle
		(center 230.0097 -405.011382)
		(end 230.8987 -405.011382)
		(stroke
			(width 0.2)
			(type default)
		)
		(fill no)
		(layer "In12.Cu")
	)
	(gr_circle
		(center 230.118158 -403.223222)
		(end 231.007158 -403.223222)
		(stroke
			(width 0.2)
			(type default)
		)
		(fill no)
		(layer "In12.Cu")
	)
	(gr_circle
		(center 230.118158 -401.920202)
		(end 231.007158 -401.920202)
		(stroke
			(width 0.2)
			(type default)
		)
		(fill no)
		(layer "In12.Cu")
	)
	(gr_circle
		(center 230.118158 -400.617182)
		(end 231.007158 -400.617182)
		(stroke
			(width 0.2)
			(type default)
		)
		(fill no)
		(layer "In12.Cu")
	)
	(gr_circle
		(center 230.7717 -408.059382)
		(end 231.6607 -408.059382)
		(stroke
			(width 0.2)
			(type default)
		)
		(fill no)
		(layer "In12.Cu")
	)
	(gr_circle
		(center 230.7717 -407.297382)
		(end 231.6607 -407.297382)
		(stroke
			(width 0.2)
			(type default)
		)
		(fill no)
		(layer "In12.Cu")
	)
	(gr_circle
		(center 230.7717 -406.535382)
		(end 231.6607 -406.535382)
		(stroke
			(width 0.2)
			(type default)
		)
		(fill no)
		(layer "In12.Cu")
	)
	(gr_circle
		(center 230.7717 -405.773382)
		(end 231.6607 -405.773382)
		(stroke
			(width 0.2)
			(type default)
		)
		(fill no)
		(layer "In12.Cu")
	)
	(gr_circle
		(center 230.7717 -405.011382)
		(end 231.6607 -405.011382)
		(stroke
			(width 0.2)
			(type default)
		)
		(fill no)
		(layer "In12.Cu")
	)
	(gr_circle
		(center 231.5337 -408.059382)
		(end 232.4227 -408.059382)
		(stroke
			(width 0.2)
			(type default)
		)
		(fill no)
		(layer "In12.Cu")
	)
	(gr_circle
		(center 231.5337 -407.297382)
		(end 232.4227 -407.297382)
		(stroke
			(width 0.2)
			(type default)
		)
		(fill no)
		(layer "In12.Cu")
	)
	(gr_circle
		(center 231.5337 -406.535382)
		(end 232.4227 -406.535382)
		(stroke
			(width 0.2)
			(type default)
		)
		(fill no)
		(layer "In12.Cu")
	)
	(gr_circle
		(center 231.5337 -405.773382)
		(end 232.4227 -405.773382)
		(stroke
			(width 0.2)
			(type default)
		)
		(fill no)
		(layer "In12.Cu")
	)
	(gr_circle
		(center 231.5337 -405.011382)
		(end 232.4227 -405.011382)
		(stroke
			(width 0.2)
			(type default)
		)
		(fill no)
		(layer "In12.Cu")
	)
	(gr_circle
		(center 231.540558 -403.223222)
		(end 232.429558 -403.223222)
		(stroke
			(width 0.2)
			(type default)
		)
		(fill no)
		(layer "In12.Cu")
	)
	(gr_circle
		(center 231.540558 -400.617182)
		(end 232.429558 -400.617182)
		(stroke
			(width 0.2)
			(type default)
		)
		(fill no)
		(layer "In12.Cu")
	)
	(gr_circle
		(center 232.2957 -408.059382)
		(end 233.1847 -408.059382)
		(stroke
			(width 0.2)
			(type default)
		)
		(fill no)
		(layer "In12.Cu")
	)
	(gr_circle
		(center 232.2957 -407.297382)
		(end 233.1847 -407.297382)
		(stroke
			(width 0.2)
			(type default)
		)
		(fill no)
		(layer "In12.Cu")
	)
	(gr_circle
		(center 232.2957 -406.535382)
		(end 233.1847 -406.535382)
		(stroke
			(width 0.2)
			(type default)
		)
		(fill no)
		(layer "In12.Cu")
	)
	(gr_circle
		(center 232.2957 -405.773382)
		(end 233.1847 -405.773382)
		(stroke
			(width 0.2)
			(type default)
		)
		(fill no)
		(layer "In12.Cu")
	)
	(gr_circle
		(center 232.2957 -405.011382)
		(end 233.1847 -405.011382)
		(stroke
			(width 0.2)
			(type default)
		)
		(fill no)
		(layer "In12.Cu")
	)
	(gr_circle
		(center 232.937558 -403.223222)
		(end 233.826558 -403.223222)
		(stroke
			(width 0.2)
			(type default)
		)
		(fill no)
		(layer "In12.Cu")
	)
	(gr_circle
		(center 232.937558 -401.920202)
		(end 233.826558 -401.920202)
		(stroke
			(width 0.2)
			(type default)
		)
		(fill no)
		(layer "In12.Cu")
	)
	(gr_circle
		(center 232.937558 -400.617182)
		(end 233.826558 -400.617182)
		(stroke
			(width 0.2)
			(type default)
		)
		(fill no)
		(layer "In12.Cu")
	)
	(gr_circle
		(center 233.0577 -408.059382)
		(end 233.9467 -408.059382)
		(stroke
			(width 0.2)
			(type default)
		)
		(fill no)
		(layer "In12.Cu")
	)
	(gr_circle
		(center 233.0577 -407.297382)
		(end 233.9467 -407.297382)
		(stroke
			(width 0.2)
			(type default)
		)
		(fill no)
		(layer "In12.Cu")
	)
	(gr_circle
		(center 233.0577 -406.535382)
		(end 233.9467 -406.535382)
		(stroke
			(width 0.2)
			(type default)
		)
		(fill no)
		(layer "In12.Cu")
	)
	(gr_circle
		(center 233.0577 -405.773382)
		(end 233.9467 -405.773382)
		(stroke
			(width 0.2)
			(type default)
		)
		(fill no)
		(layer "In12.Cu")
	)
	(gr_circle
		(center 233.0577 -405.011382)
		(end 233.9467 -405.011382)
		(stroke
			(width 0.2)
			(type default)
		)
		(fill no)
		(layer "In12.Cu")
	)
	(gr_circle
		(center 233.8197 -408.059382)
		(end 234.7087 -408.059382)
		(stroke
			(width 0.2)
			(type default)
		)
		(fill no)
		(layer "In12.Cu")
	)
	(gr_circle
		(center 233.8197 -407.297382)
		(end 234.7087 -407.297382)
		(stroke
			(width 0.2)
			(type default)
		)
		(fill no)
		(layer "In12.Cu")
	)
	(gr_line
		(start 234.717844 -410.312616)
		(end 238.882682 -406.147778)
		(stroke
			(width 0.635)
			(type default)
		)
		(layer "In12.Cu")
	)
	(gr_line
		(start 234.897676 -417.28009)
		(end 229.997 -422.180766)
		(stroke
			(width 0.635)
			(type default)
		)
		(layer "In12.Cu")
	)
	(gr_circle
		(center 237.629954 -44.025566)
		(end 238.518954 -44.025566)
		(stroke
			(width 0.2)
			(type default)
		)
		(fill no)
		(layer "In12.Cu")
	)
	(gr_circle
		(center 237.640114 -44.716446)
		(end 238.529114 -44.716446)
		(stroke
			(width 0.2)
			(type default)
		)
		(fill no)
		(layer "In12.Cu")
	)
	(gr_circle
		(center 238.292894 -44.802806)
		(end 239.181894 -44.802806)
		(stroke
			(width 0.2)
			(type default)
		)
		(fill no)
		(layer "In12.Cu")
	)
	(gr_circle
		(center 238.292894 -44.040806)
		(end 239.181894 -44.040806)
		(stroke
			(width 0.2)
			(type default)
		)
		(fill no)
		(layer "In12.Cu")
	)
	(gr_arc
		(start 238.695992 -393.003532)
		(mid 238.724179 -393.144586)
		(end 238.804196 -393.264136)
		(stroke
			(width 0.635)
			(type default)
		)
		(layer "In12.Cu")
	)
	(gr_line
		(start 238.695992 -384.337306)
		(end 238.695992 -393.003532)
		(stroke
			(width 0.635)
			(type default)
		)
		(layer "In12.Cu")
	)
	(gr_line
		(start 238.752126 -384.198876)
		(end 238.695992 -384.337306)
		(stroke
			(width 0.635)
			(type default)
		)
		(layer "In12.Cu")
	)
	(gr_line
		(start 238.804196 -393.264136)
		(end 239.027716 -393.487656)
		(stroke
			(width 0.635)
			(type default)
		)
		(layer "In12.Cu")
	)
	(gr_line
		(start 238.805974 -384.146806)
		(end 238.752126 -384.198876)
		(stroke
			(width 0.635)
			(type default)
		)
		(layer "In12.Cu")
	)
	(gr_line
		(start 238.882682 -406.147778)
		(end 238.882682 -394.001498)
		(stroke
			(width 0.635)
			(type default)
		)
		(layer "In12.Cu")
	)
	(gr_line
		(start 238.882682 -394.210794)
		(end 238.882682 -394.001498)
		(stroke
			(width 0.635)
			(type default)
		)
		(layer "In12.Cu")
	)
	(gr_line
		(start 238.882682 -394.210794)
		(end 279.615392 -394.210794)
		(stroke
			(width 0.635)
			(type default)
		)
		(layer "In12.Cu")
	)
	(gr_line
		(start 238.882682 -394.001498)
		(end 239.28832 -393.59586)
		(stroke
			(width 0.635)
			(type default)
		)
		(layer "In12.Cu")
	)
	(gr_line
		(start 238.882682 -394.001498)
		(end 239.6998 -394.001498)
		(stroke
			(width 0.635)
			(type default)
		)
		(layer "In12.Cu")
	)
	(gr_circle
		(center 238.943134 -44.802806)
		(end 239.832134 -44.802806)
		(stroke
			(width 0.2)
			(type default)
		)
		(fill no)
		(layer "In12.Cu")
	)
	(gr_circle
		(center 238.943134 -44.040806)
		(end 239.832134 -44.040806)
		(stroke
			(width 0.2)
			(type default)
		)
		(fill no)
		(layer "In12.Cu")
	)
	(gr_arc
		(start 239.027716 -393.487656)
		(mid 239.147257 -393.567682)
		(end 239.28832 -393.59586)
		(stroke
			(width 0.635)
			(type default)
		)
		(layer "In12.Cu")
	)
	(gr_line
		(start 239.281716 -383.671064)
		(end 238.805974 -384.146806)
		(stroke
			(width 0.635)
			(type default)
		)
		(layer "In12.Cu")
	)
	(gr_line
		(start 239.28832 -393.59586)
		(end 273.155664 -393.59586)
		(stroke
			(width 0.635)
			(type default)
		)
		(layer "In12.Cu")
	)
	(gr_arc
		(start 239.54232 -383.56286)
		(mid 239.401266 -383.591047)
		(end 239.281716 -383.671064)
		(stroke
			(width 0.635)
			(type default)
		)
		(layer "In12.Cu")
	)
	(gr_circle
		(center 239.578134 -44.802806)
		(end 240.467134 -44.802806)
		(stroke
			(width 0.2)
			(type default)
		)
		(fill no)
		(layer "In12.Cu")
	)
	(gr_circle
		(center 239.578134 -44.040806)
		(end 240.467134 -44.040806)
		(stroke
			(width 0.2)
			(type default)
		)
		(fill no)
		(layer "In12.Cu")
	)
	(gr_line
		(start 239.6998 -394.001498)
		(end 239.770412 -394.07211)
		(stroke
			(width 0.635)
			(type default)
		)
		(layer "In12.Cu")
	)
	(gr_circle
		(center 240.213134 -44.802806)
		(end 241.102134 -44.802806)
		(stroke
			(width 0.2)
			(type default)
		)
		(fill no)
		(layer "In12.Cu")
	)
	(gr_circle
		(center 240.213134 -44.040806)
		(end 241.102134 -44.040806)
		(stroke
			(width 0.2)
			(type default)
		)
		(fill no)
		(layer "In12.Cu")
	)
	(gr_circle
		(center 240.893854 -44.830746)
		(end 241.782854 -44.830746)
		(stroke
			(width 0.2)
			(type default)
		)
		(fill no)
		(layer "In12.Cu")
	)
	(gr_circle
		(center 244.518942 -43.246802)
		(end 245.407942 -43.246802)
		(stroke
			(width 0.2)
			(type default)
		)
		(fill no)
		(layer "In12.Cu")
	)
	(gr_circle
		(center 244.518942 -42.611802)
		(end 245.407942 -42.611802)
		(stroke
			(width 0.2)
			(type default)
		)
		(fill no)
		(layer "In12.Cu")
	)
	(gr_circle
		(center 245.857522 -52.022502)
		(end 246.746522 -52.022502)
		(stroke
			(width 0.2)
			(type default)
		)
		(fill no)
		(layer "In12.Cu")
	)
	(gr_circle
		(center 246.873522 -52.022502)
		(end 247.762522 -52.022502)
		(stroke
			(width 0.2)
			(type default)
		)
		(fill no)
		(layer "In12.Cu")
	)
	(gr_circle
		(center 247.825514 -40.94988)
		(end 248.714514 -40.94988)
		(stroke
			(width 0.2)
			(type default)
		)
		(fill no)
		(layer "In12.Cu")
	)
	(gr_circle
		(center 247.840246 -51.320446)
		(end 248.729246 -51.320446)
		(stroke
			(width 0.2)
			(type default)
		)
		(fill no)
		(layer "In12.Cu")
	)
	(gr_circle
		(center 248.214134 -52.171346)
		(end 249.103134 -52.171346)
		(stroke
			(width 0.2)
			(type default)
		)
		(fill no)
		(layer "In12.Cu")
	)
	(gr_circle
		(center 248.881646 -51.320446)
		(end 249.770646 -51.320446)
		(stroke
			(width 0.2)
			(type default)
		)
		(fill no)
		(layer "In12.Cu")
	)
	(gr_circle
		(center 249.202448 -40.945816)
		(end 250.091448 -40.945816)
		(stroke
			(width 0.2)
			(type default)
		)
		(fill no)
		(layer "In12.Cu")
	)
	(gr_circle
		(center 249.905266 -51.349148)
		(end 250.794266 -51.349148)
		(stroke
			(width 0.2)
			(type default)
		)
		(fill no)
		(layer "In12.Cu")
	)
	(gr_circle
		(center 250.449334 -49.555146)
		(end 251.338334 -49.555146)
		(stroke
			(width 0.2)
			(type default)
		)
		(fill no)
		(layer "In12.Cu")
	)
	(gr_circle
		(center 250.779534 -52.222146)
		(end 251.668534 -52.222146)
		(stroke
			(width 0.2)
			(type default)
		)
		(fill no)
		(layer "In12.Cu")
	)
	(gr_circle
		(center 250.779534 -51.333146)
		(end 251.668534 -51.333146)
		(stroke
			(width 0.2)
			(type default)
		)
		(fill no)
		(layer "In12.Cu")
	)
	(gr_circle
		(center 250.779534 -50.444146)
		(end 251.668534 -50.444146)
		(stroke
			(width 0.2)
			(type default)
		)
		(fill no)
		(layer "In12.Cu")
	)
	(gr_circle
		(center 251.516134 -52.501546)
		(end 252.405134 -52.501546)
		(stroke
			(width 0.2)
			(type default)
		)
		(fill no)
		(layer "In12.Cu")
	)
	(gr_circle
		(center 251.516134 -51.612546)
		(end 252.405134 -51.612546)
		(stroke
			(width 0.2)
			(type default)
		)
		(fill no)
		(layer "In12.Cu")
	)
	(gr_circle
		(center 251.516134 -50.723546)
		(end 252.405134 -50.723546)
		(stroke
			(width 0.2)
			(type default)
		)
		(fill no)
		(layer "In12.Cu")
	)
	(gr_circle
		(center 255.347978 -39.380922)
		(end 256.236978 -39.380922)
		(stroke
			(width 0.2)
			(type default)
		)
		(fill no)
		(layer "In12.Cu")
	)
	(gr_line
		(start 256.800096 -36.62807)
		(end 225.300032 -36.62807)
		(stroke
			(width 0.2)
			(type default)
		)
		(layer "In12.Cu")
	)
	(gr_arc
		(start 256.800096 -36.62807)
		(mid 258.57351 -35.893495)
		(end 259.308092 -34.120074)
		(stroke
			(width 0.2)
			(type default)
		)
		(layer "In12.Cu")
	)
	(gr_arc
		(start 256.800096 -36.12007)
		(mid 258.214307 -35.534285)
		(end 258.800092 -34.120074)
		(stroke
			(width 1.016)
			(type default)
		)
		(layer "In12.Cu")
	)
	(gr_line
		(start 258.800092 -34.120074)
		(end 258.800092 -13.780008)
		(stroke
			(width 1.016)
			(type default)
		)
		(layer "In12.Cu")
	)
	(gr_line
		(start 259.308092 -13.780008)
		(end 259.308092 -34.120074)
		(stroke
			(width 0.2)
			(type default)
		)
		(layer "In12.Cu")
	)
	(gr_arc
		(start 260.800088 -12.288012)
		(mid 259.745088 -12.725008)
		(end 259.308092 -13.780008)
		(stroke
			(width 0.2)
			(type default)
		)
		(layer "In12.Cu")
	)
	(gr_arc
		(start 260.800088 -11.780012)
		(mid 259.385888 -12.365802)
		(end 258.800092 -13.780008)
		(stroke
			(width 1.016)
			(type default)
		)
		(layer "In12.Cu")
	)
	(gr_line
		(start 260.800088 -11.780012)
		(end 385.601972 -11.780012)
		(stroke
			(width 1.016)
			(type default)
		)
		(layer "In12.Cu")
	)
	(gr_line
		(start 272.19021 -417.28009)
		(end 234.897676 -417.28009)
		(stroke
			(width 0.635)
			(type default)
		)
		(layer "In12.Cu")
	)
	(gr_arc
		(start 273.155664 -393.59586)
		(mid 273.296718 -393.567673)
		(end 273.416268 -393.487656)
		(stroke
			(width 0.635)
			(type default)
		)
		(layer "In12.Cu")
	)
	(gr_line
		(start 273.33067 -394.041884)
		(end 279.547066 -394.041884)
		(stroke
			(width 0.635)
			(type default)
		)
		(layer "In12.Cu")
	)
	(gr_line
		(start 273.416268 -393.487656)
		(end 273.893788 -393.010136)
		(stroke
			(width 0.635)
			(type default)
		)
		(layer "In12.Cu")
	)
	(gr_line
		(start 273.481546 -383.56286)
		(end 239.54232 -383.56286)
		(stroke
			(width 0.635)
			(type default)
		)
		(layer "In12.Cu")
	)
	(gr_line
		(start 273.619976 -383.618994)
		(end 273.481546 -383.56286)
		(stroke
			(width 0.635)
			(type default)
		)
		(layer "In12.Cu")
	)
	(gr_line
		(start 273.672046 -383.672842)
		(end 273.619976 -383.618994)
		(stroke
			(width 0.635)
			(type default)
		)
		(layer "In12.Cu")
	)
	(gr_arc
		(start 273.893788 -393.010136)
		(mid 273.97387 -392.890613)
		(end 274.001992 -392.749532)
		(stroke
			(width 0.635)
			(type default)
		)
		(layer "In12.Cu")
	)
	(gr_line
		(start 273.893788 -383.894584)
		(end 273.672046 -383.672842)
		(stroke
			(width 0.635)
			(type default)
		)
		(layer "In12.Cu")
	)
	(gr_line
		(start 274.001992 -392.749532)
		(end 274.001992 -384.155188)
		(stroke
			(width 0.635)
			(type default)
		)
		(layer "In12.Cu")
	)
	(gr_arc
		(start 274.001992 -384.155188)
		(mid 273.973805 -384.014134)
		(end 273.893788 -383.894584)
		(stroke
			(width 0.635)
			(type default)
		)
		(layer "In12.Cu")
	)
	(gr_line
		(start 274.123404 -393.697206)
		(end 279.133554 -393.697206)
		(stroke
			(width 0.635)
			(type default)
		)
		(layer "In12.Cu")
	)
	(gr_line
		(start 274.433792 -392.938762)
		(end 273.33067 -394.041884)
		(stroke
			(width 0.635)
			(type default)
		)
		(layer "In12.Cu")
	)
	(gr_line
		(start 274.433792 -392.938762)
		(end 274.50288 -392.869674)
		(stroke
			(width 0.635)
			(type default)
		)
		(layer "In12.Cu")
	)
	(gr_line
		(start 274.433792 -392.317732)
		(end 274.67052 -392.55446)
		(stroke
			(width 0.635)
			(type default)
		)
		(layer "In12.Cu")
	)
	(gr_line
		(start 274.433792 -384.002788)
		(end 274.433792 -392.938762)
		(stroke
			(width 0.635)
			(type default)
		)
		(layer "In12.Cu")
	)
	(gr_line
		(start 274.433792 -384.002788)
		(end 274.433792 -392.317732)
		(stroke
			(width 0.635)
			(type default)
		)
		(layer "In12.Cu")
	)
	(gr_line
		(start 274.50288 -392.869674)
		(end 279.110694 -392.869674)
		(stroke
			(width 0.635)
			(type default)
		)
		(layer "In12.Cu")
	)
	(gr_line
		(start 274.732496 -393.237466)
		(end 274.433792 -392.938762)
		(stroke
			(width 0.635)
			(type default)
		)
		(layer "In12.Cu")
	)
	(gr_line
		(start 274.778724 -392.605514)
		(end 274.192746 -392.019536)
		(stroke
			(width 0.635)
			(type default)
		)
		(layer "In12.Cu")
	)
	(gr_line
		(start 274.87372 -383.56286)
		(end 274.433792 -384.002788)
		(stroke
			(width 0.635)
			(type default)
		)
		(layer "In12.Cu")
	)
	(gr_circle
		(center 276.112986 -348.704662)
		(end 276.993096 -348.704662)
		(stroke
			(width 0.2)
			(type default)
		)
		(fill no)
		(layer "In12.Cu")
	)
	(gr_line
		(start 276.314916 -440.669934)
		(end 195.50507 -440.669934)
		(stroke
			(width 1.016)
			(type default)
		)
		(layer "In12.Cu")
	)
	(gr_circle
		(center 276.730206 -348.704662)
		(end 277.610316 -348.704662)
		(stroke
			(width 0.2)
			(type default)
		)
		(fill no)
		(layer "In12.Cu")
	)
	(gr_line
		(start 276.815042 -441.4901)
		(end 276.815042 -441.17006)
		(stroke
			(width 1.016)
			(type default)
		)
		(layer "In12.Cu")
	)
	(gr_arc
		(start 276.815042 -441.4901)
		(mid 276.961452 -441.843558)
		(end 277.314914 -441.989972)
		(stroke
			(width 1.016)
			(type default)
		)
		(layer "In12.Cu")
	)
	(gr_arc
		(start 276.815042 -441.17006)
		(mid 276.668558 -440.816418)
		(end 276.314916 -440.669934)
		(stroke
			(width 1.016)
			(type default)
		)
		(layer "In12.Cu")
	)
	(gr_line
		(start 277.323042 -441.481972)
		(end 463.300064 -441.481972)
		(stroke
			(width 0.2)
			(type default)
		)
		(layer "In12.Cu")
	)
	(gr_arc
		(start 277.323042 -441.17006)
		(mid 277.027756 -440.457227)
		(end 276.314916 -440.161934)
		(stroke
			(width 0.2)
			(type default)
		)
		(layer "In12.Cu")
	)
	(gr_line
		(start 277.323042 -441.17006)
		(end 277.323042 -441.481972)
		(stroke
			(width 0.2)
			(type default)
		)
		(layer "In12.Cu")
	)
	(gr_circle
		(center 277.347426 -348.704662)
		(end 278.227536 -348.704662)
		(stroke
			(width 0.2)
			(type default)
		)
		(fill no)
		(layer "In12.Cu")
	)
	(gr_circle
		(center 277.593806 -348.025212)
		(end 278.482806 -348.025212)
		(stroke
			(width 0.2)
			(type default)
		)
		(fill no)
		(layer "In12.Cu")
	)
	(gr_circle
		(center 277.593806 -347.288612)
		(end 278.482806 -347.288612)
		(stroke
			(width 0.2)
			(type default)
		)
		(fill no)
		(layer "In12.Cu")
	)
	(gr_circle
		(center 278.049482 -350.313752)
		(end 278.938482 -350.313752)
		(stroke
			(width 0.2)
			(type default)
		)
		(fill no)
		(layer "In12.Cu")
	)
	(gr_circle
		(center 278.049482 -349.577152)
		(end 278.938482 -349.577152)
		(stroke
			(width 0.2)
			(type default)
		)
		(fill no)
		(layer "In12.Cu")
	)
	(gr_circle
		(center 278.574246 -349.137732)
		(end 279.463246 -349.137732)
		(stroke
			(width 0.2)
			(type default)
		)
		(fill no)
		(layer "In12.Cu")
	)
	(gr_circle
		(center 278.599646 -349.899732)
		(end 279.488646 -349.899732)
		(stroke
			(width 0.2)
			(type default)
		)
		(fill no)
		(layer "In12.Cu")
	)
	(gr_line
		(start 278.892508 -393.237466)
		(end 274.732496 -393.237466)
		(stroke
			(width 0.635)
			(type default)
		)
		(layer "In12.Cu")
	)
	(gr_line
		(start 279.110694 -392.869674)
		(end 279.351994 -392.628374)
		(stroke
			(width 0.635)
			(type default)
		)
		(layer "In12.Cu")
	)
	(gr_circle
		(center 279.133046 -350.255332)
		(end 280.022046 -350.255332)
		(stroke
			(width 0.2)
			(type default)
		)
		(fill no)
		(layer "In12.Cu")
	)
	(gr_circle
		(center 279.133046 -349.518732)
		(end 280.022046 -349.518732)
		(stroke
			(width 0.2)
			(type default)
		)
		(fill no)
		(layer "In12.Cu")
	)
	(gr_circle
		(center 279.133046 -348.782132)
		(end 280.022046 -348.782132)
		(stroke
			(width 0.2)
			(type default)
		)
		(fill no)
		(layer "In12.Cu")
	)
	(gr_line
		(start 279.133554 -393.697206)
		(end 279.983946 -392.846814)
		(stroke
			(width 0.635)
			(type default)
		)
		(layer "In12.Cu")
	)
	(gr_line
		(start 279.329134 -392.605514)
		(end 274.778724 -392.605514)
		(stroke
			(width 0.635)
			(type default)
		)
		(layer "In12.Cu")
	)
	(gr_line
		(start 279.351994 -392.628374)
		(end 279.329134 -392.605514)
		(stroke
			(width 0.635)
			(type default)
		)
		(layer "In12.Cu")
	)
	(gr_line
		(start 279.547066 -394.041884)
		(end 280.477976 -393.110974)
		(stroke
			(width 0.635)
			(type default)
		)
		(layer "In12.Cu")
	)
	(gr_line
		(start 279.616408 -392.513566)
		(end 278.892508 -393.237466)
		(stroke
			(width 0.635)
			(type default)
		)
		(layer "In12.Cu")
	)
	(gr_line
		(start 279.616408 -383.780538)
		(end 279.616408 -392.513566)
		(stroke
			(width 0.635)
			(type default)
		)
		(layer "In12.Cu")
	)
	(gr_line
		(start 279.834086 -383.56286)
		(end 279.616408 -383.780538)
		(stroke
			(width 0.635)
			(type default)
		)
		(layer "In12.Cu")
	)
	(gr_arc
		(start 279.875996 -394.318998)
		(mid 279.756473 -394.238916)
		(end 279.615392 -394.210794)
		(stroke
			(width 0.635)
			(type default)
		)
		(layer "In12.Cu")
	)
	(gr_line
		(start 279.983946 -392.846814)
		(end 279.983946 -383.781046)
		(stroke
			(width 0.635)
			(type default)
		)
		(layer "In12.Cu")
	)
	(gr_line
		(start 279.983946 -383.781046)
		(end 280.202132 -383.56286)
		(stroke
			(width 0.635)
			(type default)
		)
		(layer "In12.Cu")
	)
	(gr_line
		(start 280.202132 -383.56286)
		(end 274.87372 -383.56286)
		(stroke
			(width 0.635)
			(type default)
		)
		(layer "In12.Cu")
	)
	(gr_line
		(start 280.202132 -383.56286)
		(end 279.834086 -383.56286)
		(stroke
			(width 0.635)
			(type default)
		)
		(layer "In12.Cu")
	)
	(gr_line
		(start 280.259536 -394.702538)
		(end 279.875996 -394.318998)
		(stroke
			(width 0.635)
			(type default)
		)
		(layer "In12.Cu")
	)
	(gr_line
		(start 280.36774 -409.10256)
		(end 272.19021 -417.28009)
		(stroke
			(width 0.635)
			(type default)
		)
		(layer "In12.Cu")
	)
	(gr_arc
		(start 280.36774 -394.963142)
		(mid 280.339553 -394.822088)
		(end 280.259536 -394.702538)
		(stroke
			(width 0.635)
			(type default)
		)
		(layer "In12.Cu")
	)
	(gr_line
		(start 280.36774 -394.963142)
		(end 280.36774 -409.10256)
		(stroke
			(width 0.635)
			(type default)
		)
		(layer "In12.Cu")
	)
	(gr_line
		(start 280.477976 -393.110974)
		(end 280.477976 -383.838704)
		(stroke
			(width 0.635)
			(type default)
		)
		(layer "In12.Cu")
	)
	(gr_line
		(start 280.477976 -383.838704)
		(end 280.202132 -383.56286)
		(stroke
			(width 0.635)
			(type default)
		)
		(layer "In12.Cu")
	)
	(gr_line
		(start 280.537412 -392.55446)
		(end 274.67052 -392.55446)
		(stroke
			(width 0.635)
			(type default)
		)
		(layer "In12.Cu")
	)
	(gr_line
		(start 280.537412 -392.55446)
		(end 280.9113 -392.180572)
		(stroke
			(width 0.635)
			(type default)
		)
		(layer "In12.Cu")
	)
	(gr_line
		(start 280.9113 -392.180572)
		(end 280.9113 -384.272028)
		(stroke
			(width 0.635)
			(type default)
		)
		(layer "In12.Cu")
	)
	(gr_line
		(start 280.9113 -384.272028)
		(end 280.202132 -383.56286)
		(stroke
			(width 0.635)
			(type default)
		)
		(layer "In12.Cu")
	)
	(gr_circle
		(center 284.393386 -348.704662)
		(end 285.273496 -348.704662)
		(stroke
			(width 0.2)
			(type default)
		)
		(fill no)
		(layer "In12.Cu")
	)
	(gr_circle
		(center 285.010606 -348.704662)
		(end 285.890716 -348.704662)
		(stroke
			(width 0.2)
			(type default)
		)
		(fill no)
		(layer "In12.Cu")
	)
	(gr_circle
		(center 285.627826 -348.704662)
		(end 286.507936 -348.704662)
		(stroke
			(width 0.2)
			(type default)
		)
		(fill no)
		(layer "In12.Cu")
	)
	(gr_circle
		(center 285.869126 -347.982032)
		(end 286.758126 -347.982032)
		(stroke
			(width 0.2)
			(type default)
		)
		(fill no)
		(layer "In12.Cu")
	)
	(gr_circle
		(center 285.869126 -347.245432)
		(end 286.758126 -347.245432)
		(stroke
			(width 0.2)
			(type default)
		)
		(fill no)
		(layer "In12.Cu")
	)
	(gr_circle
		(center 286.329882 -350.313752)
		(end 287.218882 -350.313752)
		(stroke
			(width 0.2)
			(type default)
		)
		(fill no)
		(layer "In12.Cu")
	)
	(gr_circle
		(center 286.329882 -349.577152)
		(end 287.218882 -349.577152)
		(stroke
			(width 0.2)
			(type default)
		)
		(fill no)
		(layer "In12.Cu")
	)
	(gr_circle
		(center 286.36595 -355.279198)
		(end 287.25495 -355.279198)
		(stroke
			(width 0.2)
			(type default)
		)
		(fill no)
		(layer "In12.Cu")
	)
	(gr_circle
		(center 286.37611 -356.584758)
		(end 287.26511 -356.584758)
		(stroke
			(width 0.2)
			(type default)
		)
		(fill no)
		(layer "In12.Cu")
	)
	(gr_circle
		(center 286.37611 -355.949758)
		(end 287.26511 -355.949758)
		(stroke
			(width 0.2)
			(type default)
		)
		(fill no)
		(layer "In12.Cu")
	)
	(gr_circle
		(center 286.854646 -349.137732)
		(end 287.743646 -349.137732)
		(stroke
			(width 0.2)
			(type default)
		)
		(fill no)
		(layer "In12.Cu")
	)
	(gr_circle
		(center 286.880046 -349.899732)
		(end 287.769046 -349.899732)
		(stroke
			(width 0.2)
			(type default)
		)
		(fill no)
		(layer "In12.Cu")
	)
	(gr_circle
		(center 287.00095 -355.279198)
		(end 287.88995 -355.279198)
		(stroke
			(width 0.2)
			(type default)
		)
		(fill no)
		(layer "In12.Cu")
	)
	(gr_circle
		(center 287.01111 -356.584758)
		(end 287.90011 -356.584758)
		(stroke
			(width 0.2)
			(type default)
		)
		(fill no)
		(layer "In12.Cu")
	)
	(gr_circle
		(center 287.01111 -355.949758)
		(end 287.90011 -355.949758)
		(stroke
			(width 0.2)
			(type default)
		)
		(fill no)
		(layer "In12.Cu")
	)
	(gr_circle
		(center 287.413446 -350.255332)
		(end 288.302446 -350.255332)
		(stroke
			(width 0.2)
			(type default)
		)
		(fill no)
		(layer "In12.Cu")
	)
	(gr_circle
		(center 287.413446 -349.518732)
		(end 288.302446 -349.518732)
		(stroke
			(width 0.2)
			(type default)
		)
		(fill no)
		(layer "In12.Cu")
	)
	(gr_circle
		(center 287.413446 -348.782132)
		(end 288.302446 -348.782132)
		(stroke
			(width 0.2)
			(type default)
		)
		(fill no)
		(layer "In12.Cu")
	)
	(gr_circle
		(center 287.63595 -355.279198)
		(end 288.52495 -355.279198)
		(stroke
			(width 0.2)
			(type default)
		)
		(fill no)
		(layer "In12.Cu")
	)
	(gr_circle
		(center 287.64611 -356.584758)
		(end 288.53511 -356.584758)
		(stroke
			(width 0.2)
			(type default)
		)
		(fill no)
		(layer "In12.Cu")
	)
	(gr_circle
		(center 287.64611 -355.949758)
		(end 288.53511 -355.949758)
		(stroke
			(width 0.2)
			(type default)
		)
		(fill no)
		(layer "In12.Cu")
	)
	(gr_circle
		(center 288.27095 -355.279198)
		(end 289.15995 -355.279198)
		(stroke
			(width 0.2)
			(type default)
		)
		(fill no)
		(layer "In12.Cu")
	)
	(gr_circle
		(center 288.28111 -356.584758)
		(end 289.17011 -356.584758)
		(stroke
			(width 0.2)
			(type default)
		)
		(fill no)
		(layer "In12.Cu")
	)
	(gr_circle
		(center 288.28111 -355.949758)
		(end 289.17011 -355.949758)
		(stroke
			(width 0.2)
			(type default)
		)
		(fill no)
		(layer "In12.Cu")
	)
	(gr_circle
		(center 288.90595 -355.279198)
		(end 289.79495 -355.279198)
		(stroke
			(width 0.2)
			(type default)
		)
		(fill no)
		(layer "In12.Cu")
	)
	(gr_circle
		(center 288.91611 -356.584758)
		(end 289.80511 -356.584758)
		(stroke
			(width 0.2)
			(type default)
		)
		(fill no)
		(layer "In12.Cu")
	)
	(gr_circle
		(center 288.91611 -355.949758)
		(end 289.80511 -355.949758)
		(stroke
			(width 0.2)
			(type default)
		)
		(fill no)
		(layer "In12.Cu")
	)
	(gr_circle
		(center 292.699186 -348.704662)
		(end 293.579296 -348.704662)
		(stroke
			(width 0.2)
			(type default)
		)
		(fill no)
		(layer "In12.Cu")
	)
	(gr_circle
		(center 293.316406 -348.704662)
		(end 294.196516 -348.704662)
		(stroke
			(width 0.2)
			(type default)
		)
		(fill no)
		(layer "In12.Cu")
	)
	(gr_circle
		(center 293.933626 -348.704662)
		(end 294.813736 -348.704662)
		(stroke
			(width 0.2)
			(type default)
		)
		(fill no)
		(layer "In12.Cu")
	)
	(gr_circle
		(center 294.146986 -347.959172)
		(end 295.035986 -347.959172)
		(stroke
			(width 0.2)
			(type default)
		)
		(fill no)
		(layer "In12.Cu")
	)
	(gr_circle
		(center 294.146986 -347.222572)
		(end 295.035986 -347.222572)
		(stroke
			(width 0.2)
			(type default)
		)
		(fill no)
		(layer "In12.Cu")
	)
	(gr_circle
		(center 294.635682 -350.313752)
		(end 295.524682 -350.313752)
		(stroke
			(width 0.2)
			(type default)
		)
		(fill no)
		(layer "In12.Cu")
	)
	(gr_circle
		(center 294.635682 -349.577152)
		(end 295.524682 -349.577152)
		(stroke
			(width 0.2)
			(type default)
		)
		(fill no)
		(layer "In12.Cu")
	)
	(gr_circle
		(center 295.160446 -349.137732)
		(end 296.049446 -349.137732)
		(stroke
			(width 0.2)
			(type default)
		)
		(fill no)
		(layer "In12.Cu")
	)
	(gr_circle
		(center 295.185846 -349.899732)
		(end 296.074846 -349.899732)
		(stroke
			(width 0.2)
			(type default)
		)
		(fill no)
		(layer "In12.Cu")
	)
	(gr_circle
		(center 295.719246 -350.255332)
		(end 296.608246 -350.255332)
		(stroke
			(width 0.2)
			(type default)
		)
		(fill no)
		(layer "In12.Cu")
	)
	(gr_circle
		(center 295.719246 -349.518732)
		(end 296.608246 -349.518732)
		(stroke
			(width 0.2)
			(type default)
		)
		(fill no)
		(layer "In12.Cu")
	)
	(gr_circle
		(center 295.719246 -348.782132)
		(end 296.608246 -348.782132)
		(stroke
			(width 0.2)
			(type default)
		)
		(fill no)
		(layer "In12.Cu")
	)
	(gr_circle
		(center 296.29989 -358.769666)
		(end 297.69689 -358.769666)
		(stroke
			(width 0.2)
			(type default)
		)
		(fill no)
		(layer "In12.Cu")
	)
	(gr_circle
		(center 301.055786 -348.704662)
		(end 301.935896 -348.704662)
		(stroke
			(width 0.2)
			(type default)
		)
		(fill no)
		(layer "In12.Cu")
	)
	(gr_circle
		(center 301.673006 -348.704662)
		(end 302.553116 -348.704662)
		(stroke
			(width 0.2)
			(type default)
		)
		(fill no)
		(layer "In12.Cu")
	)
	(gr_circle
		(center 302.290226 -348.704662)
		(end 303.170336 -348.704662)
		(stroke
			(width 0.2)
			(type default)
		)
		(fill no)
		(layer "In12.Cu")
	)
	(gr_circle
		(center 302.526446 -348.002352)
		(end 303.415446 -348.002352)
		(stroke
			(width 0.2)
			(type default)
		)
		(fill no)
		(layer "In12.Cu")
	)
	(gr_circle
		(center 302.526446 -347.265752)
		(end 303.415446 -347.265752)
		(stroke
			(width 0.2)
			(type default)
		)
		(fill no)
		(layer "In12.Cu")
	)
	(gr_circle
		(center 302.992282 -350.313752)
		(end 303.881282 -350.313752)
		(stroke
			(width 0.2)
			(type default)
		)
		(fill no)
		(layer "In12.Cu")
	)
	(gr_circle
		(center 302.992282 -349.577152)
		(end 303.881282 -349.577152)
		(stroke
			(width 0.2)
			(type default)
		)
		(fill no)
		(layer "In12.Cu")
	)
	(gr_circle
		(center 303.517046 -349.137732)
		(end 304.406046 -349.137732)
		(stroke
			(width 0.2)
			(type default)
		)
		(fill no)
		(layer "In12.Cu")
	)
	(gr_circle
		(center 303.542446 -349.899732)
		(end 304.431446 -349.899732)
		(stroke
			(width 0.2)
			(type default)
		)
		(fill no)
		(layer "In12.Cu")
	)
	(gr_circle
		(center 304.075846 -350.255332)
		(end 304.964846 -350.255332)
		(stroke
			(width 0.2)
			(type default)
		)
		(fill no)
		(layer "In12.Cu")
	)
	(gr_circle
		(center 304.075846 -349.518732)
		(end 304.964846 -349.518732)
		(stroke
			(width 0.2)
			(type default)
		)
		(fill no)
		(layer "In12.Cu")
	)
	(gr_circle
		(center 304.075846 -348.782132)
		(end 304.964846 -348.782132)
		(stroke
			(width 0.2)
			(type default)
		)
		(fill no)
		(layer "In12.Cu")
	)
	(gr_circle
		(center 309.386986 -348.704662)
		(end 310.267096 -348.704662)
		(stroke
			(width 0.2)
			(type default)
		)
		(fill no)
		(layer "In12.Cu")
	)
	(gr_circle
		(center 310.004206 -348.704662)
		(end 310.884316 -348.704662)
		(stroke
			(width 0.2)
			(type default)
		)
		(fill no)
		(layer "In12.Cu")
	)
	(gr_circle
		(center 310.621426 -348.704662)
		(end 311.501536 -348.704662)
		(stroke
			(width 0.2)
			(type default)
		)
		(fill no)
		(layer "In12.Cu")
	)
	(gr_circle
		(center 310.867806 -348.002352)
		(end 311.756806 -348.002352)
		(stroke
			(width 0.2)
			(type default)
		)
		(fill no)
		(layer "In12.Cu")
	)
	(gr_circle
		(center 310.867806 -347.265752)
		(end 311.756806 -347.265752)
		(stroke
			(width 0.2)
			(type default)
		)
		(fill no)
		(layer "In12.Cu")
	)
	(gr_circle
		(center 311.323482 -350.313752)
		(end 312.212482 -350.313752)
		(stroke
			(width 0.2)
			(type default)
		)
		(fill no)
		(layer "In12.Cu")
	)
	(gr_circle
		(center 311.323482 -349.577152)
		(end 312.212482 -349.577152)
		(stroke
			(width 0.2)
			(type default)
		)
		(fill no)
		(layer "In12.Cu")
	)
	(gr_circle
		(center 311.848246 -349.137732)
		(end 312.737246 -349.137732)
		(stroke
			(width 0.2)
			(type default)
		)
		(fill no)
		(layer "In12.Cu")
	)
	(gr_circle
		(center 311.873646 -349.899732)
		(end 312.762646 -349.899732)
		(stroke
			(width 0.2)
			(type default)
		)
		(fill no)
		(layer "In12.Cu")
	)
	(gr_circle
		(center 312.407046 -350.255332)
		(end 313.296046 -350.255332)
		(stroke
			(width 0.2)
			(type default)
		)
		(fill no)
		(layer "In12.Cu")
	)
	(gr_circle
		(center 312.407046 -349.518732)
		(end 313.296046 -349.518732)
		(stroke
			(width 0.2)
			(type default)
		)
		(fill no)
		(layer "In12.Cu")
	)
	(gr_circle
		(center 312.407046 -348.782132)
		(end 313.296046 -348.782132)
		(stroke
			(width 0.2)
			(type default)
		)
		(fill no)
		(layer "In12.Cu")
	)
	(gr_circle
		(center 319.0367 -336.983578)
		(end 319.91681 -336.983578)
		(stroke
			(width 0.2)
			(type default)
		)
		(fill no)
		(layer "In12.Cu")
	)
	(gr_circle
		(center 319.65392 -336.983578)
		(end 320.53403 -336.983578)
		(stroke
			(width 0.2)
			(type default)
		)
		(fill no)
		(layer "In12.Cu")
	)
	(gr_circle
		(center 320.27114 -336.983578)
		(end 321.15125 -336.983578)
		(stroke
			(width 0.2)
			(type default)
		)
		(fill no)
		(layer "In12.Cu")
	)
	(gr_circle
		(center 320.5607 -336.239612)
		(end 321.4497 -336.239612)
		(stroke
			(width 0.2)
			(type default)
		)
		(fill no)
		(layer "In12.Cu")
	)
	(gr_circle
		(center 320.5607 -335.503012)
		(end 321.4497 -335.503012)
		(stroke
			(width 0.2)
			(type default)
		)
		(fill no)
		(layer "In12.Cu")
	)
	(gr_circle
		(center 320.973196 -338.592668)
		(end 321.862196 -338.592668)
		(stroke
			(width 0.2)
			(type default)
		)
		(fill no)
		(layer "In12.Cu")
	)
	(gr_circle
		(center 320.973196 -337.856068)
		(end 321.862196 -337.856068)
		(stroke
			(width 0.2)
			(type default)
		)
		(fill no)
		(layer "In12.Cu")
	)
	(gr_circle
		(center 321.49796 -337.416648)
		(end 322.38696 -337.416648)
		(stroke
			(width 0.2)
			(type default)
		)
		(fill no)
		(layer "In12.Cu")
	)
	(gr_circle
		(center 321.52336 -338.178648)
		(end 322.41236 -338.178648)
		(stroke
			(width 0.2)
			(type default)
		)
		(fill no)
		(layer "In12.Cu")
	)
	(gr_circle
		(center 322.05676 -338.534248)
		(end 322.94576 -338.534248)
		(stroke
			(width 0.2)
			(type default)
		)
		(fill no)
		(layer "In12.Cu")
	)
	(gr_circle
		(center 322.05676 -337.797648)
		(end 322.94576 -337.797648)
		(stroke
			(width 0.2)
			(type default)
		)
		(fill no)
		(layer "In12.Cu")
	)
	(gr_circle
		(center 322.05676 -337.061048)
		(end 322.94576 -337.061048)
		(stroke
			(width 0.2)
			(type default)
		)
		(fill no)
		(layer "In12.Cu")
	)
	(gr_circle
		(center 327.392284 -336.976466)
		(end 328.272394 -336.976466)
		(stroke
			(width 0.2)
			(type default)
		)
		(fill no)
		(layer "In12.Cu")
	)
	(gr_circle
		(center 327.692258 -104.30129)
		(end 328.581258 -104.30129)
		(stroke
			(width 0.2)
			(type default)
		)
		(fill no)
		(layer "In12.Cu")
	)
	(gr_circle
		(center 327.951084 -349.43161)
		(end 329.348084 -349.43161)
		(stroke
			(width 0.2)
			(type default)
		)
		(fill no)
		(layer "In12.Cu")
	)
	(gr_circle
		(center 328.009504 -336.976466)
		(end 328.889614 -336.976466)
		(stroke
			(width 0.2)
			(type default)
		)
		(fill no)
		(layer "In12.Cu")
	)
	(gr_circle
		(center 328.626724 -336.976466)
		(end 329.506834 -336.976466)
		(stroke
			(width 0.2)
			(type default)
		)
		(fill no)
		(layer "In12.Cu")
	)
	(gr_circle
		(center 328.918824 -336.253836)
		(end 329.807824 -336.253836)
		(stroke
			(width 0.2)
			(type default)
		)
		(fill no)
		(layer "In12.Cu")
	)
	(gr_circle
		(center 328.918824 -335.517236)
		(end 329.807824 -335.517236)
		(stroke
			(width 0.2)
			(type default)
		)
		(fill no)
		(layer "In12.Cu")
	)
	(gr_circle
		(center 329.32878 -338.585556)
		(end 330.21778 -338.585556)
		(stroke
			(width 0.2)
			(type default)
		)
		(fill no)
		(layer "In12.Cu")
	)
	(gr_circle
		(center 329.32878 -337.848956)
		(end 330.21778 -337.848956)
		(stroke
			(width 0.2)
			(type default)
		)
		(fill no)
		(layer "In12.Cu")
	)
	(gr_circle
		(center 329.853544 -337.409536)
		(end 330.742544 -337.409536)
		(stroke
			(width 0.2)
			(type default)
		)
		(fill no)
		(layer "In12.Cu")
	)
	(gr_circle
		(center 329.878944 -338.171536)
		(end 330.767944 -338.171536)
		(stroke
			(width 0.2)
			(type default)
		)
		(fill no)
		(layer "In12.Cu")
	)
	(gr_circle
		(center 330.412344 -338.527136)
		(end 331.301344 -338.527136)
		(stroke
			(width 0.2)
			(type default)
		)
		(fill no)
		(layer "In12.Cu")
	)
	(gr_circle
		(center 330.412344 -337.790536)
		(end 331.301344 -337.790536)
		(stroke
			(width 0.2)
			(type default)
		)
		(fill no)
		(layer "In12.Cu")
	)
	(gr_circle
		(center 330.412344 -337.053936)
		(end 331.301344 -337.053936)
		(stroke
			(width 0.2)
			(type default)
		)
		(fill no)
		(layer "In12.Cu")
	)
	(gr_circle
		(center 335.411064 -349.43161)
		(end 336.808064 -349.43161)
		(stroke
			(width 0.2)
			(type default)
		)
		(fill no)
		(layer "In12.Cu")
	)
	(gr_circle
		(center 335.7499 -336.961988)
		(end 336.63001 -336.961988)
		(stroke
			(width 0.2)
			(type default)
		)
		(fill no)
		(layer "In12.Cu")
	)
	(gr_circle
		(center 336.36712 -336.961988)
		(end 337.24723 -336.961988)
		(stroke
			(width 0.2)
			(type default)
		)
		(fill no)
		(layer "In12.Cu")
	)
	(gr_circle
		(center 336.98434 -336.961988)
		(end 337.86445 -336.961988)
		(stroke
			(width 0.2)
			(type default)
		)
		(fill no)
		(layer "In12.Cu")
	)
	(gr_circle
		(center 337.280504 -336.253836)
		(end 338.169504 -336.253836)
		(stroke
			(width 0.2)
			(type default)
		)
		(fill no)
		(layer "In12.Cu")
	)
	(gr_circle
		(center 337.280504 -335.517236)
		(end 338.169504 -335.517236)
		(stroke
			(width 0.2)
			(type default)
		)
		(fill no)
		(layer "In12.Cu")
	)
	(gr_circle
		(center 337.686396 -338.571078)
		(end 338.575396 -338.571078)
		(stroke
			(width 0.2)
			(type default)
		)
		(fill no)
		(layer "In12.Cu")
	)
	(gr_circle
		(center 337.686396 -337.834478)
		(end 338.575396 -337.834478)
		(stroke
			(width 0.2)
			(type default)
		)
		(fill no)
		(layer "In12.Cu")
	)
	(gr_circle
		(center 338.21116 -337.395058)
		(end 339.10016 -337.395058)
		(stroke
			(width 0.2)
			(type default)
		)
		(fill no)
		(layer "In12.Cu")
	)
	(gr_circle
		(center 338.23656 -338.157058)
		(end 339.12556 -338.157058)
		(stroke
			(width 0.2)
			(type default)
		)
		(fill no)
		(layer "In12.Cu")
	)
	(gr_circle
		(center 338.76996 -338.512658)
		(end 339.65896 -338.512658)
		(stroke
			(width 0.2)
			(type default)
		)
		(fill no)
		(layer "In12.Cu")
	)
	(gr_circle
		(center 338.76996 -337.776058)
		(end 339.65896 -337.776058)
		(stroke
			(width 0.2)
			(type default)
		)
		(fill no)
		(layer "In12.Cu")
	)
	(gr_circle
		(center 338.76996 -337.039458)
		(end 339.65896 -337.039458)
		(stroke
			(width 0.2)
			(type default)
		)
		(fill no)
		(layer "In12.Cu")
	)
	(gr_circle
		(center 339.73897 -352.973132)
		(end 340.62797 -352.973132)
		(stroke
			(width 0.2)
			(type default)
		)
		(fill no)
		(layer "In12.Cu")
	)
	(gr_circle
		(center 339.739224 -352.215196)
		(end 340.628224 -352.215196)
		(stroke
			(width 0.2)
			(type default)
		)
		(fill no)
		(layer "In12.Cu")
	)
	(gr_circle
		(center 339.739224 -351.453196)
		(end 340.628224 -351.453196)
		(stroke
			(width 0.2)
			(type default)
		)
		(fill no)
		(layer "In12.Cu")
	)
	(gr_circle
		(center 340.501224 -352.215196)
		(end 341.390224 -352.215196)
		(stroke
			(width 0.2)
			(type default)
		)
		(fill no)
		(layer "In12.Cu")
	)
	(gr_circle
		(center 340.501224 -351.453196)
		(end 341.390224 -351.453196)
		(stroke
			(width 0.2)
			(type default)
		)
		(fill no)
		(layer "In12.Cu")
	)
	(gr_circle
		(center 340.667848 -353.010216)
		(end 341.556848 -353.010216)
		(stroke
			(width 0.2)
			(type default)
		)
		(fill no)
		(layer "In12.Cu")
	)
	(gr_circle
		(center 341.263224 -352.215196)
		(end 342.152224 -352.215196)
		(stroke
			(width 0.2)
			(type default)
		)
		(fill no)
		(layer "In12.Cu")
	)
	(gr_circle
		(center 341.263224 -351.453196)
		(end 342.152224 -351.453196)
		(stroke
			(width 0.2)
			(type default)
		)
		(fill no)
		(layer "In12.Cu")
	)
	(gr_circle
		(center 341.302848 -353.010216)
		(end 342.191848 -353.010216)
		(stroke
			(width 0.2)
			(type default)
		)
		(fill no)
		(layer "In12.Cu")
	)
	(gr_circle
		(center 341.937848 -353.010216)
		(end 342.826848 -353.010216)
		(stroke
			(width 0.2)
			(type default)
		)
		(fill no)
		(layer "In12.Cu")
	)
	(gr_circle
		(center 342.025224 -352.215196)
		(end 342.914224 -352.215196)
		(stroke
			(width 0.2)
			(type default)
		)
		(fill no)
		(layer "In12.Cu")
	)
	(gr_circle
		(center 342.025224 -351.453196)
		(end 342.914224 -351.453196)
		(stroke
			(width 0.2)
			(type default)
		)
		(fill no)
		(layer "In12.Cu")
	)
	(gr_circle
		(center 342.572848 -353.010216)
		(end 343.461848 -353.010216)
		(stroke
			(width 0.2)
			(type default)
		)
		(fill no)
		(layer "In12.Cu")
	)
	(gr_circle
		(center 342.787224 -352.215196)
		(end 343.676224 -352.215196)
		(stroke
			(width 0.2)
			(type default)
		)
		(fill no)
		(layer "In12.Cu")
	)
	(gr_circle
		(center 342.787224 -351.453196)
		(end 343.676224 -351.453196)
		(stroke
			(width 0.2)
			(type default)
		)
		(fill no)
		(layer "In12.Cu")
	)
	(gr_circle
		(center 343.46515 -353.006152)
		(end 344.35415 -353.006152)
		(stroke
			(width 0.2)
			(type default)
		)
		(fill no)
		(layer "In12.Cu")
	)
	(gr_circle
		(center 343.465404 -352.248216)
		(end 344.354404 -352.248216)
		(stroke
			(width 0.2)
			(type default)
		)
		(fill no)
		(layer "In12.Cu")
	)
	(gr_circle
		(center 343.465404 -351.486216)
		(end 344.354404 -351.486216)
		(stroke
			(width 0.2)
			(type default)
		)
		(fill no)
		(layer "In12.Cu")
	)
	(gr_circle
		(center 344.016838 -159.073596)
		(end 344.905838 -159.073596)
		(stroke
			(width 0.2)
			(type default)
		)
		(fill no)
		(layer "In12.Cu")
	)
	(gr_circle
		(center 344.016838 -158.336996)
		(end 344.905838 -158.336996)
		(stroke
			(width 0.2)
			(type default)
		)
		(fill no)
		(layer "In12.Cu")
	)
	(gr_circle
		(center 344.016838 -157.600396)
		(end 344.905838 -157.600396)
		(stroke
			(width 0.2)
			(type default)
		)
		(fill no)
		(layer "In12.Cu")
	)
	(gr_circle
		(center 344.0811 -337.012788)
		(end 344.96121 -337.012788)
		(stroke
			(width 0.2)
			(type default)
		)
		(fill no)
		(layer "In12.Cu")
	)
	(gr_circle
		(center 344.550238 -157.955996)
		(end 345.439238 -157.955996)
		(stroke
			(width 0.2)
			(type default)
		)
		(fill no)
		(layer "In12.Cu")
	)
	(gr_circle
		(center 344.575638 -158.717996)
		(end 345.464638 -158.717996)
		(stroke
			(width 0.2)
			(type default)
		)
		(fill no)
		(layer "In12.Cu")
	)
	(gr_circle
		(center 344.69832 -337.012788)
		(end 345.57843 -337.012788)
		(stroke
			(width 0.2)
			(type default)
		)
		(fill no)
		(layer "In12.Cu")
	)
	(gr_circle
		(center 345.100402 -158.278576)
		(end 345.989402 -158.278576)
		(stroke
			(width 0.2)
			(type default)
		)
		(fill no)
		(layer "In12.Cu")
	)
	(gr_circle
		(center 345.100402 -157.541976)
		(end 345.989402 -157.541976)
		(stroke
			(width 0.2)
			(type default)
		)
		(fill no)
		(layer "In12.Cu")
	)
	(gr_circle
		(center 345.31554 -337.012788)
		(end 346.19565 -337.012788)
		(stroke
			(width 0.2)
			(type default)
		)
		(fill no)
		(layer "In12.Cu")
	)
	(gr_circle
		(center 345.623896 -336.317336)
		(end 346.512896 -336.317336)
		(stroke
			(width 0.2)
			(type default)
		)
		(fill no)
		(layer "In12.Cu")
	)
	(gr_circle
		(center 345.623896 -335.580736)
		(end 346.512896 -335.580736)
		(stroke
			(width 0.2)
			(type default)
		)
		(fill no)
		(layer "In12.Cu")
	)
	(gr_circle
		(center 345.684856 -160.633156)
		(end 346.573856 -160.633156)
		(stroke
			(width 0.2)
			(type default)
		)
		(fill no)
		(layer "In12.Cu")
	)
	(gr_circle
		(center 345.684856 -159.896556)
		(end 346.573856 -159.896556)
		(stroke
			(width 0.2)
			(type default)
		)
		(fill no)
		(layer "In12.Cu")
	)
	(gr_circle
		(center 345.802458 -159.151066)
		(end 346.682568 -159.151066)
		(stroke
			(width 0.2)
			(type default)
		)
		(fill no)
		(layer "In12.Cu")
	)
	(gr_circle
		(center 345.921076 -273.27606)
		(end 346.175076 -273.27606)
		(stroke
			(width 0.1016)
			(type default)
		)
		(fill no)
		(layer "In12.Cu")
	)
	(gr_circle
		(center 345.921076 -271.656048)
		(end 346.175076 -271.656048)
		(stroke
			(width 0.1016)
			(type default)
		)
		(fill no)
		(layer "In12.Cu")
	)
	(gr_circle
		(center 345.921076 -270.036036)
		(end 346.175076 -270.036036)
		(stroke
			(width 0.1016)
			(type default)
		)
		(fill no)
		(layer "In12.Cu")
	)
	(gr_circle
		(center 346.017596 -339.358478)
		(end 346.906596 -339.358478)
		(stroke
			(width 0.2)
			(type default)
		)
		(fill no)
		(layer "In12.Cu")
	)
	(gr_circle
		(center 346.017596 -338.621878)
		(end 346.906596 -338.621878)
		(stroke
			(width 0.2)
			(type default)
		)
		(fill no)
		(layer "In12.Cu")
	)
	(gr_circle
		(center 346.017596 -337.885278)
		(end 346.906596 -337.885278)
		(stroke
			(width 0.2)
			(type default)
		)
		(fill no)
		(layer "In12.Cu")
	)
	(gr_circle
		(center 346.419678 -159.151066)
		(end 347.299788 -159.151066)
		(stroke
			(width 0.2)
			(type default)
		)
		(fill no)
		(layer "In12.Cu")
	)
	(gr_circle
		(center 346.54236 -337.445858)
		(end 347.43136 -337.445858)
		(stroke
			(width 0.2)
			(type default)
		)
		(fill no)
		(layer "In12.Cu")
	)
	(gr_circle
		(center 346.56776 -339.731858)
		(end 347.45676 -339.731858)
		(stroke
			(width 0.2)
			(type default)
		)
		(fill no)
		(layer "In12.Cu")
	)
	(gr_circle
		(center 346.56776 -338.969858)
		(end 347.45676 -338.969858)
		(stroke
			(width 0.2)
			(type default)
		)
		(fill no)
		(layer "In12.Cu")
	)
	(gr_circle
		(center 346.56776 -338.207858)
		(end 347.45676 -338.207858)
		(stroke
			(width 0.2)
			(type default)
		)
		(fill no)
		(layer "In12.Cu")
	)
	(gr_circle
		(center 346.86113 -273.27606)
		(end 347.11513 -273.27606)
		(stroke
			(width 0.1016)
			(type default)
		)
		(fill no)
		(layer "In12.Cu")
	)
	(gr_circle
		(center 346.86113 -271.656048)
		(end 347.11513 -271.656048)
		(stroke
			(width 0.1016)
			(type default)
		)
		(fill no)
		(layer "In12.Cu")
	)
	(gr_circle
		(center 346.86113 -270.036036)
		(end 347.11513 -270.036036)
		(stroke
			(width 0.1016)
			(type default)
		)
		(fill no)
		(layer "In12.Cu")
	)
	(gr_circle
		(center 347.036898 -159.151066)
		(end 347.917008 -159.151066)
		(stroke
			(width 0.2)
			(type default)
		)
		(fill no)
		(layer "In12.Cu")
	)
	(gr_circle
		(center 348.740984 -273.27606)
		(end 348.994984 -273.27606)
		(stroke
			(width 0.1016)
			(type default)
		)
		(fill no)
		(layer "In12.Cu")
	)
	(gr_circle
		(center 348.740984 -271.656048)
		(end 348.994984 -271.656048)
		(stroke
			(width 0.1016)
			(type default)
		)
		(fill no)
		(layer "In12.Cu")
	)
	(gr_circle
		(center 348.740984 -270.036036)
		(end 348.994984 -270.036036)
		(stroke
			(width 0.1016)
			(type default)
		)
		(fill no)
		(layer "In12.Cu")
	)
	(gr_circle
		(center 349.681038 -273.27606)
		(end 349.935038 -273.27606)
		(stroke
			(width 0.1016)
			(type default)
		)
		(fill no)
		(layer "In12.Cu")
	)
	(gr_circle
		(center 349.681038 -271.656048)
		(end 349.935038 -271.656048)
		(stroke
			(width 0.1016)
			(type default)
		)
		(fill no)
		(layer "In12.Cu")
	)
	(gr_circle
		(center 349.681038 -270.036036)
		(end 349.935038 -270.036036)
		(stroke
			(width 0.1016)
			(type default)
		)
		(fill no)
		(layer "In12.Cu")
	)
	(gr_circle
		(center 351.561146 -273.27606)
		(end 351.815146 -273.27606)
		(stroke
			(width 0.1016)
			(type default)
		)
		(fill no)
		(layer "In12.Cu")
	)
	(gr_circle
		(center 351.561146 -271.656048)
		(end 351.815146 -271.656048)
		(stroke
			(width 0.1016)
			(type default)
		)
		(fill no)
		(layer "In12.Cu")
	)
	(gr_circle
		(center 351.561146 -270.036036)
		(end 351.815146 -270.036036)
		(stroke
			(width 0.1016)
			(type default)
		)
		(fill no)
		(layer "In12.Cu")
	)
	(gr_circle
		(center 352.322638 -167.430196)
		(end 353.211638 -167.430196)
		(stroke
			(width 0.2)
			(type default)
		)
		(fill no)
		(layer "In12.Cu")
	)
	(gr_circle
		(center 352.322638 -166.693596)
		(end 353.211638 -166.693596)
		(stroke
			(width 0.2)
			(type default)
		)
		(fill no)
		(layer "In12.Cu")
	)
	(gr_circle
		(center 352.322638 -165.956996)
		(end 353.211638 -165.956996)
		(stroke
			(width 0.2)
			(type default)
		)
		(fill no)
		(layer "In12.Cu")
	)
	(gr_circle
		(center 352.356928 -341.922862)
		(end 353.237038 -341.922862)
		(stroke
			(width 0.2)
			(type default)
		)
		(fill no)
		(layer "In12.Cu")
	)
	(gr_circle
		(center 352.5012 -273.27606)
		(end 352.7552 -273.27606)
		(stroke
			(width 0.1016)
			(type default)
		)
		(fill no)
		(layer "In12.Cu")
	)
	(gr_circle
		(center 352.5012 -271.656048)
		(end 352.7552 -271.656048)
		(stroke
			(width 0.1016)
			(type default)
		)
		(fill no)
		(layer "In12.Cu")
	)
	(gr_circle
		(center 352.5012 -270.036036)
		(end 352.7552 -270.036036)
		(stroke
			(width 0.1016)
			(type default)
		)
		(fill no)
		(layer "In12.Cu")
	)
	(gr_circle
		(center 352.856038 -166.312596)
		(end 353.745038 -166.312596)
		(stroke
			(width 0.2)
			(type default)
		)
		(fill no)
		(layer "In12.Cu")
	)
	(gr_circle
		(center 352.881438 -167.074596)
		(end 353.770438 -167.074596)
		(stroke
			(width 0.2)
			(type default)
		)
		(fill no)
		(layer "In12.Cu")
	)
	(gr_circle
		(center 352.974148 -341.922862)
		(end 353.854258 -341.922862)
		(stroke
			(width 0.2)
			(type default)
		)
		(fill no)
		(layer "In12.Cu")
	)
	(gr_circle
		(center 353.406202 -166.635176)
		(end 354.295202 -166.635176)
		(stroke
			(width 0.2)
			(type default)
		)
		(fill no)
		(layer "In12.Cu")
	)
	(gr_circle
		(center 353.406202 -165.898576)
		(end 354.295202 -165.898576)
		(stroke
			(width 0.2)
			(type default)
		)
		(fill no)
		(layer "In12.Cu")
	)
	(gr_circle
		(center 353.591368 -341.922862)
		(end 354.471478 -341.922862)
		(stroke
			(width 0.2)
			(type default)
		)
		(fill no)
		(layer "In12.Cu")
	)
	(gr_circle
		(center 353.899724 -341.22741)
		(end 354.788724 -341.22741)
		(stroke
			(width 0.2)
			(type default)
		)
		(fill no)
		(layer "In12.Cu")
	)
	(gr_circle
		(center 353.899724 -340.49081)
		(end 354.788724 -340.49081)
		(stroke
			(width 0.2)
			(type default)
		)
		(fill no)
		(layer "In12.Cu")
	)
	(gr_circle
		(center 353.990656 -168.982136)
		(end 354.879656 -168.982136)
		(stroke
			(width 0.2)
			(type default)
		)
		(fill no)
		(layer "In12.Cu")
	)
	(gr_circle
		(center 353.990656 -168.245536)
		(end 354.879656 -168.245536)
		(stroke
			(width 0.2)
			(type default)
		)
		(fill no)
		(layer "In12.Cu")
	)
	(gr_circle
		(center 354.108258 -167.507666)
		(end 354.988368 -167.507666)
		(stroke
			(width 0.2)
			(type default)
		)
		(fill no)
		(layer "In12.Cu")
	)
	(gr_circle
		(center 354.293424 -343.531952)
		(end 355.182424 -343.531952)
		(stroke
			(width 0.2)
			(type default)
		)
		(fill no)
		(layer "In12.Cu")
	)
	(gr_circle
		(center 354.293424 -342.795352)
		(end 355.182424 -342.795352)
		(stroke
			(width 0.2)
			(type default)
		)
		(fill no)
		(layer "In12.Cu")
	)
	(gr_circle
		(center 354.381054 -273.27606)
		(end 354.635054 -273.27606)
		(stroke
			(width 0.1016)
			(type default)
		)
		(fill no)
		(layer "In12.Cu")
	)
	(gr_circle
		(center 354.381054 -271.656048)
		(end 354.635054 -271.656048)
		(stroke
			(width 0.1016)
			(type default)
		)
		(fill no)
		(layer "In12.Cu")
	)
	(gr_circle
		(center 354.381054 -270.036036)
		(end 354.635054 -270.036036)
		(stroke
			(width 0.1016)
			(type default)
		)
		(fill no)
		(layer "In12.Cu")
	)
	(gr_circle
		(center 354.725478 -167.507666)
		(end 355.605588 -167.507666)
		(stroke
			(width 0.2)
			(type default)
		)
		(fill no)
		(layer "In12.Cu")
	)
	(gr_circle
		(center 354.818188 -342.355932)
		(end 355.707188 -342.355932)
		(stroke
			(width 0.2)
			(type default)
		)
		(fill no)
		(layer "In12.Cu")
	)
	(gr_circle
		(center 354.843588 -343.117932)
		(end 355.732588 -343.117932)
		(stroke
			(width 0.2)
			(type default)
		)
		(fill no)
		(layer "In12.Cu")
	)
	(gr_circle
		(center 355.321108 -273.27606)
		(end 355.575108 -273.27606)
		(stroke
			(width 0.1016)
			(type default)
		)
		(fill no)
		(layer "In12.Cu")
	)
	(gr_circle
		(center 355.321108 -271.656048)
		(end 355.575108 -271.656048)
		(stroke
			(width 0.1016)
			(type default)
		)
		(fill no)
		(layer "In12.Cu")
	)
	(gr_circle
		(center 355.321108 -270.036036)
		(end 355.575108 -270.036036)
		(stroke
			(width 0.1016)
			(type default)
		)
		(fill no)
		(layer "In12.Cu")
	)
	(gr_circle
		(center 355.342698 -167.507666)
		(end 356.222808 -167.507666)
		(stroke
			(width 0.2)
			(type default)
		)
		(fill no)
		(layer "In12.Cu")
	)
	(gr_circle
		(center 355.376988 -343.473532)
		(end 356.265988 -343.473532)
		(stroke
			(width 0.2)
			(type default)
		)
		(fill no)
		(layer "In12.Cu")
	)
	(gr_circle
		(center 355.376988 -342.736932)
		(end 356.265988 -342.736932)
		(stroke
			(width 0.2)
			(type default)
		)
		(fill no)
		(layer "In12.Cu")
	)
	(gr_circle
		(center 355.376988 -342.000332)
		(end 356.265988 -342.000332)
		(stroke
			(width 0.2)
			(type default)
		)
		(fill no)
		(layer "In12.Cu")
	)
	(gr_circle
		(center 356.731062 -274.086066)
		(end 356.985062 -274.086066)
		(stroke
			(width 0.1016)
			(type default)
		)
		(fill no)
		(layer "In12.Cu")
	)
	(gr_circle
		(center 356.731062 -272.466054)
		(end 356.985062 -272.466054)
		(stroke
			(width 0.1016)
			(type default)
		)
		(fill no)
		(layer "In12.Cu")
	)
	(gr_circle
		(center 356.731062 -270.846042)
		(end 356.985062 -270.846042)
		(stroke
			(width 0.1016)
			(type default)
		)
		(fill no)
		(layer "In12.Cu")
	)
	(gr_circle
		(center 356.731062 -269.22603)
		(end 356.985062 -269.22603)
		(stroke
			(width 0.1016)
			(type default)
		)
		(fill no)
		(layer "In12.Cu")
	)
	(gr_circle
		(center 357.671116 -274.086066)
		(end 357.925116 -274.086066)
		(stroke
			(width 0.1016)
			(type default)
		)
		(fill no)
		(layer "In12.Cu")
	)
	(gr_circle
		(center 357.671116 -272.466054)
		(end 357.925116 -272.466054)
		(stroke
			(width 0.1016)
			(type default)
		)
		(fill no)
		(layer "In12.Cu")
	)
	(gr_circle
		(center 357.671116 -270.846042)
		(end 357.925116 -270.846042)
		(stroke
			(width 0.1016)
			(type default)
		)
		(fill no)
		(layer "In12.Cu")
	)
	(gr_circle
		(center 357.671116 -269.22603)
		(end 357.925116 -269.22603)
		(stroke
			(width 0.1016)
			(type default)
		)
		(fill no)
		(layer "In12.Cu")
	)
	(gr_circle
		(center 359.58526 -152.71242)
		(end 360.98226 -152.71242)
		(stroke
			(width 0.2)
			(type default)
		)
		(fill no)
		(layer "In12.Cu")
	)
	(gr_circle
		(center 360.603038 -175.705516)
		(end 361.492038 -175.705516)
		(stroke
			(width 0.2)
			(type default)
		)
		(fill no)
		(layer "In12.Cu")
	)
	(gr_circle
		(center 360.603038 -174.968916)
		(end 361.492038 -174.968916)
		(stroke
			(width 0.2)
			(type default)
		)
		(fill no)
		(layer "In12.Cu")
	)
	(gr_circle
		(center 360.603038 -174.232316)
		(end 361.492038 -174.232316)
		(stroke
			(width 0.2)
			(type default)
		)
		(fill no)
		(layer "In12.Cu")
	)
	(gr_circle
		(center 361.136438 -174.587916)
		(end 362.025438 -174.587916)
		(stroke
			(width 0.2)
			(type default)
		)
		(fill no)
		(layer "In12.Cu")
	)
	(gr_circle
		(center 361.161838 -175.349916)
		(end 362.050838 -175.349916)
		(stroke
			(width 0.2)
			(type default)
		)
		(fill no)
		(layer "In12.Cu")
	)
	(gr_circle
		(center 361.686602 -174.910496)
		(end 362.575602 -174.910496)
		(stroke
			(width 0.2)
			(type default)
		)
		(fill no)
		(layer "In12.Cu")
	)
	(gr_circle
		(center 361.686602 -174.173896)
		(end 362.575602 -174.173896)
		(stroke
			(width 0.2)
			(type default)
		)
		(fill no)
		(layer "In12.Cu")
	)
	(gr_circle
		(center 362.271056 -177.254916)
		(end 363.160056 -177.254916)
		(stroke
			(width 0.2)
			(type default)
		)
		(fill no)
		(layer "In12.Cu")
	)
	(gr_circle
		(center 362.271056 -176.518316)
		(end 363.160056 -176.518316)
		(stroke
			(width 0.2)
			(type default)
		)
		(fill no)
		(layer "In12.Cu")
	)
	(gr_circle
		(center 362.364782 -274.086066)
		(end 362.618782 -274.086066)
		(stroke
			(width 0.1016)
			(type default)
		)
		(fill no)
		(layer "In12.Cu")
	)
	(gr_circle
		(center 362.364782 -272.466054)
		(end 362.618782 -272.466054)
		(stroke
			(width 0.1016)
			(type default)
		)
		(fill no)
		(layer "In12.Cu")
	)
	(gr_circle
		(center 362.364782 -270.846042)
		(end 362.618782 -270.846042)
		(stroke
			(width 0.1016)
			(type default)
		)
		(fill no)
		(layer "In12.Cu")
	)
	(gr_circle
		(center 362.364782 -269.22603)
		(end 362.618782 -269.22603)
		(stroke
			(width 0.1016)
			(type default)
		)
		(fill no)
		(layer "In12.Cu")
	)
	(gr_circle
		(center 362.396278 -175.859186)
		(end 363.276388 -175.859186)
		(stroke
			(width 0.2)
			(type default)
		)
		(fill no)
		(layer "In12.Cu")
	)
	(gr_circle
		(center 363.013498 -175.859186)
		(end 363.893608 -175.859186)
		(stroke
			(width 0.2)
			(type default)
		)
		(fill no)
		(layer "In12.Cu")
	)
	(gr_circle
		(center 363.304836 -274.086066)
		(end 363.558836 -274.086066)
		(stroke
			(width 0.1016)
			(type default)
		)
		(fill no)
		(layer "In12.Cu")
	)
	(gr_circle
		(center 363.304836 -272.466054)
		(end 363.558836 -272.466054)
		(stroke
			(width 0.1016)
			(type default)
		)
		(fill no)
		(layer "In12.Cu")
	)
	(gr_circle
		(center 363.304836 -270.846042)
		(end 363.558836 -270.846042)
		(stroke
			(width 0.1016)
			(type default)
		)
		(fill no)
		(layer "In12.Cu")
	)
	(gr_circle
		(center 363.304836 -269.22603)
		(end 363.558836 -269.22603)
		(stroke
			(width 0.1016)
			(type default)
		)
		(fill no)
		(layer "In12.Cu")
	)
	(gr_circle
		(center 363.630718 -175.859186)
		(end 364.510828 -175.859186)
		(stroke
			(width 0.2)
			(type default)
		)
		(fill no)
		(layer "In12.Cu")
	)
	(gr_circle
		(center 364.71479 -273.27606)
		(end 364.96879 -273.27606)
		(stroke
			(width 0.1016)
			(type default)
		)
		(fill no)
		(layer "In12.Cu")
	)
	(gr_circle
		(center 364.71479 -271.656048)
		(end 364.96879 -271.656048)
		(stroke
			(width 0.1016)
			(type default)
		)
		(fill no)
		(layer "In12.Cu")
	)
	(gr_circle
		(center 364.71479 -270.036036)
		(end 364.96879 -270.036036)
		(stroke
			(width 0.1016)
			(type default)
		)
		(fill no)
		(layer "In12.Cu")
	)
	(gr_circle
		(center 365.654844 -273.27606)
		(end 365.908844 -273.27606)
		(stroke
			(width 0.1016)
			(type default)
		)
		(fill no)
		(layer "In12.Cu")
	)
	(gr_circle
		(center 365.654844 -271.656048)
		(end 365.908844 -271.656048)
		(stroke
			(width 0.1016)
			(type default)
		)
		(fill no)
		(layer "In12.Cu")
	)
	(gr_circle
		(center 365.654844 -270.036036)
		(end 365.908844 -270.036036)
		(stroke
			(width 0.1016)
			(type default)
		)
		(fill no)
		(layer "In12.Cu")
	)
	(gr_circle
		(center 366.744504 -164.53358)
		(end 367.633504 -164.53358)
		(stroke
			(width 0.2)
			(type default)
		)
		(fill no)
		(layer "In12.Cu")
	)
	(gr_circle
		(center 366.744504 -163.89858)
		(end 367.633504 -163.89858)
		(stroke
			(width 0.2)
			(type default)
		)
		(fill no)
		(layer "In12.Cu")
	)
	(gr_circle
		(center 366.757204 -165.19398)
		(end 367.646204 -165.19398)
		(stroke
			(width 0.2)
			(type default)
		)
		(fill no)
		(layer "In12.Cu")
	)
	(gr_circle
		(center 367.379504 -164.53358)
		(end 368.268504 -164.53358)
		(stroke
			(width 0.2)
			(type default)
		)
		(fill no)
		(layer "In12.Cu")
	)
	(gr_circle
		(center 367.379504 -163.89858)
		(end 368.268504 -163.89858)
		(stroke
			(width 0.2)
			(type default)
		)
		(fill no)
		(layer "In12.Cu")
	)
	(gr_circle
		(center 367.392204 -165.19398)
		(end 368.281204 -165.19398)
		(stroke
			(width 0.2)
			(type default)
		)
		(fill no)
		(layer "In12.Cu")
	)
	(gr_circle
		(center 367.534698 -273.27606)
		(end 367.788698 -273.27606)
		(stroke
			(width 0.1016)
			(type default)
		)
		(fill no)
		(layer "In12.Cu")
	)
	(gr_circle
		(center 367.534698 -271.656048)
		(end 367.788698 -271.656048)
		(stroke
			(width 0.1016)
			(type default)
		)
		(fill no)
		(layer "In12.Cu")
	)
	(gr_circle
		(center 367.534698 -270.036036)
		(end 367.788698 -270.036036)
		(stroke
			(width 0.1016)
			(type default)
		)
		(fill no)
		(layer "In12.Cu")
	)
	(gr_circle
		(center 368.044984 -164.53358)
		(end 368.933984 -164.53358)
		(stroke
			(width 0.2)
			(type default)
		)
		(fill no)
		(layer "In12.Cu")
	)
	(gr_circle
		(center 368.044984 -163.89858)
		(end 368.933984 -163.89858)
		(stroke
			(width 0.2)
			(type default)
		)
		(fill no)
		(layer "In12.Cu")
	)
	(gr_circle
		(center 368.057684 -165.19398)
		(end 368.946684 -165.19398)
		(stroke
			(width 0.2)
			(type default)
		)
		(fill no)
		(layer "In12.Cu")
	)
	(gr_circle
		(center 368.474752 -273.27606)
		(end 368.728752 -273.27606)
		(stroke
			(width 0.1016)
			(type default)
		)
		(fill no)
		(layer "In12.Cu")
	)
	(gr_circle
		(center 368.474752 -271.656048)
		(end 368.728752 -271.656048)
		(stroke
			(width 0.1016)
			(type default)
		)
		(fill no)
		(layer "In12.Cu")
	)
	(gr_circle
		(center 368.474752 -270.036036)
		(end 368.728752 -270.036036)
		(stroke
			(width 0.1016)
			(type default)
		)
		(fill no)
		(layer "In12.Cu")
	)
	(gr_circle
		(center 368.679984 -164.53358)
		(end 369.568984 -164.53358)
		(stroke
			(width 0.2)
			(type default)
		)
		(fill no)
		(layer "In12.Cu")
	)
	(gr_circle
		(center 368.679984 -163.89858)
		(end 369.568984 -163.89858)
		(stroke
			(width 0.2)
			(type default)
		)
		(fill no)
		(layer "In12.Cu")
	)
	(gr_circle
		(center 368.692684 -165.19398)
		(end 369.581684 -165.19398)
		(stroke
			(width 0.2)
			(type default)
		)
		(fill no)
		(layer "In12.Cu")
	)
	(gr_circle
		(center 368.96421 -179.204874)
		(end 369.85321 -179.204874)
		(stroke
			(width 0.2)
			(type default)
		)
		(fill no)
		(layer "In12.Cu")
	)
	(gr_circle
		(center 369.314984 -164.53358)
		(end 370.203984 -164.53358)
		(stroke
			(width 0.2)
			(type default)
		)
		(fill no)
		(layer "In12.Cu")
	)
	(gr_circle
		(center 369.314984 -163.89858)
		(end 370.203984 -163.89858)
		(stroke
			(width 0.2)
			(type default)
		)
		(fill no)
		(layer "In12.Cu")
	)
	(gr_circle
		(center 369.327684 -165.19398)
		(end 370.216684 -165.19398)
		(stroke
			(width 0.2)
			(type default)
		)
		(fill no)
		(layer "In12.Cu")
	)
	(gr_circle
		(center 369.49761 -179.560474)
		(end 370.38661 -179.560474)
		(stroke
			(width 0.2)
			(type default)
		)
		(fill no)
		(layer "In12.Cu")
	)
	(gr_circle
		(center 369.49761 -178.798474)
		(end 370.38661 -178.798474)
		(stroke
			(width 0.2)
			(type default)
		)
		(fill no)
		(layer "In12.Cu")
	)
	(gr_circle
		(center 369.49761 -178.036474)
		(end 370.38661 -178.036474)
		(stroke
			(width 0.2)
			(type default)
		)
		(fill no)
		(layer "In12.Cu")
	)
	(gr_circle
		(center 369.52301 -180.322474)
		(end 370.41201 -180.322474)
		(stroke
			(width 0.2)
			(type default)
		)
		(fill no)
		(layer "In12.Cu")
	)
	(gr_circle
		(center 369.949984 -164.53358)
		(end 370.838984 -164.53358)
		(stroke
			(width 0.2)
			(type default)
		)
		(fill no)
		(layer "In12.Cu")
	)
	(gr_circle
		(center 369.949984 -163.89858)
		(end 370.838984 -163.89858)
		(stroke
			(width 0.2)
			(type default)
		)
		(fill no)
		(layer "In12.Cu")
	)
	(gr_circle
		(center 369.962684 -165.19398)
		(end 370.851684 -165.19398)
		(stroke
			(width 0.2)
			(type default)
		)
		(fill no)
		(layer "In12.Cu")
	)
	(gr_circle
		(center 370.047774 -179.883054)
		(end 370.936774 -179.883054)
		(stroke
			(width 0.2)
			(type default)
		)
		(fill no)
		(layer "In12.Cu")
	)
	(gr_circle
		(center 370.047774 -179.146454)
		(end 370.936774 -179.146454)
		(stroke
			(width 0.2)
			(type default)
		)
		(fill no)
		(layer "In12.Cu")
	)
	(gr_circle
		(center 370.35486 -273.27606)
		(end 370.60886 -273.27606)
		(stroke
			(width 0.1016)
			(type default)
		)
		(fill no)
		(layer "In12.Cu")
	)
	(gr_circle
		(center 370.35486 -271.656048)
		(end 370.60886 -271.656048)
		(stroke
			(width 0.1016)
			(type default)
		)
		(fill no)
		(layer "In12.Cu")
	)
	(gr_circle
		(center 370.35486 -270.036036)
		(end 370.60886 -270.036036)
		(stroke
			(width 0.1016)
			(type default)
		)
		(fill no)
		(layer "In12.Cu")
	)
	(gr_circle
		(center 370.529358 -182.141876)
		(end 371.418358 -182.141876)
		(stroke
			(width 0.2)
			(type default)
		)
		(fill no)
		(layer "In12.Cu")
	)
	(gr_circle
		(center 370.529358 -181.405276)
		(end 371.418358 -181.405276)
		(stroke
			(width 0.2)
			(type default)
		)
		(fill no)
		(layer "In12.Cu")
	)
	(gr_circle
		(center 370.686584 -164.53358)
		(end 371.575584 -164.53358)
		(stroke
			(width 0.2)
			(type default)
		)
		(fill no)
		(layer "In12.Cu")
	)
	(gr_circle
		(center 370.686584 -163.89858)
		(end 371.575584 -163.89858)
		(stroke
			(width 0.2)
			(type default)
		)
		(fill no)
		(layer "In12.Cu")
	)
	(gr_circle
		(center 370.699284 -165.19398)
		(end 371.588284 -165.19398)
		(stroke
			(width 0.2)
			(type default)
		)
		(fill no)
		(layer "In12.Cu")
	)
	(gr_circle
		(center 370.74221 -180.803804)
		(end 371.62232 -180.803804)
		(stroke
			(width 0.2)
			(type default)
		)
		(fill no)
		(layer "In12.Cu")
	)
	(gr_circle
		(center 371.294914 -273.27606)
		(end 371.548914 -273.27606)
		(stroke
			(width 0.1016)
			(type default)
		)
		(fill no)
		(layer "In12.Cu")
	)
	(gr_circle
		(center 371.294914 -271.656048)
		(end 371.548914 -271.656048)
		(stroke
			(width 0.1016)
			(type default)
		)
		(fill no)
		(layer "In12.Cu")
	)
	(gr_circle
		(center 371.294914 -270.036036)
		(end 371.548914 -270.036036)
		(stroke
			(width 0.1016)
			(type default)
		)
		(fill no)
		(layer "In12.Cu")
	)
	(gr_circle
		(center 371.35943 -180.803804)
		(end 372.23954 -180.803804)
		(stroke
			(width 0.2)
			(type default)
		)
		(fill no)
		(layer "In12.Cu")
	)
	(gr_circle
		(center 371.97665 -180.803804)
		(end 372.85676 -180.803804)
		(stroke
			(width 0.2)
			(type default)
		)
		(fill no)
		(layer "In12.Cu")
	)
	(gr_circle
		(center 373.174768 -273.27606)
		(end 373.428768 -273.27606)
		(stroke
			(width 0.1016)
			(type default)
		)
		(fill no)
		(layer "In12.Cu")
	)
	(gr_circle
		(center 373.174768 -271.656048)
		(end 373.428768 -271.656048)
		(stroke
			(width 0.1016)
			(type default)
		)
		(fill no)
		(layer "In12.Cu")
	)
	(gr_circle
		(center 373.174768 -270.036036)
		(end 373.428768 -270.036036)
		(stroke
			(width 0.1016)
			(type default)
		)
		(fill no)
		(layer "In12.Cu")
	)
	(gr_circle
		(center 374.114822 -273.27606)
		(end 374.368822 -273.27606)
		(stroke
			(width 0.1016)
			(type default)
		)
		(fill no)
		(layer "In12.Cu")
	)
	(gr_circle
		(center 374.114822 -271.656048)
		(end 374.368822 -271.656048)
		(stroke
			(width 0.1016)
			(type default)
		)
		(fill no)
		(layer "In12.Cu")
	)
	(gr_circle
		(center 374.114822 -270.036036)
		(end 374.368822 -270.036036)
		(stroke
			(width 0.1016)
			(type default)
		)
		(fill no)
		(layer "In12.Cu")
	)
	(gr_circle
		(center 377.367038 -180.678074)
		(end 378.256038 -180.678074)
		(stroke
			(width 0.2)
			(type default)
		)
		(fill no)
		(layer "In12.Cu")
	)
	(gr_circle
		(center 377.367038 -179.941474)
		(end 378.256038 -179.941474)
		(stroke
			(width 0.2)
			(type default)
		)
		(fill no)
		(layer "In12.Cu")
	)
	(gr_circle
		(center 377.367038 -179.204874)
		(end 378.256038 -179.204874)
		(stroke
			(width 0.2)
			(type default)
		)
		(fill no)
		(layer "In12.Cu")
	)
	(gr_circle
		(center 377.869958 -162.59683)
		(end 379.266958 -162.59683)
		(stroke
			(width 0.2)
			(type default)
		)
		(fill no)
		(layer "In12.Cu")
	)
	(gr_circle
		(center 377.900438 -179.560474)
		(end 378.789438 -179.560474)
		(stroke
			(width 0.2)
			(type default)
		)
		(fill no)
		(layer "In12.Cu")
	)
	(gr_circle
		(center 377.925838 -180.322474)
		(end 378.814838 -180.322474)
		(stroke
			(width 0.2)
			(type default)
		)
		(fill no)
		(layer "In12.Cu")
	)
	(gr_circle
		(center 378.450602 -179.883054)
		(end 379.339602 -179.883054)
		(stroke
			(width 0.2)
			(type default)
		)
		(fill no)
		(layer "In12.Cu")
	)
	(gr_circle
		(center 378.450602 -179.146454)
		(end 379.339602 -179.146454)
		(stroke
			(width 0.2)
			(type default)
		)
		(fill no)
		(layer "In12.Cu")
	)
	(gr_circle
		(center 379.035056 -182.230776)
		(end 379.924056 -182.230776)
		(stroke
			(width 0.2)
			(type default)
		)
		(fill no)
		(layer "In12.Cu")
	)
	(gr_circle
		(center 379.035056 -181.494176)
		(end 379.924056 -181.494176)
		(stroke
			(width 0.2)
			(type default)
		)
		(fill no)
		(layer "In12.Cu")
	)
	(gr_circle
		(center 379.152658 -180.755544)
		(end 380.032768 -180.755544)
		(stroke
			(width 0.2)
			(type default)
		)
		(fill no)
		(layer "In12.Cu")
	)
	(gr_circle
		(center 379.769878 -180.755544)
		(end 380.649988 -180.755544)
		(stroke
			(width 0.2)
			(type default)
		)
		(fill no)
		(layer "In12.Cu")
	)
	(gr_circle
		(center 380.387098 -180.755544)
		(end 381.267208 -180.755544)
		(stroke
			(width 0.2)
			(type default)
		)
		(fill no)
		(layer "In12.Cu")
	)
	(gr_line
		(start 385.601972 -12.288012)
		(end 260.800088 -12.288012)
		(stroke
			(width 0.2)
			(type default)
		)
		(layer "In12.Cu")
	)
	(gr_arc
		(start 385.601972 -12.288012)
		(mid 387.375417 -11.553448)
		(end 388.109968 -9.780016)
		(stroke
			(width 0.2)
			(type default)
		)
		(layer "In12.Cu")
	)
	(gr_arc
		(start 385.601972 -11.780012)
		(mid 387.016183 -11.194227)
		(end 387.601968 -9.780016)
		(stroke
			(width 1.016)
			(type default)
		)
		(layer "In12.Cu")
	)
	(gr_circle
		(center 385.698238 -180.678074)
		(end 386.587238 -180.678074)
		(stroke
			(width 0.2)
			(type default)
		)
		(fill no)
		(layer "In12.Cu")
	)
	(gr_circle
		(center 385.698238 -179.941474)
		(end 386.587238 -179.941474)
		(stroke
			(width 0.2)
			(type default)
		)
		(fill no)
		(layer "In12.Cu")
	)
	(gr_circle
		(center 385.698238 -179.204874)
		(end 386.587238 -179.204874)
		(stroke
			(width 0.2)
			(type default)
		)
		(fill no)
		(layer "In12.Cu")
	)
	(gr_circle
		(center 386.231638 -179.560474)
		(end 387.120638 -179.560474)
		(stroke
			(width 0.2)
			(type default)
		)
		(fill no)
		(layer "In12.Cu")
	)
	(gr_circle
		(center 386.257038 -180.322474)
		(end 387.146038 -180.322474)
		(stroke
			(width 0.2)
			(type default)
		)
		(fill no)
		(layer "In12.Cu")
	)
	(gr_circle
		(center 386.781802 -179.883054)
		(end 387.670802 -179.883054)
		(stroke
			(width 0.2)
			(type default)
		)
		(fill no)
		(layer "In12.Cu")
	)
	(gr_circle
		(center 386.781802 -179.146454)
		(end 387.670802 -179.146454)
		(stroke
			(width 0.2)
			(type default)
		)
		(fill no)
		(layer "In12.Cu")
	)
	(gr_circle
		(center 387.206998 -162.65271)
		(end 388.603998 -162.65271)
		(stroke
			(width 0.2)
			(type default)
		)
		(fill no)
		(layer "In12.Cu")
	)
	(gr_circle
		(center 387.293358 -157.001972)
		(end 388.182358 -157.001972)
		(stroke
			(width 0.2)
			(type default)
		)
		(fill no)
		(layer "In12.Cu")
	)
	(gr_circle
		(center 387.293358 -156.366972)
		(end 388.182358 -156.366972)
		(stroke
			(width 0.2)
			(type default)
		)
		(fill no)
		(layer "In12.Cu")
	)
	(gr_circle
		(center 387.293358 -155.724352)
		(end 388.182358 -155.724352)
		(stroke
			(width 0.2)
			(type default)
		)
		(fill no)
		(layer "In12.Cu")
	)
	(gr_circle
		(center 387.293358 -155.089352)
		(end 388.182358 -155.089352)
		(stroke
			(width 0.2)
			(type default)
		)
		(fill no)
		(layer "In12.Cu")
	)
	(gr_circle
		(center 387.293358 -154.428952)
		(end 388.182358 -154.428952)
		(stroke
			(width 0.2)
			(type default)
		)
		(fill no)
		(layer "In12.Cu")
	)
	(gr_circle
		(center 387.293358 -153.793952)
		(end 388.182358 -153.793952)
		(stroke
			(width 0.2)
			(type default)
		)
		(fill no)
		(layer "In12.Cu")
	)
	(gr_circle
		(center 387.366256 -182.230776)
		(end 388.255256 -182.230776)
		(stroke
			(width 0.2)
			(type default)
		)
		(fill no)
		(layer "In12.Cu")
	)
	(gr_circle
		(center 387.366256 -181.494176)
		(end 388.255256 -181.494176)
		(stroke
			(width 0.2)
			(type default)
		)
		(fill no)
		(layer "In12.Cu")
	)
	(gr_circle
		(center 387.483858 -180.755544)
		(end 388.363968 -180.755544)
		(stroke
			(width 0.2)
			(type default)
		)
		(fill no)
		(layer "In12.Cu")
	)
	(gr_line
		(start 387.601968 -9.780016)
		(end 387.601968 -0.500126)
		(stroke
			(width 1.016)
			(type default)
		)
		(layer "In12.Cu")
	)
	(gr_circle
		(center 387.928358 -157.001972)
		(end 388.817358 -157.001972)
		(stroke
			(width 0.2)
			(type default)
		)
		(fill no)
		(layer "In12.Cu")
	)
	(gr_circle
		(center 387.928358 -156.366972)
		(end 388.817358 -156.366972)
		(stroke
			(width 0.2)
			(type default)
		)
		(fill no)
		(layer "In12.Cu")
	)
	(gr_circle
		(center 387.928358 -155.724352)
		(end 388.817358 -155.724352)
		(stroke
			(width 0.2)
			(type default)
		)
		(fill no)
		(layer "In12.Cu")
	)
	(gr_circle
		(center 387.928358 -155.089352)
		(end 388.817358 -155.089352)
		(stroke
			(width 0.2)
			(type default)
		)
		(fill no)
		(layer "In12.Cu")
	)
	(gr_circle
		(center 387.928358 -154.428952)
		(end 388.817358 -154.428952)
		(stroke
			(width 0.2)
			(type default)
		)
		(fill no)
		(layer "In12.Cu")
	)
	(gr_circle
		(center 387.928358 -153.793952)
		(end 388.817358 -153.793952)
		(stroke
			(width 0.2)
			(type default)
		)
		(fill no)
		(layer "In12.Cu")
	)
	(gr_circle
		(center 388.101078 -180.755544)
		(end 388.981188 -180.755544)
		(stroke
			(width 0.2)
			(type default)
		)
		(fill no)
		(layer "In12.Cu")
	)
	(gr_arc
		(start 388.102094 0)
		(mid 387.748465 -0.146487)
		(end 387.601968 -0.500126)
		(stroke
			(width 1.016)
			(type default)
		)
		(layer "In12.Cu")
	)
	(gr_line
		(start 388.102094 0)
		(end 455.701908 0)
		(stroke
			(width 1.016)
			(type default)
		)
		(layer "In12.Cu")
	)
	(gr_line
		(start 388.109968 -0.508)
		(end 388.109968 -9.780016)
		(stroke
			(width 0.2)
			(type default)
		)
		(layer "In12.Cu")
	)
	(gr_circle
		(center 388.718298 -180.755544)
		(end 389.598408 -180.755544)
		(stroke
			(width 0.2)
			(type default)
		)
		(fill no)
		(layer "In12.Cu")
	)
	(gr_circle
		(center 394.628878 -173.21911)
		(end 395.517878 -173.21911)
		(stroke
			(width 0.2)
			(type default)
		)
		(fill no)
		(layer "In12.Cu")
	)
	(gr_circle
		(center 394.628878 -172.45711)
		(end 395.517878 -172.45711)
		(stroke
			(width 0.2)
			(type default)
		)
		(fill no)
		(layer "In12.Cu")
	)
	(gr_circle
		(center 394.646658 -173.987714)
		(end 395.535658 -173.987714)
		(stroke
			(width 0.2)
			(type default)
		)
		(fill no)
		(layer "In12.Cu")
	)
	(gr_circle
		(center 394.672058 -174.749714)
		(end 395.561058 -174.749714)
		(stroke
			(width 0.2)
			(type default)
		)
		(fill no)
		(layer "In12.Cu")
	)
	(gr_circle
		(center 395.196822 -174.310294)
		(end 396.085822 -174.310294)
		(stroke
			(width 0.2)
			(type default)
		)
		(fill no)
		(layer "In12.Cu")
	)
	(gr_circle
		(center 395.196822 -173.573694)
		(end 396.085822 -173.573694)
		(stroke
			(width 0.2)
			(type default)
		)
		(fill no)
		(layer "In12.Cu")
	)
	(gr_circle
		(center 395.230858 -172.819314)
		(end 396.119858 -172.819314)
		(stroke
			(width 0.2)
			(type default)
		)
		(fill no)
		(layer "In12.Cu")
	)
	(gr_circle
		(center 395.781276 -176.657254)
		(end 396.670276 -176.657254)
		(stroke
			(width 0.2)
			(type default)
		)
		(fill no)
		(layer "In12.Cu")
	)
	(gr_circle
		(center 395.781276 -175.895254)
		(end 396.670276 -175.895254)
		(stroke
			(width 0.2)
			(type default)
		)
		(fill no)
		(layer "In12.Cu")
	)
	(gr_circle
		(center 395.898878 -175.182784)
		(end 396.778988 -175.182784)
		(stroke
			(width 0.2)
			(type default)
		)
		(fill no)
		(layer "In12.Cu")
	)
	(gr_circle
		(center 396.516098 -175.182784)
		(end 397.396208 -175.182784)
		(stroke
			(width 0.2)
			(type default)
		)
		(fill no)
		(layer "In12.Cu")
	)
	(gr_circle
		(center 397.133318 -175.182784)
		(end 398.013428 -175.182784)
		(stroke
			(width 0.2)
			(type default)
		)
		(fill no)
		(layer "In12.Cu")
	)
	(gr_circle
		(center 399.165064 -81.051146)
		(end 400.054064 -81.051146)
		(stroke
			(width 0.2)
			(type default)
		)
		(fill no)
		(layer "In12.Cu")
	)
	(gr_circle
		(center 402.436838 -166.527988)
		(end 403.325838 -166.527988)
		(stroke
			(width 0.2)
			(type default)
		)
		(fill no)
		(layer "In12.Cu")
	)
	(gr_circle
		(center 402.436838 -165.791388)
		(end 403.325838 -165.791388)
		(stroke
			(width 0.2)
			(type default)
		)
		(fill no)
		(layer "In12.Cu")
	)
	(gr_circle
		(center 402.436838 -165.054788)
		(end 403.325838 -165.054788)
		(stroke
			(width 0.2)
			(type default)
		)
		(fill no)
		(layer "In12.Cu")
	)
	(gr_circle
		(center 402.970238 -165.410388)
		(end 403.859238 -165.410388)
		(stroke
			(width 0.2)
			(type default)
		)
		(fill no)
		(layer "In12.Cu")
	)
	(gr_circle
		(center 402.995638 -166.172388)
		(end 403.884638 -166.172388)
		(stroke
			(width 0.2)
			(type default)
		)
		(fill no)
		(layer "In12.Cu")
	)
	(gr_circle
		(center 403.520402 -165.732968)
		(end 404.409402 -165.732968)
		(stroke
			(width 0.2)
			(type default)
		)
		(fill no)
		(layer "In12.Cu")
	)
	(gr_circle
		(center 403.520402 -164.996368)
		(end 404.409402 -164.996368)
		(stroke
			(width 0.2)
			(type default)
		)
		(fill no)
		(layer "In12.Cu")
	)
	(gr_circle
		(center 404.104856 -168.082214)
		(end 404.993856 -168.082214)
		(stroke
			(width 0.2)
			(type default)
		)
		(fill no)
		(layer "In12.Cu")
	)
	(gr_circle
		(center 404.104856 -167.320214)
		(end 404.993856 -167.320214)
		(stroke
			(width 0.2)
			(type default)
		)
		(fill no)
		(layer "In12.Cu")
	)
	(gr_circle
		(center 404.222458 -166.605458)
		(end 405.102568 -166.605458)
		(stroke
			(width 0.2)
			(type default)
		)
		(fill no)
		(layer "In12.Cu")
	)
	(gr_circle
		(center 404.839678 -166.605458)
		(end 405.719788 -166.605458)
		(stroke
			(width 0.2)
			(type default)
		)
		(fill no)
		(layer "In12.Cu")
	)
	(gr_circle
		(center 405.456898 -166.605458)
		(end 406.337008 -166.605458)
		(stroke
			(width 0.2)
			(type default)
		)
		(fill no)
		(layer "In12.Cu")
	)
	(gr_circle
		(center 410.818838 -161.701988)
		(end 411.707838 -161.701988)
		(stroke
			(width 0.2)
			(type default)
		)
		(fill no)
		(layer "In12.Cu")
	)
	(gr_circle
		(center 410.818838 -160.965388)
		(end 411.707838 -160.965388)
		(stroke
			(width 0.2)
			(type default)
		)
		(fill no)
		(layer "In12.Cu")
	)
	(gr_circle
		(center 410.818838 -160.228788)
		(end 411.707838 -160.228788)
		(stroke
			(width 0.2)
			(type default)
		)
		(fill no)
		(layer "In12.Cu")
	)
	(gr_circle
		(center 411.352238 -160.584388)
		(end 412.241238 -160.584388)
		(stroke
			(width 0.2)
			(type default)
		)
		(fill no)
		(layer "In12.Cu")
	)
	(gr_circle
		(center 411.377638 -161.346388)
		(end 412.266638 -161.346388)
		(stroke
			(width 0.2)
			(type default)
		)
		(fill no)
		(layer "In12.Cu")
	)
	(gr_circle
		(center 411.902402 -160.906968)
		(end 412.791402 -160.906968)
		(stroke
			(width 0.2)
			(type default)
		)
		(fill no)
		(layer "In12.Cu")
	)
	(gr_circle
		(center 411.902402 -160.170368)
		(end 412.791402 -160.170368)
		(stroke
			(width 0.2)
			(type default)
		)
		(fill no)
		(layer "In12.Cu")
	)
	(gr_circle
		(center 412.486856 -163.256214)
		(end 413.375856 -163.256214)
		(stroke
			(width 0.2)
			(type default)
		)
		(fill no)
		(layer "In12.Cu")
	)
	(gr_circle
		(center 412.486856 -162.494214)
		(end 413.375856 -162.494214)
		(stroke
			(width 0.2)
			(type default)
		)
		(fill no)
		(layer "In12.Cu")
	)
	(gr_circle
		(center 412.604458 -161.779458)
		(end 413.484568 -161.779458)
		(stroke
			(width 0.2)
			(type default)
		)
		(fill no)
		(layer "In12.Cu")
	)
	(gr_circle
		(center 413.221678 -161.779458)
		(end 414.101788 -161.779458)
		(stroke
			(width 0.2)
			(type default)
		)
		(fill no)
		(layer "In12.Cu")
	)
	(gr_circle
		(center 413.838898 -161.779458)
		(end 414.719008 -161.779458)
		(stroke
			(width 0.2)
			(type default)
		)
		(fill no)
		(layer "In12.Cu")
	)
	(gr_circle
		(center 424.33494 -353.10318)
		(end 425.21505 -353.10318)
		(stroke
			(width 0.2)
			(type default)
		)
		(fill no)
		(layer "In12.Cu")
	)
	(gr_circle
		(center 424.95216 -353.10318)
		(end 425.83227 -353.10318)
		(stroke
			(width 0.2)
			(type default)
		)
		(fill no)
		(layer "In12.Cu")
	)
	(gr_circle
		(center 425.56938 -353.10318)
		(end 426.44949 -353.10318)
		(stroke
			(width 0.2)
			(type default)
		)
		(fill no)
		(layer "In12.Cu")
	)
	(gr_circle
		(center 425.686474 -352.35769)
		(end 426.575474 -352.35769)
		(stroke
			(width 0.2)
			(type default)
		)
		(fill no)
		(layer "In12.Cu")
	)
	(gr_circle
		(center 425.686474 -351.62109)
		(end 426.575474 -351.62109)
		(stroke
			(width 0.2)
			(type default)
		)
		(fill no)
		(layer "In12.Cu")
	)
	(gr_circle
		(center 426.271436 -354.71227)
		(end 427.160436 -354.71227)
		(stroke
			(width 0.2)
			(type default)
		)
		(fill no)
		(layer "In12.Cu")
	)
	(gr_circle
		(center 426.271436 -353.97567)
		(end 427.160436 -353.97567)
		(stroke
			(width 0.2)
			(type default)
		)
		(fill no)
		(layer "In12.Cu")
	)
	(gr_circle
		(center 426.7962 -353.53625)
		(end 427.6852 -353.53625)
		(stroke
			(width 0.2)
			(type default)
		)
		(fill no)
		(layer "In12.Cu")
	)
	(gr_circle
		(center 426.8216 -354.29825)
		(end 427.7106 -354.29825)
		(stroke
			(width 0.2)
			(type default)
		)
		(fill no)
		(layer "In12.Cu")
	)
	(gr_circle
		(center 427.355 -354.65385)
		(end 428.244 -354.65385)
		(stroke
			(width 0.2)
			(type default)
		)
		(fill no)
		(layer "In12.Cu")
	)
	(gr_circle
		(center 427.355 -353.91725)
		(end 428.244 -353.91725)
		(stroke
			(width 0.2)
			(type default)
		)
		(fill no)
		(layer "In12.Cu")
	)
	(gr_circle
		(center 427.355 -353.18065)
		(end 428.244 -353.18065)
		(stroke
			(width 0.2)
			(type default)
		)
		(fill no)
		(layer "In12.Cu")
	)
	(gr_circle
		(center 432.01336 -361.827826)
		(end 433.41036 -361.827826)
		(stroke
			(width 0.2)
			(type default)
		)
		(fill no)
		(layer "In12.Cu")
	)
	(gr_circle
		(center 432.661568 -353.12858)
		(end 433.541678 -353.12858)
		(stroke
			(width 0.2)
			(type default)
		)
		(fill no)
		(layer "In12.Cu")
	)
	(gr_circle
		(center 433.278788 -353.12858)
		(end 434.158898 -353.12858)
		(stroke
			(width 0.2)
			(type default)
		)
		(fill no)
		(layer "In12.Cu")
	)
	(gr_circle
		(center 433.896008 -353.12858)
		(end 434.776118 -353.12858)
		(stroke
			(width 0.2)
			(type default)
		)
		(fill no)
		(layer "In12.Cu")
	)
	(gr_circle
		(center 434.013102 -352.38309)
		(end 434.902102 -352.38309)
		(stroke
			(width 0.2)
			(type default)
		)
		(fill no)
		(layer "In12.Cu")
	)
	(gr_circle
		(center 434.013102 -351.64649)
		(end 434.902102 -351.64649)
		(stroke
			(width 0.2)
			(type default)
		)
		(fill no)
		(layer "In12.Cu")
	)
	(gr_circle
		(center 434.598064 -354.73767)
		(end 435.487064 -354.73767)
		(stroke
			(width 0.2)
			(type default)
		)
		(fill no)
		(layer "In12.Cu")
	)
	(gr_circle
		(center 434.598064 -354.00107)
		(end 435.487064 -354.00107)
		(stroke
			(width 0.2)
			(type default)
		)
		(fill no)
		(layer "In12.Cu")
	)
	(gr_circle
		(center 435.122828 -353.56165)
		(end 436.011828 -353.56165)
		(stroke
			(width 0.2)
			(type default)
		)
		(fill no)
		(layer "In12.Cu")
	)
	(gr_circle
		(center 435.148228 -354.32365)
		(end 436.037228 -354.32365)
		(stroke
			(width 0.2)
			(type default)
		)
		(fill no)
		(layer "In12.Cu")
	)
	(gr_circle
		(center 435.469538 -361.496102)
		(end 436.358538 -361.496102)
		(stroke
			(width 0.2)
			(type default)
		)
		(fill no)
		(layer "In12.Cu")
	)
	(gr_circle
		(center 435.469538 -360.734102)
		(end 436.358538 -360.734102)
		(stroke
			(width 0.2)
			(type default)
		)
		(fill no)
		(layer "In12.Cu")
	)
	(gr_circle
		(center 435.469538 -359.972102)
		(end 436.358538 -359.972102)
		(stroke
			(width 0.2)
			(type default)
		)
		(fill no)
		(layer "In12.Cu")
	)
	(gr_circle
		(center 435.681628 -354.67925)
		(end 436.570628 -354.67925)
		(stroke
			(width 0.2)
			(type default)
		)
		(fill no)
		(layer "In12.Cu")
	)
	(gr_circle
		(center 435.681628 -353.94265)
		(end 436.570628 -353.94265)
		(stroke
			(width 0.2)
			(type default)
		)
		(fill no)
		(layer "In12.Cu")
	)
	(gr_circle
		(center 435.681628 -353.20605)
		(end 436.570628 -353.20605)
		(stroke
			(width 0.2)
			(type default)
		)
		(fill no)
		(layer "In12.Cu")
	)
	(gr_circle
		(center 436.231538 -361.496102)
		(end 437.120538 -361.496102)
		(stroke
			(width 0.2)
			(type default)
		)
		(fill no)
		(layer "In12.Cu")
	)
	(gr_circle
		(center 436.231538 -360.734102)
		(end 437.120538 -360.734102)
		(stroke
			(width 0.2)
			(type default)
		)
		(fill no)
		(layer "In12.Cu")
	)
	(gr_circle
		(center 436.231538 -359.972102)
		(end 437.120538 -359.972102)
		(stroke
			(width 0.2)
			(type default)
		)
		(fill no)
		(layer "In12.Cu")
	)
	(gr_circle
		(center 437.703214 -12.400788)
		(end 438.592214 -12.400788)
		(stroke
			(width 0.2)
			(type default)
		)
		(fill no)
		(layer "In12.Cu")
	)
	(gr_circle
		(center 438.06999 -13.069316)
		(end 438.95899 -13.069316)
		(stroke
			(width 0.2)
			(type default)
		)
		(fill no)
		(layer "In12.Cu")
	)
	(gr_circle
		(center 438.592214 -12.400788)
		(end 439.481214 -12.400788)
		(stroke
			(width 0.2)
			(type default)
		)
		(fill no)
		(layer "In12.Cu")
	)
	(gr_circle
		(center 438.71515 -13.061696)
		(end 439.60415 -13.061696)
		(stroke
			(width 0.2)
			(type default)
		)
		(fill no)
		(layer "In12.Cu")
	)
	(gr_circle
		(center 439.39333 -13.043916)
		(end 440.28233 -13.043916)
		(stroke
			(width 0.2)
			(type default)
		)
		(fill no)
		(layer "In12.Cu")
	)
	(gr_circle
		(center 439.481214 -12.400788)
		(end 440.370214 -12.400788)
		(stroke
			(width 0.2)
			(type default)
		)
		(fill no)
		(layer "In12.Cu")
	)
	(gr_circle
		(center 440.945524 -11.261852)
		(end 441.834524 -11.261852)
		(stroke
			(width 0.2)
			(type default)
		)
		(fill no)
		(layer "In12.Cu")
	)
	(gr_circle
		(center 440.945524 -10.626852)
		(end 441.834524 -10.626852)
		(stroke
			(width 0.2)
			(type default)
		)
		(fill no)
		(layer "In12.Cu")
	)
	(gr_circle
		(center 441.129674 -25.982422)
		(end 442.018674 -25.982422)
		(stroke
			(width 0.2)
			(type default)
		)
		(fill no)
		(layer "In12.Cu")
	)
	(gr_circle
		(center 441.354718 -20.73656)
		(end 442.243718 -20.73656)
		(stroke
			(width 0.2)
			(type default)
		)
		(fill no)
		(layer "In12.Cu")
	)
	(gr_circle
		(center 441.354718 -20.10156)
		(end 442.243718 -20.10156)
		(stroke
			(width 0.2)
			(type default)
		)
		(fill no)
		(layer "In12.Cu")
	)
	(gr_circle
		(center 441.354718 -19.21256)
		(end 442.243718 -19.21256)
		(stroke
			(width 0.2)
			(type default)
		)
		(fill no)
		(layer "In12.Cu")
	)
	(gr_circle
		(center 441.354718 -18.57756)
		(end 442.243718 -18.57756)
		(stroke
			(width 0.2)
			(type default)
		)
		(fill no)
		(layer "In12.Cu")
	)
	(gr_circle
		(center 441.475622 -14.123162)
		(end 442.364622 -14.123162)
		(stroke
			(width 0.2)
			(type default)
		)
		(fill no)
		(layer "In12.Cu")
	)
	(gr_circle
		(center 441.475622 -13.488162)
		(end 442.364622 -13.488162)
		(stroke
			(width 0.2)
			(type default)
		)
		(fill no)
		(layer "In12.Cu")
	)
	(gr_circle
		(center 441.56249 -25.461976)
		(end 442.45149 -25.461976)
		(stroke
			(width 0.2)
			(type default)
		)
		(fill no)
		(layer "In12.Cu")
	)
	(gr_circle
		(center 442.018674 -25.982422)
		(end 442.907674 -25.982422)
		(stroke
			(width 0.2)
			(type default)
		)
		(fill no)
		(layer "In12.Cu")
	)
	(gr_circle
		(center 442.371734 -20.983702)
		(end 443.260734 -20.983702)
		(stroke
			(width 0.2)
			(type default)
		)
		(fill no)
		(layer "In12.Cu")
	)
	(gr_circle
		(center 442.371734 -20.348702)
		(end 443.260734 -20.348702)
		(stroke
			(width 0.2)
			(type default)
		)
		(fill no)
		(layer "In12.Cu")
	)
	(gr_circle
		(center 442.371734 -19.459702)
		(end 443.260734 -19.459702)
		(stroke
			(width 0.2)
			(type default)
		)
		(fill no)
		(layer "In12.Cu")
	)
	(gr_circle
		(center 442.371734 -18.824702)
		(end 443.260734 -18.824702)
		(stroke
			(width 0.2)
			(type default)
		)
		(fill no)
		(layer "In12.Cu")
	)
	(gr_circle
		(center 442.45149 -25.461976)
		(end 443.34049 -25.461976)
		(stroke
			(width 0.2)
			(type default)
		)
		(fill no)
		(layer "In12.Cu")
	)
	(gr_circle
		(center 442.907674 -25.982422)
		(end 443.796674 -25.982422)
		(stroke
			(width 0.2)
			(type default)
		)
		(fill no)
		(layer "In12.Cu")
	)
	(gr_circle
		(center 443.34049 -25.461976)
		(end 444.22949 -25.461976)
		(stroke
			(width 0.2)
			(type default)
		)
		(fill no)
		(layer "In12.Cu")
	)
	(gr_circle
		(center 444.166244 -24.741632)
		(end 445.055244 -24.741632)
		(stroke
			(width 0.2)
			(type default)
		)
		(fill no)
		(layer "In12.Cu")
	)
	(gr_circle
		(center 450.669914 -14.526514)
		(end 451.558914 -14.526514)
		(stroke
			(width 0.2)
			(type default)
		)
		(fill no)
		(layer "In12.Cu")
	)
	(gr_circle
		(center 450.670676 -16.010382)
		(end 451.559676 -16.010382)
		(stroke
			(width 0.2)
			(type default)
		)
		(fill no)
		(layer "In12.Cu")
	)
	(gr_circle
		(center 450.670676 -15.273782)
		(end 451.559676 -15.273782)
		(stroke
			(width 0.2)
			(type default)
		)
		(fill no)
		(layer "In12.Cu")
	)
	(gr_circle
		(center 452.054976 -18.535142)
		(end 452.943976 -18.535142)
		(stroke
			(width 0.2)
			(type default)
		)
		(fill no)
		(layer "In12.Cu")
	)
	(gr_circle
		(center 452.054976 -17.798542)
		(end 452.943976 -17.798542)
		(stroke
			(width 0.2)
			(type default)
		)
		(fill no)
		(layer "In12.Cu")
	)
	(gr_line
		(start 455.694034 -9.780016)
		(end 455.694034 -0.508)
		(stroke
			(width 0.2)
			(type default)
		)
		(layer "In12.Cu")
	)
	(gr_arc
		(start 455.694034 -9.780016)
		(mid 456.428616 -11.553416)
		(end 458.20203 -12.288012)
		(stroke
			(width 0.2)
			(type default)
		)
		(layer "In12.Cu")
	)
	(gr_line
		(start 455.694034 -0.508)
		(end 388.109968 -0.508)
		(stroke
			(width 0.2)
			(type default)
		)
		(layer "In12.Cu")
	)
	(gr_arc
		(start 456.202034 -9.780016)
		(mid 456.787819 -11.194227)
		(end 458.20203 -11.780012)
		(stroke
			(width 1.016)
			(type default)
		)
		(layer "In12.Cu")
	)
	(gr_arc
		(start 456.202034 -0.500126)
		(mid 456.05556 -0.146464)
		(end 455.701908 0)
		(stroke
			(width 1.016)
			(type default)
		)
		(layer "In12.Cu")
	)
	(gr_line
		(start 456.202034 -0.500126)
		(end 456.202034 -9.780016)
		(stroke
			(width 1.016)
			(type default)
		)
		(layer "In12.Cu")
	)
	(gr_line
		(start 458.20203 -11.780012)
		(end 469.799924 -11.780012)
		(stroke
			(width 1.016)
			(type default)
		)
		(layer "In12.Cu")
	)
	(gr_line
		(start 463.300064 -441.989972)
		(end 277.314914 -441.989972)
		(stroke
			(width 1.016)
			(type default)
		)
		(layer "In12.Cu")
	)
	(gr_arc
		(start 463.300064 -441.989972)
		(mid 464.71429 -441.404198)
		(end 465.30006 -439.989976)
		(stroke
			(width 1.016)
			(type default)
		)
		(layer "In12.Cu")
	)
	(gr_arc
		(start 463.300064 -441.481972)
		(mid 464.355064 -441.044976)
		(end 464.79206 -439.989976)
		(stroke
			(width 0.2)
			(type default)
		)
		(layer "In12.Cu")
	)
	(gr_line
		(start 464.79206 -439.989976)
		(end 464.79206 -409.528264)
		(stroke
			(width 0.2)
			(type default)
		)
		(layer "In12.Cu")
	)
	(gr_line
		(start 465.30006 -409.528518)
		(end 465.30006 -439.989976)
		(stroke
			(width 1.016)
			(type default)
		)
		(layer "In12.Cu")
	)
	(gr_arc
		(start 465.526628 -407.75509)
		(mid 464.983024 -408.568632)
		(end 464.79206 -409.528264)
		(stroke
			(width 0.2)
			(type default)
		)
		(layer "In12.Cu")
	)
	(gr_line
		(start 465.526628 -407.75509)
		(end 467.355174 -405.926544)
		(stroke
			(width 0.2)
			(type default)
		)
		(layer "In12.Cu")
	)
	(gr_arc
		(start 465.885784 -408.114246)
		(mid 465.452221 -408.76312)
		(end 465.30006 -409.528518)
		(stroke
			(width 1.016)
			(type default)
		)
		(layer "In12.Cu")
	)
	(gr_arc
		(start 467.355174 -405.926544)
		(mid 467.678507 -405.442687)
		(end 467.792054 -404.871936)
		(stroke
			(width 0.2)
			(type default)
		)
		(layer "In12.Cu")
	)
	(gr_line
		(start 467.71433 -406.2857)
		(end 465.885784 -408.114246)
		(stroke
			(width 1.016)
			(type default)
		)
		(layer "In12.Cu")
	)
	(gr_arc
		(start 467.71433 -406.2857)
		(mid 468.147828 -405.636947)
		(end 468.300054 -404.871682)
		(stroke
			(width 1.016)
			(type default)
		)
		(layer "In12.Cu")
	)
	(gr_line
		(start 467.792054 -404.871936)
		(end 467.792054 -82.82813)
		(stroke
			(width 0.2)
			(type default)
		)
		(layer "In12.Cu")
	)
	(gr_line
		(start 468.300054 -82.828384)
		(end 468.300054 -404.871682)
		(stroke
			(width 1.016)
			(type default)
		)
		(layer "In12.Cu")
	)
	(gr_arc
		(start 468.526622 -81.054956)
		(mid 467.983009 -81.868496)
		(end 467.792054 -82.82813)
		(stroke
			(width 0.2)
			(type default)
		)
		(layer "In12.Cu")
	)
	(gr_line
		(start 468.526622 -81.054956)
		(end 470.85504 -78.726538)
		(stroke
			(width 0.2)
			(type default)
		)
		(layer "In12.Cu")
	)
	(gr_arc
		(start 468.885778 -81.414112)
		(mid 468.452215 -82.062986)
		(end 468.300054 -82.828384)
		(stroke
			(width 1.016)
			(type default)
		)
		(layer "In12.Cu")
	)
	(gr_line
		(start 469.799924 -12.288012)
		(end 458.20203 -12.288012)
		(stroke
			(width 0.2)
			(type default)
		)
		(layer "In12.Cu")
	)
	(gr_arc
		(start 470.85504 -78.726538)
		(mid 471.178373 -78.242681)
		(end 471.29192 -77.67193)
		(stroke
			(width 0.2)
			(type default)
		)
		(layer "In12.Cu")
	)
	(gr_line
		(start 471.214196 -79.085694)
		(end 468.885778 -81.414112)
		(stroke
			(width 1.016)
			(type default)
		)
		(layer "In12.Cu")
	)
	(gr_arc
		(start 471.214196 -79.085694)
		(mid 471.6477 -78.436942)
		(end 471.79992 -77.671676)
		(stroke
			(width 1.016)
			(type default)
		)
		(layer "In12.Cu")
	)
	(gr_line
		(start 471.29192 -77.67193)
		(end 471.29192 -13.780008)
		(stroke
			(width 0.2)
			(type default)
		)
		(layer "In12.Cu")
	)
	(gr_arc
		(start 471.29192 -13.780008)
		(mid 470.854924 -12.725008)
		(end 469.799924 -12.288012)
		(stroke
			(width 0.2)
			(type default)
		)
		(layer "In12.Cu")
	)
	(gr_arc
		(start 471.79992 -13.780008)
		(mid 471.214139 -12.365784)
		(end 469.799924 -11.780012)
		(stroke
			(width 1.016)
			(type default)
		)
		(layer "In12.Cu")
	)
	(gr_line
		(start 471.79992 -13.780008)
		(end 471.79992 -77.671676)
		(stroke
			(width 1.016)
			(type default)
		)
		(layer "In12.Cu")
	)
	(gr_poly
		(pts
			(xy 78.264004 -294.781732) (xy 78.22565 -294.75938) (xy 78.088998 -294.795956) (xy 78.125574 -294.932608)
			(xy 78.164182 -294.95496)
		)
		(stroke
			(width 0)
			(type solid)
		)
		(fill yes)
		(layer "In13.Cu")
		(net "M_B_CPU1_SB_DQ<28>")
	)
	(gr_poly
		(pts
			(xy 78.385416 -223.728534) (xy 78.31709 -223.540574) (xy 78.27518 -223.555814) (xy 78.21549 -223.684084)
			(xy 78.34376 -223.743774)
		)
		(stroke
			(width 0)
			(type solid)
		)
		(fill yes)
		(layer "In13.Cu")
		(net "M_B_CPU1_SA_DQ<6>")
	)
	(gr_poly
		(pts
			(xy 78.498446 -247.522746) (xy 78.498446 -247.475248) (xy 78.298548 -247.475248) (xy 78.298548 -247.522746)
			(xy 78.398624 -247.622822)
		)
		(stroke
			(width 0)
			(type solid)
		)
		(fill yes)
		(layer "In13.Cu")
		(net "M_B_CPU1_SA_DQS_DP<9>")
	)
	(gr_poly
		(pts
			(xy 78.498446 -242.66271) (xy 78.498446 -242.615212) (xy 78.298548 -242.615212) (xy 78.298548 -242.66271)
			(xy 78.398624 -242.762786)
		)
		(stroke
			(width 0)
			(type solid)
		)
		(fill yes)
		(layer "In13.Cu")
		(net "M_B_CPU1_SA_DQS_DP<8>")
	)
	(gr_poly
		(pts
			(xy 78.501494 -254.002794) (xy 78.501494 -253.958344) (xy 78.301342 -253.958344) (xy 78.301342 -254.002794)
			(xy 78.401418 -254.102616)
		)
		(stroke
			(width 0)
			(type solid)
		)
		(fill yes)
		(layer "In13.Cu")
		(net "M_B_CPU1_SA_CA<3>")
	)
	(gr_poly
		(pts
			(xy 78.501494 -252.382782) (xy 78.501494 -252.338332) (xy 78.301342 -252.338332) (xy 78.301342 -252.382782)
			(xy 78.401418 -252.482604)
		)
		(stroke
			(width 0)
			(type solid)
		)
		(fill yes)
		(layer "In13.Cu")
		(net "M_B_CPU1_SA_CS_N<1>")
	)
	(gr_poly
		(pts
			(xy 78.501494 -249.142758) (xy 78.501494 -249.098308) (xy 78.301342 -249.098308) (xy 78.301342 -249.142758)
			(xy 78.401418 -249.24258)
		)
		(stroke
			(width 0)
			(type solid)
		)
		(fill yes)
		(layer "In13.Cu")
		(net "M_B_CPU1_SA_CB<7>")
	)
	(gr_poly
		(pts
			(xy 78.501494 -245.902734) (xy 78.501494 -245.858284) (xy 78.301342 -245.858284) (xy 78.301342 -245.902734)
			(xy 78.401418 -246.002556)
		)
		(stroke
			(width 0)
			(type solid)
		)
		(fill yes)
		(layer "In13.Cu")
		(net "M_B_CPU1_SA_CB<3>")
	)
	(gr_poly
		(pts
			(xy 78.501494 -244.282722) (xy 78.501494 -244.238272) (xy 78.301342 -244.238272) (xy 78.301342 -244.282722)
			(xy 78.401418 -244.382544)
		)
		(stroke
			(width 0)
			(type solid)
		)
		(fill yes)
		(layer "In13.Cu")
		(net "M_B_CPU1_SA_DQ<31>")
	)
	(gr_poly
		(pts
			(xy 78.528926 -223.223836) (xy 78.565756 -223.087184) (xy 78.429104 -223.050608) (xy 78.390496 -223.07296)
			(xy 78.490572 -223.246188)
		)
		(stroke
			(width 0)
			(type solid)
		)
		(fill yes)
		(layer "In13.Cu")
		(net "M_B_CPU1_SA_DQ<4>")
	)
	(gr_poly
		(pts
			(xy 78.530704 -254.406146) (xy 78.430628 -254.30607) (xy 78.330806 -254.406146) (xy 78.330806 -254.450596)
			(xy 78.530704 -254.450596)
		)
		(stroke
			(width 0)
			(type solid)
		)
		(fill yes)
		(layer "In13.Cu")
		(net "M_B_CPU1_SA_CA<4>")
	)
	(gr_poly
		(pts
			(xy 78.530704 -252.786134) (xy 78.430628 -252.686058) (xy 78.330806 -252.786134) (xy 78.330806 -252.830584)
			(xy 78.530704 -252.830584)
		)
		(stroke
			(width 0)
			(type solid)
		)
		(fill yes)
		(layer "In13.Cu")
		(net "M_B_CPU1_SA_CA<0>")
	)
	(gr_poly
		(pts
			(xy 78.530704 -247.926098) (xy 78.430628 -247.826022) (xy 78.330806 -247.926098) (xy 78.330806 -247.970548)
			(xy 78.530704 -247.970548)
		)
		(stroke
			(width 0)
			(type solid)
		)
		(fill yes)
		(layer "In13.Cu")
		(net "M_B_CPU1_SA_CB<4>")
	)
	(gr_poly
		(pts
			(xy 78.730348 -293.986712) (xy 78.691994 -293.96436) (xy 78.555342 -294.000936) (xy 78.591918 -294.137588)
			(xy 78.630526 -294.15994)
		)
		(stroke
			(width 0)
			(type solid)
		)
		(fill yes)
		(layer "In13.Cu")
		(net "M_B_CPU1_SB_DQ<28>")
	)
	(gr_poly
		(pts
			(xy 78.801468 -289.677856) (xy 78.701392 -289.578034) (xy 78.60157 -289.677856) (xy 78.60157 -289.722306)
			(xy 78.801468 -289.722306)
		)
		(stroke
			(width 0)
			(type solid)
		)
		(fill yes)
		(layer "In13.Cu")
		(net "M_B_CPU1_SB_DQ<25>")
	)
	(gr_poly
		(pts
			(xy 78.801468 -286.437832) (xy 78.701392 -286.33801) (xy 78.60157 -286.437832) (xy 78.60157 -286.485584)
			(xy 78.801468 -286.485584)
		)
		(stroke
			(width 0)
			(type solid)
		)
		(fill yes)
		(layer "In13.Cu")
		(net "M_B_CPU1_SB_DQS_DN<7>")
	)
	(gr_poly
		(pts
			(xy 78.801468 -284.818074) (xy 78.701392 -284.718252) (xy 78.60157 -284.818074) (xy 78.60157 -284.862524)
			(xy 78.801468 -284.862524)
		)
		(stroke
			(width 0)
			(type solid)
		)
		(fill yes)
		(layer "In13.Cu")
		(net "M_B_CPU1_SB_DQ<17>")
	)
	(gr_poly
		(pts
			(xy 78.801468 -273.074638) (xy 78.801468 -273.030188) (xy 78.60157 -273.030188) (xy 78.60157 -273.074638)
			(xy 78.701392 -273.17446)
		)
		(stroke
			(width 0)
			(type solid)
		)
		(fill yes)
		(layer "In13.Cu")
		(net "M_B_CPU1_SB_CB<2>")
	)
	(gr_poly
		(pts
			(xy 78.801468 -269.834614) (xy 78.801468 -269.790164) (xy 78.60157 -269.790164) (xy 78.60157 -269.834614)
			(xy 78.701392 -269.934436)
		)
		(stroke
			(width 0)
			(type solid)
		)
		(fill yes)
		(layer "In13.Cu")
		(net "M_B_CPU1_SB_CB<6>")
	)
	(gr_poly
		(pts
			(xy 78.80223 -288.057844) (xy 78.702408 -287.957768) (xy 78.602332 -288.057844) (xy 78.602332 -288.102294)
			(xy 78.80223 -288.102294)
		)
		(stroke
			(width 0)
			(type solid)
		)
		(fill yes)
		(layer "In13.Cu")
		(net "M_B_CPU1_SB_DQ<21>")
	)
	(gr_poly
		(pts
			(xy 78.819756 -281.174698) (xy 78.819756 -281.1272) (xy 78.619858 -281.1272) (xy 78.619858 -281.174698)
			(xy 78.71968 -281.274774)
		)
		(stroke
			(width 0)
			(type solid)
		)
		(fill yes)
		(layer "In13.Cu")
		(net "M_B_CPU1_SB_DQS_DN<1>")
	)
	(gr_poly
		(pts
			(xy 78.900274 -224.582736) (xy 78.800198 -224.409508) (xy 78.76159 -224.431606) (xy 78.725014 -224.568258)
			(xy 78.861666 -224.604834)
		)
		(stroke
			(width 0)
			(type solid)
		)
		(fill yes)
		(layer "In13.Cu")
		(net "M_B_CPU1_SA_DQ<6>")
	)
	(gr_poly
		(pts
			(xy 78.904846 -222.964502) (xy 78.80477 -222.791274) (xy 78.763622 -222.81515) (xy 78.727046 -222.951802)
			(xy 78.863698 -222.988378)
		)
		(stroke
			(width 0)
			(type solid)
		)
		(fill yes)
		(layer "In13.Cu")
		(net "M_B_CPU1_SA_DQS_DP<5>")
	)
	(gr_poly
		(pts
			(xy 78.96225 -256.433066) (xy 78.96225 -256.385568) (xy 78.762352 -256.385568) (xy 78.762352 -256.433066)
			(xy 78.862428 -256.533142)
		)
		(stroke
			(width 0)
			(type solid)
		)
		(fill yes)
		(layer "In13.Cu")
		(net "M_B_CPU1_CLK_DN<0>")
	)
	(gr_poly
		(pts
			(xy 78.96733 -239.015778) (xy 78.867254 -238.915702) (xy 78.767178 -239.015778) (xy 78.767178 -239.060228)
			(xy 78.96733 -239.060228)
		)
		(stroke
			(width 0)
			(type solid)
		)
		(fill yes)
		(layer "In13.Cu")
		(net "M_B_CPU1_SA_DQ<21>")
	)
	(gr_poly
		(pts
			(xy 78.969362 -254.813054) (xy 78.969362 -254.768604) (xy 78.769464 -254.768604) (xy 78.769464 -254.813054)
			(xy 78.86954 -254.91313)
		)
		(stroke
			(width 0)
			(type solid)
		)
		(fill yes)
		(layer "In13.Cu")
		(net "M_B_CPU1_SA_CA<5>")
	)
	(gr_poly
		(pts
			(xy 78.969362 -253.193042) (xy 78.969362 -253.148592) (xy 78.769464 -253.148592) (xy 78.769464 -253.193042)
			(xy 78.86954 -253.293118)
		)
		(stroke
			(width 0)
			(type solid)
		)
		(fill yes)
		(layer "In13.Cu")
		(net "M_B_CPU1_SA_CA<1>")
	)
	(gr_poly
		(pts
			(xy 78.969362 -248.333006) (xy 78.969362 -248.288556) (xy 78.769464 -248.288556) (xy 78.769464 -248.333006)
			(xy 78.86954 -248.433082)
		)
		(stroke
			(width 0)
			(type solid)
		)
		(fill yes)
		(layer "In13.Cu")
		(net "M_B_CPU1_SA_CB<6>")
	)
	(gr_poly
		(pts
			(xy 78.969362 -246.712994) (xy 78.969362 -246.665496) (xy 78.769464 -246.665496) (xy 78.769464 -246.712994)
			(xy 78.86954 -246.81307)
		)
		(stroke
			(width 0)
			(type solid)
		)
		(fill yes)
		(layer "In13.Cu")
		(net "M_B_CPU1_SA_DQS_DN<4>")
	)
	(gr_poly
		(pts
			(xy 78.969362 -245.092982) (xy 78.969362 -245.048532) (xy 78.769464 -245.048532) (xy 78.769464 -245.092982)
			(xy 78.86954 -245.193058)
		)
		(stroke
			(width 0)
			(type solid)
		)
		(fill yes)
		(layer "In13.Cu")
		(net "M_B_CPU1_SA_CB<2>")
	)
	(gr_poly
		(pts
			(xy 78.969362 -243.47297) (xy 78.969362 -243.42852) (xy 78.769464 -243.42852) (xy 78.769464 -243.47297)
			(xy 78.86954 -243.573046)
		)
		(stroke
			(width 0)
			(type solid)
		)
		(fill yes)
		(layer "In13.Cu")
		(net "M_B_CPU1_SA_DQ<30>")
	)
	(gr_poly
		(pts
			(xy 78.969362 -240.232946) (xy 78.969362 -240.188496) (xy 78.769464 -240.188496) (xy 78.769464 -240.232946)
			(xy 78.86954 -240.333022)
		)
		(stroke
			(width 0)
			(type solid)
		)
		(fill yes)
		(layer "In13.Cu")
		(net "M_B_CPU1_SA_DQ<26>")
	)
	(gr_poly
		(pts
			(xy 78.969362 -238.612934) (xy 78.969362 -238.568484) (xy 78.769464 -238.568484) (xy 78.769464 -238.612934)
			(xy 78.86954 -238.71301)
		)
		(stroke
			(width 0)
			(type solid)
		)
		(fill yes)
		(layer "In13.Cu")
		(net "M_B_CPU1_SA_DQ<22>")
	)
	(gr_poly
		(pts
			(xy 78.969362 -237.395512) (xy 78.869286 -237.295436) (xy 78.769464 -237.395512) (xy 78.769464 -237.443264)
			(xy 78.969362 -237.443264)
		)
		(stroke
			(width 0)
			(type solid)
		)
		(fill yes)
		(layer "In13.Cu")
		(net "M_B_CPU1_SA_DQS_DN<7>")
	)
	(gr_poly
		(pts
			(xy 78.969362 -236.992922) (xy 78.969362 -236.945424) (xy 78.769464 -236.945424) (xy 78.769464 -236.992922)
			(xy 78.86954 -237.092998)
		)
		(stroke
			(width 0)
			(type solid)
		)
		(fill yes)
		(layer "In13.Cu")
		(net "M_B_CPU1_SA_DQS_DN<2>")
	)
	(gr_poly
		(pts
			(xy 78.97495 -251.572522) (xy 78.97495 -251.528072) (xy 78.774798 -251.528072) (xy 78.774798 -251.572522)
			(xy 78.874874 -251.672598)
		)
		(stroke
			(width 0)
			(type solid)
		)
		(fill yes)
		(layer "In13.Cu")
		(net "M_B_CPU1_SA_CS_N<0>")
	)
	(gr_poly
		(pts
			(xy 78.97495 -240.636298) (xy 78.874874 -240.536222) (xy 78.774798 -240.636298) (xy 78.774798 -240.680748)
			(xy 78.97495 -240.680748)
		)
		(stroke
			(width 0)
			(type solid)
		)
		(fill yes)
		(layer "In13.Cu")
		(net "M_B_CPU1_SA_DQ<25>")
	)
	(gr_poly
		(pts
			(xy 78.981046 -250.35637) (xy 78.88097 -250.256294) (xy 78.780894 -250.35637) (xy 78.780894 -250.40082)
			(xy 78.981046 -250.40082)
		)
		(stroke
			(width 0)
			(type solid)
		)
		(fill yes)
		(layer "In13.Cu")
		(net "M_B_CPU1_ALERT_R_N")
	)
	(gr_poly
		(pts
			(xy 78.981046 -241.852704) (xy 78.981046 -241.804952) (xy 78.780894 -241.804952) (xy 78.780894 -241.852704)
			(xy 78.88097 -241.952526)
		)
		(stroke
			(width 0)
			(type solid)
		)
		(fill yes)
		(layer "In13.Cu")
		(net "M_B_CPU1_SA_DQS_DN<3>")
	)
	(gr_poly
		(pts
			(xy 78.98384 -255.216406) (xy 78.883764 -255.11633) (xy 78.783688 -255.216406) (xy 78.783688 -255.260856)
			(xy 78.98384 -255.260856)
		)
		(stroke
			(width 0)
			(type solid)
		)
		(fill yes)
		(layer "In13.Cu")
		(net "M_B_CPU1_SA_CA<6>")
	)
	(gr_poly
		(pts
			(xy 78.98384 -253.596394) (xy 78.883764 -253.496318) (xy 78.783688 -253.596394) (xy 78.783688 -253.640844)
			(xy 78.98384 -253.640844)
		)
		(stroke
			(width 0)
			(type solid)
		)
		(fill yes)
		(layer "In13.Cu")
		(net "M_B_CPU1_SA_CA<2>")
	)
	(gr_poly
		(pts
			(xy 78.98384 -248.736358) (xy 78.883764 -248.636282) (xy 78.783688 -248.736358) (xy 78.783688 -248.780808)
			(xy 78.98384 -248.780808)
		)
		(stroke
			(width 0)
			(type solid)
		)
		(fill yes)
		(layer "In13.Cu")
		(net "M_B_CPU1_SA_CB<5>")
	)
	(gr_poly
		(pts
			(xy 78.98384 -245.496334) (xy 78.883764 -245.396258) (xy 78.783688 -245.496334) (xy 78.783688 -245.540784)
			(xy 78.98384 -245.540784)
		)
		(stroke
			(width 0)
			(type solid)
		)
		(fill yes)
		(layer "In13.Cu")
		(net "M_B_CPU1_SA_CB<1>")
	)
	(gr_poly
		(pts
			(xy 78.98384 -243.876322) (xy 78.883764 -243.776246) (xy 78.783688 -243.876322) (xy 78.783688 -243.920772)
			(xy 78.98384 -243.920772)
		)
		(stroke
			(width 0)
			(type solid)
		)
		(fill yes)
		(layer "In13.Cu")
		(net "M_B_CPU1_SA_DQ<29>")
	)
	(gr_poly
		(pts
			(xy 78.98892 -247.116092) (xy 78.888844 -247.01627) (xy 78.789022 -247.116092) (xy 78.789022 -247.163844)
			(xy 78.98892 -247.163844)
		)
		(stroke
			(width 0)
			(type solid)
		)
		(fill yes)
		(layer "In13.Cu")
		(net "M_B_CPU1_SA_DQS_DN<9>")
	)
	(gr_poly
		(pts
			(xy 78.99273 -242.256056) (xy 78.892654 -242.15598) (xy 78.792578 -242.256056) (xy 78.792578 -242.303554)
			(xy 78.99273 -242.303554)
		)
		(stroke
			(width 0)
			(type solid)
		)
		(fill yes)
		(layer "In13.Cu")
		(net "M_B_CPU1_SA_DQS_DN<8>")
	)
	(gr_poly
		(pts
			(xy 78.995524 -224.045272) (xy 79.043784 -223.91243) (xy 78.910942 -223.86417) (xy 78.870556 -223.882966)
			(xy 78.955138 -224.064068)
		)
		(stroke
			(width 0)
			(type solid)
		)
		(fill yes)
		(layer "In13.Cu")
		(net "M_B_CPU1_SA_DQ<4>")
	)
	(gr_poly
		(pts
			(xy 79.00035 -222.41637) (xy 79.036926 -222.279718) (xy 78.900274 -222.243142) (xy 78.859126 -222.266764)
			(xy 78.959202 -222.439992)
		)
		(stroke
			(width 0)
			(type solid)
		)
		(fill yes)
		(layer "In13.Cu")
		(net "M_B_CPU1_SA_DQS_DN<5>")
	)
	(gr_poly
		(pts
			(xy 79.000604 -225.656902) (xy 79.03718 -225.520504) (xy 78.900528 -225.483928) (xy 78.862174 -225.506026)
			(xy 78.96225 -225.679254)
		)
		(stroke
			(width 0)
			(type solid)
		)
		(fill yes)
		(layer "In13.Cu")
		(net "M_B_CPU1_SA_DQ<5>")
	)
	(gr_poly
		(pts
			(xy 79.200248 -293.177468) (xy 79.16164 -293.155116) (xy 79.025242 -293.191692) (xy 79.061818 -293.328344)
			(xy 79.100172 -293.350696)
		)
		(stroke
			(width 0)
			(type solid)
		)
		(fill yes)
		(layer "In13.Cu")
		(net "M_B_CPU1_SB_DQ<28>")
	)
	(gr_poly
		(pts
			(xy 79.267304 -283.60497) (xy 79.267304 -283.56052) (xy 79.067152 -283.56052) (xy 79.067152 -283.60497)
			(xy 79.167228 -283.705046)
		)
		(stroke
			(width 0)
			(type solid)
		)
		(fill yes)
		(layer "In13.Cu")
		(net "M_B_CPU1_SB_DQ<15>")
	)
	(gr_poly
		(pts
			(xy 79.27213 -287.248092) (xy 79.172308 -287.14827) (xy 79.072232 -287.248092) (xy 79.072232 -287.292542)
			(xy 79.27213 -287.292542)
		)
		(stroke
			(width 0)
			(type solid)
		)
		(fill yes)
		(layer "In13.Cu")
		(net "M_B_CPU1_SB_DQ<20>")
	)
	(gr_poly
		(pts
			(xy 79.275178 -285.62808) (xy 79.175356 -285.528004) (xy 79.07528 -285.62808) (xy 79.07528 -285.675578)
			(xy 79.275178 -285.675578)
		)
		(stroke
			(width 0)
			(type solid)
		)
		(fill yes)
		(layer "In13.Cu")
		(net "M_B_CPU1_SB_DQS_DP<2>")
	)
	(gr_poly
		(pts
			(xy 79.275178 -280.768044) (xy 79.175356 -280.667968) (xy 79.07528 -280.768044) (xy 79.07528 -280.815542)
			(xy 79.275178 -280.815542)
		)
		(stroke
			(width 0)
			(type solid)
		)
		(fill yes)
		(layer "In13.Cu")
		(net "M_B_CPU1_SB_DQS_DP<1>")
	)
	(gr_poly
		(pts
			(xy 79.28102 -288.464498) (xy 79.28102 -288.420048) (xy 79.080868 -288.420048) (xy 79.080868 -288.464498)
			(xy 79.180944 -288.564574)
		)
		(stroke
			(width 0)
			(type solid)
		)
		(fill yes)
		(layer "In13.Cu")
		(net "M_B_CPU1_SB_DQ<23>")
	)
	(gr_poly
		(pts
			(xy 79.283814 -290.084256) (xy 79.283814 -290.039806) (xy 79.083662 -290.039806) (xy 79.083662 -290.084256)
			(xy 79.183738 -290.184332)
		)
		(stroke
			(width 0)
			(type solid)
		)
		(fill yes)
		(layer "In13.Cu")
		(net "M_B_CPU1_SB_DQ<27>")
	)
	(gr_poly
		(pts
			(xy 79.283814 -286.844486) (xy 79.283814 -286.796988) (xy 79.083662 -286.796988) (xy 79.083662 -286.844486)
			(xy 79.183738 -286.944562)
		)
		(stroke
			(width 0)
			(type solid)
		)
		(fill yes)
		(layer "In13.Cu")
		(net "M_B_CPU1_SB_DQS_DP<7>")
	)
	(gr_poly
		(pts
			(xy 79.283814 -285.224474) (xy 79.283814 -285.180024) (xy 79.083662 -285.180024) (xy 79.083662 -285.224474)
			(xy 79.183738 -285.32455)
		)
		(stroke
			(width 0)
			(type solid)
		)
		(fill yes)
		(layer "In13.Cu")
		(net "M_B_CPU1_SB_DQ<19>")
	)
	(gr_poly
		(pts
			(xy 79.283814 -284.008322) (xy 79.183738 -283.908246) (xy 79.083662 -284.008322) (xy 79.083662 -284.052772)
			(xy 79.283814 -284.052772)
		)
		(stroke
			(width 0)
			(type solid)
		)
		(fill yes)
		(layer "In13.Cu")
		(net "M_B_CPU1_SB_DQ<16>")
	)
	(gr_poly
		(pts
			(xy 79.283814 -282.38831) (xy 79.183738 -282.288234) (xy 79.083662 -282.38831) (xy 79.083662 -282.43276)
			(xy 79.283814 -282.43276)
		)
		(stroke
			(width 0)
			(type solid)
		)
		(fill yes)
		(layer "In13.Cu")
		(net "M_B_CPU1_SB_DQ<12>")
	)
	(gr_poly
		(pts
			(xy 79.283814 -279.148286) (xy 79.183738 -279.04821) (xy 79.083662 -279.148286) (xy 79.083662 -279.192736)
			(xy 79.283814 -279.192736)
		)
		(stroke
			(width 0)
			(type solid)
		)
		(fill yes)
		(layer "In13.Cu")
		(net "M_B_CPU1_SB_DQ<8>")
	)
	(gr_poly
		(pts
			(xy 79.283814 -277.528274) (xy 79.183738 -277.428198) (xy 79.083662 -277.528274) (xy 79.083662 -277.572724)
			(xy 79.283814 -277.572724)
		)
		(stroke
			(width 0)
			(type solid)
		)
		(fill yes)
		(layer "In13.Cu")
		(net "M_B_CPU1_SB_DQ<4>")
	)
	(gr_poly
		(pts
			(xy 79.283814 -274.28825) (xy 79.183738 -274.188174) (xy 79.083662 -274.28825) (xy 79.083662 -274.3327)
			(xy 79.283814 -274.3327)
		)
		(stroke
			(width 0)
			(type solid)
		)
		(fill yes)
		(layer "In13.Cu")
		(net "M_B_CPU1_SB_DQ<0>")
	)
	(gr_poly
		(pts
			(xy 79.283814 -273.88439) (xy 79.283814 -273.83994) (xy 79.083662 -273.83994) (xy 79.083662 -273.88439)
			(xy 79.183738 -273.984466)
		)
		(stroke
			(width 0)
			(type solid)
		)
		(fill yes)
		(layer "In13.Cu")
		(net "M_B_CPU1_SB_CB<3>")
	)
	(gr_poly
		(pts
			(xy 79.283814 -272.668238) (xy 79.183738 -272.568162) (xy 79.083662 -272.668238) (xy 79.083662 -272.712688)
			(xy 79.283814 -272.712688)
		)
		(stroke
			(width 0)
			(type solid)
		)
		(fill yes)
		(layer "In13.Cu")
		(net "M_B_CPU1_SB_CB<0>")
	)
	(gr_poly
		(pts
			(xy 79.283814 -264.568178) (xy 79.183738 -264.468102) (xy 79.083662 -264.568178) (xy 79.083662 -264.612628)
			(xy 79.283814 -264.612628)
		)
		(stroke
			(width 0)
			(type solid)
		)
		(fill yes)
		(layer "In13.Cu")
		(net "M_B_CPU1_SB_CA<6>")
	)
	(gr_poly
		(pts
			(xy 79.28991 -288.86785) (xy 79.189834 -288.768028) (xy 79.089758 -288.86785) (xy 79.089758 -288.9123)
			(xy 79.28991 -288.9123)
		)
		(stroke
			(width 0)
			(type solid)
		)
		(fill yes)
		(layer "In13.Cu")
		(net "M_B_CPU1_SB_DQ<24>")
	)
	(gr_poly
		(pts
			(xy 79.28991 -269.42796) (xy 79.189834 -269.328138) (xy 79.089758 -269.42796) (xy 79.089758 -269.47241)
			(xy 79.28991 -269.47241)
		)
		(stroke
			(width 0)
			(type solid)
		)
		(fill yes)
		(layer "In13.Cu")
		(net "M_B_CPU1_SB_CB<4>")
	)
	(gr_poly
		(pts
			(xy 79.29499 -267.801344) (xy 79.194914 -267.701268) (xy 79.095092 -267.801344) (xy 79.095092 -267.845794)
			(xy 79.29499 -267.845794)
		)
		(stroke
			(width 0)
			(type solid)
		)
		(fill yes)
		(layer "In13.Cu")
		(net "M_B_CPU1_SB_RSP<0>")
	)
	(gr_poly
		(pts
			(xy 79.3369 -295.481502) (xy 79.300324 -295.34485) (xy 79.261716 -295.322498) (xy 79.161894 -295.495726)
			(xy 79.200248 -295.518078)
		)
		(stroke
			(width 0)
			(type solid)
		)
		(fill yes)
		(layer "In13.Cu")
		(net "M_B_CPU1_SB_DQ<30>")
	)
	(gr_poly
		(pts
			(xy 79.36992 -225.392742) (xy 79.269844 -225.219514) (xy 79.23149 -225.241866) (xy 79.194914 -225.378264)
			(xy 79.331312 -225.41484)
		)
		(stroke
			(width 0)
			(type solid)
		)
		(fill yes)
		(layer "In13.Cu")
		(net "M_B_CPU1_SA_DQ<6>")
	)
	(gr_poly
		(pts
			(xy 79.372968 -223.771968) (xy 79.273146 -223.59874) (xy 79.231744 -223.622362) (xy 79.195168 -223.759014)
			(xy 79.33182 -223.79559)
		)
		(stroke
			(width 0)
			(type solid)
		)
		(fill yes)
		(layer "In13.Cu")
		(net "M_B_CPU1_SA_DQS_DP<5>")
	)
	(gr_poly
		(pts
			(xy 79.437992 -246.30634) (xy 79.33817 -246.206264) (xy 79.238094 -246.30634) (xy 79.238094 -246.353838)
			(xy 79.437992 -246.353838)
		)
		(stroke
			(width 0)
			(type solid)
		)
		(fill yes)
		(layer "In13.Cu")
		(net "M_B_CPU1_SA_DQS_DP<4>")
	)
	(gr_poly
		(pts
			(xy 79.437992 -236.586268) (xy 79.33817 -236.486192) (xy 79.238094 -236.586268) (xy 79.238094 -236.633766)
			(xy 79.437992 -236.633766)
		)
		(stroke
			(width 0)
			(type solid)
		)
		(fill yes)
		(layer "In13.Cu")
		(net "M_B_CPU1_SA_DQS_DP<2>")
	)
	(gr_poly
		(pts
			(xy 79.439262 -239.422432) (xy 79.439262 -239.377728) (xy 79.239364 -239.377728) (xy 79.239364 -239.422432)
			(xy 79.339186 -239.522254)
		)
		(stroke
			(width 0)
			(type solid)
		)
		(fill yes)
		(layer "In13.Cu")
		(net "M_B_CPU1_SA_DQ<23>")
	)
	(gr_poly
		(pts
			(xy 79.440278 -254.406654) (xy 79.340202 -254.306578) (xy 79.240126 -254.406654) (xy 79.240126 -254.451104)
			(xy 79.440278 -254.451104)
		)
		(stroke
			(width 0)
			(type solid)
		)
		(fill yes)
		(layer "In13.Cu")
		(net "M_B_CPU1_SA_CA<4>")
	)
	(gr_poly
		(pts
			(xy 79.440278 -252.786642) (xy 79.340202 -252.686566) (xy 79.240126 -252.786642) (xy 79.240126 -252.831092)
			(xy 79.440278 -252.831092)
		)
		(stroke
			(width 0)
			(type solid)
		)
		(fill yes)
		(layer "In13.Cu")
		(net "M_B_CPU1_SA_CA<0>")
	)
	(gr_poly
		(pts
			(xy 79.440278 -247.926606) (xy 79.340202 -247.82653) (xy 79.240126 -247.926606) (xy 79.240126 -247.971056)
			(xy 79.440278 -247.971056)
		)
		(stroke
			(width 0)
			(type solid)
		)
		(fill yes)
		(layer "In13.Cu")
		(net "M_B_CPU1_SA_CB<4>")
	)
	(gr_poly
		(pts
			(xy 79.440278 -244.686582) (xy 79.340202 -244.586506) (xy 79.240126 -244.686582) (xy 79.240126 -244.731032)
			(xy 79.440278 -244.731032)
		)
		(stroke
			(width 0)
			(type solid)
		)
		(fill yes)
		(layer "In13.Cu")
		(net "M_B_CPU1_SA_CB<0>")
	)
	(gr_poly
		(pts
			(xy 79.440278 -243.06657) (xy 79.340202 -242.966494) (xy 79.240126 -243.06657) (xy 79.240126 -243.11102)
			(xy 79.440278 -243.11102)
		)
		(stroke
			(width 0)
			(type solid)
		)
		(fill yes)
		(layer "In13.Cu")
		(net "M_B_CPU1_SA_DQ<28>")
	)
	(gr_poly
		(pts
			(xy 79.440278 -239.826546) (xy 79.340202 -239.72647) (xy 79.240126 -239.826546) (xy 79.240126 -239.870996)
			(xy 79.440278 -239.870996)
		)
		(stroke
			(width 0)
			(type solid)
		)
		(fill yes)
		(layer "In13.Cu")
		(net "M_B_CPU1_SA_DQ<24>")
	)
	(gr_poly
		(pts
			(xy 79.440278 -238.206534) (xy 79.340202 -238.106458) (xy 79.240126 -238.206534) (xy 79.240126 -238.250984)
			(xy 79.440278 -238.250984)
		)
		(stroke
			(width 0)
			(type solid)
		)
		(fill yes)
		(layer "In13.Cu")
		(net "M_B_CPU1_SA_DQ<20>")
	)
	(gr_poly
		(pts
			(xy 79.44231 -242.662964) (xy 79.44231 -242.615212) (xy 79.242412 -242.615212) (xy 79.242412 -242.662964)
			(xy 79.342488 -242.762786)
		)
		(stroke
			(width 0)
			(type solid)
		)
		(fill yes)
		(layer "In13.Cu")
		(net "M_B_CPU1_SA_DQS_DP<8>")
	)
	(gr_poly
		(pts
			(xy 79.4512 -250.762516) (xy 79.4512 -250.718066) (xy 79.251048 -250.718066) (xy 79.251048 -250.762516)
			(xy 79.351124 -250.862592)
		)
		(stroke
			(width 0)
			(type solid)
		)
		(fill yes)
		(layer "In13.Cu")
		(net "M_B_CPU1_RESET_N")
	)
	(gr_poly
		(pts
			(xy 79.4512 -241.44605) (xy 79.351124 -241.346228) (xy 79.251048 -241.44605) (xy 79.251048 -241.493802)
			(xy 79.4512 -241.493802)
		)
		(stroke
			(width 0)
			(type solid)
		)
		(fill yes)
		(layer "In13.Cu")
		(net "M_B_CPU1_SA_DQS_DP<3>")
	)
	(gr_poly
		(pts
			(xy 79.456534 -255.622552) (xy 79.456534 -255.578102) (xy 79.256382 -255.578102) (xy 79.256382 -255.622552)
			(xy 79.356458 -255.722628)
		)
		(stroke
			(width 0)
			(type solid)
		)
		(fill yes)
		(layer "In13.Cu")
		(net "M_B_CPU1_SA_PAR")
	)
	(gr_poly
		(pts
			(xy 79.456534 -254.00254) (xy 79.456534 -253.95809) (xy 79.256382 -253.95809) (xy 79.256382 -254.00254)
			(xy 79.356458 -254.102616)
		)
		(stroke
			(width 0)
			(type solid)
		)
		(fill yes)
		(layer "In13.Cu")
		(net "M_B_CPU1_SA_CA<3>")
	)
	(gr_poly
		(pts
			(xy 79.456534 -252.382528) (xy 79.456534 -252.338078) (xy 79.256382 -252.338078) (xy 79.256382 -252.382528)
			(xy 79.356458 -252.482604)
		)
		(stroke
			(width 0)
			(type solid)
		)
		(fill yes)
		(layer "In13.Cu")
		(net "M_B_CPU1_SA_CS_N<1>")
	)
	(gr_poly
		(pts
			(xy 79.456534 -249.142504) (xy 79.456534 -249.098054) (xy 79.256382 -249.098054) (xy 79.256382 -249.142504)
			(xy 79.356458 -249.24258)
		)
		(stroke
			(width 0)
			(type solid)
		)
		(fill yes)
		(layer "In13.Cu")
		(net "M_B_CPU1_SA_CB<7>")
	)
	(gr_poly
		(pts
			(xy 79.456534 -247.522746) (xy 79.456534 -247.475248) (xy 79.256382 -247.475248) (xy 79.256382 -247.522746)
			(xy 79.356458 -247.622822)
		)
		(stroke
			(width 0)
			(type solid)
		)
		(fill yes)
		(layer "In13.Cu")
		(net "M_B_CPU1_SA_DQS_DP<9>")
	)
	(gr_poly
		(pts
			(xy 79.456534 -245.90248) (xy 79.456534 -245.85803) (xy 79.256382 -245.85803) (xy 79.256382 -245.90248)
			(xy 79.356458 -246.002556)
		)
		(stroke
			(width 0)
			(type solid)
		)
		(fill yes)
		(layer "In13.Cu")
		(net "M_B_CPU1_SA_CB<3>")
	)
	(gr_poly
		(pts
			(xy 79.456534 -244.282468) (xy 79.456534 -244.238018) (xy 79.256382 -244.238018) (xy 79.256382 -244.282468)
			(xy 79.356458 -244.382544)
		)
		(stroke
			(width 0)
			(type solid)
		)
		(fill yes)
		(layer "In13.Cu")
		(net "M_B_CPU1_SA_DQ<31>")
	)
	(gr_poly
		(pts
			(xy 79.459074 -241.042444) (xy 79.459074 -240.997994) (xy 79.259176 -240.997994) (xy 79.259176 -241.042444)
			(xy 79.358998 -241.14252)
		)
		(stroke
			(width 0)
			(type solid)
		)
		(fill yes)
		(layer "In13.Cu")
		(net "M_B_CPU1_SA_DQ<27>")
	)
	(gr_poly
		(pts
			(xy 79.464916 -223.235266) (xy 79.51343 -223.102424) (xy 79.380334 -223.05391) (xy 79.337408 -223.07423)
			(xy 79.421736 -223.255332)
		)
		(stroke
			(width 0)
			(type solid)
		)
		(fill yes)
		(layer "In13.Cu")
		(net "M_B_CPU1_SA_DQS_DN<5>")
	)
	(gr_poly
		(pts
			(xy 79.46644 -256.026412) (xy 79.366364 -255.926336) (xy 79.266542 -256.026412) (xy 79.266542 -256.07391)
			(xy 79.46644 -256.07391)
		)
		(stroke
			(width 0)
			(type solid)
		)
		(fill yes)
		(layer "In13.Cu")
		(net "M_B_CPU1_CLK_DP<0>")
	)
	(gr_poly
		(pts
			(xy 79.469742 -226.465892) (xy 79.506318 -226.32924) (xy 79.369666 -226.292664) (xy 79.331312 -226.314762)
			(xy 79.431388 -226.48799)
		)
		(stroke
			(width 0)
			(type solid)
		)
		(fill yes)
		(layer "In13.Cu")
		(net "M_B_CPU1_SA_DQ<5>")
	)
	(gr_poly
		(pts
			(xy 79.469996 -224.84588) (xy 79.506572 -224.709228) (xy 79.36992 -224.672652) (xy 79.331566 -224.695004)
			(xy 79.431642 -224.868232)
		)
		(stroke
			(width 0)
			(type solid)
		)
		(fill yes)
		(layer "In13.Cu")
		(net "M_B_CPU1_SA_DQ<4>")
	)
	(gr_poly
		(pts
			(xy 79.670148 -292.367462) (xy 79.63154 -292.34511) (xy 79.495142 -292.381686) (xy 79.531718 -292.518338)
			(xy 79.570072 -292.54069)
		)
		(stroke
			(width 0)
			(type solid)
		)
		(fill yes)
		(layer "In13.Cu")
		(net "M_B_CPU1_SB_DQ<28>")
	)
	(gr_poly
		(pts
			(xy 79.670402 -295.607486) (xy 79.631794 -295.585134) (xy 79.495142 -295.62171) (xy 79.531972 -295.758362)
			(xy 79.570326 -295.780714)
		)
		(stroke
			(width 0)
			(type solid)
		)
		(fill yes)
		(layer "In13.Cu")
		(net "M_B_CPU1_SB_DQ<29>")
	)
	(gr_poly
		(pts
			(xy 79.739236 -283.198316) (xy 79.63916 -283.098494) (xy 79.539338 -283.198316) (xy 79.539338 -283.24302)
			(xy 79.739236 -283.24302)
		)
		(stroke
			(width 0)
			(type solid)
		)
		(fill yes)
		(layer "In13.Cu")
		(net "M_B_CPU1_SB_DQ<13>")
	)
	(gr_poly
		(pts
			(xy 79.742284 -289.274504) (xy 79.742284 -289.230054) (xy 79.542386 -289.230054) (xy 79.542386 -289.274504)
			(xy 79.642462 -289.37458)
		)
		(stroke
			(width 0)
			(type solid)
		)
		(fill yes)
		(layer "In13.Cu")
		(net "M_B_CPU1_SB_DQ<26>")
	)
	(gr_poly
		(pts
			(xy 79.742284 -269.834614) (xy 79.742284 -269.790164) (xy 79.542386 -269.790164) (xy 79.542386 -269.834614)
			(xy 79.642462 -269.934436)
		)
		(stroke
			(width 0)
			(type solid)
		)
		(fill yes)
		(layer "In13.Cu")
		(net "M_B_CPU1_SB_CB<6>")
	)
	(gr_poly
		(pts
			(xy 79.745078 -286.034734) (xy 79.745078 -285.986982) (xy 79.54518 -285.986982) (xy 79.54518 -286.034734)
			(xy 79.645256 -286.134556)
		)
		(stroke
			(width 0)
			(type solid)
		)
		(fill yes)
		(layer "In13.Cu")
		(net "M_B_CPU1_SB_DQS_DN<2>")
	)
	(gr_poly
		(pts
			(xy 79.745078 -281.174698) (xy 79.745078 -281.126946) (xy 79.54518 -281.126946) (xy 79.54518 -281.174698)
			(xy 79.645256 -281.27452)
		)
		(stroke
			(width 0)
			(type solid)
		)
		(fill yes)
		(layer "In13.Cu")
		(net "M_B_CPU1_SB_DQS_DN<1>")
	)
	(gr_poly
		(pts
			(xy 79.751174 -288.058098) (xy 79.651098 -287.958022) (xy 79.551022 -288.058098) (xy 79.551022 -288.102548)
			(xy 79.751174 -288.102548)
		)
		(stroke
			(width 0)
			(type solid)
		)
		(fill yes)
		(layer "In13.Cu")
		(net "M_B_CPU1_SB_DQ<21>")
	)
	(gr_poly
		(pts
			(xy 79.756508 -284.414468) (xy 79.756508 -284.370018) (xy 79.55661 -284.370018) (xy 79.55661 -284.414468)
			(xy 79.656432 -284.514544)
		)
		(stroke
			(width 0)
			(type solid)
		)
		(fill yes)
		(layer "In13.Cu")
		(net "M_B_CPU1_SB_DQ<18>")
	)
	(gr_poly
		(pts
			(xy 79.756508 -282.794456) (xy 79.756508 -282.750006) (xy 79.55661 -282.750006) (xy 79.55661 -282.794456)
			(xy 79.656432 -282.894532)
		)
		(stroke
			(width 0)
			(type solid)
		)
		(fill yes)
		(layer "In13.Cu")
		(net "M_B_CPU1_SB_DQ<14>")
	)
	(gr_poly
		(pts
			(xy 79.756508 -279.554432) (xy 79.756508 -279.509982) (xy 79.55661 -279.509982) (xy 79.55661 -279.554432)
			(xy 79.656432 -279.654508)
		)
		(stroke
			(width 0)
			(type solid)
		)
		(fill yes)
		(layer "In13.Cu")
		(net "M_B_CPU1_SB_DQ<10>")
	)
	(gr_poly
		(pts
			(xy 79.756508 -277.93442) (xy 79.756508 -277.88997) (xy 79.55661 -277.88997) (xy 79.55661 -277.93442)
			(xy 79.656432 -278.034496)
		)
		(stroke
			(width 0)
			(type solid)
		)
		(fill yes)
		(layer "In13.Cu")
		(net "M_B_CPU1_SB_DQ<6>")
	)
	(gr_poly
		(pts
			(xy 79.756508 -274.694396) (xy 79.756508 -274.649946) (xy 79.55661 -274.649946) (xy 79.55661 -274.694396)
			(xy 79.656432 -274.794472)
		)
		(stroke
			(width 0)
			(type solid)
		)
		(fill yes)
		(layer "In13.Cu")
		(net "M_B_CPU1_SB_DQ<2>")
	)
	(gr_poly
		(pts
			(xy 79.756508 -273.074384) (xy 79.756508 -273.029934) (xy 79.55661 -273.029934) (xy 79.55661 -273.074384)
			(xy 79.656432 -273.17446)
		)
		(stroke
			(width 0)
			(type solid)
		)
		(fill yes)
		(layer "In13.Cu")
		(net "M_B_CPU1_SB_CB<2>")
	)
	(gr_poly
		(pts
			(xy 79.756508 -264.974324) (xy 79.756508 -264.929874) (xy 79.55661 -264.929874) (xy 79.55661 -264.974324)
			(xy 79.656432 -265.0744)
		)
		(stroke
			(width 0)
			(type solid)
		)
		(fill yes)
		(layer "In13.Cu")
		(net "M_B_CPU1_SB_PAR")
	)
	(gr_poly
		(pts
			(xy 79.758794 -289.677856) (xy 79.658718 -289.57778) (xy 79.558896 -289.677856) (xy 79.558896 -289.722306)
			(xy 79.758794 -289.722306)
		)
		(stroke
			(width 0)
			(type solid)
		)
		(fill yes)
		(layer "In13.Cu")
		(net "M_B_CPU1_SB_DQ<25>")
	)
	(gr_poly
		(pts
			(xy 79.758794 -286.437832) (xy 79.658718 -286.337756) (xy 79.558896 -286.437832) (xy 79.558896 -286.485584)
			(xy 79.758794 -286.485584)
		)
		(stroke
			(width 0)
			(type solid)
		)
		(fill yes)
		(layer "In13.Cu")
		(net "M_B_CPU1_SB_DQS_DN<7>")
	)
	(gr_poly
		(pts
			(xy 79.758794 -284.818074) (xy 79.658718 -284.718252) (xy 79.558896 -284.818074) (xy 79.558896 -284.862524)
			(xy 79.758794 -284.862524)
		)
		(stroke
			(width 0)
			(type solid)
		)
		(fill yes)
		(layer "In13.Cu")
		(net "M_B_CPU1_SB_DQ<17>")
	)
	(gr_poly
		(pts
			(xy 79.758794 -273.47799) (xy 79.658718 -273.378168) (xy 79.558896 -273.47799) (xy 79.558896 -273.52244)
			(xy 79.758794 -273.52244)
		)
		(stroke
			(width 0)
			(type solid)
		)
		(fill yes)
		(layer "In13.Cu")
		(net "M_B_CPU1_SB_CB<1>")
	)
	(gr_poly
		(pts
			(xy 79.76108 -287.654492) (xy 79.76108 -287.610042) (xy 79.561182 -287.610042) (xy 79.561182 -287.654492)
			(xy 79.661004 -287.754568)
		)
		(stroke
			(width 0)
			(type solid)
		)
		(fill yes)
		(layer "In13.Cu")
		(net "M_B_CPU1_SB_DQ<22>")
	)
	(gr_poly
		(pts
			(xy 79.806546 -294.672004) (xy 79.76997 -294.535352) (xy 79.731362 -294.513254) (xy 79.631286 -294.686482)
			(xy 79.669894 -294.70858)
		)
		(stroke
			(width 0)
			(type solid)
		)
		(fill yes)
		(layer "In13.Cu")
		(net "M_B_CPU1_SB_DQ<30>")
	)
	(gr_poly
		(pts
			(xy 79.840328 -231.063292) (xy 79.740252 -230.890064) (xy 79.701898 -230.912416) (xy 79.665322 -231.049068)
			(xy 79.80172 -231.085644)
		)
		(stroke
			(width 0)
			(type solid)
		)
		(fill yes)
		(layer "In13.Cu")
		(net "M_B_CPU1_SA_DQ<11>")
	)
	(gr_poly
		(pts
			(xy 79.841344 -226.20478) (xy 79.741268 -226.031552) (xy 79.70266 -226.05365) (xy 79.666084 -226.190302)
			(xy 79.802736 -226.226878)
		)
		(stroke
			(width 0)
			(type solid)
		)
		(fill yes)
		(layer "In13.Cu")
		(net "M_B_CPU1_SA_DQ<6>")
	)
	(gr_poly
		(pts
			(xy 79.843376 -222.96247) (xy 79.743554 -222.789242) (xy 79.702152 -222.813118) (xy 79.665576 -222.949516)
			(xy 79.802228 -222.986092)
		)
		(stroke
			(width 0)
			(type solid)
		)
		(fill yes)
		(layer "In13.Cu")
		(net "M_B_CPU1_SA_DQS_DN<0>")
	)
	(gr_poly
		(pts
			(xy 79.844138 -224.583752) (xy 79.744316 -224.410524) (xy 79.702914 -224.4344) (xy 79.666338 -224.571052)
			(xy 79.80299 -224.607628)
		)
		(stroke
			(width 0)
			(type solid)
		)
		(fill yes)
		(layer "In13.Cu")
		(net "M_B_CPU1_SA_DQS_DP<5>")
	)
	(gr_poly
		(pts
			(xy 79.91475 -255.216406) (xy 79.814928 -255.11633) (xy 79.714852 -255.216406) (xy 79.714852 -255.260856)
			(xy 79.91475 -255.260856)
		)
		(stroke
			(width 0)
			(type solid)
		)
		(fill yes)
		(layer "In13.Cu")
		(net "M_B_CPU1_SA_CA<6>")
	)
	(gr_poly
		(pts
			(xy 79.91475 -253.596394) (xy 79.814928 -253.496318) (xy 79.714852 -253.596394) (xy 79.714852 -253.640844)
			(xy 79.91475 -253.640844)
		)
		(stroke
			(width 0)
			(type solid)
		)
		(fill yes)
		(layer "In13.Cu")
		(net "M_B_CPU1_SA_CA<2>")
	)
	(gr_poly
		(pts
			(xy 79.91475 -251.572522) (xy 79.91475 -251.528072) (xy 79.714852 -251.528072) (xy 79.714852 -251.572522)
			(xy 79.814928 -251.672598)
		)
		(stroke
			(width 0)
			(type solid)
		)
		(fill yes)
		(layer "In13.Cu")
		(net "M_B_CPU1_SA_CS_N<0>")
	)
	(gr_poly
		(pts
			(xy 79.91475 -248.736358) (xy 79.814928 -248.636282) (xy 79.714852 -248.736358) (xy 79.714852 -248.780808)
			(xy 79.91475 -248.780808)
		)
		(stroke
			(width 0)
			(type solid)
		)
		(fill yes)
		(layer "In13.Cu")
		(net "M_B_CPU1_SA_CB<5>")
	)
	(gr_poly
		(pts
			(xy 79.91475 -247.116092) (xy 79.814928 -247.016016) (xy 79.714852 -247.116092) (xy 79.714852 -247.16359)
			(xy 79.91475 -247.16359)
		)
		(stroke
			(width 0)
			(type solid)
		)
		(fill yes)
		(layer "In13.Cu")
		(net "M_B_CPU1_SA_DQS_DN<9>")
	)
	(gr_poly
		(pts
			(xy 79.91475 -245.496334) (xy 79.814928 -245.396258) (xy 79.714852 -245.496334) (xy 79.714852 -245.540784)
			(xy 79.91475 -245.540784)
		)
		(stroke
			(width 0)
			(type solid)
		)
		(fill yes)
		(layer "In13.Cu")
		(net "M_B_CPU1_SA_CB<1>")
	)
	(gr_poly
		(pts
			(xy 79.91475 -243.876322) (xy 79.814928 -243.776246) (xy 79.714852 -243.876322) (xy 79.714852 -243.920772)
			(xy 79.91475 -243.920772)
		)
		(stroke
			(width 0)
			(type solid)
		)
		(fill yes)
		(layer "In13.Cu")
		(net "M_B_CPU1_SA_DQ<29>")
	)
	(gr_poly
		(pts
			(xy 79.91475 -240.636298) (xy 79.814928 -240.536222) (xy 79.714852 -240.636298) (xy 79.714852 -240.680748)
			(xy 79.91475 -240.680748)
		)
		(stroke
			(width 0)
			(type solid)
		)
		(fill yes)
		(layer "In13.Cu")
		(net "M_B_CPU1_SA_DQ<25>")
	)
	(gr_poly
		(pts
			(xy 79.91475 -235.776262) (xy 79.814928 -235.676186) (xy 79.714852 -235.776262) (xy 79.714852 -235.820712)
			(xy 79.91475 -235.820712)
		)
		(stroke
			(width 0)
			(type solid)
		)
		(fill yes)
		(layer "In13.Cu")
		(net "M_B_CPU1_SA_DQ<17>")
	)
	(gr_poly
		(pts
			(xy 79.9211 -256.432812) (xy 79.9211 -256.38506) (xy 79.720948 -256.38506) (xy 79.720948 -256.432812)
			(xy 79.821024 -256.532634)
		)
		(stroke
			(width 0)
			(type solid)
		)
		(fill yes)
		(layer "In13.Cu")
		(net "M_B_CPU1_CLK_DN<0>")
	)
	(gr_poly
		(pts
			(xy 79.9211 -250.35637) (xy 79.821024 -250.256294) (xy 79.720948 -250.35637) (xy 79.720948 -250.40082)
			(xy 79.9211 -250.40082)
		)
		(stroke
			(width 0)
			(type solid)
		)
		(fill yes)
		(layer "In13.Cu")
		(net "M_B_CPU1_ALERT_R_N")
	)
	(gr_poly
		(pts
			(xy 79.9211 -242.256056) (xy 79.821024 -242.156234) (xy 79.720948 -242.256056) (xy 79.720948 -242.303808)
			(xy 79.9211 -242.303808)
		)
		(stroke
			(width 0)
			(type solid)
		)
		(fill yes)
		(layer "In13.Cu")
		(net "M_B_CPU1_SA_DQS_DN<8>")
	)
	(gr_poly
		(pts
			(xy 79.9211 -241.852704) (xy 79.9211 -241.804952) (xy 79.720948 -241.804952) (xy 79.720948 -241.852704)
			(xy 79.821024 -241.952526)
		)
		(stroke
			(width 0)
			(type solid)
		)
		(fill yes)
		(layer "In13.Cu")
		(net "M_B_CPU1_SA_DQS_DN<3>")
	)
	(gr_poly
		(pts
			(xy 79.9211 -232.132632) (xy 79.9211 -232.08488) (xy 79.720948 -232.08488) (xy 79.720948 -232.132632)
			(xy 79.821024 -232.232454)
		)
		(stroke
			(width 0)
			(type solid)
		)
		(fill yes)
		(layer "In13.Cu")
		(net "M_B_CPU1_SA_DQS_DN<1>")
	)
	(gr_poly
		(pts
			(xy 79.934308 -254.812292) (xy 79.934308 -254.767842) (xy 79.734156 -254.767842) (xy 79.734156 -254.812292)
			(xy 79.834232 -254.912368)
		)
		(stroke
			(width 0)
			(type solid)
		)
		(fill yes)
		(layer "In13.Cu")
		(net "M_B_CPU1_SA_CA<5>")
	)
	(gr_poly
		(pts
			(xy 79.934308 -253.19228) (xy 79.934308 -253.14783) (xy 79.734156 -253.14783) (xy 79.734156 -253.19228)
			(xy 79.834232 -253.292356)
		)
		(stroke
			(width 0)
			(type solid)
		)
		(fill yes)
		(layer "In13.Cu")
		(net "M_B_CPU1_SA_CA<1>")
	)
	(gr_poly
		(pts
			(xy 79.934308 -248.332244) (xy 79.934308 -248.287794) (xy 79.734156 -248.287794) (xy 79.734156 -248.332244)
			(xy 79.834232 -248.43232)
		)
		(stroke
			(width 0)
			(type solid)
		)
		(fill yes)
		(layer "In13.Cu")
		(net "M_B_CPU1_SA_CB<6>")
	)
	(gr_poly
		(pts
			(xy 79.934308 -245.09222) (xy 79.934308 -245.04777) (xy 79.734156 -245.04777) (xy 79.734156 -245.09222)
			(xy 79.834232 -245.192296)
		)
		(stroke
			(width 0)
			(type solid)
		)
		(fill yes)
		(layer "In13.Cu")
		(net "M_B_CPU1_SA_CB<2>")
	)
	(gr_poly
		(pts
			(xy 79.934308 -243.472208) (xy 79.934308 -243.427758) (xy 79.734156 -243.427758) (xy 79.734156 -243.472208)
			(xy 79.834232 -243.572284)
		)
		(stroke
			(width 0)
			(type solid)
		)
		(fill yes)
		(layer "In13.Cu")
		(net "M_B_CPU1_SA_DQ<30>")
	)
	(gr_poly
		(pts
			(xy 79.934308 -240.232184) (xy 79.934308 -240.187734) (xy 79.734156 -240.187734) (xy 79.734156 -240.232184)
			(xy 79.834232 -240.33226)
		)
		(stroke
			(width 0)
			(type solid)
		)
		(fill yes)
		(layer "In13.Cu")
		(net "M_B_CPU1_SA_DQ<26>")
	)
	(gr_poly
		(pts
			(xy 79.934308 -238.612172) (xy 79.934308 -238.567722) (xy 79.734156 -238.567722) (xy 79.734156 -238.612172)
			(xy 79.834232 -238.712248)
		)
		(stroke
			(width 0)
			(type solid)
		)
		(fill yes)
		(layer "In13.Cu")
		(net "M_B_CPU1_SA_DQ<22>")
	)
	(gr_poly
		(pts
			(xy 79.934308 -235.372148) (xy 79.934308 -235.327698) (xy 79.734156 -235.327698) (xy 79.734156 -235.372148)
			(xy 79.834232 -235.472224)
		)
		(stroke
			(width 0)
			(type solid)
		)
		(fill yes)
		(layer "In13.Cu")
		(net "M_B_CPU1_SA_DQ<18>")
	)
	(gr_poly
		(pts
			(xy 79.934308 -233.752136) (xy 79.934308 -233.707686) (xy 79.734156 -233.707686) (xy 79.734156 -233.752136)
			(xy 79.834232 -233.852212)
		)
		(stroke
			(width 0)
			(type solid)
		)
		(fill yes)
		(layer "In13.Cu")
		(net "M_B_CPU1_SA_DQ<14>")
	)
	(gr_poly
		(pts
			(xy 79.935578 -239.01654) (xy 79.835756 -238.916464) (xy 79.73568 -239.01654) (xy 79.73568 -239.060736)
			(xy 79.935578 -239.060736)
		)
		(stroke
			(width 0)
			(type solid)
		)
		(fill yes)
		(layer "In13.Cu")
		(net "M_B_CPU1_SA_DQ<21>")
	)
	(gr_poly
		(pts
			(xy 79.93634 -246.712486) (xy 79.93634 -246.664988) (xy 79.736442 -246.664988) (xy 79.736442 -246.712486)
			(xy 79.836264 -246.812562)
		)
		(stroke
			(width 0)
			(type solid)
		)
		(fill yes)
		(layer "In13.Cu")
		(net "M_B_CPU1_SA_DQS_DN<4>")
	)
	(gr_poly
		(pts
			(xy 79.93634 -236.992414) (xy 79.93634 -236.944916) (xy 79.736442 -236.944916) (xy 79.736442 -236.992414)
			(xy 79.836264 -237.09249)
		)
		(stroke
			(width 0)
			(type solid)
		)
		(fill yes)
		(layer "In13.Cu")
		(net "M_B_CPU1_SA_DQS_DN<2>")
	)
	(gr_poly
		(pts
			(xy 79.939388 -227.274882) (xy 79.975964 -227.138484) (xy 79.839312 -227.101654) (xy 79.800704 -227.124006)
			(xy 79.90078 -227.297234)
		)
		(stroke
			(width 0)
			(type solid)
		)
		(fill yes)
		(layer "In13.Cu")
		(net "M_B_CPU1_SA_DQ<5>")
	)
	(gr_poly
		(pts
			(xy 79.939642 -224.03562) (xy 79.976472 -223.898968) (xy 79.83982 -223.862392) (xy 79.798418 -223.886268)
			(xy 79.898494 -224.059496)
		)
		(stroke
			(width 0)
			(type solid)
		)
		(fill yes)
		(layer "In13.Cu")
		(net "M_B_CPU1_SA_DQS_DN<5>")
	)
	(gr_poly
		(pts
			(xy 79.939896 -230.515414) (xy 79.976472 -230.378762) (xy 79.83982 -230.342186) (xy 79.801212 -230.364284)
			(xy 79.901288 -230.537512)
		)
		(stroke
			(width 0)
			(type solid)
		)
		(fill yes)
		(layer "In13.Cu")
		(net "M_B_CPU1_SA_DQ<9>")
	)
	(gr_poly
		(pts
			(xy 79.94015 -225.655886) (xy 79.976726 -225.519234) (xy 79.840074 -225.482658) (xy 79.80172 -225.50501)
			(xy 79.901542 -225.678238)
		)
		(stroke
			(width 0)
			(type solid)
		)
		(fill yes)
		(layer "In13.Cu")
		(net "M_B_CPU1_SA_DQ<4>")
	)
	(gr_poly
		(pts
			(xy 79.940404 -228.896672) (xy 79.977234 -228.76002) (xy 79.840582 -228.723444) (xy 79.801974 -228.745796)
			(xy 79.90205 -228.919024)
		)
		(stroke
			(width 0)
			(type solid)
		)
		(fill yes)
		(layer "In13.Cu")
		(net "M_B_CPU1_SA_DQ<8>")
	)
	(gr_poly
		(pts
			(xy 79.940912 -222.416624) (xy 79.977488 -222.279972) (xy 79.840836 -222.243396) (xy 79.799688 -222.267272)
			(xy 79.89951 -222.4405)
		)
		(stroke
			(width 0)
			(type solid)
		)
		(fill yes)
		(layer "In13.Cu")
		(net "M_B_CPU1_SA_DQS_DP<0>")
	)
	(gr_poly
		(pts
			(xy 80.141318 -294.795956) (xy 80.10271 -294.773858) (xy 79.966058 -294.810434) (xy 80.002634 -294.947086)
			(xy 80.041242 -294.969184)
		)
		(stroke
			(width 0)
			(type solid)
		)
		(fill yes)
		(layer "In13.Cu")
		(net "M_B_CPU1_SB_DQ<29>")
	)
	(gr_poly
		(pts
			(xy 80.212184 -290.08451) (xy 80.212184 -290.04006) (xy 80.012286 -290.04006) (xy 80.012286 -290.08451)
			(xy 80.112362 -290.184332)
		)
		(stroke
			(width 0)
			(type solid)
		)
		(fill yes)
		(layer "In13.Cu")
		(net "M_B_CPU1_SB_DQ<27>")
	)
	(gr_poly
		(pts
			(xy 80.212184 -286.84474) (xy 80.212184 -286.796988) (xy 80.012286 -286.796988) (xy 80.012286 -286.84474)
			(xy 80.112362 -286.944816)
		)
		(stroke
			(width 0)
			(type solid)
		)
		(fill yes)
		(layer "In13.Cu")
		(net "M_B_CPU1_SB_DQS_DP<7>")
	)
	(gr_poly
		(pts
			(xy 80.212184 -285.224728) (xy 80.212184 -285.180278) (xy 80.012286 -285.180278) (xy 80.012286 -285.224728)
			(xy 80.112362 -285.324804)
		)
		(stroke
			(width 0)
			(type solid)
		)
		(fill yes)
		(layer "In13.Cu")
		(net "M_B_CPU1_SB_DQ<19>")
	)
	(gr_poly
		(pts
			(xy 80.212184 -280.364692) (xy 80.212184 -280.320242) (xy 80.012286 -280.320242) (xy 80.012286 -280.364692)
			(xy 80.112362 -280.464768)
		)
		(stroke
			(width 0)
			(type solid)
		)
		(fill yes)
		(layer "In13.Cu")
		(net "M_B_CPU1_SB_DQ<11>")
	)
	(gr_poly
		(pts
			(xy 80.212184 -277.124922) (xy 80.212184 -277.07717) (xy 80.012286 -277.07717) (xy 80.012286 -277.124922)
			(xy 80.112362 -277.224744)
		)
		(stroke
			(width 0)
			(type solid)
		)
		(fill yes)
		(layer "In13.Cu")
		(net "M_B_CPU1_SB_DQS_DP<5>")
	)
	(gr_poly
		(pts
			(xy 80.212184 -275.504656) (xy 80.212184 -275.460206) (xy 80.012286 -275.460206) (xy 80.012286 -275.504656)
			(xy 80.112362 -275.604732)
		)
		(stroke
			(width 0)
			(type solid)
		)
		(fill yes)
		(layer "In13.Cu")
		(net "M_B_CPU1_SB_DQ<3>")
	)
	(gr_poly
		(pts
			(xy 80.212184 -273.884644) (xy 80.212184 -273.840194) (xy 80.012286 -273.840194) (xy 80.012286 -273.884644)
			(xy 80.112362 -273.98472)
		)
		(stroke
			(width 0)
			(type solid)
		)
		(fill yes)
		(layer "In13.Cu")
		(net "M_B_CPU1_SB_CB<3>")
	)
	(gr_poly
		(pts
			(xy 80.212184 -272.264886) (xy 80.212184 -272.217134) (xy 80.012286 -272.217134) (xy 80.012286 -272.264886)
			(xy 80.112362 -272.364708)
		)
		(stroke
			(width 0)
			(type solid)
		)
		(fill yes)
		(layer "In13.Cu")
		(net "M_B_CPU1_SB_DQS_DP<4>")
	)
	(gr_poly
		(pts
			(xy 80.212184 -270.64462) (xy 80.212184 -270.60017) (xy 80.012286 -270.60017) (xy 80.012286 -270.64462)
			(xy 80.112362 -270.744696)
		)
		(stroke
			(width 0)
			(type solid)
		)
		(fill yes)
		(layer "In13.Cu")
		(net "M_B_CPU1_SB_CB<7>")
	)
	(gr_poly
		(pts
			(xy 80.212184 -265.784584) (xy 80.212184 -265.740134) (xy 80.012286 -265.740134) (xy 80.012286 -265.784584)
			(xy 80.112362 -265.88466)
		)
		(stroke
			(width 0)
			(type solid)
		)
		(fill yes)
		(layer "In13.Cu")
		(net "M_B_CPU1_SB_CS_N<0>")
	)
	(gr_poly
		(pts
			(xy 80.212184 -264.164572) (xy 80.212184 -264.120122) (xy 80.012286 -264.120122) (xy 80.012286 -264.164572)
			(xy 80.112362 -264.264648)
		)
		(stroke
			(width 0)
			(type solid)
		)
		(fill yes)
		(layer "In13.Cu")
		(net "M_B_CPU1_SB_CA<5>")
	)
	(gr_poly
		(pts
			(xy 80.212184 -262.54456) (xy 80.212184 -262.50011) (xy 80.012286 -262.50011) (xy 80.012286 -262.54456)
			(xy 80.112362 -262.644636)
		)
		(stroke
			(width 0)
			(type solid)
		)
		(fill yes)
		(layer "In13.Cu")
		(net "M_B_CPU1_SB_CA<1>")
	)
	(gr_poly
		(pts
			(xy 80.214216 -281.98445) (xy 80.214216 -281.936698) (xy 80.014318 -281.936698) (xy 80.014318 -281.98445)
			(xy 80.11414 -282.084272)
		)
		(stroke
			(width 0)
			(type solid)
		)
		(fill yes)
		(layer "In13.Cu")
		(net "M_B_CPU1_SB_DQS_DP<6>")
	)
	(gr_poly
		(pts
			(xy 80.214978 -287.248092) (xy 80.114902 -287.148016) (xy 80.014826 -287.248092) (xy 80.014826 -287.292542)
			(xy 80.214978 -287.292542)
		)
		(stroke
			(width 0)
			(type solid)
		)
		(fill yes)
		(layer "In13.Cu")
		(net "M_B_CPU1_SB_DQ<20>")
	)
	(gr_poly
		(pts
			(xy 80.214978 -284.008322) (xy 80.114902 -283.908246) (xy 80.014826 -284.008322) (xy 80.014826 -284.052772)
			(xy 80.214978 -284.052772)
		)
		(stroke
			(width 0)
			(type solid)
		)
		(fill yes)
		(layer "In13.Cu")
		(net "M_B_CPU1_SB_DQ<16>")
	)
	(gr_poly
		(pts
			(xy 80.214978 -282.38831) (xy 80.114902 -282.288234) (xy 80.014826 -282.38831) (xy 80.014826 -282.43276)
			(xy 80.214978 -282.43276)
		)
		(stroke
			(width 0)
			(type solid)
		)
		(fill yes)
		(layer "In13.Cu")
		(net "M_B_CPU1_SB_DQ<12>")
	)
	(gr_poly
		(pts
			(xy 80.214978 -279.148286) (xy 80.114902 -279.04821) (xy 80.014826 -279.148286) (xy 80.014826 -279.192736)
			(xy 80.214978 -279.192736)
		)
		(stroke
			(width 0)
			(type solid)
		)
		(fill yes)
		(layer "In13.Cu")
		(net "M_B_CPU1_SB_DQ<8>")
	)
	(gr_poly
		(pts
			(xy 80.214978 -278.744426) (xy 80.214978 -278.699976) (xy 80.014826 -278.699976) (xy 80.014826 -278.744426)
			(xy 80.114902 -278.844502)
		)
		(stroke
			(width 0)
			(type solid)
		)
		(fill yes)
		(layer "In13.Cu")
		(net "M_B_CPU1_SB_DQ<7>")
	)
	(gr_poly
		(pts
			(xy 80.214978 -277.528274) (xy 80.114902 -277.428198) (xy 80.014826 -277.528274) (xy 80.014826 -277.572724)
			(xy 80.214978 -277.572724)
		)
		(stroke
			(width 0)
			(type solid)
		)
		(fill yes)
		(layer "In13.Cu")
		(net "M_B_CPU1_SB_DQ<4>")
	)
	(gr_poly
		(pts
			(xy 80.214978 -275.908008) (xy 80.114902 -275.807932) (xy 80.014826 -275.908008) (xy 80.014826 -275.955506)
			(xy 80.214978 -275.955506)
		)
		(stroke
			(width 0)
			(type solid)
		)
		(fill yes)
		(layer "In13.Cu")
		(net "M_B_CPU1_SB_DQS_DP<0>")
	)
	(gr_poly
		(pts
			(xy 80.214978 -274.28825) (xy 80.114902 -274.188174) (xy 80.014826 -274.28825) (xy 80.014826 -274.3327)
			(xy 80.214978 -274.3327)
		)
		(stroke
			(width 0)
			(type solid)
		)
		(fill yes)
		(layer "In13.Cu")
		(net "M_B_CPU1_SB_DQ<0>")
	)
	(gr_poly
		(pts
			(xy 80.214978 -272.668238) (xy 80.114902 -272.568162) (xy 80.014826 -272.668238) (xy 80.014826 -272.712688)
			(xy 80.214978 -272.712688)
		)
		(stroke
			(width 0)
			(type solid)
		)
		(fill yes)
		(layer "In13.Cu")
		(net "M_B_CPU1_SB_CB<0>")
	)
	(gr_poly
		(pts
			(xy 80.214978 -271.047972) (xy 80.114902 -270.947896) (xy 80.014826 -271.047972) (xy 80.014826 -271.09547)
			(xy 80.214978 -271.09547)
		)
		(stroke
			(width 0)
			(type solid)
		)
		(fill yes)
		(layer "In13.Cu")
		(net "M_B_CPU1_SB_DQS_DP<9>")
	)
	(gr_poly
		(pts
			(xy 80.214978 -264.568178) (xy 80.114902 -264.468102) (xy 80.014826 -264.568178) (xy 80.014826 -264.612628)
			(xy 80.214978 -264.612628)
		)
		(stroke
			(width 0)
			(type solid)
		)
		(fill yes)
		(layer "In13.Cu")
		(net "M_B_CPU1_SB_CA<6>")
	)
	(gr_poly
		(pts
			(xy 80.214978 -262.948166) (xy 80.114902 -262.84809) (xy 80.014826 -262.948166) (xy 80.014826 -262.992616)
			(xy 80.214978 -262.992616)
		)
		(stroke
			(width 0)
			(type solid)
		)
		(fill yes)
		(layer "In13.Cu")
		(net "M_B_CPU1_SB_CA<2>")
	)
	(gr_poly
		(pts
			(xy 80.221074 -292.108128) (xy 80.120998 -292.008052) (xy 80.020922 -292.108128) (xy 80.020922 -292.152578)
			(xy 80.221074 -292.152578)
		)
		(stroke
			(width 0)
			(type solid)
		)
		(fill yes)
		(layer "In13.Cu")
		(net "M_B_CPU1_SB_DQ<28>")
	)
	(gr_poly
		(pts
			(xy 80.221074 -288.868104) (xy 80.120998 -288.768028) (xy 80.020922 -288.868104) (xy 80.020922 -288.912554)
			(xy 80.221074 -288.912554)
		)
		(stroke
			(width 0)
			(type solid)
		)
		(fill yes)
		(layer "In13.Cu")
		(net "M_B_CPU1_SB_DQ<24>")
	)
	(gr_poly
		(pts
			(xy 80.221074 -288.464498) (xy 80.221074 -288.420048) (xy 80.020922 -288.420048) (xy 80.020922 -288.464498)
			(xy 80.120998 -288.564574)
		)
		(stroke
			(width 0)
			(type solid)
		)
		(fill yes)
		(layer "In13.Cu")
		(net "M_B_CPU1_SB_DQ<23>")
	)
	(gr_poly
		(pts
			(xy 80.221074 -269.428214) (xy 80.120998 -269.328138) (xy 80.020922 -269.428214) (xy 80.020922 -269.472664)
			(xy 80.221074 -269.472664)
		)
		(stroke
			(width 0)
			(type solid)
		)
		(fill yes)
		(layer "In13.Cu")
		(net "M_B_CPU1_SB_CB<4>")
	)
	(gr_poly
		(pts
			(xy 80.22717 -285.62808) (xy 80.127094 -285.528258) (xy 80.027018 -285.62808) (xy 80.027018 -285.675832)
			(xy 80.22717 -285.675832)
		)
		(stroke
			(width 0)
			(type solid)
		)
		(fill yes)
		(layer "In13.Cu")
		(net "M_B_CPU1_SB_DQS_DP<2>")
	)
	(gr_poly
		(pts
			(xy 80.22717 -280.768044) (xy 80.127094 -280.668222) (xy 80.027018 -280.768044) (xy 80.027018 -280.815796)
			(xy 80.22717 -280.815796)
		)
		(stroke
			(width 0)
			(type solid)
		)
		(fill yes)
		(layer "In13.Cu")
		(net "M_B_CPU1_SB_DQS_DP<1>")
	)
	(gr_poly
		(pts
			(xy 80.235044 -267.801852) (xy 80.134968 -267.701776) (xy 80.035146 -267.801852) (xy 80.035146 -267.846302)
			(xy 80.235044 -267.846302)
		)
		(stroke
			(width 0)
			(type solid)
		)
		(fill yes)
		(layer "In13.Cu")
		(net "M_B_CPU1_SB_RSP<0>")
	)
	(gr_poly
		(pts
			(xy 80.235552 -283.604208) (xy 80.235552 -283.560012) (xy 80.035654 -283.560012) (xy 80.035654 -283.604208)
			(xy 80.13573 -283.704284)
		)
		(stroke
			(width 0)
			(type solid)
		)
		(fill yes)
		(layer "In13.Cu")
		(net "M_B_CPU1_SB_DQ<15>")
	)
	(gr_poly
		(pts
			(xy 80.276954 -293.860728) (xy 80.240378 -293.724076) (xy 80.202024 -293.701724) (xy 80.101948 -293.874952)
			(xy 80.140556 -293.897304)
		)
		(stroke
			(width 0)
			(type solid)
		)
		(fill yes)
		(layer "In13.Cu")
		(net "M_B_CPU1_SB_DQ<30>")
	)
	(gr_poly
		(pts
			(xy 80.310228 -228.633274) (xy 80.210152 -228.460046) (xy 80.171798 -228.482398) (xy 80.135222 -228.61905)
			(xy 80.27162 -228.655626)
		)
		(stroke
			(width 0)
			(type solid)
		)
		(fill yes)
		(layer "In13.Cu")
		(net "M_B_CPU1_SA_DQ<7>")
	)
	(gr_poly
		(pts
			(xy 80.310228 -227.013262) (xy 80.210152 -226.840034) (xy 80.171798 -226.862386) (xy 80.135222 -226.999038)
			(xy 80.27162 -227.035614)
		)
		(stroke
			(width 0)
			(type solid)
		)
		(fill yes)
		(layer "In13.Cu")
		(net "M_B_CPU1_SA_DQ<6>")
	)
	(gr_poly
		(pts
			(xy 80.31099 -230.254556) (xy 80.210914 -230.081328) (xy 80.172306 -230.103426) (xy 80.13573 -230.240078)
			(xy 80.272382 -230.276654)
		)
		(stroke
			(width 0)
			(type solid)
		)
		(fill yes)
		(layer "In13.Cu")
		(net "M_B_CPU1_SA_DQ<10>")
	)
	(gr_poly
		(pts
			(xy 80.313022 -225.392488) (xy 80.2132 -225.21926) (xy 80.171798 -225.243136) (xy 80.135222 -225.379534)
			(xy 80.271874 -225.416364)
		)
		(stroke
			(width 0)
			(type solid)
		)
		(fill yes)
		(layer "In13.Cu")
		(net "M_B_CPU1_SA_DQS_DP<5>")
	)
	(gr_poly
		(pts
			(xy 80.314038 -223.773746) (xy 80.214216 -223.600518) (xy 80.172814 -223.624394) (xy 80.136238 -223.761046)
			(xy 80.27289 -223.797622)
		)
		(stroke
			(width 0)
			(type solid)
		)
		(fill yes)
		(layer "In13.Cu")
		(net "M_B_CPU1_SA_DQS_DN<0>")
	)
	(gr_poly
		(pts
			(xy 80.391254 -256.026158) (xy 80.291178 -255.926336) (xy 80.191102 -256.026158) (xy 80.191102 -256.07391)
			(xy 80.391254 -256.07391)
		)
		(stroke
			(width 0)
			(type solid)
		)
		(fill yes)
		(layer "In13.Cu")
		(net "M_B_CPU1_CLK_DP<0>")
	)
	(gr_poly
		(pts
			(xy 80.391254 -255.622552) (xy 80.391254 -255.578102) (xy 80.191102 -255.578102) (xy 80.191102 -255.622552)
			(xy 80.291178 -255.722628)
		)
		(stroke
			(width 0)
			(type solid)
		)
		(fill yes)
		(layer "In13.Cu")
		(net "M_B_CPU1_SA_PAR")
	)
	(gr_poly
		(pts
			(xy 80.391254 -254.4064) (xy 80.291178 -254.306324) (xy 80.191102 -254.4064) (xy 80.191102 -254.45085)
			(xy 80.391254 -254.45085)
		)
		(stroke
			(width 0)
			(type solid)
		)
		(fill yes)
		(layer "In13.Cu")
		(net "M_B_CPU1_SA_CA<4>")
	)
	(gr_poly
		(pts
			(xy 80.391254 -254.00254) (xy 80.391254 -253.95809) (xy 80.191102 -253.95809) (xy 80.191102 -254.00254)
			(xy 80.291178 -254.102616)
		)
		(stroke
			(width 0)
			(type solid)
		)
		(fill yes)
		(layer "In13.Cu")
		(net "M_B_CPU1_SA_CA<3>")
	)
	(gr_poly
		(pts
			(xy 80.391254 -252.786388) (xy 80.291178 -252.686312) (xy 80.191102 -252.786388) (xy 80.191102 -252.830838)
			(xy 80.391254 -252.830838)
		)
		(stroke
			(width 0)
			(type solid)
		)
		(fill yes)
		(layer "In13.Cu")
		(net "M_B_CPU1_SA_CA<0>")
	)
	(gr_poly
		(pts
			(xy 80.391254 -252.382528) (xy 80.391254 -252.338078) (xy 80.191102 -252.338078) (xy 80.191102 -252.382528)
			(xy 80.291178 -252.482604)
		)
		(stroke
			(width 0)
			(type solid)
		)
		(fill yes)
		(layer "In13.Cu")
		(net "M_B_CPU1_SA_CS_N<1>")
	)
	(gr_poly
		(pts
			(xy 80.391254 -250.762516) (xy 80.391254 -250.718066) (xy 80.191102 -250.718066) (xy 80.191102 -250.762516)
			(xy 80.291178 -250.862592)
		)
		(stroke
			(width 0)
			(type solid)
		)
		(fill yes)
		(layer "In13.Cu")
		(net "M_B_CPU1_RESET_N")
	)
	(gr_poly
		(pts
			(xy 80.391254 -249.142504) (xy 80.391254 -249.098054) (xy 80.191102 -249.098054) (xy 80.191102 -249.142504)
			(xy 80.291178 -249.24258)
		)
		(stroke
			(width 0)
			(type solid)
		)
		(fill yes)
		(layer "In13.Cu")
		(net "M_B_CPU1_SA_CB<7>")
	)
	(gr_poly
		(pts
			(xy 80.391254 -247.926352) (xy 80.291178 -247.826276) (xy 80.191102 -247.926352) (xy 80.191102 -247.970802)
			(xy 80.391254 -247.970802)
		)
		(stroke
			(width 0)
			(type solid)
		)
		(fill yes)
		(layer "In13.Cu")
		(net "M_B_CPU1_SA_CB<4>")
	)
	(gr_poly
		(pts
			(xy 80.391254 -247.522746) (xy 80.391254 -247.474994) (xy 80.191102 -247.474994) (xy 80.191102 -247.522746)
			(xy 80.291178 -247.622568)
		)
		(stroke
			(width 0)
			(type solid)
		)
		(fill yes)
		(layer "In13.Cu")
		(net "M_B_CPU1_SA_DQS_DP<9>")
	)
	(gr_poly
		(pts
			(xy 80.391254 -246.306086) (xy 80.291178 -246.206264) (xy 80.191102 -246.306086) (xy 80.191102 -246.353838)
			(xy 80.391254 -246.353838)
		)
		(stroke
			(width 0)
			(type solid)
		)
		(fill yes)
		(layer "In13.Cu")
		(net "M_B_CPU1_SA_DQS_DP<4>")
	)
	(gr_poly
		(pts
			(xy 80.391254 -245.90248) (xy 80.391254 -245.85803) (xy 80.191102 -245.85803) (xy 80.191102 -245.90248)
			(xy 80.291178 -246.002556)
		)
		(stroke
			(width 0)
			(type solid)
		)
		(fill yes)
		(layer "In13.Cu")
		(net "M_B_CPU1_SA_CB<3>")
	)
	(gr_poly
		(pts
			(xy 80.391254 -244.686328) (xy 80.291178 -244.586252) (xy 80.191102 -244.686328) (xy 80.191102 -244.730778)
			(xy 80.391254 -244.730778)
		)
		(stroke
			(width 0)
			(type solid)
		)
		(fill yes)
		(layer "In13.Cu")
		(net "M_B_CPU1_SA_CB<0>")
	)
	(gr_poly
		(pts
			(xy 80.391254 -244.282468) (xy 80.391254 -244.238018) (xy 80.191102 -244.238018) (xy 80.191102 -244.282468)
			(xy 80.291178 -244.382544)
		)
		(stroke
			(width 0)
			(type solid)
		)
		(fill yes)
		(layer "In13.Cu")
		(net "M_B_CPU1_SA_DQ<31>")
	)
	(gr_poly
		(pts
			(xy 80.391254 -243.066316) (xy 80.291178 -242.96624) (xy 80.191102 -243.066316) (xy 80.191102 -243.110766)
			(xy 80.391254 -243.110766)
		)
		(stroke
			(width 0)
			(type solid)
		)
		(fill yes)
		(layer "In13.Cu")
		(net "M_B_CPU1_SA_DQ<28>")
	)
	(gr_poly
		(pts
			(xy 80.391254 -242.66271) (xy 80.391254 -242.614958) (xy 80.191102 -242.614958) (xy 80.191102 -242.66271)
			(xy 80.291178 -242.762532)
		)
		(stroke
			(width 0)
			(type solid)
		)
		(fill yes)
		(layer "In13.Cu")
		(net "M_B_CPU1_SA_DQS_DP<8>")
	)
	(gr_poly
		(pts
			(xy 80.391254 -241.44605) (xy 80.291178 -241.346228) (xy 80.191102 -241.44605) (xy 80.191102 -241.493802)
			(xy 80.391254 -241.493802)
		)
		(stroke
			(width 0)
			(type solid)
		)
		(fill yes)
		(layer "In13.Cu")
		(net "M_B_CPU1_SA_DQS_DP<3>")
	)
	(gr_poly
		(pts
			(xy 80.391254 -241.042444) (xy 80.391254 -240.997994) (xy 80.191102 -240.997994) (xy 80.191102 -241.042444)
			(xy 80.291178 -241.14252)
		)
		(stroke
			(width 0)
			(type solid)
		)
		(fill yes)
		(layer "In13.Cu")
		(net "M_B_CPU1_SA_DQ<27>")
	)
	(gr_poly
		(pts
			(xy 80.391254 -239.826292) (xy 80.291178 -239.726216) (xy 80.191102 -239.826292) (xy 80.191102 -239.870742)
			(xy 80.391254 -239.870742)
		)
		(stroke
			(width 0)
			(type solid)
		)
		(fill yes)
		(layer "In13.Cu")
		(net "M_B_CPU1_SA_DQ<24>")
	)
	(gr_poly
		(pts
			(xy 80.391254 -239.422432) (xy 80.391254 -239.377982) (xy 80.191102 -239.377982) (xy 80.191102 -239.422432)
			(xy 80.291178 -239.522508)
		)
		(stroke
			(width 0)
			(type solid)
		)
		(fill yes)
		(layer "In13.Cu")
		(net "M_B_CPU1_SA_DQ<23>")
	)
	(gr_poly
		(pts
			(xy 80.391254 -238.20628) (xy 80.291178 -238.106204) (xy 80.191102 -238.20628) (xy 80.191102 -238.25073)
			(xy 80.391254 -238.25073)
		)
		(stroke
			(width 0)
			(type solid)
		)
		(fill yes)
		(layer "In13.Cu")
		(net "M_B_CPU1_SA_DQ<20>")
	)
	(gr_poly
		(pts
			(xy 80.391254 -237.802674) (xy 80.391254 -237.754922) (xy 80.191102 -237.754922) (xy 80.191102 -237.802674)
			(xy 80.291178 -237.902496)
		)
		(stroke
			(width 0)
			(type solid)
		)
		(fill yes)
		(layer "In13.Cu")
		(net "M_B_CPU1_SA_DQS_DP<7>")
	)
	(gr_poly
		(pts
			(xy 80.391254 -236.586014) (xy 80.291178 -236.486192) (xy 80.191102 -236.586014) (xy 80.191102 -236.633766)
			(xy 80.391254 -236.633766)
		)
		(stroke
			(width 0)
			(type solid)
		)
		(fill yes)
		(layer "In13.Cu")
		(net "M_B_CPU1_SA_DQS_DP<2>")
	)
	(gr_poly
		(pts
			(xy 80.391254 -236.182408) (xy 80.391254 -236.137958) (xy 80.191102 -236.137958) (xy 80.191102 -236.182408)
			(xy 80.291178 -236.282484)
		)
		(stroke
			(width 0)
			(type solid)
		)
		(fill yes)
		(layer "In13.Cu")
		(net "M_B_CPU1_SA_DQ<19>")
	)
	(gr_poly
		(pts
			(xy 80.391254 -234.966256) (xy 80.291178 -234.86618) (xy 80.191102 -234.966256) (xy 80.191102 -235.010706)
			(xy 80.391254 -235.010706)
		)
		(stroke
			(width 0)
			(type solid)
		)
		(fill yes)
		(layer "In13.Cu")
		(net "M_B_CPU1_SA_DQ<16>")
	)
	(gr_poly
		(pts
			(xy 80.391254 -234.562396) (xy 80.391254 -234.517946) (xy 80.191102 -234.517946) (xy 80.191102 -234.562396)
			(xy 80.291178 -234.662472)
		)
		(stroke
			(width 0)
			(type solid)
		)
		(fill yes)
		(layer "In13.Cu")
		(net "M_B_CPU1_SA_DQ<15>")
	)
	(gr_poly
		(pts
			(xy 80.391254 -233.346244) (xy 80.291178 -233.246168) (xy 80.191102 -233.346244) (xy 80.191102 -233.390694)
			(xy 80.391254 -233.390694)
		)
		(stroke
			(width 0)
			(type solid)
		)
		(fill yes)
		(layer "In13.Cu")
		(net "M_B_CPU1_SA_DQ<12>")
	)
	(gr_poly
		(pts
			(xy 80.391254 -232.942638) (xy 80.391254 -232.894886) (xy 80.191102 -232.894886) (xy 80.191102 -232.942638)
			(xy 80.291178 -233.04246)
		)
		(stroke
			(width 0)
			(type solid)
		)
		(fill yes)
		(layer "In13.Cu")
		(net "M_B_CPU1_SA_DQS_DP<6>")
	)
	(gr_poly
		(pts
			(xy 80.391254 -231.725978) (xy 80.291178 -231.626156) (xy 80.191102 -231.725978) (xy 80.191102 -231.77373)
			(xy 80.391254 -231.77373)
		)
		(stroke
			(width 0)
			(type solid)
		)
		(fill yes)
		(layer "In13.Cu")
		(net "M_B_CPU1_SA_DQS_DP<1>")
	)
	(gr_poly
		(pts
			(xy 80.391254 -231.322626) (xy 80.391254 -231.278176) (xy 80.191102 -231.278176) (xy 80.191102 -231.322626)
			(xy 80.291178 -231.422702)
		)
		(stroke
			(width 0)
			(type solid)
		)
		(fill yes)
		(layer "In13.Cu")
		(net "M_B_CPU1_SA_DQ<11>")
	)
	(gr_poly
		(pts
			(xy 80.409542 -223.224598) (xy 80.446118 -223.087946) (xy 80.309466 -223.05137) (xy 80.268318 -223.075246)
			(xy 80.36814 -223.248474)
		)
		(stroke
			(width 0)
			(type solid)
		)
		(fill yes)
		(layer "In13.Cu")
		(net "M_B_CPU1_SA_DQS_DP<0>")
	)
	(gr_poly
		(pts
			(xy 80.41005 -224.846388) (xy 80.446626 -224.709736) (xy 80.309974 -224.67316) (xy 80.268572 -224.697036)
			(xy 80.368648 -224.870264)
		)
		(stroke
			(width 0)
			(type solid)
		)
		(fill yes)
		(layer "In13.Cu")
		(net "M_B_CPU1_SA_DQS_DN<5>")
	)
	(gr_poly
		(pts
			(xy 80.410304 -229.706424) (xy 80.447134 -229.569772) (xy 80.310482 -229.533196) (xy 80.271874 -229.555548)
			(xy 80.37195 -229.728776)
		)
		(stroke
			(width 0)
			(type solid)
		)
		(fill yes)
		(layer "In13.Cu")
		(net "M_B_CPU1_SA_DQ<8>")
	)
	(gr_poly
		(pts
			(xy 80.410304 -228.086666) (xy 80.447134 -227.950014) (xy 80.310482 -227.913438) (xy 80.271874 -227.93579)
			(xy 80.37195 -228.109018)
		)
		(stroke
			(width 0)
			(type solid)
		)
		(fill yes)
		(layer "In13.Cu")
		(net "M_B_CPU1_SA_DQ<5>")
	)
	(gr_poly
		(pts
			(xy 80.410304 -226.466654) (xy 80.447134 -226.330002) (xy 80.310482 -226.293426) (xy 80.271874 -226.315778)
			(xy 80.37195 -226.489006)
		)
		(stroke
			(width 0)
			(type solid)
		)
		(fill yes)
		(layer "In13.Cu")
		(net "M_B_CPU1_SA_DQ<4>")
	)
	(gr_poly
		(pts
			(xy 80.610202 -293.987474) (xy 80.571594 -293.965122) (xy 80.434942 -294.001698) (xy 80.471772 -294.13835)
			(xy 80.510126 -294.160702)
		)
		(stroke
			(width 0)
			(type solid)
		)
		(fill yes)
		(layer "In13.Cu")
		(net "M_B_CPU1_SB_DQ<29>")
	)
	(gr_poly
		(pts
			(xy 80.684878 -266.991846) (xy 80.584802 -266.89177) (xy 80.48498 -266.991846) (xy 80.48498 -267.036296)
			(xy 80.684878 -267.036296)
		)
		(stroke
			(width 0)
			(type solid)
		)
		(fill yes)
		(layer "In13.Cu")
		(net "M_B_CPU1_SA_RSP<0>")
	)
	(gr_poly
		(pts
			(xy 80.691228 -291.297868) (xy 80.591152 -291.198046) (xy 80.491076 -291.297868) (xy 80.491076 -291.34562)
			(xy 80.691228 -291.34562)
		)
		(stroke
			(width 0)
			(type solid)
		)
		(fill yes)
		(layer "In13.Cu")
		(net "M_B_CPU1_SB_DQS_DN<8>")
	)
	(gr_poly
		(pts
			(xy 80.691228 -290.894516) (xy 80.691228 -290.846764) (xy 80.491076 -290.846764) (xy 80.491076 -290.894516)
			(xy 80.591152 -290.994338)
		)
		(stroke
			(width 0)
			(type solid)
		)
		(fill yes)
		(layer "In13.Cu")
		(net "M_B_CPU1_SB_DQS_DN<3>")
	)
	(gr_poly
		(pts
			(xy 80.691228 -289.67811) (xy 80.591152 -289.578034) (xy 80.491076 -289.67811) (xy 80.491076 -289.72256)
			(xy 80.691228 -289.72256)
		)
		(stroke
			(width 0)
			(type solid)
		)
		(fill yes)
		(layer "In13.Cu")
		(net "M_B_CPU1_SB_DQ<25>")
	)
	(gr_poly
		(pts
			(xy 80.691228 -289.27425) (xy 80.691228 -289.2298) (xy 80.491076 -289.2298) (xy 80.491076 -289.27425)
			(xy 80.591152 -289.374326)
		)
		(stroke
			(width 0)
			(type solid)
		)
		(fill yes)
		(layer "In13.Cu")
		(net "M_B_CPU1_SB_DQ<26>")
	)
	(gr_poly
		(pts
			(xy 80.691228 -288.058098) (xy 80.591152 -287.958022) (xy 80.491076 -288.058098) (xy 80.491076 -288.102548)
			(xy 80.691228 -288.102548)
		)
		(stroke
			(width 0)
			(type solid)
		)
		(fill yes)
		(layer "In13.Cu")
		(net "M_B_CPU1_SB_DQ<21>")
	)
	(gr_poly
		(pts
			(xy 80.691228 -287.654492) (xy 80.691228 -287.610042) (xy 80.491076 -287.610042) (xy 80.491076 -287.654492)
			(xy 80.591152 -287.754568)
		)
		(stroke
			(width 0)
			(type solid)
		)
		(fill yes)
		(layer "In13.Cu")
		(net "M_B_CPU1_SB_DQ<22>")
	)
	(gr_poly
		(pts
			(xy 80.691228 -286.438086) (xy 80.591152 -286.33801) (xy 80.491076 -286.438086) (xy 80.491076 -286.485838)
			(xy 80.691228 -286.485838)
		)
		(stroke
			(width 0)
			(type solid)
		)
		(fill yes)
		(layer "In13.Cu")
		(net "M_B_CPU1_SB_DQS_DN<7>")
	)
	(gr_poly
		(pts
			(xy 80.691228 -286.034734) (xy 80.691228 -285.986982) (xy 80.491076 -285.986982) (xy 80.491076 -286.034734)
			(xy 80.591152 -286.134556)
		)
		(stroke
			(width 0)
			(type solid)
		)
		(fill yes)
		(layer "In13.Cu")
		(net "M_B_CPU1_SB_DQS_DN<2>")
	)
	(gr_poly
		(pts
			(xy 80.691228 -284.818328) (xy 80.591152 -284.718252) (xy 80.491076 -284.818328) (xy 80.491076 -284.862778)
			(xy 80.691228 -284.862778)
		)
		(stroke
			(width 0)
			(type solid)
		)
		(fill yes)
		(layer "In13.Cu")
		(net "M_B_CPU1_SB_DQ<17>")
	)
	(gr_poly
		(pts
			(xy 80.691228 -284.414468) (xy 80.691228 -284.370018) (xy 80.491076 -284.370018) (xy 80.491076 -284.414468)
			(xy 80.591152 -284.514544)
		)
		(stroke
			(width 0)
			(type solid)
		)
		(fill yes)
		(layer "In13.Cu")
		(net "M_B_CPU1_SB_DQ<18>")
	)
	(gr_poly
		(pts
			(xy 80.691228 -283.198316) (xy 80.591152 -283.09824) (xy 80.491076 -283.198316) (xy 80.491076 -283.242766)
			(xy 80.691228 -283.242766)
		)
		(stroke
			(width 0)
			(type solid)
		)
		(fill yes)
		(layer "In13.Cu")
		(net "M_B_CPU1_SB_DQ<13>")
	)
	(gr_poly
		(pts
			(xy 80.691228 -282.794456) (xy 80.691228 -282.750006) (xy 80.491076 -282.750006) (xy 80.491076 -282.794456)
			(xy 80.591152 -282.894532)
		)
		(stroke
			(width 0)
			(type solid)
		)
		(fill yes)
		(layer "In13.Cu")
		(net "M_B_CPU1_SB_DQ<14>")
	)
	(gr_poly
		(pts
			(xy 80.691228 -281.57805) (xy 80.591152 -281.478228) (xy 80.491076 -281.57805) (xy 80.491076 -281.625802)
			(xy 80.691228 -281.625802)
		)
		(stroke
			(width 0)
			(type solid)
		)
		(fill yes)
		(layer "In13.Cu")
		(net "M_B_CPU1_SB_DQS_DN<6>")
	)
	(gr_poly
		(pts
			(xy 80.691228 -281.174698) (xy 80.691228 -281.126946) (xy 80.491076 -281.126946) (xy 80.491076 -281.174698)
			(xy 80.591152 -281.27452)
		)
		(stroke
			(width 0)
			(type solid)
		)
		(fill yes)
		(layer "In13.Cu")
		(net "M_B_CPU1_SB_DQS_DN<1>")
	)
	(gr_poly
		(pts
			(xy 80.691228 -279.958292) (xy 80.591152 -279.858216) (xy 80.491076 -279.958292) (xy 80.491076 -280.002742)
			(xy 80.691228 -280.002742)
		)
		(stroke
			(width 0)
			(type solid)
		)
		(fill yes)
		(layer "In13.Cu")
		(net "M_B_CPU1_SB_DQ<9>")
	)
	(gr_poly
		(pts
			(xy 80.691228 -279.554432) (xy 80.691228 -279.509982) (xy 80.491076 -279.509982) (xy 80.491076 -279.554432)
			(xy 80.591152 -279.654508)
		)
		(stroke
			(width 0)
			(type solid)
		)
		(fill yes)
		(layer "In13.Cu")
		(net "M_B_CPU1_SB_DQ<10>")
	)
	(gr_poly
		(pts
			(xy 80.691228 -278.33828) (xy 80.591152 -278.238204) (xy 80.491076 -278.33828) (xy 80.491076 -278.38273)
			(xy 80.691228 -278.38273)
		)
		(stroke
			(width 0)
			(type solid)
		)
		(fill yes)
		(layer "In13.Cu")
		(net "M_B_CPU1_SB_DQ<5>")
	)
	(gr_poly
		(pts
			(xy 80.691228 -277.93442) (xy 80.691228 -277.88997) (xy 80.491076 -277.88997) (xy 80.491076 -277.93442)
			(xy 80.591152 -278.034496)
		)
		(stroke
			(width 0)
			(type solid)
		)
		(fill yes)
		(layer "In13.Cu")
		(net "M_B_CPU1_SB_DQ<6>")
	)
	(gr_poly
		(pts
			(xy 80.691228 -276.718014) (xy 80.591152 -276.618192) (xy 80.491076 -276.718014) (xy 80.491076 -276.765766)
			(xy 80.691228 -276.765766)
		)
		(stroke
			(width 0)
			(type solid)
		)
		(fill yes)
		(layer "In13.Cu")
		(net "M_B_CPU1_SB_DQS_DN<5>")
	)
	(gr_poly
		(pts
			(xy 80.691228 -276.314662) (xy 80.691228 -276.26691) (xy 80.491076 -276.26691) (xy 80.491076 -276.314662)
			(xy 80.591152 -276.414484)
		)
		(stroke
			(width 0)
			(type solid)
		)
		(fill yes)
		(layer "In13.Cu")
		(net "M_B_CPU1_SB_DQS_DN<0>")
	)
	(gr_poly
		(pts
			(xy 80.691228 -275.098256) (xy 80.591152 -274.99818) (xy 80.491076 -275.098256) (xy 80.491076 -275.142706)
			(xy 80.691228 -275.142706)
		)
		(stroke
			(width 0)
			(type solid)
		)
		(fill yes)
		(layer "In13.Cu")
		(net "M_B_CPU1_SB_DQ<1>")
	)
	(gr_poly
		(pts
			(xy 80.691228 -274.694396) (xy 80.691228 -274.649946) (xy 80.491076 -274.649946) (xy 80.491076 -274.694396)
			(xy 80.591152 -274.794472)
		)
		(stroke
			(width 0)
			(type solid)
		)
		(fill yes)
		(layer "In13.Cu")
		(net "M_B_CPU1_SB_DQ<2>")
	)
	(gr_poly
		(pts
			(xy 80.691228 -273.478244) (xy 80.591152 -273.378168) (xy 80.491076 -273.478244) (xy 80.491076 -273.522694)
			(xy 80.691228 -273.522694)
		)
		(stroke
			(width 0)
			(type solid)
		)
		(fill yes)
		(layer "In13.Cu")
		(net "M_B_CPU1_SB_CB<1>")
	)
	(gr_poly
		(pts
			(xy 80.691228 -273.074384) (xy 80.691228 -273.029934) (xy 80.491076 -273.029934) (xy 80.491076 -273.074384)
			(xy 80.591152 -273.17446)
		)
		(stroke
			(width 0)
			(type solid)
		)
		(fill yes)
		(layer "In13.Cu")
		(net "M_B_CPU1_SB_CB<2>")
	)
	(gr_poly
		(pts
			(xy 80.691228 -271.857978) (xy 80.591152 -271.758156) (xy 80.491076 -271.857978) (xy 80.491076 -271.90573)
			(xy 80.691228 -271.90573)
		)
		(stroke
			(width 0)
			(type solid)
		)
		(fill yes)
		(layer "In13.Cu")
		(net "M_B_CPU1_SB_DQS_DN<4>")
	)
	(gr_poly
		(pts
			(xy 80.691228 -271.454626) (xy 80.691228 -271.406874) (xy 80.491076 -271.406874) (xy 80.491076 -271.454626)
			(xy 80.591152 -271.554448)
		)
		(stroke
			(width 0)
			(type solid)
		)
		(fill yes)
		(layer "In13.Cu")
		(net "M_B_CPU1_SB_DQS_DN<9>")
	)
	(gr_poly
		(pts
			(xy 80.691228 -270.23822) (xy 80.591152 -270.138144) (xy 80.491076 -270.23822) (xy 80.491076 -270.28267)
			(xy 80.691228 -270.28267)
		)
		(stroke
			(width 0)
			(type solid)
		)
		(fill yes)
		(layer "In13.Cu")
		(net "M_B_CPU1_SB_CB<5>")
	)
	(gr_poly
		(pts
			(xy 80.691228 -269.83436) (xy 80.691228 -269.78991) (xy 80.491076 -269.78991) (xy 80.491076 -269.83436)
			(xy 80.591152 -269.934436)
		)
		(stroke
			(width 0)
			(type solid)
		)
		(fill yes)
		(layer "In13.Cu")
		(net "M_B_CPU1_SB_CB<6>")
	)
	(gr_poly
		(pts
			(xy 80.691228 -266.594336) (xy 80.691228 -266.549886) (xy 80.491076 -266.549886) (xy 80.491076 -266.594336)
			(xy 80.591152 -266.694412)
		)
		(stroke
			(width 0)
			(type solid)
		)
		(fill yes)
		(layer "In13.Cu")
		(net "M_B_CPU1_SB_CS_N<1>")
	)
	(gr_poly
		(pts
			(xy 80.691228 -264.974324) (xy 80.691228 -264.929874) (xy 80.491076 -264.929874) (xy 80.491076 -264.974324)
			(xy 80.591152 -265.0744)
		)
		(stroke
			(width 0)
			(type solid)
		)
		(fill yes)
		(layer "In13.Cu")
		(net "M_B_CPU1_SB_PAR")
	)
	(gr_poly
		(pts
			(xy 80.691228 -263.758172) (xy 80.591152 -263.658096) (xy 80.491076 -263.758172) (xy 80.491076 -263.802622)
			(xy 80.691228 -263.802622)
		)
		(stroke
			(width 0)
			(type solid)
		)
		(fill yes)
		(layer "In13.Cu")
		(net "M_B_CPU1_SB_CA<4>")
	)
	(gr_poly
		(pts
			(xy 80.691228 -263.354312) (xy 80.691228 -263.309862) (xy 80.491076 -263.309862) (xy 80.491076 -263.354312)
			(xy 80.591152 -263.454388)
		)
		(stroke
			(width 0)
			(type solid)
		)
		(fill yes)
		(layer "In13.Cu")
		(net "M_B_CPU1_SB_CA<3>")
	)
	(gr_poly
		(pts
			(xy 80.691228 -262.13816) (xy 80.591152 -262.038084) (xy 80.491076 -262.13816) (xy 80.491076 -262.18261)
			(xy 80.691228 -262.18261)
		)
		(stroke
			(width 0)
			(type solid)
		)
		(fill yes)
		(layer "In13.Cu")
		(net "M_B_CPU1_SB_CA<0>")
	)
	(gr_poly
		(pts
			(xy 80.746854 -293.050722) (xy 80.710278 -292.91407) (xy 80.671924 -292.891718) (xy 80.571848 -293.064946)
			(xy 80.610456 -293.087298)
		)
		(stroke
			(width 0)
			(type solid)
		)
		(fill yes)
		(layer "In13.Cu")
		(net "M_B_CPU1_SB_DQ<30>")
	)
	(gr_poly
		(pts
			(xy 80.747362 -296.289984) (xy 80.710532 -296.153332) (xy 80.672178 -296.131234) (xy 80.572102 -296.304462)
			(xy 80.61071 -296.32656)
		)
		(stroke
			(width 0)
			(type solid)
		)
		(fill yes)
		(layer "In13.Cu")
		(net "M_B_CPU1_SB_DQ<31>")
	)
	(gr_poly
		(pts
			(xy 80.781144 -229.444804) (xy 80.681068 -229.271576) (xy 80.64246 -229.293674) (xy 80.605884 -229.430326)
			(xy 80.742536 -229.466902)
		)
		(stroke
			(width 0)
			(type solid)
		)
		(fill yes)
		(layer "In13.Cu")
		(net "M_B_CPU1_SA_DQ<7>")
	)
	(gr_poly
		(pts
			(xy 80.781144 -227.824792) (xy 80.681068 -227.651564) (xy 80.64246 -227.673662) (xy 80.605884 -227.810314)
			(xy 80.742536 -227.84689)
		)
		(stroke
			(width 0)
			(type solid)
		)
		(fill yes)
		(layer "In13.Cu")
		(net "M_B_CPU1_SA_DQ<6>")
	)
	(gr_poly
		(pts
			(xy 80.781144 -222.964756) (xy 80.681068 -222.791528) (xy 80.64246 -222.813626) (xy 80.605884 -222.950278)
			(xy 80.742536 -222.986854)
		)
		(stroke
			(width 0)
			(type solid)
		)
		(fill yes)
		(layer "In13.Cu")
		(net "M_B_CPU1_SA_DQ<3>")
	)
	(gr_poly
		(pts
			(xy 80.783938 -226.203764) (xy 80.684116 -226.030536) (xy 80.642714 -226.054412) (xy 80.606138 -226.191064)
			(xy 80.74279 -226.22764)
		)
		(stroke
			(width 0)
			(type solid)
		)
		(fill yes)
		(layer "In13.Cu")
		(net "M_B_CPU1_SA_DQS_DP<5>")
	)
	(gr_poly
		(pts
			(xy 80.783938 -224.583752) (xy 80.684116 -224.410524) (xy 80.642714 -224.4344) (xy 80.606138 -224.571052)
			(xy 80.74279 -224.607628)
		)
		(stroke
			(width 0)
			(type solid)
		)
		(fill yes)
		(layer "In13.Cu")
		(net "M_B_CPU1_SA_DQS_DN<0>")
	)
	(gr_poly
		(pts
			(xy 80.861154 -256.432812) (xy 80.861154 -256.38506) (xy 80.661002 -256.38506) (xy 80.661002 -256.432812)
			(xy 80.761078 -256.532634)
		)
		(stroke
			(width 0)
			(type solid)
		)
		(fill yes)
		(layer "In13.Cu")
		(net "M_B_CPU1_CLK_DN<0>")
	)
	(gr_poly
		(pts
			(xy 80.861154 -255.216406) (xy 80.761078 -255.11633) (xy 80.661002 -255.216406) (xy 80.661002 -255.260856)
			(xy 80.861154 -255.260856)
		)
		(stroke
			(width 0)
			(type solid)
		)
		(fill yes)
		(layer "In13.Cu")
		(net "M_B_CPU1_SA_CA<6>")
	)
	(gr_poly
		(pts
			(xy 80.861154 -254.812546) (xy 80.861154 -254.768096) (xy 80.661002 -254.768096) (xy 80.661002 -254.812546)
			(xy 80.761078 -254.912622)
		)
		(stroke
			(width 0)
			(type solid)
		)
		(fill yes)
		(layer "In13.Cu")
		(net "M_B_CPU1_SA_CA<5>")
	)
	(gr_poly
		(pts
			(xy 80.861154 -253.596394) (xy 80.761078 -253.496318) (xy 80.661002 -253.596394) (xy 80.661002 -253.640844)
			(xy 80.861154 -253.640844)
		)
		(stroke
			(width 0)
			(type solid)
		)
		(fill yes)
		(layer "In13.Cu")
		(net "M_B_CPU1_SA_CA<2>")
	)
	(gr_poly
		(pts
			(xy 80.861154 -253.192534) (xy 80.861154 -253.148084) (xy 80.661002 -253.148084) (xy 80.661002 -253.192534)
			(xy 80.761078 -253.29261)
		)
		(stroke
			(width 0)
			(type solid)
		)
		(fill yes)
		(layer "In13.Cu")
		(net "M_B_CPU1_SA_CA<1>")
	)
	(gr_poly
		(pts
			(xy 80.861154 -251.572522) (xy 80.861154 -251.528072) (xy 80.661002 -251.528072) (xy 80.661002 -251.572522)
			(xy 80.761078 -251.672598)
		)
		(stroke
			(width 0)
			(type solid)
		)
		(fill yes)
		(layer "In13.Cu")
		(net "M_B_CPU1_SA_CS_N<0>")
	)
	(gr_poly
		(pts
			(xy 80.861154 -250.35637) (xy 80.761078 -250.256294) (xy 80.661002 -250.35637) (xy 80.661002 -250.40082)
			(xy 80.861154 -250.40082)
		)
		(stroke
			(width 0)
			(type solid)
		)
		(fill yes)
		(layer "In13.Cu")
		(net "M_B_CPU1_ALERT_R_N")
	)
	(gr_poly
		(pts
			(xy 80.861154 -248.736358) (xy 80.761078 -248.636282) (xy 80.661002 -248.736358) (xy 80.661002 -248.780808)
			(xy 80.861154 -248.780808)
		)
		(stroke
			(width 0)
			(type solid)
		)
		(fill yes)
		(layer "In13.Cu")
		(net "M_B_CPU1_SA_CB<5>")
	)
	(gr_poly
		(pts
			(xy 80.861154 -248.332498) (xy 80.861154 -248.288048) (xy 80.661002 -248.288048) (xy 80.661002 -248.332498)
			(xy 80.761078 -248.432574)
		)
		(stroke
			(width 0)
			(type solid)
		)
		(fill yes)
		(layer "In13.Cu")
		(net "M_B_CPU1_SA_CB<6>")
	)
	(gr_poly
		(pts
			(xy 80.861154 -247.116092) (xy 80.761078 -247.01627) (xy 80.661002 -247.116092) (xy 80.661002 -247.163844)
			(xy 80.861154 -247.163844)
		)
		(stroke
			(width 0)
			(type solid)
		)
		(fill yes)
		(layer "In13.Cu")
		(net "M_B_CPU1_SA_DQS_DN<9>")
	)
	(gr_poly
		(pts
			(xy 80.861154 -246.71274) (xy 80.861154 -246.664988) (xy 80.661002 -246.664988) (xy 80.661002 -246.71274)
			(xy 80.761078 -246.812562)
		)
		(stroke
			(width 0)
			(type solid)
		)
		(fill yes)
		(layer "In13.Cu")
		(net "M_B_CPU1_SA_DQS_DN<4>")
	)
	(gr_poly
		(pts
			(xy 80.861154 -245.496334) (xy 80.761078 -245.396258) (xy 80.661002 -245.496334) (xy 80.661002 -245.540784)
			(xy 80.861154 -245.540784)
		)
		(stroke
			(width 0)
			(type solid)
		)
		(fill yes)
		(layer "In13.Cu")
		(net "M_B_CPU1_SA_CB<1>")
	)
	(gr_poly
		(pts
			(xy 80.861154 -245.092474) (xy 80.861154 -245.048024) (xy 80.661002 -245.048024) (xy 80.661002 -245.092474)
			(xy 80.761078 -245.19255)
		)
		(stroke
			(width 0)
			(type solid)
		)
		(fill yes)
		(layer "In13.Cu")
		(net "M_B_CPU1_SA_CB<2>")
	)
	(gr_poly
		(pts
			(xy 80.861154 -243.876322) (xy 80.761078 -243.776246) (xy 80.661002 -243.876322) (xy 80.661002 -243.920772)
			(xy 80.861154 -243.920772)
		)
		(stroke
			(width 0)
			(type solid)
		)
		(fill yes)
		(layer "In13.Cu")
		(net "M_B_CPU1_SA_DQ<29>")
	)
	(gr_poly
		(pts
			(xy 80.861154 -243.472462) (xy 80.861154 -243.428012) (xy 80.661002 -243.428012) (xy 80.661002 -243.472462)
			(xy 80.761078 -243.572538)
		)
		(stroke
			(width 0)
			(type solid)
		)
		(fill yes)
		(layer "In13.Cu")
		(net "M_B_CPU1_SA_DQ<30>")
	)
	(gr_poly
		(pts
			(xy 80.861154 -242.256056) (xy 80.761078 -242.156234) (xy 80.661002 -242.256056) (xy 80.661002 -242.303808)
			(xy 80.861154 -242.303808)
		)
		(stroke
			(width 0)
			(type solid)
		)
		(fill yes)
		(layer "In13.Cu")
		(net "M_B_CPU1_SA_DQS_DN<8>")
	)
	(gr_poly
		(pts
			(xy 80.861154 -241.852704) (xy 80.861154 -241.804952) (xy 80.661002 -241.804952) (xy 80.661002 -241.852704)
			(xy 80.761078 -241.952526)
		)
		(stroke
			(width 0)
			(type solid)
		)
		(fill yes)
		(layer "In13.Cu")
		(net "M_B_CPU1_SA_DQS_DN<3>")
	)
	(gr_poly
		(pts
			(xy 80.861154 -240.636298) (xy 80.761078 -240.536222) (xy 80.661002 -240.636298) (xy 80.661002 -240.680748)
			(xy 80.861154 -240.680748)
		)
		(stroke
			(width 0)
			(type solid)
		)
		(fill yes)
		(layer "In13.Cu")
		(net "M_B_CPU1_SA_DQ<25>")
	)
	(gr_poly
		(pts
			(xy 80.861154 -240.232438) (xy 80.861154 -240.187988) (xy 80.661002 -240.187988) (xy 80.661002 -240.232438)
			(xy 80.761078 -240.332514)
		)
		(stroke
			(width 0)
			(type solid)
		)
		(fill yes)
		(layer "In13.Cu")
		(net "M_B_CPU1_SA_DQ<26>")
	)
	(gr_poly
		(pts
			(xy 80.861154 -239.016286) (xy 80.761078 -238.91621) (xy 80.661002 -239.016286) (xy 80.661002 -239.060736)
			(xy 80.861154 -239.060736)
		)
		(stroke
			(width 0)
			(type solid)
		)
		(fill yes)
		(layer "In13.Cu")
		(net "M_B_CPU1_SA_DQ<21>")
	)
	(gr_poly
		(pts
			(xy 80.861154 -238.612426) (xy 80.861154 -238.567976) (xy 80.661002 -238.567976) (xy 80.661002 -238.612426)
			(xy 80.761078 -238.712502)
		)
		(stroke
			(width 0)
			(type solid)
		)
		(fill yes)
		(layer "In13.Cu")
		(net "M_B_CPU1_SA_DQ<22>")
	)
	(gr_poly
		(pts
			(xy 80.861154 -237.39602) (xy 80.761078 -237.296198) (xy 80.661002 -237.39602) (xy 80.661002 -237.443772)
			(xy 80.861154 -237.443772)
		)
		(stroke
			(width 0)
			(type solid)
		)
		(fill yes)
		(layer "In13.Cu")
		(net "M_B_CPU1_SA_DQS_DN<7>")
	)
	(gr_poly
		(pts
			(xy 80.861154 -236.992668) (xy 80.861154 -236.944916) (xy 80.661002 -236.944916) (xy 80.661002 -236.992668)
			(xy 80.761078 -237.09249)
		)
		(stroke
			(width 0)
			(type solid)
		)
		(fill yes)
		(layer "In13.Cu")
		(net "M_B_CPU1_SA_DQS_DN<2>")
	)
	(gr_poly
		(pts
			(xy 80.861154 -235.776262) (xy 80.761078 -235.676186) (xy 80.661002 -235.776262) (xy 80.661002 -235.820712)
			(xy 80.861154 -235.820712)
		)
		(stroke
			(width 0)
			(type solid)
		)
		(fill yes)
		(layer "In13.Cu")
		(net "M_B_CPU1_SA_DQ<17>")
	)
	(gr_poly
		(pts
			(xy 80.861154 -235.372402) (xy 80.861154 -235.327952) (xy 80.661002 -235.327952) (xy 80.661002 -235.372402)
			(xy 80.761078 -235.472478)
		)
		(stroke
			(width 0)
			(type solid)
		)
		(fill yes)
		(layer "In13.Cu")
		(net "M_B_CPU1_SA_DQ<18>")
	)
	(gr_poly
		(pts
			(xy 80.861154 -234.15625) (xy 80.761078 -234.056174) (xy 80.661002 -234.15625) (xy 80.661002 -234.2007)
			(xy 80.861154 -234.2007)
		)
		(stroke
			(width 0)
			(type solid)
		)
		(fill yes)
		(layer "In13.Cu")
		(net "M_B_CPU1_SA_DQ<13>")
	)
	(gr_poly
		(pts
			(xy 80.861154 -233.75239) (xy 80.861154 -233.70794) (xy 80.661002 -233.70794) (xy 80.661002 -233.75239)
			(xy 80.761078 -233.852466)
		)
		(stroke
			(width 0)
			(type solid)
		)
		(fill yes)
		(layer "In13.Cu")
		(net "M_B_CPU1_SA_DQ<14>")
	)
	(gr_poly
		(pts
			(xy 80.861154 -232.535984) (xy 80.761078 -232.436162) (xy 80.661002 -232.535984) (xy 80.661002 -232.583736)
			(xy 80.861154 -232.583736)
		)
		(stroke
			(width 0)
			(type solid)
		)
		(fill yes)
		(layer "In13.Cu")
		(net "M_B_CPU1_SA_DQS_DN<6>")
	)
	(gr_poly
		(pts
			(xy 80.861154 -232.132632) (xy 80.861154 -232.08488) (xy 80.661002 -232.08488) (xy 80.661002 -232.132632)
			(xy 80.761078 -232.232454)
		)
		(stroke
			(width 0)
			(type solid)
		)
		(fill yes)
		(layer "In13.Cu")
		(net "M_B_CPU1_SA_DQS_DN<1>")
	)
	(gr_poly
		(pts
			(xy 80.861154 -230.916226) (xy 80.761078 -230.81615) (xy 80.661002 -230.916226) (xy 80.661002 -230.960676)
			(xy 80.861154 -230.960676)
		)
		(stroke
			(width 0)
			(type solid)
		)
		(fill yes)
		(layer "In13.Cu")
		(net "M_B_CPU1_SA_DQ<9>")
	)
	(gr_poly
		(pts
			(xy 80.861154 -230.51262) (xy 80.861154 -230.46817) (xy 80.661002 -230.46817) (xy 80.661002 -230.51262)
			(xy 80.761078 -230.612696)
		)
		(stroke
			(width 0)
			(type solid)
		)
		(fill yes)
		(layer "In13.Cu")
		(net "M_B_CPU1_SA_DQ<10>")
	)
	(gr_poly
		(pts
			(xy 80.879442 -224.034604) (xy 80.916018 -223.897952) (xy 80.779366 -223.861376) (xy 80.738218 -223.885252)
			(xy 80.83804 -224.05848)
		)
		(stroke
			(width 0)
			(type solid)
		)
		(fill yes)
		(layer "In13.Cu")
		(net "M_B_CPU1_SA_DQS_DP<0>")
	)
	(gr_poly
		(pts
			(xy 80.879696 -228.895402) (xy 80.916272 -228.75875) (xy 80.77962 -228.722174) (xy 80.741012 -228.744272)
			(xy 80.841088 -228.9175)
		)
		(stroke
			(width 0)
			(type solid)
		)
		(fill yes)
		(layer "In13.Cu")
		(net "M_B_CPU1_SA_DQ<5>")
	)
	(gr_poly
		(pts
			(xy 80.879696 -227.27539) (xy 80.916272 -227.138738) (xy 80.77962 -227.102162) (xy 80.741012 -227.12426)
			(xy 80.841088 -227.297488)
		)
		(stroke
			(width 0)
			(type solid)
		)
		(fill yes)
		(layer "In13.Cu")
		(net "M_B_CPU1_SA_DQ<4>")
	)
	(gr_poly
		(pts
			(xy 80.87995 -222.415354) (xy 80.916526 -222.278702) (xy 80.779874 -222.242126) (xy 80.741266 -222.264224)
			(xy 80.841342 -222.437452)
		)
		(stroke
			(width 0)
			(type solid)
		)
		(fill yes)
		(layer "In13.Cu")
		(net "M_B_CPU1_SA_DQ<1>")
	)
	(gr_poly
		(pts
			(xy 80.880458 -225.656902) (xy 80.917034 -225.52025) (xy 80.780382 -225.483674) (xy 80.739234 -225.507296)
			(xy 80.839056 -225.680524)
		)
		(stroke
			(width 0)
			(type solid)
		)
		(fill yes)
		(layer "In13.Cu")
		(net "M_B_CPU1_SA_DQS_DN<5>")
	)
	(gr_poly
		(pts
			(xy 81.081118 -293.175944) (xy 81.04251 -293.153846) (xy 80.905858 -293.190422) (xy 80.942434 -293.327074)
			(xy 80.981042 -293.349172)
		)
		(stroke
			(width 0)
			(type solid)
		)
		(fill yes)
		(layer "In13.Cu")
		(net "M_B_CPU1_SB_DQ<29>")
	)
	(gr_poly
		(pts
			(xy 81.161128 -292.108128) (xy 81.061052 -292.008052) (xy 80.960976 -292.108128) (xy 80.960976 -292.152578)
			(xy 81.161128 -292.152578)
		)
		(stroke
			(width 0)
			(type solid)
		)
		(fill yes)
		(layer "In13.Cu")
		(net "M_B_CPU1_SB_DQ<28>")
	)
	(gr_poly
		(pts
			(xy 81.161128 -291.704522) (xy 81.161128 -291.65677) (xy 80.960976 -291.65677) (xy 80.960976 -291.704522)
			(xy 81.061052 -291.804344)
		)
		(stroke
			(width 0)
			(type solid)
		)
		(fill yes)
		(layer "In13.Cu")
		(net "M_B_CPU1_SB_DQS_DP<8>")
	)
	(gr_poly
		(pts
			(xy 81.161128 -290.487862) (xy 81.061052 -290.38804) (xy 80.960976 -290.487862) (xy 80.960976 -290.535614)
			(xy 81.161128 -290.535614)
		)
		(stroke
			(width 0)
			(type solid)
		)
		(fill yes)
		(layer "In13.Cu")
		(net "M_B_CPU1_SB_DQS_DP<3>")
	)
	(gr_poly
		(pts
			(xy 81.161128 -290.084256) (xy 81.161128 -290.039806) (xy 80.960976 -290.039806) (xy 80.960976 -290.084256)
			(xy 81.061052 -290.184332)
		)
		(stroke
			(width 0)
			(type solid)
		)
		(fill yes)
		(layer "In13.Cu")
		(net "M_B_CPU1_SB_DQ<27>")
	)
	(gr_poly
		(pts
			(xy 81.161128 -288.868104) (xy 81.061052 -288.768028) (xy 80.960976 -288.868104) (xy 80.960976 -288.912554)
			(xy 81.161128 -288.912554)
		)
		(stroke
			(width 0)
			(type solid)
		)
		(fill yes)
		(layer "In13.Cu")
		(net "M_B_CPU1_SB_DQ<24>")
	)
	(gr_poly
		(pts
			(xy 81.161128 -288.464498) (xy 81.161128 -288.420048) (xy 80.960976 -288.420048) (xy 80.960976 -288.464498)
			(xy 81.061052 -288.564574)
		)
		(stroke
			(width 0)
			(type solid)
		)
		(fill yes)
		(layer "In13.Cu")
		(net "M_B_CPU1_SB_DQ<23>")
	)
	(gr_poly
		(pts
			(xy 81.161128 -287.248092) (xy 81.061052 -287.148016) (xy 80.960976 -287.248092) (xy 80.960976 -287.292542)
			(xy 81.161128 -287.292542)
		)
		(stroke
			(width 0)
			(type solid)
		)
		(fill yes)
		(layer "In13.Cu")
		(net "M_B_CPU1_SB_DQ<20>")
	)
	(gr_poly
		(pts
			(xy 81.161128 -286.844486) (xy 81.161128 -286.796734) (xy 80.960976 -286.796734) (xy 80.960976 -286.844486)
			(xy 81.061052 -286.944562)
		)
		(stroke
			(width 0)
			(type solid)
		)
		(fill yes)
		(layer "In13.Cu")
		(net "M_B_CPU1_SB_DQS_DP<7>")
	)
	(gr_poly
		(pts
			(xy 81.161128 -285.62808) (xy 81.061052 -285.528258) (xy 80.960976 -285.62808) (xy 80.960976 -285.675832)
			(xy 81.161128 -285.675832)
		)
		(stroke
			(width 0)
			(type solid)
		)
		(fill yes)
		(layer "In13.Cu")
		(net "M_B_CPU1_SB_DQS_DP<2>")
	)
	(gr_poly
		(pts
			(xy 81.161128 -285.224474) (xy 81.161128 -285.180024) (xy 80.960976 -285.180024) (xy 80.960976 -285.224474)
			(xy 81.061052 -285.32455)
		)
		(stroke
			(width 0)
			(type solid)
		)
		(fill yes)
		(layer "In13.Cu")
		(net "M_B_CPU1_SB_DQ<19>")
	)
	(gr_poly
		(pts
			(xy 81.161128 -284.008322) (xy 81.061052 -283.908246) (xy 80.960976 -284.008322) (xy 80.960976 -284.052772)
			(xy 81.161128 -284.052772)
		)
		(stroke
			(width 0)
			(type solid)
		)
		(fill yes)
		(layer "In13.Cu")
		(net "M_B_CPU1_SB_DQ<16>")
	)
	(gr_poly
		(pts
			(xy 81.161128 -283.604462) (xy 81.161128 -283.560012) (xy 80.960976 -283.560012) (xy 80.960976 -283.604462)
			(xy 81.061052 -283.704538)
		)
		(stroke
			(width 0)
			(type solid)
		)
		(fill yes)
		(layer "In13.Cu")
		(net "M_B_CPU1_SB_DQ<15>")
	)
	(gr_poly
		(pts
			(xy 81.161128 -282.38831) (xy 81.061052 -282.288234) (xy 80.960976 -282.38831) (xy 80.960976 -282.43276)
			(xy 81.161128 -282.43276)
		)
		(stroke
			(width 0)
			(type solid)
		)
		(fill yes)
		(layer "In13.Cu")
		(net "M_B_CPU1_SB_DQ<12>")
	)
	(gr_poly
		(pts
			(xy 81.161128 -281.984704) (xy 81.161128 -281.936952) (xy 80.960976 -281.936952) (xy 80.960976 -281.984704)
			(xy 81.061052 -282.084526)
		)
		(stroke
			(width 0)
			(type solid)
		)
		(fill yes)
		(layer "In13.Cu")
		(net "M_B_CPU1_SB_DQS_DP<6>")
	)
	(gr_poly
		(pts
			(xy 81.161128 -280.768044) (xy 81.061052 -280.668222) (xy 80.960976 -280.768044) (xy 80.960976 -280.815796)
			(xy 81.161128 -280.815796)
		)
		(stroke
			(width 0)
			(type solid)
		)
		(fill yes)
		(layer "In13.Cu")
		(net "M_B_CPU1_SB_DQS_DP<1>")
	)
	(gr_poly
		(pts
			(xy 81.161128 -280.364438) (xy 81.161128 -280.319988) (xy 80.960976 -280.319988) (xy 80.960976 -280.364438)
			(xy 81.061052 -280.464514)
		)
		(stroke
			(width 0)
			(type solid)
		)
		(fill yes)
		(layer "In13.Cu")
		(net "M_B_CPU1_SB_DQ<11>")
	)
	(gr_poly
		(pts
			(xy 81.161128 -279.148286) (xy 81.061052 -279.04821) (xy 80.960976 -279.148286) (xy 80.960976 -279.192736)
			(xy 81.161128 -279.192736)
		)
		(stroke
			(width 0)
			(type solid)
		)
		(fill yes)
		(layer "In13.Cu")
		(net "M_B_CPU1_SB_DQ<8>")
	)
	(gr_poly
		(pts
			(xy 81.161128 -278.744426) (xy 81.161128 -278.699976) (xy 80.960976 -278.699976) (xy 80.960976 -278.744426)
			(xy 81.061052 -278.844502)
		)
		(stroke
			(width 0)
			(type solid)
		)
		(fill yes)
		(layer "In13.Cu")
		(net "M_B_CPU1_SB_DQ<7>")
	)
	(gr_poly
		(pts
			(xy 81.161128 -277.528274) (xy 81.061052 -277.428198) (xy 80.960976 -277.528274) (xy 80.960976 -277.572724)
			(xy 81.161128 -277.572724)
		)
		(stroke
			(width 0)
			(type solid)
		)
		(fill yes)
		(layer "In13.Cu")
		(net "M_B_CPU1_SB_DQ<4>")
	)
	(gr_poly
		(pts
			(xy 81.161128 -277.124668) (xy 81.161128 -277.076916) (xy 80.960976 -277.076916) (xy 80.960976 -277.124668)
			(xy 81.061052 -277.22449)
		)
		(stroke
			(width 0)
			(type solid)
		)
		(fill yes)
		(layer "In13.Cu")
		(net "M_B_CPU1_SB_DQS_DP<5>")
	)
	(gr_poly
		(pts
			(xy 81.161128 -275.908008) (xy 81.061052 -275.808186) (xy 80.960976 -275.908008) (xy 80.960976 -275.95576)
			(xy 81.161128 -275.95576)
		)
		(stroke
			(width 0)
			(type solid)
		)
		(fill yes)
		(layer "In13.Cu")
		(net "M_B_CPU1_SB_DQS_DP<0>")
	)
	(gr_poly
		(pts
			(xy 81.161128 -275.504402) (xy 81.161128 -275.459952) (xy 80.960976 -275.459952) (xy 80.960976 -275.504402)
			(xy 81.061052 -275.604478)
		)
		(stroke
			(width 0)
			(type solid)
		)
		(fill yes)
		(layer "In13.Cu")
		(net "M_B_CPU1_SB_DQ<3>")
	)
	(gr_poly
		(pts
			(xy 81.161128 -274.28825) (xy 81.061052 -274.188174) (xy 80.960976 -274.28825) (xy 80.960976 -274.3327)
			(xy 81.161128 -274.3327)
		)
		(stroke
			(width 0)
			(type solid)
		)
		(fill yes)
		(layer "In13.Cu")
		(net "M_B_CPU1_SB_DQ<0>")
	)
	(gr_poly
		(pts
			(xy 81.161128 -273.88439) (xy 81.161128 -273.83994) (xy 80.960976 -273.83994) (xy 80.960976 -273.88439)
			(xy 81.061052 -273.984466)
		)
		(stroke
			(width 0)
			(type solid)
		)
		(fill yes)
		(layer "In13.Cu")
		(net "M_B_CPU1_SB_CB<3>")
	)
	(gr_poly
		(pts
			(xy 81.161128 -272.668238) (xy 81.061052 -272.568162) (xy 80.960976 -272.668238) (xy 80.960976 -272.712688)
			(xy 81.161128 -272.712688)
		)
		(stroke
			(width 0)
			(type solid)
		)
		(fill yes)
		(layer "In13.Cu")
		(net "M_B_CPU1_SB_CB<0>")
	)
	(gr_poly
		(pts
			(xy 81.161128 -272.264632) (xy 81.161128 -272.21688) (xy 80.960976 -272.21688) (xy 80.960976 -272.264632)
			(xy 81.061052 -272.364454)
		)
		(stroke
			(width 0)
			(type solid)
		)
		(fill yes)
		(layer "In13.Cu")
		(net "M_B_CPU1_SB_DQS_DP<4>")
	)
	(gr_poly
		(pts
			(xy 81.161128 -271.047972) (xy 81.061052 -270.94815) (xy 80.960976 -271.047972) (xy 80.960976 -271.095724)
			(xy 81.161128 -271.095724)
		)
		(stroke
			(width 0)
			(type solid)
		)
		(fill yes)
		(layer "In13.Cu")
		(net "M_B_CPU1_SB_DQS_DP<9>")
	)
	(gr_poly
		(pts
			(xy 81.161128 -270.644366) (xy 81.161128 -270.599916) (xy 80.960976 -270.599916) (xy 80.960976 -270.644366)
			(xy 81.061052 -270.744442)
		)
		(stroke
			(width 0)
			(type solid)
		)
		(fill yes)
		(layer "In13.Cu")
		(net "M_B_CPU1_SB_CB<7>")
	)
	(gr_poly
		(pts
			(xy 81.161128 -269.428214) (xy 81.061052 -269.328138) (xy 80.960976 -269.428214) (xy 80.960976 -269.472664)
			(xy 81.161128 -269.472664)
		)
		(stroke
			(width 0)
			(type solid)
		)
		(fill yes)
		(layer "In13.Cu")
		(net "M_B_CPU1_SB_CB<4>")
	)
	(gr_poly
		(pts
			(xy 81.161128 -267.801852) (xy 81.061052 -267.701776) (xy 80.960976 -267.801852) (xy 80.960976 -267.846302)
			(xy 81.161128 -267.846302)
		)
		(stroke
			(width 0)
			(type solid)
		)
		(fill yes)
		(layer "In13.Cu")
		(net "M_B_CPU1_SB_RSP<0>")
	)
	(gr_poly
		(pts
			(xy 81.161128 -265.78433) (xy 81.161128 -265.73988) (xy 80.960976 -265.73988) (xy 80.960976 -265.78433)
			(xy 81.061052 -265.884406)
		)
		(stroke
			(width 0)
			(type solid)
		)
		(fill yes)
		(layer "In13.Cu")
		(net "M_B_CPU1_SB_CS_N<0>")
	)
	(gr_poly
		(pts
			(xy 81.161128 -264.568178) (xy 81.061052 -264.468102) (xy 80.960976 -264.568178) (xy 80.960976 -264.612628)
			(xy 81.161128 -264.612628)
		)
		(stroke
			(width 0)
			(type solid)
		)
		(fill yes)
		(layer "In13.Cu")
		(net "M_B_CPU1_SB_CA<6>")
	)
	(gr_poly
		(pts
			(xy 81.161128 -264.164318) (xy 81.161128 -264.119868) (xy 80.960976 -264.119868) (xy 80.960976 -264.164318)
			(xy 81.061052 -264.264394)
		)
		(stroke
			(width 0)
			(type solid)
		)
		(fill yes)
		(layer "In13.Cu")
		(net "M_B_CPU1_SB_CA<5>")
	)
	(gr_poly
		(pts
			(xy 81.161128 -262.948166) (xy 81.061052 -262.84809) (xy 80.960976 -262.948166) (xy 80.960976 -262.992616)
			(xy 81.161128 -262.992616)
		)
		(stroke
			(width 0)
			(type solid)
		)
		(fill yes)
		(layer "In13.Cu")
		(net "M_B_CPU1_SB_CA<2>")
	)
	(gr_poly
		(pts
			(xy 81.161128 -262.544306) (xy 81.161128 -262.499856) (xy 80.960976 -262.499856) (xy 80.960976 -262.544306)
			(xy 81.061052 -262.644382)
		)
		(stroke
			(width 0)
			(type solid)
		)
		(fill yes)
		(layer "In13.Cu")
		(net "M_B_CPU1_SB_CA<1>")
	)
	(gr_poly
		(pts
			(xy 81.216754 -295.48074) (xy 81.180178 -295.344088) (xy 81.141824 -295.321736) (xy 81.041748 -295.494964)
			(xy 81.080356 -295.517316)
		)
		(stroke
			(width 0)
			(type solid)
		)
		(fill yes)
		(layer "In13.Cu")
		(net "M_B_CPU1_SB_DQ<31>")
	)
	(gr_poly
		(pts
			(xy 81.250282 -228.633274) (xy 81.150206 -228.460046) (xy 81.111852 -228.482398) (xy 81.075022 -228.61905)
			(xy 81.211674 -228.655626)
		)
		(stroke
			(width 0)
			(type solid)
		)
		(fill yes)
		(layer "In13.Cu")
		(net "M_B_CPU1_SA_DQ<6>")
	)
	(gr_poly
		(pts
			(xy 81.250282 -223.773238) (xy 81.150206 -223.60001) (xy 81.111852 -223.622362) (xy 81.075022 -223.759014)
			(xy 81.211674 -223.79559)
		)
		(stroke
			(width 0)
			(type solid)
		)
		(fill yes)
		(layer "In13.Cu")
		(net "M_B_CPU1_SA_DQ<3>")
	)
	(gr_poly
		(pts
			(xy 81.253076 -227.0125) (xy 81.153254 -226.839272) (xy 81.111852 -226.863148) (xy 81.075276 -226.999546)
			(xy 81.211928 -227.036376)
		)
		(stroke
			(width 0)
			(type solid)
		)
		(fill yes)
		(layer "In13.Cu")
		(net "M_B_CPU1_SA_DQS_DP<5>")
	)
	(gr_poly
		(pts
			(xy 81.253076 -225.392488) (xy 81.153254 -225.21926) (xy 81.111852 -225.243136) (xy 81.075276 -225.379534)
			(xy 81.211928 -225.416364)
		)
		(stroke
			(width 0)
			(type solid)
		)
		(fill yes)
		(layer "In13.Cu")
		(net "M_B_CPU1_SA_DQS_DN<0>")
	)
	(gr_poly
		(pts
			(xy 81.331054 -256.026158) (xy 81.230978 -255.926336) (xy 81.130902 -256.026158) (xy 81.130902 -256.07391)
			(xy 81.331054 -256.07391)
		)
		(stroke
			(width 0)
			(type solid)
		)
		(fill yes)
		(layer "In13.Cu")
		(net "M_B_CPU1_CLK_DP<0>")
	)
	(gr_poly
		(pts
			(xy 81.331054 -255.622552) (xy 81.331054 -255.578102) (xy 81.130902 -255.578102) (xy 81.130902 -255.622552)
			(xy 81.230978 -255.722628)
		)
		(stroke
			(width 0)
			(type solid)
		)
		(fill yes)
		(layer "In13.Cu")
		(net "M_B_CPU1_SA_PAR")
	)
	(gr_poly
		(pts
			(xy 81.331054 -254.4064) (xy 81.230978 -254.306324) (xy 81.130902 -254.4064) (xy 81.130902 -254.45085)
			(xy 81.331054 -254.45085)
		)
		(stroke
			(width 0)
			(type solid)
		)
		(fill yes)
		(layer "In13.Cu")
		(net "M_B_CPU1_SA_CA<4>")
	)
	(gr_poly
		(pts
			(xy 81.331054 -254.00254) (xy 81.331054 -253.95809) (xy 81.130902 -253.95809) (xy 81.130902 -254.00254)
			(xy 81.230978 -254.102616)
		)
		(stroke
			(width 0)
			(type solid)
		)
		(fill yes)
		(layer "In13.Cu")
		(net "M_B_CPU1_SA_CA<3>")
	)
	(gr_poly
		(pts
			(xy 81.331054 -252.786388) (xy 81.230978 -252.686312) (xy 81.130902 -252.786388) (xy 81.130902 -252.830838)
			(xy 81.331054 -252.830838)
		)
		(stroke
			(width 0)
			(type solid)
		)
		(fill yes)
		(layer "In13.Cu")
		(net "M_B_CPU1_SA_CA<0>")
	)
	(gr_poly
		(pts
			(xy 81.331054 -252.382528) (xy 81.331054 -252.338078) (xy 81.130902 -252.338078) (xy 81.130902 -252.382528)
			(xy 81.230978 -252.482604)
		)
		(stroke
			(width 0)
			(type solid)
		)
		(fill yes)
		(layer "In13.Cu")
		(net "M_B_CPU1_SA_CS_N<1>")
	)
	(gr_poly
		(pts
			(xy 81.331054 -250.762516) (xy 81.331054 -250.718066) (xy 81.130902 -250.718066) (xy 81.130902 -250.762516)
			(xy 81.230978 -250.862592)
		)
		(stroke
			(width 0)
			(type solid)
		)
		(fill yes)
		(layer "In13.Cu")
		(net "M_B_CPU1_RESET_N")
	)
	(gr_poly
		(pts
			(xy 81.331054 -249.142504) (xy 81.331054 -249.098054) (xy 81.130902 -249.098054) (xy 81.130902 -249.142504)
			(xy 81.230978 -249.24258)
		)
		(stroke
			(width 0)
			(type solid)
		)
		(fill yes)
		(layer "In13.Cu")
		(net "M_B_CPU1_SA_CB<7>")
	)
	(gr_poly
		(pts
			(xy 81.331054 -247.926352) (xy 81.230978 -247.826276) (xy 81.130902 -247.926352) (xy 81.130902 -247.970802)
			(xy 81.331054 -247.970802)
		)
		(stroke
			(width 0)
			(type solid)
		)
		(fill yes)
		(layer "In13.Cu")
		(net "M_B_CPU1_SA_CB<4>")
	)
	(gr_poly
		(pts
			(xy 81.331054 -247.522746) (xy 81.331054 -247.474994) (xy 81.130902 -247.474994) (xy 81.130902 -247.522746)
			(xy 81.230978 -247.622568)
		)
		(stroke
			(width 0)
			(type solid)
		)
		(fill yes)
		(layer "In13.Cu")
		(net "M_B_CPU1_SA_DQS_DP<9>")
	)
	(gr_poly
		(pts
			(xy 81.331054 -246.306086) (xy 81.230978 -246.206264) (xy 81.130902 -246.306086) (xy 81.130902 -246.353838)
			(xy 81.331054 -246.353838)
		)
		(stroke
			(width 0)
			(type solid)
		)
		(fill yes)
		(layer "In13.Cu")
		(net "M_B_CPU1_SA_DQS_DP<4>")
	)
	(gr_poly
		(pts
			(xy 81.331054 -245.90248) (xy 81.331054 -245.85803) (xy 81.130902 -245.85803) (xy 81.130902 -245.90248)
			(xy 81.230978 -246.002556)
		)
		(stroke
			(width 0)
			(type solid)
		)
		(fill yes)
		(layer "In13.Cu")
		(net "M_B_CPU1_SA_CB<3>")
	)
	(gr_poly
		(pts
			(xy 81.331054 -244.686328) (xy 81.230978 -244.586252) (xy 81.130902 -244.686328) (xy 81.130902 -244.730778)
			(xy 81.331054 -244.730778)
		)
		(stroke
			(width 0)
			(type solid)
		)
		(fill yes)
		(layer "In13.Cu")
		(net "M_B_CPU1_SA_CB<0>")
	)
	(gr_poly
		(pts
			(xy 81.331054 -244.282468) (xy 81.331054 -244.238018) (xy 81.130902 -244.238018) (xy 81.130902 -244.282468)
			(xy 81.230978 -244.382544)
		)
		(stroke
			(width 0)
			(type solid)
		)
		(fill yes)
		(layer "In13.Cu")
		(net "M_B_CPU1_SA_DQ<31>")
	)
	(gr_poly
		(pts
			(xy 81.331054 -243.066316) (xy 81.230978 -242.96624) (xy 81.130902 -243.066316) (xy 81.130902 -243.110766)
			(xy 81.331054 -243.110766)
		)
		(stroke
			(width 0)
			(type solid)
		)
		(fill yes)
		(layer "In13.Cu")
		(net "M_B_CPU1_SA_DQ<28>")
	)
	(gr_poly
		(pts
			(xy 81.331054 -242.66271) (xy 81.331054 -242.614958) (xy 81.130902 -242.614958) (xy 81.130902 -242.66271)
			(xy 81.230978 -242.762532)
		)
		(stroke
			(width 0)
			(type solid)
		)
		(fill yes)
		(layer "In13.Cu")
		(net "M_B_CPU1_SA_DQS_DP<8>")
	)
	(gr_poly
		(pts
			(xy 81.331054 -241.44605) (xy 81.230978 -241.346228) (xy 81.130902 -241.44605) (xy 81.130902 -241.493802)
			(xy 81.331054 -241.493802)
		)
		(stroke
			(width 0)
			(type solid)
		)
		(fill yes)
		(layer "In13.Cu")
		(net "M_B_CPU1_SA_DQS_DP<3>")
	)
	(gr_poly
		(pts
			(xy 81.331054 -241.042444) (xy 81.331054 -240.997994) (xy 81.130902 -240.997994) (xy 81.130902 -241.042444)
			(xy 81.230978 -241.14252)
		)
		(stroke
			(width 0)
			(type solid)
		)
		(fill yes)
		(layer "In13.Cu")
		(net "M_B_CPU1_SA_DQ<27>")
	)
	(gr_poly
		(pts
			(xy 81.331054 -239.826292) (xy 81.230978 -239.726216) (xy 81.130902 -239.826292) (xy 81.130902 -239.870742)
			(xy 81.331054 -239.870742)
		)
		(stroke
			(width 0)
			(type solid)
		)
		(fill yes)
		(layer "In13.Cu")
		(net "M_B_CPU1_SA_DQ<24>")
	)
	(gr_poly
		(pts
			(xy 81.331054 -239.422432) (xy 81.331054 -239.377982) (xy 81.130902 -239.377982) (xy 81.130902 -239.422432)
			(xy 81.230978 -239.522508)
		)
		(stroke
			(width 0)
			(type solid)
		)
		(fill yes)
		(layer "In13.Cu")
		(net "M_B_CPU1_SA_DQ<23>")
	)
	(gr_poly
		(pts
			(xy 81.331054 -238.20628) (xy 81.230978 -238.106204) (xy 81.130902 -238.20628) (xy 81.130902 -238.25073)
			(xy 81.331054 -238.25073)
		)
		(stroke
			(width 0)
			(type solid)
		)
		(fill yes)
		(layer "In13.Cu")
		(net "M_B_CPU1_SA_DQ<20>")
	)
	(gr_poly
		(pts
			(xy 81.331054 -237.802674) (xy 81.331054 -237.754922) (xy 81.130902 -237.754922) (xy 81.130902 -237.802674)
			(xy 81.230978 -237.902496)
		)
		(stroke
			(width 0)
			(type solid)
		)
		(fill yes)
		(layer "In13.Cu")
		(net "M_B_CPU1_SA_DQS_DP<7>")
	)
	(gr_poly
		(pts
			(xy 81.331054 -236.586014) (xy 81.230978 -236.486192) (xy 81.130902 -236.586014) (xy 81.130902 -236.633766)
			(xy 81.331054 -236.633766)
		)
		(stroke
			(width 0)
			(type solid)
		)
		(fill yes)
		(layer "In13.Cu")
		(net "M_B_CPU1_SA_DQS_DP<2>")
	)
	(gr_poly
		(pts
			(xy 81.331054 -236.182408) (xy 81.331054 -236.137958) (xy 81.130902 -236.137958) (xy 81.130902 -236.182408)
			(xy 81.230978 -236.282484)
		)
		(stroke
			(width 0)
			(type solid)
		)
		(fill yes)
		(layer "In13.Cu")
		(net "M_B_CPU1_SA_DQ<19>")
	)
	(gr_poly
		(pts
			(xy 81.331054 -234.966256) (xy 81.230978 -234.86618) (xy 81.130902 -234.966256) (xy 81.130902 -235.010706)
			(xy 81.331054 -235.010706)
		)
		(stroke
			(width 0)
			(type solid)
		)
		(fill yes)
		(layer "In13.Cu")
		(net "M_B_CPU1_SA_DQ<16>")
	)
	(gr_poly
		(pts
			(xy 81.331054 -234.562396) (xy 81.331054 -234.517946) (xy 81.130902 -234.517946) (xy 81.130902 -234.562396)
			(xy 81.230978 -234.662472)
		)
		(stroke
			(width 0)
			(type solid)
		)
		(fill yes)
		(layer "In13.Cu")
		(net "M_B_CPU1_SA_DQ<15>")
	)
	(gr_poly
		(pts
			(xy 81.331054 -233.346244) (xy 81.230978 -233.246168) (xy 81.130902 -233.346244) (xy 81.130902 -233.390694)
			(xy 81.331054 -233.390694)
		)
		(stroke
			(width 0)
			(type solid)
		)
		(fill yes)
		(layer "In13.Cu")
		(net "M_B_CPU1_SA_DQ<12>")
	)
	(gr_poly
		(pts
			(xy 81.331054 -232.942638) (xy 81.331054 -232.894886) (xy 81.130902 -232.894886) (xy 81.130902 -232.942638)
			(xy 81.230978 -233.04246)
		)
		(stroke
			(width 0)
			(type solid)
		)
		(fill yes)
		(layer "In13.Cu")
		(net "M_B_CPU1_SA_DQS_DP<6>")
	)
	(gr_poly
		(pts
			(xy 81.331054 -231.725978) (xy 81.230978 -231.626156) (xy 81.130902 -231.725978) (xy 81.130902 -231.77373)
			(xy 81.331054 -231.77373)
		)
		(stroke
			(width 0)
			(type solid)
		)
		(fill yes)
		(layer "In13.Cu")
		(net "M_B_CPU1_SA_DQS_DP<1>")
	)
	(gr_poly
		(pts
			(xy 81.331054 -231.322626) (xy 81.331054 -231.278176) (xy 81.130902 -231.278176) (xy 81.130902 -231.322626)
			(xy 81.230978 -231.422702)
		)
		(stroke
			(width 0)
			(type solid)
		)
		(fill yes)
		(layer "In13.Cu")
		(net "M_B_CPU1_SA_DQ<11>")
	)
	(gr_poly
		(pts
			(xy 81.331054 -230.10622) (xy 81.230978 -230.006144) (xy 81.130902 -230.10622) (xy 81.130902 -230.15067)
			(xy 81.331054 -230.15067)
		)
		(stroke
			(width 0)
			(type solid)
		)
		(fill yes)
		(layer "In13.Cu")
		(net "M_B_CPU1_SA_DQ<8>")
	)
	(gr_poly
		(pts
			(xy 81.331054 -229.702614) (xy 81.331054 -229.658164) (xy 81.130902 -229.658164) (xy 81.130902 -229.702614)
			(xy 81.230978 -229.80269)
		)
		(stroke
			(width 0)
			(type solid)
		)
		(fill yes)
		(layer "In13.Cu")
		(net "M_B_CPU1_SA_DQ<7>")
	)
	(gr_poly
		(pts
			(xy 81.350358 -228.086666) (xy 81.386934 -227.950014) (xy 81.250536 -227.913438) (xy 81.211928 -227.93579)
			(xy 81.312004 -228.109018)
		)
		(stroke
			(width 0)
			(type solid)
		)
		(fill yes)
		(layer "In13.Cu")
		(net "M_B_CPU1_SA_DQ<4>")
	)
	(gr_poly
		(pts
			(xy 81.350358 -226.466908) (xy 81.386934 -226.330256) (xy 81.250282 -226.29368) (xy 81.209134 -226.317302)
			(xy 81.308956 -226.49053)
		)
		(stroke
			(width 0)
			(type solid)
		)
		(fill yes)
		(layer "In13.Cu")
		(net "M_B_CPU1_SA_DQS_DN<5>")
	)
	(gr_poly
		(pts
			(xy 81.350358 -224.84588) (xy 81.386934 -224.709482) (xy 81.250282 -224.672652) (xy 81.209134 -224.696528)
			(xy 81.308956 -224.869756)
		)
		(stroke
			(width 0)
			(type solid)
		)
		(fill yes)
		(layer "In13.Cu")
		(net "M_B_CPU1_SA_DQS_DP<0>")
	)
	(gr_poly
		(pts
			(xy 81.350358 -223.22663) (xy 81.386934 -223.089978) (xy 81.250536 -223.053402) (xy 81.211928 -223.075754)
			(xy 81.312004 -223.248982)
		)
		(stroke
			(width 0)
			(type solid)
		)
		(fill yes)
		(layer "In13.Cu")
		(net "M_B_CPU1_SA_DQ<1>")
	)
	(gr_poly
		(pts
			(xy 81.631028 -292.514274) (xy 81.631028 -292.469824) (xy 81.430876 -292.469824) (xy 81.430876 -292.514274)
			(xy 81.530952 -292.61435)
		)
		(stroke
			(width 0)
			(type solid)
		)
		(fill yes)
		(layer "In13.Cu")
		(net "M_B_CPU1_SB_DQ<30>")
	)
	(gr_poly
		(pts
			(xy 81.631028 -291.297868) (xy 81.530952 -291.198046) (xy 81.430876 -291.297868) (xy 81.430876 -291.34562)
			(xy 81.631028 -291.34562)
		)
		(stroke
			(width 0)
			(type solid)
		)
		(fill yes)
		(layer "In13.Cu")
		(net "M_B_CPU1_SB_DQS_DN<8>")
	)
	(gr_poly
		(pts
			(xy 81.631028 -290.894516) (xy 81.631028 -290.846764) (xy 81.430876 -290.846764) (xy 81.430876 -290.894516)
			(xy 81.530952 -290.994338)
		)
		(stroke
			(width 0)
			(type solid)
		)
		(fill yes)
		(layer "In13.Cu")
		(net "M_B_CPU1_SB_DQS_DN<3>")
	)
	(gr_poly
		(pts
			(xy 81.631028 -289.67811) (xy 81.530952 -289.578034) (xy 81.430876 -289.67811) (xy 81.430876 -289.72256)
			(xy 81.631028 -289.72256)
		)
		(stroke
			(width 0)
			(type solid)
		)
		(fill yes)
		(layer "In13.Cu")
		(net "M_B_CPU1_SB_DQ<25>")
	)
	(gr_poly
		(pts
			(xy 81.631028 -289.27425) (xy 81.631028 -289.2298) (xy 81.430876 -289.2298) (xy 81.430876 -289.27425)
			(xy 81.530952 -289.374326)
		)
		(stroke
			(width 0)
			(type solid)
		)
		(fill yes)
		(layer "In13.Cu")
		(net "M_B_CPU1_SB_DQ<26>")
	)
	(gr_poly
		(pts
			(xy 81.631028 -288.058098) (xy 81.530952 -287.958022) (xy 81.430876 -288.058098) (xy 81.430876 -288.102548)
			(xy 81.631028 -288.102548)
		)
		(stroke
			(width 0)
			(type solid)
		)
		(fill yes)
		(layer "In13.Cu")
		(net "M_B_CPU1_SB_DQ<21>")
	)
	(gr_poly
		(pts
			(xy 81.631028 -287.654492) (xy 81.631028 -287.610042) (xy 81.430876 -287.610042) (xy 81.430876 -287.654492)
			(xy 81.530952 -287.754568)
		)
		(stroke
			(width 0)
			(type solid)
		)
		(fill yes)
		(layer "In13.Cu")
		(net "M_B_CPU1_SB_DQ<22>")
	)
	(gr_poly
		(pts
			(xy 81.631028 -286.438086) (xy 81.530952 -286.33801) (xy 81.430876 -286.438086) (xy 81.430876 -286.485838)
			(xy 81.631028 -286.485838)
		)
		(stroke
			(width 0)
			(type solid)
		)
		(fill yes)
		(layer "In13.Cu")
		(net "M_B_CPU1_SB_DQS_DN<7>")
	)
	(gr_poly
		(pts
			(xy 81.631028 -286.034734) (xy 81.631028 -285.986982) (xy 81.430876 -285.986982) (xy 81.430876 -286.034734)
			(xy 81.530952 -286.134556)
		)
		(stroke
			(width 0)
			(type solid)
		)
		(fill yes)
		(layer "In13.Cu")
		(net "M_B_CPU1_SB_DQS_DN<2>")
	)
	(gr_poly
		(pts
			(xy 81.631028 -284.818328) (xy 81.530952 -284.718252) (xy 81.430876 -284.818328) (xy 81.430876 -284.862778)
			(xy 81.631028 -284.862778)
		)
		(stroke
			(width 0)
			(type solid)
		)
		(fill yes)
		(layer "In13.Cu")
		(net "M_B_CPU1_SB_DQ<17>")
	)
	(gr_poly
		(pts
			(xy 81.631028 -284.414468) (xy 81.631028 -284.370018) (xy 81.430876 -284.370018) (xy 81.430876 -284.414468)
			(xy 81.530952 -284.514544)
		)
		(stroke
			(width 0)
			(type solid)
		)
		(fill yes)
		(layer "In13.Cu")
		(net "M_B_CPU1_SB_DQ<18>")
	)
	(gr_poly
		(pts
			(xy 81.631028 -283.198316) (xy 81.530952 -283.09824) (xy 81.430876 -283.198316) (xy 81.430876 -283.242766)
			(xy 81.631028 -283.242766)
		)
		(stroke
			(width 0)
			(type solid)
		)
		(fill yes)
		(layer "In13.Cu")
		(net "M_B_CPU1_SB_DQ<13>")
	)
	(gr_poly
		(pts
			(xy 81.631028 -282.794456) (xy 81.631028 -282.750006) (xy 81.430876 -282.750006) (xy 81.430876 -282.794456)
			(xy 81.530952 -282.894532)
		)
		(stroke
			(width 0)
			(type solid)
		)
		(fill yes)
		(layer "In13.Cu")
		(net "M_B_CPU1_SB_DQ<14>")
	)
	(gr_poly
		(pts
			(xy 81.631028 -281.57805) (xy 81.530952 -281.478228) (xy 81.430876 -281.57805) (xy 81.430876 -281.625802)
			(xy 81.631028 -281.625802)
		)
		(stroke
			(width 0)
			(type solid)
		)
		(fill yes)
		(layer "In13.Cu")
		(net "M_B_CPU1_SB_DQS_DN<6>")
	)
	(gr_poly
		(pts
			(xy 81.631028 -281.174698) (xy 81.631028 -281.126946) (xy 81.430876 -281.126946) (xy 81.430876 -281.174698)
			(xy 81.530952 -281.27452)
		)
		(stroke
			(width 0)
			(type solid)
		)
		(fill yes)
		(layer "In13.Cu")
		(net "M_B_CPU1_SB_DQS_DN<1>")
	)
	(gr_poly
		(pts
			(xy 81.631028 -279.958292) (xy 81.530952 -279.858216) (xy 81.430876 -279.958292) (xy 81.430876 -280.002742)
			(xy 81.631028 -280.002742)
		)
		(stroke
			(width 0)
			(type solid)
		)
		(fill yes)
		(layer "In13.Cu")
		(net "M_B_CPU1_SB_DQ<9>")
	)
	(gr_poly
		(pts
			(xy 81.631028 -279.554432) (xy 81.631028 -279.509982) (xy 81.430876 -279.509982) (xy 81.430876 -279.554432)
			(xy 81.530952 -279.654508)
		)
		(stroke
			(width 0)
			(type solid)
		)
		(fill yes)
		(layer "In13.Cu")
		(net "M_B_CPU1_SB_DQ<10>")
	)
	(gr_poly
		(pts
			(xy 81.631028 -278.33828) (xy 81.530952 -278.238204) (xy 81.430876 -278.33828) (xy 81.430876 -278.38273)
			(xy 81.631028 -278.38273)
		)
		(stroke
			(width 0)
			(type solid)
		)
		(fill yes)
		(layer "In13.Cu")
		(net "M_B_CPU1_SB_DQ<5>")
	)
	(gr_poly
		(pts
			(xy 81.631028 -277.93442) (xy 81.631028 -277.88997) (xy 81.430876 -277.88997) (xy 81.430876 -277.93442)
			(xy 81.530952 -278.034496)
		)
		(stroke
			(width 0)
			(type solid)
		)
		(fill yes)
		(layer "In13.Cu")
		(net "M_B_CPU1_SB_DQ<6>")
	)
	(gr_poly
		(pts
			(xy 81.631028 -275.098256) (xy 81.530952 -274.99818) (xy 81.430876 -275.098256) (xy 81.430876 -275.142706)
			(xy 81.631028 -275.142706)
		)
		(stroke
			(width 0)
			(type solid)
		)
		(fill yes)
		(layer "In13.Cu")
		(net "M_B_CPU1_SB_DQ<1>")
	)
	(gr_poly
		(pts
			(xy 81.631028 -274.694396) (xy 81.631028 -274.649946) (xy 81.430876 -274.649946) (xy 81.430876 -274.694396)
			(xy 81.530952 -274.794472)
		)
		(stroke
			(width 0)
			(type solid)
		)
		(fill yes)
		(layer "In13.Cu")
		(net "M_B_CPU1_SB_DQ<2>")
	)
	(gr_poly
		(pts
			(xy 81.631028 -273.478244) (xy 81.530952 -273.378168) (xy 81.430876 -273.478244) (xy 81.430876 -273.522694)
			(xy 81.631028 -273.522694)
		)
		(stroke
			(width 0)
			(type solid)
		)
		(fill yes)
		(layer "In13.Cu")
		(net "M_B_CPU1_SB_CB<1>")
	)
	(gr_poly
		(pts
			(xy 81.631028 -273.074384) (xy 81.631028 -273.029934) (xy 81.430876 -273.029934) (xy 81.430876 -273.074384)
			(xy 81.530952 -273.17446)
		)
		(stroke
			(width 0)
			(type solid)
		)
		(fill yes)
		(layer "In13.Cu")
		(net "M_B_CPU1_SB_CB<2>")
	)
	(gr_poly
		(pts
			(xy 81.631028 -271.857978) (xy 81.530952 -271.758156) (xy 81.430876 -271.857978) (xy 81.430876 -271.90573)
			(xy 81.631028 -271.90573)
		)
		(stroke
			(width 0)
			(type solid)
		)
		(fill yes)
		(layer "In13.Cu")
		(net "M_B_CPU1_SB_DQS_DN<4>")
	)
	(gr_poly
		(pts
			(xy 81.631028 -271.454626) (xy 81.631028 -271.406874) (xy 81.430876 -271.406874) (xy 81.430876 -271.454626)
			(xy 81.530952 -271.554448)
		)
		(stroke
			(width 0)
			(type solid)
		)
		(fill yes)
		(layer "In13.Cu")
		(net "M_B_CPU1_SB_DQS_DN<9>")
	)
	(gr_poly
		(pts
			(xy 81.631028 -270.23822) (xy 81.530952 -270.138144) (xy 81.430876 -270.23822) (xy 81.430876 -270.28267)
			(xy 81.631028 -270.28267)
		)
		(stroke
			(width 0)
			(type solid)
		)
		(fill yes)
		(layer "In13.Cu")
		(net "M_B_CPU1_SB_CB<5>")
	)
	(gr_poly
		(pts
			(xy 81.631028 -269.83436) (xy 81.631028 -269.78991) (xy 81.430876 -269.78991) (xy 81.430876 -269.83436)
			(xy 81.530952 -269.934436)
		)
		(stroke
			(width 0)
			(type solid)
		)
		(fill yes)
		(layer "In13.Cu")
		(net "M_B_CPU1_SB_CB<6>")
	)
	(gr_poly
		(pts
			(xy 81.631028 -266.594336) (xy 81.631028 -266.549886) (xy 81.430876 -266.549886) (xy 81.430876 -266.594336)
			(xy 81.530952 -266.694412)
		)
		(stroke
			(width 0)
			(type solid)
		)
		(fill yes)
		(layer "In13.Cu")
		(net "M_B_CPU1_SB_CS_N<1>")
	)
	(gr_poly
		(pts
			(xy 81.631028 -264.974324) (xy 81.631028 -264.929874) (xy 81.430876 -264.929874) (xy 81.430876 -264.974324)
			(xy 81.530952 -265.0744)
		)
		(stroke
			(width 0)
			(type solid)
		)
		(fill yes)
		(layer "In13.Cu")
		(net "M_B_CPU1_SB_PAR")
	)
	(gr_poly
		(pts
			(xy 81.631028 -263.758172) (xy 81.530952 -263.658096) (xy 81.430876 -263.758172) (xy 81.430876 -263.802622)
			(xy 81.631028 -263.802622)
		)
		(stroke
			(width 0)
			(type solid)
		)
		(fill yes)
		(layer "In13.Cu")
		(net "M_B_CPU1_SB_CA<4>")
	)
	(gr_poly
		(pts
			(xy 81.631028 -263.354312) (xy 81.631028 -263.309862) (xy 81.430876 -263.309862) (xy 81.430876 -263.354312)
			(xy 81.530952 -263.454388)
		)
		(stroke
			(width 0)
			(type solid)
		)
		(fill yes)
		(layer "In13.Cu")
		(net "M_B_CPU1_SB_CA<3>")
	)
	(gr_poly
		(pts
			(xy 81.631028 -262.13816) (xy 81.530952 -262.038084) (xy 81.430876 -262.13816) (xy 81.430876 -262.18261)
			(xy 81.631028 -262.18261)
		)
		(stroke
			(width 0)
			(type solid)
		)
		(fill yes)
		(layer "In13.Cu")
		(net "M_B_CPU1_SB_CA<0>")
	)
	(gr_poly
		(pts
			(xy 81.637124 -266.991846) (xy 81.537302 -266.89177) (xy 81.437226 -266.991846) (xy 81.437226 -267.036296)
			(xy 81.637124 -267.036296)
		)
		(stroke
			(width 0)
			(type solid)
		)
		(fill yes)
		(layer "In13.Cu")
		(net "M_B_CPU1_SA_RSP<0>")
	)
	(gr_poly
		(pts
			(xy 81.638394 -276.718268) (xy 81.538318 -276.618192) (xy 81.438242 -276.718268) (xy 81.438242 -276.765766)
			(xy 81.638394 -276.765766)
		)
		(stroke
			(width 0)
			(type solid)
		)
		(fill yes)
		(layer "In13.Cu")
		(net "M_B_CPU1_SB_DQS_DN<5>")
	)
	(gr_poly
		(pts
			(xy 81.638394 -276.314408) (xy 81.638394 -276.26691) (xy 81.438242 -276.26691) (xy 81.438242 -276.314408)
			(xy 81.538318 -276.414484)
		)
		(stroke
			(width 0)
			(type solid)
		)
		(fill yes)
		(layer "In13.Cu")
		(net "M_B_CPU1_SB_DQS_DN<0>")
	)
	(gr_poly
		(pts
			(xy 81.687162 -294.670734) (xy 81.650332 -294.534082) (xy 81.611978 -294.51173) (xy 81.511902 -294.684958)
			(xy 81.55051 -294.70731)
		)
		(stroke
			(width 0)
			(type solid)
		)
		(fill yes)
		(layer "In13.Cu")
		(net "M_B_CPU1_SB_DQ<31>")
	)
	(gr_poly
		(pts
			(xy 81.720182 -224.583244) (xy 81.620106 -224.410016) (xy 81.581752 -224.432368) (xy 81.544922 -224.56902)
			(xy 81.681574 -224.605596)
		)
		(stroke
			(width 0)
			(type solid)
		)
		(fill yes)
		(layer "In13.Cu")
		(net "M_B_CPU1_SA_DQ<3>")
	)
	(gr_poly
		(pts
			(xy 81.720182 -222.963232) (xy 81.620106 -222.790004) (xy 81.581752 -222.812356) (xy 81.544922 -222.949008)
			(xy 81.681574 -222.985584)
		)
		(stroke
			(width 0)
			(type solid)
		)
		(fill yes)
		(layer "In13.Cu")
		(net "M_B_CPU1_SA_DQ<2>")
	)
	(gr_poly
		(pts
			(xy 81.722976 -227.822506) (xy 81.623154 -227.649278) (xy 81.581752 -227.673154) (xy 81.545176 -227.809552)
			(xy 81.681828 -227.846128)
		)
		(stroke
			(width 0)
			(type solid)
		)
		(fill yes)
		(layer "In13.Cu")
		(net "M_B_CPU1_SA_DQS_DP<5>")
	)
	(gr_poly
		(pts
			(xy 81.722976 -226.202494) (xy 81.623154 -226.029266) (xy 81.581752 -226.053142) (xy 81.545176 -226.18954)
			(xy 81.681828 -226.22637)
		)
		(stroke
			(width 0)
			(type solid)
		)
		(fill yes)
		(layer "In13.Cu")
		(net "M_B_CPU1_SA_DQS_DN<0>")
	)
	(gr_poly
		(pts
			(xy 81.801208 -256.432812) (xy 81.801208 -256.38506) (xy 81.601056 -256.38506) (xy 81.601056 -256.432812)
			(xy 81.701132 -256.532634)
		)
		(stroke
			(width 0)
			(type solid)
		)
		(fill yes)
		(layer "In13.Cu")
		(net "M_B_CPU1_CLK_DN<0>")
	)
	(gr_poly
		(pts
			(xy 81.801208 -255.216406) (xy 81.701132 -255.11633) (xy 81.601056 -255.216406) (xy 81.601056 -255.260856)
			(xy 81.801208 -255.260856)
		)
		(stroke
			(width 0)
			(type solid)
		)
		(fill yes)
		(layer "In13.Cu")
		(net "M_B_CPU1_SA_CA<6>")
	)
	(gr_poly
		(pts
			(xy 81.801208 -254.812546) (xy 81.801208 -254.768096) (xy 81.601056 -254.768096) (xy 81.601056 -254.812546)
			(xy 81.701132 -254.912622)
		)
		(stroke
			(width 0)
			(type solid)
		)
		(fill yes)
		(layer "In13.Cu")
		(net "M_B_CPU1_SA_CA<5>")
	)
	(gr_poly
		(pts
			(xy 81.801208 -253.596394) (xy 81.701132 -253.496318) (xy 81.601056 -253.596394) (xy 81.601056 -253.640844)
			(xy 81.801208 -253.640844)
		)
		(stroke
			(width 0)
			(type solid)
		)
		(fill yes)
		(layer "In13.Cu")
		(net "M_B_CPU1_SA_CA<2>")
	)
	(gr_poly
		(pts
			(xy 81.801208 -253.192534) (xy 81.801208 -253.148084) (xy 81.601056 -253.148084) (xy 81.601056 -253.192534)
			(xy 81.701132 -253.29261)
		)
		(stroke
			(width 0)
			(type solid)
		)
		(fill yes)
		(layer "In13.Cu")
		(net "M_B_CPU1_SA_CA<1>")
	)
	(gr_poly
		(pts
			(xy 81.801208 -251.572522) (xy 81.801208 -251.528072) (xy 81.601056 -251.528072) (xy 81.601056 -251.572522)
			(xy 81.701132 -251.672598)
		)
		(stroke
			(width 0)
			(type solid)
		)
		(fill yes)
		(layer "In13.Cu")
		(net "M_B_CPU1_SA_CS_N<0>")
	)
	(gr_poly
		(pts
			(xy 81.801208 -250.35637) (xy 81.701132 -250.256294) (xy 81.601056 -250.35637) (xy 81.601056 -250.40082)
			(xy 81.801208 -250.40082)
		)
		(stroke
			(width 0)
			(type solid)
		)
		(fill yes)
		(layer "In13.Cu")
		(net "M_B_CPU1_ALERT_R_N")
	)
	(gr_poly
		(pts
			(xy 81.801208 -248.736358) (xy 81.701132 -248.636282) (xy 81.601056 -248.736358) (xy 81.601056 -248.780808)
			(xy 81.801208 -248.780808)
		)
		(stroke
			(width 0)
			(type solid)
		)
		(fill yes)
		(layer "In13.Cu")
		(net "M_B_CPU1_SA_CB<5>")
	)
	(gr_poly
		(pts
			(xy 81.801208 -248.332498) (xy 81.801208 -248.288048) (xy 81.601056 -248.288048) (xy 81.601056 -248.332498)
			(xy 81.701132 -248.432574)
		)
		(stroke
			(width 0)
			(type solid)
		)
		(fill yes)
		(layer "In13.Cu")
		(net "M_B_CPU1_SA_CB<6>")
	)
	(gr_poly
		(pts
			(xy 81.801208 -247.116092) (xy 81.701132 -247.01627) (xy 81.601056 -247.116092) (xy 81.601056 -247.163844)
			(xy 81.801208 -247.163844)
		)
		(stroke
			(width 0)
			(type solid)
		)
		(fill yes)
		(layer "In13.Cu")
		(net "M_B_CPU1_SA_DQS_DN<9>")
	)
	(gr_poly
		(pts
			(xy 81.801208 -246.71274) (xy 81.801208 -246.664988) (xy 81.601056 -246.664988) (xy 81.601056 -246.71274)
			(xy 81.701132 -246.812562)
		)
		(stroke
			(width 0)
			(type solid)
		)
		(fill yes)
		(layer "In13.Cu")
		(net "M_B_CPU1_SA_DQS_DN<4>")
	)
	(gr_poly
		(pts
			(xy 81.801208 -245.496334) (xy 81.701132 -245.396258) (xy 81.601056 -245.496334) (xy 81.601056 -245.540784)
			(xy 81.801208 -245.540784)
		)
		(stroke
			(width 0)
			(type solid)
		)
		(fill yes)
		(layer "In13.Cu")
		(net "M_B_CPU1_SA_CB<1>")
	)
	(gr_poly
		(pts
			(xy 81.801208 -245.092474) (xy 81.801208 -245.048024) (xy 81.601056 -245.048024) (xy 81.601056 -245.092474)
			(xy 81.701132 -245.19255)
		)
		(stroke
			(width 0)
			(type solid)
		)
		(fill yes)
		(layer "In13.Cu")
		(net "M_B_CPU1_SA_CB<2>")
	)
	(gr_poly
		(pts
			(xy 81.801208 -243.876322) (xy 81.701132 -243.776246) (xy 81.601056 -243.876322) (xy 81.601056 -243.920772)
			(xy 81.801208 -243.920772)
		)
		(stroke
			(width 0)
			(type solid)
		)
		(fill yes)
		(layer "In13.Cu")
		(net "M_B_CPU1_SA_DQ<29>")
	)
	(gr_poly
		(pts
			(xy 81.801208 -243.472462) (xy 81.801208 -243.428012) (xy 81.601056 -243.428012) (xy 81.601056 -243.472462)
			(xy 81.701132 -243.572538)
		)
		(stroke
			(width 0)
			(type solid)
		)
		(fill yes)
		(layer "In13.Cu")
		(net "M_B_CPU1_SA_DQ<30>")
	)
	(gr_poly
		(pts
			(xy 81.801208 -242.256056) (xy 81.701132 -242.156234) (xy 81.601056 -242.256056) (xy 81.601056 -242.303808)
			(xy 81.801208 -242.303808)
		)
		(stroke
			(width 0)
			(type solid)
		)
		(fill yes)
		(layer "In13.Cu")
		(net "M_B_CPU1_SA_DQS_DN<8>")
	)
	(gr_poly
		(pts
			(xy 81.801208 -241.852704) (xy 81.801208 -241.804952) (xy 81.601056 -241.804952) (xy 81.601056 -241.852704)
			(xy 81.701132 -241.952526)
		)
		(stroke
			(width 0)
			(type solid)
		)
		(fill yes)
		(layer "In13.Cu")
		(net "M_B_CPU1_SA_DQS_DN<3>")
	)
	(gr_poly
		(pts
			(xy 81.801208 -240.636298) (xy 81.701132 -240.536222) (xy 81.601056 -240.636298) (xy 81.601056 -240.680748)
			(xy 81.801208 -240.680748)
		)
		(stroke
			(width 0)
			(type solid)
		)
		(fill yes)
		(layer "In13.Cu")
		(net "M_B_CPU1_SA_DQ<25>")
	)
	(gr_poly
		(pts
			(xy 81.801208 -240.232438) (xy 81.801208 -240.187988) (xy 81.601056 -240.187988) (xy 81.601056 -240.232438)
			(xy 81.701132 -240.332514)
		)
		(stroke
			(width 0)
			(type solid)
		)
		(fill yes)
		(layer "In13.Cu")
		(net "M_B_CPU1_SA_DQ<26>")
	)
	(gr_poly
		(pts
			(xy 81.801208 -239.016286) (xy 81.701132 -238.91621) (xy 81.601056 -239.016286) (xy 81.601056 -239.060736)
			(xy 81.801208 -239.060736)
		)
		(stroke
			(width 0)
			(type solid)
		)
		(fill yes)
		(layer "In13.Cu")
		(net "M_B_CPU1_SA_DQ<21>")
	)
	(gr_poly
		(pts
			(xy 81.801208 -238.612426) (xy 81.801208 -238.567976) (xy 81.601056 -238.567976) (xy 81.601056 -238.612426)
			(xy 81.701132 -238.712502)
		)
		(stroke
			(width 0)
			(type solid)
		)
		(fill yes)
		(layer "In13.Cu")
		(net "M_B_CPU1_SA_DQ<22>")
	)
	(gr_poly
		(pts
			(xy 81.801208 -237.39602) (xy 81.701132 -237.296198) (xy 81.601056 -237.39602) (xy 81.601056 -237.443772)
			(xy 81.801208 -237.443772)
		)
		(stroke
			(width 0)
			(type solid)
		)
		(fill yes)
		(layer "In13.Cu")
		(net "M_B_CPU1_SA_DQS_DN<7>")
	)
	(gr_poly
		(pts
			(xy 81.801208 -236.992668) (xy 81.801208 -236.944916) (xy 81.601056 -236.944916) (xy 81.601056 -236.992668)
			(xy 81.701132 -237.09249)
		)
		(stroke
			(width 0)
			(type solid)
		)
		(fill yes)
		(layer "In13.Cu")
		(net "M_B_CPU1_SA_DQS_DN<2>")
	)
	(gr_poly
		(pts
			(xy 81.801208 -235.776262) (xy 81.701132 -235.676186) (xy 81.601056 -235.776262) (xy 81.601056 -235.820712)
			(xy 81.801208 -235.820712)
		)
		(stroke
			(width 0)
			(type solid)
		)
		(fill yes)
		(layer "In13.Cu")
		(net "M_B_CPU1_SA_DQ<17>")
	)
	(gr_poly
		(pts
			(xy 81.801208 -235.372402) (xy 81.801208 -235.327952) (xy 81.601056 -235.327952) (xy 81.601056 -235.372402)
			(xy 81.701132 -235.472478)
		)
		(stroke
			(width 0)
			(type solid)
		)
		(fill yes)
		(layer "In13.Cu")
		(net "M_B_CPU1_SA_DQ<18>")
	)
	(gr_poly
		(pts
			(xy 81.801208 -234.15625) (xy 81.701132 -234.056174) (xy 81.601056 -234.15625) (xy 81.601056 -234.2007)
			(xy 81.801208 -234.2007)
		)
		(stroke
			(width 0)
			(type solid)
		)
		(fill yes)
		(layer "In13.Cu")
		(net "M_B_CPU1_SA_DQ<13>")
	)
	(gr_poly
		(pts
			(xy 81.801208 -233.75239) (xy 81.801208 -233.70794) (xy 81.601056 -233.70794) (xy 81.601056 -233.75239)
			(xy 81.701132 -233.852466)
		)
		(stroke
			(width 0)
			(type solid)
		)
		(fill yes)
		(layer "In13.Cu")
		(net "M_B_CPU1_SA_DQ<14>")
	)
	(gr_poly
		(pts
			(xy 81.801208 -232.535984) (xy 81.701132 -232.436162) (xy 81.601056 -232.535984) (xy 81.601056 -232.583736)
			(xy 81.801208 -232.583736)
		)
		(stroke
			(width 0)
			(type solid)
		)
		(fill yes)
		(layer "In13.Cu")
		(net "M_B_CPU1_SA_DQS_DN<6>")
	)
	(gr_poly
		(pts
			(xy 81.801208 -232.132632) (xy 81.801208 -232.08488) (xy 81.601056 -232.08488) (xy 81.601056 -232.132632)
			(xy 81.701132 -232.232454)
		)
		(stroke
			(width 0)
			(type solid)
		)
		(fill yes)
		(layer "In13.Cu")
		(net "M_B_CPU1_SA_DQS_DN<1>")
	)
	(gr_poly
		(pts
			(xy 81.801208 -230.916226) (xy 81.701132 -230.81615) (xy 81.601056 -230.916226) (xy 81.601056 -230.960676)
			(xy 81.801208 -230.960676)
		)
		(stroke
			(width 0)
			(type solid)
		)
		(fill yes)
		(layer "In13.Cu")
		(net "M_B_CPU1_SA_DQ<9>")
	)
	(gr_poly
		(pts
			(xy 81.801208 -230.51262) (xy 81.801208 -230.46817) (xy 81.601056 -230.46817) (xy 81.601056 -230.51262)
			(xy 81.701132 -230.612696)
		)
		(stroke
			(width 0)
			(type solid)
		)
		(fill yes)
		(layer "In13.Cu")
		(net "M_B_CPU1_SA_DQ<10>")
	)
	(gr_poly
		(pts
			(xy 81.801208 -229.296214) (xy 81.701132 -229.196138) (xy 81.601056 -229.296214) (xy 81.601056 -229.340664)
			(xy 81.801208 -229.340664)
		)
		(stroke
			(width 0)
			(type solid)
		)
		(fill yes)
		(layer "In13.Cu")
		(net "M_B_CPU1_SA_DQ<5>")
	)
	(gr_poly
		(pts
			(xy 81.801208 -228.892608) (xy 81.801208 -228.848158) (xy 81.601056 -228.848158) (xy 81.601056 -228.892608)
			(xy 81.701132 -228.992684)
		)
		(stroke
			(width 0)
			(type solid)
		)
		(fill yes)
		(layer "In13.Cu")
		(net "M_B_CPU1_SA_DQ<6>")
	)
	(gr_poly
		(pts
			(xy 81.81975 -227.276406) (xy 81.85658 -227.139754) (xy 81.719928 -227.103178) (xy 81.678526 -227.127054)
			(xy 81.778602 -227.300282)
		)
		(stroke
			(width 0)
			(type solid)
		)
		(fill yes)
		(layer "In13.Cu")
		(net "M_B_CPU1_SA_DQS_DN<5>")
	)
	(gr_poly
		(pts
			(xy 81.820258 -225.655886) (xy 81.856834 -225.519488) (xy 81.720182 -225.482912) (xy 81.679034 -225.506534)
			(xy 81.778856 -225.679762)
		)
		(stroke
			(width 0)
			(type solid)
		)
		(fill yes)
		(layer "In13.Cu")
		(net "M_B_CPU1_SA_DQS_DP<0>")
	)
	(gr_poly
		(pts
			(xy 81.820258 -224.036636) (xy 81.856834 -223.899984) (xy 81.720436 -223.863408) (xy 81.681828 -223.88576)
			(xy 81.781904 -224.058988)
		)
		(stroke
			(width 0)
			(type solid)
		)
		(fill yes)
		(layer "In13.Cu")
		(net "M_B_CPU1_SA_DQ<1>")
	)
	(gr_poly
		(pts
			(xy 82.094832 -267.801852) (xy 81.994756 -267.701776) (xy 81.894934 -267.801852) (xy 81.894934 -267.846302)
			(xy 82.094832 -267.846302)
		)
		(stroke
			(width 0)
			(type solid)
		)
		(fill yes)
		(layer "In13.Cu")
		(net "M_B_CPU1_SB_RSP<0>")
	)
	(gr_poly
		(pts
			(xy 82.101182 -292.108128) (xy 82.001106 -292.008052) (xy 81.90103 -292.108128) (xy 81.90103 -292.152578)
			(xy 82.101182 -292.152578)
		)
		(stroke
			(width 0)
			(type solid)
		)
		(fill yes)
		(layer "In13.Cu")
		(net "M_B_CPU1_SB_DQ<28>")
	)
	(gr_poly
		(pts
			(xy 82.101182 -291.704522) (xy 82.101182 -291.65677) (xy 81.90103 -291.65677) (xy 81.90103 -291.704522)
			(xy 82.001106 -291.804344)
		)
		(stroke
			(width 0)
			(type solid)
		)
		(fill yes)
		(layer "In13.Cu")
		(net "M_B_CPU1_SB_DQS_DP<8>")
	)
	(gr_poly
		(pts
			(xy 82.101182 -290.487862) (xy 82.001106 -290.38804) (xy 81.90103 -290.487862) (xy 81.90103 -290.535614)
			(xy 82.101182 -290.535614)
		)
		(stroke
			(width 0)
			(type solid)
		)
		(fill yes)
		(layer "In13.Cu")
		(net "M_B_CPU1_SB_DQS_DP<3>")
	)
	(gr_poly
		(pts
			(xy 82.101182 -290.084256) (xy 82.101182 -290.039806) (xy 81.90103 -290.039806) (xy 81.90103 -290.084256)
			(xy 82.001106 -290.184332)
		)
		(stroke
			(width 0)
			(type solid)
		)
		(fill yes)
		(layer "In13.Cu")
		(net "M_B_CPU1_SB_DQ<27>")
	)
	(gr_poly
		(pts
			(xy 82.101182 -288.868104) (xy 82.001106 -288.768028) (xy 81.90103 -288.868104) (xy 81.90103 -288.912554)
			(xy 82.101182 -288.912554)
		)
		(stroke
			(width 0)
			(type solid)
		)
		(fill yes)
		(layer "In13.Cu")
		(net "M_B_CPU1_SB_DQ<24>")
	)
	(gr_poly
		(pts
			(xy 82.101182 -288.464498) (xy 82.101182 -288.420048) (xy 81.90103 -288.420048) (xy 81.90103 -288.464498)
			(xy 82.001106 -288.564574)
		)
		(stroke
			(width 0)
			(type solid)
		)
		(fill yes)
		(layer "In13.Cu")
		(net "M_B_CPU1_SB_DQ<23>")
	)
	(gr_poly
		(pts
			(xy 82.101182 -287.248092) (xy 82.001106 -287.148016) (xy 81.90103 -287.248092) (xy 81.90103 -287.292542)
			(xy 82.101182 -287.292542)
		)
		(stroke
			(width 0)
			(type solid)
		)
		(fill yes)
		(layer "In13.Cu")
		(net "M_B_CPU1_SB_DQ<20>")
	)
	(gr_poly
		(pts
			(xy 82.101182 -286.844486) (xy 82.101182 -286.796734) (xy 81.90103 -286.796734) (xy 81.90103 -286.844486)
			(xy 82.001106 -286.944562)
		)
		(stroke
			(width 0)
			(type solid)
		)
		(fill yes)
		(layer "In13.Cu")
		(net "M_B_CPU1_SB_DQS_DP<7>")
	)
	(gr_poly
		(pts
			(xy 82.101182 -285.62808) (xy 82.001106 -285.528258) (xy 81.90103 -285.62808) (xy 81.90103 -285.675832)
			(xy 82.101182 -285.675832)
		)
		(stroke
			(width 0)
			(type solid)
		)
		(fill yes)
		(layer "In13.Cu")
		(net "M_B_CPU1_SB_DQS_DP<2>")
	)
	(gr_poly
		(pts
			(xy 82.101182 -285.224474) (xy 82.101182 -285.180024) (xy 81.90103 -285.180024) (xy 81.90103 -285.224474)
			(xy 82.001106 -285.32455)
		)
		(stroke
			(width 0)
			(type solid)
		)
		(fill yes)
		(layer "In13.Cu")
		(net "M_B_CPU1_SB_DQ<19>")
	)
	(gr_poly
		(pts
			(xy 82.101182 -284.008322) (xy 82.001106 -283.908246) (xy 81.90103 -284.008322) (xy 81.90103 -284.052772)
			(xy 82.101182 -284.052772)
		)
		(stroke
			(width 0)
			(type solid)
		)
		(fill yes)
		(layer "In13.Cu")
		(net "M_B_CPU1_SB_DQ<16>")
	)
	(gr_poly
		(pts
			(xy 82.101182 -283.604462) (xy 82.101182 -283.560012) (xy 81.90103 -283.560012) (xy 81.90103 -283.604462)
			(xy 82.001106 -283.704538)
		)
		(stroke
			(width 0)
			(type solid)
		)
		(fill yes)
		(layer "In13.Cu")
		(net "M_B_CPU1_SB_DQ<15>")
	)
	(gr_poly
		(pts
			(xy 82.101182 -282.38831) (xy 82.001106 -282.288234) (xy 81.90103 -282.38831) (xy 81.90103 -282.43276)
			(xy 82.101182 -282.43276)
		)
		(stroke
			(width 0)
			(type solid)
		)
		(fill yes)
		(layer "In13.Cu")
		(net "M_B_CPU1_SB_DQ<12>")
	)
	(gr_poly
		(pts
			(xy 82.101182 -281.984704) (xy 82.101182 -281.936952) (xy 81.90103 -281.936952) (xy 81.90103 -281.984704)
			(xy 82.001106 -282.084526)
		)
		(stroke
			(width 0)
			(type solid)
		)
		(fill yes)
		(layer "In13.Cu")
		(net "M_B_CPU1_SB_DQS_DP<6>")
	)
	(gr_poly
		(pts
			(xy 82.101182 -280.768044) (xy 82.001106 -280.668222) (xy 81.90103 -280.768044) (xy 81.90103 -280.815796)
			(xy 82.101182 -280.815796)
		)
		(stroke
			(width 0)
			(type solid)
		)
		(fill yes)
		(layer "In13.Cu")
		(net "M_B_CPU1_SB_DQS_DP<1>")
	)
	(gr_poly
		(pts
			(xy 82.101182 -280.364438) (xy 82.101182 -280.319988) (xy 81.90103 -280.319988) (xy 81.90103 -280.364438)
			(xy 82.001106 -280.464514)
		)
		(stroke
			(width 0)
			(type solid)
		)
		(fill yes)
		(layer "In13.Cu")
		(net "M_B_CPU1_SB_DQ<11>")
	)
	(gr_poly
		(pts
			(xy 82.101182 -279.148286) (xy 82.001106 -279.04821) (xy 81.90103 -279.148286) (xy 81.90103 -279.192736)
			(xy 82.101182 -279.192736)
		)
		(stroke
			(width 0)
			(type solid)
		)
		(fill yes)
		(layer "In13.Cu")
		(net "M_B_CPU1_SB_DQ<8>")
	)
	(gr_poly
		(pts
			(xy 82.101182 -278.744426) (xy 82.101182 -278.699976) (xy 81.90103 -278.699976) (xy 81.90103 -278.744426)
			(xy 82.001106 -278.844502)
		)
		(stroke
			(width 0)
			(type solid)
		)
		(fill yes)
		(layer "In13.Cu")
		(net "M_B_CPU1_SB_DQ<7>")
	)
	(gr_poly
		(pts
			(xy 82.101182 -277.528274) (xy 82.001106 -277.428198) (xy 81.90103 -277.528274) (xy 81.90103 -277.572724)
			(xy 82.101182 -277.572724)
		)
		(stroke
			(width 0)
			(type solid)
		)
		(fill yes)
		(layer "In13.Cu")
		(net "M_B_CPU1_SB_DQ<4>")
	)
	(gr_poly
		(pts
			(xy 82.101182 -277.124668) (xy 82.101182 -277.076916) (xy 81.90103 -277.076916) (xy 81.90103 -277.124668)
			(xy 82.001106 -277.22449)
		)
		(stroke
			(width 0)
			(type solid)
		)
		(fill yes)
		(layer "In13.Cu")
		(net "M_B_CPU1_SB_DQS_DP<5>")
	)
	(gr_poly
		(pts
			(xy 82.101182 -275.908008) (xy 82.001106 -275.808186) (xy 81.90103 -275.908008) (xy 81.90103 -275.95576)
			(xy 82.101182 -275.95576)
		)
		(stroke
			(width 0)
			(type solid)
		)
		(fill yes)
		(layer "In13.Cu")
		(net "M_B_CPU1_SB_DQS_DP<0>")
	)
	(gr_poly
		(pts
			(xy 82.101182 -275.504402) (xy 82.101182 -275.459952) (xy 81.90103 -275.459952) (xy 81.90103 -275.504402)
			(xy 82.001106 -275.604478)
		)
		(stroke
			(width 0)
			(type solid)
		)
		(fill yes)
		(layer "In13.Cu")
		(net "M_B_CPU1_SB_DQ<3>")
	)
	(gr_poly
		(pts
			(xy 82.101182 -274.28825) (xy 82.001106 -274.188174) (xy 81.90103 -274.28825) (xy 81.90103 -274.3327)
			(xy 82.101182 -274.3327)
		)
		(stroke
			(width 0)
			(type solid)
		)
		(fill yes)
		(layer "In13.Cu")
		(net "M_B_CPU1_SB_DQ<0>")
	)
	(gr_poly
		(pts
			(xy 82.101182 -273.88439) (xy 82.101182 -273.83994) (xy 81.90103 -273.83994) (xy 81.90103 -273.88439)
			(xy 82.001106 -273.984466)
		)
		(stroke
			(width 0)
			(type solid)
		)
		(fill yes)
		(layer "In13.Cu")
		(net "M_B_CPU1_SB_CB<3>")
	)
	(gr_poly
		(pts
			(xy 82.101182 -272.668238) (xy 82.001106 -272.568162) (xy 81.90103 -272.668238) (xy 81.90103 -272.712688)
			(xy 82.101182 -272.712688)
		)
		(stroke
			(width 0)
			(type solid)
		)
		(fill yes)
		(layer "In13.Cu")
		(net "M_B_CPU1_SB_CB<0>")
	)
	(gr_poly
		(pts
			(xy 82.101182 -272.264632) (xy 82.101182 -272.21688) (xy 81.90103 -272.21688) (xy 81.90103 -272.264632)
			(xy 82.001106 -272.364454)
		)
		(stroke
			(width 0)
			(type solid)
		)
		(fill yes)
		(layer "In13.Cu")
		(net "M_B_CPU1_SB_DQS_DP<4>")
	)
	(gr_poly
		(pts
			(xy 82.101182 -271.047972) (xy 82.001106 -270.94815) (xy 81.90103 -271.047972) (xy 81.90103 -271.095724)
			(xy 82.101182 -271.095724)
		)
		(stroke
			(width 0)
			(type solid)
		)
		(fill yes)
		(layer "In13.Cu")
		(net "M_B_CPU1_SB_DQS_DP<9>")
	)
	(gr_poly
		(pts
			(xy 82.101182 -270.644366) (xy 82.101182 -270.599916) (xy 81.90103 -270.599916) (xy 81.90103 -270.644366)
			(xy 82.001106 -270.744442)
		)
		(stroke
			(width 0)
			(type solid)
		)
		(fill yes)
		(layer "In13.Cu")
		(net "M_B_CPU1_SB_CB<7>")
	)
	(gr_poly
		(pts
			(xy 82.101182 -269.428214) (xy 82.001106 -269.328138) (xy 81.90103 -269.428214) (xy 81.90103 -269.472664)
			(xy 82.101182 -269.472664)
		)
		(stroke
			(width 0)
			(type solid)
		)
		(fill yes)
		(layer "In13.Cu")
		(net "M_B_CPU1_SB_CB<4>")
	)
	(gr_poly
		(pts
			(xy 82.101182 -265.78433) (xy 82.101182 -265.73988) (xy 81.90103 -265.73988) (xy 81.90103 -265.78433)
			(xy 82.001106 -265.884406)
		)
		(stroke
			(width 0)
			(type solid)
		)
		(fill yes)
		(layer "In13.Cu")
		(net "M_B_CPU1_SB_CS_N<0>")
	)
	(gr_poly
		(pts
			(xy 82.101182 -264.568178) (xy 82.001106 -264.468102) (xy 81.90103 -264.568178) (xy 81.90103 -264.612628)
			(xy 82.101182 -264.612628)
		)
		(stroke
			(width 0)
			(type solid)
		)
		(fill yes)
		(layer "In13.Cu")
		(net "M_B_CPU1_SB_CA<6>")
	)
	(gr_poly
		(pts
			(xy 82.101182 -264.164318) (xy 82.101182 -264.119868) (xy 81.90103 -264.119868) (xy 81.90103 -264.164318)
			(xy 82.001106 -264.264394)
		)
		(stroke
			(width 0)
			(type solid)
		)
		(fill yes)
		(layer "In13.Cu")
		(net "M_B_CPU1_SB_CA<5>")
	)
	(gr_poly
		(pts
			(xy 82.101182 -262.948166) (xy 82.001106 -262.84809) (xy 81.90103 -262.948166) (xy 81.90103 -262.992616)
			(xy 82.101182 -262.992616)
		)
		(stroke
			(width 0)
			(type solid)
		)
		(fill yes)
		(layer "In13.Cu")
		(net "M_B_CPU1_SB_CA<2>")
	)
	(gr_poly
		(pts
			(xy 82.101182 -262.544306) (xy 82.101182 -262.499856) (xy 81.90103 -262.499856) (xy 81.90103 -262.544306)
			(xy 82.001106 -262.644382)
		)
		(stroke
			(width 0)
			(type solid)
		)
		(fill yes)
		(layer "In13.Cu")
		(net "M_B_CPU1_SB_CA<1>")
	)
	(gr_poly
		(pts
			(xy 82.146394 -293.878762) (xy 82.109818 -293.74211) (xy 82.07121 -293.719758) (xy 81.971388 -293.892986)
			(xy 82.009742 -293.915338)
		)
		(stroke
			(width 0)
			(type solid)
		)
		(fill yes)
		(layer "In13.Cu")
		(net "M_B_CPU1_SB_DQ<31>")
	)
	(gr_poly
		(pts
			(xy 82.191098 -225.394774) (xy 82.091022 -225.221546) (xy 82.052414 -225.243644) (xy 82.015838 -225.380296)
			(xy 82.15249 -225.416872)
		)
		(stroke
			(width 0)
			(type solid)
		)
		(fill yes)
		(layer "In13.Cu")
		(net "M_B_CPU1_SA_DQ<3>")
	)
	(gr_poly
		(pts
			(xy 82.191098 -223.774762) (xy 82.091022 -223.601534) (xy 82.052414 -223.623632) (xy 82.015838 -223.760284)
			(xy 82.15249 -223.79686)
		)
		(stroke
			(width 0)
			(type solid)
		)
		(fill yes)
		(layer "In13.Cu")
		(net "M_B_CPU1_SA_DQ<2>")
	)
	(gr_poly
		(pts
			(xy 82.194146 -227.01377) (xy 82.09407 -226.840542) (xy 82.052668 -226.864418) (xy 82.016092 -227.00107)
			(xy 82.152744 -227.037646)
		)
		(stroke
			(width 0)
			(type solid)
		)
		(fill yes)
		(layer "In13.Cu")
		(net "M_B_CPU1_SA_DQS_DN<0>")
	)
	(gr_poly
		(pts
			(xy 82.271108 -256.026158) (xy 82.171032 -255.926336) (xy 82.070956 -256.026158) (xy 82.070956 -256.07391)
			(xy 82.271108 -256.07391)
		)
		(stroke
			(width 0)
			(type solid)
		)
		(fill yes)
		(layer "In13.Cu")
		(net "M_B_CPU1_CLK_DP<0>")
	)
	(gr_poly
		(pts
			(xy 82.271108 -255.622552) (xy 82.271108 -255.578102) (xy 82.070956 -255.578102) (xy 82.070956 -255.622552)
			(xy 82.171032 -255.722628)
		)
		(stroke
			(width 0)
			(type solid)
		)
		(fill yes)
		(layer "In13.Cu")
		(net "M_B_CPU1_SA_PAR")
	)
	(gr_poly
		(pts
			(xy 82.271108 -254.4064) (xy 82.171032 -254.306324) (xy 82.070956 -254.4064) (xy 82.070956 -254.45085)
			(xy 82.271108 -254.45085)
		)
		(stroke
			(width 0)
			(type solid)
		)
		(fill yes)
		(layer "In13.Cu")
		(net "M_B_CPU1_SA_CA<4>")
	)
	(gr_poly
		(pts
			(xy 82.271108 -254.00254) (xy 82.271108 -253.95809) (xy 82.070956 -253.95809) (xy 82.070956 -254.00254)
			(xy 82.171032 -254.102616)
		)
		(stroke
			(width 0)
			(type solid)
		)
		(fill yes)
		(layer "In13.Cu")
		(net "M_B_CPU1_SA_CA<3>")
	)
	(gr_poly
		(pts
			(xy 82.271108 -252.786388) (xy 82.171032 -252.686312) (xy 82.070956 -252.786388) (xy 82.070956 -252.830838)
			(xy 82.271108 -252.830838)
		)
		(stroke
			(width 0)
			(type solid)
		)
		(fill yes)
		(layer "In13.Cu")
		(net "M_B_CPU1_SA_CA<0>")
	)
	(gr_poly
		(pts
			(xy 82.271108 -252.382528) (xy 82.271108 -252.338078) (xy 82.070956 -252.338078) (xy 82.070956 -252.382528)
			(xy 82.171032 -252.482604)
		)
		(stroke
			(width 0)
			(type solid)
		)
		(fill yes)
		(layer "In13.Cu")
		(net "M_B_CPU1_SA_CS_N<1>")
	)
	(gr_poly
		(pts
			(xy 82.271108 -250.762516) (xy 82.271108 -250.718066) (xy 82.070956 -250.718066) (xy 82.070956 -250.762516)
			(xy 82.171032 -250.862592)
		)
		(stroke
			(width 0)
			(type solid)
		)
		(fill yes)
		(layer "In13.Cu")
		(net "M_B_CPU1_RESET_N")
	)
	(gr_poly
		(pts
			(xy 82.271108 -249.142504) (xy 82.271108 -249.098054) (xy 82.070956 -249.098054) (xy 82.070956 -249.142504)
			(xy 82.171032 -249.24258)
		)
		(stroke
			(width 0)
			(type solid)
		)
		(fill yes)
		(layer "In13.Cu")
		(net "M_B_CPU1_SA_CB<7>")
	)
	(gr_poly
		(pts
			(xy 82.271108 -247.926352) (xy 82.171032 -247.826276) (xy 82.070956 -247.926352) (xy 82.070956 -247.970802)
			(xy 82.271108 -247.970802)
		)
		(stroke
			(width 0)
			(type solid)
		)
		(fill yes)
		(layer "In13.Cu")
		(net "M_B_CPU1_SA_CB<4>")
	)
	(gr_poly
		(pts
			(xy 82.271108 -247.522746) (xy 82.271108 -247.474994) (xy 82.070956 -247.474994) (xy 82.070956 -247.522746)
			(xy 82.171032 -247.622568)
		)
		(stroke
			(width 0)
			(type solid)
		)
		(fill yes)
		(layer "In13.Cu")
		(net "M_B_CPU1_SA_DQS_DP<9>")
	)
	(gr_poly
		(pts
			(xy 82.271108 -246.306086) (xy 82.171032 -246.206264) (xy 82.070956 -246.306086) (xy 82.070956 -246.353838)
			(xy 82.271108 -246.353838)
		)
		(stroke
			(width 0)
			(type solid)
		)
		(fill yes)
		(layer "In13.Cu")
		(net "M_B_CPU1_SA_DQS_DP<4>")
	)
	(gr_poly
		(pts
			(xy 82.271108 -245.90248) (xy 82.271108 -245.85803) (xy 82.070956 -245.85803) (xy 82.070956 -245.90248)
			(xy 82.171032 -246.002556)
		)
		(stroke
			(width 0)
			(type solid)
		)
		(fill yes)
		(layer "In13.Cu")
		(net "M_B_CPU1_SA_CB<3>")
	)
	(gr_poly
		(pts
			(xy 82.271108 -244.686328) (xy 82.171032 -244.586252) (xy 82.070956 -244.686328) (xy 82.070956 -244.730778)
			(xy 82.271108 -244.730778)
		)
		(stroke
			(width 0)
			(type solid)
		)
		(fill yes)
		(layer "In13.Cu")
		(net "M_B_CPU1_SA_CB<0>")
	)
	(gr_poly
		(pts
			(xy 82.271108 -244.282468) (xy 82.271108 -244.238018) (xy 82.070956 -244.238018) (xy 82.070956 -244.282468)
			(xy 82.171032 -244.382544)
		)
		(stroke
			(width 0)
			(type solid)
		)
		(fill yes)
		(layer "In13.Cu")
		(net "M_B_CPU1_SA_DQ<31>")
	)
	(gr_poly
		(pts
			(xy 82.271108 -243.066316) (xy 82.171032 -242.96624) (xy 82.070956 -243.066316) (xy 82.070956 -243.110766)
			(xy 82.271108 -243.110766)
		)
		(stroke
			(width 0)
			(type solid)
		)
		(fill yes)
		(layer "In13.Cu")
		(net "M_B_CPU1_SA_DQ<28>")
	)
	(gr_poly
		(pts
			(xy 82.271108 -242.66271) (xy 82.271108 -242.614958) (xy 82.070956 -242.614958) (xy 82.070956 -242.66271)
			(xy 82.171032 -242.762532)
		)
		(stroke
			(width 0)
			(type solid)
		)
		(fill yes)
		(layer "In13.Cu")
		(net "M_B_CPU1_SA_DQS_DP<8>")
	)
	(gr_poly
		(pts
			(xy 82.271108 -241.44605) (xy 82.171032 -241.346228) (xy 82.070956 -241.44605) (xy 82.070956 -241.493802)
			(xy 82.271108 -241.493802)
		)
		(stroke
			(width 0)
			(type solid)
		)
		(fill yes)
		(layer "In13.Cu")
		(net "M_B_CPU1_SA_DQS_DP<3>")
	)
	(gr_poly
		(pts
			(xy 82.271108 -241.042444) (xy 82.271108 -240.997994) (xy 82.070956 -240.997994) (xy 82.070956 -241.042444)
			(xy 82.171032 -241.14252)
		)
		(stroke
			(width 0)
			(type solid)
		)
		(fill yes)
		(layer "In13.Cu")
		(net "M_B_CPU1_SA_DQ<27>")
	)
	(gr_poly
		(pts
			(xy 82.271108 -239.826292) (xy 82.171032 -239.726216) (xy 82.070956 -239.826292) (xy 82.070956 -239.870742)
			(xy 82.271108 -239.870742)
		)
		(stroke
			(width 0)
			(type solid)
		)
		(fill yes)
		(layer "In13.Cu")
		(net "M_B_CPU1_SA_DQ<24>")
	)
	(gr_poly
		(pts
			(xy 82.271108 -239.422432) (xy 82.271108 -239.377982) (xy 82.070956 -239.377982) (xy 82.070956 -239.422432)
			(xy 82.171032 -239.522508)
		)
		(stroke
			(width 0)
			(type solid)
		)
		(fill yes)
		(layer "In13.Cu")
		(net "M_B_CPU1_SA_DQ<23>")
	)
	(gr_poly
		(pts
			(xy 82.271108 -238.20628) (xy 82.171032 -238.106204) (xy 82.070956 -238.20628) (xy 82.070956 -238.25073)
			(xy 82.271108 -238.25073)
		)
		(stroke
			(width 0)
			(type solid)
		)
		(fill yes)
		(layer "In13.Cu")
		(net "M_B_CPU1_SA_DQ<20>")
	)
	(gr_poly
		(pts
			(xy 82.271108 -237.802674) (xy 82.271108 -237.754922) (xy 82.070956 -237.754922) (xy 82.070956 -237.802674)
			(xy 82.171032 -237.902496)
		)
		(stroke
			(width 0)
			(type solid)
		)
		(fill yes)
		(layer "In13.Cu")
		(net "M_B_CPU1_SA_DQS_DP<7>")
	)
	(gr_poly
		(pts
			(xy 82.271108 -236.586014) (xy 82.171032 -236.486192) (xy 82.070956 -236.586014) (xy 82.070956 -236.633766)
			(xy 82.271108 -236.633766)
		)
		(stroke
			(width 0)
			(type solid)
		)
		(fill yes)
		(layer "In13.Cu")
		(net "M_B_CPU1_SA_DQS_DP<2>")
	)
	(gr_poly
		(pts
			(xy 82.271108 -236.182408) (xy 82.271108 -236.137958) (xy 82.070956 -236.137958) (xy 82.070956 -236.182408)
			(xy 82.171032 -236.282484)
		)
		(stroke
			(width 0)
			(type solid)
		)
		(fill yes)
		(layer "In13.Cu")
		(net "M_B_CPU1_SA_DQ<19>")
	)
	(gr_poly
		(pts
			(xy 82.271108 -234.966256) (xy 82.171032 -234.86618) (xy 82.070956 -234.966256) (xy 82.070956 -235.010706)
			(xy 82.271108 -235.010706)
		)
		(stroke
			(width 0)
			(type solid)
		)
		(fill yes)
		(layer "In13.Cu")
		(net "M_B_CPU1_SA_DQ<16>")
	)
	(gr_poly
		(pts
			(xy 82.271108 -234.562396) (xy 82.271108 -234.517946) (xy 82.070956 -234.517946) (xy 82.070956 -234.562396)
			(xy 82.171032 -234.662472)
		)
		(stroke
			(width 0)
			(type solid)
		)
		(fill yes)
		(layer "In13.Cu")
		(net "M_B_CPU1_SA_DQ<15>")
	)
	(gr_poly
		(pts
			(xy 82.271108 -233.346244) (xy 82.171032 -233.246168) (xy 82.070956 -233.346244) (xy 82.070956 -233.390694)
			(xy 82.271108 -233.390694)
		)
		(stroke
			(width 0)
			(type solid)
		)
		(fill yes)
		(layer "In13.Cu")
		(net "M_B_CPU1_SA_DQ<12>")
	)
	(gr_poly
		(pts
			(xy 82.271108 -232.942638) (xy 82.271108 -232.894886) (xy 82.070956 -232.894886) (xy 82.070956 -232.942638)
			(xy 82.171032 -233.04246)
		)
		(stroke
			(width 0)
			(type solid)
		)
		(fill yes)
		(layer "In13.Cu")
		(net "M_B_CPU1_SA_DQS_DP<6>")
	)
	(gr_poly
		(pts
			(xy 82.271108 -231.725978) (xy 82.171032 -231.626156) (xy 82.070956 -231.725978) (xy 82.070956 -231.77373)
			(xy 82.271108 -231.77373)
		)
		(stroke
			(width 0)
			(type solid)
		)
		(fill yes)
		(layer "In13.Cu")
		(net "M_B_CPU1_SA_DQS_DP<1>")
	)
	(gr_poly
		(pts
			(xy 82.271108 -231.322626) (xy 82.271108 -231.278176) (xy 82.070956 -231.278176) (xy 82.070956 -231.322626)
			(xy 82.171032 -231.422702)
		)
		(stroke
			(width 0)
			(type solid)
		)
		(fill yes)
		(layer "In13.Cu")
		(net "M_B_CPU1_SA_DQ<11>")
	)
	(gr_poly
		(pts
			(xy 82.271108 -230.10622) (xy 82.171032 -230.006144) (xy 82.070956 -230.10622) (xy 82.070956 -230.15067)
			(xy 82.271108 -230.15067)
		)
		(stroke
			(width 0)
			(type solid)
		)
		(fill yes)
		(layer "In13.Cu")
		(net "M_B_CPU1_SA_DQ<8>")
	)
	(gr_poly
		(pts
			(xy 82.271108 -229.702614) (xy 82.271108 -229.658164) (xy 82.070956 -229.658164) (xy 82.070956 -229.702614)
			(xy 82.171032 -229.80269)
		)
		(stroke
			(width 0)
			(type solid)
		)
		(fill yes)
		(layer "In13.Cu")
		(net "M_B_CPU1_SA_DQ<7>")
	)
	(gr_poly
		(pts
			(xy 82.271108 -228.486462) (xy 82.171032 -228.386386) (xy 82.070956 -228.486462) (xy 82.070956 -228.530912)
			(xy 82.271108 -228.530912)
		)
		(stroke
			(width 0)
			(type solid)
		)
		(fill yes)
		(layer "In13.Cu")
		(net "M_B_CPU1_SA_DQ<4>")
	)
	(gr_poly
		(pts
			(xy 82.271108 -228.082856) (xy 82.271108 -228.035104) (xy 82.070956 -228.035104) (xy 82.070956 -228.082856)
			(xy 82.171032 -228.182678)
		)
		(stroke
			(width 0)
			(type solid)
		)
		(fill yes)
		(layer "In13.Cu")
		(net "M_B_CPU1_SA_DQS_DP<5>")
	)
	(gr_poly
		(pts
			(xy 82.289396 -226.464622) (xy 82.325972 -226.32797) (xy 82.18932 -226.291394) (xy 82.147918 -226.31527)
			(xy 82.247994 -226.488498)
		)
		(stroke
			(width 0)
			(type solid)
		)
		(fill yes)
		(layer "In13.Cu")
		(net "M_B_CPU1_SA_DQS_DP<0>")
	)
	(gr_poly
		(pts
			(xy 82.28965 -224.845372) (xy 82.326226 -224.70872) (xy 82.189574 -224.672144) (xy 82.150966 -224.694242)
			(xy 82.251042 -224.86747)
		)
		(stroke
			(width 0)
			(type solid)
		)
		(fill yes)
		(layer "In13.Cu")
		(net "M_B_CPU1_SA_DQ<1>")
	)
	(gr_poly
		(pts
			(xy 82.28965 -223.22536) (xy 82.326226 -223.088708) (xy 82.189574 -223.052132) (xy 82.150966 -223.07423)
			(xy 82.251042 -223.247458)
		)
		(stroke
			(width 0)
			(type solid)
		)
		(fill yes)
		(layer "In13.Cu")
		(net "M_B_CPU1_SA_DQ<0>")
	)
	(gr_poly
		(pts
			(xy 82.571082 -292.918134) (xy 82.471006 -292.818058) (xy 82.37093 -292.918134) (xy 82.37093 -292.962584)
			(xy 82.571082 -292.962584)
		)
		(stroke
			(width 0)
			(type solid)
		)
		(fill yes)
		(layer "In13.Cu")
		(net "M_B_CPU1_SB_DQ<29>")
	)
	(gr_poly
		(pts
			(xy 82.571082 -292.514274) (xy 82.571082 -292.469824) (xy 82.37093 -292.469824) (xy 82.37093 -292.514274)
			(xy 82.471006 -292.61435)
		)
		(stroke
			(width 0)
			(type solid)
		)
		(fill yes)
		(layer "In13.Cu")
		(net "M_B_CPU1_SB_DQ<30>")
	)
	(gr_poly
		(pts
			(xy 82.571082 -291.297868) (xy 82.471006 -291.198046) (xy 82.37093 -291.297868) (xy 82.37093 -291.34562)
			(xy 82.571082 -291.34562)
		)
		(stroke
			(width 0)
			(type solid)
		)
		(fill yes)
		(layer "In13.Cu")
		(net "M_B_CPU1_SB_DQS_DN<8>")
	)
	(gr_poly
		(pts
			(xy 82.571082 -290.894516) (xy 82.571082 -290.846764) (xy 82.37093 -290.846764) (xy 82.37093 -290.894516)
			(xy 82.471006 -290.994338)
		)
		(stroke
			(width 0)
			(type solid)
		)
		(fill yes)
		(layer "In13.Cu")
		(net "M_B_CPU1_SB_DQS_DN<3>")
	)
	(gr_poly
		(pts
			(xy 82.571082 -289.67811) (xy 82.471006 -289.578034) (xy 82.37093 -289.67811) (xy 82.37093 -289.72256)
			(xy 82.571082 -289.72256)
		)
		(stroke
			(width 0)
			(type solid)
		)
		(fill yes)
		(layer "In13.Cu")
		(net "M_B_CPU1_SB_DQ<25>")
	)
	(gr_poly
		(pts
			(xy 82.571082 -289.27425) (xy 82.571082 -289.2298) (xy 82.37093 -289.2298) (xy 82.37093 -289.27425)
			(xy 82.471006 -289.374326)
		)
		(stroke
			(width 0)
			(type solid)
		)
		(fill yes)
		(layer "In13.Cu")
		(net "M_B_CPU1_SB_DQ<26>")
	)
	(gr_poly
		(pts
			(xy 82.571082 -288.058098) (xy 82.471006 -287.958022) (xy 82.37093 -288.058098) (xy 82.37093 -288.102548)
			(xy 82.571082 -288.102548)
		)
		(stroke
			(width 0)
			(type solid)
		)
		(fill yes)
		(layer "In13.Cu")
		(net "M_B_CPU1_SB_DQ<21>")
	)
	(gr_poly
		(pts
			(xy 82.571082 -287.654492) (xy 82.571082 -287.610042) (xy 82.37093 -287.610042) (xy 82.37093 -287.654492)
			(xy 82.471006 -287.754568)
		)
		(stroke
			(width 0)
			(type solid)
		)
		(fill yes)
		(layer "In13.Cu")
		(net "M_B_CPU1_SB_DQ<22>")
	)
	(gr_poly
		(pts
			(xy 82.571082 -286.438086) (xy 82.471006 -286.33801) (xy 82.37093 -286.438086) (xy 82.37093 -286.485838)
			(xy 82.571082 -286.485838)
		)
		(stroke
			(width 0)
			(type solid)
		)
		(fill yes)
		(layer "In13.Cu")
		(net "M_B_CPU1_SB_DQS_DN<7>")
	)
	(gr_poly
		(pts
			(xy 82.571082 -286.034734) (xy 82.571082 -285.986982) (xy 82.37093 -285.986982) (xy 82.37093 -286.034734)
			(xy 82.471006 -286.134556)
		)
		(stroke
			(width 0)
			(type solid)
		)
		(fill yes)
		(layer "In13.Cu")
		(net "M_B_CPU1_SB_DQS_DN<2>")
	)
	(gr_poly
		(pts
			(xy 82.571082 -284.818328) (xy 82.471006 -284.718252) (xy 82.37093 -284.818328) (xy 82.37093 -284.862778)
			(xy 82.571082 -284.862778)
		)
		(stroke
			(width 0)
			(type solid)
		)
		(fill yes)
		(layer "In13.Cu")
		(net "M_B_CPU1_SB_DQ<17>")
	)
	(gr_poly
		(pts
			(xy 82.571082 -284.414468) (xy 82.571082 -284.370018) (xy 82.37093 -284.370018) (xy 82.37093 -284.414468)
			(xy 82.471006 -284.514544)
		)
		(stroke
			(width 0)
			(type solid)
		)
		(fill yes)
		(layer "In13.Cu")
		(net "M_B_CPU1_SB_DQ<18>")
	)
	(gr_poly
		(pts
			(xy 82.571082 -283.198316) (xy 82.471006 -283.09824) (xy 82.37093 -283.198316) (xy 82.37093 -283.242766)
			(xy 82.571082 -283.242766)
		)
		(stroke
			(width 0)
			(type solid)
		)
		(fill yes)
		(layer "In13.Cu")
		(net "M_B_CPU1_SB_DQ<13>")
	)
	(gr_poly
		(pts
			(xy 82.571082 -282.794456) (xy 82.571082 -282.750006) (xy 82.37093 -282.750006) (xy 82.37093 -282.794456)
			(xy 82.471006 -282.894532)
		)
		(stroke
			(width 0)
			(type solid)
		)
		(fill yes)
		(layer "In13.Cu")
		(net "M_B_CPU1_SB_DQ<14>")
	)
	(gr_poly
		(pts
			(xy 82.571082 -281.57805) (xy 82.471006 -281.478228) (xy 82.37093 -281.57805) (xy 82.37093 -281.625802)
			(xy 82.571082 -281.625802)
		)
		(stroke
			(width 0)
			(type solid)
		)
		(fill yes)
		(layer "In13.Cu")
		(net "M_B_CPU1_SB_DQS_DN<6>")
	)
	(gr_poly
		(pts
			(xy 82.571082 -281.174698) (xy 82.571082 -281.126946) (xy 82.37093 -281.126946) (xy 82.37093 -281.174698)
			(xy 82.471006 -281.27452)
		)
		(stroke
			(width 0)
			(type solid)
		)
		(fill yes)
		(layer "In13.Cu")
		(net "M_B_CPU1_SB_DQS_DN<1>")
	)
	(gr_poly
		(pts
			(xy 82.571082 -279.958292) (xy 82.471006 -279.858216) (xy 82.37093 -279.958292) (xy 82.37093 -280.002742)
			(xy 82.571082 -280.002742)
		)
		(stroke
			(width 0)
			(type solid)
		)
		(fill yes)
		(layer "In13.Cu")
		(net "M_B_CPU1_SB_DQ<9>")
	)
	(gr_poly
		(pts
			(xy 82.571082 -279.554432) (xy 82.571082 -279.509982) (xy 82.37093 -279.509982) (xy 82.37093 -279.554432)
			(xy 82.471006 -279.654508)
		)
		(stroke
			(width 0)
			(type solid)
		)
		(fill yes)
		(layer "In13.Cu")
		(net "M_B_CPU1_SB_DQ<10>")
	)
	(gr_poly
		(pts
			(xy 82.571082 -278.33828) (xy 82.471006 -278.238204) (xy 82.37093 -278.33828) (xy 82.37093 -278.38273)
			(xy 82.571082 -278.38273)
		)
		(stroke
			(width 0)
			(type solid)
		)
		(fill yes)
		(layer "In13.Cu")
		(net "M_B_CPU1_SB_DQ<5>")
	)
	(gr_poly
		(pts
			(xy 82.571082 -277.93442) (xy 82.571082 -277.88997) (xy 82.37093 -277.88997) (xy 82.37093 -277.93442)
			(xy 82.471006 -278.034496)
		)
		(stroke
			(width 0)
			(type solid)
		)
		(fill yes)
		(layer "In13.Cu")
		(net "M_B_CPU1_SB_DQ<6>")
	)
	(gr_poly
		(pts
			(xy 82.571082 -276.718014) (xy 82.471006 -276.618192) (xy 82.37093 -276.718014) (xy 82.37093 -276.765766)
			(xy 82.571082 -276.765766)
		)
		(stroke
			(width 0)
			(type solid)
		)
		(fill yes)
		(layer "In13.Cu")
		(net "M_B_CPU1_SB_DQS_DN<5>")
	)
	(gr_poly
		(pts
			(xy 82.571082 -276.314662) (xy 82.571082 -276.26691) (xy 82.37093 -276.26691) (xy 82.37093 -276.314662)
			(xy 82.471006 -276.414484)
		)
		(stroke
			(width 0)
			(type solid)
		)
		(fill yes)
		(layer "In13.Cu")
		(net "M_B_CPU1_SB_DQS_DN<0>")
	)
	(gr_poly
		(pts
			(xy 82.571082 -275.098256) (xy 82.471006 -274.99818) (xy 82.37093 -275.098256) (xy 82.37093 -275.142706)
			(xy 82.571082 -275.142706)
		)
		(stroke
			(width 0)
			(type solid)
		)
		(fill yes)
		(layer "In13.Cu")
		(net "M_B_CPU1_SB_DQ<1>")
	)
	(gr_poly
		(pts
			(xy 82.571082 -274.694396) (xy 82.571082 -274.649946) (xy 82.37093 -274.649946) (xy 82.37093 -274.694396)
			(xy 82.471006 -274.794472)
		)
		(stroke
			(width 0)
			(type solid)
		)
		(fill yes)
		(layer "In13.Cu")
		(net "M_B_CPU1_SB_DQ<2>")
	)
	(gr_poly
		(pts
			(xy 82.571082 -273.478244) (xy 82.471006 -273.378168) (xy 82.37093 -273.478244) (xy 82.37093 -273.522694)
			(xy 82.571082 -273.522694)
		)
		(stroke
			(width 0)
			(type solid)
		)
		(fill yes)
		(layer "In13.Cu")
		(net "M_B_CPU1_SB_CB<1>")
	)
	(gr_poly
		(pts
			(xy 82.571082 -273.074384) (xy 82.571082 -273.029934) (xy 82.37093 -273.029934) (xy 82.37093 -273.074384)
			(xy 82.471006 -273.17446)
		)
		(stroke
			(width 0)
			(type solid)
		)
		(fill yes)
		(layer "In13.Cu")
		(net "M_B_CPU1_SB_CB<2>")
	)
	(gr_poly
		(pts
			(xy 82.571082 -271.857978) (xy 82.471006 -271.758156) (xy 82.37093 -271.857978) (xy 82.37093 -271.90573)
			(xy 82.571082 -271.90573)
		)
		(stroke
			(width 0)
			(type solid)
		)
		(fill yes)
		(layer "In13.Cu")
		(net "M_B_CPU1_SB_DQS_DN<4>")
	)
	(gr_poly
		(pts
			(xy 82.571082 -271.454626) (xy 82.571082 -271.406874) (xy 82.37093 -271.406874) (xy 82.37093 -271.454626)
			(xy 82.471006 -271.554448)
		)
		(stroke
			(width 0)
			(type solid)
		)
		(fill yes)
		(layer "In13.Cu")
		(net "M_B_CPU1_SB_DQS_DN<9>")
	)
	(gr_poly
		(pts
			(xy 82.571082 -270.23822) (xy 82.471006 -270.138144) (xy 82.37093 -270.23822) (xy 82.37093 -270.28267)
			(xy 82.571082 -270.28267)
		)
		(stroke
			(width 0)
			(type solid)
		)
		(fill yes)
		(layer "In13.Cu")
		(net "M_B_CPU1_SB_CB<5>")
	)
	(gr_poly
		(pts
			(xy 82.571082 -269.83436) (xy 82.571082 -269.78991) (xy 82.37093 -269.78991) (xy 82.37093 -269.83436)
			(xy 82.471006 -269.934436)
		)
		(stroke
			(width 0)
			(type solid)
		)
		(fill yes)
		(layer "In13.Cu")
		(net "M_B_CPU1_SB_CB<6>")
	)
	(gr_poly
		(pts
			(xy 82.571082 -266.991846) (xy 82.471006 -266.89177) (xy 82.37093 -266.991846) (xy 82.37093 -267.036296)
			(xy 82.571082 -267.036296)
		)
		(stroke
			(width 0)
			(type solid)
		)
		(fill yes)
		(layer "In13.Cu")
		(net "M_B_CPU1_SA_RSP<0>")
	)
	(gr_poly
		(pts
			(xy 82.571082 -266.594336) (xy 82.571082 -266.549886) (xy 82.37093 -266.549886) (xy 82.37093 -266.594336)
			(xy 82.471006 -266.694412)
		)
		(stroke
			(width 0)
			(type solid)
		)
		(fill yes)
		(layer "In13.Cu")
		(net "M_B_CPU1_SB_CS_N<1>")
	)
	(gr_poly
		(pts
			(xy 82.571082 -264.974324) (xy 82.571082 -264.929874) (xy 82.37093 -264.929874) (xy 82.37093 -264.974324)
			(xy 82.471006 -265.0744)
		)
		(stroke
			(width 0)
			(type solid)
		)
		(fill yes)
		(layer "In13.Cu")
		(net "M_B_CPU1_SB_PAR")
	)
	(gr_poly
		(pts
			(xy 82.571082 -263.758172) (xy 82.471006 -263.658096) (xy 82.37093 -263.758172) (xy 82.37093 -263.802622)
			(xy 82.571082 -263.802622)
		)
		(stroke
			(width 0)
			(type solid)
		)
		(fill yes)
		(layer "In13.Cu")
		(net "M_B_CPU1_SB_CA<4>")
	)
	(gr_poly
		(pts
			(xy 82.571082 -263.354312) (xy 82.571082 -263.309862) (xy 82.37093 -263.309862) (xy 82.37093 -263.354312)
			(xy 82.471006 -263.454388)
		)
		(stroke
			(width 0)
			(type solid)
		)
		(fill yes)
		(layer "In13.Cu")
		(net "M_B_CPU1_SB_CA<3>")
	)
	(gr_poly
		(pts
			(xy 82.571082 -262.13816) (xy 82.471006 -262.038084) (xy 82.37093 -262.13816) (xy 82.37093 -262.18261)
			(xy 82.571082 -262.18261)
		)
		(stroke
			(width 0)
			(type solid)
		)
		(fill yes)
		(layer "In13.Cu")
		(net "M_B_CPU1_SB_CA<0>")
	)
	(gr_poly
		(pts
			(xy 82.660236 -226.203256) (xy 82.56016 -226.030028) (xy 82.521806 -226.05238) (xy 82.48523 -226.189032)
			(xy 82.621628 -226.225608)
		)
		(stroke
			(width 0)
			(type solid)
		)
		(fill yes)
		(layer "In13.Cu")
		(net "M_B_CPU1_SA_DQ<3>")
	)
	(gr_poly
		(pts
			(xy 82.660236 -224.583244) (xy 82.56016 -224.410016) (xy 82.521806 -224.432368) (xy 82.48523 -224.56902)
			(xy 82.621628 -224.605596)
		)
		(stroke
			(width 0)
			(type solid)
		)
		(fill yes)
		(layer "In13.Cu")
		(net "M_B_CPU1_SA_DQ<2>")
	)
	(gr_poly
		(pts
			(xy 82.741008 -256.432812) (xy 82.741008 -256.38506) (xy 82.540856 -256.38506) (xy 82.540856 -256.432812)
			(xy 82.640932 -256.532634)
		)
		(stroke
			(width 0)
			(type solid)
		)
		(fill yes)
		(layer "In13.Cu")
		(net "M_B_CPU1_CLK_DN<0>")
	)
	(gr_poly
		(pts
			(xy 82.741008 -255.216406) (xy 82.640932 -255.11633) (xy 82.540856 -255.216406) (xy 82.540856 -255.260856)
			(xy 82.741008 -255.260856)
		)
		(stroke
			(width 0)
			(type solid)
		)
		(fill yes)
		(layer "In13.Cu")
		(net "M_B_CPU1_SA_CA<6>")
	)
	(gr_poly
		(pts
			(xy 82.741008 -254.812546) (xy 82.741008 -254.768096) (xy 82.540856 -254.768096) (xy 82.540856 -254.812546)
			(xy 82.640932 -254.912622)
		)
		(stroke
			(width 0)
			(type solid)
		)
		(fill yes)
		(layer "In13.Cu")
		(net "M_B_CPU1_SA_CA<5>")
	)
	(gr_poly
		(pts
			(xy 82.741008 -253.596394) (xy 82.640932 -253.496318) (xy 82.540856 -253.596394) (xy 82.540856 -253.640844)
			(xy 82.741008 -253.640844)
		)
		(stroke
			(width 0)
			(type solid)
		)
		(fill yes)
		(layer "In13.Cu")
		(net "M_B_CPU1_SA_CA<2>")
	)
	(gr_poly
		(pts
			(xy 82.741008 -253.192534) (xy 82.741008 -253.148084) (xy 82.540856 -253.148084) (xy 82.540856 -253.192534)
			(xy 82.640932 -253.29261)
		)
		(stroke
			(width 0)
			(type solid)
		)
		(fill yes)
		(layer "In13.Cu")
		(net "M_B_CPU1_SA_CA<1>")
	)
	(gr_poly
		(pts
			(xy 82.741008 -251.572522) (xy 82.741008 -251.528072) (xy 82.540856 -251.528072) (xy 82.540856 -251.572522)
			(xy 82.640932 -251.672598)
		)
		(stroke
			(width 0)
			(type solid)
		)
		(fill yes)
		(layer "In13.Cu")
		(net "M_B_CPU1_SA_CS_N<0>")
	)
	(gr_poly
		(pts
			(xy 82.741008 -250.35637) (xy 82.640932 -250.256294) (xy 82.540856 -250.35637) (xy 82.540856 -250.40082)
			(xy 82.741008 -250.40082)
		)
		(stroke
			(width 0)
			(type solid)
		)
		(fill yes)
		(layer "In13.Cu")
		(net "M_B_CPU1_ALERT_R_N")
	)
	(gr_poly
		(pts
			(xy 82.741008 -248.736358) (xy 82.640932 -248.636282) (xy 82.540856 -248.736358) (xy 82.540856 -248.780808)
			(xy 82.741008 -248.780808)
		)
		(stroke
			(width 0)
			(type solid)
		)
		(fill yes)
		(layer "In13.Cu")
		(net "M_B_CPU1_SA_CB<5>")
	)
	(gr_poly
		(pts
			(xy 82.741008 -248.332498) (xy 82.741008 -248.288048) (xy 82.540856 -248.288048) (xy 82.540856 -248.332498)
			(xy 82.640932 -248.432574)
		)
		(stroke
			(width 0)
			(type solid)
		)
		(fill yes)
		(layer "In13.Cu")
		(net "M_B_CPU1_SA_CB<6>")
	)
	(gr_poly
		(pts
			(xy 82.741008 -247.116092) (xy 82.640932 -247.01627) (xy 82.540856 -247.116092) (xy 82.540856 -247.163844)
			(xy 82.741008 -247.163844)
		)
		(stroke
			(width 0)
			(type solid)
		)
		(fill yes)
		(layer "In13.Cu")
		(net "M_B_CPU1_SA_DQS_DN<9>")
	)
	(gr_poly
		(pts
			(xy 82.741008 -246.71274) (xy 82.741008 -246.664988) (xy 82.540856 -246.664988) (xy 82.540856 -246.71274)
			(xy 82.640932 -246.812562)
		)
		(stroke
			(width 0)
			(type solid)
		)
		(fill yes)
		(layer "In13.Cu")
		(net "M_B_CPU1_SA_DQS_DN<4>")
	)
	(gr_poly
		(pts
			(xy 82.741008 -245.496334) (xy 82.640932 -245.396258) (xy 82.540856 -245.496334) (xy 82.540856 -245.540784)
			(xy 82.741008 -245.540784)
		)
		(stroke
			(width 0)
			(type solid)
		)
		(fill yes)
		(layer "In13.Cu")
		(net "M_B_CPU1_SA_CB<1>")
	)
	(gr_poly
		(pts
			(xy 82.741008 -245.092474) (xy 82.741008 -245.048024) (xy 82.540856 -245.048024) (xy 82.540856 -245.092474)
			(xy 82.640932 -245.19255)
		)
		(stroke
			(width 0)
			(type solid)
		)
		(fill yes)
		(layer "In13.Cu")
		(net "M_B_CPU1_SA_CB<2>")
	)
	(gr_poly
		(pts
			(xy 82.741008 -243.876322) (xy 82.640932 -243.776246) (xy 82.540856 -243.876322) (xy 82.540856 -243.920772)
			(xy 82.741008 -243.920772)
		)
		(stroke
			(width 0)
			(type solid)
		)
		(fill yes)
		(layer "In13.Cu")
		(net "M_B_CPU1_SA_DQ<29>")
	)
	(gr_poly
		(pts
			(xy 82.741008 -243.472462) (xy 82.741008 -243.428012) (xy 82.540856 -243.428012) (xy 82.540856 -243.472462)
			(xy 82.640932 -243.572538)
		)
		(stroke
			(width 0)
			(type solid)
		)
		(fill yes)
		(layer "In13.Cu")
		(net "M_B_CPU1_SA_DQ<30>")
	)
	(gr_poly
		(pts
			(xy 82.741008 -242.256056) (xy 82.640932 -242.156234) (xy 82.540856 -242.256056) (xy 82.540856 -242.303808)
			(xy 82.741008 -242.303808)
		)
		(stroke
			(width 0)
			(type solid)
		)
		(fill yes)
		(layer "In13.Cu")
		(net "M_B_CPU1_SA_DQS_DN<8>")
	)
	(gr_poly
		(pts
			(xy 82.741008 -241.852704) (xy 82.741008 -241.804952) (xy 82.540856 -241.804952) (xy 82.540856 -241.852704)
			(xy 82.640932 -241.952526)
		)
		(stroke
			(width 0)
			(type solid)
		)
		(fill yes)
		(layer "In13.Cu")
		(net "M_B_CPU1_SA_DQS_DN<3>")
	)
	(gr_poly
		(pts
			(xy 82.741008 -240.636298) (xy 82.640932 -240.536222) (xy 82.540856 -240.636298) (xy 82.540856 -240.680748)
			(xy 82.741008 -240.680748)
		)
		(stroke
			(width 0)
			(type solid)
		)
		(fill yes)
		(layer "In13.Cu")
		(net "M_B_CPU1_SA_DQ<25>")
	)
	(gr_poly
		(pts
			(xy 82.741008 -240.232438) (xy 82.741008 -240.187988) (xy 82.540856 -240.187988) (xy 82.540856 -240.232438)
			(xy 82.640932 -240.332514)
		)
		(stroke
			(width 0)
			(type solid)
		)
		(fill yes)
		(layer "In13.Cu")
		(net "M_B_CPU1_SA_DQ<26>")
	)
	(gr_poly
		(pts
			(xy 82.741008 -239.016286) (xy 82.640932 -238.91621) (xy 82.540856 -239.016286) (xy 82.540856 -239.060736)
			(xy 82.741008 -239.060736)
		)
		(stroke
			(width 0)
			(type solid)
		)
		(fill yes)
		(layer "In13.Cu")
		(net "M_B_CPU1_SA_DQ<21>")
	)
	(gr_poly
		(pts
			(xy 82.741008 -238.612426) (xy 82.741008 -238.567976) (xy 82.540856 -238.567976) (xy 82.540856 -238.612426)
			(xy 82.640932 -238.712502)
		)
		(stroke
			(width 0)
			(type solid)
		)
		(fill yes)
		(layer "In13.Cu")
		(net "M_B_CPU1_SA_DQ<22>")
	)
	(gr_poly
		(pts
			(xy 82.741008 -237.39602) (xy 82.640932 -237.296198) (xy 82.540856 -237.39602) (xy 82.540856 -237.443772)
			(xy 82.741008 -237.443772)
		)
		(stroke
			(width 0)
			(type solid)
		)
		(fill yes)
		(layer "In13.Cu")
		(net "M_B_CPU1_SA_DQS_DN<7>")
	)
	(gr_poly
		(pts
			(xy 82.741008 -236.992668) (xy 82.741008 -236.944916) (xy 82.540856 -236.944916) (xy 82.540856 -236.992668)
			(xy 82.640932 -237.09249)
		)
		(stroke
			(width 0)
			(type solid)
		)
		(fill yes)
		(layer "In13.Cu")
		(net "M_B_CPU1_SA_DQS_DN<2>")
	)
	(gr_poly
		(pts
			(xy 82.741008 -235.776262) (xy 82.640932 -235.676186) (xy 82.540856 -235.776262) (xy 82.540856 -235.820712)
			(xy 82.741008 -235.820712)
		)
		(stroke
			(width 0)
			(type solid)
		)
		(fill yes)
		(layer "In13.Cu")
		(net "M_B_CPU1_SA_DQ<17>")
	)
	(gr_poly
		(pts
			(xy 82.741008 -235.372402) (xy 82.741008 -235.327952) (xy 82.540856 -235.327952) (xy 82.540856 -235.372402)
			(xy 82.640932 -235.472478)
		)
		(stroke
			(width 0)
			(type solid)
		)
		(fill yes)
		(layer "In13.Cu")
		(net "M_B_CPU1_SA_DQ<18>")
	)
	(gr_poly
		(pts
			(xy 82.741008 -234.15625) (xy 82.640932 -234.056174) (xy 82.540856 -234.15625) (xy 82.540856 -234.2007)
			(xy 82.741008 -234.2007)
		)
		(stroke
			(width 0)
			(type solid)
		)
		(fill yes)
		(layer "In13.Cu")
		(net "M_B_CPU1_SA_DQ<13>")
	)
	(gr_poly
		(pts
			(xy 82.741008 -233.75239) (xy 82.741008 -233.70794) (xy 82.540856 -233.70794) (xy 82.540856 -233.75239)
			(xy 82.640932 -233.852466)
		)
		(stroke
			(width 0)
			(type solid)
		)
		(fill yes)
		(layer "In13.Cu")
		(net "M_B_CPU1_SA_DQ<14>")
	)
	(gr_poly
		(pts
			(xy 82.741008 -232.535984) (xy 82.640932 -232.436162) (xy 82.540856 -232.535984) (xy 82.540856 -232.583736)
			(xy 82.741008 -232.583736)
		)
		(stroke
			(width 0)
			(type solid)
		)
		(fill yes)
		(layer "In13.Cu")
		(net "M_B_CPU1_SA_DQS_DN<6>")
	)
	(gr_poly
		(pts
			(xy 82.741008 -232.132632) (xy 82.741008 -232.08488) (xy 82.540856 -232.08488) (xy 82.540856 -232.132632)
			(xy 82.640932 -232.232454)
		)
		(stroke
			(width 0)
			(type solid)
		)
		(fill yes)
		(layer "In13.Cu")
		(net "M_B_CPU1_SA_DQS_DN<1>")
	)
	(gr_poly
		(pts
			(xy 82.741008 -230.916226) (xy 82.640932 -230.81615) (xy 82.540856 -230.916226) (xy 82.540856 -230.960676)
			(xy 82.741008 -230.960676)
		)
		(stroke
			(width 0)
			(type solid)
		)
		(fill yes)
		(layer "In13.Cu")
		(net "M_B_CPU1_SA_DQ<9>")
	)
	(gr_poly
		(pts
			(xy 82.741008 -230.51262) (xy 82.741008 -230.46817) (xy 82.540856 -230.46817) (xy 82.540856 -230.51262)
			(xy 82.640932 -230.612696)
		)
		(stroke
			(width 0)
			(type solid)
		)
		(fill yes)
		(layer "In13.Cu")
		(net "M_B_CPU1_SA_DQ<10>")
	)
	(gr_poly
		(pts
			(xy 82.741008 -229.296214) (xy 82.640932 -229.196138) (xy 82.540856 -229.296214) (xy 82.540856 -229.340664)
			(xy 82.741008 -229.340664)
		)
		(stroke
			(width 0)
			(type solid)
		)
		(fill yes)
		(layer "In13.Cu")
		(net "M_B_CPU1_SA_DQ<5>")
	)
	(gr_poly
		(pts
			(xy 82.741008 -228.892608) (xy 82.741008 -228.848158) (xy 82.540856 -228.848158) (xy 82.540856 -228.892608)
			(xy 82.640932 -228.992684)
		)
		(stroke
			(width 0)
			(type solid)
		)
		(fill yes)
		(layer "In13.Cu")
		(net "M_B_CPU1_SA_DQ<6>")
	)
	(gr_poly
		(pts
			(xy 82.741008 -227.27285) (xy 82.741008 -227.225098) (xy 82.540856 -227.225098) (xy 82.540856 -227.27285)
			(xy 82.640932 -227.372672)
		)
		(stroke
			(width 0)
			(type solid)
		)
		(fill yes)
		(layer "In13.Cu")
		(net "M_B_CPU1_SA_DQS_DN<0>")
	)
	(gr_poly
		(pts
			(xy 82.747104 -227.67671) (xy 82.647028 -227.576634) (xy 82.547206 -227.67671) (xy 82.547206 -227.724208)
			(xy 82.747104 -227.724208)
		)
		(stroke
			(width 0)
			(type solid)
		)
		(fill yes)
		(layer "In13.Cu")
		(net "M_B_CPU1_SA_DQS_DN<5>")
	)
	(gr_poly
		(pts
			(xy 82.760312 -225.656648) (xy 82.797142 -225.519996) (xy 82.66049 -225.48342) (xy 82.621882 -225.505772)
			(xy 82.721958 -225.679)
		)
		(stroke
			(width 0)
			(type solid)
		)
		(fill yes)
		(layer "In13.Cu")
		(net "M_B_CPU1_SA_DQ<1>")
	)
	(gr_poly
		(pts
			(xy 82.760312 -224.036636) (xy 82.797142 -223.899984) (xy 82.66049 -223.863408) (xy 82.621882 -223.88576)
			(xy 82.721958 -224.058988)
		)
		(stroke
			(width 0)
			(type solid)
		)
		(fill yes)
		(layer "In13.Cu")
		(net "M_B_CPU1_SA_DQ<0>")
	)
	(gr_poly
		(pts
			(xy 83.040982 -293.32428) (xy 83.040982 -293.27983) (xy 82.84083 -293.27983) (xy 82.84083 -293.32428)
			(xy 82.940906 -293.424356)
		)
		(stroke
			(width 0)
			(type solid)
		)
		(fill yes)
		(layer "In13.Cu")
		(net "M_B_CPU1_SB_DQ<31>")
	)
	(gr_poly
		(pts
			(xy 83.040982 -292.108128) (xy 82.940906 -292.008052) (xy 82.84083 -292.108128) (xy 82.84083 -292.152578)
			(xy 83.040982 -292.152578)
		)
		(stroke
			(width 0)
			(type solid)
		)
		(fill yes)
		(layer "In13.Cu")
		(net "M_B_CPU1_SB_DQ<28>")
	)
	(gr_poly
		(pts
			(xy 83.040982 -291.704522) (xy 83.040982 -291.65677) (xy 82.84083 -291.65677) (xy 82.84083 -291.704522)
			(xy 82.940906 -291.804344)
		)
		(stroke
			(width 0)
			(type solid)
		)
		(fill yes)
		(layer "In13.Cu")
		(net "M_B_CPU1_SB_DQS_DP<8>")
	)
	(gr_poly
		(pts
			(xy 83.040982 -290.487862) (xy 82.940906 -290.38804) (xy 82.84083 -290.487862) (xy 82.84083 -290.535614)
			(xy 83.040982 -290.535614)
		)
		(stroke
			(width 0)
			(type solid)
		)
		(fill yes)
		(layer "In13.Cu")
		(net "M_B_CPU1_SB_DQS_DP<3>")
	)
	(gr_poly
		(pts
			(xy 83.040982 -290.084256) (xy 83.040982 -290.039806) (xy 82.84083 -290.039806) (xy 82.84083 -290.084256)
			(xy 82.940906 -290.184332)
		)
		(stroke
			(width 0)
			(type solid)
		)
		(fill yes)
		(layer "In13.Cu")
		(net "M_B_CPU1_SB_DQ<27>")
	)
	(gr_poly
		(pts
			(xy 83.040982 -288.868104) (xy 82.940906 -288.768028) (xy 82.84083 -288.868104) (xy 82.84083 -288.912554)
			(xy 83.040982 -288.912554)
		)
		(stroke
			(width 0)
			(type solid)
		)
		(fill yes)
		(layer "In13.Cu")
		(net "M_B_CPU1_SB_DQ<24>")
	)
	(gr_poly
		(pts
			(xy 83.040982 -288.464498) (xy 83.040982 -288.420048) (xy 82.84083 -288.420048) (xy 82.84083 -288.464498)
			(xy 82.940906 -288.564574)
		)
		(stroke
			(width 0)
			(type solid)
		)
		(fill yes)
		(layer "In13.Cu")
		(net "M_B_CPU1_SB_DQ<23>")
	)
	(gr_poly
		(pts
			(xy 83.040982 -287.248092) (xy 82.940906 -287.148016) (xy 82.84083 -287.248092) (xy 82.84083 -287.292542)
			(xy 83.040982 -287.292542)
		)
		(stroke
			(width 0)
			(type solid)
		)
		(fill yes)
		(layer "In13.Cu")
		(net "M_B_CPU1_SB_DQ<20>")
	)
	(gr_poly
		(pts
			(xy 83.040982 -286.844486) (xy 83.040982 -286.796734) (xy 82.84083 -286.796734) (xy 82.84083 -286.844486)
			(xy 82.940906 -286.944562)
		)
		(stroke
			(width 0)
			(type solid)
		)
		(fill yes)
		(layer "In13.Cu")
		(net "M_B_CPU1_SB_DQS_DP<7>")
	)
	(gr_poly
		(pts
			(xy 83.040982 -285.62808) (xy 82.940906 -285.528258) (xy 82.84083 -285.62808) (xy 82.84083 -285.675832)
			(xy 83.040982 -285.675832)
		)
		(stroke
			(width 0)
			(type solid)
		)
		(fill yes)
		(layer "In13.Cu")
		(net "M_B_CPU1_SB_DQS_DP<2>")
	)
	(gr_poly
		(pts
			(xy 83.040982 -285.224474) (xy 83.040982 -285.180024) (xy 82.84083 -285.180024) (xy 82.84083 -285.224474)
			(xy 82.940906 -285.32455)
		)
		(stroke
			(width 0)
			(type solid)
		)
		(fill yes)
		(layer "In13.Cu")
		(net "M_B_CPU1_SB_DQ<19>")
	)
	(gr_poly
		(pts
			(xy 83.040982 -284.008322) (xy 82.940906 -283.908246) (xy 82.84083 -284.008322) (xy 82.84083 -284.052772)
			(xy 83.040982 -284.052772)
		)
		(stroke
			(width 0)
			(type solid)
		)
		(fill yes)
		(layer "In13.Cu")
		(net "M_B_CPU1_SB_DQ<16>")
	)
	(gr_poly
		(pts
			(xy 83.040982 -283.604462) (xy 83.040982 -283.560012) (xy 82.84083 -283.560012) (xy 82.84083 -283.604462)
			(xy 82.940906 -283.704538)
		)
		(stroke
			(width 0)
			(type solid)
		)
		(fill yes)
		(layer "In13.Cu")
		(net "M_B_CPU1_SB_DQ<15>")
	)
	(gr_poly
		(pts
			(xy 83.040982 -282.38831) (xy 82.940906 -282.288234) (xy 82.84083 -282.38831) (xy 82.84083 -282.43276)
			(xy 83.040982 -282.43276)
		)
		(stroke
			(width 0)
			(type solid)
		)
		(fill yes)
		(layer "In13.Cu")
		(net "M_B_CPU1_SB_DQ<12>")
	)
	(gr_poly
		(pts
			(xy 83.040982 -281.984704) (xy 83.040982 -281.936952) (xy 82.84083 -281.936952) (xy 82.84083 -281.984704)
			(xy 82.940906 -282.084526)
		)
		(stroke
			(width 0)
			(type solid)
		)
		(fill yes)
		(layer "In13.Cu")
		(net "M_B_CPU1_SB_DQS_DP<6>")
	)
	(gr_poly
		(pts
			(xy 83.040982 -280.768044) (xy 82.940906 -280.668222) (xy 82.84083 -280.768044) (xy 82.84083 -280.815796)
			(xy 83.040982 -280.815796)
		)
		(stroke
			(width 0)
			(type solid)
		)
		(fill yes)
		(layer "In13.Cu")
		(net "M_B_CPU1_SB_DQS_DP<1>")
	)
	(gr_poly
		(pts
			(xy 83.040982 -280.364438) (xy 83.040982 -280.319988) (xy 82.84083 -280.319988) (xy 82.84083 -280.364438)
			(xy 82.940906 -280.464514)
		)
		(stroke
			(width 0)
			(type solid)
		)
		(fill yes)
		(layer "In13.Cu")
		(net "M_B_CPU1_SB_DQ<11>")
	)
	(gr_poly
		(pts
			(xy 83.040982 -279.148286) (xy 82.940906 -279.04821) (xy 82.84083 -279.148286) (xy 82.84083 -279.192736)
			(xy 83.040982 -279.192736)
		)
		(stroke
			(width 0)
			(type solid)
		)
		(fill yes)
		(layer "In13.Cu")
		(net "M_B_CPU1_SB_DQ<8>")
	)
	(gr_poly
		(pts
			(xy 83.040982 -278.744426) (xy 83.040982 -278.699976) (xy 82.84083 -278.699976) (xy 82.84083 -278.744426)
			(xy 82.940906 -278.844502)
		)
		(stroke
			(width 0)
			(type solid)
		)
		(fill yes)
		(layer "In13.Cu")
		(net "M_B_CPU1_SB_DQ<7>")
	)
	(gr_poly
		(pts
			(xy 83.040982 -277.528274) (xy 82.940906 -277.428198) (xy 82.84083 -277.528274) (xy 82.84083 -277.572724)
			(xy 83.040982 -277.572724)
		)
		(stroke
			(width 0)
			(type solid)
		)
		(fill yes)
		(layer "In13.Cu")
		(net "M_B_CPU1_SB_DQ<4>")
	)
	(gr_poly
		(pts
			(xy 83.040982 -275.504402) (xy 83.040982 -275.459952) (xy 82.84083 -275.459952) (xy 82.84083 -275.504402)
			(xy 82.940906 -275.604478)
		)
		(stroke
			(width 0)
			(type solid)
		)
		(fill yes)
		(layer "In13.Cu")
		(net "M_B_CPU1_SB_DQ<3>")
	)
	(gr_poly
		(pts
			(xy 83.040982 -274.28825) (xy 82.940906 -274.188174) (xy 82.84083 -274.28825) (xy 82.84083 -274.3327)
			(xy 83.040982 -274.3327)
		)
		(stroke
			(width 0)
			(type solid)
		)
		(fill yes)
		(layer "In13.Cu")
		(net "M_B_CPU1_SB_DQ<0>")
	)
	(gr_poly
		(pts
			(xy 83.040982 -273.88439) (xy 83.040982 -273.83994) (xy 82.84083 -273.83994) (xy 82.84083 -273.88439)
			(xy 82.940906 -273.984466)
		)
		(stroke
			(width 0)
			(type solid)
		)
		(fill yes)
		(layer "In13.Cu")
		(net "M_B_CPU1_SB_CB<3>")
	)
	(gr_poly
		(pts
			(xy 83.040982 -272.668238) (xy 82.940906 -272.568162) (xy 82.84083 -272.668238) (xy 82.84083 -272.712688)
			(xy 83.040982 -272.712688)
		)
		(stroke
			(width 0)
			(type solid)
		)
		(fill yes)
		(layer "In13.Cu")
		(net "M_B_CPU1_SB_CB<0>")
	)
	(gr_poly
		(pts
			(xy 83.040982 -272.264632) (xy 83.040982 -272.21688) (xy 82.84083 -272.21688) (xy 82.84083 -272.264632)
			(xy 82.940906 -272.364454)
		)
		(stroke
			(width 0)
			(type solid)
		)
		(fill yes)
		(layer "In13.Cu")
		(net "M_B_CPU1_SB_DQS_DP<4>")
	)
	(gr_poly
		(pts
			(xy 83.040982 -271.047972) (xy 82.940906 -270.94815) (xy 82.84083 -271.047972) (xy 82.84083 -271.095724)
			(xy 83.040982 -271.095724)
		)
		(stroke
			(width 0)
			(type solid)
		)
		(fill yes)
		(layer "In13.Cu")
		(net "M_B_CPU1_SB_DQS_DP<9>")
	)
	(gr_poly
		(pts
			(xy 83.040982 -270.644366) (xy 83.040982 -270.599916) (xy 82.84083 -270.599916) (xy 82.84083 -270.644366)
			(xy 82.940906 -270.744442)
		)
		(stroke
			(width 0)
			(type solid)
		)
		(fill yes)
		(layer "In13.Cu")
		(net "M_B_CPU1_SB_CB<7>")
	)
	(gr_poly
		(pts
			(xy 83.040982 -269.428214) (xy 82.940906 -269.328138) (xy 82.84083 -269.428214) (xy 82.84083 -269.472664)
			(xy 83.040982 -269.472664)
		)
		(stroke
			(width 0)
			(type solid)
		)
		(fill yes)
		(layer "In13.Cu")
		(net "M_B_CPU1_SB_CB<4>")
	)
	(gr_poly
		(pts
			(xy 83.040982 -264.164318) (xy 83.040982 -264.119868) (xy 82.84083 -264.119868) (xy 82.84083 -264.164318)
			(xy 82.940906 -264.264394)
		)
		(stroke
			(width 0)
			(type solid)
		)
		(fill yes)
		(layer "In13.Cu")
		(net "M_B_CPU1_SB_CA<5>")
	)
	(gr_poly
		(pts
			(xy 83.040982 -262.948166) (xy 82.940906 -262.84809) (xy 82.84083 -262.948166) (xy 82.84083 -262.992616)
			(xy 83.040982 -262.992616)
		)
		(stroke
			(width 0)
			(type solid)
		)
		(fill yes)
		(layer "In13.Cu")
		(net "M_B_CPU1_SB_CA<2>")
	)
	(gr_poly
		(pts
			(xy 83.040982 -262.544306) (xy 83.040982 -262.499856) (xy 82.84083 -262.499856) (xy 82.84083 -262.544306)
			(xy 82.940906 -262.644382)
		)
		(stroke
			(width 0)
			(type solid)
		)
		(fill yes)
		(layer "In13.Cu")
		(net "M_B_CPU1_SB_CA<1>")
	)
	(gr_poly
		(pts
			(xy 83.041236 -265.78433) (xy 83.041236 -265.73988) (xy 82.841084 -265.73988) (xy 82.841084 -265.78433)
			(xy 82.94116 -265.884406)
		)
		(stroke
			(width 0)
			(type solid)
		)
		(fill yes)
		(layer "In13.Cu")
		(net "M_B_CPU1_SB_CS_N<0>")
	)
	(gr_poly
		(pts
			(xy 83.041236 -264.568178) (xy 82.94116 -264.468102) (xy 82.841084 -264.568178) (xy 82.841084 -264.612628)
			(xy 83.041236 -264.612628)
		)
		(stroke
			(width 0)
			(type solid)
		)
		(fill yes)
		(layer "In13.Cu")
		(net "M_B_CPU1_SB_CA<6>")
	)
	(gr_poly
		(pts
			(xy 83.047078 -267.801852) (xy 82.947256 -267.701776) (xy 82.84718 -267.801852) (xy 82.84718 -267.846302)
			(xy 83.047078 -267.846302)
		)
		(stroke
			(width 0)
			(type solid)
		)
		(fill yes)
		(layer "In13.Cu")
		(net "M_B_CPU1_SB_RSP<0>")
	)
	(gr_poly
		(pts
			(xy 83.048094 -277.124668) (xy 83.048094 -277.076916) (xy 82.848196 -277.076916) (xy 82.848196 -277.124668)
			(xy 82.948272 -277.22449)
		)
		(stroke
			(width 0)
			(type solid)
		)
		(fill yes)
		(layer "In13.Cu")
		(net "M_B_CPU1_SB_DQS_DP<5>")
	)
	(gr_poly
		(pts
			(xy 83.048094 -275.908008) (xy 82.948272 -275.808186) (xy 82.848196 -275.908008) (xy 82.848196 -275.95576)
			(xy 83.048094 -275.95576)
		)
		(stroke
			(width 0)
			(type solid)
		)
		(fill yes)
		(layer "In13.Cu")
		(net "M_B_CPU1_SB_DQS_DP<0>")
	)
	(gr_poly
		(pts
			(xy 83.130136 -225.39325) (xy 83.03006 -225.220022) (xy 82.991706 -225.242374) (xy 82.95513 -225.379026)
			(xy 83.091528 -225.415602)
		)
		(stroke
			(width 0)
			(type solid)
		)
		(fill yes)
		(layer "In13.Cu")
		(net "M_B_CPU1_SA_DQ<2>")
	)
	(gr_poly
		(pts
			(xy 83.211162 -256.026158) (xy 83.111086 -255.926336) (xy 83.01101 -256.026158) (xy 83.01101 -256.07391)
			(xy 83.211162 -256.07391)
		)
		(stroke
			(width 0)
			(type solid)
		)
		(fill yes)
		(layer "In13.Cu")
		(net "M_B_CPU1_CLK_DP<0>")
	)
	(gr_poly
		(pts
			(xy 83.211162 -255.622552) (xy 83.211162 -255.578102) (xy 83.01101 -255.578102) (xy 83.01101 -255.622552)
			(xy 83.111086 -255.722628)
		)
		(stroke
			(width 0)
			(type solid)
		)
		(fill yes)
		(layer "In13.Cu")
		(net "M_B_CPU1_SA_PAR")
	)
	(gr_poly
		(pts
			(xy 83.211162 -254.4064) (xy 83.111086 -254.306324) (xy 83.01101 -254.4064) (xy 83.01101 -254.45085)
			(xy 83.211162 -254.45085)
		)
		(stroke
			(width 0)
			(type solid)
		)
		(fill yes)
		(layer "In13.Cu")
		(net "M_B_CPU1_SA_CA<4>")
	)
	(gr_poly
		(pts
			(xy 83.211162 -254.00254) (xy 83.211162 -253.95809) (xy 83.01101 -253.95809) (xy 83.01101 -254.00254)
			(xy 83.111086 -254.102616)
		)
		(stroke
			(width 0)
			(type solid)
		)
		(fill yes)
		(layer "In13.Cu")
		(net "M_B_CPU1_SA_CA<3>")
	)
	(gr_poly
		(pts
			(xy 83.211162 -252.786388) (xy 83.111086 -252.686312) (xy 83.01101 -252.786388) (xy 83.01101 -252.830838)
			(xy 83.211162 -252.830838)
		)
		(stroke
			(width 0)
			(type solid)
		)
		(fill yes)
		(layer "In13.Cu")
		(net "M_B_CPU1_SA_CA<0>")
	)
	(gr_poly
		(pts
			(xy 83.211162 -252.382528) (xy 83.211162 -252.338078) (xy 83.01101 -252.338078) (xy 83.01101 -252.382528)
			(xy 83.111086 -252.482604)
		)
		(stroke
			(width 0)
			(type solid)
		)
		(fill yes)
		(layer "In13.Cu")
		(net "M_B_CPU1_SA_CS_N<1>")
	)
	(gr_poly
		(pts
			(xy 83.211162 -250.762516) (xy 83.211162 -250.718066) (xy 83.01101 -250.718066) (xy 83.01101 -250.762516)
			(xy 83.111086 -250.862592)
		)
		(stroke
			(width 0)
			(type solid)
		)
		(fill yes)
		(layer "In13.Cu")
		(net "M_B_CPU1_RESET_N")
	)
	(gr_poly
		(pts
			(xy 83.211162 -249.142504) (xy 83.211162 -249.098054) (xy 83.01101 -249.098054) (xy 83.01101 -249.142504)
			(xy 83.111086 -249.24258)
		)
		(stroke
			(width 0)
			(type solid)
		)
		(fill yes)
		(layer "In13.Cu")
		(net "M_B_CPU1_SA_CB<7>")
	)
	(gr_poly
		(pts
			(xy 83.211162 -247.926352) (xy 83.111086 -247.826276) (xy 83.01101 -247.926352) (xy 83.01101 -247.970802)
			(xy 83.211162 -247.970802)
		)
		(stroke
			(width 0)
			(type solid)
		)
		(fill yes)
		(layer "In13.Cu")
		(net "M_B_CPU1_SA_CB<4>")
	)
	(gr_poly
		(pts
			(xy 83.211162 -247.522746) (xy 83.211162 -247.474994) (xy 83.01101 -247.474994) (xy 83.01101 -247.522746)
			(xy 83.111086 -247.622568)
		)
		(stroke
			(width 0)
			(type solid)
		)
		(fill yes)
		(layer "In13.Cu")
		(net "M_B_CPU1_SA_DQS_DP<9>")
	)
	(gr_poly
		(pts
			(xy 83.211162 -246.306086) (xy 83.111086 -246.206264) (xy 83.01101 -246.306086) (xy 83.01101 -246.353838)
			(xy 83.211162 -246.353838)
		)
		(stroke
			(width 0)
			(type solid)
		)
		(fill yes)
		(layer "In13.Cu")
		(net "M_B_CPU1_SA_DQS_DP<4>")
	)
	(gr_poly
		(pts
			(xy 83.211162 -245.90248) (xy 83.211162 -245.85803) (xy 83.01101 -245.85803) (xy 83.01101 -245.90248)
			(xy 83.111086 -246.002556)
		)
		(stroke
			(width 0)
			(type solid)
		)
		(fill yes)
		(layer "In13.Cu")
		(net "M_B_CPU1_SA_CB<3>")
	)
	(gr_poly
		(pts
			(xy 83.211162 -244.686328) (xy 83.111086 -244.586252) (xy 83.01101 -244.686328) (xy 83.01101 -244.730778)
			(xy 83.211162 -244.730778)
		)
		(stroke
			(width 0)
			(type solid)
		)
		(fill yes)
		(layer "In13.Cu")
		(net "M_B_CPU1_SA_CB<0>")
	)
	(gr_poly
		(pts
			(xy 83.211162 -244.282468) (xy 83.211162 -244.238018) (xy 83.01101 -244.238018) (xy 83.01101 -244.282468)
			(xy 83.111086 -244.382544)
		)
		(stroke
			(width 0)
			(type solid)
		)
		(fill yes)
		(layer "In13.Cu")
		(net "M_B_CPU1_SA_DQ<31>")
	)
	(gr_poly
		(pts
			(xy 83.211162 -243.066316) (xy 83.111086 -242.96624) (xy 83.01101 -243.066316) (xy 83.01101 -243.110766)
			(xy 83.211162 -243.110766)
		)
		(stroke
			(width 0)
			(type solid)
		)
		(fill yes)
		(layer "In13.Cu")
		(net "M_B_CPU1_SA_DQ<28>")
	)
	(gr_poly
		(pts
			(xy 83.211162 -242.66271) (xy 83.211162 -242.614958) (xy 83.01101 -242.614958) (xy 83.01101 -242.66271)
			(xy 83.111086 -242.762532)
		)
		(stroke
			(width 0)
			(type solid)
		)
		(fill yes)
		(layer "In13.Cu")
		(net "M_B_CPU1_SA_DQS_DP<8>")
	)
	(gr_poly
		(pts
			(xy 83.211162 -241.44605) (xy 83.111086 -241.346228) (xy 83.01101 -241.44605) (xy 83.01101 -241.493802)
			(xy 83.211162 -241.493802)
		)
		(stroke
			(width 0)
			(type solid)
		)
		(fill yes)
		(layer "In13.Cu")
		(net "M_B_CPU1_SA_DQS_DP<3>")
	)
	(gr_poly
		(pts
			(xy 83.211162 -241.042444) (xy 83.211162 -240.997994) (xy 83.01101 -240.997994) (xy 83.01101 -241.042444)
			(xy 83.111086 -241.14252)
		)
		(stroke
			(width 0)
			(type solid)
		)
		(fill yes)
		(layer "In13.Cu")
		(net "M_B_CPU1_SA_DQ<27>")
	)
	(gr_poly
		(pts
			(xy 83.211162 -239.826292) (xy 83.111086 -239.726216) (xy 83.01101 -239.826292) (xy 83.01101 -239.870742)
			(xy 83.211162 -239.870742)
		)
		(stroke
			(width 0)
			(type solid)
		)
		(fill yes)
		(layer "In13.Cu")
		(net "M_B_CPU1_SA_DQ<24>")
	)
	(gr_poly
		(pts
			(xy 83.211162 -239.422432) (xy 83.211162 -239.377982) (xy 83.01101 -239.377982) (xy 83.01101 -239.422432)
			(xy 83.111086 -239.522508)
		)
		(stroke
			(width 0)
			(type solid)
		)
		(fill yes)
		(layer "In13.Cu")
		(net "M_B_CPU1_SA_DQ<23>")
	)
	(gr_poly
		(pts
			(xy 83.211162 -238.20628) (xy 83.111086 -238.106204) (xy 83.01101 -238.20628) (xy 83.01101 -238.25073)
			(xy 83.211162 -238.25073)
		)
		(stroke
			(width 0)
			(type solid)
		)
		(fill yes)
		(layer "In13.Cu")
		(net "M_B_CPU1_SA_DQ<20>")
	)
	(gr_poly
		(pts
			(xy 83.211162 -237.802674) (xy 83.211162 -237.754922) (xy 83.01101 -237.754922) (xy 83.01101 -237.802674)
			(xy 83.111086 -237.902496)
		)
		(stroke
			(width 0)
			(type solid)
		)
		(fill yes)
		(layer "In13.Cu")
		(net "M_B_CPU1_SA_DQS_DP<7>")
	)
	(gr_poly
		(pts
			(xy 83.211162 -236.586014) (xy 83.111086 -236.486192) (xy 83.01101 -236.586014) (xy 83.01101 -236.633766)
			(xy 83.211162 -236.633766)
		)
		(stroke
			(width 0)
			(type solid)
		)
		(fill yes)
		(layer "In13.Cu")
		(net "M_B_CPU1_SA_DQS_DP<2>")
	)
	(gr_poly
		(pts
			(xy 83.211162 -236.182408) (xy 83.211162 -236.137958) (xy 83.01101 -236.137958) (xy 83.01101 -236.182408)
			(xy 83.111086 -236.282484)
		)
		(stroke
			(width 0)
			(type solid)
		)
		(fill yes)
		(layer "In13.Cu")
		(net "M_B_CPU1_SA_DQ<19>")
	)
	(gr_poly
		(pts
			(xy 83.211162 -234.966256) (xy 83.111086 -234.86618) (xy 83.01101 -234.966256) (xy 83.01101 -235.010706)
			(xy 83.211162 -235.010706)
		)
		(stroke
			(width 0)
			(type solid)
		)
		(fill yes)
		(layer "In13.Cu")
		(net "M_B_CPU1_SA_DQ<16>")
	)
	(gr_poly
		(pts
			(xy 83.211162 -234.562396) (xy 83.211162 -234.517946) (xy 83.01101 -234.517946) (xy 83.01101 -234.562396)
			(xy 83.111086 -234.662472)
		)
		(stroke
			(width 0)
			(type solid)
		)
		(fill yes)
		(layer "In13.Cu")
		(net "M_B_CPU1_SA_DQ<15>")
	)
	(gr_poly
		(pts
			(xy 83.211162 -233.346244) (xy 83.111086 -233.246168) (xy 83.01101 -233.346244) (xy 83.01101 -233.390694)
			(xy 83.211162 -233.390694)
		)
		(stroke
			(width 0)
			(type solid)
		)
		(fill yes)
		(layer "In13.Cu")
		(net "M_B_CPU1_SA_DQ<12>")
	)
	(gr_poly
		(pts
			(xy 83.211162 -232.942638) (xy 83.211162 -232.894886) (xy 83.01101 -232.894886) (xy 83.01101 -232.942638)
			(xy 83.111086 -233.04246)
		)
		(stroke
			(width 0)
			(type solid)
		)
		(fill yes)
		(layer "In13.Cu")
		(net "M_B_CPU1_SA_DQS_DP<6>")
	)
	(gr_poly
		(pts
			(xy 83.211162 -231.725978) (xy 83.111086 -231.626156) (xy 83.01101 -231.725978) (xy 83.01101 -231.77373)
			(xy 83.211162 -231.77373)
		)
		(stroke
			(width 0)
			(type solid)
		)
		(fill yes)
		(layer "In13.Cu")
		(net "M_B_CPU1_SA_DQS_DP<1>")
	)
	(gr_poly
		(pts
			(xy 83.211162 -231.322626) (xy 83.211162 -231.278176) (xy 83.01101 -231.278176) (xy 83.01101 -231.322626)
			(xy 83.111086 -231.422702)
		)
		(stroke
			(width 0)
			(type solid)
		)
		(fill yes)
		(layer "In13.Cu")
		(net "M_B_CPU1_SA_DQ<11>")
	)
	(gr_poly
		(pts
			(xy 83.211162 -230.10622) (xy 83.111086 -230.006144) (xy 83.01101 -230.10622) (xy 83.01101 -230.15067)
			(xy 83.211162 -230.15067)
		)
		(stroke
			(width 0)
			(type solid)
		)
		(fill yes)
		(layer "In13.Cu")
		(net "M_B_CPU1_SA_DQ<8>")
	)
	(gr_poly
		(pts
			(xy 83.211162 -229.702614) (xy 83.211162 -229.658164) (xy 83.01101 -229.658164) (xy 83.01101 -229.702614)
			(xy 83.111086 -229.80269)
		)
		(stroke
			(width 0)
			(type solid)
		)
		(fill yes)
		(layer "In13.Cu")
		(net "M_B_CPU1_SA_DQ<7>")
	)
	(gr_poly
		(pts
			(xy 83.211162 -228.486462) (xy 83.111086 -228.386386) (xy 83.01101 -228.486462) (xy 83.01101 -228.530912)
			(xy 83.211162 -228.530912)
		)
		(stroke
			(width 0)
			(type solid)
		)
		(fill yes)
		(layer "In13.Cu")
		(net "M_B_CPU1_SA_DQ<4>")
	)
	(gr_poly
		(pts
			(xy 83.211162 -228.082856) (xy 83.211162 -228.035104) (xy 83.01101 -228.035104) (xy 83.01101 -228.082856)
			(xy 83.111086 -228.182678)
		)
		(stroke
			(width 0)
			(type solid)
		)
		(fill yes)
		(layer "In13.Cu")
		(net "M_B_CPU1_SA_DQS_DP<5>")
	)
	(gr_poly
		(pts
			(xy 83.211162 -226.866196) (xy 83.111086 -226.766374) (xy 83.01101 -226.866196) (xy 83.01101 -226.913948)
			(xy 83.211162 -226.913948)
		)
		(stroke
			(width 0)
			(type solid)
		)
		(fill yes)
		(layer "In13.Cu")
		(net "M_B_CPU1_SA_DQS_DP<0>")
	)
	(gr_poly
		(pts
			(xy 83.211162 -226.46259) (xy 83.211162 -226.41814) (xy 83.01101 -226.41814) (xy 83.01101 -226.46259)
			(xy 83.111086 -226.562666)
		)
		(stroke
			(width 0)
			(type solid)
		)
		(fill yes)
		(layer "In13.Cu")
		(net "M_B_CPU1_SA_DQ<3>")
	)
	(gr_poly
		(pts
			(xy 83.230212 -224.846642) (xy 83.267042 -224.70999) (xy 83.13039 -224.673414) (xy 83.091782 -224.695766)
			(xy 83.191858 -224.868994)
		)
		(stroke
			(width 0)
			(type solid)
		)
		(fill yes)
		(layer "In13.Cu")
		(net "M_B_CPU1_SA_DQ<0>")
	)
	(gr_poly
		(pts
			(xy 83.504786 -266.991846) (xy 83.40471 -266.89177) (xy 83.304888 -266.991846) (xy 83.304888 -267.036296)
			(xy 83.504786 -267.036296)
		)
		(stroke
			(width 0)
			(type solid)
		)
		(fill yes)
		(layer "In13.Cu")
		(net "M_B_CPU1_SA_RSP<0>")
	)
	(gr_poly
		(pts
			(xy 83.511136 -292.918134) (xy 83.41106 -292.818058) (xy 83.310984 -292.918134) (xy 83.310984 -292.962584)
			(xy 83.511136 -292.962584)
		)
		(stroke
			(width 0)
			(type solid)
		)
		(fill yes)
		(layer "In13.Cu")
		(net "M_B_CPU1_SB_DQ<29>")
	)
	(gr_poly
		(pts
			(xy 83.511136 -292.514274) (xy 83.511136 -292.469824) (xy 83.310984 -292.469824) (xy 83.310984 -292.514274)
			(xy 83.41106 -292.61435)
		)
		(stroke
			(width 0)
			(type solid)
		)
		(fill yes)
		(layer "In13.Cu")
		(net "M_B_CPU1_SB_DQ<30>")
	)
	(gr_poly
		(pts
			(xy 83.511136 -291.297868) (xy 83.41106 -291.198046) (xy 83.310984 -291.297868) (xy 83.310984 -291.34562)
			(xy 83.511136 -291.34562)
		)
		(stroke
			(width 0)
			(type solid)
		)
		(fill yes)
		(layer "In13.Cu")
		(net "M_B_CPU1_SB_DQS_DN<8>")
	)
	(gr_poly
		(pts
			(xy 83.511136 -290.894516) (xy 83.511136 -290.846764) (xy 83.310984 -290.846764) (xy 83.310984 -290.894516)
			(xy 83.41106 -290.994338)
		)
		(stroke
			(width 0)
			(type solid)
		)
		(fill yes)
		(layer "In13.Cu")
		(net "M_B_CPU1_SB_DQS_DN<3>")
	)
	(gr_poly
		(pts
			(xy 83.511136 -289.67811) (xy 83.41106 -289.578034) (xy 83.310984 -289.67811) (xy 83.310984 -289.72256)
			(xy 83.511136 -289.72256)
		)
		(stroke
			(width 0)
			(type solid)
		)
		(fill yes)
		(layer "In13.Cu")
		(net "M_B_CPU1_SB_DQ<25>")
	)
	(gr_poly
		(pts
			(xy 83.511136 -289.27425) (xy 83.511136 -289.2298) (xy 83.310984 -289.2298) (xy 83.310984 -289.27425)
			(xy 83.41106 -289.374326)
		)
		(stroke
			(width 0)
			(type solid)
		)
		(fill yes)
		(layer "In13.Cu")
		(net "M_B_CPU1_SB_DQ<26>")
	)
	(gr_poly
		(pts
			(xy 83.511136 -288.058098) (xy 83.41106 -287.958022) (xy 83.310984 -288.058098) (xy 83.310984 -288.102548)
			(xy 83.511136 -288.102548)
		)
		(stroke
			(width 0)
			(type solid)
		)
		(fill yes)
		(layer "In13.Cu")
		(net "M_B_CPU1_SB_DQ<21>")
	)
	(gr_poly
		(pts
			(xy 83.511136 -287.654492) (xy 83.511136 -287.610042) (xy 83.310984 -287.610042) (xy 83.310984 -287.654492)
			(xy 83.41106 -287.754568)
		)
		(stroke
			(width 0)
			(type solid)
		)
		(fill yes)
		(layer "In13.Cu")
		(net "M_B_CPU1_SB_DQ<22>")
	)
	(gr_poly
		(pts
			(xy 83.511136 -286.438086) (xy 83.41106 -286.33801) (xy 83.310984 -286.438086) (xy 83.310984 -286.485838)
			(xy 83.511136 -286.485838)
		)
		(stroke
			(width 0)
			(type solid)
		)
		(fill yes)
		(layer "In13.Cu")
		(net "M_B_CPU1_SB_DQS_DN<7>")
	)
	(gr_poly
		(pts
			(xy 83.511136 -286.034734) (xy 83.511136 -285.986982) (xy 83.310984 -285.986982) (xy 83.310984 -286.034734)
			(xy 83.41106 -286.134556)
		)
		(stroke
			(width 0)
			(type solid)
		)
		(fill yes)
		(layer "In13.Cu")
		(net "M_B_CPU1_SB_DQS_DN<2>")
	)
	(gr_poly
		(pts
			(xy 83.511136 -284.818328) (xy 83.41106 -284.718252) (xy 83.310984 -284.818328) (xy 83.310984 -284.862778)
			(xy 83.511136 -284.862778)
		)
		(stroke
			(width 0)
			(type solid)
		)
		(fill yes)
		(layer "In13.Cu")
		(net "M_B_CPU1_SB_DQ<17>")
	)
	(gr_poly
		(pts
			(xy 83.511136 -284.414468) (xy 83.511136 -284.370018) (xy 83.310984 -284.370018) (xy 83.310984 -284.414468)
			(xy 83.41106 -284.514544)
		)
		(stroke
			(width 0)
			(type solid)
		)
		(fill yes)
		(layer "In13.Cu")
		(net "M_B_CPU1_SB_DQ<18>")
	)
	(gr_poly
		(pts
			(xy 83.511136 -283.198316) (xy 83.41106 -283.09824) (xy 83.310984 -283.198316) (xy 83.310984 -283.242766)
			(xy 83.511136 -283.242766)
		)
		(stroke
			(width 0)
			(type solid)
		)
		(fill yes)
		(layer "In13.Cu")
		(net "M_B_CPU1_SB_DQ<13>")
	)
	(gr_poly
		(pts
			(xy 83.511136 -282.794456) (xy 83.511136 -282.750006) (xy 83.310984 -282.750006) (xy 83.310984 -282.794456)
			(xy 83.41106 -282.894532)
		)
		(stroke
			(width 0)
			(type solid)
		)
		(fill yes)
		(layer "In13.Cu")
		(net "M_B_CPU1_SB_DQ<14>")
	)
	(gr_poly
		(pts
			(xy 83.511136 -281.57805) (xy 83.41106 -281.478228) (xy 83.310984 -281.57805) (xy 83.310984 -281.625802)
			(xy 83.511136 -281.625802)
		)
		(stroke
			(width 0)
			(type solid)
		)
		(fill yes)
		(layer "In13.Cu")
		(net "M_B_CPU1_SB_DQS_DN<6>")
	)
	(gr_poly
		(pts
			(xy 83.511136 -281.174698) (xy 83.511136 -281.126946) (xy 83.310984 -281.126946) (xy 83.310984 -281.174698)
			(xy 83.41106 -281.27452)
		)
		(stroke
			(width 0)
			(type solid)
		)
		(fill yes)
		(layer "In13.Cu")
		(net "M_B_CPU1_SB_DQS_DN<1>")
	)
	(gr_poly
		(pts
			(xy 83.511136 -279.958292) (xy 83.41106 -279.858216) (xy 83.310984 -279.958292) (xy 83.310984 -280.002742)
			(xy 83.511136 -280.002742)
		)
		(stroke
			(width 0)
			(type solid)
		)
		(fill yes)
		(layer "In13.Cu")
		(net "M_B_CPU1_SB_DQ<9>")
	)
	(gr_poly
		(pts
			(xy 83.511136 -279.554432) (xy 83.511136 -279.509982) (xy 83.310984 -279.509982) (xy 83.310984 -279.554432)
			(xy 83.41106 -279.654508)
		)
		(stroke
			(width 0)
			(type solid)
		)
		(fill yes)
		(layer "In13.Cu")
		(net "M_B_CPU1_SB_DQ<10>")
	)
	(gr_poly
		(pts
			(xy 83.511136 -278.33828) (xy 83.41106 -278.238204) (xy 83.310984 -278.33828) (xy 83.310984 -278.38273)
			(xy 83.511136 -278.38273)
		)
		(stroke
			(width 0)
			(type solid)
		)
		(fill yes)
		(layer "In13.Cu")
		(net "M_B_CPU1_SB_DQ<5>")
	)
	(gr_poly
		(pts
			(xy 83.511136 -277.93442) (xy 83.511136 -277.88997) (xy 83.310984 -277.88997) (xy 83.310984 -277.93442)
			(xy 83.41106 -278.034496)
		)
		(stroke
			(width 0)
			(type solid)
		)
		(fill yes)
		(layer "In13.Cu")
		(net "M_B_CPU1_SB_DQ<6>")
	)
	(gr_poly
		(pts
			(xy 83.511136 -276.718014) (xy 83.41106 -276.618192) (xy 83.310984 -276.718014) (xy 83.310984 -276.765766)
			(xy 83.511136 -276.765766)
		)
		(stroke
			(width 0)
			(type solid)
		)
		(fill yes)
		(layer "In13.Cu")
		(net "M_B_CPU1_SB_DQS_DN<5>")
	)
	(gr_poly
		(pts
			(xy 83.511136 -276.314662) (xy 83.511136 -276.26691) (xy 83.310984 -276.26691) (xy 83.310984 -276.314662)
			(xy 83.41106 -276.414484)
		)
		(stroke
			(width 0)
			(type solid)
		)
		(fill yes)
		(layer "In13.Cu")
		(net "M_B_CPU1_SB_DQS_DN<0>")
	)
	(gr_poly
		(pts
			(xy 83.511136 -275.098256) (xy 83.41106 -274.99818) (xy 83.310984 -275.098256) (xy 83.310984 -275.142706)
			(xy 83.511136 -275.142706)
		)
		(stroke
			(width 0)
			(type solid)
		)
		(fill yes)
		(layer "In13.Cu")
		(net "M_B_CPU1_SB_DQ<1>")
	)
	(gr_poly
		(pts
			(xy 83.511136 -274.694396) (xy 83.511136 -274.649946) (xy 83.310984 -274.649946) (xy 83.310984 -274.694396)
			(xy 83.41106 -274.794472)
		)
		(stroke
			(width 0)
			(type solid)
		)
		(fill yes)
		(layer "In13.Cu")
		(net "M_B_CPU1_SB_DQ<2>")
	)
	(gr_poly
		(pts
			(xy 83.511136 -273.478244) (xy 83.41106 -273.378168) (xy 83.310984 -273.478244) (xy 83.310984 -273.522694)
			(xy 83.511136 -273.522694)
		)
		(stroke
			(width 0)
			(type solid)
		)
		(fill yes)
		(layer "In13.Cu")
		(net "M_B_CPU1_SB_CB<1>")
	)
	(gr_poly
		(pts
			(xy 83.511136 -273.074384) (xy 83.511136 -273.029934) (xy 83.310984 -273.029934) (xy 83.310984 -273.074384)
			(xy 83.41106 -273.17446)
		)
		(stroke
			(width 0)
			(type solid)
		)
		(fill yes)
		(layer "In13.Cu")
		(net "M_B_CPU1_SB_CB<2>")
	)
	(gr_poly
		(pts
			(xy 83.511136 -271.857978) (xy 83.41106 -271.758156) (xy 83.310984 -271.857978) (xy 83.310984 -271.90573)
			(xy 83.511136 -271.90573)
		)
		(stroke
			(width 0)
			(type solid)
		)
		(fill yes)
		(layer "In13.Cu")
		(net "M_B_CPU1_SB_DQS_DN<4>")
	)
	(gr_poly
		(pts
			(xy 83.511136 -271.454626) (xy 83.511136 -271.406874) (xy 83.310984 -271.406874) (xy 83.310984 -271.454626)
			(xy 83.41106 -271.554448)
		)
		(stroke
			(width 0)
			(type solid)
		)
		(fill yes)
		(layer "In13.Cu")
		(net "M_B_CPU1_SB_DQS_DN<9>")
	)
	(gr_poly
		(pts
			(xy 83.511136 -270.23822) (xy 83.41106 -270.138144) (xy 83.310984 -270.23822) (xy 83.310984 -270.28267)
			(xy 83.511136 -270.28267)
		)
		(stroke
			(width 0)
			(type solid)
		)
		(fill yes)
		(layer "In13.Cu")
		(net "M_B_CPU1_SB_CB<5>")
	)
	(gr_poly
		(pts
			(xy 83.511136 -269.83436) (xy 83.511136 -269.78991) (xy 83.310984 -269.78991) (xy 83.310984 -269.83436)
			(xy 83.41106 -269.934436)
		)
		(stroke
			(width 0)
			(type solid)
		)
		(fill yes)
		(layer "In13.Cu")
		(net "M_B_CPU1_SB_CB<6>")
	)
	(gr_poly
		(pts
			(xy 83.511136 -266.594336) (xy 83.511136 -266.549886) (xy 83.310984 -266.549886) (xy 83.310984 -266.594336)
			(xy 83.41106 -266.694412)
		)
		(stroke
			(width 0)
			(type solid)
		)
		(fill yes)
		(layer "In13.Cu")
		(net "M_B_CPU1_SB_CS_N<1>")
	)
	(gr_poly
		(pts
			(xy 83.511136 -264.974324) (xy 83.511136 -264.929874) (xy 83.310984 -264.929874) (xy 83.310984 -264.974324)
			(xy 83.41106 -265.0744)
		)
		(stroke
			(width 0)
			(type solid)
		)
		(fill yes)
		(layer "In13.Cu")
		(net "M_B_CPU1_SB_PAR")
	)
	(gr_poly
		(pts
			(xy 83.511136 -263.758172) (xy 83.41106 -263.658096) (xy 83.310984 -263.758172) (xy 83.310984 -263.802622)
			(xy 83.511136 -263.802622)
		)
		(stroke
			(width 0)
			(type solid)
		)
		(fill yes)
		(layer "In13.Cu")
		(net "M_B_CPU1_SB_CA<4>")
	)
	(gr_poly
		(pts
			(xy 83.511136 -263.354312) (xy 83.511136 -263.309862) (xy 83.310984 -263.309862) (xy 83.310984 -263.354312)
			(xy 83.41106 -263.454388)
		)
		(stroke
			(width 0)
			(type solid)
		)
		(fill yes)
		(layer "In13.Cu")
		(net "M_B_CPU1_SB_CA<3>")
	)
	(gr_poly
		(pts
			(xy 83.511136 -262.13816) (xy 83.41106 -262.038084) (xy 83.310984 -262.13816) (xy 83.310984 -262.18261)
			(xy 83.511136 -262.18261)
		)
		(stroke
			(width 0)
			(type solid)
		)
		(fill yes)
		(layer "In13.Cu")
		(net "M_B_CPU1_SB_CA<0>")
	)
	(gr_poly
		(pts
			(xy 83.681062 -256.432812) (xy 83.681062 -256.38506) (xy 83.48091 -256.38506) (xy 83.48091 -256.432812)
			(xy 83.580986 -256.532634)
		)
		(stroke
			(width 0)
			(type solid)
		)
		(fill yes)
		(layer "In13.Cu")
		(net "M_B_CPU1_CLK_DN<0>")
	)
	(gr_poly
		(pts
			(xy 83.681062 -255.216406) (xy 83.580986 -255.11633) (xy 83.48091 -255.216406) (xy 83.48091 -255.260856)
			(xy 83.681062 -255.260856)
		)
		(stroke
			(width 0)
			(type solid)
		)
		(fill yes)
		(layer "In13.Cu")
		(net "M_B_CPU1_SA_CA<6>")
	)
	(gr_poly
		(pts
			(xy 83.681062 -254.812546) (xy 83.681062 -254.768096) (xy 83.48091 -254.768096) (xy 83.48091 -254.812546)
			(xy 83.580986 -254.912622)
		)
		(stroke
			(width 0)
			(type solid)
		)
		(fill yes)
		(layer "In13.Cu")
		(net "M_B_CPU1_SA_CA<5>")
	)
	(gr_poly
		(pts
			(xy 83.681062 -253.596394) (xy 83.580986 -253.496318) (xy 83.48091 -253.596394) (xy 83.48091 -253.640844)
			(xy 83.681062 -253.640844)
		)
		(stroke
			(width 0)
			(type solid)
		)
		(fill yes)
		(layer "In13.Cu")
		(net "M_B_CPU1_SA_CA<2>")
	)
	(gr_poly
		(pts
			(xy 83.681062 -253.192534) (xy 83.681062 -253.148084) (xy 83.48091 -253.148084) (xy 83.48091 -253.192534)
			(xy 83.580986 -253.29261)
		)
		(stroke
			(width 0)
			(type solid)
		)
		(fill yes)
		(layer "In13.Cu")
		(net "M_B_CPU1_SA_CA<1>")
	)
	(gr_poly
		(pts
			(xy 83.681062 -251.572522) (xy 83.681062 -251.528072) (xy 83.48091 -251.528072) (xy 83.48091 -251.572522)
			(xy 83.580986 -251.672598)
		)
		(stroke
			(width 0)
			(type solid)
		)
		(fill yes)
		(layer "In13.Cu")
		(net "M_B_CPU1_SA_CS_N<0>")
	)
	(gr_poly
		(pts
			(xy 83.681062 -250.35637) (xy 83.580986 -250.256294) (xy 83.48091 -250.35637) (xy 83.48091 -250.40082)
			(xy 83.681062 -250.40082)
		)
		(stroke
			(width 0)
			(type solid)
		)
		(fill yes)
		(layer "In13.Cu")
		(net "M_B_CPU1_ALERT_R_N")
	)
	(gr_poly
		(pts
			(xy 83.681062 -248.736358) (xy 83.580986 -248.636282) (xy 83.48091 -248.736358) (xy 83.48091 -248.780808)
			(xy 83.681062 -248.780808)
		)
		(stroke
			(width 0)
			(type solid)
		)
		(fill yes)
		(layer "In13.Cu")
		(net "M_B_CPU1_SA_CB<5>")
	)
	(gr_poly
		(pts
			(xy 83.681062 -248.332498) (xy 83.681062 -248.288048) (xy 83.48091 -248.288048) (xy 83.48091 -248.332498)
			(xy 83.580986 -248.432574)
		)
		(stroke
			(width 0)
			(type solid)
		)
		(fill yes)
		(layer "In13.Cu")
		(net "M_B_CPU1_SA_CB<6>")
	)
	(gr_poly
		(pts
			(xy 83.681062 -247.116092) (xy 83.580986 -247.01627) (xy 83.48091 -247.116092) (xy 83.48091 -247.163844)
			(xy 83.681062 -247.163844)
		)
		(stroke
			(width 0)
			(type solid)
		)
		(fill yes)
		(layer "In13.Cu")
		(net "M_B_CPU1_SA_DQS_DN<9>")
	)
	(gr_poly
		(pts
			(xy 83.681062 -246.71274) (xy 83.681062 -246.664988) (xy 83.48091 -246.664988) (xy 83.48091 -246.71274)
			(xy 83.580986 -246.812562)
		)
		(stroke
			(width 0)
			(type solid)
		)
		(fill yes)
		(layer "In13.Cu")
		(net "M_B_CPU1_SA_DQS_DN<4>")
	)
	(gr_poly
		(pts
			(xy 83.681062 -245.496334) (xy 83.580986 -245.396258) (xy 83.48091 -245.496334) (xy 83.48091 -245.540784)
			(xy 83.681062 -245.540784)
		)
		(stroke
			(width 0)
			(type solid)
		)
		(fill yes)
		(layer "In13.Cu")
		(net "M_B_CPU1_SA_CB<1>")
	)
	(gr_poly
		(pts
			(xy 83.681062 -245.092474) (xy 83.681062 -245.048024) (xy 83.48091 -245.048024) (xy 83.48091 -245.092474)
			(xy 83.580986 -245.19255)
		)
		(stroke
			(width 0)
			(type solid)
		)
		(fill yes)
		(layer "In13.Cu")
		(net "M_B_CPU1_SA_CB<2>")
	)
	(gr_poly
		(pts
			(xy 83.681062 -243.876322) (xy 83.580986 -243.776246) (xy 83.48091 -243.876322) (xy 83.48091 -243.920772)
			(xy 83.681062 -243.920772)
		)
		(stroke
			(width 0)
			(type solid)
		)
		(fill yes)
		(layer "In13.Cu")
		(net "M_B_CPU1_SA_DQ<29>")
	)
	(gr_poly
		(pts
			(xy 83.681062 -243.472462) (xy 83.681062 -243.428012) (xy 83.48091 -243.428012) (xy 83.48091 -243.472462)
			(xy 83.580986 -243.572538)
		)
		(stroke
			(width 0)
			(type solid)
		)
		(fill yes)
		(layer "In13.Cu")
		(net "M_B_CPU1_SA_DQ<30>")
	)
	(gr_poly
		(pts
			(xy 83.681062 -242.256056) (xy 83.580986 -242.156234) (xy 83.48091 -242.256056) (xy 83.48091 -242.303808)
			(xy 83.681062 -242.303808)
		)
		(stroke
			(width 0)
			(type solid)
		)
		(fill yes)
		(layer "In13.Cu")
		(net "M_B_CPU1_SA_DQS_DN<8>")
	)
	(gr_poly
		(pts
			(xy 83.681062 -241.852704) (xy 83.681062 -241.804952) (xy 83.48091 -241.804952) (xy 83.48091 -241.852704)
			(xy 83.580986 -241.952526)
		)
		(stroke
			(width 0)
			(type solid)
		)
		(fill yes)
		(layer "In13.Cu")
		(net "M_B_CPU1_SA_DQS_DN<3>")
	)
	(gr_poly
		(pts
			(xy 83.681062 -240.636298) (xy 83.580986 -240.536222) (xy 83.48091 -240.636298) (xy 83.48091 -240.680748)
			(xy 83.681062 -240.680748)
		)
		(stroke
			(width 0)
			(type solid)
		)
		(fill yes)
		(layer "In13.Cu")
		(net "M_B_CPU1_SA_DQ<25>")
	)
	(gr_poly
		(pts
			(xy 83.681062 -240.232438) (xy 83.681062 -240.187988) (xy 83.48091 -240.187988) (xy 83.48091 -240.232438)
			(xy 83.580986 -240.332514)
		)
		(stroke
			(width 0)
			(type solid)
		)
		(fill yes)
		(layer "In13.Cu")
		(net "M_B_CPU1_SA_DQ<26>")
	)
	(gr_poly
		(pts
			(xy 83.681062 -239.016286) (xy 83.580986 -238.91621) (xy 83.48091 -239.016286) (xy 83.48091 -239.060736)
			(xy 83.681062 -239.060736)
		)
		(stroke
			(width 0)
			(type solid)
		)
		(fill yes)
		(layer "In13.Cu")
		(net "M_B_CPU1_SA_DQ<21>")
	)
	(gr_poly
		(pts
			(xy 83.681062 -238.612426) (xy 83.681062 -238.567976) (xy 83.48091 -238.567976) (xy 83.48091 -238.612426)
			(xy 83.580986 -238.712502)
		)
		(stroke
			(width 0)
			(type solid)
		)
		(fill yes)
		(layer "In13.Cu")
		(net "M_B_CPU1_SA_DQ<22>")
	)
	(gr_poly
		(pts
			(xy 83.681062 -237.39602) (xy 83.580986 -237.296198) (xy 83.48091 -237.39602) (xy 83.48091 -237.443772)
			(xy 83.681062 -237.443772)
		)
		(stroke
			(width 0)
			(type solid)
		)
		(fill yes)
		(layer "In13.Cu")
		(net "M_B_CPU1_SA_DQS_DN<7>")
	)
	(gr_poly
		(pts
			(xy 83.681062 -236.992668) (xy 83.681062 -236.944916) (xy 83.48091 -236.944916) (xy 83.48091 -236.992668)
			(xy 83.580986 -237.09249)
		)
		(stroke
			(width 0)
			(type solid)
		)
		(fill yes)
		(layer "In13.Cu")
		(net "M_B_CPU1_SA_DQS_DN<2>")
	)
	(gr_poly
		(pts
			(xy 83.681062 -235.776262) (xy 83.580986 -235.676186) (xy 83.48091 -235.776262) (xy 83.48091 -235.820712)
			(xy 83.681062 -235.820712)
		)
		(stroke
			(width 0)
			(type solid)
		)
		(fill yes)
		(layer "In13.Cu")
		(net "M_B_CPU1_SA_DQ<17>")
	)
	(gr_poly
		(pts
			(xy 83.681062 -235.372402) (xy 83.681062 -235.327952) (xy 83.48091 -235.327952) (xy 83.48091 -235.372402)
			(xy 83.580986 -235.472478)
		)
		(stroke
			(width 0)
			(type solid)
		)
		(fill yes)
		(layer "In13.Cu")
		(net "M_B_CPU1_SA_DQ<18>")
	)
	(gr_poly
		(pts
			(xy 83.681062 -234.15625) (xy 83.580986 -234.056174) (xy 83.48091 -234.15625) (xy 83.48091 -234.2007)
			(xy 83.681062 -234.2007)
		)
		(stroke
			(width 0)
			(type solid)
		)
		(fill yes)
		(layer "In13.Cu")
		(net "M_B_CPU1_SA_DQ<13>")
	)
	(gr_poly
		(pts
			(xy 83.681062 -233.75239) (xy 83.681062 -233.70794) (xy 83.48091 -233.70794) (xy 83.48091 -233.75239)
			(xy 83.580986 -233.852466)
		)
		(stroke
			(width 0)
			(type solid)
		)
		(fill yes)
		(layer "In13.Cu")
		(net "M_B_CPU1_SA_DQ<14>")
	)
	(gr_poly
		(pts
			(xy 83.681062 -232.535984) (xy 83.580986 -232.436162) (xy 83.48091 -232.535984) (xy 83.48091 -232.583736)
			(xy 83.681062 -232.583736)
		)
		(stroke
			(width 0)
			(type solid)
		)
		(fill yes)
		(layer "In13.Cu")
		(net "M_B_CPU1_SA_DQS_DN<6>")
	)
	(gr_poly
		(pts
			(xy 83.681062 -232.132632) (xy 83.681062 -232.08488) (xy 83.48091 -232.08488) (xy 83.48091 -232.132632)
			(xy 83.580986 -232.232454)
		)
		(stroke
			(width 0)
			(type solid)
		)
		(fill yes)
		(layer "In13.Cu")
		(net "M_B_CPU1_SA_DQS_DN<1>")
	)
	(gr_poly
		(pts
			(xy 83.681062 -230.916226) (xy 83.580986 -230.81615) (xy 83.48091 -230.916226) (xy 83.48091 -230.960676)
			(xy 83.681062 -230.960676)
		)
		(stroke
			(width 0)
			(type solid)
		)
		(fill yes)
		(layer "In13.Cu")
		(net "M_B_CPU1_SA_DQ<9>")
	)
	(gr_poly
		(pts
			(xy 83.681062 -230.51262) (xy 83.681062 -230.46817) (xy 83.48091 -230.46817) (xy 83.48091 -230.51262)
			(xy 83.580986 -230.612696)
		)
		(stroke
			(width 0)
			(type solid)
		)
		(fill yes)
		(layer "In13.Cu")
		(net "M_B_CPU1_SA_DQ<10>")
	)
	(gr_poly
		(pts
			(xy 83.681062 -229.296214) (xy 83.580986 -229.196138) (xy 83.48091 -229.296214) (xy 83.48091 -229.340664)
			(xy 83.681062 -229.340664)
		)
		(stroke
			(width 0)
			(type solid)
		)
		(fill yes)
		(layer "In13.Cu")
		(net "M_B_CPU1_SA_DQ<5>")
	)
	(gr_poly
		(pts
			(xy 83.681062 -228.892608) (xy 83.681062 -228.848158) (xy 83.48091 -228.848158) (xy 83.48091 -228.892608)
			(xy 83.580986 -228.992684)
		)
		(stroke
			(width 0)
			(type solid)
		)
		(fill yes)
		(layer "In13.Cu")
		(net "M_B_CPU1_SA_DQ<6>")
	)
	(gr_poly
		(pts
			(xy 83.681062 -227.27285) (xy 83.681062 -227.225098) (xy 83.48091 -227.225098) (xy 83.48091 -227.27285)
			(xy 83.580986 -227.372672)
		)
		(stroke
			(width 0)
			(type solid)
		)
		(fill yes)
		(layer "In13.Cu")
		(net "M_B_CPU1_SA_DQS_DN<0>")
	)
	(gr_poly
		(pts
			(xy 83.681062 -226.056444) (xy 83.580986 -225.956368) (xy 83.48091 -226.056444) (xy 83.48091 -226.100894)
			(xy 83.681062 -226.100894)
		)
		(stroke
			(width 0)
			(type solid)
		)
		(fill yes)
		(layer "In13.Cu")
		(net "M_B_CPU1_SA_DQ<1>")
	)
	(gr_poly
		(pts
			(xy 83.681062 -225.652584) (xy 83.681062 -225.608134) (xy 83.48091 -225.608134) (xy 83.48091 -225.652584)
			(xy 83.580986 -225.75266)
		)
		(stroke
			(width 0)
			(type solid)
		)
		(fill yes)
		(layer "In13.Cu")
		(net "M_B_CPU1_SA_DQ<2>")
	)
	(gr_poly
		(pts
			(xy 83.687158 -227.67671) (xy 83.587082 -227.576634) (xy 83.487006 -227.67671) (xy 83.487006 -227.724208)
			(xy 83.687158 -227.724208)
		)
		(stroke
			(width 0)
			(type solid)
		)
		(fill yes)
		(layer "In13.Cu")
		(net "M_B_CPU1_SA_DQS_DN<5>")
	)
	(gr_poly
		(pts
			(xy 83.981036 -293.32428) (xy 83.981036 -293.27983) (xy 83.780884 -293.27983) (xy 83.780884 -293.32428)
			(xy 83.88096 -293.424356)
		)
		(stroke
			(width 0)
			(type solid)
		)
		(fill yes)
		(layer "In13.Cu")
		(net "M_B_CPU1_SB_DQ<31>")
	)
	(gr_poly
		(pts
			(xy 83.981036 -292.108128) (xy 83.88096 -292.008052) (xy 83.780884 -292.108128) (xy 83.780884 -292.152578)
			(xy 83.981036 -292.152578)
		)
		(stroke
			(width 0)
			(type solid)
		)
		(fill yes)
		(layer "In13.Cu")
		(net "M_B_CPU1_SB_DQ<28>")
	)
	(gr_poly
		(pts
			(xy 83.981036 -291.704522) (xy 83.981036 -291.65677) (xy 83.780884 -291.65677) (xy 83.780884 -291.704522)
			(xy 83.88096 -291.804344)
		)
		(stroke
			(width 0)
			(type solid)
		)
		(fill yes)
		(layer "In13.Cu")
		(net "M_B_CPU1_SB_DQS_DP<8>")
	)
	(gr_poly
		(pts
			(xy 83.981036 -290.487862) (xy 83.88096 -290.38804) (xy 83.780884 -290.487862) (xy 83.780884 -290.535614)
			(xy 83.981036 -290.535614)
		)
		(stroke
			(width 0)
			(type solid)
		)
		(fill yes)
		(layer "In13.Cu")
		(net "M_B_CPU1_SB_DQS_DP<3>")
	)
	(gr_poly
		(pts
			(xy 83.981036 -290.084256) (xy 83.981036 -290.039806) (xy 83.780884 -290.039806) (xy 83.780884 -290.084256)
			(xy 83.88096 -290.184332)
		)
		(stroke
			(width 0)
			(type solid)
		)
		(fill yes)
		(layer "In13.Cu")
		(net "M_B_CPU1_SB_DQ<27>")
	)
	(gr_poly
		(pts
			(xy 83.981036 -288.868104) (xy 83.88096 -288.768028) (xy 83.780884 -288.868104) (xy 83.780884 -288.912554)
			(xy 83.981036 -288.912554)
		)
		(stroke
			(width 0)
			(type solid)
		)
		(fill yes)
		(layer "In13.Cu")
		(net "M_B_CPU1_SB_DQ<24>")
	)
	(gr_poly
		(pts
			(xy 83.981036 -288.464498) (xy 83.981036 -288.420048) (xy 83.780884 -288.420048) (xy 83.780884 -288.464498)
			(xy 83.88096 -288.564574)
		)
		(stroke
			(width 0)
			(type solid)
		)
		(fill yes)
		(layer "In13.Cu")
		(net "M_B_CPU1_SB_DQ<23>")
	)
	(gr_poly
		(pts
			(xy 83.981036 -287.248092) (xy 83.88096 -287.148016) (xy 83.780884 -287.248092) (xy 83.780884 -287.292542)
			(xy 83.981036 -287.292542)
		)
		(stroke
			(width 0)
			(type solid)
		)
		(fill yes)
		(layer "In13.Cu")
		(net "M_B_CPU1_SB_DQ<20>")
	)
	(gr_poly
		(pts
			(xy 83.981036 -286.844486) (xy 83.981036 -286.796734) (xy 83.780884 -286.796734) (xy 83.780884 -286.844486)
			(xy 83.88096 -286.944562)
		)
		(stroke
			(width 0)
			(type solid)
		)
		(fill yes)
		(layer "In13.Cu")
		(net "M_B_CPU1_SB_DQS_DP<7>")
	)
	(gr_poly
		(pts
			(xy 83.981036 -285.62808) (xy 83.88096 -285.528258) (xy 83.780884 -285.62808) (xy 83.780884 -285.675832)
			(xy 83.981036 -285.675832)
		)
		(stroke
			(width 0)
			(type solid)
		)
		(fill yes)
		(layer "In13.Cu")
		(net "M_B_CPU1_SB_DQS_DP<2>")
	)
	(gr_poly
		(pts
			(xy 83.981036 -285.224474) (xy 83.981036 -285.180024) (xy 83.780884 -285.180024) (xy 83.780884 -285.224474)
			(xy 83.88096 -285.32455)
		)
		(stroke
			(width 0)
			(type solid)
		)
		(fill yes)
		(layer "In13.Cu")
		(net "M_B_CPU1_SB_DQ<19>")
	)
	(gr_poly
		(pts
			(xy 83.981036 -284.008322) (xy 83.88096 -283.908246) (xy 83.780884 -284.008322) (xy 83.780884 -284.052772)
			(xy 83.981036 -284.052772)
		)
		(stroke
			(width 0)
			(type solid)
		)
		(fill yes)
		(layer "In13.Cu")
		(net "M_B_CPU1_SB_DQ<16>")
	)
	(gr_poly
		(pts
			(xy 83.981036 -283.604462) (xy 83.981036 -283.560012) (xy 83.780884 -283.560012) (xy 83.780884 -283.604462)
			(xy 83.88096 -283.704538)
		)
		(stroke
			(width 0)
			(type solid)
		)
		(fill yes)
		(layer "In13.Cu")
		(net "M_B_CPU1_SB_DQ<15>")
	)
	(gr_poly
		(pts
			(xy 83.981036 -282.38831) (xy 83.88096 -282.288234) (xy 83.780884 -282.38831) (xy 83.780884 -282.43276)
			(xy 83.981036 -282.43276)
		)
		(stroke
			(width 0)
			(type solid)
		)
		(fill yes)
		(layer "In13.Cu")
		(net "M_B_CPU1_SB_DQ<12>")
	)
	(gr_poly
		(pts
			(xy 83.981036 -281.984704) (xy 83.981036 -281.936952) (xy 83.780884 -281.936952) (xy 83.780884 -281.984704)
			(xy 83.88096 -282.084526)
		)
		(stroke
			(width 0)
			(type solid)
		)
		(fill yes)
		(layer "In13.Cu")
		(net "M_B_CPU1_SB_DQS_DP<6>")
	)
	(gr_poly
		(pts
			(xy 83.981036 -280.768044) (xy 83.88096 -280.668222) (xy 83.780884 -280.768044) (xy 83.780884 -280.815796)
			(xy 83.981036 -280.815796)
		)
		(stroke
			(width 0)
			(type solid)
		)
		(fill yes)
		(layer "In13.Cu")
		(net "M_B_CPU1_SB_DQS_DP<1>")
	)
	(gr_poly
		(pts
			(xy 83.981036 -280.364438) (xy 83.981036 -280.319988) (xy 83.780884 -280.319988) (xy 83.780884 -280.364438)
			(xy 83.88096 -280.464514)
		)
		(stroke
			(width 0)
			(type solid)
		)
		(fill yes)
		(layer "In13.Cu")
		(net "M_B_CPU1_SB_DQ<11>")
	)
	(gr_poly
		(pts
			(xy 83.981036 -279.148286) (xy 83.88096 -279.04821) (xy 83.780884 -279.148286) (xy 83.780884 -279.192736)
			(xy 83.981036 -279.192736)
		)
		(stroke
			(width 0)
			(type solid)
		)
		(fill yes)
		(layer "In13.Cu")
		(net "M_B_CPU1_SB_DQ<8>")
	)
	(gr_poly
		(pts
			(xy 83.981036 -278.744426) (xy 83.981036 -278.699976) (xy 83.780884 -278.699976) (xy 83.780884 -278.744426)
			(xy 83.88096 -278.844502)
		)
		(stroke
			(width 0)
			(type solid)
		)
		(fill yes)
		(layer "In13.Cu")
		(net "M_B_CPU1_SB_DQ<7>")
	)
	(gr_poly
		(pts
			(xy 83.981036 -277.528274) (xy 83.88096 -277.428198) (xy 83.780884 -277.528274) (xy 83.780884 -277.572724)
			(xy 83.981036 -277.572724)
		)
		(stroke
			(width 0)
			(type solid)
		)
		(fill yes)
		(layer "In13.Cu")
		(net "M_B_CPU1_SB_DQ<4>")
	)
	(gr_poly
		(pts
			(xy 83.981036 -275.504402) (xy 83.981036 -275.459952) (xy 83.780884 -275.459952) (xy 83.780884 -275.504402)
			(xy 83.88096 -275.604478)
		)
		(stroke
			(width 0)
			(type solid)
		)
		(fill yes)
		(layer "In13.Cu")
		(net "M_B_CPU1_SB_DQ<3>")
	)
	(gr_poly
		(pts
			(xy 83.981036 -274.28825) (xy 83.88096 -274.188174) (xy 83.780884 -274.28825) (xy 83.780884 -274.3327)
			(xy 83.981036 -274.3327)
		)
		(stroke
			(width 0)
			(type solid)
		)
		(fill yes)
		(layer "In13.Cu")
		(net "M_B_CPU1_SB_DQ<0>")
	)
	(gr_poly
		(pts
			(xy 83.981036 -273.88439) (xy 83.981036 -273.83994) (xy 83.780884 -273.83994) (xy 83.780884 -273.88439)
			(xy 83.88096 -273.984466)
		)
		(stroke
			(width 0)
			(type solid)
		)
		(fill yes)
		(layer "In13.Cu")
		(net "M_B_CPU1_SB_CB<3>")
	)
	(gr_poly
		(pts
			(xy 83.981036 -272.668238) (xy 83.88096 -272.568162) (xy 83.780884 -272.668238) (xy 83.780884 -272.712688)
			(xy 83.981036 -272.712688)
		)
		(stroke
			(width 0)
			(type solid)
		)
		(fill yes)
		(layer "In13.Cu")
		(net "M_B_CPU1_SB_CB<0>")
	)
	(gr_poly
		(pts
			(xy 83.981036 -272.264632) (xy 83.981036 -272.21688) (xy 83.780884 -272.21688) (xy 83.780884 -272.264632)
			(xy 83.88096 -272.364454)
		)
		(stroke
			(width 0)
			(type solid)
		)
		(fill yes)
		(layer "In13.Cu")
		(net "M_B_CPU1_SB_DQS_DP<4>")
	)
	(gr_poly
		(pts
			(xy 83.981036 -271.047972) (xy 83.88096 -270.94815) (xy 83.780884 -271.047972) (xy 83.780884 -271.095724)
			(xy 83.981036 -271.095724)
		)
		(stroke
			(width 0)
			(type solid)
		)
		(fill yes)
		(layer "In13.Cu")
		(net "M_B_CPU1_SB_DQS_DP<9>")
	)
	(gr_poly
		(pts
			(xy 83.981036 -270.644366) (xy 83.981036 -270.599916) (xy 83.780884 -270.599916) (xy 83.780884 -270.644366)
			(xy 83.88096 -270.744442)
		)
		(stroke
			(width 0)
			(type solid)
		)
		(fill yes)
		(layer "In13.Cu")
		(net "M_B_CPU1_SB_CB<7>")
	)
	(gr_poly
		(pts
			(xy 83.981036 -269.428214) (xy 83.88096 -269.328138) (xy 83.780884 -269.428214) (xy 83.780884 -269.472664)
			(xy 83.981036 -269.472664)
		)
		(stroke
			(width 0)
			(type solid)
		)
		(fill yes)
		(layer "In13.Cu")
		(net "M_B_CPU1_SB_CB<4>")
	)
	(gr_poly
		(pts
			(xy 83.981036 -265.78433) (xy 83.981036 -265.73988) (xy 83.780884 -265.73988) (xy 83.780884 -265.78433)
			(xy 83.88096 -265.884406)
		)
		(stroke
			(width 0)
			(type solid)
		)
		(fill yes)
		(layer "In13.Cu")
		(net "M_B_CPU1_SB_CS_N<0>")
	)
	(gr_poly
		(pts
			(xy 83.981036 -264.568178) (xy 83.88096 -264.468102) (xy 83.780884 -264.568178) (xy 83.780884 -264.612628)
			(xy 83.981036 -264.612628)
		)
		(stroke
			(width 0)
			(type solid)
		)
		(fill yes)
		(layer "In13.Cu")
		(net "M_B_CPU1_SB_CA<6>")
	)
	(gr_poly
		(pts
			(xy 83.981036 -264.164318) (xy 83.981036 -264.119868) (xy 83.780884 -264.119868) (xy 83.780884 -264.164318)
			(xy 83.88096 -264.264394)
		)
		(stroke
			(width 0)
			(type solid)
		)
		(fill yes)
		(layer "In13.Cu")
		(net "M_B_CPU1_SB_CA<5>")
	)
	(gr_poly
		(pts
			(xy 83.981036 -262.948166) (xy 83.88096 -262.84809) (xy 83.780884 -262.948166) (xy 83.780884 -262.992616)
			(xy 83.981036 -262.992616)
		)
		(stroke
			(width 0)
			(type solid)
		)
		(fill yes)
		(layer "In13.Cu")
		(net "M_B_CPU1_SB_CA<2>")
	)
	(gr_poly
		(pts
			(xy 83.981036 -262.544306) (xy 83.981036 -262.499856) (xy 83.780884 -262.499856) (xy 83.780884 -262.544306)
			(xy 83.88096 -262.644382)
		)
		(stroke
			(width 0)
			(type solid)
		)
		(fill yes)
		(layer "In13.Cu")
		(net "M_B_CPU1_SB_CA<1>")
	)
	(gr_poly
		(pts
			(xy 83.987132 -267.801852) (xy 83.88731 -267.701776) (xy 83.787234 -267.801852) (xy 83.787234 -267.846302)
			(xy 83.987132 -267.846302)
		)
		(stroke
			(width 0)
			(type solid)
		)
		(fill yes)
		(layer "In13.Cu")
		(net "M_B_CPU1_SB_RSP<0>")
	)
	(gr_poly
		(pts
			(xy 83.988402 -277.124414) (xy 83.988402 -277.076916) (xy 83.78825 -277.076916) (xy 83.78825 -277.124414)
			(xy 83.888326 -277.22449)
		)
		(stroke
			(width 0)
			(type solid)
		)
		(fill yes)
		(layer "In13.Cu")
		(net "M_B_CPU1_SB_DQS_DP<5>")
	)
	(gr_poly
		(pts
			(xy 83.988402 -275.908262) (xy 83.888326 -275.808186) (xy 83.78825 -275.908262) (xy 83.78825 -275.95576)
			(xy 83.988402 -275.95576)
		)
		(stroke
			(width 0)
			(type solid)
		)
		(fill yes)
		(layer "In13.Cu")
		(net "M_B_CPU1_SB_DQS_DP<0>")
	)
	(gr_poly
		(pts
			(xy 84.151216 -256.026158) (xy 84.05114 -255.926336) (xy 83.951064 -256.026158) (xy 83.951064 -256.07391)
			(xy 84.151216 -256.07391)
		)
		(stroke
			(width 0)
			(type solid)
		)
		(fill yes)
		(layer "In13.Cu")
		(net "M_B_CPU1_CLK_DP<0>")
	)
	(gr_poly
		(pts
			(xy 84.151216 -255.622552) (xy 84.151216 -255.578102) (xy 83.951064 -255.578102) (xy 83.951064 -255.622552)
			(xy 84.05114 -255.722628)
		)
		(stroke
			(width 0)
			(type solid)
		)
		(fill yes)
		(layer "In13.Cu")
		(net "M_B_CPU1_SA_PAR")
	)
	(gr_poly
		(pts
			(xy 84.151216 -254.4064) (xy 84.05114 -254.306324) (xy 83.951064 -254.4064) (xy 83.951064 -254.45085)
			(xy 84.151216 -254.45085)
		)
		(stroke
			(width 0)
			(type solid)
		)
		(fill yes)
		(layer "In13.Cu")
		(net "M_B_CPU1_SA_CA<4>")
	)
	(gr_poly
		(pts
			(xy 84.151216 -254.00254) (xy 84.151216 -253.95809) (xy 83.951064 -253.95809) (xy 83.951064 -254.00254)
			(xy 84.05114 -254.102616)
		)
		(stroke
			(width 0)
			(type solid)
		)
		(fill yes)
		(layer "In13.Cu")
		(net "M_B_CPU1_SA_CA<3>")
	)
	(gr_poly
		(pts
			(xy 84.151216 -252.786388) (xy 84.05114 -252.686312) (xy 83.951064 -252.786388) (xy 83.951064 -252.830838)
			(xy 84.151216 -252.830838)
		)
		(stroke
			(width 0)
			(type solid)
		)
		(fill yes)
		(layer "In13.Cu")
		(net "M_B_CPU1_SA_CA<0>")
	)
	(gr_poly
		(pts
			(xy 84.151216 -252.382528) (xy 84.151216 -252.338078) (xy 83.951064 -252.338078) (xy 83.951064 -252.382528)
			(xy 84.05114 -252.482604)
		)
		(stroke
			(width 0)
			(type solid)
		)
		(fill yes)
		(layer "In13.Cu")
		(net "M_B_CPU1_SA_CS_N<1>")
	)
	(gr_poly
		(pts
			(xy 84.151216 -250.762516) (xy 84.151216 -250.718066) (xy 83.951064 -250.718066) (xy 83.951064 -250.762516)
			(xy 84.05114 -250.862592)
		)
		(stroke
			(width 0)
			(type solid)
		)
		(fill yes)
		(layer "In13.Cu")
		(net "M_B_CPU1_RESET_N")
	)
	(gr_poly
		(pts
			(xy 84.151216 -249.142504) (xy 84.151216 -249.098054) (xy 83.951064 -249.098054) (xy 83.951064 -249.142504)
			(xy 84.05114 -249.24258)
		)
		(stroke
			(width 0)
			(type solid)
		)
		(fill yes)
		(layer "In13.Cu")
		(net "M_B_CPU1_SA_CB<7>")
	)
	(gr_poly
		(pts
			(xy 84.151216 -247.926352) (xy 84.05114 -247.826276) (xy 83.951064 -247.926352) (xy 83.951064 -247.970802)
			(xy 84.151216 -247.970802)
		)
		(stroke
			(width 0)
			(type solid)
		)
		(fill yes)
		(layer "In13.Cu")
		(net "M_B_CPU1_SA_CB<4>")
	)
	(gr_poly
		(pts
			(xy 84.151216 -247.522746) (xy 84.151216 -247.474994) (xy 83.951064 -247.474994) (xy 83.951064 -247.522746)
			(xy 84.05114 -247.622568)
		)
		(stroke
			(width 0)
			(type solid)
		)
		(fill yes)
		(layer "In13.Cu")
		(net "M_B_CPU1_SA_DQS_DP<9>")
	)
	(gr_poly
		(pts
			(xy 84.151216 -246.306086) (xy 84.05114 -246.206264) (xy 83.951064 -246.306086) (xy 83.951064 -246.353838)
			(xy 84.151216 -246.353838)
		)
		(stroke
			(width 0)
			(type solid)
		)
		(fill yes)
		(layer "In13.Cu")
		(net "M_B_CPU1_SA_DQS_DP<4>")
	)
	(gr_poly
		(pts
			(xy 84.151216 -245.90248) (xy 84.151216 -245.85803) (xy 83.951064 -245.85803) (xy 83.951064 -245.90248)
			(xy 84.05114 -246.002556)
		)
		(stroke
			(width 0)
			(type solid)
		)
		(fill yes)
		(layer "In13.Cu")
		(net "M_B_CPU1_SA_CB<3>")
	)
	(gr_poly
		(pts
			(xy 84.151216 -244.686328) (xy 84.05114 -244.586252) (xy 83.951064 -244.686328) (xy 83.951064 -244.730778)
			(xy 84.151216 -244.730778)
		)
		(stroke
			(width 0)
			(type solid)
		)
		(fill yes)
		(layer "In13.Cu")
		(net "M_B_CPU1_SA_CB<0>")
	)
	(gr_poly
		(pts
			(xy 84.151216 -244.282468) (xy 84.151216 -244.238018) (xy 83.951064 -244.238018) (xy 83.951064 -244.282468)
			(xy 84.05114 -244.382544)
		)
		(stroke
			(width 0)
			(type solid)
		)
		(fill yes)
		(layer "In13.Cu")
		(net "M_B_CPU1_SA_DQ<31>")
	)
	(gr_poly
		(pts
			(xy 84.151216 -243.066316) (xy 84.05114 -242.96624) (xy 83.951064 -243.066316) (xy 83.951064 -243.110766)
			(xy 84.151216 -243.110766)
		)
		(stroke
			(width 0)
			(type solid)
		)
		(fill yes)
		(layer "In13.Cu")
		(net "M_B_CPU1_SA_DQ<28>")
	)
	(gr_poly
		(pts
			(xy 84.151216 -242.66271) (xy 84.151216 -242.614958) (xy 83.951064 -242.614958) (xy 83.951064 -242.66271)
			(xy 84.05114 -242.762532)
		)
		(stroke
			(width 0)
			(type solid)
		)
		(fill yes)
		(layer "In13.Cu")
		(net "M_B_CPU1_SA_DQS_DP<8>")
	)
	(gr_poly
		(pts
			(xy 84.151216 -241.44605) (xy 84.05114 -241.346228) (xy 83.951064 -241.44605) (xy 83.951064 -241.493802)
			(xy 84.151216 -241.493802)
		)
		(stroke
			(width 0)
			(type solid)
		)
		(fill yes)
		(layer "In13.Cu")
		(net "M_B_CPU1_SA_DQS_DP<3>")
	)
	(gr_poly
		(pts
			(xy 84.151216 -241.042444) (xy 84.151216 -240.997994) (xy 83.951064 -240.997994) (xy 83.951064 -241.042444)
			(xy 84.05114 -241.14252)
		)
		(stroke
			(width 0)
			(type solid)
		)
		(fill yes)
		(layer "In13.Cu")
		(net "M_B_CPU1_SA_DQ<27>")
	)
	(gr_poly
		(pts
			(xy 84.151216 -239.826292) (xy 84.05114 -239.726216) (xy 83.951064 -239.826292) (xy 83.951064 -239.870742)
			(xy 84.151216 -239.870742)
		)
		(stroke
			(width 0)
			(type solid)
		)
		(fill yes)
		(layer "In13.Cu")
		(net "M_B_CPU1_SA_DQ<24>")
	)
	(gr_poly
		(pts
			(xy 84.151216 -239.422432) (xy 84.151216 -239.377982) (xy 83.951064 -239.377982) (xy 83.951064 -239.422432)
			(xy 84.05114 -239.522508)
		)
		(stroke
			(width 0)
			(type solid)
		)
		(fill yes)
		(layer "In13.Cu")
		(net "M_B_CPU1_SA_DQ<23>")
	)
	(gr_poly
		(pts
			(xy 84.151216 -238.20628) (xy 84.05114 -238.106204) (xy 83.951064 -238.20628) (xy 83.951064 -238.25073)
			(xy 84.151216 -238.25073)
		)
		(stroke
			(width 0)
			(type solid)
		)
		(fill yes)
		(layer "In13.Cu")
		(net "M_B_CPU1_SA_DQ<20>")
	)
	(gr_poly
		(pts
			(xy 84.151216 -237.802674) (xy 84.151216 -237.754922) (xy 83.951064 -237.754922) (xy 83.951064 -237.802674)
			(xy 84.05114 -237.902496)
		)
		(stroke
			(width 0)
			(type solid)
		)
		(fill yes)
		(layer "In13.Cu")
		(net "M_B_CPU1_SA_DQS_DP<7>")
	)
	(gr_poly
		(pts
			(xy 84.151216 -236.586014) (xy 84.05114 -236.486192) (xy 83.951064 -236.586014) (xy 83.951064 -236.633766)
			(xy 84.151216 -236.633766)
		)
		(stroke
			(width 0)
			(type solid)
		)
		(fill yes)
		(layer "In13.Cu")
		(net "M_B_CPU1_SA_DQS_DP<2>")
	)
	(gr_poly
		(pts
			(xy 84.151216 -236.182408) (xy 84.151216 -236.137958) (xy 83.951064 -236.137958) (xy 83.951064 -236.182408)
			(xy 84.05114 -236.282484)
		)
		(stroke
			(width 0)
			(type solid)
		)
		(fill yes)
		(layer "In13.Cu")
		(net "M_B_CPU1_SA_DQ<19>")
	)
	(gr_poly
		(pts
			(xy 84.151216 -234.966256) (xy 84.05114 -234.86618) (xy 83.951064 -234.966256) (xy 83.951064 -235.010706)
			(xy 84.151216 -235.010706)
		)
		(stroke
			(width 0)
			(type solid)
		)
		(fill yes)
		(layer "In13.Cu")
		(net "M_B_CPU1_SA_DQ<16>")
	)
	(gr_poly
		(pts
			(xy 84.151216 -234.562396) (xy 84.151216 -234.517946) (xy 83.951064 -234.517946) (xy 83.951064 -234.562396)
			(xy 84.05114 -234.662472)
		)
		(stroke
			(width 0)
			(type solid)
		)
		(fill yes)
		(layer "In13.Cu")
		(net "M_B_CPU1_SA_DQ<15>")
	)
	(gr_poly
		(pts
			(xy 84.151216 -233.346244) (xy 84.05114 -233.246168) (xy 83.951064 -233.346244) (xy 83.951064 -233.390694)
			(xy 84.151216 -233.390694)
		)
		(stroke
			(width 0)
			(type solid)
		)
		(fill yes)
		(layer "In13.Cu")
		(net "M_B_CPU1_SA_DQ<12>")
	)
	(gr_poly
		(pts
			(xy 84.151216 -232.942638) (xy 84.151216 -232.894886) (xy 83.951064 -232.894886) (xy 83.951064 -232.942638)
			(xy 84.05114 -233.04246)
		)
		(stroke
			(width 0)
			(type solid)
		)
		(fill yes)
		(layer "In13.Cu")
		(net "M_B_CPU1_SA_DQS_DP<6>")
	)
	(gr_poly
		(pts
			(xy 84.151216 -231.725978) (xy 84.05114 -231.626156) (xy 83.951064 -231.725978) (xy 83.951064 -231.77373)
			(xy 84.151216 -231.77373)
		)
		(stroke
			(width 0)
			(type solid)
		)
		(fill yes)
		(layer "In13.Cu")
		(net "M_B_CPU1_SA_DQS_DP<1>")
	)
	(gr_poly
		(pts
			(xy 84.151216 -231.322626) (xy 84.151216 -231.278176) (xy 83.951064 -231.278176) (xy 83.951064 -231.322626)
			(xy 84.05114 -231.422702)
		)
		(stroke
			(width 0)
			(type solid)
		)
		(fill yes)
		(layer "In13.Cu")
		(net "M_B_CPU1_SA_DQ<11>")
	)
	(gr_poly
		(pts
			(xy 84.151216 -230.10622) (xy 84.05114 -230.006144) (xy 83.951064 -230.10622) (xy 83.951064 -230.15067)
			(xy 84.151216 -230.15067)
		)
		(stroke
			(width 0)
			(type solid)
		)
		(fill yes)
		(layer "In13.Cu")
		(net "M_B_CPU1_SA_DQ<8>")
	)
	(gr_poly
		(pts
			(xy 84.151216 -229.702614) (xy 84.151216 -229.658164) (xy 83.951064 -229.658164) (xy 83.951064 -229.702614)
			(xy 84.05114 -229.80269)
		)
		(stroke
			(width 0)
			(type solid)
		)
		(fill yes)
		(layer "In13.Cu")
		(net "M_B_CPU1_SA_DQ<7>")
	)
	(gr_poly
		(pts
			(xy 84.151216 -228.486462) (xy 84.05114 -228.386386) (xy 83.951064 -228.486462) (xy 83.951064 -228.530912)
			(xy 84.151216 -228.530912)
		)
		(stroke
			(width 0)
			(type solid)
		)
		(fill yes)
		(layer "In13.Cu")
		(net "M_B_CPU1_SA_DQ<4>")
	)
	(gr_poly
		(pts
			(xy 84.151216 -228.082856) (xy 84.151216 -228.035104) (xy 83.951064 -228.035104) (xy 83.951064 -228.082856)
			(xy 84.05114 -228.182678)
		)
		(stroke
			(width 0)
			(type solid)
		)
		(fill yes)
		(layer "In13.Cu")
		(net "M_B_CPU1_SA_DQS_DP<5>")
	)
	(gr_poly
		(pts
			(xy 84.151216 -226.866196) (xy 84.05114 -226.766374) (xy 83.951064 -226.866196) (xy 83.951064 -226.913948)
			(xy 84.151216 -226.913948)
		)
		(stroke
			(width 0)
			(type solid)
		)
		(fill yes)
		(layer "In13.Cu")
		(net "M_B_CPU1_SA_DQS_DP<0>")
	)
	(gr_poly
		(pts
			(xy 84.151216 -226.46259) (xy 84.151216 -226.41814) (xy 83.951064 -226.41814) (xy 83.951064 -226.46259)
			(xy 84.05114 -226.562666)
		)
		(stroke
			(width 0)
			(type solid)
		)
		(fill yes)
		(layer "In13.Cu")
		(net "M_B_CPU1_SA_DQ<3>")
	)
	(gr_poly
		(pts
			(xy 84.151216 -225.246438) (xy 84.05114 -225.146362) (xy 83.951064 -225.246438) (xy 83.951064 -225.290888)
			(xy 84.151216 -225.290888)
		)
		(stroke
			(width 0)
			(type solid)
		)
		(fill yes)
		(layer "In13.Cu")
		(net "M_B_CPU1_SA_DQ<0>")
	)
	(gr_poly
		(pts
			(xy 84.44484 -266.991846) (xy 84.344764 -266.89177) (xy 84.244942 -266.991846) (xy 84.244942 -267.036296)
			(xy 84.44484 -267.036296)
		)
		(stroke
			(width 0)
			(type solid)
		)
		(fill yes)
		(layer "In13.Cu")
		(net "M_B_CPU1_SA_RSP<0>")
	)
	(gr_poly
		(pts
			(xy 84.45119 -292.918134) (xy 84.351114 -292.818058) (xy 84.251038 -292.918134) (xy 84.251038 -292.962584)
			(xy 84.45119 -292.962584)
		)
		(stroke
			(width 0)
			(type solid)
		)
		(fill yes)
		(layer "In13.Cu")
		(net "M_B_CPU1_SB_DQ<29>")
	)
	(gr_poly
		(pts
			(xy 84.45119 -292.514274) (xy 84.45119 -292.469824) (xy 84.251038 -292.469824) (xy 84.251038 -292.514274)
			(xy 84.351114 -292.61435)
		)
		(stroke
			(width 0)
			(type solid)
		)
		(fill yes)
		(layer "In13.Cu")
		(net "M_B_CPU1_SB_DQ<30>")
	)
	(gr_poly
		(pts
			(xy 84.45119 -291.297868) (xy 84.351114 -291.198046) (xy 84.251038 -291.297868) (xy 84.251038 -291.34562)
			(xy 84.45119 -291.34562)
		)
		(stroke
			(width 0)
			(type solid)
		)
		(fill yes)
		(layer "In13.Cu")
		(net "M_B_CPU1_SB_DQS_DN<8>")
	)
	(gr_poly
		(pts
			(xy 84.45119 -290.894516) (xy 84.45119 -290.846764) (xy 84.251038 -290.846764) (xy 84.251038 -290.894516)
			(xy 84.351114 -290.994338)
		)
		(stroke
			(width 0)
			(type solid)
		)
		(fill yes)
		(layer "In13.Cu")
		(net "M_B_CPU1_SB_DQS_DN<3>")
	)
	(gr_poly
		(pts
			(xy 84.45119 -289.67811) (xy 84.351114 -289.578034) (xy 84.251038 -289.67811) (xy 84.251038 -289.72256)
			(xy 84.45119 -289.72256)
		)
		(stroke
			(width 0)
			(type solid)
		)
		(fill yes)
		(layer "In13.Cu")
		(net "M_B_CPU1_SB_DQ<25>")
	)
	(gr_poly
		(pts
			(xy 84.45119 -289.27425) (xy 84.45119 -289.2298) (xy 84.251038 -289.2298) (xy 84.251038 -289.27425)
			(xy 84.351114 -289.374326)
		)
		(stroke
			(width 0)
			(type solid)
		)
		(fill yes)
		(layer "In13.Cu")
		(net "M_B_CPU1_SB_DQ<26>")
	)
	(gr_poly
		(pts
			(xy 84.45119 -288.058098) (xy 84.351114 -287.958022) (xy 84.251038 -288.058098) (xy 84.251038 -288.102548)
			(xy 84.45119 -288.102548)
		)
		(stroke
			(width 0)
			(type solid)
		)
		(fill yes)
		(layer "In13.Cu")
		(net "M_B_CPU1_SB_DQ<21>")
	)
	(gr_poly
		(pts
			(xy 84.45119 -287.654492) (xy 84.45119 -287.610042) (xy 84.251038 -287.610042) (xy 84.251038 -287.654492)
			(xy 84.351114 -287.754568)
		)
		(stroke
			(width 0)
			(type solid)
		)
		(fill yes)
		(layer "In13.Cu")
		(net "M_B_CPU1_SB_DQ<22>")
	)
	(gr_poly
		(pts
			(xy 84.45119 -286.438086) (xy 84.351114 -286.33801) (xy 84.251038 -286.438086) (xy 84.251038 -286.485838)
			(xy 84.45119 -286.485838)
		)
		(stroke
			(width 0)
			(type solid)
		)
		(fill yes)
		(layer "In13.Cu")
		(net "M_B_CPU1_SB_DQS_DN<7>")
	)
	(gr_poly
		(pts
			(xy 84.45119 -286.034734) (xy 84.45119 -285.986982) (xy 84.251038 -285.986982) (xy 84.251038 -286.034734)
			(xy 84.351114 -286.134556)
		)
		(stroke
			(width 0)
			(type solid)
		)
		(fill yes)
		(layer "In13.Cu")
		(net "M_B_CPU1_SB_DQS_DN<2>")
	)
	(gr_poly
		(pts
			(xy 84.45119 -284.818328) (xy 84.351114 -284.718252) (xy 84.251038 -284.818328) (xy 84.251038 -284.862778)
			(xy 84.45119 -284.862778)
		)
		(stroke
			(width 0)
			(type solid)
		)
		(fill yes)
		(layer "In13.Cu")
		(net "M_B_CPU1_SB_DQ<17>")
	)
	(gr_poly
		(pts
			(xy 84.45119 -284.414468) (xy 84.45119 -284.370018) (xy 84.251038 -284.370018) (xy 84.251038 -284.414468)
			(xy 84.351114 -284.514544)
		)
		(stroke
			(width 0)
			(type solid)
		)
		(fill yes)
		(layer "In13.Cu")
		(net "M_B_CPU1_SB_DQ<18>")
	)
	(gr_poly
		(pts
			(xy 84.45119 -283.198316) (xy 84.351114 -283.09824) (xy 84.251038 -283.198316) (xy 84.251038 -283.242766)
			(xy 84.45119 -283.242766)
		)
		(stroke
			(width 0)
			(type solid)
		)
		(fill yes)
		(layer "In13.Cu")
		(net "M_B_CPU1_SB_DQ<13>")
	)
	(gr_poly
		(pts
			(xy 84.45119 -282.794456) (xy 84.45119 -282.750006) (xy 84.251038 -282.750006) (xy 84.251038 -282.794456)
			(xy 84.351114 -282.894532)
		)
		(stroke
			(width 0)
			(type solid)
		)
		(fill yes)
		(layer "In13.Cu")
		(net "M_B_CPU1_SB_DQ<14>")
	)
	(gr_poly
		(pts
			(xy 84.45119 -281.57805) (xy 84.351114 -281.478228) (xy 84.251038 -281.57805) (xy 84.251038 -281.625802)
			(xy 84.45119 -281.625802)
		)
		(stroke
			(width 0)
			(type solid)
		)
		(fill yes)
		(layer "In13.Cu")
		(net "M_B_CPU1_SB_DQS_DN<6>")
	)
	(gr_poly
		(pts
			(xy 84.45119 -281.174698) (xy 84.45119 -281.126946) (xy 84.251038 -281.126946) (xy 84.251038 -281.174698)
			(xy 84.351114 -281.27452)
		)
		(stroke
			(width 0)
			(type solid)
		)
		(fill yes)
		(layer "In13.Cu")
		(net "M_B_CPU1_SB_DQS_DN<1>")
	)
	(gr_poly
		(pts
			(xy 84.45119 -279.958292) (xy 84.351114 -279.858216) (xy 84.251038 -279.958292) (xy 84.251038 -280.002742)
			(xy 84.45119 -280.002742)
		)
		(stroke
			(width 0)
			(type solid)
		)
		(fill yes)
		(layer "In13.Cu")
		(net "M_B_CPU1_SB_DQ<9>")
	)
	(gr_poly
		(pts
			(xy 84.45119 -279.554432) (xy 84.45119 -279.509982) (xy 84.251038 -279.509982) (xy 84.251038 -279.554432)
			(xy 84.351114 -279.654508)
		)
		(stroke
			(width 0)
			(type solid)
		)
		(fill yes)
		(layer "In13.Cu")
		(net "M_B_CPU1_SB_DQ<10>")
	)
	(gr_poly
		(pts
			(xy 84.45119 -278.33828) (xy 84.351114 -278.238204) (xy 84.251038 -278.33828) (xy 84.251038 -278.38273)
			(xy 84.45119 -278.38273)
		)
		(stroke
			(width 0)
			(type solid)
		)
		(fill yes)
		(layer "In13.Cu")
		(net "M_B_CPU1_SB_DQ<5>")
	)
	(gr_poly
		(pts
			(xy 84.45119 -277.93442) (xy 84.45119 -277.88997) (xy 84.251038 -277.88997) (xy 84.251038 -277.93442)
			(xy 84.351114 -278.034496)
		)
		(stroke
			(width 0)
			(type solid)
		)
		(fill yes)
		(layer "In13.Cu")
		(net "M_B_CPU1_SB_DQ<6>")
	)
	(gr_poly
		(pts
			(xy 84.45119 -276.718014) (xy 84.351114 -276.618192) (xy 84.251038 -276.718014) (xy 84.251038 -276.765766)
			(xy 84.45119 -276.765766)
		)
		(stroke
			(width 0)
			(type solid)
		)
		(fill yes)
		(layer "In13.Cu")
		(net "M_B_CPU1_SB_DQS_DN<5>")
	)
	(gr_poly
		(pts
			(xy 84.45119 -276.314662) (xy 84.45119 -276.26691) (xy 84.251038 -276.26691) (xy 84.251038 -276.314662)
			(xy 84.351114 -276.414484)
		)
		(stroke
			(width 0)
			(type solid)
		)
		(fill yes)
		(layer "In13.Cu")
		(net "M_B_CPU1_SB_DQS_DN<0>")
	)
	(gr_poly
		(pts
			(xy 84.45119 -275.098256) (xy 84.351114 -274.99818) (xy 84.251038 -275.098256) (xy 84.251038 -275.142706)
			(xy 84.45119 -275.142706)
		)
		(stroke
			(width 0)
			(type solid)
		)
		(fill yes)
		(layer "In13.Cu")
		(net "M_B_CPU1_SB_DQ<1>")
	)
	(gr_poly
		(pts
			(xy 84.45119 -274.694396) (xy 84.45119 -274.649946) (xy 84.251038 -274.649946) (xy 84.251038 -274.694396)
			(xy 84.351114 -274.794472)
		)
		(stroke
			(width 0)
			(type solid)
		)
		(fill yes)
		(layer "In13.Cu")
		(net "M_B_CPU1_SB_DQ<2>")
	)
	(gr_poly
		(pts
			(xy 84.45119 -273.478244) (xy 84.351114 -273.378168) (xy 84.251038 -273.478244) (xy 84.251038 -273.522694)
			(xy 84.45119 -273.522694)
		)
		(stroke
			(width 0)
			(type solid)
		)
		(fill yes)
		(layer "In13.Cu")
		(net "M_B_CPU1_SB_CB<1>")
	)
	(gr_poly
		(pts
			(xy 84.45119 -273.074384) (xy 84.45119 -273.029934) (xy 84.251038 -273.029934) (xy 84.251038 -273.074384)
			(xy 84.351114 -273.17446)
		)
		(stroke
			(width 0)
			(type solid)
		)
		(fill yes)
		(layer "In13.Cu")
		(net "M_B_CPU1_SB_CB<2>")
	)
	(gr_poly
		(pts
			(xy 84.45119 -271.857978) (xy 84.351114 -271.758156) (xy 84.251038 -271.857978) (xy 84.251038 -271.90573)
			(xy 84.45119 -271.90573)
		)
		(stroke
			(width 0)
			(type solid)
		)
		(fill yes)
		(layer "In13.Cu")
		(net "M_B_CPU1_SB_DQS_DN<4>")
	)
	(gr_poly
		(pts
			(xy 84.45119 -271.454626) (xy 84.45119 -271.406874) (xy 84.251038 -271.406874) (xy 84.251038 -271.454626)
			(xy 84.351114 -271.554448)
		)
		(stroke
			(width 0)
			(type solid)
		)
		(fill yes)
		(layer "In13.Cu")
		(net "M_B_CPU1_SB_DQS_DN<9>")
	)
	(gr_poly
		(pts
			(xy 84.45119 -270.23822) (xy 84.351114 -270.138144) (xy 84.251038 -270.23822) (xy 84.251038 -270.28267)
			(xy 84.45119 -270.28267)
		)
		(stroke
			(width 0)
			(type solid)
		)
		(fill yes)
		(layer "In13.Cu")
		(net "M_B_CPU1_SB_CB<5>")
	)
	(gr_poly
		(pts
			(xy 84.45119 -269.83436) (xy 84.45119 -269.78991) (xy 84.251038 -269.78991) (xy 84.251038 -269.83436)
			(xy 84.351114 -269.934436)
		)
		(stroke
			(width 0)
			(type solid)
		)
		(fill yes)
		(layer "In13.Cu")
		(net "M_B_CPU1_SB_CB<6>")
	)
	(gr_poly
		(pts
			(xy 84.45119 -266.594336) (xy 84.45119 -266.549886) (xy 84.251038 -266.549886) (xy 84.251038 -266.594336)
			(xy 84.351114 -266.694412)
		)
		(stroke
			(width 0)
			(type solid)
		)
		(fill yes)
		(layer "In13.Cu")
		(net "M_B_CPU1_SB_CS_N<1>")
	)
	(gr_poly
		(pts
			(xy 84.45119 -264.974324) (xy 84.45119 -264.929874) (xy 84.251038 -264.929874) (xy 84.251038 -264.974324)
			(xy 84.351114 -265.0744)
		)
		(stroke
			(width 0)
			(type solid)
		)
		(fill yes)
		(layer "In13.Cu")
		(net "M_B_CPU1_SB_PAR")
	)
	(gr_poly
		(pts
			(xy 84.45119 -263.758172) (xy 84.351114 -263.658096) (xy 84.251038 -263.758172) (xy 84.251038 -263.802622)
			(xy 84.45119 -263.802622)
		)
		(stroke
			(width 0)
			(type solid)
		)
		(fill yes)
		(layer "In13.Cu")
		(net "M_B_CPU1_SB_CA<4>")
	)
	(gr_poly
		(pts
			(xy 84.45119 -263.354312) (xy 84.45119 -263.309862) (xy 84.251038 -263.309862) (xy 84.251038 -263.354312)
			(xy 84.351114 -263.454388)
		)
		(stroke
			(width 0)
			(type solid)
		)
		(fill yes)
		(layer "In13.Cu")
		(net "M_B_CPU1_SB_CA<3>")
	)
	(gr_poly
		(pts
			(xy 84.45119 -262.13816) (xy 84.351114 -262.038084) (xy 84.251038 -262.13816) (xy 84.251038 -262.18261)
			(xy 84.45119 -262.18261)
		)
		(stroke
			(width 0)
			(type solid)
		)
		(fill yes)
		(layer "In13.Cu")
		(net "M_B_CPU1_SB_CA<0>")
	)
	(gr_poly
		(pts
			(xy 84.621116 -256.432812) (xy 84.621116 -256.38506) (xy 84.420964 -256.38506) (xy 84.420964 -256.432812)
			(xy 84.52104 -256.532634)
		)
		(stroke
			(width 0)
			(type solid)
		)
		(fill yes)
		(layer "In13.Cu")
		(net "M_B_CPU1_CLK_DN<0>")
	)
	(gr_poly
		(pts
			(xy 84.621116 -255.216406) (xy 84.52104 -255.11633) (xy 84.420964 -255.216406) (xy 84.420964 -255.260856)
			(xy 84.621116 -255.260856)
		)
		(stroke
			(width 0)
			(type solid)
		)
		(fill yes)
		(layer "In13.Cu")
		(net "M_B_CPU1_SA_CA<6>")
	)
	(gr_poly
		(pts
			(xy 84.621116 -254.812546) (xy 84.621116 -254.768096) (xy 84.420964 -254.768096) (xy 84.420964 -254.812546)
			(xy 84.52104 -254.912622)
		)
		(stroke
			(width 0)
			(type solid)
		)
		(fill yes)
		(layer "In13.Cu")
		(net "M_B_CPU1_SA_CA<5>")
	)
	(gr_poly
		(pts
			(xy 84.621116 -253.596394) (xy 84.52104 -253.496318) (xy 84.420964 -253.596394) (xy 84.420964 -253.640844)
			(xy 84.621116 -253.640844)
		)
		(stroke
			(width 0)
			(type solid)
		)
		(fill yes)
		(layer "In13.Cu")
		(net "M_B_CPU1_SA_CA<2>")
	)
	(gr_poly
		(pts
			(xy 84.621116 -253.192534) (xy 84.621116 -253.148084) (xy 84.420964 -253.148084) (xy 84.420964 -253.192534)
			(xy 84.52104 -253.29261)
		)
		(stroke
			(width 0)
			(type solid)
		)
		(fill yes)
		(layer "In13.Cu")
		(net "M_B_CPU1_SA_CA<1>")
	)
	(gr_poly
		(pts
			(xy 84.621116 -251.572522) (xy 84.621116 -251.528072) (xy 84.420964 -251.528072) (xy 84.420964 -251.572522)
			(xy 84.52104 -251.672598)
		)
		(stroke
			(width 0)
			(type solid)
		)
		(fill yes)
		(layer "In13.Cu")
		(net "M_B_CPU1_SA_CS_N<0>")
	)
	(gr_poly
		(pts
			(xy 84.621116 -250.35637) (xy 84.52104 -250.256294) (xy 84.420964 -250.35637) (xy 84.420964 -250.40082)
			(xy 84.621116 -250.40082)
		)
		(stroke
			(width 0)
			(type solid)
		)
		(fill yes)
		(layer "In13.Cu")
		(net "M_B_CPU1_ALERT_R_N")
	)
	(gr_poly
		(pts
			(xy 84.621116 -248.736358) (xy 84.52104 -248.636282) (xy 84.420964 -248.736358) (xy 84.420964 -248.780808)
			(xy 84.621116 -248.780808)
		)
		(stroke
			(width 0)
			(type solid)
		)
		(fill yes)
		(layer "In13.Cu")
		(net "M_B_CPU1_SA_CB<5>")
	)
	(gr_poly
		(pts
			(xy 84.621116 -248.332498) (xy 84.621116 -248.288048) (xy 84.420964 -248.288048) (xy 84.420964 -248.332498)
			(xy 84.52104 -248.432574)
		)
		(stroke
			(width 0)
			(type solid)
		)
		(fill yes)
		(layer "In13.Cu")
		(net "M_B_CPU1_SA_CB<6>")
	)
	(gr_poly
		(pts
			(xy 84.621116 -247.116092) (xy 84.52104 -247.01627) (xy 84.420964 -247.116092) (xy 84.420964 -247.163844)
			(xy 84.621116 -247.163844)
		)
		(stroke
			(width 0)
			(type solid)
		)
		(fill yes)
		(layer "In13.Cu")
		(net "M_B_CPU1_SA_DQS_DN<9>")
	)
	(gr_poly
		(pts
			(xy 84.621116 -246.71274) (xy 84.621116 -246.664988) (xy 84.420964 -246.664988) (xy 84.420964 -246.71274)
			(xy 84.52104 -246.812562)
		)
		(stroke
			(width 0)
			(type solid)
		)
		(fill yes)
		(layer "In13.Cu")
		(net "M_B_CPU1_SA_DQS_DN<4>")
	)
	(gr_poly
		(pts
			(xy 84.621116 -245.496334) (xy 84.52104 -245.396258) (xy 84.420964 -245.496334) (xy 84.420964 -245.540784)
			(xy 84.621116 -245.540784)
		)
		(stroke
			(width 0)
			(type solid)
		)
		(fill yes)
		(layer "In13.Cu")
		(net "M_B_CPU1_SA_CB<1>")
	)
	(gr_poly
		(pts
			(xy 84.621116 -245.092474) (xy 84.621116 -245.048024) (xy 84.420964 -245.048024) (xy 84.420964 -245.092474)
			(xy 84.52104 -245.19255)
		)
		(stroke
			(width 0)
			(type solid)
		)
		(fill yes)
		(layer "In13.Cu")
		(net "M_B_CPU1_SA_CB<2>")
	)
	(gr_poly
		(pts
			(xy 84.621116 -243.876322) (xy 84.52104 -243.776246) (xy 84.420964 -243.876322) (xy 84.420964 -243.920772)
			(xy 84.621116 -243.920772)
		)
		(stroke
			(width 0)
			(type solid)
		)
		(fill yes)
		(layer "In13.Cu")
		(net "M_B_CPU1_SA_DQ<29>")
	)
	(gr_poly
		(pts
			(xy 84.621116 -243.472462) (xy 84.621116 -243.428012) (xy 84.420964 -243.428012) (xy 84.420964 -243.472462)
			(xy 84.52104 -243.572538)
		)
		(stroke
			(width 0)
			(type solid)
		)
		(fill yes)
		(layer "In13.Cu")
		(net "M_B_CPU1_SA_DQ<30>")
	)
	(gr_poly
		(pts
			(xy 84.621116 -242.256056) (xy 84.52104 -242.156234) (xy 84.420964 -242.256056) (xy 84.420964 -242.303808)
			(xy 84.621116 -242.303808)
		)
		(stroke
			(width 0)
			(type solid)
		)
		(fill yes)
		(layer "In13.Cu")
		(net "M_B_CPU1_SA_DQS_DN<8>")
	)
	(gr_poly
		(pts
			(xy 84.621116 -241.852704) (xy 84.621116 -241.804952) (xy 84.420964 -241.804952) (xy 84.420964 -241.852704)
			(xy 84.52104 -241.952526)
		)
		(stroke
			(width 0)
			(type solid)
		)
		(fill yes)
		(layer "In13.Cu")
		(net "M_B_CPU1_SA_DQS_DN<3>")
	)
	(gr_poly
		(pts
			(xy 84.621116 -240.636298) (xy 84.52104 -240.536222) (xy 84.420964 -240.636298) (xy 84.420964 -240.680748)
			(xy 84.621116 -240.680748)
		)
		(stroke
			(width 0)
			(type solid)
		)
		(fill yes)
		(layer "In13.Cu")
		(net "M_B_CPU1_SA_DQ<25>")
	)
	(gr_poly
		(pts
			(xy 84.621116 -240.232438) (xy 84.621116 -240.187988) (xy 84.420964 -240.187988) (xy 84.420964 -240.232438)
			(xy 84.52104 -240.332514)
		)
		(stroke
			(width 0)
			(type solid)
		)
		(fill yes)
		(layer "In13.Cu")
		(net "M_B_CPU1_SA_DQ<26>")
	)
	(gr_poly
		(pts
			(xy 84.621116 -239.016286) (xy 84.52104 -238.91621) (xy 84.420964 -239.016286) (xy 84.420964 -239.060736)
			(xy 84.621116 -239.060736)
		)
		(stroke
			(width 0)
			(type solid)
		)
		(fill yes)
		(layer "In13.Cu")
		(net "M_B_CPU1_SA_DQ<21>")
	)
	(gr_poly
		(pts
			(xy 84.621116 -238.612426) (xy 84.621116 -238.567976) (xy 84.420964 -238.567976) (xy 84.420964 -238.612426)
			(xy 84.52104 -238.712502)
		)
		(stroke
			(width 0)
			(type solid)
		)
		(fill yes)
		(layer "In13.Cu")
		(net "M_B_CPU1_SA_DQ<22>")
	)
	(gr_poly
		(pts
			(xy 84.621116 -237.39602) (xy 84.52104 -237.296198) (xy 84.420964 -237.39602) (xy 84.420964 -237.443772)
			(xy 84.621116 -237.443772)
		)
		(stroke
			(width 0)
			(type solid)
		)
		(fill yes)
		(layer "In13.Cu")
		(net "M_B_CPU1_SA_DQS_DN<7>")
	)
	(gr_poly
		(pts
			(xy 84.621116 -236.992668) (xy 84.621116 -236.944916) (xy 84.420964 -236.944916) (xy 84.420964 -236.992668)
			(xy 84.52104 -237.09249)
		)
		(stroke
			(width 0)
			(type solid)
		)
		(fill yes)
		(layer "In13.Cu")
		(net "M_B_CPU1_SA_DQS_DN<2>")
	)
	(gr_poly
		(pts
			(xy 84.621116 -235.776262) (xy 84.52104 -235.676186) (xy 84.420964 -235.776262) (xy 84.420964 -235.820712)
			(xy 84.621116 -235.820712)
		)
		(stroke
			(width 0)
			(type solid)
		)
		(fill yes)
		(layer "In13.Cu")
		(net "M_B_CPU1_SA_DQ<17>")
	)
	(gr_poly
		(pts
			(xy 84.621116 -235.372402) (xy 84.621116 -235.327952) (xy 84.420964 -235.327952) (xy 84.420964 -235.372402)
			(xy 84.52104 -235.472478)
		)
		(stroke
			(width 0)
			(type solid)
		)
		(fill yes)
		(layer "In13.Cu")
		(net "M_B_CPU1_SA_DQ<18>")
	)
	(gr_poly
		(pts
			(xy 84.621116 -234.15625) (xy 84.52104 -234.056174) (xy 84.420964 -234.15625) (xy 84.420964 -234.2007)
			(xy 84.621116 -234.2007)
		)
		(stroke
			(width 0)
			(type solid)
		)
		(fill yes)
		(layer "In13.Cu")
		(net "M_B_CPU1_SA_DQ<13>")
	)
	(gr_poly
		(pts
			(xy 84.621116 -233.75239) (xy 84.621116 -233.70794) (xy 84.420964 -233.70794) (xy 84.420964 -233.75239)
			(xy 84.52104 -233.852466)
		)
		(stroke
			(width 0)
			(type solid)
		)
		(fill yes)
		(layer "In13.Cu")
		(net "M_B_CPU1_SA_DQ<14>")
	)
	(gr_poly
		(pts
			(xy 84.621116 -232.535984) (xy 84.52104 -232.436162) (xy 84.420964 -232.535984) (xy 84.420964 -232.583736)
			(xy 84.621116 -232.583736)
		)
		(stroke
			(width 0)
			(type solid)
		)
		(fill yes)
		(layer "In13.Cu")
		(net "M_B_CPU1_SA_DQS_DN<6>")
	)
	(gr_poly
		(pts
			(xy 84.621116 -232.132632) (xy 84.621116 -232.08488) (xy 84.420964 -232.08488) (xy 84.420964 -232.132632)
			(xy 84.52104 -232.232454)
		)
		(stroke
			(width 0)
			(type solid)
		)
		(fill yes)
		(layer "In13.Cu")
		(net "M_B_CPU1_SA_DQS_DN<1>")
	)
	(gr_poly
		(pts
			(xy 84.621116 -230.916226) (xy 84.52104 -230.81615) (xy 84.420964 -230.916226) (xy 84.420964 -230.960676)
			(xy 84.621116 -230.960676)
		)
		(stroke
			(width 0)
			(type solid)
		)
		(fill yes)
		(layer "In13.Cu")
		(net "M_B_CPU1_SA_DQ<9>")
	)
	(gr_poly
		(pts
			(xy 84.621116 -230.51262) (xy 84.621116 -230.46817) (xy 84.420964 -230.46817) (xy 84.420964 -230.51262)
			(xy 84.52104 -230.612696)
		)
		(stroke
			(width 0)
			(type solid)
		)
		(fill yes)
		(layer "In13.Cu")
		(net "M_B_CPU1_SA_DQ<10>")
	)
	(gr_poly
		(pts
			(xy 84.621116 -229.296214) (xy 84.52104 -229.196138) (xy 84.420964 -229.296214) (xy 84.420964 -229.340664)
			(xy 84.621116 -229.340664)
		)
		(stroke
			(width 0)
			(type solid)
		)
		(fill yes)
		(layer "In13.Cu")
		(net "M_B_CPU1_SA_DQ<5>")
	)
	(gr_poly
		(pts
			(xy 84.621116 -228.892608) (xy 84.621116 -228.848158) (xy 84.420964 -228.848158) (xy 84.420964 -228.892608)
			(xy 84.52104 -228.992684)
		)
		(stroke
			(width 0)
			(type solid)
		)
		(fill yes)
		(layer "In13.Cu")
		(net "M_B_CPU1_SA_DQ<6>")
	)
	(gr_poly
		(pts
			(xy 84.621116 -227.67671) (xy 84.52104 -227.576634) (xy 84.420964 -227.67671) (xy 84.420964 -227.724462)
			(xy 84.621116 -227.724462)
		)
		(stroke
			(width 0)
			(type solid)
		)
		(fill yes)
		(layer "In13.Cu")
		(net "M_B_CPU1_SA_DQS_DN<5>")
	)
	(gr_poly
		(pts
			(xy 84.621116 -227.27285) (xy 84.621116 -227.225098) (xy 84.420964 -227.225098) (xy 84.420964 -227.27285)
			(xy 84.52104 -227.372672)
		)
		(stroke
			(width 0)
			(type solid)
		)
		(fill yes)
		(layer "In13.Cu")
		(net "M_B_CPU1_SA_DQS_DN<0>")
	)
	(gr_poly
		(pts
			(xy 84.621116 -226.056444) (xy 84.52104 -225.956368) (xy 84.420964 -226.056444) (xy 84.420964 -226.100894)
			(xy 84.621116 -226.100894)
		)
		(stroke
			(width 0)
			(type solid)
		)
		(fill yes)
		(layer "In13.Cu")
		(net "M_B_CPU1_SA_DQ<1>")
	)
	(gr_poly
		(pts
			(xy 84.621116 -225.652584) (xy 84.621116 -225.608134) (xy 84.420964 -225.608134) (xy 84.420964 -225.652584)
			(xy 84.52104 -225.75266)
		)
		(stroke
			(width 0)
			(type solid)
		)
		(fill yes)
		(layer "In13.Cu")
		(net "M_B_CPU1_SA_DQ<2>")
	)
	(gr_poly
		(pts
			(xy 84.92109 -293.32428) (xy 84.92109 -293.27983) (xy 84.720938 -293.27983) (xy 84.720938 -293.32428)
			(xy 84.821014 -293.424356)
		)
		(stroke
			(width 0)
			(type solid)
		)
		(fill yes)
		(layer "In13.Cu")
		(net "M_B_CPU1_SB_DQ<31>")
	)
	(gr_poly
		(pts
			(xy 84.92109 -292.108128) (xy 84.821014 -292.008052) (xy 84.720938 -292.108128) (xy 84.720938 -292.152578)
			(xy 84.92109 -292.152578)
		)
		(stroke
			(width 0)
			(type solid)
		)
		(fill yes)
		(layer "In13.Cu")
		(net "M_B_CPU1_SB_DQ<28>")
	)
	(gr_poly
		(pts
			(xy 84.92109 -291.704522) (xy 84.92109 -291.65677) (xy 84.720938 -291.65677) (xy 84.720938 -291.704522)
			(xy 84.821014 -291.804344)
		)
		(stroke
			(width 0)
			(type solid)
		)
		(fill yes)
		(layer "In13.Cu")
		(net "M_B_CPU1_SB_DQS_DP<8>")
	)
	(gr_poly
		(pts
			(xy 84.92109 -290.487862) (xy 84.821014 -290.38804) (xy 84.720938 -290.487862) (xy 84.720938 -290.535614)
			(xy 84.92109 -290.535614)
		)
		(stroke
			(width 0)
			(type solid)
		)
		(fill yes)
		(layer "In13.Cu")
		(net "M_B_CPU1_SB_DQS_DP<3>")
	)
	(gr_poly
		(pts
			(xy 84.92109 -290.084256) (xy 84.92109 -290.039806) (xy 84.720938 -290.039806) (xy 84.720938 -290.084256)
			(xy 84.821014 -290.184332)
		)
		(stroke
			(width 0)
			(type solid)
		)
		(fill yes)
		(layer "In13.Cu")
		(net "M_B_CPU1_SB_DQ<27>")
	)
	(gr_poly
		(pts
			(xy 84.92109 -288.868104) (xy 84.821014 -288.768028) (xy 84.720938 -288.868104) (xy 84.720938 -288.912554)
			(xy 84.92109 -288.912554)
		)
		(stroke
			(width 0)
			(type solid)
		)
		(fill yes)
		(layer "In13.Cu")
		(net "M_B_CPU1_SB_DQ<24>")
	)
	(gr_poly
		(pts
			(xy 84.92109 -288.464498) (xy 84.92109 -288.420048) (xy 84.720938 -288.420048) (xy 84.720938 -288.464498)
			(xy 84.821014 -288.564574)
		)
		(stroke
			(width 0)
			(type solid)
		)
		(fill yes)
		(layer "In13.Cu")
		(net "M_B_CPU1_SB_DQ<23>")
	)
	(gr_poly
		(pts
			(xy 84.92109 -287.248092) (xy 84.821014 -287.148016) (xy 84.720938 -287.248092) (xy 84.720938 -287.292542)
			(xy 84.92109 -287.292542)
		)
		(stroke
			(width 0)
			(type solid)
		)
		(fill yes)
		(layer "In13.Cu")
		(net "M_B_CPU1_SB_DQ<20>")
	)
	(gr_poly
		(pts
			(xy 84.92109 -286.844486) (xy 84.92109 -286.796734) (xy 84.720938 -286.796734) (xy 84.720938 -286.844486)
			(xy 84.821014 -286.944562)
		)
		(stroke
			(width 0)
			(type solid)
		)
		(fill yes)
		(layer "In13.Cu")
		(net "M_B_CPU1_SB_DQS_DP<7>")
	)
	(gr_poly
		(pts
			(xy 84.92109 -285.62808) (xy 84.821014 -285.528258) (xy 84.720938 -285.62808) (xy 84.720938 -285.675832)
			(xy 84.92109 -285.675832)
		)
		(stroke
			(width 0)
			(type solid)
		)
		(fill yes)
		(layer "In13.Cu")
		(net "M_B_CPU1_SB_DQS_DP<2>")
	)
	(gr_poly
		(pts
			(xy 84.92109 -285.224474) (xy 84.92109 -285.180024) (xy 84.720938 -285.180024) (xy 84.720938 -285.224474)
			(xy 84.821014 -285.32455)
		)
		(stroke
			(width 0)
			(type solid)
		)
		(fill yes)
		(layer "In13.Cu")
		(net "M_B_CPU1_SB_DQ<19>")
	)
	(gr_poly
		(pts
			(xy 84.92109 -284.008322) (xy 84.821014 -283.908246) (xy 84.720938 -284.008322) (xy 84.720938 -284.052772)
			(xy 84.92109 -284.052772)
		)
		(stroke
			(width 0)
			(type solid)
		)
		(fill yes)
		(layer "In13.Cu")
		(net "M_B_CPU1_SB_DQ<16>")
	)
	(gr_poly
		(pts
			(xy 84.92109 -283.604462) (xy 84.92109 -283.560012) (xy 84.720938 -283.560012) (xy 84.720938 -283.604462)
			(xy 84.821014 -283.704538)
		)
		(stroke
			(width 0)
			(type solid)
		)
		(fill yes)
		(layer "In13.Cu")
		(net "M_B_CPU1_SB_DQ<15>")
	)
	(gr_poly
		(pts
			(xy 84.92109 -282.38831) (xy 84.821014 -282.288234) (xy 84.720938 -282.38831) (xy 84.720938 -282.43276)
			(xy 84.92109 -282.43276)
		)
		(stroke
			(width 0)
			(type solid)
		)
		(fill yes)
		(layer "In13.Cu")
		(net "M_B_CPU1_SB_DQ<12>")
	)
	(gr_poly
		(pts
			(xy 84.92109 -281.984704) (xy 84.92109 -281.936952) (xy 84.720938 -281.936952) (xy 84.720938 -281.984704)
			(xy 84.821014 -282.084526)
		)
		(stroke
			(width 0)
			(type solid)
		)
		(fill yes)
		(layer "In13.Cu")
		(net "M_B_CPU1_SB_DQS_DP<6>")
	)
	(gr_poly
		(pts
			(xy 84.92109 -280.768044) (xy 84.821014 -280.668222) (xy 84.720938 -280.768044) (xy 84.720938 -280.815796)
			(xy 84.92109 -280.815796)
		)
		(stroke
			(width 0)
			(type solid)
		)
		(fill yes)
		(layer "In13.Cu")
		(net "M_B_CPU1_SB_DQS_DP<1>")
	)
	(gr_poly
		(pts
			(xy 84.92109 -280.364438) (xy 84.92109 -280.319988) (xy 84.720938 -280.319988) (xy 84.720938 -280.364438)
			(xy 84.821014 -280.464514)
		)
		(stroke
			(width 0)
			(type solid)
		)
		(fill yes)
		(layer "In13.Cu")
		(net "M_B_CPU1_SB_DQ<11>")
	)
	(gr_poly
		(pts
			(xy 84.92109 -279.148286) (xy 84.821014 -279.04821) (xy 84.720938 -279.148286) (xy 84.720938 -279.192736)
			(xy 84.92109 -279.192736)
		)
		(stroke
			(width 0)
			(type solid)
		)
		(fill yes)
		(layer "In13.Cu")
		(net "M_B_CPU1_SB_DQ<8>")
	)
	(gr_poly
		(pts
			(xy 84.92109 -278.744426) (xy 84.92109 -278.699976) (xy 84.720938 -278.699976) (xy 84.720938 -278.744426)
			(xy 84.821014 -278.844502)
		)
		(stroke
			(width 0)
			(type solid)
		)
		(fill yes)
		(layer "In13.Cu")
		(net "M_B_CPU1_SB_DQ<7>")
	)
	(gr_poly
		(pts
			(xy 84.92109 -277.528274) (xy 84.821014 -277.428198) (xy 84.720938 -277.528274) (xy 84.720938 -277.572724)
			(xy 84.92109 -277.572724)
		)
		(stroke
			(width 0)
			(type solid)
		)
		(fill yes)
		(layer "In13.Cu")
		(net "M_B_CPU1_SB_DQ<4>")
	)
	(gr_poly
		(pts
			(xy 84.92109 -277.124668) (xy 84.92109 -277.076916) (xy 84.720938 -277.076916) (xy 84.720938 -277.124668)
			(xy 84.821014 -277.22449)
		)
		(stroke
			(width 0)
			(type solid)
		)
		(fill yes)
		(layer "In13.Cu")
		(net "M_B_CPU1_SB_DQS_DP<5>")
	)
	(gr_poly
		(pts
			(xy 84.92109 -275.908008) (xy 84.821014 -275.808186) (xy 84.720938 -275.908008) (xy 84.720938 -275.95576)
			(xy 84.92109 -275.95576)
		)
		(stroke
			(width 0)
			(type solid)
		)
		(fill yes)
		(layer "In13.Cu")
		(net "M_B_CPU1_SB_DQS_DP<0>")
	)
	(gr_poly
		(pts
			(xy 84.92109 -275.504402) (xy 84.92109 -275.459952) (xy 84.720938 -275.459952) (xy 84.720938 -275.504402)
			(xy 84.821014 -275.604478)
		)
		(stroke
			(width 0)
			(type solid)
		)
		(fill yes)
		(layer "In13.Cu")
		(net "M_B_CPU1_SB_DQ<3>")
	)
	(gr_poly
		(pts
			(xy 84.92109 -274.28825) (xy 84.821014 -274.188174) (xy 84.720938 -274.28825) (xy 84.720938 -274.3327)
			(xy 84.92109 -274.3327)
		)
		(stroke
			(width 0)
			(type solid)
		)
		(fill yes)
		(layer "In13.Cu")
		(net "M_B_CPU1_SB_DQ<0>")
	)
	(gr_poly
		(pts
			(xy 84.92109 -273.88439) (xy 84.92109 -273.83994) (xy 84.720938 -273.83994) (xy 84.720938 -273.88439)
			(xy 84.821014 -273.984466)
		)
		(stroke
			(width 0)
			(type solid)
		)
		(fill yes)
		(layer "In13.Cu")
		(net "M_B_CPU1_SB_CB<3>")
	)
	(gr_poly
		(pts
			(xy 84.92109 -272.668238) (xy 84.821014 -272.568162) (xy 84.720938 -272.668238) (xy 84.720938 -272.712688)
			(xy 84.92109 -272.712688)
		)
		(stroke
			(width 0)
			(type solid)
		)
		(fill yes)
		(layer "In13.Cu")
		(net "M_B_CPU1_SB_CB<0>")
	)
	(gr_poly
		(pts
			(xy 84.92109 -272.264632) (xy 84.92109 -272.21688) (xy 84.720938 -272.21688) (xy 84.720938 -272.264632)
			(xy 84.821014 -272.364454)
		)
		(stroke
			(width 0)
			(type solid)
		)
		(fill yes)
		(layer "In13.Cu")
		(net "M_B_CPU1_SB_DQS_DP<4>")
	)
	(gr_poly
		(pts
			(xy 84.92109 -271.047972) (xy 84.821014 -270.94815) (xy 84.720938 -271.047972) (xy 84.720938 -271.095724)
			(xy 84.92109 -271.095724)
		)
		(stroke
			(width 0)
			(type solid)
		)
		(fill yes)
		(layer "In13.Cu")
		(net "M_B_CPU1_SB_DQS_DP<9>")
	)
	(gr_poly
		(pts
			(xy 84.92109 -270.644366) (xy 84.92109 -270.599916) (xy 84.720938 -270.599916) (xy 84.720938 -270.644366)
			(xy 84.821014 -270.744442)
		)
		(stroke
			(width 0)
			(type solid)
		)
		(fill yes)
		(layer "In13.Cu")
		(net "M_B_CPU1_SB_CB<7>")
	)
	(gr_poly
		(pts
			(xy 84.92109 -269.428214) (xy 84.821014 -269.328138) (xy 84.720938 -269.428214) (xy 84.720938 -269.472664)
			(xy 84.92109 -269.472664)
		)
		(stroke
			(width 0)
			(type solid)
		)
		(fill yes)
		(layer "In13.Cu")
		(net "M_B_CPU1_SB_CB<4>")
	)
	(gr_poly
		(pts
			(xy 84.92109 -267.801852) (xy 84.821014 -267.701776) (xy 84.720938 -267.801852) (xy 84.720938 -267.846302)
			(xy 84.92109 -267.846302)
		)
		(stroke
			(width 0)
			(type solid)
		)
		(fill yes)
		(layer "In13.Cu")
		(net "M_B_CPU1_SB_RSP<0>")
	)
	(gr_poly
		(pts
			(xy 84.92109 -265.78433) (xy 84.92109 -265.73988) (xy 84.720938 -265.73988) (xy 84.720938 -265.78433)
			(xy 84.821014 -265.884406)
		)
		(stroke
			(width 0)
			(type solid)
		)
		(fill yes)
		(layer "In13.Cu")
		(net "M_B_CPU1_SB_CS_N<0>")
	)
	(gr_poly
		(pts
			(xy 84.92109 -264.568178) (xy 84.821014 -264.468102) (xy 84.720938 -264.568178) (xy 84.720938 -264.612628)
			(xy 84.92109 -264.612628)
		)
		(stroke
			(width 0)
			(type solid)
		)
		(fill yes)
		(layer "In13.Cu")
		(net "M_B_CPU1_SB_CA<6>")
	)
	(gr_poly
		(pts
			(xy 84.92109 -264.164318) (xy 84.92109 -264.119868) (xy 84.720938 -264.119868) (xy 84.720938 -264.164318)
			(xy 84.821014 -264.264394)
		)
		(stroke
			(width 0)
			(type solid)
		)
		(fill yes)
		(layer "In13.Cu")
		(net "M_B_CPU1_SB_CA<5>")
	)
	(gr_poly
		(pts
			(xy 84.92109 -262.948166) (xy 84.821014 -262.84809) (xy 84.720938 -262.948166) (xy 84.720938 -262.992616)
			(xy 84.92109 -262.992616)
		)
		(stroke
			(width 0)
			(type solid)
		)
		(fill yes)
		(layer "In13.Cu")
		(net "M_B_CPU1_SB_CA<2>")
	)
	(gr_poly
		(pts
			(xy 84.92109 -262.544306) (xy 84.92109 -262.499856) (xy 84.720938 -262.499856) (xy 84.720938 -262.544306)
			(xy 84.821014 -262.644382)
		)
		(stroke
			(width 0)
			(type solid)
		)
		(fill yes)
		(layer "In13.Cu")
		(net "M_B_CPU1_SB_CA<1>")
	)
	(gr_poly
		(pts
			(xy 85.091016 -256.026158) (xy 84.99094 -255.926336) (xy 84.890864 -256.026158) (xy 84.890864 -256.07391)
			(xy 85.091016 -256.07391)
		)
		(stroke
			(width 0)
			(type solid)
		)
		(fill yes)
		(layer "In13.Cu")
		(net "M_B_CPU1_CLK_DP<0>")
	)
	(gr_poly
		(pts
			(xy 85.091016 -255.622552) (xy 85.091016 -255.578102) (xy 84.890864 -255.578102) (xy 84.890864 -255.622552)
			(xy 84.99094 -255.722628)
		)
		(stroke
			(width 0)
			(type solid)
		)
		(fill yes)
		(layer "In13.Cu")
		(net "M_B_CPU1_SA_PAR")
	)
	(gr_poly
		(pts
			(xy 85.091016 -254.4064) (xy 84.99094 -254.306324) (xy 84.890864 -254.4064) (xy 84.890864 -254.45085)
			(xy 85.091016 -254.45085)
		)
		(stroke
			(width 0)
			(type solid)
		)
		(fill yes)
		(layer "In13.Cu")
		(net "M_B_CPU1_SA_CA<4>")
	)
	(gr_poly
		(pts
			(xy 85.091016 -254.00254) (xy 85.091016 -253.95809) (xy 84.890864 -253.95809) (xy 84.890864 -254.00254)
			(xy 84.99094 -254.102616)
		)
		(stroke
			(width 0)
			(type solid)
		)
		(fill yes)
		(layer "In13.Cu")
		(net "M_B_CPU1_SA_CA<3>")
	)
	(gr_poly
		(pts
			(xy 85.091016 -252.786388) (xy 84.99094 -252.686312) (xy 84.890864 -252.786388) (xy 84.890864 -252.830838)
			(xy 85.091016 -252.830838)
		)
		(stroke
			(width 0)
			(type solid)
		)
		(fill yes)
		(layer "In13.Cu")
		(net "M_B_CPU1_SA_CA<0>")
	)
	(gr_poly
		(pts
			(xy 85.091016 -252.382528) (xy 85.091016 -252.338078) (xy 84.890864 -252.338078) (xy 84.890864 -252.382528)
			(xy 84.99094 -252.482604)
		)
		(stroke
			(width 0)
			(type solid)
		)
		(fill yes)
		(layer "In13.Cu")
		(net "M_B_CPU1_SA_CS_N<1>")
	)
	(gr_poly
		(pts
			(xy 85.091016 -250.762516) (xy 85.091016 -250.718066) (xy 84.890864 -250.718066) (xy 84.890864 -250.762516)
			(xy 84.99094 -250.862592)
		)
		(stroke
			(width 0)
			(type solid)
		)
		(fill yes)
		(layer "In13.Cu")
		(net "M_B_CPU1_RESET_N")
	)
	(gr_poly
		(pts
			(xy 85.091016 -249.142504) (xy 85.091016 -249.098054) (xy 84.890864 -249.098054) (xy 84.890864 -249.142504)
			(xy 84.99094 -249.24258)
		)
		(stroke
			(width 0)
			(type solid)
		)
		(fill yes)
		(layer "In13.Cu")
		(net "M_B_CPU1_SA_CB<7>")
	)
	(gr_poly
		(pts
			(xy 85.091016 -247.926352) (xy 84.99094 -247.826276) (xy 84.890864 -247.926352) (xy 84.890864 -247.970802)
			(xy 85.091016 -247.970802)
		)
		(stroke
			(width 0)
			(type solid)
		)
		(fill yes)
		(layer "In13.Cu")
		(net "M_B_CPU1_SA_CB<4>")
	)
	(gr_poly
		(pts
			(xy 85.091016 -247.522746) (xy 85.091016 -247.474994) (xy 84.890864 -247.474994) (xy 84.890864 -247.522746)
			(xy 84.99094 -247.622568)
		)
		(stroke
			(width 0)
			(type solid)
		)
		(fill yes)
		(layer "In13.Cu")
		(net "M_B_CPU1_SA_DQS_DP<9>")
	)
	(gr_poly
		(pts
			(xy 85.091016 -246.306086) (xy 84.99094 -246.206264) (xy 84.890864 -246.306086) (xy 84.890864 -246.353838)
			(xy 85.091016 -246.353838)
		)
		(stroke
			(width 0)
			(type solid)
		)
		(fill yes)
		(layer "In13.Cu")
		(net "M_B_CPU1_SA_DQS_DP<4>")
	)
	(gr_poly
		(pts
			(xy 85.091016 -245.90248) (xy 85.091016 -245.85803) (xy 84.890864 -245.85803) (xy 84.890864 -245.90248)
			(xy 84.99094 -246.002556)
		)
		(stroke
			(width 0)
			(type solid)
		)
		(fill yes)
		(layer "In13.Cu")
		(net "M_B_CPU1_SA_CB<3>")
	)
	(gr_poly
		(pts
			(xy 85.091016 -244.686328) (xy 84.99094 -244.586252) (xy 84.890864 -244.686328) (xy 84.890864 -244.730778)
			(xy 85.091016 -244.730778)
		)
		(stroke
			(width 0)
			(type solid)
		)
		(fill yes)
		(layer "In13.Cu")
		(net "M_B_CPU1_SA_CB<0>")
	)
	(gr_poly
		(pts
			(xy 85.091016 -244.282468) (xy 85.091016 -244.238018) (xy 84.890864 -244.238018) (xy 84.890864 -244.282468)
			(xy 84.99094 -244.382544)
		)
		(stroke
			(width 0)
			(type solid)
		)
		(fill yes)
		(layer "In13.Cu")
		(net "M_B_CPU1_SA_DQ<31>")
	)
	(gr_poly
		(pts
			(xy 85.091016 -243.066316) (xy 84.99094 -242.96624) (xy 84.890864 -243.066316) (xy 84.890864 -243.110766)
			(xy 85.091016 -243.110766)
		)
		(stroke
			(width 0)
			(type solid)
		)
		(fill yes)
		(layer "In13.Cu")
		(net "M_B_CPU1_SA_DQ<28>")
	)
	(gr_poly
		(pts
			(xy 85.091016 -242.66271) (xy 85.091016 -242.614958) (xy 84.890864 -242.614958) (xy 84.890864 -242.66271)
			(xy 84.99094 -242.762532)
		)
		(stroke
			(width 0)
			(type solid)
		)
		(fill yes)
		(layer "In13.Cu")
		(net "M_B_CPU1_SA_DQS_DP<8>")
	)
	(gr_poly
		(pts
			(xy 85.091016 -241.44605) (xy 84.99094 -241.346228) (xy 84.890864 -241.44605) (xy 84.890864 -241.493802)
			(xy 85.091016 -241.493802)
		)
		(stroke
			(width 0)
			(type solid)
		)
		(fill yes)
		(layer "In13.Cu")
		(net "M_B_CPU1_SA_DQS_DP<3>")
	)
	(gr_poly
		(pts
			(xy 85.091016 -241.042444) (xy 85.091016 -240.997994) (xy 84.890864 -240.997994) (xy 84.890864 -241.042444)
			(xy 84.99094 -241.14252)
		)
		(stroke
			(width 0)
			(type solid)
		)
		(fill yes)
		(layer "In13.Cu")
		(net "M_B_CPU1_SA_DQ<27>")
	)
	(gr_poly
		(pts
			(xy 85.091016 -239.826292) (xy 84.99094 -239.726216) (xy 84.890864 -239.826292) (xy 84.890864 -239.870742)
			(xy 85.091016 -239.870742)
		)
		(stroke
			(width 0)
			(type solid)
		)
		(fill yes)
		(layer "In13.Cu")
		(net "M_B_CPU1_SA_DQ<24>")
	)
	(gr_poly
		(pts
			(xy 85.091016 -239.422432) (xy 85.091016 -239.377982) (xy 84.890864 -239.377982) (xy 84.890864 -239.422432)
			(xy 84.99094 -239.522508)
		)
		(stroke
			(width 0)
			(type solid)
		)
		(fill yes)
		(layer "In13.Cu")
		(net "M_B_CPU1_SA_DQ<23>")
	)
	(gr_poly
		(pts
			(xy 85.091016 -238.20628) (xy 84.99094 -238.106204) (xy 84.890864 -238.20628) (xy 84.890864 -238.25073)
			(xy 85.091016 -238.25073)
		)
		(stroke
			(width 0)
			(type solid)
		)
		(fill yes)
		(layer "In13.Cu")
		(net "M_B_CPU1_SA_DQ<20>")
	)
	(gr_poly
		(pts
			(xy 85.091016 -237.802674) (xy 85.091016 -237.754922) (xy 84.890864 -237.754922) (xy 84.890864 -237.802674)
			(xy 84.99094 -237.902496)
		)
		(stroke
			(width 0)
			(type solid)
		)
		(fill yes)
		(layer "In13.Cu")
		(net "M_B_CPU1_SA_DQS_DP<7>")
	)
	(gr_poly
		(pts
			(xy 85.091016 -236.586014) (xy 84.99094 -236.486192) (xy 84.890864 -236.586014) (xy 84.890864 -236.633766)
			(xy 85.091016 -236.633766)
		)
		(stroke
			(width 0)
			(type solid)
		)
		(fill yes)
		(layer "In13.Cu")
		(net "M_B_CPU1_SA_DQS_DP<2>")
	)
	(gr_poly
		(pts
			(xy 85.091016 -236.182408) (xy 85.091016 -236.137958) (xy 84.890864 -236.137958) (xy 84.890864 -236.182408)
			(xy 84.99094 -236.282484)
		)
		(stroke
			(width 0)
			(type solid)
		)
		(fill yes)
		(layer "In13.Cu")
		(net "M_B_CPU1_SA_DQ<19>")
	)
	(gr_poly
		(pts
			(xy 85.091016 -234.966256) (xy 84.99094 -234.86618) (xy 84.890864 -234.966256) (xy 84.890864 -235.010706)
			(xy 85.091016 -235.010706)
		)
		(stroke
			(width 0)
			(type solid)
		)
		(fill yes)
		(layer "In13.Cu")
		(net "M_B_CPU1_SA_DQ<16>")
	)
	(gr_poly
		(pts
			(xy 85.091016 -234.562396) (xy 85.091016 -234.517946) (xy 84.890864 -234.517946) (xy 84.890864 -234.562396)
			(xy 84.99094 -234.662472)
		)
		(stroke
			(width 0)
			(type solid)
		)
		(fill yes)
		(layer "In13.Cu")
		(net "M_B_CPU1_SA_DQ<15>")
	)
	(gr_poly
		(pts
			(xy 85.091016 -233.346244) (xy 84.99094 -233.246168) (xy 84.890864 -233.346244) (xy 84.890864 -233.390694)
			(xy 85.091016 -233.390694)
		)
		(stroke
			(width 0)
			(type solid)
		)
		(fill yes)
		(layer "In13.Cu")
		(net "M_B_CPU1_SA_DQ<12>")
	)
	(gr_poly
		(pts
			(xy 85.091016 -232.942638) (xy 85.091016 -232.894886) (xy 84.890864 -232.894886) (xy 84.890864 -232.942638)
			(xy 84.99094 -233.04246)
		)
		(stroke
			(width 0)
			(type solid)
		)
		(fill yes)
		(layer "In13.Cu")
		(net "M_B_CPU1_SA_DQS_DP<6>")
	)
	(gr_poly
		(pts
			(xy 85.091016 -231.725978) (xy 84.99094 -231.626156) (xy 84.890864 -231.725978) (xy 84.890864 -231.77373)
			(xy 85.091016 -231.77373)
		)
		(stroke
			(width 0)
			(type solid)
		)
		(fill yes)
		(layer "In13.Cu")
		(net "M_B_CPU1_SA_DQS_DP<1>")
	)
	(gr_poly
		(pts
			(xy 85.091016 -231.322626) (xy 85.091016 -231.278176) (xy 84.890864 -231.278176) (xy 84.890864 -231.322626)
			(xy 84.99094 -231.422702)
		)
		(stroke
			(width 0)
			(type solid)
		)
		(fill yes)
		(layer "In13.Cu")
		(net "M_B_CPU1_SA_DQ<11>")
	)
	(gr_poly
		(pts
			(xy 85.091016 -230.10622) (xy 84.99094 -230.006144) (xy 84.890864 -230.10622) (xy 84.890864 -230.15067)
			(xy 85.091016 -230.15067)
		)
		(stroke
			(width 0)
			(type solid)
		)
		(fill yes)
		(layer "In13.Cu")
		(net "M_B_CPU1_SA_DQ<8>")
	)
	(gr_poly
		(pts
			(xy 85.091016 -229.702614) (xy 85.091016 -229.658164) (xy 84.890864 -229.658164) (xy 84.890864 -229.702614)
			(xy 84.99094 -229.80269)
		)
		(stroke
			(width 0)
			(type solid)
		)
		(fill yes)
		(layer "In13.Cu")
		(net "M_B_CPU1_SA_DQ<7>")
	)
	(gr_poly
		(pts
			(xy 85.091016 -228.486462) (xy 84.99094 -228.386386) (xy 84.890864 -228.486462) (xy 84.890864 -228.530912)
			(xy 85.091016 -228.530912)
		)
		(stroke
			(width 0)
			(type solid)
		)
		(fill yes)
		(layer "In13.Cu")
		(net "M_B_CPU1_SA_DQ<4>")
	)
	(gr_poly
		(pts
			(xy 85.091016 -228.082856) (xy 85.091016 -228.035104) (xy 84.890864 -228.035104) (xy 84.890864 -228.082856)
			(xy 84.99094 -228.182678)
		)
		(stroke
			(width 0)
			(type solid)
		)
		(fill yes)
		(layer "In13.Cu")
		(net "M_B_CPU1_SA_DQS_DP<5>")
	)
	(gr_poly
		(pts
			(xy 85.091016 -226.866196) (xy 84.99094 -226.766374) (xy 84.890864 -226.866196) (xy 84.890864 -226.913948)
			(xy 85.091016 -226.913948)
		)
		(stroke
			(width 0)
			(type solid)
		)
		(fill yes)
		(layer "In13.Cu")
		(net "M_B_CPU1_SA_DQS_DP<0>")
	)
	(gr_poly
		(pts
			(xy 85.091016 -226.46259) (xy 85.091016 -226.41814) (xy 84.890864 -226.41814) (xy 84.890864 -226.46259)
			(xy 84.99094 -226.562666)
		)
		(stroke
			(width 0)
			(type solid)
		)
		(fill yes)
		(layer "In13.Cu")
		(net "M_B_CPU1_SA_DQ<3>")
	)
	(gr_poly
		(pts
			(xy 85.091016 -225.246438) (xy 84.99094 -225.146362) (xy 84.890864 -225.246438) (xy 84.890864 -225.290888)
			(xy 85.091016 -225.290888)
		)
		(stroke
			(width 0)
			(type solid)
		)
		(fill yes)
		(layer "In13.Cu")
		(net "M_B_CPU1_SA_DQ<0>")
	)
	(gr_poly
		(pts
			(xy 85.39099 -292.918134) (xy 85.290914 -292.818058) (xy 85.190838 -292.918134) (xy 85.190838 -292.962584)
			(xy 85.39099 -292.962584)
		)
		(stroke
			(width 0)
			(type solid)
		)
		(fill yes)
		(layer "In13.Cu")
		(net "M_B_CPU1_SB_DQ<29>")
	)
	(gr_poly
		(pts
			(xy 85.39099 -292.514274) (xy 85.39099 -292.469824) (xy 85.190838 -292.469824) (xy 85.190838 -292.514274)
			(xy 85.290914 -292.61435)
		)
		(stroke
			(width 0)
			(type solid)
		)
		(fill yes)
		(layer "In13.Cu")
		(net "M_B_CPU1_SB_DQ<30>")
	)
	(gr_poly
		(pts
			(xy 85.39099 -291.297868) (xy 85.290914 -291.198046) (xy 85.190838 -291.297868) (xy 85.190838 -291.34562)
			(xy 85.39099 -291.34562)
		)
		(stroke
			(width 0)
			(type solid)
		)
		(fill yes)
		(layer "In13.Cu")
		(net "M_B_CPU1_SB_DQS_DN<8>")
	)
	(gr_poly
		(pts
			(xy 85.39099 -290.894516) (xy 85.39099 -290.846764) (xy 85.190838 -290.846764) (xy 85.190838 -290.894516)
			(xy 85.290914 -290.994338)
		)
		(stroke
			(width 0)
			(type solid)
		)
		(fill yes)
		(layer "In13.Cu")
		(net "M_B_CPU1_SB_DQS_DN<3>")
	)
	(gr_poly
		(pts
			(xy 85.39099 -289.67811) (xy 85.290914 -289.578034) (xy 85.190838 -289.67811) (xy 85.190838 -289.72256)
			(xy 85.39099 -289.72256)
		)
		(stroke
			(width 0)
			(type solid)
		)
		(fill yes)
		(layer "In13.Cu")
		(net "M_B_CPU1_SB_DQ<25>")
	)
	(gr_poly
		(pts
			(xy 85.39099 -289.27425) (xy 85.39099 -289.2298) (xy 85.190838 -289.2298) (xy 85.190838 -289.27425)
			(xy 85.290914 -289.374326)
		)
		(stroke
			(width 0)
			(type solid)
		)
		(fill yes)
		(layer "In13.Cu")
		(net "M_B_CPU1_SB_DQ<26>")
	)
	(gr_poly
		(pts
			(xy 85.39099 -288.058098) (xy 85.290914 -287.958022) (xy 85.190838 -288.058098) (xy 85.190838 -288.102548)
			(xy 85.39099 -288.102548)
		)
		(stroke
			(width 0)
			(type solid)
		)
		(fill yes)
		(layer "In13.Cu")
		(net "M_B_CPU1_SB_DQ<21>")
	)
	(gr_poly
		(pts
			(xy 85.39099 -287.654492) (xy 85.39099 -287.610042) (xy 85.190838 -287.610042) (xy 85.190838 -287.654492)
			(xy 85.290914 -287.754568)
		)
		(stroke
			(width 0)
			(type solid)
		)
		(fill yes)
		(layer "In13.Cu")
		(net "M_B_CPU1_SB_DQ<22>")
	)
	(gr_poly
		(pts
			(xy 85.39099 -286.438086) (xy 85.290914 -286.33801) (xy 85.190838 -286.438086) (xy 85.190838 -286.485838)
			(xy 85.39099 -286.485838)
		)
		(stroke
			(width 0)
			(type solid)
		)
		(fill yes)
		(layer "In13.Cu")
		(net "M_B_CPU1_SB_DQS_DN<7>")
	)
	(gr_poly
		(pts
			(xy 85.39099 -286.034734) (xy 85.39099 -285.986982) (xy 85.190838 -285.986982) (xy 85.190838 -286.034734)
			(xy 85.290914 -286.134556)
		)
		(stroke
			(width 0)
			(type solid)
		)
		(fill yes)
		(layer "In13.Cu")
		(net "M_B_CPU1_SB_DQS_DN<2>")
	)
	(gr_poly
		(pts
			(xy 85.39099 -284.818328) (xy 85.290914 -284.718252) (xy 85.190838 -284.818328) (xy 85.190838 -284.862778)
			(xy 85.39099 -284.862778)
		)
		(stroke
			(width 0)
			(type solid)
		)
		(fill yes)
		(layer "In13.Cu")
		(net "M_B_CPU1_SB_DQ<17>")
	)
	(gr_poly
		(pts
			(xy 85.39099 -284.414468) (xy 85.39099 -284.370018) (xy 85.190838 -284.370018) (xy 85.190838 -284.414468)
			(xy 85.290914 -284.514544)
		)
		(stroke
			(width 0)
			(type solid)
		)
		(fill yes)
		(layer "In13.Cu")
		(net "M_B_CPU1_SB_DQ<18>")
	)
	(gr_poly
		(pts
			(xy 85.39099 -283.198316) (xy 85.290914 -283.09824) (xy 85.190838 -283.198316) (xy 85.190838 -283.242766)
			(xy 85.39099 -283.242766)
		)
		(stroke
			(width 0)
			(type solid)
		)
		(fill yes)
		(layer "In13.Cu")
		(net "M_B_CPU1_SB_DQ<13>")
	)
	(gr_poly
		(pts
			(xy 85.39099 -282.794456) (xy 85.39099 -282.750006) (xy 85.190838 -282.750006) (xy 85.190838 -282.794456)
			(xy 85.290914 -282.894532)
		)
		(stroke
			(width 0)
			(type solid)
		)
		(fill yes)
		(layer "In13.Cu")
		(net "M_B_CPU1_SB_DQ<14>")
	)
	(gr_poly
		(pts
			(xy 85.39099 -281.57805) (xy 85.290914 -281.478228) (xy 85.190838 -281.57805) (xy 85.190838 -281.625802)
			(xy 85.39099 -281.625802)
		)
		(stroke
			(width 0)
			(type solid)
		)
		(fill yes)
		(layer "In13.Cu")
		(net "M_B_CPU1_SB_DQS_DN<6>")
	)
	(gr_poly
		(pts
			(xy 85.39099 -281.174698) (xy 85.39099 -281.126946) (xy 85.190838 -281.126946) (xy 85.190838 -281.174698)
			(xy 85.290914 -281.27452)
		)
		(stroke
			(width 0)
			(type solid)
		)
		(fill yes)
		(layer "In13.Cu")
		(net "M_B_CPU1_SB_DQS_DN<1>")
	)
	(gr_poly
		(pts
			(xy 85.39099 -279.958292) (xy 85.290914 -279.858216) (xy 85.190838 -279.958292) (xy 85.190838 -280.002742)
			(xy 85.39099 -280.002742)
		)
		(stroke
			(width 0)
			(type solid)
		)
		(fill yes)
		(layer "In13.Cu")
		(net "M_B_CPU1_SB_DQ<9>")
	)
	(gr_poly
		(pts
			(xy 85.39099 -279.554432) (xy 85.39099 -279.509982) (xy 85.190838 -279.509982) (xy 85.190838 -279.554432)
			(xy 85.290914 -279.654508)
		)
		(stroke
			(width 0)
			(type solid)
		)
		(fill yes)
		(layer "In13.Cu")
		(net "M_B_CPU1_SB_DQ<10>")
	)
	(gr_poly
		(pts
			(xy 85.39099 -278.33828) (xy 85.290914 -278.238204) (xy 85.190838 -278.33828) (xy 85.190838 -278.38273)
			(xy 85.39099 -278.38273)
		)
		(stroke
			(width 0)
			(type solid)
		)
		(fill yes)
		(layer "In13.Cu")
		(net "M_B_CPU1_SB_DQ<5>")
	)
	(gr_poly
		(pts
			(xy 85.39099 -277.93442) (xy 85.39099 -277.88997) (xy 85.190838 -277.88997) (xy 85.190838 -277.93442)
			(xy 85.290914 -278.034496)
		)
		(stroke
			(width 0)
			(type solid)
		)
		(fill yes)
		(layer "In13.Cu")
		(net "M_B_CPU1_SB_DQ<6>")
	)
	(gr_poly
		(pts
			(xy 85.39099 -275.098256) (xy 85.290914 -274.99818) (xy 85.190838 -275.098256) (xy 85.190838 -275.142706)
			(xy 85.39099 -275.142706)
		)
		(stroke
			(width 0)
			(type solid)
		)
		(fill yes)
		(layer "In13.Cu")
		(net "M_B_CPU1_SB_DQ<1>")
	)
	(gr_poly
		(pts
			(xy 85.39099 -274.694396) (xy 85.39099 -274.649946) (xy 85.190838 -274.649946) (xy 85.190838 -274.694396)
			(xy 85.290914 -274.794472)
		)
		(stroke
			(width 0)
			(type solid)
		)
		(fill yes)
		(layer "In13.Cu")
		(net "M_B_CPU1_SB_DQ<2>")
	)
	(gr_poly
		(pts
			(xy 85.39099 -273.478244) (xy 85.290914 -273.378168) (xy 85.190838 -273.478244) (xy 85.190838 -273.522694)
			(xy 85.39099 -273.522694)
		)
		(stroke
			(width 0)
			(type solid)
		)
		(fill yes)
		(layer "In13.Cu")
		(net "M_B_CPU1_SB_CB<1>")
	)
	(gr_poly
		(pts
			(xy 85.39099 -273.074384) (xy 85.39099 -273.029934) (xy 85.190838 -273.029934) (xy 85.190838 -273.074384)
			(xy 85.290914 -273.17446)
		)
		(stroke
			(width 0)
			(type solid)
		)
		(fill yes)
		(layer "In13.Cu")
		(net "M_B_CPU1_SB_CB<2>")
	)
	(gr_poly
		(pts
			(xy 85.39099 -271.857978) (xy 85.290914 -271.758156) (xy 85.190838 -271.857978) (xy 85.190838 -271.90573)
			(xy 85.39099 -271.90573)
		)
		(stroke
			(width 0)
			(type solid)
		)
		(fill yes)
		(layer "In13.Cu")
		(net "M_B_CPU1_SB_DQS_DN<4>")
	)
	(gr_poly
		(pts
			(xy 85.39099 -271.454626) (xy 85.39099 -271.406874) (xy 85.190838 -271.406874) (xy 85.190838 -271.454626)
			(xy 85.290914 -271.554448)
		)
		(stroke
			(width 0)
			(type solid)
		)
		(fill yes)
		(layer "In13.Cu")
		(net "M_B_CPU1_SB_DQS_DN<9>")
	)
	(gr_poly
		(pts
			(xy 85.39099 -270.23822) (xy 85.290914 -270.138144) (xy 85.190838 -270.23822) (xy 85.190838 -270.28267)
			(xy 85.39099 -270.28267)
		)
		(stroke
			(width 0)
			(type solid)
		)
		(fill yes)
		(layer "In13.Cu")
		(net "M_B_CPU1_SB_CB<5>")
	)
	(gr_poly
		(pts
			(xy 85.39099 -269.83436) (xy 85.39099 -269.78991) (xy 85.190838 -269.78991) (xy 85.190838 -269.83436)
			(xy 85.290914 -269.934436)
		)
		(stroke
			(width 0)
			(type solid)
		)
		(fill yes)
		(layer "In13.Cu")
		(net "M_B_CPU1_SB_CB<6>")
	)
	(gr_poly
		(pts
			(xy 85.39099 -266.594336) (xy 85.39099 -266.549886) (xy 85.190838 -266.549886) (xy 85.190838 -266.594336)
			(xy 85.290914 -266.694412)
		)
		(stroke
			(width 0)
			(type solid)
		)
		(fill yes)
		(layer "In13.Cu")
		(net "M_B_CPU1_SB_CS_N<1>")
	)
	(gr_poly
		(pts
			(xy 85.39099 -264.974324) (xy 85.39099 -264.929874) (xy 85.190838 -264.929874) (xy 85.190838 -264.974324)
			(xy 85.290914 -265.0744)
		)
		(stroke
			(width 0)
			(type solid)
		)
		(fill yes)
		(layer "In13.Cu")
		(net "M_B_CPU1_SB_PAR")
	)
	(gr_poly
		(pts
			(xy 85.39099 -263.758172) (xy 85.290914 -263.658096) (xy 85.190838 -263.758172) (xy 85.190838 -263.802622)
			(xy 85.39099 -263.802622)
		)
		(stroke
			(width 0)
			(type solid)
		)
		(fill yes)
		(layer "In13.Cu")
		(net "M_B_CPU1_SB_CA<4>")
	)
	(gr_poly
		(pts
			(xy 85.39099 -263.354312) (xy 85.39099 -263.309862) (xy 85.190838 -263.309862) (xy 85.190838 -263.354312)
			(xy 85.290914 -263.454388)
		)
		(stroke
			(width 0)
			(type solid)
		)
		(fill yes)
		(layer "In13.Cu")
		(net "M_B_CPU1_SB_CA<3>")
	)
	(gr_poly
		(pts
			(xy 85.39099 -262.13816) (xy 85.290914 -262.038084) (xy 85.190838 -262.13816) (xy 85.190838 -262.18261)
			(xy 85.39099 -262.18261)
		)
		(stroke
			(width 0)
			(type solid)
		)
		(fill yes)
		(layer "In13.Cu")
		(net "M_B_CPU1_SB_CA<0>")
	)
	(gr_poly
		(pts
			(xy 85.397086 -266.991846) (xy 85.297264 -266.89177) (xy 85.197188 -266.991846) (xy 85.197188 -267.036296)
			(xy 85.397086 -267.036296)
		)
		(stroke
			(width 0)
			(type solid)
		)
		(fill yes)
		(layer "In13.Cu")
		(net "M_B_CPU1_SA_RSP<0>")
	)
	(gr_poly
		(pts
			(xy 85.398102 -276.718268) (xy 85.29828 -276.618192) (xy 85.198204 -276.718268) (xy 85.198204 -276.765766)
			(xy 85.398102 -276.765766)
		)
		(stroke
			(width 0)
			(type solid)
		)
		(fill yes)
		(layer "In13.Cu")
		(net "M_B_CPU1_SB_DQS_DN<5>")
	)
	(gr_poly
		(pts
			(xy 85.398102 -276.314408) (xy 85.398102 -276.26691) (xy 85.198204 -276.26691) (xy 85.198204 -276.314408)
			(xy 85.29828 -276.414484)
		)
		(stroke
			(width 0)
			(type solid)
		)
		(fill yes)
		(layer "In13.Cu")
		(net "M_B_CPU1_SB_DQS_DN<0>")
	)
	(gr_poly
		(pts
			(xy 85.555074 -227.67671) (xy 85.454998 -227.576634) (xy 85.354922 -227.67671) (xy 85.354922 -227.724208)
			(xy 85.555074 -227.724208)
		)
		(stroke
			(width 0)
			(type solid)
		)
		(fill yes)
		(layer "In13.Cu")
		(net "M_B_CPU1_SA_DQS_DN<5>")
	)
	(gr_poly
		(pts
			(xy 85.56117 -256.432812) (xy 85.56117 -256.38506) (xy 85.361018 -256.38506) (xy 85.361018 -256.432812)
			(xy 85.461094 -256.532634)
		)
		(stroke
			(width 0)
			(type solid)
		)
		(fill yes)
		(layer "In13.Cu")
		(net "M_B_CPU1_CLK_DN<0>")
	)
	(gr_poly
		(pts
			(xy 85.56117 -255.216406) (xy 85.461094 -255.11633) (xy 85.361018 -255.216406) (xy 85.361018 -255.260856)
			(xy 85.56117 -255.260856)
		)
		(stroke
			(width 0)
			(type solid)
		)
		(fill yes)
		(layer "In13.Cu")
		(net "M_B_CPU1_SA_CA<6>")
	)
	(gr_poly
		(pts
			(xy 85.56117 -254.812546) (xy 85.56117 -254.768096) (xy 85.361018 -254.768096) (xy 85.361018 -254.812546)
			(xy 85.461094 -254.912622)
		)
		(stroke
			(width 0)
			(type solid)
		)
		(fill yes)
		(layer "In13.Cu")
		(net "M_B_CPU1_SA_CA<5>")
	)
	(gr_poly
		(pts
			(xy 85.56117 -253.596394) (xy 85.461094 -253.496318) (xy 85.361018 -253.596394) (xy 85.361018 -253.640844)
			(xy 85.56117 -253.640844)
		)
		(stroke
			(width 0)
			(type solid)
		)
		(fill yes)
		(layer "In13.Cu")
		(net "M_B_CPU1_SA_CA<2>")
	)
	(gr_poly
		(pts
			(xy 85.56117 -253.192534) (xy 85.56117 -253.148084) (xy 85.361018 -253.148084) (xy 85.361018 -253.192534)
			(xy 85.461094 -253.29261)
		)
		(stroke
			(width 0)
			(type solid)
		)
		(fill yes)
		(layer "In13.Cu")
		(net "M_B_CPU1_SA_CA<1>")
	)
	(gr_poly
		(pts
			(xy 85.56117 -251.572522) (xy 85.56117 -251.528072) (xy 85.361018 -251.528072) (xy 85.361018 -251.572522)
			(xy 85.461094 -251.672598)
		)
		(stroke
			(width 0)
			(type solid)
		)
		(fill yes)
		(layer "In13.Cu")
		(net "M_B_CPU1_SA_CS_N<0>")
	)
	(gr_poly
		(pts
			(xy 85.56117 -250.35637) (xy 85.461094 -250.256294) (xy 85.361018 -250.35637) (xy 85.361018 -250.40082)
			(xy 85.56117 -250.40082)
		)
		(stroke
			(width 0)
			(type solid)
		)
		(fill yes)
		(layer "In13.Cu")
		(net "M_B_CPU1_ALERT_R_N")
	)
	(gr_poly
		(pts
			(xy 85.56117 -248.736358) (xy 85.461094 -248.636282) (xy 85.361018 -248.736358) (xy 85.361018 -248.780808)
			(xy 85.56117 -248.780808)
		)
		(stroke
			(width 0)
			(type solid)
		)
		(fill yes)
		(layer "In13.Cu")
		(net "M_B_CPU1_SA_CB<5>")
	)
	(gr_poly
		(pts
			(xy 85.56117 -248.332498) (xy 85.56117 -248.288048) (xy 85.361018 -248.288048) (xy 85.361018 -248.332498)
			(xy 85.461094 -248.432574)
		)
		(stroke
			(width 0)
			(type solid)
		)
		(fill yes)
		(layer "In13.Cu")
		(net "M_B_CPU1_SA_CB<6>")
	)
	(gr_poly
		(pts
			(xy 85.56117 -247.116092) (xy 85.461094 -247.01627) (xy 85.361018 -247.116092) (xy 85.361018 -247.163844)
			(xy 85.56117 -247.163844)
		)
		(stroke
			(width 0)
			(type solid)
		)
		(fill yes)
		(layer "In13.Cu")
		(net "M_B_CPU1_SA_DQS_DN<9>")
	)
	(gr_poly
		(pts
			(xy 85.56117 -246.71274) (xy 85.56117 -246.664988) (xy 85.361018 -246.664988) (xy 85.361018 -246.71274)
			(xy 85.461094 -246.812562)
		)
		(stroke
			(width 0)
			(type solid)
		)
		(fill yes)
		(layer "In13.Cu")
		(net "M_B_CPU1_SA_DQS_DN<4>")
	)
	(gr_poly
		(pts
			(xy 85.56117 -245.496334) (xy 85.461094 -245.396258) (xy 85.361018 -245.496334) (xy 85.361018 -245.540784)
			(xy 85.56117 -245.540784)
		)
		(stroke
			(width 0)
			(type solid)
		)
		(fill yes)
		(layer "In13.Cu")
		(net "M_B_CPU1_SA_CB<1>")
	)
	(gr_poly
		(pts
			(xy 85.56117 -245.092474) (xy 85.56117 -245.048024) (xy 85.361018 -245.048024) (xy 85.361018 -245.092474)
			(xy 85.461094 -245.19255)
		)
		(stroke
			(width 0)
			(type solid)
		)
		(fill yes)
		(layer "In13.Cu")
		(net "M_B_CPU1_SA_CB<2>")
	)
	(gr_poly
		(pts
			(xy 85.56117 -243.876322) (xy 85.461094 -243.776246) (xy 85.361018 -243.876322) (xy 85.361018 -243.920772)
			(xy 85.56117 -243.920772)
		)
		(stroke
			(width 0)
			(type solid)
		)
		(fill yes)
		(layer "In13.Cu")
		(net "M_B_CPU1_SA_DQ<29>")
	)
	(gr_poly
		(pts
			(xy 85.56117 -243.472462) (xy 85.56117 -243.428012) (xy 85.361018 -243.428012) (xy 85.361018 -243.472462)
			(xy 85.461094 -243.572538)
		)
		(stroke
			(width 0)
			(type solid)
		)
		(fill yes)
		(layer "In13.Cu")
		(net "M_B_CPU1_SA_DQ<30>")
	)
	(gr_poly
		(pts
			(xy 85.56117 -242.256056) (xy 85.461094 -242.156234) (xy 85.361018 -242.256056) (xy 85.361018 -242.303808)
			(xy 85.56117 -242.303808)
		)
		(stroke
			(width 0)
			(type solid)
		)
		(fill yes)
		(layer "In13.Cu")
		(net "M_B_CPU1_SA_DQS_DN<8>")
	)
	(gr_poly
		(pts
			(xy 85.56117 -241.852704) (xy 85.56117 -241.804952) (xy 85.361018 -241.804952) (xy 85.361018 -241.852704)
			(xy 85.461094 -241.952526)
		)
		(stroke
			(width 0)
			(type solid)
		)
		(fill yes)
		(layer "In13.Cu")
		(net "M_B_CPU1_SA_DQS_DN<3>")
	)
	(gr_poly
		(pts
			(xy 85.56117 -240.636298) (xy 85.461094 -240.536222) (xy 85.361018 -240.636298) (xy 85.361018 -240.680748)
			(xy 85.56117 -240.680748)
		)
		(stroke
			(width 0)
			(type solid)
		)
		(fill yes)
		(layer "In13.Cu")
		(net "M_B_CPU1_SA_DQ<25>")
	)
	(gr_poly
		(pts
			(xy 85.56117 -240.232438) (xy 85.56117 -240.187988) (xy 85.361018 -240.187988) (xy 85.361018 -240.232438)
			(xy 85.461094 -240.332514)
		)
		(stroke
			(width 0)
			(type solid)
		)
		(fill yes)
		(layer "In13.Cu")
		(net "M_B_CPU1_SA_DQ<26>")
	)
	(gr_poly
		(pts
			(xy 85.56117 -239.016286) (xy 85.461094 -238.91621) (xy 85.361018 -239.016286) (xy 85.361018 -239.060736)
			(xy 85.56117 -239.060736)
		)
		(stroke
			(width 0)
			(type solid)
		)
		(fill yes)
		(layer "In13.Cu")
		(net "M_B_CPU1_SA_DQ<21>")
	)
	(gr_poly
		(pts
			(xy 85.56117 -238.612426) (xy 85.56117 -238.567976) (xy 85.361018 -238.567976) (xy 85.361018 -238.612426)
			(xy 85.461094 -238.712502)
		)
		(stroke
			(width 0)
			(type solid)
		)
		(fill yes)
		(layer "In13.Cu")
		(net "M_B_CPU1_SA_DQ<22>")
	)
	(gr_poly
		(pts
			(xy 85.56117 -237.39602) (xy 85.461094 -237.296198) (xy 85.361018 -237.39602) (xy 85.361018 -237.443772)
			(xy 85.56117 -237.443772)
		)
		(stroke
			(width 0)
			(type solid)
		)
		(fill yes)
		(layer "In13.Cu")
		(net "M_B_CPU1_SA_DQS_DN<7>")
	)
	(gr_poly
		(pts
			(xy 85.56117 -236.992668) (xy 85.56117 -236.944916) (xy 85.361018 -236.944916) (xy 85.361018 -236.992668)
			(xy 85.461094 -237.09249)
		)
		(stroke
			(width 0)
			(type solid)
		)
		(fill yes)
		(layer "In13.Cu")
		(net "M_B_CPU1_SA_DQS_DN<2>")
	)
	(gr_poly
		(pts
			(xy 85.56117 -235.776262) (xy 85.461094 -235.676186) (xy 85.361018 -235.776262) (xy 85.361018 -235.820712)
			(xy 85.56117 -235.820712)
		)
		(stroke
			(width 0)
			(type solid)
		)
		(fill yes)
		(layer "In13.Cu")
		(net "M_B_CPU1_SA_DQ<17>")
	)
	(gr_poly
		(pts
			(xy 85.56117 -235.372402) (xy 85.56117 -235.327952) (xy 85.361018 -235.327952) (xy 85.361018 -235.372402)
			(xy 85.461094 -235.472478)
		)
		(stroke
			(width 0)
			(type solid)
		)
		(fill yes)
		(layer "In13.Cu")
		(net "M_B_CPU1_SA_DQ<18>")
	)
	(gr_poly
		(pts
			(xy 85.56117 -234.15625) (xy 85.461094 -234.056174) (xy 85.361018 -234.15625) (xy 85.361018 -234.2007)
			(xy 85.56117 -234.2007)
		)
		(stroke
			(width 0)
			(type solid)
		)
		(fill yes)
		(layer "In13.Cu")
		(net "M_B_CPU1_SA_DQ<13>")
	)
	(gr_poly
		(pts
			(xy 85.56117 -233.75239) (xy 85.56117 -233.70794) (xy 85.361018 -233.70794) (xy 85.361018 -233.75239)
			(xy 85.461094 -233.852466)
		)
		(stroke
			(width 0)
			(type solid)
		)
		(fill yes)
		(layer "In13.Cu")
		(net "M_B_CPU1_SA_DQ<14>")
	)
	(gr_poly
		(pts
			(xy 85.56117 -232.535984) (xy 85.461094 -232.436162) (xy 85.361018 -232.535984) (xy 85.361018 -232.583736)
			(xy 85.56117 -232.583736)
		)
		(stroke
			(width 0)
			(type solid)
		)
		(fill yes)
		(layer "In13.Cu")
		(net "M_B_CPU1_SA_DQS_DN<6>")
	)
	(gr_poly
		(pts
			(xy 85.56117 -232.132632) (xy 85.56117 -232.08488) (xy 85.361018 -232.08488) (xy 85.361018 -232.132632)
			(xy 85.461094 -232.232454)
		)
		(stroke
			(width 0)
			(type solid)
		)
		(fill yes)
		(layer "In13.Cu")
		(net "M_B_CPU1_SA_DQS_DN<1>")
	)
	(gr_poly
		(pts
			(xy 85.56117 -230.916226) (xy 85.461094 -230.81615) (xy 85.361018 -230.916226) (xy 85.361018 -230.960676)
			(xy 85.56117 -230.960676)
		)
		(stroke
			(width 0)
			(type solid)
		)
		(fill yes)
		(layer "In13.Cu")
		(net "M_B_CPU1_SA_DQ<9>")
	)
	(gr_poly
		(pts
			(xy 85.56117 -230.51262) (xy 85.56117 -230.46817) (xy 85.361018 -230.46817) (xy 85.361018 -230.51262)
			(xy 85.461094 -230.612696)
		)
		(stroke
			(width 0)
			(type solid)
		)
		(fill yes)
		(layer "In13.Cu")
		(net "M_B_CPU1_SA_DQ<10>")
	)
	(gr_poly
		(pts
			(xy 85.56117 -229.296214) (xy 85.461094 -229.196138) (xy 85.361018 -229.296214) (xy 85.361018 -229.340664)
			(xy 85.56117 -229.340664)
		)
		(stroke
			(width 0)
			(type solid)
		)
		(fill yes)
		(layer "In13.Cu")
		(net "M_B_CPU1_SA_DQ<5>")
	)
	(gr_poly
		(pts
			(xy 85.56117 -228.892608) (xy 85.56117 -228.848158) (xy 85.361018 -228.848158) (xy 85.361018 -228.892608)
			(xy 85.461094 -228.992684)
		)
		(stroke
			(width 0)
			(type solid)
		)
		(fill yes)
		(layer "In13.Cu")
		(net "M_B_CPU1_SA_DQ<6>")
	)
	(gr_poly
		(pts
			(xy 85.56117 -227.27285) (xy 85.56117 -227.225098) (xy 85.361018 -227.225098) (xy 85.361018 -227.27285)
			(xy 85.461094 -227.372672)
		)
		(stroke
			(width 0)
			(type solid)
		)
		(fill yes)
		(layer "In13.Cu")
		(net "M_B_CPU1_SA_DQS_DN<0>")
	)
	(gr_poly
		(pts
			(xy 85.56117 -226.056444) (xy 85.461094 -225.956368) (xy 85.361018 -226.056444) (xy 85.361018 -226.100894)
			(xy 85.56117 -226.100894)
		)
		(stroke
			(width 0)
			(type solid)
		)
		(fill yes)
		(layer "In13.Cu")
		(net "M_B_CPU1_SA_DQ<1>")
	)
	(gr_poly
		(pts
			(xy 85.56117 -225.652584) (xy 85.56117 -225.608134) (xy 85.361018 -225.608134) (xy 85.361018 -225.652584)
			(xy 85.461094 -225.75266)
		)
		(stroke
			(width 0)
			(type solid)
		)
		(fill yes)
		(layer "In13.Cu")
		(net "M_B_CPU1_SA_DQ<2>")
	)
	(gr_poly
		(pts
			(xy 85.854794 -267.801852) (xy 85.754718 -267.701776) (xy 85.654896 -267.801852) (xy 85.654896 -267.846302)
			(xy 85.854794 -267.846302)
		)
		(stroke
			(width 0)
			(type solid)
		)
		(fill yes)
		(layer "In13.Cu")
		(net "M_B_CPU1_SB_RSP<0>")
	)
	(gr_poly
		(pts
			(xy 85.861144 -293.32428) (xy 85.861144 -293.27983) (xy 85.660992 -293.27983) (xy 85.660992 -293.32428)
			(xy 85.761068 -293.424356)
		)
		(stroke
			(width 0)
			(type solid)
		)
		(fill yes)
		(layer "In13.Cu")
		(net "M_B_CPU1_SB_DQ<31>")
	)
	(gr_poly
		(pts
			(xy 85.861144 -292.108128) (xy 85.761068 -292.008052) (xy 85.660992 -292.108128) (xy 85.660992 -292.152578)
			(xy 85.861144 -292.152578)
		)
		(stroke
			(width 0)
			(type solid)
		)
		(fill yes)
		(layer "In13.Cu")
		(net "M_B_CPU1_SB_DQ<28>")
	)
	(gr_poly
		(pts
			(xy 85.861144 -291.704522) (xy 85.861144 -291.65677) (xy 85.660992 -291.65677) (xy 85.660992 -291.704522)
			(xy 85.761068 -291.804344)
		)
		(stroke
			(width 0)
			(type solid)
		)
		(fill yes)
		(layer "In13.Cu")
		(net "M_B_CPU1_SB_DQS_DP<8>")
	)
	(gr_poly
		(pts
			(xy 85.861144 -290.487862) (xy 85.761068 -290.38804) (xy 85.660992 -290.487862) (xy 85.660992 -290.535614)
			(xy 85.861144 -290.535614)
		)
		(stroke
			(width 0)
			(type solid)
		)
		(fill yes)
		(layer "In13.Cu")
		(net "M_B_CPU1_SB_DQS_DP<3>")
	)
	(gr_poly
		(pts
			(xy 85.861144 -290.084256) (xy 85.861144 -290.039806) (xy 85.660992 -290.039806) (xy 85.660992 -290.084256)
			(xy 85.761068 -290.184332)
		)
		(stroke
			(width 0)
			(type solid)
		)
		(fill yes)
		(layer "In13.Cu")
		(net "M_B_CPU1_SB_DQ<27>")
	)
	(gr_poly
		(pts
			(xy 85.861144 -288.868104) (xy 85.761068 -288.768028) (xy 85.660992 -288.868104) (xy 85.660992 -288.912554)
			(xy 85.861144 -288.912554)
		)
		(stroke
			(width 0)
			(type solid)
		)
		(fill yes)
		(layer "In13.Cu")
		(net "M_B_CPU1_SB_DQ<24>")
	)
	(gr_poly
		(pts
			(xy 85.861144 -288.464498) (xy 85.861144 -288.420048) (xy 85.660992 -288.420048) (xy 85.660992 -288.464498)
			(xy 85.761068 -288.564574)
		)
		(stroke
			(width 0)
			(type solid)
		)
		(fill yes)
		(layer "In13.Cu")
		(net "M_B_CPU1_SB_DQ<23>")
	)
	(gr_poly
		(pts
			(xy 85.861144 -287.248092) (xy 85.761068 -287.148016) (xy 85.660992 -287.248092) (xy 85.660992 -287.292542)
			(xy 85.861144 -287.292542)
		)
		(stroke
			(width 0)
			(type solid)
		)
		(fill yes)
		(layer "In13.Cu")
		(net "M_B_CPU1_SB_DQ<20>")
	)
	(gr_poly
		(pts
			(xy 85.861144 -286.844486) (xy 85.861144 -286.796734) (xy 85.660992 -286.796734) (xy 85.660992 -286.844486)
			(xy 85.761068 -286.944562)
		)
		(stroke
			(width 0)
			(type solid)
		)
		(fill yes)
		(layer "In13.Cu")
		(net "M_B_CPU1_SB_DQS_DP<7>")
	)
	(gr_poly
		(pts
			(xy 85.861144 -285.62808) (xy 85.761068 -285.528258) (xy 85.660992 -285.62808) (xy 85.660992 -285.675832)
			(xy 85.861144 -285.675832)
		)
		(stroke
			(width 0)
			(type solid)
		)
		(fill yes)
		(layer "In13.Cu")
		(net "M_B_CPU1_SB_DQS_DP<2>")
	)
	(gr_poly
		(pts
			(xy 85.861144 -285.224474) (xy 85.861144 -285.180024) (xy 85.660992 -285.180024) (xy 85.660992 -285.224474)
			(xy 85.761068 -285.32455)
		)
		(stroke
			(width 0)
			(type solid)
		)
		(fill yes)
		(layer "In13.Cu")
		(net "M_B_CPU1_SB_DQ<19>")
	)
	(gr_poly
		(pts
			(xy 85.861144 -284.008322) (xy 85.761068 -283.908246) (xy 85.660992 -284.008322) (xy 85.660992 -284.052772)
			(xy 85.861144 -284.052772)
		)
		(stroke
			(width 0)
			(type solid)
		)
		(fill yes)
		(layer "In13.Cu")
		(net "M_B_CPU1_SB_DQ<16>")
	)
	(gr_poly
		(pts
			(xy 85.861144 -283.604462) (xy 85.861144 -283.560012) (xy 85.660992 -283.560012) (xy 85.660992 -283.604462)
			(xy 85.761068 -283.704538)
		)
		(stroke
			(width 0)
			(type solid)
		)
		(fill yes)
		(layer "In13.Cu")
		(net "M_B_CPU1_SB_DQ<15>")
	)
	(gr_poly
		(pts
			(xy 85.861144 -282.38831) (xy 85.761068 -282.288234) (xy 85.660992 -282.38831) (xy 85.660992 -282.43276)
			(xy 85.861144 -282.43276)
		)
		(stroke
			(width 0)
			(type solid)
		)
		(fill yes)
		(layer "In13.Cu")
		(net "M_B_CPU1_SB_DQ<12>")
	)
	(gr_poly
		(pts
			(xy 85.861144 -281.984704) (xy 85.861144 -281.936952) (xy 85.660992 -281.936952) (xy 85.660992 -281.984704)
			(xy 85.761068 -282.084526)
		)
		(stroke
			(width 0)
			(type solid)
		)
		(fill yes)
		(layer "In13.Cu")
		(net "M_B_CPU1_SB_DQS_DP<6>")
	)
	(gr_poly
		(pts
			(xy 85.861144 -280.768044) (xy 85.761068 -280.668222) (xy 85.660992 -280.768044) (xy 85.660992 -280.815796)
			(xy 85.861144 -280.815796)
		)
		(stroke
			(width 0)
			(type solid)
		)
		(fill yes)
		(layer "In13.Cu")
		(net "M_B_CPU1_SB_DQS_DP<1>")
	)
	(gr_poly
		(pts
			(xy 85.861144 -280.364438) (xy 85.861144 -280.319988) (xy 85.660992 -280.319988) (xy 85.660992 -280.364438)
			(xy 85.761068 -280.464514)
		)
		(stroke
			(width 0)
			(type solid)
		)
		(fill yes)
		(layer "In13.Cu")
		(net "M_B_CPU1_SB_DQ<11>")
	)
	(gr_poly
		(pts
			(xy 85.861144 -279.148286) (xy 85.761068 -279.04821) (xy 85.660992 -279.148286) (xy 85.660992 -279.192736)
			(xy 85.861144 -279.192736)
		)
		(stroke
			(width 0)
			(type solid)
		)
		(fill yes)
		(layer "In13.Cu")
		(net "M_B_CPU1_SB_DQ<8>")
	)
	(gr_poly
		(pts
			(xy 85.861144 -278.744426) (xy 85.861144 -278.699976) (xy 85.660992 -278.699976) (xy 85.660992 -278.744426)
			(xy 85.761068 -278.844502)
		)
		(stroke
			(width 0)
			(type solid)
		)
		(fill yes)
		(layer "In13.Cu")
		(net "M_B_CPU1_SB_DQ<7>")
	)
	(gr_poly
		(pts
			(xy 85.861144 -277.528274) (xy 85.761068 -277.428198) (xy 85.660992 -277.528274) (xy 85.660992 -277.572724)
			(xy 85.861144 -277.572724)
		)
		(stroke
			(width 0)
			(type solid)
		)
		(fill yes)
		(layer "In13.Cu")
		(net "M_B_CPU1_SB_DQ<4>")
	)
	(gr_poly
		(pts
			(xy 85.861144 -277.124668) (xy 85.861144 -277.076916) (xy 85.660992 -277.076916) (xy 85.660992 -277.124668)
			(xy 85.761068 -277.22449)
		)
		(stroke
			(width 0)
			(type solid)
		)
		(fill yes)
		(layer "In13.Cu")
		(net "M_B_CPU1_SB_DQS_DP<5>")
	)
	(gr_poly
		(pts
			(xy 85.861144 -275.908008) (xy 85.761068 -275.808186) (xy 85.660992 -275.908008) (xy 85.660992 -275.95576)
			(xy 85.861144 -275.95576)
		)
		(stroke
			(width 0)
			(type solid)
		)
		(fill yes)
		(layer "In13.Cu")
		(net "M_B_CPU1_SB_DQS_DP<0>")
	)
	(gr_poly
		(pts
			(xy 85.861144 -275.504402) (xy 85.861144 -275.459952) (xy 85.660992 -275.459952) (xy 85.660992 -275.504402)
			(xy 85.761068 -275.604478)
		)
		(stroke
			(width 0)
			(type solid)
		)
		(fill yes)
		(layer "In13.Cu")
		(net "M_B_CPU1_SB_DQ<3>")
	)
	(gr_poly
		(pts
			(xy 85.861144 -274.28825) (xy 85.761068 -274.188174) (xy 85.660992 -274.28825) (xy 85.660992 -274.3327)
			(xy 85.861144 -274.3327)
		)
		(stroke
			(width 0)
			(type solid)
		)
		(fill yes)
		(layer "In13.Cu")
		(net "M_B_CPU1_SB_DQ<0>")
	)
	(gr_poly
		(pts
			(xy 85.861144 -273.88439) (xy 85.861144 -273.83994) (xy 85.660992 -273.83994) (xy 85.660992 -273.88439)
			(xy 85.761068 -273.984466)
		)
		(stroke
			(width 0)
			(type solid)
		)
		(fill yes)
		(layer "In13.Cu")
		(net "M_B_CPU1_SB_CB<3>")
	)
	(gr_poly
		(pts
			(xy 85.861144 -272.668238) (xy 85.761068 -272.568162) (xy 85.660992 -272.668238) (xy 85.660992 -272.712688)
			(xy 85.861144 -272.712688)
		)
		(stroke
			(width 0)
			(type solid)
		)
		(fill yes)
		(layer "In13.Cu")
		(net "M_B_CPU1_SB_CB<0>")
	)
	(gr_poly
		(pts
			(xy 85.861144 -272.264632) (xy 85.861144 -272.21688) (xy 85.660992 -272.21688) (xy 85.660992 -272.264632)
			(xy 85.761068 -272.364454)
		)
		(stroke
			(width 0)
			(type solid)
		)
		(fill yes)
		(layer "In13.Cu")
		(net "M_B_CPU1_SB_DQS_DP<4>")
	)
	(gr_poly
		(pts
			(xy 85.861144 -271.047972) (xy 85.761068 -270.94815) (xy 85.660992 -271.047972) (xy 85.660992 -271.095724)
			(xy 85.861144 -271.095724)
		)
		(stroke
			(width 0)
			(type solid)
		)
		(fill yes)
		(layer "In13.Cu")
		(net "M_B_CPU1_SB_DQS_DP<9>")
	)
	(gr_poly
		(pts
			(xy 85.861144 -270.644366) (xy 85.861144 -270.599916) (xy 85.660992 -270.599916) (xy 85.660992 -270.644366)
			(xy 85.761068 -270.744442)
		)
		(stroke
			(width 0)
			(type solid)
		)
		(fill yes)
		(layer "In13.Cu")
		(net "M_B_CPU1_SB_CB<7>")
	)
	(gr_poly
		(pts
			(xy 85.861144 -269.428214) (xy 85.761068 -269.328138) (xy 85.660992 -269.428214) (xy 85.660992 -269.472664)
			(xy 85.861144 -269.472664)
		)
		(stroke
			(width 0)
			(type solid)
		)
		(fill yes)
		(layer "In13.Cu")
		(net "M_B_CPU1_SB_CB<4>")
	)
	(gr_poly
		(pts
			(xy 85.861144 -265.78433) (xy 85.861144 -265.73988) (xy 85.660992 -265.73988) (xy 85.660992 -265.78433)
			(xy 85.761068 -265.884406)
		)
		(stroke
			(width 0)
			(type solid)
		)
		(fill yes)
		(layer "In13.Cu")
		(net "M_B_CPU1_SB_CS_N<0>")
	)
	(gr_poly
		(pts
			(xy 85.861144 -264.568178) (xy 85.761068 -264.468102) (xy 85.660992 -264.568178) (xy 85.660992 -264.612628)
			(xy 85.861144 -264.612628)
		)
		(stroke
			(width 0)
			(type solid)
		)
		(fill yes)
		(layer "In13.Cu")
		(net "M_B_CPU1_SB_CA<6>")
	)
	(gr_poly
		(pts
			(xy 85.861144 -264.164318) (xy 85.861144 -264.119868) (xy 85.660992 -264.119868) (xy 85.660992 -264.164318)
			(xy 85.761068 -264.264394)
		)
		(stroke
			(width 0)
			(type solid)
		)
		(fill yes)
		(layer "In13.Cu")
		(net "M_B_CPU1_SB_CA<5>")
	)
	(gr_poly
		(pts
			(xy 85.861144 -262.948166) (xy 85.761068 -262.84809) (xy 85.660992 -262.948166) (xy 85.660992 -262.992616)
			(xy 85.861144 -262.992616)
		)
		(stroke
			(width 0)
			(type solid)
		)
		(fill yes)
		(layer "In13.Cu")
		(net "M_B_CPU1_SB_CA<2>")
	)
	(gr_poly
		(pts
			(xy 85.861144 -262.544306) (xy 85.861144 -262.499856) (xy 85.660992 -262.499856) (xy 85.660992 -262.544306)
			(xy 85.761068 -262.644382)
		)
		(stroke
			(width 0)
			(type solid)
		)
		(fill yes)
		(layer "In13.Cu")
		(net "M_B_CPU1_SB_CA<1>")
	)
	(gr_poly
		(pts
			(xy 86.03107 -256.026158) (xy 85.930994 -255.926336) (xy 85.830918 -256.026158) (xy 85.830918 -256.07391)
			(xy 86.03107 -256.07391)
		)
		(stroke
			(width 0)
			(type solid)
		)
		(fill yes)
		(layer "In13.Cu")
		(net "M_B_CPU1_CLK_DP<0>")
	)
	(gr_poly
		(pts
			(xy 86.03107 -255.622552) (xy 86.03107 -255.578102) (xy 85.830918 -255.578102) (xy 85.830918 -255.622552)
			(xy 85.930994 -255.722628)
		)
		(stroke
			(width 0)
			(type solid)
		)
		(fill yes)
		(layer "In13.Cu")
		(net "M_B_CPU1_SA_PAR")
	)
	(gr_poly
		(pts
			(xy 86.03107 -254.4064) (xy 85.930994 -254.306324) (xy 85.830918 -254.4064) (xy 85.830918 -254.45085)
			(xy 86.03107 -254.45085)
		)
		(stroke
			(width 0)
			(type solid)
		)
		(fill yes)
		(layer "In13.Cu")
		(net "M_B_CPU1_SA_CA<4>")
	)
	(gr_poly
		(pts
			(xy 86.03107 -254.00254) (xy 86.03107 -253.95809) (xy 85.830918 -253.95809) (xy 85.830918 -254.00254)
			(xy 85.930994 -254.102616)
		)
		(stroke
			(width 0)
			(type solid)
		)
		(fill yes)
		(layer "In13.Cu")
		(net "M_B_CPU1_SA_CA<3>")
	)
	(gr_poly
		(pts
			(xy 86.03107 -252.786388) (xy 85.930994 -252.686312) (xy 85.830918 -252.786388) (xy 85.830918 -252.830838)
			(xy 86.03107 -252.830838)
		)
		(stroke
			(width 0)
			(type solid)
		)
		(fill yes)
		(layer "In13.Cu")
		(net "M_B_CPU1_SA_CA<0>")
	)
	(gr_poly
		(pts
			(xy 86.03107 -252.382528) (xy 86.03107 -252.338078) (xy 85.830918 -252.338078) (xy 85.830918 -252.382528)
			(xy 85.930994 -252.482604)
		)
		(stroke
			(width 0)
			(type solid)
		)
		(fill yes)
		(layer "In13.Cu")
		(net "M_B_CPU1_SA_CS_N<1>")
	)
	(gr_poly
		(pts
			(xy 86.03107 -250.762516) (xy 86.03107 -250.718066) (xy 85.830918 -250.718066) (xy 85.830918 -250.762516)
			(xy 85.930994 -250.862592)
		)
		(stroke
			(width 0)
			(type solid)
		)
		(fill yes)
		(layer "In13.Cu")
		(net "M_B_CPU1_RESET_N")
	)
	(gr_poly
		(pts
			(xy 86.03107 -249.142504) (xy 86.03107 -249.098054) (xy 85.830918 -249.098054) (xy 85.830918 -249.142504)
			(xy 85.930994 -249.24258)
		)
		(stroke
			(width 0)
			(type solid)
		)
		(fill yes)
		(layer "In13.Cu")
		(net "M_B_CPU1_SA_CB<7>")
	)
	(gr_poly
		(pts
			(xy 86.03107 -247.926352) (xy 85.930994 -247.826276) (xy 85.830918 -247.926352) (xy 85.830918 -247.970802)
			(xy 86.03107 -247.970802)
		)
		(stroke
			(width 0)
			(type solid)
		)
		(fill yes)
		(layer "In13.Cu")
		(net "M_B_CPU1_SA_CB<4>")
	)
	(gr_poly
		(pts
			(xy 86.03107 -247.522746) (xy 86.03107 -247.474994) (xy 85.830918 -247.474994) (xy 85.830918 -247.522746)
			(xy 85.930994 -247.622568)
		)
		(stroke
			(width 0)
			(type solid)
		)
		(fill yes)
		(layer "In13.Cu")
		(net "M_B_CPU1_SA_DQS_DP<9>")
	)
	(gr_poly
		(pts
			(xy 86.03107 -246.306086) (xy 85.930994 -246.206264) (xy 85.830918 -246.306086) (xy 85.830918 -246.353838)
			(xy 86.03107 -246.353838)
		)
		(stroke
			(width 0)
			(type solid)
		)
		(fill yes)
		(layer "In13.Cu")
		(net "M_B_CPU1_SA_DQS_DP<4>")
	)
	(gr_poly
		(pts
			(xy 86.03107 -245.90248) (xy 86.03107 -245.85803) (xy 85.830918 -245.85803) (xy 85.830918 -245.90248)
			(xy 85.930994 -246.002556)
		)
		(stroke
			(width 0)
			(type solid)
		)
		(fill yes)
		(layer "In13.Cu")
		(net "M_B_CPU1_SA_CB<3>")
	)
	(gr_poly
		(pts
			(xy 86.03107 -244.686328) (xy 85.930994 -244.586252) (xy 85.830918 -244.686328) (xy 85.830918 -244.730778)
			(xy 86.03107 -244.730778)
		)
		(stroke
			(width 0)
			(type solid)
		)
		(fill yes)
		(layer "In13.Cu")
		(net "M_B_CPU1_SA_CB<0>")
	)
	(gr_poly
		(pts
			(xy 86.03107 -244.282468) (xy 86.03107 -244.238018) (xy 85.830918 -244.238018) (xy 85.830918 -244.282468)
			(xy 85.930994 -244.382544)
		)
		(stroke
			(width 0)
			(type solid)
		)
		(fill yes)
		(layer "In13.Cu")
		(net "M_B_CPU1_SA_DQ<31>")
	)
	(gr_poly
		(pts
			(xy 86.03107 -243.066316) (xy 85.930994 -242.96624) (xy 85.830918 -243.066316) (xy 85.830918 -243.110766)
			(xy 86.03107 -243.110766)
		)
		(stroke
			(width 0)
			(type solid)
		)
		(fill yes)
		(layer "In13.Cu")
		(net "M_B_CPU1_SA_DQ<28>")
	)
	(gr_poly
		(pts
			(xy 86.03107 -242.66271) (xy 86.03107 -242.614958) (xy 85.830918 -242.614958) (xy 85.830918 -242.66271)
			(xy 85.930994 -242.762532)
		)
		(stroke
			(width 0)
			(type solid)
		)
		(fill yes)
		(layer "In13.Cu")
		(net "M_B_CPU1_SA_DQS_DP<8>")
	)
	(gr_poly
		(pts
			(xy 86.03107 -241.44605) (xy 85.930994 -241.346228) (xy 85.830918 -241.44605) (xy 85.830918 -241.493802)
			(xy 86.03107 -241.493802)
		)
		(stroke
			(width 0)
			(type solid)
		)
		(fill yes)
		(layer "In13.Cu")
		(net "M_B_CPU1_SA_DQS_DP<3>")
	)
	(gr_poly
		(pts
			(xy 86.03107 -241.042444) (xy 86.03107 -240.997994) (xy 85.830918 -240.997994) (xy 85.830918 -241.042444)
			(xy 85.930994 -241.14252)
		)
		(stroke
			(width 0)
			(type solid)
		)
		(fill yes)
		(layer "In13.Cu")
		(net "M_B_CPU1_SA_DQ<27>")
	)
	(gr_poly
		(pts
			(xy 86.03107 -239.826292) (xy 85.930994 -239.726216) (xy 85.830918 -239.826292) (xy 85.830918 -239.870742)
			(xy 86.03107 -239.870742)
		)
		(stroke
			(width 0)
			(type solid)
		)
		(fill yes)
		(layer "In13.Cu")
		(net "M_B_CPU1_SA_DQ<24>")
	)
	(gr_poly
		(pts
			(xy 86.03107 -239.422432) (xy 86.03107 -239.377982) (xy 85.830918 -239.377982) (xy 85.830918 -239.422432)
			(xy 85.930994 -239.522508)
		)
		(stroke
			(width 0)
			(type solid)
		)
		(fill yes)
		(layer "In13.Cu")
		(net "M_B_CPU1_SA_DQ<23>")
	)
	(gr_poly
		(pts
			(xy 86.03107 -238.20628) (xy 85.930994 -238.106204) (xy 85.830918 -238.20628) (xy 85.830918 -238.25073)
			(xy 86.03107 -238.25073)
		)
		(stroke
			(width 0)
			(type solid)
		)
		(fill yes)
		(layer "In13.Cu")
		(net "M_B_CPU1_SA_DQ<20>")
	)
	(gr_poly
		(pts
			(xy 86.03107 -237.802674) (xy 86.03107 -237.754922) (xy 85.830918 -237.754922) (xy 85.830918 -237.802674)
			(xy 85.930994 -237.902496)
		)
		(stroke
			(width 0)
			(type solid)
		)
		(fill yes)
		(layer "In13.Cu")
		(net "M_B_CPU1_SA_DQS_DP<7>")
	)
	(gr_poly
		(pts
			(xy 86.03107 -236.586014) (xy 85.930994 -236.486192) (xy 85.830918 -236.586014) (xy 85.830918 -236.633766)
			(xy 86.03107 -236.633766)
		)
		(stroke
			(width 0)
			(type solid)
		)
		(fill yes)
		(layer "In13.Cu")
		(net "M_B_CPU1_SA_DQS_DP<2>")
	)
	(gr_poly
		(pts
			(xy 86.03107 -236.182408) (xy 86.03107 -236.137958) (xy 85.830918 -236.137958) (xy 85.830918 -236.182408)
			(xy 85.930994 -236.282484)
		)
		(stroke
			(width 0)
			(type solid)
		)
		(fill yes)
		(layer "In13.Cu")
		(net "M_B_CPU1_SA_DQ<19>")
	)
	(gr_poly
		(pts
			(xy 86.03107 -234.966256) (xy 85.930994 -234.86618) (xy 85.830918 -234.966256) (xy 85.830918 -235.010706)
			(xy 86.03107 -235.010706)
		)
		(stroke
			(width 0)
			(type solid)
		)
		(fill yes)
		(layer "In13.Cu")
		(net "M_B_CPU1_SA_DQ<16>")
	)
	(gr_poly
		(pts
			(xy 86.03107 -234.562396) (xy 86.03107 -234.517946) (xy 85.830918 -234.517946) (xy 85.830918 -234.562396)
			(xy 85.930994 -234.662472)
		)
		(stroke
			(width 0)
			(type solid)
		)
		(fill yes)
		(layer "In13.Cu")
		(net "M_B_CPU1_SA_DQ<15>")
	)
	(gr_poly
		(pts
			(xy 86.03107 -233.346244) (xy 85.930994 -233.246168) (xy 85.830918 -233.346244) (xy 85.830918 -233.390694)
			(xy 86.03107 -233.390694)
		)
		(stroke
			(width 0)
			(type solid)
		)
		(fill yes)
		(layer "In13.Cu")
		(net "M_B_CPU1_SA_DQ<12>")
	)
	(gr_poly
		(pts
			(xy 86.03107 -232.942638) (xy 86.03107 -232.894886) (xy 85.830918 -232.894886) (xy 85.830918 -232.942638)
			(xy 85.930994 -233.04246)
		)
		(stroke
			(width 0)
			(type solid)
		)
		(fill yes)
		(layer "In13.Cu")
		(net "M_B_CPU1_SA_DQS_DP<6>")
	)
	(gr_poly
		(pts
			(xy 86.03107 -231.725978) (xy 85.930994 -231.626156) (xy 85.830918 -231.725978) (xy 85.830918 -231.77373)
			(xy 86.03107 -231.77373)
		)
		(stroke
			(width 0)
			(type solid)
		)
		(fill yes)
		(layer "In13.Cu")
		(net "M_B_CPU1_SA_DQS_DP<1>")
	)
	(gr_poly
		(pts
			(xy 86.03107 -231.322626) (xy 86.03107 -231.278176) (xy 85.830918 -231.278176) (xy 85.830918 -231.322626)
			(xy 85.930994 -231.422702)
		)
		(stroke
			(width 0)
			(type solid)
		)
		(fill yes)
		(layer "In13.Cu")
		(net "M_B_CPU1_SA_DQ<11>")
	)
	(gr_poly
		(pts
			(xy 86.03107 -230.10622) (xy 85.930994 -230.006144) (xy 85.830918 -230.10622) (xy 85.830918 -230.15067)
			(xy 86.03107 -230.15067)
		)
		(stroke
			(width 0)
			(type solid)
		)
		(fill yes)
		(layer "In13.Cu")
		(net "M_B_CPU1_SA_DQ<8>")
	)
	(gr_poly
		(pts
			(xy 86.03107 -229.702614) (xy 86.03107 -229.658164) (xy 85.830918 -229.658164) (xy 85.830918 -229.702614)
			(xy 85.930994 -229.80269)
		)
		(stroke
			(width 0)
			(type solid)
		)
		(fill yes)
		(layer "In13.Cu")
		(net "M_B_CPU1_SA_DQ<7>")
	)
	(gr_poly
		(pts
			(xy 86.03107 -228.486462) (xy 85.930994 -228.386386) (xy 85.830918 -228.486462) (xy 85.830918 -228.530912)
			(xy 86.03107 -228.530912)
		)
		(stroke
			(width 0)
			(type solid)
		)
		(fill yes)
		(layer "In13.Cu")
		(net "M_B_CPU1_SA_DQ<4>")
	)
	(gr_poly
		(pts
			(xy 86.03107 -228.082856) (xy 86.03107 -228.035104) (xy 85.830918 -228.035104) (xy 85.830918 -228.082856)
			(xy 85.930994 -228.182678)
		)
		(stroke
			(width 0)
			(type solid)
		)
		(fill yes)
		(layer "In13.Cu")
		(net "M_B_CPU1_SA_DQS_DP<5>")
	)
	(gr_poly
		(pts
			(xy 86.03107 -226.866196) (xy 85.930994 -226.766374) (xy 85.830918 -226.866196) (xy 85.830918 -226.913948)
			(xy 86.03107 -226.913948)
		)
		(stroke
			(width 0)
			(type solid)
		)
		(fill yes)
		(layer "In13.Cu")
		(net "M_B_CPU1_SA_DQS_DP<0>")
	)
	(gr_poly
		(pts
			(xy 86.03107 -226.46259) (xy 86.03107 -226.41814) (xy 85.830918 -226.41814) (xy 85.830918 -226.46259)
			(xy 85.930994 -226.562666)
		)
		(stroke
			(width 0)
			(type solid)
		)
		(fill yes)
		(layer "In13.Cu")
		(net "M_B_CPU1_SA_DQ<3>")
	)
	(gr_poly
		(pts
			(xy 86.03107 -225.246438) (xy 85.930994 -225.146362) (xy 85.830918 -225.246438) (xy 85.830918 -225.290888)
			(xy 86.03107 -225.290888)
		)
		(stroke
			(width 0)
			(type solid)
		)
		(fill yes)
		(layer "In13.Cu")
		(net "M_B_CPU1_SA_DQ<0>")
	)
	(gr_poly
		(pts
			(xy 86.331044 -292.918134) (xy 86.230968 -292.818058) (xy 86.130892 -292.918134) (xy 86.130892 -292.962584)
			(xy 86.331044 -292.962584)
		)
		(stroke
			(width 0)
			(type solid)
		)
		(fill yes)
		(layer "In13.Cu")
		(net "M_B_CPU1_SB_DQ<29>")
	)
	(gr_poly
		(pts
			(xy 86.331044 -292.514274) (xy 86.331044 -292.469824) (xy 86.130892 -292.469824) (xy 86.130892 -292.514274)
			(xy 86.230968 -292.61435)
		)
		(stroke
			(width 0)
			(type solid)
		)
		(fill yes)
		(layer "In13.Cu")
		(net "M_B_CPU1_SB_DQ<30>")
	)
	(gr_poly
		(pts
			(xy 86.331044 -291.297868) (xy 86.230968 -291.198046) (xy 86.130892 -291.297868) (xy 86.130892 -291.34562)
			(xy 86.331044 -291.34562)
		)
		(stroke
			(width 0)
			(type solid)
		)
		(fill yes)
		(layer "In13.Cu")
		(net "M_B_CPU1_SB_DQS_DN<8>")
	)
	(gr_poly
		(pts
			(xy 86.331044 -290.894516) (xy 86.331044 -290.846764) (xy 86.130892 -290.846764) (xy 86.130892 -290.894516)
			(xy 86.230968 -290.994338)
		)
		(stroke
			(width 0)
			(type solid)
		)
		(fill yes)
		(layer "In13.Cu")
		(net "M_B_CPU1_SB_DQS_DN<3>")
	)
	(gr_poly
		(pts
			(xy 86.331044 -289.67811) (xy 86.230968 -289.578034) (xy 86.130892 -289.67811) (xy 86.130892 -289.72256)
			(xy 86.331044 -289.72256)
		)
		(stroke
			(width 0)
			(type solid)
		)
		(fill yes)
		(layer "In13.Cu")
		(net "M_B_CPU1_SB_DQ<25>")
	)
	(gr_poly
		(pts
			(xy 86.331044 -289.27425) (xy 86.331044 -289.2298) (xy 86.130892 -289.2298) (xy 86.130892 -289.27425)
			(xy 86.230968 -289.374326)
		)
		(stroke
			(width 0)
			(type solid)
		)
		(fill yes)
		(layer "In13.Cu")
		(net "M_B_CPU1_SB_DQ<26>")
	)
	(gr_poly
		(pts
			(xy 86.331044 -288.058098) (xy 86.230968 -287.958022) (xy 86.130892 -288.058098) (xy 86.130892 -288.102548)
			(xy 86.331044 -288.102548)
		)
		(stroke
			(width 0)
			(type solid)
		)
		(fill yes)
		(layer "In13.Cu")
		(net "M_B_CPU1_SB_DQ<21>")
	)
	(gr_poly
		(pts
			(xy 86.331044 -287.654492) (xy 86.331044 -287.610042) (xy 86.130892 -287.610042) (xy 86.130892 -287.654492)
			(xy 86.230968 -287.754568)
		)
		(stroke
			(width 0)
			(type solid)
		)
		(fill yes)
		(layer "In13.Cu")
		(net "M_B_CPU1_SB_DQ<22>")
	)
	(gr_poly
		(pts
			(xy 86.331044 -286.438086) (xy 86.230968 -286.33801) (xy 86.130892 -286.438086) (xy 86.130892 -286.485838)
			(xy 86.331044 -286.485838)
		)
		(stroke
			(width 0)
			(type solid)
		)
		(fill yes)
		(layer "In13.Cu")
		(net "M_B_CPU1_SB_DQS_DN<7>")
	)
	(gr_poly
		(pts
			(xy 86.331044 -286.034734) (xy 86.331044 -285.986982) (xy 86.130892 -285.986982) (xy 86.130892 -286.034734)
			(xy 86.230968 -286.134556)
		)
		(stroke
			(width 0)
			(type solid)
		)
		(fill yes)
		(layer "In13.Cu")
		(net "M_B_CPU1_SB_DQS_DN<2>")
	)
	(gr_poly
		(pts
			(xy 86.331044 -284.818328) (xy 86.230968 -284.718252) (xy 86.130892 -284.818328) (xy 86.130892 -284.862778)
			(xy 86.331044 -284.862778)
		)
		(stroke
			(width 0)
			(type solid)
		)
		(fill yes)
		(layer "In13.Cu")
		(net "M_B_CPU1_SB_DQ<17>")
	)
	(gr_poly
		(pts
			(xy 86.331044 -284.414468) (xy 86.331044 -284.370018) (xy 86.130892 -284.370018) (xy 86.130892 -284.414468)
			(xy 86.230968 -284.514544)
		)
		(stroke
			(width 0)
			(type solid)
		)
		(fill yes)
		(layer "In13.Cu")
		(net "M_B_CPU1_SB_DQ<18>")
	)
	(gr_poly
		(pts
			(xy 86.331044 -283.198316) (xy 86.230968 -283.09824) (xy 86.130892 -283.198316) (xy 86.130892 -283.242766)
			(xy 86.331044 -283.242766)
		)
		(stroke
			(width 0)
			(type solid)
		)
		(fill yes)
		(layer "In13.Cu")
		(net "M_B_CPU1_SB_DQ<13>")
	)
	(gr_poly
		(pts
			(xy 86.331044 -282.794456) (xy 86.331044 -282.750006) (xy 86.130892 -282.750006) (xy 86.130892 -282.794456)
			(xy 86.230968 -282.894532)
		)
		(stroke
			(width 0)
			(type solid)
		)
		(fill yes)
		(layer "In13.Cu")
		(net "M_B_CPU1_SB_DQ<14>")
	)
	(gr_poly
		(pts
			(xy 86.331044 -281.57805) (xy 86.230968 -281.478228) (xy 86.130892 -281.57805) (xy 86.130892 -281.625802)
			(xy 86.331044 -281.625802)
		)
		(stroke
			(width 0)
			(type solid)
		)
		(fill yes)
		(layer "In13.Cu")
		(net "M_B_CPU1_SB_DQS_DN<6>")
	)
	(gr_poly
		(pts
			(xy 86.331044 -281.174698) (xy 86.331044 -281.126946) (xy 86.130892 -281.126946) (xy 86.130892 -281.174698)
			(xy 86.230968 -281.27452)
		)
		(stroke
			(width 0)
			(type solid)
		)
		(fill yes)
		(layer "In13.Cu")
		(net "M_B_CPU1_SB_DQS_DN<1>")
	)
	(gr_poly
		(pts
			(xy 86.331044 -279.958292) (xy 86.230968 -279.858216) (xy 86.130892 -279.958292) (xy 86.130892 -280.002742)
			(xy 86.331044 -280.002742)
		)
		(stroke
			(width 0)
			(type solid)
		)
		(fill yes)
		(layer "In13.Cu")
		(net "M_B_CPU1_SB_DQ<9>")
	)
	(gr_poly
		(pts
			(xy 86.331044 -279.554432) (xy 86.331044 -279.509982) (xy 86.130892 -279.509982) (xy 86.130892 -279.554432)
			(xy 86.230968 -279.654508)
		)
		(stroke
			(width 0)
			(type solid)
		)
		(fill yes)
		(layer "In13.Cu")
		(net "M_B_CPU1_SB_DQ<10>")
	)
	(gr_poly
		(pts
			(xy 86.331044 -278.33828) (xy 86.230968 -278.238204) (xy 86.130892 -278.33828) (xy 86.130892 -278.38273)
			(xy 86.331044 -278.38273)
		)
		(stroke
			(width 0)
			(type solid)
		)
		(fill yes)
		(layer "In13.Cu")
		(net "M_B_CPU1_SB_DQ<5>")
	)
	(gr_poly
		(pts
			(xy 86.331044 -277.93442) (xy 86.331044 -277.88997) (xy 86.130892 -277.88997) (xy 86.130892 -277.93442)
			(xy 86.230968 -278.034496)
		)
		(stroke
			(width 0)
			(type solid)
		)
		(fill yes)
		(layer "In13.Cu")
		(net "M_B_CPU1_SB_DQ<6>")
	)
	(gr_poly
		(pts
			(xy 86.331044 -275.098256) (xy 86.230968 -274.99818) (xy 86.130892 -275.098256) (xy 86.130892 -275.142706)
			(xy 86.331044 -275.142706)
		)
		(stroke
			(width 0)
			(type solid)
		)
		(fill yes)
		(layer "In13.Cu")
		(net "M_B_CPU1_SB_DQ<1>")
	)
	(gr_poly
		(pts
			(xy 86.331044 -274.694396) (xy 86.331044 -274.649946) (xy 86.130892 -274.649946) (xy 86.130892 -274.694396)
			(xy 86.230968 -274.794472)
		)
		(stroke
			(width 0)
			(type solid)
		)
		(fill yes)
		(layer "In13.Cu")
		(net "M_B_CPU1_SB_DQ<2>")
	)
	(gr_poly
		(pts
			(xy 86.331044 -273.478244) (xy 86.230968 -273.378168) (xy 86.130892 -273.478244) (xy 86.130892 -273.522694)
			(xy 86.331044 -273.522694)
		)
		(stroke
			(width 0)
			(type solid)
		)
		(fill yes)
		(layer "In13.Cu")
		(net "M_B_CPU1_SB_CB<1>")
	)
	(gr_poly
		(pts
			(xy 86.331044 -273.074384) (xy 86.331044 -273.029934) (xy 86.130892 -273.029934) (xy 86.130892 -273.074384)
			(xy 86.230968 -273.17446)
		)
		(stroke
			(width 0)
			(type solid)
		)
		(fill yes)
		(layer "In13.Cu")
		(net "M_B_CPU1_SB_CB<2>")
	)
	(gr_poly
		(pts
			(xy 86.331044 -271.857978) (xy 86.230968 -271.758156) (xy 86.130892 -271.857978) (xy 86.130892 -271.90573)
			(xy 86.331044 -271.90573)
		)
		(stroke
			(width 0)
			(type solid)
		)
		(fill yes)
		(layer "In13.Cu")
		(net "M_B_CPU1_SB_DQS_DN<4>")
	)
	(gr_poly
		(pts
			(xy 86.331044 -271.454626) (xy 86.331044 -271.406874) (xy 86.130892 -271.406874) (xy 86.130892 -271.454626)
			(xy 86.230968 -271.554448)
		)
		(stroke
			(width 0)
			(type solid)
		)
		(fill yes)
		(layer "In13.Cu")
		(net "M_B_CPU1_SB_DQS_DN<9>")
	)
	(gr_poly
		(pts
			(xy 86.331044 -270.23822) (xy 86.230968 -270.138144) (xy 86.130892 -270.23822) (xy 86.130892 -270.28267)
			(xy 86.331044 -270.28267)
		)
		(stroke
			(width 0)
			(type solid)
		)
		(fill yes)
		(layer "In13.Cu")
		(net "M_B_CPU1_SB_CB<5>")
	)
	(gr_poly
		(pts
			(xy 86.331044 -269.83436) (xy 86.331044 -269.78991) (xy 86.130892 -269.78991) (xy 86.130892 -269.83436)
			(xy 86.230968 -269.934436)
		)
		(stroke
			(width 0)
			(type solid)
		)
		(fill yes)
		(layer "In13.Cu")
		(net "M_B_CPU1_SB_CB<6>")
	)
	(gr_poly
		(pts
			(xy 86.331044 -266.594336) (xy 86.331044 -266.549886) (xy 86.130892 -266.549886) (xy 86.130892 -266.594336)
			(xy 86.230968 -266.694412)
		)
		(stroke
			(width 0)
			(type solid)
		)
		(fill yes)
		(layer "In13.Cu")
		(net "M_B_CPU1_SB_CS_N<1>")
	)
	(gr_poly
		(pts
			(xy 86.331044 -264.974324) (xy 86.331044 -264.929874) (xy 86.130892 -264.929874) (xy 86.130892 -264.974324)
			(xy 86.230968 -265.0744)
		)
		(stroke
			(width 0)
			(type solid)
		)
		(fill yes)
		(layer "In13.Cu")
		(net "M_B_CPU1_SB_PAR")
	)
	(gr_poly
		(pts
			(xy 86.331044 -263.758172) (xy 86.230968 -263.658096) (xy 86.130892 -263.758172) (xy 86.130892 -263.802622)
			(xy 86.331044 -263.802622)
		)
		(stroke
			(width 0)
			(type solid)
		)
		(fill yes)
		(layer "In13.Cu")
		(net "M_B_CPU1_SB_CA<4>")
	)
	(gr_poly
		(pts
			(xy 86.331044 -263.354312) (xy 86.331044 -263.309862) (xy 86.130892 -263.309862) (xy 86.130892 -263.354312)
			(xy 86.230968 -263.454388)
		)
		(stroke
			(width 0)
			(type solid)
		)
		(fill yes)
		(layer "In13.Cu")
		(net "M_B_CPU1_SB_CA<3>")
	)
	(gr_poly
		(pts
			(xy 86.331044 -262.13816) (xy 86.230968 -262.038084) (xy 86.130892 -262.13816) (xy 86.130892 -262.18261)
			(xy 86.331044 -262.18261)
		)
		(stroke
			(width 0)
			(type solid)
		)
		(fill yes)
		(layer "In13.Cu")
		(net "M_B_CPU1_SB_CA<0>")
	)
	(gr_poly
		(pts
			(xy 86.33714 -266.991846) (xy 86.237318 -266.89177) (xy 86.137242 -266.991846) (xy 86.137242 -267.036296)
			(xy 86.33714 -267.036296)
		)
		(stroke
			(width 0)
			(type solid)
		)
		(fill yes)
		(layer "In13.Cu")
		(net "M_B_CPU1_SA_RSP<0>")
	)
	(gr_poly
		(pts
			(xy 86.33841 -276.718268) (xy 86.238334 -276.618192) (xy 86.138258 -276.718268) (xy 86.138258 -276.765766)
			(xy 86.33841 -276.765766)
		)
		(stroke
			(width 0)
			(type solid)
		)
		(fill yes)
		(layer "In13.Cu")
		(net "M_B_CPU1_SB_DQS_DN<5>")
	)
	(gr_poly
		(pts
			(xy 86.33841 -276.314408) (xy 86.33841 -276.26691) (xy 86.138258 -276.26691) (xy 86.138258 -276.314408)
			(xy 86.238334 -276.414484)
		)
		(stroke
			(width 0)
			(type solid)
		)
		(fill yes)
		(layer "In13.Cu")
		(net "M_B_CPU1_SB_DQS_DN<0>")
	)
	(gr_poly
		(pts
			(xy 86.494874 -227.67671) (xy 86.395052 -227.576634) (xy 86.294976 -227.67671) (xy 86.294976 -227.724208)
			(xy 86.494874 -227.724208)
		)
		(stroke
			(width 0)
			(type solid)
		)
		(fill yes)
		(layer "In13.Cu")
		(net "M_B_CPU1_SA_DQS_DN<5>")
	)
	(gr_poly
		(pts
			(xy 86.501224 -256.432812) (xy 86.501224 -256.38506) (xy 86.301072 -256.38506) (xy 86.301072 -256.432812)
			(xy 86.401148 -256.532634)
		)
		(stroke
			(width 0)
			(type solid)
		)
		(fill yes)
		(layer "In13.Cu")
		(net "M_B_CPU1_CLK_DN<0>")
	)
	(gr_poly
		(pts
			(xy 86.501224 -255.216406) (xy 86.401148 -255.11633) (xy 86.301072 -255.216406) (xy 86.301072 -255.260856)
			(xy 86.501224 -255.260856)
		)
		(stroke
			(width 0)
			(type solid)
		)
		(fill yes)
		(layer "In13.Cu")
		(net "M_B_CPU1_SA_CA<6>")
	)
	(gr_poly
		(pts
			(xy 86.501224 -254.812546) (xy 86.501224 -254.768096) (xy 86.301072 -254.768096) (xy 86.301072 -254.812546)
			(xy 86.401148 -254.912622)
		)
		(stroke
			(width 0)
			(type solid)
		)
		(fill yes)
		(layer "In13.Cu")
		(net "M_B_CPU1_SA_CA<5>")
	)
	(gr_poly
		(pts
			(xy 86.501224 -253.596394) (xy 86.401148 -253.496318) (xy 86.301072 -253.596394) (xy 86.301072 -253.640844)
			(xy 86.501224 -253.640844)
		)
		(stroke
			(width 0)
			(type solid)
		)
		(fill yes)
		(layer "In13.Cu")
		(net "M_B_CPU1_SA_CA<2>")
	)
	(gr_poly
		(pts
			(xy 86.501224 -253.192534) (xy 86.501224 -253.148084) (xy 86.301072 -253.148084) (xy 86.301072 -253.192534)
			(xy 86.401148 -253.29261)
		)
		(stroke
			(width 0)
			(type solid)
		)
		(fill yes)
		(layer "In13.Cu")
		(net "M_B_CPU1_SA_CA<1>")
	)
	(gr_poly
		(pts
			(xy 86.501224 -251.572522) (xy 86.501224 -251.528072) (xy 86.301072 -251.528072) (xy 86.301072 -251.572522)
			(xy 86.401148 -251.672598)
		)
		(stroke
			(width 0)
			(type solid)
		)
		(fill yes)
		(layer "In13.Cu")
		(net "M_B_CPU1_SA_CS_N<0>")
	)
	(gr_poly
		(pts
			(xy 86.501224 -250.35637) (xy 86.401148 -250.256294) (xy 86.301072 -250.35637) (xy 86.301072 -250.40082)
			(xy 86.501224 -250.40082)
		)
		(stroke
			(width 0)
			(type solid)
		)
		(fill yes)
		(layer "In13.Cu")
		(net "M_B_CPU1_ALERT_R_N")
	)
	(gr_poly
		(pts
			(xy 86.501224 -248.736358) (xy 86.401148 -248.636282) (xy 86.301072 -248.736358) (xy 86.301072 -248.780808)
			(xy 86.501224 -248.780808)
		)
		(stroke
			(width 0)
			(type solid)
		)
		(fill yes)
		(layer "In13.Cu")
		(net "M_B_CPU1_SA_CB<5>")
	)
	(gr_poly
		(pts
			(xy 86.501224 -248.332498) (xy 86.501224 -248.288048) (xy 86.301072 -248.288048) (xy 86.301072 -248.332498)
			(xy 86.401148 -248.432574)
		)
		(stroke
			(width 0)
			(type solid)
		)
		(fill yes)
		(layer "In13.Cu")
		(net "M_B_CPU1_SA_CB<6>")
	)
	(gr_poly
		(pts
			(xy 86.501224 -247.116092) (xy 86.401148 -247.01627) (xy 86.301072 -247.116092) (xy 86.301072 -247.163844)
			(xy 86.501224 -247.163844)
		)
		(stroke
			(width 0)
			(type solid)
		)
		(fill yes)
		(layer "In13.Cu")
		(net "M_B_CPU1_SA_DQS_DN<9>")
	)
	(gr_poly
		(pts
			(xy 86.501224 -246.71274) (xy 86.501224 -246.664988) (xy 86.301072 -246.664988) (xy 86.301072 -246.71274)
			(xy 86.401148 -246.812562)
		)
		(stroke
			(width 0)
			(type solid)
		)
		(fill yes)
		(layer "In13.Cu")
		(net "M_B_CPU1_SA_DQS_DN<4>")
	)
	(gr_poly
		(pts
			(xy 86.501224 -245.496334) (xy 86.401148 -245.396258) (xy 86.301072 -245.496334) (xy 86.301072 -245.540784)
			(xy 86.501224 -245.540784)
		)
		(stroke
			(width 0)
			(type solid)
		)
		(fill yes)
		(layer "In13.Cu")
		(net "M_B_CPU1_SA_CB<1>")
	)
	(gr_poly
		(pts
			(xy 86.501224 -245.092474) (xy 86.501224 -245.048024) (xy 86.301072 -245.048024) (xy 86.301072 -245.092474)
			(xy 86.401148 -245.19255)
		)
		(stroke
			(width 0)
			(type solid)
		)
		(fill yes)
		(layer "In13.Cu")
		(net "M_B_CPU1_SA_CB<2>")
	)
	(gr_poly
		(pts
			(xy 86.501224 -243.876322) (xy 86.401148 -243.776246) (xy 86.301072 -243.876322) (xy 86.301072 -243.920772)
			(xy 86.501224 -243.920772)
		)
		(stroke
			(width 0)
			(type solid)
		)
		(fill yes)
		(layer "In13.Cu")
		(net "M_B_CPU1_SA_DQ<29>")
	)
	(gr_poly
		(pts
			(xy 86.501224 -243.472462) (xy 86.501224 -243.428012) (xy 86.301072 -243.428012) (xy 86.301072 -243.472462)
			(xy 86.401148 -243.572538)
		)
		(stroke
			(width 0)
			(type solid)
		)
		(fill yes)
		(layer "In13.Cu")
		(net "M_B_CPU1_SA_DQ<30>")
	)
	(gr_poly
		(pts
			(xy 86.501224 -242.256056) (xy 86.401148 -242.156234) (xy 86.301072 -242.256056) (xy 86.301072 -242.303808)
			(xy 86.501224 -242.303808)
		)
		(stroke
			(width 0)
			(type solid)
		)
		(fill yes)
		(layer "In13.Cu")
		(net "M_B_CPU1_SA_DQS_DN<8>")
	)
	(gr_poly
		(pts
			(xy 86.501224 -241.852704) (xy 86.501224 -241.804952) (xy 86.301072 -241.804952) (xy 86.301072 -241.852704)
			(xy 86.401148 -241.952526)
		)
		(stroke
			(width 0)
			(type solid)
		)
		(fill yes)
		(layer "In13.Cu")
		(net "M_B_CPU1_SA_DQS_DN<3>")
	)
	(gr_poly
		(pts
			(xy 86.501224 -240.636298) (xy 86.401148 -240.536222) (xy 86.301072 -240.636298) (xy 86.301072 -240.680748)
			(xy 86.501224 -240.680748)
		)
		(stroke
			(width 0)
			(type solid)
		)
		(fill yes)
		(layer "In13.Cu")
		(net "M_B_CPU1_SA_DQ<25>")
	)
	(gr_poly
		(pts
			(xy 86.501224 -240.232438) (xy 86.501224 -240.187988) (xy 86.301072 -240.187988) (xy 86.301072 -240.232438)
			(xy 86.401148 -240.332514)
		)
		(stroke
			(width 0)
			(type solid)
		)
		(fill yes)
		(layer "In13.Cu")
		(net "M_B_CPU1_SA_DQ<26>")
	)
	(gr_poly
		(pts
			(xy 86.501224 -239.016286) (xy 86.401148 -238.91621) (xy 86.301072 -239.016286) (xy 86.301072 -239.060736)
			(xy 86.501224 -239.060736)
		)
		(stroke
			(width 0)
			(type solid)
		)
		(fill yes)
		(layer "In13.Cu")
		(net "M_B_CPU1_SA_DQ<21>")
	)
	(gr_poly
		(pts
			(xy 86.501224 -238.612426) (xy 86.501224 -238.567976) (xy 86.301072 -238.567976) (xy 86.301072 -238.612426)
			(xy 86.401148 -238.712502)
		)
		(stroke
			(width 0)
			(type solid)
		)
		(fill yes)
		(layer "In13.Cu")
		(net "M_B_CPU1_SA_DQ<22>")
	)
	(gr_poly
		(pts
			(xy 86.501224 -237.39602) (xy 86.401148 -237.296198) (xy 86.301072 -237.39602) (xy 86.301072 -237.443772)
			(xy 86.501224 -237.443772)
		)
		(stroke
			(width 0)
			(type solid)
		)
		(fill yes)
		(layer "In13.Cu")
		(net "M_B_CPU1_SA_DQS_DN<7>")
	)
	(gr_poly
		(pts
			(xy 86.501224 -236.992668) (xy 86.501224 -236.944916) (xy 86.301072 -236.944916) (xy 86.301072 -236.992668)
			(xy 86.401148 -237.09249)
		)
		(stroke
			(width 0)
			(type solid)
		)
		(fill yes)
		(layer "In13.Cu")
		(net "M_B_CPU1_SA_DQS_DN<2>")
	)
	(gr_poly
		(pts
			(xy 86.501224 -235.776262) (xy 86.401148 -235.676186) (xy 86.301072 -235.776262) (xy 86.301072 -235.820712)
			(xy 86.501224 -235.820712)
		)
		(stroke
			(width 0)
			(type solid)
		)
		(fill yes)
		(layer "In13.Cu")
		(net "M_B_CPU1_SA_DQ<17>")
	)
	(gr_poly
		(pts
			(xy 86.501224 -235.372402) (xy 86.501224 -235.327952) (xy 86.301072 -235.327952) (xy 86.301072 -235.372402)
			(xy 86.401148 -235.472478)
		)
		(stroke
			(width 0)
			(type solid)
		)
		(fill yes)
		(layer "In13.Cu")
		(net "M_B_CPU1_SA_DQ<18>")
	)
	(gr_poly
		(pts
			(xy 86.501224 -234.15625) (xy 86.401148 -234.056174) (xy 86.301072 -234.15625) (xy 86.301072 -234.2007)
			(xy 86.501224 -234.2007)
		)
		(stroke
			(width 0)
			(type solid)
		)
		(fill yes)
		(layer "In13.Cu")
		(net "M_B_CPU1_SA_DQ<13>")
	)
	(gr_poly
		(pts
			(xy 86.501224 -233.75239) (xy 86.501224 -233.70794) (xy 86.301072 -233.70794) (xy 86.301072 -233.75239)
			(xy 86.401148 -233.852466)
		)
		(stroke
			(width 0)
			(type solid)
		)
		(fill yes)
		(layer "In13.Cu")
		(net "M_B_CPU1_SA_DQ<14>")
	)
	(gr_poly
		(pts
			(xy 86.501224 -232.535984) (xy 86.401148 -232.436162) (xy 86.301072 -232.535984) (xy 86.301072 -232.583736)
			(xy 86.501224 -232.583736)
		)
		(stroke
			(width 0)
			(type solid)
		)
		(fill yes)
		(layer "In13.Cu")
		(net "M_B_CPU1_SA_DQS_DN<6>")
	)
	(gr_poly
		(pts
			(xy 86.501224 -232.132632) (xy 86.501224 -232.08488) (xy 86.301072 -232.08488) (xy 86.301072 -232.132632)
			(xy 86.401148 -232.232454)
		)
		(stroke
			(width 0)
			(type solid)
		)
		(fill yes)
		(layer "In13.Cu")
		(net "M_B_CPU1_SA_DQS_DN<1>")
	)
	(gr_poly
		(pts
			(xy 86.501224 -230.916226) (xy 86.401148 -230.81615) (xy 86.301072 -230.916226) (xy 86.301072 -230.960676)
			(xy 86.501224 -230.960676)
		)
		(stroke
			(width 0)
			(type solid)
		)
		(fill yes)
		(layer "In13.Cu")
		(net "M_B_CPU1_SA_DQ<9>")
	)
	(gr_poly
		(pts
			(xy 86.501224 -230.51262) (xy 86.501224 -230.46817) (xy 86.301072 -230.46817) (xy 86.301072 -230.51262)
			(xy 86.401148 -230.612696)
		)
		(stroke
			(width 0)
			(type solid)
		)
		(fill yes)
		(layer "In13.Cu")
		(net "M_B_CPU1_SA_DQ<10>")
	)
	(gr_poly
		(pts
			(xy 86.501224 -229.296214) (xy 86.401148 -229.196138) (xy 86.301072 -229.296214) (xy 86.301072 -229.340664)
			(xy 86.501224 -229.340664)
		)
		(stroke
			(width 0)
			(type solid)
		)
		(fill yes)
		(layer "In13.Cu")
		(net "M_B_CPU1_SA_DQ<5>")
	)
	(gr_poly
		(pts
			(xy 86.501224 -228.892608) (xy 86.501224 -228.848158) (xy 86.301072 -228.848158) (xy 86.301072 -228.892608)
			(xy 86.401148 -228.992684)
		)
		(stroke
			(width 0)
			(type solid)
		)
		(fill yes)
		(layer "In13.Cu")
		(net "M_B_CPU1_SA_DQ<6>")
	)
	(gr_poly
		(pts
			(xy 86.501224 -227.27285) (xy 86.501224 -227.225098) (xy 86.301072 -227.225098) (xy 86.301072 -227.27285)
			(xy 86.401148 -227.372672)
		)
		(stroke
			(width 0)
			(type solid)
		)
		(fill yes)
		(layer "In13.Cu")
		(net "M_B_CPU1_SA_DQS_DN<0>")
	)
	(gr_poly
		(pts
			(xy 86.501224 -226.056444) (xy 86.401148 -225.956368) (xy 86.301072 -226.056444) (xy 86.301072 -226.100894)
			(xy 86.501224 -226.100894)
		)
		(stroke
			(width 0)
			(type solid)
		)
		(fill yes)
		(layer "In13.Cu")
		(net "M_B_CPU1_SA_DQ<1>")
	)
	(gr_poly
		(pts
			(xy 86.501224 -225.652584) (xy 86.501224 -225.608134) (xy 86.301072 -225.608134) (xy 86.301072 -225.652584)
			(xy 86.401148 -225.75266)
		)
		(stroke
			(width 0)
			(type solid)
		)
		(fill yes)
		(layer "In13.Cu")
		(net "M_B_CPU1_SA_DQ<2>")
	)
	(gr_poly
		(pts
			(xy 86.794848 -267.801852) (xy 86.694772 -267.701776) (xy 86.59495 -267.801852) (xy 86.59495 -267.846302)
			(xy 86.794848 -267.846302)
		)
		(stroke
			(width 0)
			(type solid)
		)
		(fill yes)
		(layer "In13.Cu")
		(net "M_B_CPU1_SB_RSP<0>")
	)
	(gr_poly
		(pts
			(xy 86.801198 -293.32428) (xy 86.801198 -293.27983) (xy 86.601046 -293.27983) (xy 86.601046 -293.32428)
			(xy 86.701122 -293.424356)
		)
		(stroke
			(width 0)
			(type solid)
		)
		(fill yes)
		(layer "In13.Cu")
		(net "M_B_CPU1_SB_DQ<31>")
	)
	(gr_poly
		(pts
			(xy 86.801198 -292.108128) (xy 86.701122 -292.008052) (xy 86.601046 -292.108128) (xy 86.601046 -292.152578)
			(xy 86.801198 -292.152578)
		)
		(stroke
			(width 0)
			(type solid)
		)
		(fill yes)
		(layer "In13.Cu")
		(net "M_B_CPU1_SB_DQ<28>")
	)
	(gr_poly
		(pts
			(xy 86.801198 -291.704522) (xy 86.801198 -291.65677) (xy 86.601046 -291.65677) (xy 86.601046 -291.704522)
			(xy 86.701122 -291.804344)
		)
		(stroke
			(width 0)
			(type solid)
		)
		(fill yes)
		(layer "In13.Cu")
		(net "M_B_CPU1_SB_DQS_DP<8>")
	)
	(gr_poly
		(pts
			(xy 86.801198 -290.487862) (xy 86.701122 -290.38804) (xy 86.601046 -290.487862) (xy 86.601046 -290.535614)
			(xy 86.801198 -290.535614)
		)
		(stroke
			(width 0)
			(type solid)
		)
		(fill yes)
		(layer "In13.Cu")
		(net "M_B_CPU1_SB_DQS_DP<3>")
	)
	(gr_poly
		(pts
			(xy 86.801198 -290.084256) (xy 86.801198 -290.039806) (xy 86.601046 -290.039806) (xy 86.601046 -290.084256)
			(xy 86.701122 -290.184332)
		)
		(stroke
			(width 0)
			(type solid)
		)
		(fill yes)
		(layer "In13.Cu")
		(net "M_B_CPU1_SB_DQ<27>")
	)
	(gr_poly
		(pts
			(xy 86.801198 -288.868104) (xy 86.701122 -288.768028) (xy 86.601046 -288.868104) (xy 86.601046 -288.912554)
			(xy 86.801198 -288.912554)
		)
		(stroke
			(width 0)
			(type solid)
		)
		(fill yes)
		(layer "In13.Cu")
		(net "M_B_CPU1_SB_DQ<24>")
	)
	(gr_poly
		(pts
			(xy 86.801198 -288.464498) (xy 86.801198 -288.420048) (xy 86.601046 -288.420048) (xy 86.601046 -288.464498)
			(xy 86.701122 -288.564574)
		)
		(stroke
			(width 0)
			(type solid)
		)
		(fill yes)
		(layer "In13.Cu")
		(net "M_B_CPU1_SB_DQ<23>")
	)
	(gr_poly
		(pts
			(xy 86.801198 -287.248092) (xy 86.701122 -287.148016) (xy 86.601046 -287.248092) (xy 86.601046 -287.292542)
			(xy 86.801198 -287.292542)
		)
		(stroke
			(width 0)
			(type solid)
		)
		(fill yes)
		(layer "In13.Cu")
		(net "M_B_CPU1_SB_DQ<20>")
	)
	(gr_poly
		(pts
			(xy 86.801198 -286.844486) (xy 86.801198 -286.796734) (xy 86.601046 -286.796734) (xy 86.601046 -286.844486)
			(xy 86.701122 -286.944562)
		)
		(stroke
			(width 0)
			(type solid)
		)
		(fill yes)
		(layer "In13.Cu")
		(net "M_B_CPU1_SB_DQS_DP<7>")
	)
	(gr_poly
		(pts
			(xy 86.801198 -285.62808) (xy 86.701122 -285.528258) (xy 86.601046 -285.62808) (xy 86.601046 -285.675832)
			(xy 86.801198 -285.675832)
		)
		(stroke
			(width 0)
			(type solid)
		)
		(fill yes)
		(layer "In13.Cu")
		(net "M_B_CPU1_SB_DQS_DP<2>")
	)
	(gr_poly
		(pts
			(xy 86.801198 -285.224474) (xy 86.801198 -285.180024) (xy 86.601046 -285.180024) (xy 86.601046 -285.224474)
			(xy 86.701122 -285.32455)
		)
		(stroke
			(width 0)
			(type solid)
		)
		(fill yes)
		(layer "In13.Cu")
		(net "M_B_CPU1_SB_DQ<19>")
	)
	(gr_poly
		(pts
			(xy 86.801198 -284.008322) (xy 86.701122 -283.908246) (xy 86.601046 -284.008322) (xy 86.601046 -284.052772)
			(xy 86.801198 -284.052772)
		)
		(stroke
			(width 0)
			(type solid)
		)
		(fill yes)
		(layer "In13.Cu")
		(net "M_B_CPU1_SB_DQ<16>")
	)
	(gr_poly
		(pts
			(xy 86.801198 -283.604462) (xy 86.801198 -283.560012) (xy 86.601046 -283.560012) (xy 86.601046 -283.604462)
			(xy 86.701122 -283.704538)
		)
		(stroke
			(width 0)
			(type solid)
		)
		(fill yes)
		(layer "In13.Cu")
		(net "M_B_CPU1_SB_DQ<15>")
	)
	(gr_poly
		(pts
			(xy 86.801198 -282.38831) (xy 86.701122 -282.288234) (xy 86.601046 -282.38831) (xy 86.601046 -282.43276)
			(xy 86.801198 -282.43276)
		)
		(stroke
			(width 0)
			(type solid)
		)
		(fill yes)
		(layer "In13.Cu")
		(net "M_B_CPU1_SB_DQ<12>")
	)
	(gr_poly
		(pts
			(xy 86.801198 -281.984704) (xy 86.801198 -281.936952) (xy 86.601046 -281.936952) (xy 86.601046 -281.984704)
			(xy 86.701122 -282.084526)
		)
		(stroke
			(width 0)
			(type solid)
		)
		(fill yes)
		(layer "In13.Cu")
		(net "M_B_CPU1_SB_DQS_DP<6>")
	)
	(gr_poly
		(pts
			(xy 86.801198 -280.768044) (xy 86.701122 -280.668222) (xy 86.601046 -280.768044) (xy 86.601046 -280.815796)
			(xy 86.801198 -280.815796)
		)
		(stroke
			(width 0)
			(type solid)
		)
		(fill yes)
		(layer "In13.Cu")
		(net "M_B_CPU1_SB_DQS_DP<1>")
	)
	(gr_poly
		(pts
			(xy 86.801198 -280.364438) (xy 86.801198 -280.319988) (xy 86.601046 -280.319988) (xy 86.601046 -280.364438)
			(xy 86.701122 -280.464514)
		)
		(stroke
			(width 0)
			(type solid)
		)
		(fill yes)
		(layer "In13.Cu")
		(net "M_B_CPU1_SB_DQ<11>")
	)
	(gr_poly
		(pts
			(xy 86.801198 -279.148286) (xy 86.701122 -279.04821) (xy 86.601046 -279.148286) (xy 86.601046 -279.192736)
			(xy 86.801198 -279.192736)
		)
		(stroke
			(width 0)
			(type solid)
		)
		(fill yes)
		(layer "In13.Cu")
		(net "M_B_CPU1_SB_DQ<8>")
	)
	(gr_poly
		(pts
			(xy 86.801198 -278.744426) (xy 86.801198 -278.699976) (xy 86.601046 -278.699976) (xy 86.601046 -278.744426)
			(xy 86.701122 -278.844502)
		)
		(stroke
			(width 0)
			(type solid)
		)
		(fill yes)
		(layer "In13.Cu")
		(net "M_B_CPU1_SB_DQ<7>")
	)
	(gr_poly
		(pts
			(xy 86.801198 -277.528274) (xy 86.701122 -277.428198) (xy 86.601046 -277.528274) (xy 86.601046 -277.572724)
			(xy 86.801198 -277.572724)
		)
		(stroke
			(width 0)
			(type solid)
		)
		(fill yes)
		(layer "In13.Cu")
		(net "M_B_CPU1_SB_DQ<4>")
	)
	(gr_poly
		(pts
			(xy 86.801198 -277.124668) (xy 86.801198 -277.076916) (xy 86.601046 -277.076916) (xy 86.601046 -277.124668)
			(xy 86.701122 -277.22449)
		)
		(stroke
			(width 0)
			(type solid)
		)
		(fill yes)
		(layer "In13.Cu")
		(net "M_B_CPU1_SB_DQS_DP<5>")
	)
	(gr_poly
		(pts
			(xy 86.801198 -275.908008) (xy 86.701122 -275.808186) (xy 86.601046 -275.908008) (xy 86.601046 -275.95576)
			(xy 86.801198 -275.95576)
		)
		(stroke
			(width 0)
			(type solid)
		)
		(fill yes)
		(layer "In13.Cu")
		(net "M_B_CPU1_SB_DQS_DP<0>")
	)
	(gr_poly
		(pts
			(xy 86.801198 -275.504402) (xy 86.801198 -275.459952) (xy 86.601046 -275.459952) (xy 86.601046 -275.504402)
			(xy 86.701122 -275.604478)
		)
		(stroke
			(width 0)
			(type solid)
		)
		(fill yes)
		(layer "In13.Cu")
		(net "M_B_CPU1_SB_DQ<3>")
	)
	(gr_poly
		(pts
			(xy 86.801198 -274.28825) (xy 86.701122 -274.188174) (xy 86.601046 -274.28825) (xy 86.601046 -274.3327)
			(xy 86.801198 -274.3327)
		)
		(stroke
			(width 0)
			(type solid)
		)
		(fill yes)
		(layer "In13.Cu")
		(net "M_B_CPU1_SB_DQ<0>")
	)
	(gr_poly
		(pts
			(xy 86.801198 -273.88439) (xy 86.801198 -273.83994) (xy 86.601046 -273.83994) (xy 86.601046 -273.88439)
			(xy 86.701122 -273.984466)
		)
		(stroke
			(width 0)
			(type solid)
		)
		(fill yes)
		(layer "In13.Cu")
		(net "M_B_CPU1_SB_CB<3>")
	)
	(gr_poly
		(pts
			(xy 86.801198 -272.668238) (xy 86.701122 -272.568162) (xy 86.601046 -272.668238) (xy 86.601046 -272.712688)
			(xy 86.801198 -272.712688)
		)
		(stroke
			(width 0)
			(type solid)
		)
		(fill yes)
		(layer "In13.Cu")
		(net "M_B_CPU1_SB_CB<0>")
	)
	(gr_poly
		(pts
			(xy 86.801198 -272.264632) (xy 86.801198 -272.21688) (xy 86.601046 -272.21688) (xy 86.601046 -272.264632)
			(xy 86.701122 -272.364454)
		)
		(stroke
			(width 0)
			(type solid)
		)
		(fill yes)
		(layer "In13.Cu")
		(net "M_B_CPU1_SB_DQS_DP<4>")
	)
	(gr_poly
		(pts
			(xy 86.801198 -271.047972) (xy 86.701122 -270.94815) (xy 86.601046 -271.047972) (xy 86.601046 -271.095724)
			(xy 86.801198 -271.095724)
		)
		(stroke
			(width 0)
			(type solid)
		)
		(fill yes)
		(layer "In13.Cu")
		(net "M_B_CPU1_SB_DQS_DP<9>")
	)
	(gr_poly
		(pts
			(xy 86.801198 -270.644366) (xy 86.801198 -270.599916) (xy 86.601046 -270.599916) (xy 86.601046 -270.644366)
			(xy 86.701122 -270.744442)
		)
		(stroke
			(width 0)
			(type solid)
		)
		(fill yes)
		(layer "In13.Cu")
		(net "M_B_CPU1_SB_CB<7>")
	)
	(gr_poly
		(pts
			(xy 86.801198 -269.428214) (xy 86.701122 -269.328138) (xy 86.601046 -269.428214) (xy 86.601046 -269.472664)
			(xy 86.801198 -269.472664)
		)
		(stroke
			(width 0)
			(type solid)
		)
		(fill yes)
		(layer "In13.Cu")
		(net "M_B_CPU1_SB_CB<4>")
	)
	(gr_poly
		(pts
			(xy 86.801198 -265.78433) (xy 86.801198 -265.73988) (xy 86.601046 -265.73988) (xy 86.601046 -265.78433)
			(xy 86.701122 -265.884406)
		)
		(stroke
			(width 0)
			(type solid)
		)
		(fill yes)
		(layer "In13.Cu")
		(net "M_B_CPU1_SB_CS_N<0>")
	)
	(gr_poly
		(pts
			(xy 86.801198 -264.568178) (xy 86.701122 -264.468102) (xy 86.601046 -264.568178) (xy 86.601046 -264.612628)
			(xy 86.801198 -264.612628)
		)
		(stroke
			(width 0)
			(type solid)
		)
		(fill yes)
		(layer "In13.Cu")
		(net "M_B_CPU1_SB_CA<6>")
	)
	(gr_poly
		(pts
			(xy 86.801198 -264.164318) (xy 86.801198 -264.119868) (xy 86.601046 -264.119868) (xy 86.601046 -264.164318)
			(xy 86.701122 -264.264394)
		)
		(stroke
			(width 0)
			(type solid)
		)
		(fill yes)
		(layer "In13.Cu")
		(net "M_B_CPU1_SB_CA<5>")
	)
	(gr_poly
		(pts
			(xy 86.801198 -262.948166) (xy 86.701122 -262.84809) (xy 86.601046 -262.948166) (xy 86.601046 -262.992616)
			(xy 86.801198 -262.992616)
		)
		(stroke
			(width 0)
			(type solid)
		)
		(fill yes)
		(layer "In13.Cu")
		(net "M_B_CPU1_SB_CA<2>")
	)
	(gr_poly
		(pts
			(xy 86.801198 -262.544306) (xy 86.801198 -262.499856) (xy 86.601046 -262.499856) (xy 86.601046 -262.544306)
			(xy 86.701122 -262.644382)
		)
		(stroke
			(width 0)
			(type solid)
		)
		(fill yes)
		(layer "In13.Cu")
		(net "M_B_CPU1_SB_CA<1>")
	)
	(gr_poly
		(pts
			(xy 86.971124 -256.026158) (xy 86.871048 -255.926336) (xy 86.770972 -256.026158) (xy 86.770972 -256.07391)
			(xy 86.971124 -256.07391)
		)
		(stroke
			(width 0)
			(type solid)
		)
		(fill yes)
		(layer "In13.Cu")
		(net "M_B_CPU1_CLK_DP<0>")
	)
	(gr_poly
		(pts
			(xy 86.971124 -255.622552) (xy 86.971124 -255.578102) (xy 86.770972 -255.578102) (xy 86.770972 -255.622552)
			(xy 86.871048 -255.722628)
		)
		(stroke
			(width 0)
			(type solid)
		)
		(fill yes)
		(layer "In13.Cu")
		(net "M_B_CPU1_SA_PAR")
	)
	(gr_poly
		(pts
			(xy 86.971124 -254.4064) (xy 86.871048 -254.306324) (xy 86.770972 -254.4064) (xy 86.770972 -254.45085)
			(xy 86.971124 -254.45085)
		)
		(stroke
			(width 0)
			(type solid)
		)
		(fill yes)
		(layer "In13.Cu")
		(net "M_B_CPU1_SA_CA<4>")
	)
	(gr_poly
		(pts
			(xy 86.971124 -254.00254) (xy 86.971124 -253.95809) (xy 86.770972 -253.95809) (xy 86.770972 -254.00254)
			(xy 86.871048 -254.102616)
		)
		(stroke
			(width 0)
			(type solid)
		)
		(fill yes)
		(layer "In13.Cu")
		(net "M_B_CPU1_SA_CA<3>")
	)
	(gr_poly
		(pts
			(xy 86.971124 -252.786388) (xy 86.871048 -252.686312) (xy 86.770972 -252.786388) (xy 86.770972 -252.830838)
			(xy 86.971124 -252.830838)
		)
		(stroke
			(width 0)
			(type solid)
		)
		(fill yes)
		(layer "In13.Cu")
		(net "M_B_CPU1_SA_CA<0>")
	)
	(gr_poly
		(pts
			(xy 86.971124 -252.382528) (xy 86.971124 -252.338078) (xy 86.770972 -252.338078) (xy 86.770972 -252.382528)
			(xy 86.871048 -252.482604)
		)
		(stroke
			(width 0)
			(type solid)
		)
		(fill yes)
		(layer "In13.Cu")
		(net "M_B_CPU1_SA_CS_N<1>")
	)
	(gr_poly
		(pts
			(xy 86.971124 -250.762516) (xy 86.971124 -250.718066) (xy 86.770972 -250.718066) (xy 86.770972 -250.762516)
			(xy 86.871048 -250.862592)
		)
		(stroke
			(width 0)
			(type solid)
		)
		(fill yes)
		(layer "In13.Cu")
		(net "M_B_CPU1_RESET_N")
	)
	(gr_poly
		(pts
			(xy 86.971124 -249.142504) (xy 86.971124 -249.098054) (xy 86.770972 -249.098054) (xy 86.770972 -249.142504)
			(xy 86.871048 -249.24258)
		)
		(stroke
			(width 0)
			(type solid)
		)
		(fill yes)
		(layer "In13.Cu")
		(net "M_B_CPU1_SA_CB<7>")
	)
	(gr_poly
		(pts
			(xy 86.971124 -247.926352) (xy 86.871048 -247.826276) (xy 86.770972 -247.926352) (xy 86.770972 -247.970802)
			(xy 86.971124 -247.970802)
		)
		(stroke
			(width 0)
			(type solid)
		)
		(fill yes)
		(layer "In13.Cu")
		(net "M_B_CPU1_SA_CB<4>")
	)
	(gr_poly
		(pts
			(xy 86.971124 -247.522746) (xy 86.971124 -247.474994) (xy 86.770972 -247.474994) (xy 86.770972 -247.522746)
			(xy 86.871048 -247.622568)
		)
		(stroke
			(width 0)
			(type solid)
		)
		(fill yes)
		(layer "In13.Cu")
		(net "M_B_CPU1_SA_DQS_DP<9>")
	)
	(gr_poly
		(pts
			(xy 86.971124 -246.306086) (xy 86.871048 -246.206264) (xy 86.770972 -246.306086) (xy 86.770972 -246.353838)
			(xy 86.971124 -246.353838)
		)
		(stroke
			(width 0)
			(type solid)
		)
		(fill yes)
		(layer "In13.Cu")
		(net "M_B_CPU1_SA_DQS_DP<4>")
	)
	(gr_poly
		(pts
			(xy 86.971124 -245.90248) (xy 86.971124 -245.85803) (xy 86.770972 -245.85803) (xy 86.770972 -245.90248)
			(xy 86.871048 -246.002556)
		)
		(stroke
			(width 0)
			(type solid)
		)
		(fill yes)
		(layer "In13.Cu")
		(net "M_B_CPU1_SA_CB<3>")
	)
	(gr_poly
		(pts
			(xy 86.971124 -244.686328) (xy 86.871048 -244.586252) (xy 86.770972 -244.686328) (xy 86.770972 -244.730778)
			(xy 86.971124 -244.730778)
		)
		(stroke
			(width 0)
			(type solid)
		)
		(fill yes)
		(layer "In13.Cu")
		(net "M_B_CPU1_SA_CB<0>")
	)
	(gr_poly
		(pts
			(xy 86.971124 -244.282468) (xy 86.971124 -244.238018) (xy 86.770972 -244.238018) (xy 86.770972 -244.282468)
			(xy 86.871048 -244.382544)
		)
		(stroke
			(width 0)
			(type solid)
		)
		(fill yes)
		(layer "In13.Cu")
		(net "M_B_CPU1_SA_DQ<31>")
	)
	(gr_poly
		(pts
			(xy 86.971124 -243.066316) (xy 86.871048 -242.96624) (xy 86.770972 -243.066316) (xy 86.770972 -243.110766)
			(xy 86.971124 -243.110766)
		)
		(stroke
			(width 0)
			(type solid)
		)
		(fill yes)
		(layer "In13.Cu")
		(net "M_B_CPU1_SA_DQ<28>")
	)
	(gr_poly
		(pts
			(xy 86.971124 -242.66271) (xy 86.971124 -242.614958) (xy 86.770972 -242.614958) (xy 86.770972 -242.66271)
			(xy 86.871048 -242.762532)
		)
		(stroke
			(width 0)
			(type solid)
		)
		(fill yes)
		(layer "In13.Cu")
		(net "M_B_CPU1_SA_DQS_DP<8>")
	)
	(gr_poly
		(pts
			(xy 86.971124 -241.44605) (xy 86.871048 -241.346228) (xy 86.770972 -241.44605) (xy 86.770972 -241.493802)
			(xy 86.971124 -241.493802)
		)
		(stroke
			(width 0)
			(type solid)
		)
		(fill yes)
		(layer "In13.Cu")
		(net "M_B_CPU1_SA_DQS_DP<3>")
	)
	(gr_poly
		(pts
			(xy 86.971124 -241.042444) (xy 86.971124 -240.997994) (xy 86.770972 -240.997994) (xy 86.770972 -241.042444)
			(xy 86.871048 -241.14252)
		)
		(stroke
			(width 0)
			(type solid)
		)
		(fill yes)
		(layer "In13.Cu")
		(net "M_B_CPU1_SA_DQ<27>")
	)
	(gr_poly
		(pts
			(xy 86.971124 -239.826292) (xy 86.871048 -239.726216) (xy 86.770972 -239.826292) (xy 86.770972 -239.870742)
			(xy 86.971124 -239.870742)
		)
		(stroke
			(width 0)
			(type solid)
		)
		(fill yes)
		(layer "In13.Cu")
		(net "M_B_CPU1_SA_DQ<24>")
	)
	(gr_poly
		(pts
			(xy 86.971124 -239.422432) (xy 86.971124 -239.377982) (xy 86.770972 -239.377982) (xy 86.770972 -239.422432)
			(xy 86.871048 -239.522508)
		)
		(stroke
			(width 0)
			(type solid)
		)
		(fill yes)
		(layer "In13.Cu")
		(net "M_B_CPU1_SA_DQ<23>")
	)
	(gr_poly
		(pts
			(xy 86.971124 -238.20628) (xy 86.871048 -238.106204) (xy 86.770972 -238.20628) (xy 86.770972 -238.25073)
			(xy 86.971124 -238.25073)
		)
		(stroke
			(width 0)
			(type solid)
		)
		(fill yes)
		(layer "In13.Cu")
		(net "M_B_CPU1_SA_DQ<20>")
	)
	(gr_poly
		(pts
			(xy 86.971124 -237.802674) (xy 86.971124 -237.754922) (xy 86.770972 -237.754922) (xy 86.770972 -237.802674)
			(xy 86.871048 -237.902496)
		)
		(stroke
			(width 0)
			(type solid)
		)
		(fill yes)
		(layer "In13.Cu")
		(net "M_B_CPU1_SA_DQS_DP<7>")
	)
	(gr_poly
		(pts
			(xy 86.971124 -236.586014) (xy 86.871048 -236.486192) (xy 86.770972 -236.586014) (xy 86.770972 -236.633766)
			(xy 86.971124 -236.633766)
		)
		(stroke
			(width 0)
			(type solid)
		)
		(fill yes)
		(layer "In13.Cu")
		(net "M_B_CPU1_SA_DQS_DP<2>")
	)
	(gr_poly
		(pts
			(xy 86.971124 -236.182408) (xy 86.971124 -236.137958) (xy 86.770972 -236.137958) (xy 86.770972 -236.182408)
			(xy 86.871048 -236.282484)
		)
		(stroke
			(width 0)
			(type solid)
		)
		(fill yes)
		(layer "In13.Cu")
		(net "M_B_CPU1_SA_DQ<19>")
	)
	(gr_poly
		(pts
			(xy 86.971124 -234.966256) (xy 86.871048 -234.86618) (xy 86.770972 -234.966256) (xy 86.770972 -235.010706)
			(xy 86.971124 -235.010706)
		)
		(stroke
			(width 0)
			(type solid)
		)
		(fill yes)
		(layer "In13.Cu")
		(net "M_B_CPU1_SA_DQ<16>")
	)
	(gr_poly
		(pts
			(xy 86.971124 -234.562396) (xy 86.971124 -234.517946) (xy 86.770972 -234.517946) (xy 86.770972 -234.562396)
			(xy 86.871048 -234.662472)
		)
		(stroke
			(width 0)
			(type solid)
		)
		(fill yes)
		(layer "In13.Cu")
		(net "M_B_CPU1_SA_DQ<15>")
	)
	(gr_poly
		(pts
			(xy 86.971124 -233.346244) (xy 86.871048 -233.246168) (xy 86.770972 -233.346244) (xy 86.770972 -233.390694)
			(xy 86.971124 -233.390694)
		)
		(stroke
			(width 0)
			(type solid)
		)
		(fill yes)
		(layer "In13.Cu")
		(net "M_B_CPU1_SA_DQ<12>")
	)
	(gr_poly
		(pts
			(xy 86.971124 -232.942638) (xy 86.971124 -232.894886) (xy 86.770972 -232.894886) (xy 86.770972 -232.942638)
			(xy 86.871048 -233.04246)
		)
		(stroke
			(width 0)
			(type solid)
		)
		(fill yes)
		(layer "In13.Cu")
		(net "M_B_CPU1_SA_DQS_DP<6>")
	)
	(gr_poly
		(pts
			(xy 86.971124 -231.725978) (xy 86.871048 -231.626156) (xy 86.770972 -231.725978) (xy 86.770972 -231.77373)
			(xy 86.971124 -231.77373)
		)
		(stroke
			(width 0)
			(type solid)
		)
		(fill yes)
		(layer "In13.Cu")
		(net "M_B_CPU1_SA_DQS_DP<1>")
	)
	(gr_poly
		(pts
			(xy 86.971124 -231.322626) (xy 86.971124 -231.278176) (xy 86.770972 -231.278176) (xy 86.770972 -231.322626)
			(xy 86.871048 -231.422702)
		)
		(stroke
			(width 0)
			(type solid)
		)
		(fill yes)
		(layer "In13.Cu")
		(net "M_B_CPU1_SA_DQ<11>")
	)
	(gr_poly
		(pts
			(xy 86.971124 -230.10622) (xy 86.871048 -230.006144) (xy 86.770972 -230.10622) (xy 86.770972 -230.15067)
			(xy 86.971124 -230.15067)
		)
		(stroke
			(width 0)
			(type solid)
		)
		(fill yes)
		(layer "In13.Cu")
		(net "M_B_CPU1_SA_DQ<8>")
	)
	(gr_poly
		(pts
			(xy 86.971124 -229.702614) (xy 86.971124 -229.658164) (xy 86.770972 -229.658164) (xy 86.770972 -229.702614)
			(xy 86.871048 -229.80269)
		)
		(stroke
			(width 0)
			(type solid)
		)
		(fill yes)
		(layer "In13.Cu")
		(net "M_B_CPU1_SA_DQ<7>")
	)
	(gr_poly
		(pts
			(xy 86.971124 -228.486462) (xy 86.871048 -228.386386) (xy 86.770972 -228.486462) (xy 86.770972 -228.530912)
			(xy 86.971124 -228.530912)
		)
		(stroke
			(width 0)
			(type solid)
		)
		(fill yes)
		(layer "In13.Cu")
		(net "M_B_CPU1_SA_DQ<4>")
	)
	(gr_poly
		(pts
			(xy 86.971124 -228.082856) (xy 86.971124 -228.035104) (xy 86.770972 -228.035104) (xy 86.770972 -228.082856)
			(xy 86.871048 -228.182678)
		)
		(stroke
			(width 0)
			(type solid)
		)
		(fill yes)
		(layer "In13.Cu")
		(net "M_B_CPU1_SA_DQS_DP<5>")
	)
	(gr_poly
		(pts
			(xy 86.971124 -226.866196) (xy 86.871048 -226.766374) (xy 86.770972 -226.866196) (xy 86.770972 -226.913948)
			(xy 86.971124 -226.913948)
		)
		(stroke
			(width 0)
			(type solid)
		)
		(fill yes)
		(layer "In13.Cu")
		(net "M_B_CPU1_SA_DQS_DP<0>")
	)
	(gr_poly
		(pts
			(xy 86.971124 -226.46259) (xy 86.971124 -226.41814) (xy 86.770972 -226.41814) (xy 86.770972 -226.46259)
			(xy 86.871048 -226.562666)
		)
		(stroke
			(width 0)
			(type solid)
		)
		(fill yes)
		(layer "In13.Cu")
		(net "M_B_CPU1_SA_DQ<3>")
	)
	(gr_poly
		(pts
			(xy 86.971124 -225.246438) (xy 86.871048 -225.146362) (xy 86.770972 -225.246438) (xy 86.770972 -225.290888)
			(xy 86.971124 -225.290888)
		)
		(stroke
			(width 0)
			(type solid)
		)
		(fill yes)
		(layer "In13.Cu")
		(net "M_B_CPU1_SA_DQ<0>")
	)
	(gr_poly
		(pts
			(xy 87.271098 -292.918134) (xy 87.171022 -292.818058) (xy 87.070946 -292.918134) (xy 87.070946 -292.962584)
			(xy 87.271098 -292.962584)
		)
		(stroke
			(width 0)
			(type solid)
		)
		(fill yes)
		(layer "In13.Cu")
		(net "M_B_CPU1_SB_DQ<29>")
	)
	(gr_poly
		(pts
			(xy 87.271098 -292.514274) (xy 87.271098 -292.469824) (xy 87.070946 -292.469824) (xy 87.070946 -292.514274)
			(xy 87.171022 -292.61435)
		)
		(stroke
			(width 0)
			(type solid)
		)
		(fill yes)
		(layer "In13.Cu")
		(net "M_B_CPU1_SB_DQ<30>")
	)
	(gr_poly
		(pts
			(xy 87.271098 -291.297868) (xy 87.171022 -291.198046) (xy 87.070946 -291.297868) (xy 87.070946 -291.34562)
			(xy 87.271098 -291.34562)
		)
		(stroke
			(width 0)
			(type solid)
		)
		(fill yes)
		(layer "In13.Cu")
		(net "M_B_CPU1_SB_DQS_DN<8>")
	)
	(gr_poly
		(pts
			(xy 87.271098 -290.894516) (xy 87.271098 -290.846764) (xy 87.070946 -290.846764) (xy 87.070946 -290.894516)
			(xy 87.171022 -290.994338)
		)
		(stroke
			(width 0)
			(type solid)
		)
		(fill yes)
		(layer "In13.Cu")
		(net "M_B_CPU1_SB_DQS_DN<3>")
	)
	(gr_poly
		(pts
			(xy 87.271098 -289.67811) (xy 87.171022 -289.578034) (xy 87.070946 -289.67811) (xy 87.070946 -289.72256)
			(xy 87.271098 -289.72256)
		)
		(stroke
			(width 0)
			(type solid)
		)
		(fill yes)
		(layer "In13.Cu")
		(net "M_B_CPU1_SB_DQ<25>")
	)
	(gr_poly
		(pts
			(xy 87.271098 -289.27425) (xy 87.271098 -289.2298) (xy 87.070946 -289.2298) (xy 87.070946 -289.27425)
			(xy 87.171022 -289.374326)
		)
		(stroke
			(width 0)
			(type solid)
		)
		(fill yes)
		(layer "In13.Cu")
		(net "M_B_CPU1_SB_DQ<26>")
	)
	(gr_poly
		(pts
			(xy 87.271098 -288.058098) (xy 87.171022 -287.958022) (xy 87.070946 -288.058098) (xy 87.070946 -288.102548)
			(xy 87.271098 -288.102548)
		)
		(stroke
			(width 0)
			(type solid)
		)
		(fill yes)
		(layer "In13.Cu")
		(net "M_B_CPU1_SB_DQ<21>")
	)
	(gr_poly
		(pts
			(xy 87.271098 -287.654492) (xy 87.271098 -287.610042) (xy 87.070946 -287.610042) (xy 87.070946 -287.654492)
			(xy 87.171022 -287.754568)
		)
		(stroke
			(width 0)
			(type solid)
		)
		(fill yes)
		(layer "In13.Cu")
		(net "M_B_CPU1_SB_DQ<22>")
	)
	(gr_poly
		(pts
			(xy 87.271098 -286.438086) (xy 87.171022 -286.33801) (xy 87.070946 -286.438086) (xy 87.070946 -286.485838)
			(xy 87.271098 -286.485838)
		)
		(stroke
			(width 0)
			(type solid)
		)
		(fill yes)
		(layer "In13.Cu")
		(net "M_B_CPU1_SB_DQS_DN<7>")
	)
	(gr_poly
		(pts
			(xy 87.271098 -286.034734) (xy 87.271098 -285.986982) (xy 87.070946 -285.986982) (xy 87.070946 -286.034734)
			(xy 87.171022 -286.134556)
		)
		(stroke
			(width 0)
			(type solid)
		)
		(fill yes)
		(layer "In13.Cu")
		(net "M_B_CPU1_SB_DQS_DN<2>")
	)
	(gr_poly
		(pts
			(xy 87.271098 -284.818328) (xy 87.171022 -284.718252) (xy 87.070946 -284.818328) (xy 87.070946 -284.862778)
			(xy 87.271098 -284.862778)
		)
		(stroke
			(width 0)
			(type solid)
		)
		(fill yes)
		(layer "In13.Cu")
		(net "M_B_CPU1_SB_DQ<17>")
	)
	(gr_poly
		(pts
			(xy 87.271098 -284.414468) (xy 87.271098 -284.370018) (xy 87.070946 -284.370018) (xy 87.070946 -284.414468)
			(xy 87.171022 -284.514544)
		)
		(stroke
			(width 0)
			(type solid)
		)
		(fill yes)
		(layer "In13.Cu")
		(net "M_B_CPU1_SB_DQ<18>")
	)
	(gr_poly
		(pts
			(xy 87.271098 -283.198316) (xy 87.171022 -283.09824) (xy 87.070946 -283.198316) (xy 87.070946 -283.242766)
			(xy 87.271098 -283.242766)
		)
		(stroke
			(width 0)
			(type solid)
		)
		(fill yes)
		(layer "In13.Cu")
		(net "M_B_CPU1_SB_DQ<13>")
	)
	(gr_poly
		(pts
			(xy 87.271098 -282.794456) (xy 87.271098 -282.750006) (xy 87.070946 -282.750006) (xy 87.070946 -282.794456)
			(xy 87.171022 -282.894532)
		)
		(stroke
			(width 0)
			(type solid)
		)
		(fill yes)
		(layer "In13.Cu")
		(net "M_B_CPU1_SB_DQ<14>")
	)
	(gr_poly
		(pts
			(xy 87.271098 -281.57805) (xy 87.171022 -281.478228) (xy 87.070946 -281.57805) (xy 87.070946 -281.625802)
			(xy 87.271098 -281.625802)
		)
		(stroke
			(width 0)
			(type solid)
		)
		(fill yes)
		(layer "In13.Cu")
		(net "M_B_CPU1_SB_DQS_DN<6>")
	)
	(gr_poly
		(pts
			(xy 87.271098 -281.174698) (xy 87.271098 -281.126946) (xy 87.070946 -281.126946) (xy 87.070946 -281.174698)
			(xy 87.171022 -281.27452)
		)
		(stroke
			(width 0)
			(type solid)
		)
		(fill yes)
		(layer "In13.Cu")
		(net "M_B_CPU1_SB_DQS_DN<1>")
	)
	(gr_poly
		(pts
			(xy 87.271098 -279.958292) (xy 87.171022 -279.858216) (xy 87.070946 -279.958292) (xy 87.070946 -280.002742)
			(xy 87.271098 -280.002742)
		)
		(stroke
			(width 0)
			(type solid)
		)
		(fill yes)
		(layer "In13.Cu")
		(net "M_B_CPU1_SB_DQ<9>")
	)
	(gr_poly
		(pts
			(xy 87.271098 -279.554432) (xy 87.271098 -279.509982) (xy 87.070946 -279.509982) (xy 87.070946 -279.554432)
			(xy 87.171022 -279.654508)
		)
		(stroke
			(width 0)
			(type solid)
		)
		(fill yes)
		(layer "In13.Cu")
		(net "M_B_CPU1_SB_DQ<10>")
	)
	(gr_poly
		(pts
			(xy 87.271098 -278.33828) (xy 87.171022 -278.238204) (xy 87.070946 -278.33828) (xy 87.070946 -278.38273)
			(xy 87.271098 -278.38273)
		)
		(stroke
			(width 0)
			(type solid)
		)
		(fill yes)
		(layer "In13.Cu")
		(net "M_B_CPU1_SB_DQ<5>")
	)
	(gr_poly
		(pts
			(xy 87.271098 -277.93442) (xy 87.271098 -277.88997) (xy 87.070946 -277.88997) (xy 87.070946 -277.93442)
			(xy 87.171022 -278.034496)
		)
		(stroke
			(width 0)
			(type solid)
		)
		(fill yes)
		(layer "In13.Cu")
		(net "M_B_CPU1_SB_DQ<6>")
	)
	(gr_poly
		(pts
			(xy 87.271098 -276.718014) (xy 87.171022 -276.618192) (xy 87.070946 -276.718014) (xy 87.070946 -276.765766)
			(xy 87.271098 -276.765766)
		)
		(stroke
			(width 0)
			(type solid)
		)
		(fill yes)
		(layer "In13.Cu")
		(net "M_B_CPU1_SB_DQS_DN<5>")
	)
	(gr_poly
		(pts
			(xy 87.271098 -276.314662) (xy 87.271098 -276.26691) (xy 87.070946 -276.26691) (xy 87.070946 -276.314662)
			(xy 87.171022 -276.414484)
		)
		(stroke
			(width 0)
			(type solid)
		)
		(fill yes)
		(layer "In13.Cu")
		(net "M_B_CPU1_SB_DQS_DN<0>")
	)
	(gr_poly
		(pts
			(xy 87.271098 -275.098256) (xy 87.171022 -274.99818) (xy 87.070946 -275.098256) (xy 87.070946 -275.142706)
			(xy 87.271098 -275.142706)
		)
		(stroke
			(width 0)
			(type solid)
		)
		(fill yes)
		(layer "In13.Cu")
		(net "M_B_CPU1_SB_DQ<1>")
	)
	(gr_poly
		(pts
			(xy 87.271098 -274.694396) (xy 87.271098 -274.649946) (xy 87.070946 -274.649946) (xy 87.070946 -274.694396)
			(xy 87.171022 -274.794472)
		)
		(stroke
			(width 0)
			(type solid)
		)
		(fill yes)
		(layer "In13.Cu")
		(net "M_B_CPU1_SB_DQ<2>")
	)
	(gr_poly
		(pts
			(xy 87.271098 -273.478244) (xy 87.171022 -273.378168) (xy 87.070946 -273.478244) (xy 87.070946 -273.522694)
			(xy 87.271098 -273.522694)
		)
		(stroke
			(width 0)
			(type solid)
		)
		(fill yes)
		(layer "In13.Cu")
		(net "M_B_CPU1_SB_CB<1>")
	)
	(gr_poly
		(pts
			(xy 87.271098 -273.074384) (xy 87.271098 -273.029934) (xy 87.070946 -273.029934) (xy 87.070946 -273.074384)
			(xy 87.171022 -273.17446)
		)
		(stroke
			(width 0)
			(type solid)
		)
		(fill yes)
		(layer "In13.Cu")
		(net "M_B_CPU1_SB_CB<2>")
	)
	(gr_poly
		(pts
			(xy 87.271098 -271.857978) (xy 87.171022 -271.758156) (xy 87.070946 -271.857978) (xy 87.070946 -271.90573)
			(xy 87.271098 -271.90573)
		)
		(stroke
			(width 0)
			(type solid)
		)
		(fill yes)
		(layer "In13.Cu")
		(net "M_B_CPU1_SB_DQS_DN<4>")
	)
	(gr_poly
		(pts
			(xy 87.271098 -271.454626) (xy 87.271098 -271.406874) (xy 87.070946 -271.406874) (xy 87.070946 -271.454626)
			(xy 87.171022 -271.554448)
		)
		(stroke
			(width 0)
			(type solid)
		)
		(fill yes)
		(layer "In13.Cu")
		(net "M_B_CPU1_SB_DQS_DN<9>")
	)
	(gr_poly
		(pts
			(xy 87.271098 -270.23822) (xy 87.171022 -270.138144) (xy 87.070946 -270.23822) (xy 87.070946 -270.28267)
			(xy 87.271098 -270.28267)
		)
		(stroke
			(width 0)
			(type solid)
		)
		(fill yes)
		(layer "In13.Cu")
		(net "M_B_CPU1_SB_CB<5>")
	)
	(gr_poly
		(pts
			(xy 87.271098 -269.83436) (xy 87.271098 -269.78991) (xy 87.070946 -269.78991) (xy 87.070946 -269.83436)
			(xy 87.171022 -269.934436)
		)
		(stroke
			(width 0)
			(type solid)
		)
		(fill yes)
		(layer "In13.Cu")
		(net "M_B_CPU1_SB_CB<6>")
	)
	(gr_poly
		(pts
			(xy 87.271098 -266.991846) (xy 87.171022 -266.89177) (xy 87.070946 -266.991846) (xy 87.070946 -267.036296)
			(xy 87.271098 -267.036296)
		)
		(stroke
			(width 0)
			(type solid)
		)
		(fill yes)
		(layer "In13.Cu")
		(net "M_B_CPU1_SA_RSP<0>")
	)
	(gr_poly
		(pts
			(xy 87.271098 -266.594336) (xy 87.271098 -266.549886) (xy 87.070946 -266.549886) (xy 87.070946 -266.594336)
			(xy 87.171022 -266.694412)
		)
		(stroke
			(width 0)
			(type solid)
		)
		(fill yes)
		(layer "In13.Cu")
		(net "M_B_CPU1_SB_CS_N<1>")
	)
	(gr_poly
		(pts
			(xy 87.271098 -264.974324) (xy 87.271098 -264.929874) (xy 87.070946 -264.929874) (xy 87.070946 -264.974324)
			(xy 87.171022 -265.0744)
		)
		(stroke
			(width 0)
			(type solid)
		)
		(fill yes)
		(layer "In13.Cu")
		(net "M_B_CPU1_SB_PAR")
	)
	(gr_poly
		(pts
			(xy 87.271098 -263.758172) (xy 87.171022 -263.658096) (xy 87.070946 -263.758172) (xy 87.070946 -263.802622)
			(xy 87.271098 -263.802622)
		)
		(stroke
			(width 0)
			(type solid)
		)
		(fill yes)
		(layer "In13.Cu")
		(net "M_B_CPU1_SB_CA<4>")
	)
	(gr_poly
		(pts
			(xy 87.271098 -263.354312) (xy 87.271098 -263.309862) (xy 87.070946 -263.309862) (xy 87.070946 -263.354312)
			(xy 87.171022 -263.454388)
		)
		(stroke
			(width 0)
			(type solid)
		)
		(fill yes)
		(layer "In13.Cu")
		(net "M_B_CPU1_SB_CA<3>")
	)
	(gr_poly
		(pts
			(xy 87.271098 -262.13816) (xy 87.171022 -262.038084) (xy 87.070946 -262.13816) (xy 87.070946 -262.18261)
			(xy 87.271098 -262.18261)
		)
		(stroke
			(width 0)
			(type solid)
		)
		(fill yes)
		(layer "In13.Cu")
		(net "M_B_CPU1_SB_CA<0>")
	)
	(gr_poly
		(pts
			(xy 87.441024 -256.432812) (xy 87.441024 -256.38506) (xy 87.240872 -256.38506) (xy 87.240872 -256.432812)
			(xy 87.340948 -256.532634)
		)
		(stroke
			(width 0)
			(type solid)
		)
		(fill yes)
		(layer "In13.Cu")
		(net "M_B_CPU1_CLK_DN<0>")
	)
	(gr_poly
		(pts
			(xy 87.441024 -255.216406) (xy 87.340948 -255.11633) (xy 87.240872 -255.216406) (xy 87.240872 -255.260856)
			(xy 87.441024 -255.260856)
		)
		(stroke
			(width 0)
			(type solid)
		)
		(fill yes)
		(layer "In13.Cu")
		(net "M_B_CPU1_SA_CA<6>")
	)
	(gr_poly
		(pts
			(xy 87.441024 -254.812546) (xy 87.441024 -254.768096) (xy 87.240872 -254.768096) (xy 87.240872 -254.812546)
			(xy 87.340948 -254.912622)
		)
		(stroke
			(width 0)
			(type solid)
		)
		(fill yes)
		(layer "In13.Cu")
		(net "M_B_CPU1_SA_CA<5>")
	)
	(gr_poly
		(pts
			(xy 87.441024 -253.596394) (xy 87.340948 -253.496318) (xy 87.240872 -253.596394) (xy 87.240872 -253.640844)
			(xy 87.441024 -253.640844)
		)
		(stroke
			(width 0)
			(type solid)
		)
		(fill yes)
		(layer "In13.Cu")
		(net "M_B_CPU1_SA_CA<2>")
	)
	(gr_poly
		(pts
			(xy 87.441024 -253.192534) (xy 87.441024 -253.148084) (xy 87.240872 -253.148084) (xy 87.240872 -253.192534)
			(xy 87.340948 -253.29261)
		)
		(stroke
			(width 0)
			(type solid)
		)
		(fill yes)
		(layer "In13.Cu")
		(net "M_B_CPU1_SA_CA<1>")
	)
	(gr_poly
		(pts
			(xy 87.441024 -251.572522) (xy 87.441024 -251.528072) (xy 87.240872 -251.528072) (xy 87.240872 -251.572522)
			(xy 87.340948 -251.672598)
		)
		(stroke
			(width 0)
			(type solid)
		)
		(fill yes)
		(layer "In13.Cu")
		(net "M_B_CPU1_SA_CS_N<0>")
	)
	(gr_poly
		(pts
			(xy 87.441024 -250.35637) (xy 87.340948 -250.256294) (xy 87.240872 -250.35637) (xy 87.240872 -250.40082)
			(xy 87.441024 -250.40082)
		)
		(stroke
			(width 0)
			(type solid)
		)
		(fill yes)
		(layer "In13.Cu")
		(net "M_B_CPU1_ALERT_R_N")
	)
	(gr_poly
		(pts
			(xy 87.441024 -248.736358) (xy 87.340948 -248.636282) (xy 87.240872 -248.736358) (xy 87.240872 -248.780808)
			(xy 87.441024 -248.780808)
		)
		(stroke
			(width 0)
			(type solid)
		)
		(fill yes)
		(layer "In13.Cu")
		(net "M_B_CPU1_SA_CB<5>")
	)
	(gr_poly
		(pts
			(xy 87.441024 -248.332498) (xy 87.441024 -248.288048) (xy 87.240872 -248.288048) (xy 87.240872 -248.332498)
			(xy 87.340948 -248.432574)
		)
		(stroke
			(width 0)
			(type solid)
		)
		(fill yes)
		(layer "In13.Cu")
		(net "M_B_CPU1_SA_CB<6>")
	)
	(gr_poly
		(pts
			(xy 87.441024 -247.116092) (xy 87.340948 -247.01627) (xy 87.240872 -247.116092) (xy 87.240872 -247.163844)
			(xy 87.441024 -247.163844)
		)
		(stroke
			(width 0)
			(type solid)
		)
		(fill yes)
		(layer "In13.Cu")
		(net "M_B_CPU1_SA_DQS_DN<9>")
	)
	(gr_poly
		(pts
			(xy 87.441024 -246.71274) (xy 87.441024 -246.664988) (xy 87.240872 -246.664988) (xy 87.240872 -246.71274)
			(xy 87.340948 -246.812562)
		)
		(stroke
			(width 0)
			(type solid)
		)
		(fill yes)
		(layer "In13.Cu")
		(net "M_B_CPU1_SA_DQS_DN<4>")
	)
	(gr_poly
		(pts
			(xy 87.441024 -245.496334) (xy 87.340948 -245.396258) (xy 87.240872 -245.496334) (xy 87.240872 -245.540784)
			(xy 87.441024 -245.540784)
		)
		(stroke
			(width 0)
			(type solid)
		)
		(fill yes)
		(layer "In13.Cu")
		(net "M_B_CPU1_SA_CB<1>")
	)
	(gr_poly
		(pts
			(xy 87.441024 -245.092474) (xy 87.441024 -245.048024) (xy 87.240872 -245.048024) (xy 87.240872 -245.092474)
			(xy 87.340948 -245.19255)
		)
		(stroke
			(width 0)
			(type solid)
		)
		(fill yes)
		(layer "In13.Cu")
		(net "M_B_CPU1_SA_CB<2>")
	)
	(gr_poly
		(pts
			(xy 87.441024 -243.876322) (xy 87.340948 -243.776246) (xy 87.240872 -243.876322) (xy 87.240872 -243.920772)
			(xy 87.441024 -243.920772)
		)
		(stroke
			(width 0)
			(type solid)
		)
		(fill yes)
		(layer "In13.Cu")
		(net "M_B_CPU1_SA_DQ<29>")
	)
	(gr_poly
		(pts
			(xy 87.441024 -243.472462) (xy 87.441024 -243.428012) (xy 87.240872 -243.428012) (xy 87.240872 -243.472462)
			(xy 87.340948 -243.572538)
		)
		(stroke
			(width 0)
			(type solid)
		)
		(fill yes)
		(layer "In13.Cu")
		(net "M_B_CPU1_SA_DQ<30>")
	)
	(gr_poly
		(pts
			(xy 87.441024 -242.256056) (xy 87.340948 -242.156234) (xy 87.240872 -242.256056) (xy 87.240872 -242.303808)
			(xy 87.441024 -242.303808)
		)
		(stroke
			(width 0)
			(type solid)
		)
		(fill yes)
		(layer "In13.Cu")
		(net "M_B_CPU1_SA_DQS_DN<8>")
	)
	(gr_poly
		(pts
			(xy 87.441024 -241.852704) (xy 87.441024 -241.804952) (xy 87.240872 -241.804952) (xy 87.240872 -241.852704)
			(xy 87.340948 -241.952526)
		)
		(stroke
			(width 0)
			(type solid)
		)
		(fill yes)
		(layer "In13.Cu")
		(net "M_B_CPU1_SA_DQS_DN<3>")
	)
	(gr_poly
		(pts
			(xy 87.441024 -240.636298) (xy 87.340948 -240.536222) (xy 87.240872 -240.636298) (xy 87.240872 -240.680748)
			(xy 87.441024 -240.680748)
		)
		(stroke
			(width 0)
			(type solid)
		)
		(fill yes)
		(layer "In13.Cu")
		(net "M_B_CPU1_SA_DQ<25>")
	)
	(gr_poly
		(pts
			(xy 87.441024 -240.232438) (xy 87.441024 -240.187988) (xy 87.240872 -240.187988) (xy 87.240872 -240.232438)
			(xy 87.340948 -240.332514)
		)
		(stroke
			(width 0)
			(type solid)
		)
		(fill yes)
		(layer "In13.Cu")
		(net "M_B_CPU1_SA_DQ<26>")
	)
	(gr_poly
		(pts
			(xy 87.441024 -239.016286) (xy 87.340948 -238.91621) (xy 87.240872 -239.016286) (xy 87.240872 -239.060736)
			(xy 87.441024 -239.060736)
		)
		(stroke
			(width 0)
			(type solid)
		)
		(fill yes)
		(layer "In13.Cu")
		(net "M_B_CPU1_SA_DQ<21>")
	)
	(gr_poly
		(pts
			(xy 87.441024 -238.612426) (xy 87.441024 -238.567976) (xy 87.240872 -238.567976) (xy 87.240872 -238.612426)
			(xy 87.340948 -238.712502)
		)
		(stroke
			(width 0)
			(type solid)
		)
		(fill yes)
		(layer "In13.Cu")
		(net "M_B_CPU1_SA_DQ<22>")
	)
	(gr_poly
		(pts
			(xy 87.441024 -237.39602) (xy 87.340948 -237.296198) (xy 87.240872 -237.39602) (xy 87.240872 -237.443772)
			(xy 87.441024 -237.443772)
		)
		(stroke
			(width 0)
			(type solid)
		)
		(fill yes)
		(layer "In13.Cu")
		(net "M_B_CPU1_SA_DQS_DN<7>")
	)
	(gr_poly
		(pts
			(xy 87.441024 -236.992668) (xy 87.441024 -236.944916) (xy 87.240872 -236.944916) (xy 87.240872 -236.992668)
			(xy 87.340948 -237.09249)
		)
		(stroke
			(width 0)
			(type solid)
		)
		(fill yes)
		(layer "In13.Cu")
		(net "M_B_CPU1_SA_DQS_DN<2>")
	)
	(gr_poly
		(pts
			(xy 87.441024 -235.776262) (xy 87.340948 -235.676186) (xy 87.240872 -235.776262) (xy 87.240872 -235.820712)
			(xy 87.441024 -235.820712)
		)
		(stroke
			(width 0)
			(type solid)
		)
		(fill yes)
		(layer "In13.Cu")
		(net "M_B_CPU1_SA_DQ<17>")
	)
	(gr_poly
		(pts
			(xy 87.441024 -235.372402) (xy 87.441024 -235.327952) (xy 87.240872 -235.327952) (xy 87.240872 -235.372402)
			(xy 87.340948 -235.472478)
		)
		(stroke
			(width 0)
			(type solid)
		)
		(fill yes)
		(layer "In13.Cu")
		(net "M_B_CPU1_SA_DQ<18>")
	)
	(gr_poly
		(pts
			(xy 87.441024 -234.15625) (xy 87.340948 -234.056174) (xy 87.240872 -234.15625) (xy 87.240872 -234.2007)
			(xy 87.441024 -234.2007)
		)
		(stroke
			(width 0)
			(type solid)
		)
		(fill yes)
		(layer "In13.Cu")
		(net "M_B_CPU1_SA_DQ<13>")
	)
	(gr_poly
		(pts
			(xy 87.441024 -233.75239) (xy 87.441024 -233.70794) (xy 87.240872 -233.70794) (xy 87.240872 -233.75239)
			(xy 87.340948 -233.852466)
		)
		(stroke
			(width 0)
			(type solid)
		)
		(fill yes)
		(layer "In13.Cu")
		(net "M_B_CPU1_SA_DQ<14>")
	)
	(gr_poly
		(pts
			(xy 87.441024 -232.535984) (xy 87.340948 -232.436162) (xy 87.240872 -232.535984) (xy 87.240872 -232.583736)
			(xy 87.441024 -232.583736)
		)
		(stroke
			(width 0)
			(type solid)
		)
		(fill yes)
		(layer "In13.Cu")
		(net "M_B_CPU1_SA_DQS_DN<6>")
	)
	(gr_poly
		(pts
			(xy 87.441024 -232.132632) (xy 87.441024 -232.08488) (xy 87.240872 -232.08488) (xy 87.240872 -232.132632)
			(xy 87.340948 -232.232454)
		)
		(stroke
			(width 0)
			(type solid)
		)
		(fill yes)
		(layer "In13.Cu")
		(net "M_B_CPU1_SA_DQS_DN<1>")
	)
	(gr_poly
		(pts
			(xy 87.441024 -230.916226) (xy 87.340948 -230.81615) (xy 87.240872 -230.916226) (xy 87.240872 -230.960676)
			(xy 87.441024 -230.960676)
		)
		(stroke
			(width 0)
			(type solid)
		)
		(fill yes)
		(layer "In13.Cu")
		(net "M_B_CPU1_SA_DQ<9>")
	)
	(gr_poly
		(pts
			(xy 87.441024 -230.51262) (xy 87.441024 -230.46817) (xy 87.240872 -230.46817) (xy 87.240872 -230.51262)
			(xy 87.340948 -230.612696)
		)
		(stroke
			(width 0)
			(type solid)
		)
		(fill yes)
		(layer "In13.Cu")
		(net "M_B_CPU1_SA_DQ<10>")
	)
	(gr_poly
		(pts
			(xy 87.441024 -229.296214) (xy 87.340948 -229.196138) (xy 87.240872 -229.296214) (xy 87.240872 -229.340664)
			(xy 87.441024 -229.340664)
		)
		(stroke
			(width 0)
			(type solid)
		)
		(fill yes)
		(layer "In13.Cu")
		(net "M_B_CPU1_SA_DQ<5>")
	)
	(gr_poly
		(pts
			(xy 87.441024 -228.892608) (xy 87.441024 -228.848158) (xy 87.240872 -228.848158) (xy 87.240872 -228.892608)
			(xy 87.340948 -228.992684)
		)
		(stroke
			(width 0)
			(type solid)
		)
		(fill yes)
		(layer "In13.Cu")
		(net "M_B_CPU1_SA_DQ<6>")
	)
	(gr_poly
		(pts
			(xy 87.441024 -227.27285) (xy 87.441024 -227.225098) (xy 87.240872 -227.225098) (xy 87.240872 -227.27285)
			(xy 87.340948 -227.372672)
		)
		(stroke
			(width 0)
			(type solid)
		)
		(fill yes)
		(layer "In13.Cu")
		(net "M_B_CPU1_SA_DQS_DN<0>")
	)
	(gr_poly
		(pts
			(xy 87.441024 -226.056444) (xy 87.340948 -225.956368) (xy 87.240872 -226.056444) (xy 87.240872 -226.100894)
			(xy 87.441024 -226.100894)
		)
		(stroke
			(width 0)
			(type solid)
		)
		(fill yes)
		(layer "In13.Cu")
		(net "M_B_CPU1_SA_DQ<1>")
	)
	(gr_poly
		(pts
			(xy 87.441024 -225.652584) (xy 87.441024 -225.608134) (xy 87.240872 -225.608134) (xy 87.240872 -225.652584)
			(xy 87.340948 -225.75266)
		)
		(stroke
			(width 0)
			(type solid)
		)
		(fill yes)
		(layer "In13.Cu")
		(net "M_B_CPU1_SA_DQ<2>")
	)
	(gr_poly
		(pts
			(xy 87.44712 -227.67671) (xy 87.347044 -227.576634) (xy 87.247222 -227.67671) (xy 87.247222 -227.724208)
			(xy 87.44712 -227.724208)
		)
		(stroke
			(width 0)
			(type solid)
		)
		(fill yes)
		(layer "In13.Cu")
		(net "M_B_CPU1_SA_DQS_DN<5>")
	)
	(gr_poly
		(pts
			(xy 87.740998 -293.32428) (xy 87.740998 -293.27983) (xy 87.540846 -293.27983) (xy 87.540846 -293.32428)
			(xy 87.640922 -293.424356)
		)
		(stroke
			(width 0)
			(type solid)
		)
		(fill yes)
		(layer "In13.Cu")
		(net "M_B_CPU1_SB_DQ<31>")
	)
	(gr_poly
		(pts
			(xy 87.740998 -292.108128) (xy 87.640922 -292.008052) (xy 87.540846 -292.108128) (xy 87.540846 -292.152578)
			(xy 87.740998 -292.152578)
		)
		(stroke
			(width 0)
			(type solid)
		)
		(fill yes)
		(layer "In13.Cu")
		(net "M_B_CPU1_SB_DQ<28>")
	)
	(gr_poly
		(pts
			(xy 87.740998 -291.704522) (xy 87.740998 -291.65677) (xy 87.540846 -291.65677) (xy 87.540846 -291.704522)
			(xy 87.640922 -291.804344)
		)
		(stroke
			(width 0)
			(type solid)
		)
		(fill yes)
		(layer "In13.Cu")
		(net "M_B_CPU1_SB_DQS_DP<8>")
	)
	(gr_poly
		(pts
			(xy 87.740998 -290.487862) (xy 87.640922 -290.38804) (xy 87.540846 -290.487862) (xy 87.540846 -290.535614)
			(xy 87.740998 -290.535614)
		)
		(stroke
			(width 0)
			(type solid)
		)
		(fill yes)
		(layer "In13.Cu")
		(net "M_B_CPU1_SB_DQS_DP<3>")
	)
	(gr_poly
		(pts
			(xy 87.740998 -290.084256) (xy 87.740998 -290.039806) (xy 87.540846 -290.039806) (xy 87.540846 -290.084256)
			(xy 87.640922 -290.184332)
		)
		(stroke
			(width 0)
			(type solid)
		)
		(fill yes)
		(layer "In13.Cu")
		(net "M_B_CPU1_SB_DQ<27>")
	)
	(gr_poly
		(pts
			(xy 87.740998 -288.868104) (xy 87.640922 -288.768028) (xy 87.540846 -288.868104) (xy 87.540846 -288.912554)
			(xy 87.740998 -288.912554)
		)
		(stroke
			(width 0)
			(type solid)
		)
		(fill yes)
		(layer "In13.Cu")
		(net "M_B_CPU1_SB_DQ<24>")
	)
	(gr_poly
		(pts
			(xy 87.740998 -288.464498) (xy 87.740998 -288.420048) (xy 87.540846 -288.420048) (xy 87.540846 -288.464498)
			(xy 87.640922 -288.564574)
		)
		(stroke
			(width 0)
			(type solid)
		)
		(fill yes)
		(layer "In13.Cu")
		(net "M_B_CPU1_SB_DQ<23>")
	)
	(gr_poly
		(pts
			(xy 87.740998 -287.248092) (xy 87.640922 -287.148016) (xy 87.540846 -287.248092) (xy 87.540846 -287.292542)
			(xy 87.740998 -287.292542)
		)
		(stroke
			(width 0)
			(type solid)
		)
		(fill yes)
		(layer "In13.Cu")
		(net "M_B_CPU1_SB_DQ<20>")
	)
	(gr_poly
		(pts
			(xy 87.740998 -286.844486) (xy 87.740998 -286.796734) (xy 87.540846 -286.796734) (xy 87.540846 -286.844486)
			(xy 87.640922 -286.944562)
		)
		(stroke
			(width 0)
			(type solid)
		)
		(fill yes)
		(layer "In13.Cu")
		(net "M_B_CPU1_SB_DQS_DP<7>")
	)
	(gr_poly
		(pts
			(xy 87.740998 -285.62808) (xy 87.640922 -285.528258) (xy 87.540846 -285.62808) (xy 87.540846 -285.675832)
			(xy 87.740998 -285.675832)
		)
		(stroke
			(width 0)
			(type solid)
		)
		(fill yes)
		(layer "In13.Cu")
		(net "M_B_CPU1_SB_DQS_DP<2>")
	)
	(gr_poly
		(pts
			(xy 87.740998 -285.224474) (xy 87.740998 -285.180024) (xy 87.540846 -285.180024) (xy 87.540846 -285.224474)
			(xy 87.640922 -285.32455)
		)
		(stroke
			(width 0)
			(type solid)
		)
		(fill yes)
		(layer "In13.Cu")
		(net "M_B_CPU1_SB_DQ<19>")
	)
	(gr_poly
		(pts
			(xy 87.740998 -284.008322) (xy 87.640922 -283.908246) (xy 87.540846 -284.008322) (xy 87.540846 -284.052772)
			(xy 87.740998 -284.052772)
		)
		(stroke
			(width 0)
			(type solid)
		)
		(fill yes)
		(layer "In13.Cu")
		(net "M_B_CPU1_SB_DQ<16>")
	)
	(gr_poly
		(pts
			(xy 87.740998 -283.604462) (xy 87.740998 -283.560012) (xy 87.540846 -283.560012) (xy 87.540846 -283.604462)
			(xy 87.640922 -283.704538)
		)
		(stroke
			(width 0)
			(type solid)
		)
		(fill yes)
		(layer "In13.Cu")
		(net "M_B_CPU1_SB_DQ<15>")
	)
	(gr_poly
		(pts
			(xy 87.740998 -282.38831) (xy 87.640922 -282.288234) (xy 87.540846 -282.38831) (xy 87.540846 -282.43276)
			(xy 87.740998 -282.43276)
		)
		(stroke
			(width 0)
			(type solid)
		)
		(fill yes)
		(layer "In13.Cu")
		(net "M_B_CPU1_SB_DQ<12>")
	)
	(gr_poly
		(pts
			(xy 87.740998 -281.984704) (xy 87.740998 -281.936952) (xy 87.540846 -281.936952) (xy 87.540846 -281.984704)
			(xy 87.640922 -282.084526)
		)
		(stroke
			(width 0)
			(type solid)
		)
		(fill yes)
		(layer "In13.Cu")
		(net "M_B_CPU1_SB_DQS_DP<6>")
	)
	(gr_poly
		(pts
			(xy 87.740998 -280.768044) (xy 87.640922 -280.668222) (xy 87.540846 -280.768044) (xy 87.540846 -280.815796)
			(xy 87.740998 -280.815796)
		)
		(stroke
			(width 0)
			(type solid)
		)
		(fill yes)
		(layer "In13.Cu")
		(net "M_B_CPU1_SB_DQS_DP<1>")
	)
	(gr_poly
		(pts
			(xy 87.740998 -280.364438) (xy 87.740998 -280.319988) (xy 87.540846 -280.319988) (xy 87.540846 -280.364438)
			(xy 87.640922 -280.464514)
		)
		(stroke
			(width 0)
			(type solid)
		)
		(fill yes)
		(layer "In13.Cu")
		(net "M_B_CPU1_SB_DQ<11>")
	)
	(gr_poly
		(pts
			(xy 87.740998 -279.148286) (xy 87.640922 -279.04821) (xy 87.540846 -279.148286) (xy 87.540846 -279.192736)
			(xy 87.740998 -279.192736)
		)
		(stroke
			(width 0)
			(type solid)
		)
		(fill yes)
		(layer "In13.Cu")
		(net "M_B_CPU1_SB_DQ<8>")
	)
	(gr_poly
		(pts
			(xy 87.740998 -278.744426) (xy 87.740998 -278.699976) (xy 87.540846 -278.699976) (xy 87.540846 -278.744426)
			(xy 87.640922 -278.844502)
		)
		(stroke
			(width 0)
			(type solid)
		)
		(fill yes)
		(layer "In13.Cu")
		(net "M_B_CPU1_SB_DQ<7>")
	)
	(gr_poly
		(pts
			(xy 87.740998 -277.528274) (xy 87.640922 -277.428198) (xy 87.540846 -277.528274) (xy 87.540846 -277.572724)
			(xy 87.740998 -277.572724)
		)
		(stroke
			(width 0)
			(type solid)
		)
		(fill yes)
		(layer "In13.Cu")
		(net "M_B_CPU1_SB_DQ<4>")
	)
	(gr_poly
		(pts
			(xy 87.740998 -275.504402) (xy 87.740998 -275.459952) (xy 87.540846 -275.459952) (xy 87.540846 -275.504402)
			(xy 87.640922 -275.604478)
		)
		(stroke
			(width 0)
			(type solid)
		)
		(fill yes)
		(layer "In13.Cu")
		(net "M_B_CPU1_SB_DQ<3>")
	)
	(gr_poly
		(pts
			(xy 87.740998 -274.28825) (xy 87.640922 -274.188174) (xy 87.540846 -274.28825) (xy 87.540846 -274.3327)
			(xy 87.740998 -274.3327)
		)
		(stroke
			(width 0)
			(type solid)
		)
		(fill yes)
		(layer "In13.Cu")
		(net "M_B_CPU1_SB_DQ<0>")
	)
	(gr_poly
		(pts
			(xy 87.740998 -273.88439) (xy 87.740998 -273.83994) (xy 87.540846 -273.83994) (xy 87.540846 -273.88439)
			(xy 87.640922 -273.984466)
		)
		(stroke
			(width 0)
			(type solid)
		)
		(fill yes)
		(layer "In13.Cu")
		(net "M_B_CPU1_SB_CB<3>")
	)
	(gr_poly
		(pts
			(xy 87.740998 -272.668238) (xy 87.640922 -272.568162) (xy 87.540846 -272.668238) (xy 87.540846 -272.712688)
			(xy 87.740998 -272.712688)
		)
		(stroke
			(width 0)
			(type solid)
		)
		(fill yes)
		(layer "In13.Cu")
		(net "M_B_CPU1_SB_CB<0>")
	)
	(gr_poly
		(pts
			(xy 87.740998 -272.264632) (xy 87.740998 -272.21688) (xy 87.540846 -272.21688) (xy 87.540846 -272.264632)
			(xy 87.640922 -272.364454)
		)
		(stroke
			(width 0)
			(type solid)
		)
		(fill yes)
		(layer "In13.Cu")
		(net "M_B_CPU1_SB_DQS_DP<4>")
	)
	(gr_poly
		(pts
			(xy 87.740998 -271.047972) (xy 87.640922 -270.94815) (xy 87.540846 -271.047972) (xy 87.540846 -271.095724)
			(xy 87.740998 -271.095724)
		)
		(stroke
			(width 0)
			(type solid)
		)
		(fill yes)
		(layer "In13.Cu")
		(net "M_B_CPU1_SB_DQS_DP<9>")
	)
	(gr_poly
		(pts
			(xy 87.740998 -270.644366) (xy 87.740998 -270.599916) (xy 87.540846 -270.599916) (xy 87.540846 -270.644366)
			(xy 87.640922 -270.744442)
		)
		(stroke
			(width 0)
			(type solid)
		)
		(fill yes)
		(layer "In13.Cu")
		(net "M_B_CPU1_SB_CB<7>")
	)
	(gr_poly
		(pts
			(xy 87.740998 -269.428214) (xy 87.640922 -269.328138) (xy 87.540846 -269.428214) (xy 87.540846 -269.472664)
			(xy 87.740998 -269.472664)
		)
		(stroke
			(width 0)
			(type solid)
		)
		(fill yes)
		(layer "In13.Cu")
		(net "M_B_CPU1_SB_CB<4>")
	)
	(gr_poly
		(pts
			(xy 87.740998 -265.78433) (xy 87.740998 -265.73988) (xy 87.540846 -265.73988) (xy 87.540846 -265.78433)
			(xy 87.640922 -265.884406)
		)
		(stroke
			(width 0)
			(type solid)
		)
		(fill yes)
		(layer "In13.Cu")
		(net "M_B_CPU1_SB_CS_N<0>")
	)
	(gr_poly
		(pts
			(xy 87.740998 -264.568178) (xy 87.640922 -264.468102) (xy 87.540846 -264.568178) (xy 87.540846 -264.612628)
			(xy 87.740998 -264.612628)
		)
		(stroke
			(width 0)
			(type solid)
		)
		(fill yes)
		(layer "In13.Cu")
		(net "M_B_CPU1_SB_CA<6>")
	)
	(gr_poly
		(pts
			(xy 87.740998 -264.164318) (xy 87.740998 -264.119868) (xy 87.540846 -264.119868) (xy 87.540846 -264.164318)
			(xy 87.640922 -264.264394)
		)
		(stroke
			(width 0)
			(type solid)
		)
		(fill yes)
		(layer "In13.Cu")
		(net "M_B_CPU1_SB_CA<5>")
	)
	(gr_poly
		(pts
			(xy 87.740998 -262.948166) (xy 87.640922 -262.84809) (xy 87.540846 -262.948166) (xy 87.540846 -262.992616)
			(xy 87.740998 -262.992616)
		)
		(stroke
			(width 0)
			(type solid)
		)
		(fill yes)
		(layer "In13.Cu")
		(net "M_B_CPU1_SB_CA<2>")
	)
	(gr_poly
		(pts
			(xy 87.740998 -262.544306) (xy 87.740998 -262.499856) (xy 87.540846 -262.499856) (xy 87.540846 -262.544306)
			(xy 87.640922 -262.644382)
		)
		(stroke
			(width 0)
			(type solid)
		)
		(fill yes)
		(layer "In13.Cu")
		(net "M_B_CPU1_SB_CA<1>")
	)
	(gr_poly
		(pts
			(xy 87.747094 -267.801852) (xy 87.647272 -267.701776) (xy 87.547196 -267.801852) (xy 87.547196 -267.846302)
			(xy 87.747094 -267.846302)
		)
		(stroke
			(width 0)
			(type solid)
		)
		(fill yes)
		(layer "In13.Cu")
		(net "M_B_CPU1_SB_RSP<0>")
	)
	(gr_poly
		(pts
			(xy 87.74811 -277.124668) (xy 87.74811 -277.076916) (xy 87.548212 -277.076916) (xy 87.548212 -277.124668)
			(xy 87.648288 -277.22449)
		)
		(stroke
			(width 0)
			(type solid)
		)
		(fill yes)
		(layer "In13.Cu")
		(net "M_B_CPU1_SB_DQS_DP<5>")
	)
	(gr_poly
		(pts
			(xy 87.74811 -275.908008) (xy 87.648288 -275.808186) (xy 87.548212 -275.908008) (xy 87.548212 -275.95576)
			(xy 87.74811 -275.95576)
		)
		(stroke
			(width 0)
			(type solid)
		)
		(fill yes)
		(layer "In13.Cu")
		(net "M_B_CPU1_SB_DQS_DP<0>")
	)
	(gr_poly
		(pts
			(xy 87.911178 -255.622552) (xy 87.911178 -255.578102) (xy 87.711026 -255.578102) (xy 87.711026 -255.622552)
			(xy 87.811102 -255.722628)
		)
		(stroke
			(width 0)
			(type solid)
		)
		(fill yes)
		(layer "In13.Cu")
		(net "M_B_CPU1_SA_PAR")
	)
	(gr_poly
		(pts
			(xy 87.911178 -254.00254) (xy 87.911178 -253.95809) (xy 87.711026 -253.95809) (xy 87.711026 -254.00254)
			(xy 87.811102 -254.102616)
		)
		(stroke
			(width 0)
			(type solid)
		)
		(fill yes)
		(layer "In13.Cu")
		(net "M_B_CPU1_SA_CA<3>")
	)
	(gr_poly
		(pts
			(xy 87.911178 -252.382528) (xy 87.911178 -252.338078) (xy 87.711026 -252.338078) (xy 87.711026 -252.382528)
			(xy 87.811102 -252.482604)
		)
		(stroke
			(width 0)
			(type solid)
		)
		(fill yes)
		(layer "In13.Cu")
		(net "M_B_CPU1_SA_CS_N<1>")
	)
	(gr_poly
		(pts
			(xy 87.911178 -250.762516) (xy 87.911178 -250.718066) (xy 87.711026 -250.718066) (xy 87.711026 -250.762516)
			(xy 87.811102 -250.862592)
		)
		(stroke
			(width 0)
			(type solid)
		)
		(fill yes)
		(layer "In13.Cu")
		(net "M_B_CPU1_RESET_N")
	)
	(gr_poly
		(pts
			(xy 87.911178 -249.142504) (xy 87.911178 -249.098054) (xy 87.711026 -249.098054) (xy 87.711026 -249.142504)
			(xy 87.811102 -249.24258)
		)
		(stroke
			(width 0)
			(type solid)
		)
		(fill yes)
		(layer "In13.Cu")
		(net "M_B_CPU1_SA_CB<7>")
	)
	(gr_poly
		(pts
			(xy 87.911178 -247.522746) (xy 87.911178 -247.474994) (xy 87.711026 -247.474994) (xy 87.711026 -247.522746)
			(xy 87.811102 -247.622568)
		)
		(stroke
			(width 0)
			(type solid)
		)
		(fill yes)
		(layer "In13.Cu")
		(net "M_B_CPU1_SA_DQS_DP<9>")
	)
	(gr_poly
		(pts
			(xy 87.911178 -245.90248) (xy 87.911178 -245.85803) (xy 87.711026 -245.85803) (xy 87.711026 -245.90248)
			(xy 87.811102 -246.002556)
		)
		(stroke
			(width 0)
			(type solid)
		)
		(fill yes)
		(layer "In13.Cu")
		(net "M_B_CPU1_SA_CB<3>")
	)
	(gr_poly
		(pts
			(xy 87.911178 -244.282468) (xy 87.911178 -244.238018) (xy 87.711026 -244.238018) (xy 87.711026 -244.282468)
			(xy 87.811102 -244.382544)
		)
		(stroke
			(width 0)
			(type solid)
		)
		(fill yes)
		(layer "In13.Cu")
		(net "M_B_CPU1_SA_DQ<31>")
	)
	(gr_poly
		(pts
			(xy 87.911178 -242.66271) (xy 87.911178 -242.614958) (xy 87.711026 -242.614958) (xy 87.711026 -242.66271)
			(xy 87.811102 -242.762532)
		)
		(stroke
			(width 0)
			(type solid)
		)
		(fill yes)
		(layer "In13.Cu")
		(net "M_B_CPU1_SA_DQS_DP<8>")
	)
	(gr_poly
		(pts
			(xy 87.911178 -241.042444) (xy 87.911178 -240.997994) (xy 87.711026 -240.997994) (xy 87.711026 -241.042444)
			(xy 87.811102 -241.14252)
		)
		(stroke
			(width 0)
			(type solid)
		)
		(fill yes)
		(layer "In13.Cu")
		(net "M_B_CPU1_SA_DQ<27>")
	)
	(gr_poly
		(pts
			(xy 87.911178 -239.422432) (xy 87.911178 -239.377982) (xy 87.711026 -239.377982) (xy 87.711026 -239.422432)
			(xy 87.811102 -239.522508)
		)
		(stroke
			(width 0)
			(type solid)
		)
		(fill yes)
		(layer "In13.Cu")
		(net "M_B_CPU1_SA_DQ<23>")
	)
	(gr_poly
		(pts
			(xy 87.911178 -237.802674) (xy 87.911178 -237.754922) (xy 87.711026 -237.754922) (xy 87.711026 -237.802674)
			(xy 87.811102 -237.902496)
		)
		(stroke
			(width 0)
			(type solid)
		)
		(fill yes)
		(layer "In13.Cu")
		(net "M_B_CPU1_SA_DQS_DP<7>")
	)
	(gr_poly
		(pts
			(xy 87.911178 -236.182408) (xy 87.911178 -236.137958) (xy 87.711026 -236.137958) (xy 87.711026 -236.182408)
			(xy 87.811102 -236.282484)
		)
		(stroke
			(width 0)
			(type solid)
		)
		(fill yes)
		(layer "In13.Cu")
		(net "M_B_CPU1_SA_DQ<19>")
	)
	(gr_poly
		(pts
			(xy 87.911178 -234.562396) (xy 87.911178 -234.517946) (xy 87.711026 -234.517946) (xy 87.711026 -234.562396)
			(xy 87.811102 -234.662472)
		)
		(stroke
			(width 0)
			(type solid)
		)
		(fill yes)
		(layer "In13.Cu")
		(net "M_B_CPU1_SA_DQ<15>")
	)
	(gr_poly
		(pts
			(xy 87.911178 -232.942638) (xy 87.911178 -232.894886) (xy 87.711026 -232.894886) (xy 87.711026 -232.942638)
			(xy 87.811102 -233.04246)
		)
		(stroke
			(width 0)
			(type solid)
		)
		(fill yes)
		(layer "In13.Cu")
		(net "M_B_CPU1_SA_DQS_DP<6>")
	)
	(gr_poly
		(pts
			(xy 87.911178 -231.322626) (xy 87.911178 -231.278176) (xy 87.711026 -231.278176) (xy 87.711026 -231.322626)
			(xy 87.811102 -231.422702)
		)
		(stroke
			(width 0)
			(type solid)
		)
		(fill yes)
		(layer "In13.Cu")
		(net "M_B_CPU1_SA_DQ<11>")
	)
	(gr_poly
		(pts
			(xy 87.911178 -229.702614) (xy 87.911178 -229.658164) (xy 87.711026 -229.658164) (xy 87.711026 -229.702614)
			(xy 87.811102 -229.80269)
		)
		(stroke
			(width 0)
			(type solid)
		)
		(fill yes)
		(layer "In13.Cu")
		(net "M_B_CPU1_SA_DQ<7>")
	)
	(gr_poly
		(pts
			(xy 87.911178 -228.082856) (xy 87.911178 -228.035104) (xy 87.711026 -228.035104) (xy 87.711026 -228.082856)
			(xy 87.811102 -228.182678)
		)
		(stroke
			(width 0)
			(type solid)
		)
		(fill yes)
		(layer "In13.Cu")
		(net "M_B_CPU1_SA_DQS_DP<5>")
	)
	(gr_poly
		(pts
			(xy 87.911178 -226.46259) (xy 87.911178 -226.41814) (xy 87.711026 -226.41814) (xy 87.711026 -226.46259)
			(xy 87.811102 -226.562666)
		)
		(stroke
			(width 0)
			(type solid)
		)
		(fill yes)
		(layer "In13.Cu")
		(net "M_B_CPU1_SA_DQ<3>")
	)
	(gr_poly
		(pts
			(xy 88.204802 -266.991846) (xy 88.104726 -266.89177) (xy 88.004904 -266.991846) (xy 88.004904 -267.036296)
			(xy 88.204802 -267.036296)
		)
		(stroke
			(width 0)
			(type solid)
		)
		(fill yes)
		(layer "In13.Cu")
		(net "M_B_CPU1_SA_RSP<0>")
	)
	(gr_poly
		(pts
			(xy 88.211152 -292.918134) (xy 88.111076 -292.818058) (xy 88.011 -292.918134) (xy 88.011 -292.962584)
			(xy 88.211152 -292.962584)
		)
		(stroke
			(width 0)
			(type solid)
		)
		(fill yes)
		(layer "In13.Cu")
		(net "M_B_CPU1_SB_DQ<29>")
	)
	(gr_poly
		(pts
			(xy 88.211152 -291.297868) (xy 88.111076 -291.198046) (xy 88.011 -291.297868) (xy 88.011 -291.34562)
			(xy 88.211152 -291.34562)
		)
		(stroke
			(width 0)
			(type solid)
		)
		(fill yes)
		(layer "In13.Cu")
		(net "M_B_CPU1_SB_DQS_DN<8>")
	)
	(gr_poly
		(pts
			(xy 88.211152 -289.67811) (xy 88.111076 -289.578034) (xy 88.011 -289.67811) (xy 88.011 -289.72256)
			(xy 88.211152 -289.72256)
		)
		(stroke
			(width 0)
			(type solid)
		)
		(fill yes)
		(layer "In13.Cu")
		(net "M_B_CPU1_SB_DQ<25>")
	)
	(gr_poly
		(pts
			(xy 88.211152 -288.058098) (xy 88.111076 -287.958022) (xy 88.011 -288.058098) (xy 88.011 -288.102548)
			(xy 88.211152 -288.102548)
		)
		(stroke
			(width 0)
			(type solid)
		)
		(fill yes)
		(layer "In13.Cu")
		(net "M_B_CPU1_SB_DQ<21>")
	)
	(gr_poly
		(pts
			(xy 88.211152 -286.438086) (xy 88.111076 -286.33801) (xy 88.011 -286.438086) (xy 88.011 -286.485838)
			(xy 88.211152 -286.485838)
		)
		(stroke
			(width 0)
			(type solid)
		)
		(fill yes)
		(layer "In13.Cu")
		(net "M_B_CPU1_SB_DQS_DN<7>")
	)
	(gr_poly
		(pts
			(xy 88.211152 -284.818328) (xy 88.111076 -284.718252) (xy 88.011 -284.818328) (xy 88.011 -284.862778)
			(xy 88.211152 -284.862778)
		)
		(stroke
			(width 0)
			(type solid)
		)
		(fill yes)
		(layer "In13.Cu")
		(net "M_B_CPU1_SB_DQ<17>")
	)
	(gr_poly
		(pts
			(xy 88.211152 -283.198316) (xy 88.111076 -283.09824) (xy 88.011 -283.198316) (xy 88.011 -283.242766)
			(xy 88.211152 -283.242766)
		)
		(stroke
			(width 0)
			(type solid)
		)
		(fill yes)
		(layer "In13.Cu")
		(net "M_B_CPU1_SB_DQ<13>")
	)
	(gr_poly
		(pts
			(xy 88.211152 -281.57805) (xy 88.111076 -281.478228) (xy 88.011 -281.57805) (xy 88.011 -281.625802)
			(xy 88.211152 -281.625802)
		)
		(stroke
			(width 0)
			(type solid)
		)
		(fill yes)
		(layer "In13.Cu")
		(net "M_B_CPU1_SB_DQS_DN<6>")
	)
	(gr_poly
		(pts
			(xy 88.211152 -279.958292) (xy 88.111076 -279.858216) (xy 88.011 -279.958292) (xy 88.011 -280.002742)
			(xy 88.211152 -280.002742)
		)
		(stroke
			(width 0)
			(type solid)
		)
		(fill yes)
		(layer "In13.Cu")
		(net "M_B_CPU1_SB_DQ<9>")
	)
	(gr_poly
		(pts
			(xy 88.211152 -278.33828) (xy 88.111076 -278.238204) (xy 88.011 -278.33828) (xy 88.011 -278.38273)
			(xy 88.211152 -278.38273)
		)
		(stroke
			(width 0)
			(type solid)
		)
		(fill yes)
		(layer "In13.Cu")
		(net "M_B_CPU1_SB_DQ<5>")
	)
	(gr_poly
		(pts
			(xy 88.211152 -276.718014) (xy 88.111076 -276.618192) (xy 88.011 -276.718014) (xy 88.011 -276.765766)
			(xy 88.211152 -276.765766)
		)
		(stroke
			(width 0)
			(type solid)
		)
		(fill yes)
		(layer "In13.Cu")
		(net "M_B_CPU1_SB_DQS_DN<5>")
	)
	(gr_poly
		(pts
			(xy 88.211152 -275.098256) (xy 88.111076 -274.99818) (xy 88.011 -275.098256) (xy 88.011 -275.142706)
			(xy 88.211152 -275.142706)
		)
		(stroke
			(width 0)
			(type solid)
		)
		(fill yes)
		(layer "In13.Cu")
		(net "M_B_CPU1_SB_DQ<1>")
	)
	(gr_poly
		(pts
			(xy 88.211152 -273.478244) (xy 88.111076 -273.378168) (xy 88.011 -273.478244) (xy 88.011 -273.522694)
			(xy 88.211152 -273.522694)
		)
		(stroke
			(width 0)
			(type solid)
		)
		(fill yes)
		(layer "In13.Cu")
		(net "M_B_CPU1_SB_CB<1>")
	)
	(gr_poly
		(pts
			(xy 88.211152 -271.857978) (xy 88.111076 -271.758156) (xy 88.011 -271.857978) (xy 88.011 -271.90573)
			(xy 88.211152 -271.90573)
		)
		(stroke
			(width 0)
			(type solid)
		)
		(fill yes)
		(layer "In13.Cu")
		(net "M_B_CPU1_SB_DQS_DN<4>")
	)
	(gr_poly
		(pts
			(xy 88.211152 -270.23822) (xy 88.111076 -270.138144) (xy 88.011 -270.23822) (xy 88.011 -270.28267)
			(xy 88.211152 -270.28267)
		)
		(stroke
			(width 0)
			(type solid)
		)
		(fill yes)
		(layer "In13.Cu")
		(net "M_B_CPU1_SB_CB<5>")
	)
	(gr_poly
		(pts
			(xy 88.211152 -263.758172) (xy 88.111076 -263.658096) (xy 88.011 -263.758172) (xy 88.011 -263.802622)
			(xy 88.211152 -263.802622)
		)
		(stroke
			(width 0)
			(type solid)
		)
		(fill yes)
		(layer "In13.Cu")
		(net "M_B_CPU1_SB_CA<4>")
	)
	(gr_poly
		(pts
			(xy 88.211152 -262.13816) (xy 88.111076 -262.038084) (xy 88.011 -262.13816) (xy 88.011 -262.18261)
			(xy 88.211152 -262.18261)
		)
		(stroke
			(width 0)
			(type solid)
		)
		(fill yes)
		(layer "In13.Cu")
		(net "M_B_CPU1_SB_CA<0>")
	)
	(gr_poly
		(pts
			(xy 88.381078 -255.216406) (xy 88.281002 -255.11633) (xy 88.180926 -255.216406) (xy 88.180926 -255.260856)
			(xy 88.381078 -255.260856)
		)
		(stroke
			(width 0)
			(type solid)
		)
		(fill yes)
		(layer "In13.Cu")
		(net "M_B_CPU1_SA_CA<6>")
	)
	(gr_poly
		(pts
			(xy 88.381078 -253.596394) (xy 88.281002 -253.496318) (xy 88.180926 -253.596394) (xy 88.180926 -253.640844)
			(xy 88.381078 -253.640844)
		)
		(stroke
			(width 0)
			(type solid)
		)
		(fill yes)
		(layer "In13.Cu")
		(net "M_B_CPU1_SA_CA<2>")
	)
	(gr_poly
		(pts
			(xy 88.381078 -250.35637) (xy 88.281002 -250.256294) (xy 88.180926 -250.35637) (xy 88.180926 -250.40082)
			(xy 88.381078 -250.40082)
		)
		(stroke
			(width 0)
			(type solid)
		)
		(fill yes)
		(layer "In13.Cu")
		(net "M_B_CPU1_ALERT_R_N")
	)
	(gr_poly
		(pts
			(xy 88.381078 -248.736358) (xy 88.281002 -248.636282) (xy 88.180926 -248.736358) (xy 88.180926 -248.780808)
			(xy 88.381078 -248.780808)
		)
		(stroke
			(width 0)
			(type solid)
		)
		(fill yes)
		(layer "In13.Cu")
		(net "M_B_CPU1_SA_CB<5>")
	)
	(gr_poly
		(pts
			(xy 88.381078 -247.116092) (xy 88.281002 -247.01627) (xy 88.180926 -247.116092) (xy 88.180926 -247.163844)
			(xy 88.381078 -247.163844)
		)
		(stroke
			(width 0)
			(type solid)
		)
		(fill yes)
		(layer "In13.Cu")
		(net "M_B_CPU1_SA_DQS_DN<9>")
	)
	(gr_poly
		(pts
			(xy 88.381078 -245.496334) (xy 88.281002 -245.396258) (xy 88.180926 -245.496334) (xy 88.180926 -245.540784)
			(xy 88.381078 -245.540784)
		)
		(stroke
			(width 0)
			(type solid)
		)
		(fill yes)
		(layer "In13.Cu")
		(net "M_B_CPU1_SA_CB<1>")
	)
	(gr_poly
		(pts
			(xy 88.381078 -243.876322) (xy 88.281002 -243.776246) (xy 88.180926 -243.876322) (xy 88.180926 -243.920772)
			(xy 88.381078 -243.920772)
		)
		(stroke
			(width 0)
			(type solid)
		)
		(fill yes)
		(layer "In13.Cu")
		(net "M_B_CPU1_SA_DQ<29>")
	)
	(gr_poly
		(pts
			(xy 88.381078 -242.256056) (xy 88.281002 -242.156234) (xy 88.180926 -242.256056) (xy 88.180926 -242.303808)
			(xy 88.381078 -242.303808)
		)
		(stroke
			(width 0)
			(type solid)
		)
		(fill yes)
		(layer "In13.Cu")
		(net "M_B_CPU1_SA_DQS_DN<8>")
	)
	(gr_poly
		(pts
			(xy 88.381078 -240.636298) (xy 88.281002 -240.536222) (xy 88.180926 -240.636298) (xy 88.180926 -240.680748)
			(xy 88.381078 -240.680748)
		)
		(stroke
			(width 0)
			(type solid)
		)
		(fill yes)
		(layer "In13.Cu")
		(net "M_B_CPU1_SA_DQ<25>")
	)
	(gr_poly
		(pts
			(xy 88.381078 -239.016286) (xy 88.281002 -238.91621) (xy 88.180926 -239.016286) (xy 88.180926 -239.060736)
			(xy 88.381078 -239.060736)
		)
		(stroke
			(width 0)
			(type solid)
		)
		(fill yes)
		(layer "In13.Cu")
		(net "M_B_CPU1_SA_DQ<21>")
	)
	(gr_poly
		(pts
			(xy 88.381078 -237.39602) (xy 88.281002 -237.296198) (xy 88.180926 -237.39602) (xy 88.180926 -237.443772)
			(xy 88.381078 -237.443772)
		)
		(stroke
			(width 0)
			(type solid)
		)
		(fill yes)
		(layer "In13.Cu")
		(net "M_B_CPU1_SA_DQS_DN<7>")
	)
	(gr_poly
		(pts
			(xy 88.381078 -235.776262) (xy 88.281002 -235.676186) (xy 88.180926 -235.776262) (xy 88.180926 -235.820712)
			(xy 88.381078 -235.820712)
		)
		(stroke
			(width 0)
			(type solid)
		)
		(fill yes)
		(layer "In13.Cu")
		(net "M_B_CPU1_SA_DQ<17>")
	)
	(gr_poly
		(pts
			(xy 88.381078 -234.15625) (xy 88.281002 -234.056174) (xy 88.180926 -234.15625) (xy 88.180926 -234.2007)
			(xy 88.381078 -234.2007)
		)
		(stroke
			(width 0)
			(type solid)
		)
		(fill yes)
		(layer "In13.Cu")
		(net "M_B_CPU1_SA_DQ<13>")
	)
	(gr_poly
		(pts
			(xy 88.381078 -232.535984) (xy 88.281002 -232.436162) (xy 88.180926 -232.535984) (xy 88.180926 -232.583736)
			(xy 88.381078 -232.583736)
		)
		(stroke
			(width 0)
			(type solid)
		)
		(fill yes)
		(layer "In13.Cu")
		(net "M_B_CPU1_SA_DQS_DN<6>")
	)
	(gr_poly
		(pts
			(xy 88.381078 -230.916226) (xy 88.281002 -230.81615) (xy 88.180926 -230.916226) (xy 88.180926 -230.960676)
			(xy 88.381078 -230.960676)
		)
		(stroke
			(width 0)
			(type solid)
		)
		(fill yes)
		(layer "In13.Cu")
		(net "M_B_CPU1_SA_DQ<9>")
	)
	(gr_poly
		(pts
			(xy 88.381078 -229.296214) (xy 88.281002 -229.196138) (xy 88.180926 -229.296214) (xy 88.180926 -229.340664)
			(xy 88.381078 -229.340664)
		)
		(stroke
			(width 0)
			(type solid)
		)
		(fill yes)
		(layer "In13.Cu")
		(net "M_B_CPU1_SA_DQ<5>")
	)
	(gr_poly
		(pts
			(xy 88.381078 -226.056444) (xy 88.281002 -225.956368) (xy 88.180926 -226.056444) (xy 88.180926 -226.100894)
			(xy 88.381078 -226.100894)
		)
		(stroke
			(width 0)
			(type solid)
		)
		(fill yes)
		(layer "In13.Cu")
		(net "M_B_CPU1_SA_DQ<1>")
	)
	(gr_poly
		(pts
			(xy 88.387174 -227.67671) (xy 88.287098 -227.576634) (xy 88.187022 -227.67671) (xy 88.187022 -227.724208)
			(xy 88.387174 -227.724208)
		)
		(stroke
			(width 0)
			(type solid)
		)
		(fill yes)
		(layer "In13.Cu")
		(net "M_B_CPU1_SA_DQS_DN<5>")
	)
	(gr_poly
		(pts
			(xy 88.681052 -293.32428) (xy 88.681052 -293.27983) (xy 88.4809 -293.27983) (xy 88.4809 -293.32428)
			(xy 88.580976 -293.424356)
		)
		(stroke
			(width 0)
			(type solid)
		)
		(fill yes)
		(layer "In13.Cu")
		(net "M_B_CPU1_SB_DQ<31>")
	)
	(gr_poly
		(pts
			(xy 88.681052 -291.704522) (xy 88.681052 -291.65677) (xy 88.4809 -291.65677) (xy 88.4809 -291.704522)
			(xy 88.580976 -291.804344)
		)
		(stroke
			(width 0)
			(type solid)
		)
		(fill yes)
		(layer "In13.Cu")
		(net "M_B_CPU1_SB_DQS_DP<8>")
	)
	(gr_poly
		(pts
			(xy 88.681052 -290.084256) (xy 88.681052 -290.039806) (xy 88.4809 -290.039806) (xy 88.4809 -290.084256)
			(xy 88.580976 -290.184332)
		)
		(stroke
			(width 0)
			(type solid)
		)
		(fill yes)
		(layer "In13.Cu")
		(net "M_B_CPU1_SB_DQ<27>")
	)
	(gr_poly
		(pts
			(xy 88.681052 -288.464498) (xy 88.681052 -288.420048) (xy 88.4809 -288.420048) (xy 88.4809 -288.464498)
			(xy 88.580976 -288.564574)
		)
		(stroke
			(width 0)
			(type solid)
		)
		(fill yes)
		(layer "In13.Cu")
		(net "M_B_CPU1_SB_DQ<23>")
	)
	(gr_poly
		(pts
			(xy 88.681052 -286.844486) (xy 88.681052 -286.796734) (xy 88.4809 -286.796734) (xy 88.4809 -286.844486)
			(xy 88.580976 -286.944562)
		)
		(stroke
			(width 0)
			(type solid)
		)
		(fill yes)
		(layer "In13.Cu")
		(net "M_B_CPU1_SB_DQS_DP<7>")
	)
	(gr_poly
		(pts
			(xy 88.681052 -285.224474) (xy 88.681052 -285.180024) (xy 88.4809 -285.180024) (xy 88.4809 -285.224474)
			(xy 88.580976 -285.32455)
		)
		(stroke
			(width 0)
			(type solid)
		)
		(fill yes)
		(layer "In13.Cu")
		(net "M_B_CPU1_SB_DQ<19>")
	)
	(gr_poly
		(pts
			(xy 88.681052 -283.604462) (xy 88.681052 -283.560012) (xy 88.4809 -283.560012) (xy 88.4809 -283.604462)
			(xy 88.580976 -283.704538)
		)
		(stroke
			(width 0)
			(type solid)
		)
		(fill yes)
		(layer "In13.Cu")
		(net "M_B_CPU1_SB_DQ<15>")
	)
	(gr_poly
		(pts
			(xy 88.681052 -281.984704) (xy 88.681052 -281.936952) (xy 88.4809 -281.936952) (xy 88.4809 -281.984704)
			(xy 88.580976 -282.084526)
		)
		(stroke
			(width 0)
			(type solid)
		)
		(fill yes)
		(layer "In13.Cu")
		(net "M_B_CPU1_SB_DQS_DP<6>")
	)
	(gr_poly
		(pts
			(xy 88.681052 -280.364438) (xy 88.681052 -280.319988) (xy 88.4809 -280.319988) (xy 88.4809 -280.364438)
			(xy 88.580976 -280.464514)
		)
		(stroke
			(width 0)
			(type solid)
		)
		(fill yes)
		(layer "In13.Cu")
		(net "M_B_CPU1_SB_DQ<11>")
	)
	(gr_poly
		(pts
			(xy 88.681052 -278.744426) (xy 88.681052 -278.699976) (xy 88.4809 -278.699976) (xy 88.4809 -278.744426)
			(xy 88.580976 -278.844502)
		)
		(stroke
			(width 0)
			(type solid)
		)
		(fill yes)
		(layer "In13.Cu")
		(net "M_B_CPU1_SB_DQ<7>")
	)
	(gr_poly
		(pts
			(xy 88.681052 -275.504402) (xy 88.681052 -275.459952) (xy 88.4809 -275.459952) (xy 88.4809 -275.504402)
			(xy 88.580976 -275.604478)
		)
		(stroke
			(width 0)
			(type solid)
		)
		(fill yes)
		(layer "In13.Cu")
		(net "M_B_CPU1_SB_DQ<3>")
	)
	(gr_poly
		(pts
			(xy 88.681052 -273.88439) (xy 88.681052 -273.83994) (xy 88.4809 -273.83994) (xy 88.4809 -273.88439)
			(xy 88.580976 -273.984466)
		)
		(stroke
			(width 0)
			(type solid)
		)
		(fill yes)
		(layer "In13.Cu")
		(net "M_B_CPU1_SB_CB<3>")
	)
	(gr_poly
		(pts
			(xy 88.681052 -272.264632) (xy 88.681052 -272.21688) (xy 88.4809 -272.21688) (xy 88.4809 -272.264632)
			(xy 88.580976 -272.364454)
		)
		(stroke
			(width 0)
			(type solid)
		)
		(fill yes)
		(layer "In13.Cu")
		(net "M_B_CPU1_SB_DQS_DP<4>")
	)
	(gr_poly
		(pts
			(xy 88.681052 -270.644366) (xy 88.681052 -270.599916) (xy 88.4809 -270.599916) (xy 88.4809 -270.644366)
			(xy 88.580976 -270.744442)
		)
		(stroke
			(width 0)
			(type solid)
		)
		(fill yes)
		(layer "In13.Cu")
		(net "M_B_CPU1_SB_CB<7>")
	)
	(gr_poly
		(pts
			(xy 88.681052 -265.78433) (xy 88.681052 -265.73988) (xy 88.4809 -265.73988) (xy 88.4809 -265.78433)
			(xy 88.580976 -265.884406)
		)
		(stroke
			(width 0)
			(type solid)
		)
		(fill yes)
		(layer "In13.Cu")
		(net "M_B_CPU1_SB_CS_N<0>")
	)
	(gr_poly
		(pts
			(xy 88.681052 -264.164318) (xy 88.681052 -264.119868) (xy 88.4809 -264.119868) (xy 88.4809 -264.164318)
			(xy 88.580976 -264.264394)
		)
		(stroke
			(width 0)
			(type solid)
		)
		(fill yes)
		(layer "In13.Cu")
		(net "M_B_CPU1_SB_CA<5>")
	)
	(gr_poly
		(pts
			(xy 88.681052 -262.544306) (xy 88.681052 -262.499856) (xy 88.4809 -262.499856) (xy 88.4809 -262.544306)
			(xy 88.580976 -262.644382)
		)
		(stroke
			(width 0)
			(type solid)
		)
		(fill yes)
		(layer "In13.Cu")
		(net "M_B_CPU1_SB_CA<1>")
	)
	(gr_poly
		(pts
			(xy 88.688418 -277.124414) (xy 88.688418 -277.076916) (xy 88.488266 -277.076916) (xy 88.488266 -277.124414)
			(xy 88.588342 -277.22449)
		)
		(stroke
			(width 0)
			(type solid)
		)
		(fill yes)
		(layer "In13.Cu")
		(net "M_B_CPU1_SB_DQS_DP<5>")
	)
	(gr_poly
		(pts
			(xy 88.851232 -255.622552) (xy 88.851232 -255.578102) (xy 88.65108 -255.578102) (xy 88.65108 -255.622552)
			(xy 88.751156 -255.722628)
		)
		(stroke
			(width 0)
			(type solid)
		)
		(fill yes)
		(layer "In13.Cu")
		(net "M_B_CPU1_SA_PAR")
	)
	(gr_poly
		(pts
			(xy 88.851232 -254.00254) (xy 88.851232 -253.95809) (xy 88.65108 -253.95809) (xy 88.65108 -254.00254)
			(xy 88.751156 -254.102616)
		)
		(stroke
			(width 0)
			(type solid)
		)
		(fill yes)
		(layer "In13.Cu")
		(net "M_B_CPU1_SA_CA<3>")
	)
	(gr_poly
		(pts
			(xy 88.851232 -252.382528) (xy 88.851232 -252.338078) (xy 88.65108 -252.338078) (xy 88.65108 -252.382528)
			(xy 88.751156 -252.482604)
		)
		(stroke
			(width 0)
			(type solid)
		)
		(fill yes)
		(layer "In13.Cu")
		(net "M_B_CPU1_SA_CS_N<1>")
	)
	(gr_poly
		(pts
			(xy 88.851232 -250.762516) (xy 88.851232 -250.718066) (xy 88.65108 -250.718066) (xy 88.65108 -250.762516)
			(xy 88.751156 -250.862592)
		)
		(stroke
			(width 0)
			(type solid)
		)
		(fill yes)
		(layer "In13.Cu")
		(net "M_B_CPU1_RESET_N")
	)
	(gr_poly
		(pts
			(xy 88.851232 -249.142504) (xy 88.851232 -249.098054) (xy 88.65108 -249.098054) (xy 88.65108 -249.142504)
			(xy 88.751156 -249.24258)
		)
		(stroke
			(width 0)
			(type solid)
		)
		(fill yes)
		(layer "In13.Cu")
		(net "M_B_CPU1_SA_CB<7>")
	)
	(gr_poly
		(pts
			(xy 88.851232 -247.522746) (xy 88.851232 -247.474994) (xy 88.65108 -247.474994) (xy 88.65108 -247.522746)
			(xy 88.751156 -247.622568)
		)
		(stroke
			(width 0)
			(type solid)
		)
		(fill yes)
		(layer "In13.Cu")
		(net "M_B_CPU1_SA_DQS_DP<9>")
	)
	(gr_poly
		(pts
			(xy 88.851232 -245.90248) (xy 88.851232 -245.85803) (xy 88.65108 -245.85803) (xy 88.65108 -245.90248)
			(xy 88.751156 -246.002556)
		)
		(stroke
			(width 0)
			(type solid)
		)
		(fill yes)
		(layer "In13.Cu")
		(net "M_B_CPU1_SA_CB<3>")
	)
	(gr_poly
		(pts
			(xy 88.851232 -244.282468) (xy 88.851232 -244.238018) (xy 88.65108 -244.238018) (xy 88.65108 -244.282468)
			(xy 88.751156 -244.382544)
		)
		(stroke
			(width 0)
			(type solid)
		)
		(fill yes)
		(layer "In13.Cu")
		(net "M_B_CPU1_SA_DQ<31>")
	)
	(gr_poly
		(pts
			(xy 88.851232 -242.66271) (xy 88.851232 -242.614958) (xy 88.65108 -242.614958) (xy 88.65108 -242.66271)
			(xy 88.751156 -242.762532)
		)
		(stroke
			(width 0)
			(type solid)
		)
		(fill yes)
		(layer "In13.Cu")
		(net "M_B_CPU1_SA_DQS_DP<8>")
	)
	(gr_poly
		(pts
			(xy 88.851232 -241.042444) (xy 88.851232 -240.997994) (xy 88.65108 -240.997994) (xy 88.65108 -241.042444)
			(xy 88.751156 -241.14252)
		)
		(stroke
			(width 0)
			(type solid)
		)
		(fill yes)
		(layer "In13.Cu")
		(net "M_B_CPU1_SA_DQ<27>")
	)
	(gr_poly
		(pts
			(xy 88.851232 -239.422432) (xy 88.851232 -239.377982) (xy 88.65108 -239.377982) (xy 88.65108 -239.422432)
			(xy 88.751156 -239.522508)
		)
		(stroke
			(width 0)
			(type solid)
		)
		(fill yes)
		(layer "In13.Cu")
		(net "M_B_CPU1_SA_DQ<23>")
	)
	(gr_poly
		(pts
			(xy 88.851232 -237.802674) (xy 88.851232 -237.754922) (xy 88.65108 -237.754922) (xy 88.65108 -237.802674)
			(xy 88.751156 -237.902496)
		)
		(stroke
			(width 0)
			(type solid)
		)
		(fill yes)
		(layer "In13.Cu")
		(net "M_B_CPU1_SA_DQS_DP<7>")
	)
	(gr_poly
		(pts
			(xy 88.851232 -236.182408) (xy 88.851232 -236.137958) (xy 88.65108 -236.137958) (xy 88.65108 -236.182408)
			(xy 88.751156 -236.282484)
		)
		(stroke
			(width 0)
			(type solid)
		)
		(fill yes)
		(layer "In13.Cu")
		(net "M_B_CPU1_SA_DQ<19>")
	)
	(gr_poly
		(pts
			(xy 88.851232 -234.562396) (xy 88.851232 -234.517946) (xy 88.65108 -234.517946) (xy 88.65108 -234.562396)
			(xy 88.751156 -234.662472)
		)
		(stroke
			(width 0)
			(type solid)
		)
		(fill yes)
		(layer "In13.Cu")
		(net "M_B_CPU1_SA_DQ<15>")
	)
	(gr_poly
		(pts
			(xy 88.851232 -232.942638) (xy 88.851232 -232.894886) (xy 88.65108 -232.894886) (xy 88.65108 -232.942638)
			(xy 88.751156 -233.04246)
		)
		(stroke
			(width 0)
			(type solid)
		)
		(fill yes)
		(layer "In13.Cu")
		(net "M_B_CPU1_SA_DQS_DP<6>")
	)
	(gr_poly
		(pts
			(xy 88.851232 -231.322626) (xy 88.851232 -231.278176) (xy 88.65108 -231.278176) (xy 88.65108 -231.322626)
			(xy 88.751156 -231.422702)
		)
		(stroke
			(width 0)
			(type solid)
		)
		(fill yes)
		(layer "In13.Cu")
		(net "M_B_CPU1_SA_DQ<11>")
	)
	(gr_poly
		(pts
			(xy 88.851232 -229.702614) (xy 88.851232 -229.658164) (xy 88.65108 -229.658164) (xy 88.65108 -229.702614)
			(xy 88.751156 -229.80269)
		)
		(stroke
			(width 0)
			(type solid)
		)
		(fill yes)
		(layer "In13.Cu")
		(net "M_B_CPU1_SA_DQ<7>")
	)
	(gr_poly
		(pts
			(xy 88.851232 -228.082856) (xy 88.851232 -228.035104) (xy 88.65108 -228.035104) (xy 88.65108 -228.082856)
			(xy 88.751156 -228.182678)
		)
		(stroke
			(width 0)
			(type solid)
		)
		(fill yes)
		(layer "In13.Cu")
		(net "M_B_CPU1_SA_DQS_DP<5>")
	)
	(gr_poly
		(pts
			(xy 88.851232 -226.46259) (xy 88.851232 -226.41814) (xy 88.65108 -226.41814) (xy 88.65108 -226.46259)
			(xy 88.751156 -226.562666)
		)
		(stroke
			(width 0)
			(type solid)
		)
		(fill yes)
		(layer "In13.Cu")
		(net "M_B_CPU1_SA_DQ<3>")
	)
	(gr_poly
		(pts
			(xy 89.144856 -266.991846) (xy 89.04478 -266.89177) (xy 88.944958 -266.991846) (xy 88.944958 -267.036296)
			(xy 89.144856 -267.036296)
		)
		(stroke
			(width 0)
			(type solid)
		)
		(fill yes)
		(layer "In13.Cu")
		(net "M_B_CPU1_SA_RSP<0>")
	)
	(gr_poly
		(pts
			(xy 89.151206 -292.918134) (xy 89.05113 -292.818058) (xy 88.951054 -292.918134) (xy 88.951054 -292.962584)
			(xy 89.151206 -292.962584)
		)
		(stroke
			(width 0)
			(type solid)
		)
		(fill yes)
		(layer "In13.Cu")
		(net "M_B_CPU1_SB_DQ<29>")
	)
	(gr_poly
		(pts
			(xy 89.151206 -291.297868) (xy 89.05113 -291.198046) (xy 88.951054 -291.297868) (xy 88.951054 -291.34562)
			(xy 89.151206 -291.34562)
		)
		(stroke
			(width 0)
			(type solid)
		)
		(fill yes)
		(layer "In13.Cu")
		(net "M_B_CPU1_SB_DQS_DN<8>")
	)
	(gr_poly
		(pts
			(xy 89.151206 -289.67811) (xy 89.05113 -289.578034) (xy 88.951054 -289.67811) (xy 88.951054 -289.72256)
			(xy 89.151206 -289.72256)
		)
		(stroke
			(width 0)
			(type solid)
		)
		(fill yes)
		(layer "In13.Cu")
		(net "M_B_CPU1_SB_DQ<25>")
	)
	(gr_poly
		(pts
			(xy 89.151206 -288.058098) (xy 89.05113 -287.958022) (xy 88.951054 -288.058098) (xy 88.951054 -288.102548)
			(xy 89.151206 -288.102548)
		)
		(stroke
			(width 0)
			(type solid)
		)
		(fill yes)
		(layer "In13.Cu")
		(net "M_B_CPU1_SB_DQ<21>")
	)
	(gr_poly
		(pts
			(xy 89.151206 -286.438086) (xy 89.05113 -286.33801) (xy 88.951054 -286.438086) (xy 88.951054 -286.485838)
			(xy 89.151206 -286.485838)
		)
		(stroke
			(width 0)
			(type solid)
		)
		(fill yes)
		(layer "In13.Cu")
		(net "M_B_CPU1_SB_DQS_DN<7>")
	)
	(gr_poly
		(pts
			(xy 89.151206 -284.818328) (xy 89.05113 -284.718252) (xy 88.951054 -284.818328) (xy 88.951054 -284.862778)
			(xy 89.151206 -284.862778)
		)
		(stroke
			(width 0)
			(type solid)
		)
		(fill yes)
		(layer "In13.Cu")
		(net "M_B_CPU1_SB_DQ<17>")
	)
	(gr_poly
		(pts
			(xy 89.151206 -283.198316) (xy 89.05113 -283.09824) (xy 88.951054 -283.198316) (xy 88.951054 -283.242766)
			(xy 89.151206 -283.242766)
		)
		(stroke
			(width 0)
			(type solid)
		)
		(fill yes)
		(layer "In13.Cu")
		(net "M_B_CPU1_SB_DQ<13>")
	)
	(gr_poly
		(pts
			(xy 89.151206 -281.57805) (xy 89.05113 -281.478228) (xy 88.951054 -281.57805) (xy 88.951054 -281.625802)
			(xy 89.151206 -281.625802)
		)
		(stroke
			(width 0)
			(type solid)
		)
		(fill yes)
		(layer "In13.Cu")
		(net "M_B_CPU1_SB_DQS_DN<6>")
	)
	(gr_poly
		(pts
			(xy 89.151206 -279.958292) (xy 89.05113 -279.858216) (xy 88.951054 -279.958292) (xy 88.951054 -280.002742)
			(xy 89.151206 -280.002742)
		)
		(stroke
			(width 0)
			(type solid)
		)
		(fill yes)
		(layer "In13.Cu")
		(net "M_B_CPU1_SB_DQ<9>")
	)
	(gr_poly
		(pts
			(xy 89.151206 -278.33828) (xy 89.05113 -278.238204) (xy 88.951054 -278.33828) (xy 88.951054 -278.38273)
			(xy 89.151206 -278.38273)
		)
		(stroke
			(width 0)
			(type solid)
		)
		(fill yes)
		(layer "In13.Cu")
		(net "M_B_CPU1_SB_DQ<5>")
	)
	(gr_poly
		(pts
			(xy 89.151206 -276.718014) (xy 89.05113 -276.618192) (xy 88.951054 -276.718014) (xy 88.951054 -276.765766)
			(xy 89.151206 -276.765766)
		)
		(stroke
			(width 0)
			(type solid)
		)
		(fill yes)
		(layer "In13.Cu")
		(net "M_B_CPU1_SB_DQS_DN<5>")
	)
	(gr_poly
		(pts
			(xy 89.151206 -275.098256) (xy 89.05113 -274.99818) (xy 88.951054 -275.098256) (xy 88.951054 -275.142706)
			(xy 89.151206 -275.142706)
		)
		(stroke
			(width 0)
			(type solid)
		)
		(fill yes)
		(layer "In13.Cu")
		(net "M_B_CPU1_SB_DQ<1>")
	)
	(gr_poly
		(pts
			(xy 89.151206 -273.478244) (xy 89.05113 -273.378168) (xy 88.951054 -273.478244) (xy 88.951054 -273.522694)
			(xy 89.151206 -273.522694)
		)
		(stroke
			(width 0)
			(type solid)
		)
		(fill yes)
		(layer "In13.Cu")
		(net "M_B_CPU1_SB_CB<1>")
	)
	(gr_poly
		(pts
			(xy 89.151206 -271.857978) (xy 89.05113 -271.758156) (xy 88.951054 -271.857978) (xy 88.951054 -271.90573)
			(xy 89.151206 -271.90573)
		)
		(stroke
			(width 0)
			(type solid)
		)
		(fill yes)
		(layer "In13.Cu")
		(net "M_B_CPU1_SB_DQS_DN<4>")
	)
	(gr_poly
		(pts
			(xy 89.151206 -270.23822) (xy 89.05113 -270.138144) (xy 88.951054 -270.23822) (xy 88.951054 -270.28267)
			(xy 89.151206 -270.28267)
		)
		(stroke
			(width 0)
			(type solid)
		)
		(fill yes)
		(layer "In13.Cu")
		(net "M_B_CPU1_SB_CB<5>")
	)
	(gr_poly
		(pts
			(xy 89.151206 -263.758172) (xy 89.05113 -263.658096) (xy 88.951054 -263.758172) (xy 88.951054 -263.802622)
			(xy 89.151206 -263.802622)
		)
		(stroke
			(width 0)
			(type solid)
		)
		(fill yes)
		(layer "In13.Cu")
		(net "M_B_CPU1_SB_CA<4>")
	)
	(gr_poly
		(pts
			(xy 89.151206 -262.13816) (xy 89.05113 -262.038084) (xy 88.951054 -262.13816) (xy 88.951054 -262.18261)
			(xy 89.151206 -262.18261)
		)
		(stroke
			(width 0)
			(type solid)
		)
		(fill yes)
		(layer "In13.Cu")
		(net "M_B_CPU1_SB_CA<0>")
	)
	(gr_poly
		(pts
			(xy 134.904734 -255.622552) (xy 134.904734 -255.578102) (xy 134.704582 -255.578102) (xy 134.704582 -255.622552)
			(xy 134.804658 -255.722628)
		)
		(stroke
			(width 0)
			(type solid)
		)
		(fill yes)
		(layer "In13.Cu")
		(net "M_H_CPU1_SA_PAR")
	)
	(gr_poly
		(pts
			(xy 134.904734 -254.00254) (xy 134.904734 -253.95809) (xy 134.704582 -253.95809) (xy 134.704582 -254.00254)
			(xy 134.804658 -254.102616)
		)
		(stroke
			(width 0)
			(type solid)
		)
		(fill yes)
		(layer "In13.Cu")
		(net "M_H_CPU1_SA_CA<3>")
	)
	(gr_poly
		(pts
			(xy 134.904734 -250.762516) (xy 134.904734 -250.718066) (xy 134.704582 -250.718066) (xy 134.704582 -250.762516)
			(xy 134.804658 -250.862592)
		)
		(stroke
			(width 0)
			(type solid)
		)
		(fill yes)
		(layer "In13.Cu")
		(net "M_H_CPU1_RESET_N")
	)
	(gr_poly
		(pts
			(xy 134.904734 -249.142504) (xy 134.904734 -249.098054) (xy 134.704582 -249.098054) (xy 134.704582 -249.142504)
			(xy 134.804658 -249.24258)
		)
		(stroke
			(width 0)
			(type solid)
		)
		(fill yes)
		(layer "In13.Cu")
		(net "M_H_CPU1_SA_CB<7>")
	)
	(gr_poly
		(pts
			(xy 134.904734 -247.522746) (xy 134.904734 -247.474994) (xy 134.704582 -247.474994) (xy 134.704582 -247.522746)
			(xy 134.804658 -247.622568)
		)
		(stroke
			(width 0)
			(type solid)
		)
		(fill yes)
		(layer "In13.Cu")
		(net "M_H_CPU1_SA_DQS_DP<9>")
	)
	(gr_poly
		(pts
			(xy 134.904734 -245.90248) (xy 134.904734 -245.85803) (xy 134.704582 -245.85803) (xy 134.704582 -245.90248)
			(xy 134.804658 -246.002556)
		)
		(stroke
			(width 0)
			(type solid)
		)
		(fill yes)
		(layer "In13.Cu")
		(net "M_H_CPU1_SA_CB<3>")
	)
	(gr_poly
		(pts
			(xy 134.904734 -244.282468) (xy 134.904734 -244.238018) (xy 134.704582 -244.238018) (xy 134.704582 -244.282468)
			(xy 134.804658 -244.382544)
		)
		(stroke
			(width 0)
			(type solid)
		)
		(fill yes)
		(layer "In13.Cu")
		(net "M_H_CPU1_SA_DQ<31>")
	)
	(gr_poly
		(pts
			(xy 134.904734 -242.66271) (xy 134.904734 -242.614958) (xy 134.704582 -242.614958) (xy 134.704582 -242.66271)
			(xy 134.804658 -242.762532)
		)
		(stroke
			(width 0)
			(type solid)
		)
		(fill yes)
		(layer "In13.Cu")
		(net "M_H_CPU1_SA_DQS_DP<8>")
	)
	(gr_poly
		(pts
			(xy 134.904734 -241.042444) (xy 134.904734 -240.997994) (xy 134.704582 -240.997994) (xy 134.704582 -241.042444)
			(xy 134.804658 -241.14252)
		)
		(stroke
			(width 0)
			(type solid)
		)
		(fill yes)
		(layer "In13.Cu")
		(net "M_H_CPU1_SA_DQ<27>")
	)
	(gr_poly
		(pts
			(xy 134.904734 -239.422432) (xy 134.904734 -239.377982) (xy 134.704582 -239.377982) (xy 134.704582 -239.422432)
			(xy 134.804658 -239.522508)
		)
		(stroke
			(width 0)
			(type solid)
		)
		(fill yes)
		(layer "In13.Cu")
		(net "M_H_CPU1_SA_DQ<23>")
	)
	(gr_poly
		(pts
			(xy 134.904734 -237.802674) (xy 134.904734 -237.754922) (xy 134.704582 -237.754922) (xy 134.704582 -237.802674)
			(xy 134.804658 -237.902496)
		)
		(stroke
			(width 0)
			(type solid)
		)
		(fill yes)
		(layer "In13.Cu")
		(net "M_H_CPU1_SA_DQS_DP<7>")
	)
	(gr_poly
		(pts
			(xy 134.904734 -236.182408) (xy 134.904734 -236.137958) (xy 134.704582 -236.137958) (xy 134.704582 -236.182408)
			(xy 134.804658 -236.282484)
		)
		(stroke
			(width 0)
			(type solid)
		)
		(fill yes)
		(layer "In13.Cu")
		(net "M_H_CPU1_SA_DQ<19>")
	)
	(gr_poly
		(pts
			(xy 134.904734 -234.562396) (xy 134.904734 -234.517946) (xy 134.704582 -234.517946) (xy 134.704582 -234.562396)
			(xy 134.804658 -234.662472)
		)
		(stroke
			(width 0)
			(type solid)
		)
		(fill yes)
		(layer "In13.Cu")
		(net "M_H_CPU1_SA_DQ<15>")
	)
	(gr_poly
		(pts
			(xy 134.904734 -232.942638) (xy 134.904734 -232.894886) (xy 134.704582 -232.894886) (xy 134.704582 -232.942638)
			(xy 134.804658 -233.04246)
		)
		(stroke
			(width 0)
			(type solid)
		)
		(fill yes)
		(layer "In13.Cu")
		(net "M_H_CPU1_SA_DQS_DP<6>")
	)
	(gr_poly
		(pts
			(xy 134.904734 -231.322626) (xy 134.904734 -231.278176) (xy 134.704582 -231.278176) (xy 134.704582 -231.322626)
			(xy 134.804658 -231.422702)
		)
		(stroke
			(width 0)
			(type solid)
		)
		(fill yes)
		(layer "In13.Cu")
		(net "M_H_CPU1_SA_DQ<11>")
	)
	(gr_poly
		(pts
			(xy 134.904734 -229.702614) (xy 134.904734 -229.658164) (xy 134.704582 -229.658164) (xy 134.704582 -229.702614)
			(xy 134.804658 -229.80269)
		)
		(stroke
			(width 0)
			(type solid)
		)
		(fill yes)
		(layer "In13.Cu")
		(net "M_H_CPU1_SA_DQ<7>")
	)
	(gr_poly
		(pts
			(xy 134.904734 -228.082856) (xy 134.904734 -228.035104) (xy 134.704582 -228.035104) (xy 134.704582 -228.082856)
			(xy 134.804658 -228.182678)
		)
		(stroke
			(width 0)
			(type solid)
		)
		(fill yes)
		(layer "In13.Cu")
		(net "M_H_CPU1_SA_DQS_DP<5>")
	)
	(gr_poly
		(pts
			(xy 134.904734 -226.46259) (xy 134.904734 -226.41814) (xy 134.704582 -226.41814) (xy 134.704582 -226.46259)
			(xy 134.804658 -226.562666)
		)
		(stroke
			(width 0)
			(type solid)
		)
		(fill yes)
		(layer "In13.Cu")
		(net "M_H_CPU1_SA_DQ<3>")
	)
	(gr_poly
		(pts
			(xy 135.204708 -292.918134) (xy 135.104632 -292.818058) (xy 135.004556 -292.918134) (xy 135.004556 -292.962584)
			(xy 135.204708 -292.962584)
		)
		(stroke
			(width 0)
			(type solid)
		)
		(fill yes)
		(layer "In13.Cu")
		(net "M_H_CPU1_SB_DQ<29>")
	)
	(gr_poly
		(pts
			(xy 135.204708 -291.297868) (xy 135.104632 -291.198046) (xy 135.004556 -291.297868) (xy 135.004556 -291.34562)
			(xy 135.204708 -291.34562)
		)
		(stroke
			(width 0)
			(type solid)
		)
		(fill yes)
		(layer "In13.Cu")
		(net "M_H_CPU1_SB_DQS_DN<8>")
	)
	(gr_poly
		(pts
			(xy 135.204708 -289.67811) (xy 135.104632 -289.578034) (xy 135.004556 -289.67811) (xy 135.004556 -289.72256)
			(xy 135.204708 -289.72256)
		)
		(stroke
			(width 0)
			(type solid)
		)
		(fill yes)
		(layer "In13.Cu")
		(net "M_H_CPU1_SB_DQ<25>")
	)
	(gr_poly
		(pts
			(xy 135.204708 -288.058098) (xy 135.104632 -287.958022) (xy 135.004556 -288.058098) (xy 135.004556 -288.102548)
			(xy 135.204708 -288.102548)
		)
		(stroke
			(width 0)
			(type solid)
		)
		(fill yes)
		(layer "In13.Cu")
		(net "M_H_CPU1_SB_DQ<21>")
	)
	(gr_poly
		(pts
			(xy 135.204708 -286.438086) (xy 135.104632 -286.33801) (xy 135.004556 -286.438086) (xy 135.004556 -286.485838)
			(xy 135.204708 -286.485838)
		)
		(stroke
			(width 0)
			(type solid)
		)
		(fill yes)
		(layer "In13.Cu")
		(net "M_H_CPU1_SB_DQS_DN<7>")
	)
	(gr_poly
		(pts
			(xy 135.204708 -284.818328) (xy 135.104632 -284.718252) (xy 135.004556 -284.818328) (xy 135.004556 -284.862778)
			(xy 135.204708 -284.862778)
		)
		(stroke
			(width 0)
			(type solid)
		)
		(fill yes)
		(layer "In13.Cu")
		(net "M_H_CPU1_SB_DQ<17>")
	)
	(gr_poly
		(pts
			(xy 135.204708 -283.198316) (xy 135.104632 -283.09824) (xy 135.004556 -283.198316) (xy 135.004556 -283.242766)
			(xy 135.204708 -283.242766)
		)
		(stroke
			(width 0)
			(type solid)
		)
		(fill yes)
		(layer "In13.Cu")
		(net "M_H_CPU1_SB_DQ<13>")
	)
	(gr_poly
		(pts
			(xy 135.204708 -281.57805) (xy 135.104632 -281.478228) (xy 135.004556 -281.57805) (xy 135.004556 -281.625802)
			(xy 135.204708 -281.625802)
		)
		(stroke
			(width 0)
			(type solid)
		)
		(fill yes)
		(layer "In13.Cu")
		(net "M_H_CPU1_SB_DQS_DN<6>")
	)
	(gr_poly
		(pts
			(xy 135.204708 -279.958292) (xy 135.104632 -279.858216) (xy 135.004556 -279.958292) (xy 135.004556 -280.002742)
			(xy 135.204708 -280.002742)
		)
		(stroke
			(width 0)
			(type solid)
		)
		(fill yes)
		(layer "In13.Cu")
		(net "M_H_CPU1_SB_DQ<9>")
	)
	(gr_poly
		(pts
			(xy 135.204708 -278.33828) (xy 135.104632 -278.238204) (xy 135.004556 -278.33828) (xy 135.004556 -278.38273)
			(xy 135.204708 -278.38273)
		)
		(stroke
			(width 0)
			(type solid)
		)
		(fill yes)
		(layer "In13.Cu")
		(net "M_H_CPU1_SB_DQ<5>")
	)
	(gr_poly
		(pts
			(xy 135.204708 -276.718014) (xy 135.104632 -276.618192) (xy 135.004556 -276.718014) (xy 135.004556 -276.765766)
			(xy 135.204708 -276.765766)
		)
		(stroke
			(width 0)
			(type solid)
		)
		(fill yes)
		(layer "In13.Cu")
		(net "M_H_CPU1_SB_DQS_DN<5>")
	)
	(gr_poly
		(pts
			(xy 135.204708 -275.098256) (xy 135.104632 -274.99818) (xy 135.004556 -275.098256) (xy 135.004556 -275.142706)
			(xy 135.204708 -275.142706)
		)
		(stroke
			(width 0)
			(type solid)
		)
		(fill yes)
		(layer "In13.Cu")
		(net "M_H_CPU1_SB_DQ<1>")
	)
	(gr_poly
		(pts
			(xy 135.204708 -273.478244) (xy 135.104632 -273.378168) (xy 135.004556 -273.478244) (xy 135.004556 -273.522694)
			(xy 135.204708 -273.522694)
		)
		(stroke
			(width 0)
			(type solid)
		)
		(fill yes)
		(layer "In13.Cu")
		(net "M_H_CPU1_SB_CB<1>")
	)
	(gr_poly
		(pts
			(xy 135.204708 -271.857978) (xy 135.104632 -271.758156) (xy 135.004556 -271.857978) (xy 135.004556 -271.90573)
			(xy 135.204708 -271.90573)
		)
		(stroke
			(width 0)
			(type solid)
		)
		(fill yes)
		(layer "In13.Cu")
		(net "M_H_CPU1_SB_DQS_DN<4>")
	)
	(gr_poly
		(pts
			(xy 135.204708 -270.23822) (xy 135.104632 -270.138144) (xy 135.004556 -270.23822) (xy 135.004556 -270.28267)
			(xy 135.204708 -270.28267)
		)
		(stroke
			(width 0)
			(type solid)
		)
		(fill yes)
		(layer "In13.Cu")
		(net "M_H_CPU1_SB_CB<5>")
	)
	(gr_poly
		(pts
			(xy 135.204708 -266.998196) (xy 135.104632 -266.89812) (xy 135.004556 -266.998196) (xy 135.004556 -267.042646)
			(xy 135.204708 -267.042646)
		)
		(stroke
			(width 0)
			(type solid)
		)
		(fill yes)
		(layer "In13.Cu")
		(net "M_H_CPU1_SA_RSP<0>")
	)
	(gr_poly
		(pts
			(xy 135.204708 -265.378184) (xy 135.104632 -265.278108) (xy 135.004556 -265.378184) (xy 135.004556 -265.422634)
			(xy 135.204708 -265.422634)
		)
		(stroke
			(width 0)
			(type solid)
		)
		(fill yes)
		(layer "In13.Cu")
		(net "M_H_CPU1_SB_PAR")
	)
	(gr_poly
		(pts
			(xy 135.204708 -263.758172) (xy 135.104632 -263.658096) (xy 135.004556 -263.758172) (xy 135.004556 -263.802622)
			(xy 135.204708 -263.802622)
		)
		(stroke
			(width 0)
			(type solid)
		)
		(fill yes)
		(layer "In13.Cu")
		(net "M_H_CPU1_SB_CA<4>")
	)
	(gr_poly
		(pts
			(xy 135.204708 -262.13816) (xy 135.104632 -262.038084) (xy 135.004556 -262.13816) (xy 135.004556 -262.18261)
			(xy 135.204708 -262.18261)
		)
		(stroke
			(width 0)
			(type solid)
		)
		(fill yes)
		(layer "In13.Cu")
		(net "M_H_CPU1_SB_CA<0>")
	)
	(gr_poly
		(pts
			(xy 135.374888 -255.216406) (xy 135.274812 -255.11633) (xy 135.174736 -255.216406) (xy 135.174736 -255.260856)
			(xy 135.374888 -255.260856)
		)
		(stroke
			(width 0)
			(type solid)
		)
		(fill yes)
		(layer "In13.Cu")
		(net "M_H_CPU1_SA_CA<6>")
	)
	(gr_poly
		(pts
			(xy 135.374888 -253.596394) (xy 135.274812 -253.496318) (xy 135.174736 -253.596394) (xy 135.174736 -253.640844)
			(xy 135.374888 -253.640844)
		)
		(stroke
			(width 0)
			(type solid)
		)
		(fill yes)
		(layer "In13.Cu")
		(net "M_H_CPU1_SA_CA<2>")
	)
	(gr_poly
		(pts
			(xy 135.374888 -251.976382) (xy 135.274812 -251.876306) (xy 135.174736 -251.976382) (xy 135.174736 -252.020832)
			(xy 135.374888 -252.020832)
		)
		(stroke
			(width 0)
			(type solid)
		)
		(fill yes)
		(layer "In13.Cu")
		(net "M_H_CPU1_SA_CS_N<1>")
	)
	(gr_poly
		(pts
			(xy 135.374888 -250.35637) (xy 135.274812 -250.256294) (xy 135.174736 -250.35637) (xy 135.174736 -250.40082)
			(xy 135.374888 -250.40082)
		)
		(stroke
			(width 0)
			(type solid)
		)
		(fill yes)
		(layer "In13.Cu")
		(net "M_H_CPU1_ALERT_R_N")
	)
	(gr_poly
		(pts
			(xy 135.374888 -248.736358) (xy 135.274812 -248.636282) (xy 135.174736 -248.736358) (xy 135.174736 -248.780808)
			(xy 135.374888 -248.780808)
		)
		(stroke
			(width 0)
			(type solid)
		)
		(fill yes)
		(layer "In13.Cu")
		(net "M_H_CPU1_SA_CB<5>")
	)
	(gr_poly
		(pts
			(xy 135.374888 -247.116092) (xy 135.274812 -247.01627) (xy 135.174736 -247.116092) (xy 135.174736 -247.163844)
			(xy 135.374888 -247.163844)
		)
		(stroke
			(width 0)
			(type solid)
		)
		(fill yes)
		(layer "In13.Cu")
		(net "M_H_CPU1_SA_DQS_DN<9>")
	)
	(gr_poly
		(pts
			(xy 135.374888 -245.496334) (xy 135.274812 -245.396258) (xy 135.174736 -245.496334) (xy 135.174736 -245.540784)
			(xy 135.374888 -245.540784)
		)
		(stroke
			(width 0)
			(type solid)
		)
		(fill yes)
		(layer "In13.Cu")
		(net "M_H_CPU1_SA_CB<1>")
	)
	(gr_poly
		(pts
			(xy 135.374888 -243.876322) (xy 135.274812 -243.776246) (xy 135.174736 -243.876322) (xy 135.174736 -243.920772)
			(xy 135.374888 -243.920772)
		)
		(stroke
			(width 0)
			(type solid)
		)
		(fill yes)
		(layer "In13.Cu")
		(net "M_H_CPU1_SA_DQ<29>")
	)
	(gr_poly
		(pts
			(xy 135.374888 -242.256056) (xy 135.274812 -242.156234) (xy 135.174736 -242.256056) (xy 135.174736 -242.303808)
			(xy 135.374888 -242.303808)
		)
		(stroke
			(width 0)
			(type solid)
		)
		(fill yes)
		(layer "In13.Cu")
		(net "M_H_CPU1_SA_DQS_DN<8>")
	)
	(gr_poly
		(pts
			(xy 135.374888 -240.636298) (xy 135.274812 -240.536222) (xy 135.174736 -240.636298) (xy 135.174736 -240.680748)
			(xy 135.374888 -240.680748)
		)
		(stroke
			(width 0)
			(type solid)
		)
		(fill yes)
		(layer "In13.Cu")
		(net "M_H_CPU1_SA_DQ<25>")
	)
	(gr_poly
		(pts
			(xy 135.374888 -239.016286) (xy 135.274812 -238.91621) (xy 135.174736 -239.016286) (xy 135.174736 -239.060736)
			(xy 135.374888 -239.060736)
		)
		(stroke
			(width 0)
			(type solid)
		)
		(fill yes)
		(layer "In13.Cu")
		(net "M_H_CPU1_SA_DQ<21>")
	)
	(gr_poly
		(pts
			(xy 135.374888 -237.39602) (xy 135.274812 -237.296198) (xy 135.174736 -237.39602) (xy 135.174736 -237.443772)
			(xy 135.374888 -237.443772)
		)
		(stroke
			(width 0)
			(type solid)
		)
		(fill yes)
		(layer "In13.Cu")
		(net "M_H_CPU1_SA_DQS_DN<7>")
	)
	(gr_poly
		(pts
			(xy 135.374888 -235.776262) (xy 135.274812 -235.676186) (xy 135.174736 -235.776262) (xy 135.174736 -235.820712)
			(xy 135.374888 -235.820712)
		)
		(stroke
			(width 0)
			(type solid)
		)
		(fill yes)
		(layer "In13.Cu")
		(net "M_H_CPU1_SA_DQ<17>")
	)
	(gr_poly
		(pts
			(xy 135.374888 -234.15625) (xy 135.274812 -234.056174) (xy 135.174736 -234.15625) (xy 135.174736 -234.2007)
			(xy 135.374888 -234.2007)
		)
		(stroke
			(width 0)
			(type solid)
		)
		(fill yes)
		(layer "In13.Cu")
		(net "M_H_CPU1_SA_DQ<13>")
	)
	(gr_poly
		(pts
			(xy 135.374888 -232.535984) (xy 135.274812 -232.436162) (xy 135.174736 -232.535984) (xy 135.174736 -232.583736)
			(xy 135.374888 -232.583736)
		)
		(stroke
			(width 0)
			(type solid)
		)
		(fill yes)
		(layer "In13.Cu")
		(net "M_H_CPU1_SA_DQS_DN<6>")
	)
	(gr_poly
		(pts
			(xy 135.374888 -230.916226) (xy 135.274812 -230.81615) (xy 135.174736 -230.916226) (xy 135.174736 -230.960676)
			(xy 135.374888 -230.960676)
		)
		(stroke
			(width 0)
			(type solid)
		)
		(fill yes)
		(layer "In13.Cu")
		(net "M_H_CPU1_SA_DQ<9>")
	)
	(gr_poly
		(pts
			(xy 135.374888 -229.296214) (xy 135.274812 -229.196138) (xy 135.174736 -229.296214) (xy 135.174736 -229.340664)
			(xy 135.374888 -229.340664)
		)
		(stroke
			(width 0)
			(type solid)
		)
		(fill yes)
		(layer "In13.Cu")
		(net "M_H_CPU1_SA_DQ<5>")
	)
	(gr_poly
		(pts
			(xy 135.374888 -227.676202) (xy 135.274812 -227.57638) (xy 135.174736 -227.676202) (xy 135.174736 -227.723954)
			(xy 135.374888 -227.723954)
		)
		(stroke
			(width 0)
			(type solid)
		)
		(fill yes)
		(layer "In13.Cu")
		(net "M_H_CPU1_SA_DQS_DN<5>")
	)
	(gr_poly
		(pts
			(xy 135.374888 -226.056444) (xy 135.274812 -225.956368) (xy 135.174736 -226.056444) (xy 135.174736 -226.100894)
			(xy 135.374888 -226.100894)
		)
		(stroke
			(width 0)
			(type solid)
		)
		(fill yes)
		(layer "In13.Cu")
		(net "M_H_CPU1_SA_DQ<1>")
	)
	(gr_poly
		(pts
			(xy 135.674862 -293.32428) (xy 135.674862 -293.27983) (xy 135.47471 -293.27983) (xy 135.47471 -293.32428)
			(xy 135.574786 -293.424356)
		)
		(stroke
			(width 0)
			(type solid)
		)
		(fill yes)
		(layer "In13.Cu")
		(net "M_H_CPU1_SB_DQ<31>")
	)
	(gr_poly
		(pts
			(xy 135.674862 -291.704522) (xy 135.674862 -291.65677) (xy 135.47471 -291.65677) (xy 135.47471 -291.704522)
			(xy 135.574786 -291.804344)
		)
		(stroke
			(width 0)
			(type solid)
		)
		(fill yes)
		(layer "In13.Cu")
		(net "M_H_CPU1_SB_DQS_DP<8>")
	)
	(gr_poly
		(pts
			(xy 135.674862 -290.084256) (xy 135.674862 -290.039806) (xy 135.47471 -290.039806) (xy 135.47471 -290.084256)
			(xy 135.574786 -290.184332)
		)
		(stroke
			(width 0)
			(type solid)
		)
		(fill yes)
		(layer "In13.Cu")
		(net "M_H_CPU1_SB_DQ<27>")
	)
	(gr_poly
		(pts
			(xy 135.674862 -288.464498) (xy 135.674862 -288.420048) (xy 135.47471 -288.420048) (xy 135.47471 -288.464498)
			(xy 135.574786 -288.564574)
		)
		(stroke
			(width 0)
			(type solid)
		)
		(fill yes)
		(layer "In13.Cu")
		(net "M_H_CPU1_SB_DQ<23>")
	)
	(gr_poly
		(pts
			(xy 135.674862 -286.844486) (xy 135.674862 -286.796734) (xy 135.47471 -286.796734) (xy 135.47471 -286.844486)
			(xy 135.574786 -286.944562)
		)
		(stroke
			(width 0)
			(type solid)
		)
		(fill yes)
		(layer "In13.Cu")
		(net "M_H_CPU1_SB_DQS_DP<7>")
	)
	(gr_poly
		(pts
			(xy 135.674862 -285.224474) (xy 135.674862 -285.180024) (xy 135.47471 -285.180024) (xy 135.47471 -285.224474)
			(xy 135.574786 -285.32455)
		)
		(stroke
			(width 0)
			(type solid)
		)
		(fill yes)
		(layer "In13.Cu")
		(net "M_H_CPU1_SB_DQ<19>")
	)
	(gr_poly
		(pts
			(xy 135.674862 -283.604462) (xy 135.674862 -283.560012) (xy 135.47471 -283.560012) (xy 135.47471 -283.604462)
			(xy 135.574786 -283.704538)
		)
		(stroke
			(width 0)
			(type solid)
		)
		(fill yes)
		(layer "In13.Cu")
		(net "M_H_CPU1_SB_DQ<15>")
	)
	(gr_poly
		(pts
			(xy 135.674862 -281.984704) (xy 135.674862 -281.936952) (xy 135.47471 -281.936952) (xy 135.47471 -281.984704)
			(xy 135.574786 -282.084526)
		)
		(stroke
			(width 0)
			(type solid)
		)
		(fill yes)
		(layer "In13.Cu")
		(net "M_H_CPU1_SB_DQS_DP<6>")
	)
	(gr_poly
		(pts
			(xy 135.674862 -280.364438) (xy 135.674862 -280.319988) (xy 135.47471 -280.319988) (xy 135.47471 -280.364438)
			(xy 135.574786 -280.464514)
		)
		(stroke
			(width 0)
			(type solid)
		)
		(fill yes)
		(layer "In13.Cu")
		(net "M_H_CPU1_SB_DQ<11>")
	)
	(gr_poly
		(pts
			(xy 135.674862 -278.744426) (xy 135.674862 -278.699976) (xy 135.47471 -278.699976) (xy 135.47471 -278.744426)
			(xy 135.574786 -278.844502)
		)
		(stroke
			(width 0)
			(type solid)
		)
		(fill yes)
		(layer "In13.Cu")
		(net "M_H_CPU1_SB_DQ<7>")
	)
	(gr_poly
		(pts
			(xy 135.674862 -277.124668) (xy 135.674862 -277.076916) (xy 135.47471 -277.076916) (xy 135.47471 -277.124668)
			(xy 135.574786 -277.22449)
		)
		(stroke
			(width 0)
			(type solid)
		)
		(fill yes)
		(layer "In13.Cu")
		(net "M_H_CPU1_SB_DQS_DP<5>")
	)
	(gr_poly
		(pts
			(xy 135.674862 -275.504402) (xy 135.674862 -275.459952) (xy 135.47471 -275.459952) (xy 135.47471 -275.504402)
			(xy 135.574786 -275.604478)
		)
		(stroke
			(width 0)
			(type solid)
		)
		(fill yes)
		(layer "In13.Cu")
		(net "M_H_CPU1_SB_DQ<3>")
	)
	(gr_poly
		(pts
			(xy 135.674862 -273.88439) (xy 135.674862 -273.83994) (xy 135.47471 -273.83994) (xy 135.47471 -273.88439)
			(xy 135.574786 -273.984466)
		)
		(stroke
			(width 0)
			(type solid)
		)
		(fill yes)
		(layer "In13.Cu")
		(net "M_H_CPU1_SB_CB<3>")
	)
	(gr_poly
		(pts
			(xy 135.674862 -272.264632) (xy 135.674862 -272.21688) (xy 135.47471 -272.21688) (xy 135.47471 -272.264632)
			(xy 135.574786 -272.364454)
		)
		(stroke
			(width 0)
			(type solid)
		)
		(fill yes)
		(layer "In13.Cu")
		(net "M_H_CPU1_SB_DQS_DP<4>")
	)
	(gr_poly
		(pts
			(xy 135.674862 -270.644366) (xy 135.674862 -270.599916) (xy 135.47471 -270.599916) (xy 135.47471 -270.644366)
			(xy 135.574786 -270.744442)
		)
		(stroke
			(width 0)
			(type solid)
		)
		(fill yes)
		(layer "In13.Cu")
		(net "M_H_CPU1_SB_CB<7>")
	)
	(gr_poly
		(pts
			(xy 135.674862 -265.78433) (xy 135.674862 -265.73988) (xy 135.47471 -265.73988) (xy 135.47471 -265.78433)
			(xy 135.574786 -265.884406)
		)
		(stroke
			(width 0)
			(type solid)
		)
		(fill yes)
		(layer "In13.Cu")
		(net "M_H_CPU1_SB_CS_N<0>")
	)
	(gr_poly
		(pts
			(xy 135.674862 -264.164318) (xy 135.674862 -264.119868) (xy 135.47471 -264.119868) (xy 135.47471 -264.164318)
			(xy 135.574786 -264.264394)
		)
		(stroke
			(width 0)
			(type solid)
		)
		(fill yes)
		(layer "In13.Cu")
		(net "M_H_CPU1_SB_CA<5>")
	)
	(gr_poly
		(pts
			(xy 135.674862 -262.544306) (xy 135.674862 -262.499856) (xy 135.47471 -262.499856) (xy 135.47471 -262.544306)
			(xy 135.574786 -262.644382)
		)
		(stroke
			(width 0)
			(type solid)
		)
		(fill yes)
		(layer "In13.Cu")
		(net "M_H_CPU1_SB_CA<1>")
	)
	(gr_poly
		(pts
			(xy 135.844788 -255.622552) (xy 135.844788 -255.578102) (xy 135.644636 -255.578102) (xy 135.644636 -255.622552)
			(xy 135.744712 -255.722628)
		)
		(stroke
			(width 0)
			(type solid)
		)
		(fill yes)
		(layer "In13.Cu")
		(net "M_H_CPU1_SA_PAR")
	)
	(gr_poly
		(pts
			(xy 135.844788 -254.00254) (xy 135.844788 -253.95809) (xy 135.644636 -253.95809) (xy 135.644636 -254.00254)
			(xy 135.744712 -254.102616)
		)
		(stroke
			(width 0)
			(type solid)
		)
		(fill yes)
		(layer "In13.Cu")
		(net "M_H_CPU1_SA_CA<3>")
	)
	(gr_poly
		(pts
			(xy 135.844788 -250.762516) (xy 135.844788 -250.718066) (xy 135.644636 -250.718066) (xy 135.644636 -250.762516)
			(xy 135.744712 -250.862592)
		)
		(stroke
			(width 0)
			(type solid)
		)
		(fill yes)
		(layer "In13.Cu")
		(net "M_H_CPU1_RESET_N")
	)
	(gr_poly
		(pts
			(xy 135.844788 -249.142504) (xy 135.844788 -249.098054) (xy 135.644636 -249.098054) (xy 135.644636 -249.142504)
			(xy 135.744712 -249.24258)
		)
		(stroke
			(width 0)
			(type solid)
		)
		(fill yes)
		(layer "In13.Cu")
		(net "M_H_CPU1_SA_CB<7>")
	)
	(gr_poly
		(pts
			(xy 135.844788 -247.522746) (xy 135.844788 -247.474994) (xy 135.644636 -247.474994) (xy 135.644636 -247.522746)
			(xy 135.744712 -247.622568)
		)
		(stroke
			(width 0)
			(type solid)
		)
		(fill yes)
		(layer "In13.Cu")
		(net "M_H_CPU1_SA_DQS_DP<9>")
	)
	(gr_poly
		(pts
			(xy 135.844788 -245.90248) (xy 135.844788 -245.85803) (xy 135.644636 -245.85803) (xy 135.644636 -245.90248)
			(xy 135.744712 -246.002556)
		)
		(stroke
			(width 0)
			(type solid)
		)
		(fill yes)
		(layer "In13.Cu")
		(net "M_H_CPU1_SA_CB<3>")
	)
	(gr_poly
		(pts
			(xy 135.844788 -244.282468) (xy 135.844788 -244.238018) (xy 135.644636 -244.238018) (xy 135.644636 -244.282468)
			(xy 135.744712 -244.382544)
		)
		(stroke
			(width 0)
			(type solid)
		)
		(fill yes)
		(layer "In13.Cu")
		(net "M_H_CPU1_SA_DQ<31>")
	)
	(gr_poly
		(pts
			(xy 135.844788 -242.66271) (xy 135.844788 -242.614958) (xy 135.644636 -242.614958) (xy 135.644636 -242.66271)
			(xy 135.744712 -242.762532)
		)
		(stroke
			(width 0)
			(type solid)
		)
		(fill yes)
		(layer "In13.Cu")
		(net "M_H_CPU1_SA_DQS_DP<8>")
	)
	(gr_poly
		(pts
			(xy 135.844788 -241.042444) (xy 135.844788 -240.997994) (xy 135.644636 -240.997994) (xy 135.644636 -241.042444)
			(xy 135.744712 -241.14252)
		)
		(stroke
			(width 0)
			(type solid)
		)
		(fill yes)
		(layer "In13.Cu")
		(net "M_H_CPU1_SA_DQ<27>")
	)
	(gr_poly
		(pts
			(xy 135.844788 -239.422432) (xy 135.844788 -239.377982) (xy 135.644636 -239.377982) (xy 135.644636 -239.422432)
			(xy 135.744712 -239.522508)
		)
		(stroke
			(width 0)
			(type solid)
		)
		(fill yes)
		(layer "In13.Cu")
		(net "M_H_CPU1_SA_DQ<23>")
	)
	(gr_poly
		(pts
			(xy 135.844788 -237.802674) (xy 135.844788 -237.754922) (xy 135.644636 -237.754922) (xy 135.644636 -237.802674)
			(xy 135.744712 -237.902496)
		)
		(stroke
			(width 0)
			(type solid)
		)
		(fill yes)
		(layer "In13.Cu")
		(net "M_H_CPU1_SA_DQS_DP<7>")
	)
	(gr_poly
		(pts
			(xy 135.844788 -236.182408) (xy 135.844788 -236.137958) (xy 135.644636 -236.137958) (xy 135.644636 -236.182408)
			(xy 135.744712 -236.282484)
		)
		(stroke
			(width 0)
			(type solid)
		)
		(fill yes)
		(layer "In13.Cu")
		(net "M_H_CPU1_SA_DQ<19>")
	)
	(gr_poly
		(pts
			(xy 135.844788 -234.562396) (xy 135.844788 -234.517946) (xy 135.644636 -234.517946) (xy 135.644636 -234.562396)
			(xy 135.744712 -234.662472)
		)
		(stroke
			(width 0)
			(type solid)
		)
		(fill yes)
		(layer "In13.Cu")
		(net "M_H_CPU1_SA_DQ<15>")
	)
	(gr_poly
		(pts
			(xy 135.844788 -232.942638) (xy 135.844788 -232.894886) (xy 135.644636 -232.894886) (xy 135.644636 -232.942638)
			(xy 135.744712 -233.04246)
		)
		(stroke
			(width 0)
			(type solid)
		)
		(fill yes)
		(layer "In13.Cu")
		(net "M_H_CPU1_SA_DQS_DP<6>")
	)
	(gr_poly
		(pts
			(xy 135.844788 -231.322626) (xy 135.844788 -231.278176) (xy 135.644636 -231.278176) (xy 135.644636 -231.322626)
			(xy 135.744712 -231.422702)
		)
		(stroke
			(width 0)
			(type solid)
		)
		(fill yes)
		(layer "In13.Cu")
		(net "M_H_CPU1_SA_DQ<11>")
	)
	(gr_poly
		(pts
			(xy 135.844788 -229.702614) (xy 135.844788 -229.658164) (xy 135.644636 -229.658164) (xy 135.644636 -229.702614)
			(xy 135.744712 -229.80269)
		)
		(stroke
			(width 0)
			(type solid)
		)
		(fill yes)
		(layer "In13.Cu")
		(net "M_H_CPU1_SA_DQ<7>")
	)
	(gr_poly
		(pts
			(xy 135.844788 -228.082856) (xy 135.844788 -228.035104) (xy 135.644636 -228.035104) (xy 135.644636 -228.082856)
			(xy 135.744712 -228.182678)
		)
		(stroke
			(width 0)
			(type solid)
		)
		(fill yes)
		(layer "In13.Cu")
		(net "M_H_CPU1_SA_DQS_DP<5>")
	)
	(gr_poly
		(pts
			(xy 135.844788 -226.46259) (xy 135.844788 -226.41814) (xy 135.644636 -226.41814) (xy 135.644636 -226.46259)
			(xy 135.744712 -226.562666)
		)
		(stroke
			(width 0)
			(type solid)
		)
		(fill yes)
		(layer "In13.Cu")
		(net "M_H_CPU1_SA_DQ<3>")
	)
	(gr_poly
		(pts
			(xy 136.144762 -292.918134) (xy 136.044686 -292.818058) (xy 135.94461 -292.918134) (xy 135.94461 -292.962584)
			(xy 136.144762 -292.962584)
		)
		(stroke
			(width 0)
			(type solid)
		)
		(fill yes)
		(layer "In13.Cu")
		(net "M_H_CPU1_SB_DQ<29>")
	)
	(gr_poly
		(pts
			(xy 136.144762 -291.297868) (xy 136.044686 -291.198046) (xy 135.94461 -291.297868) (xy 135.94461 -291.34562)
			(xy 136.144762 -291.34562)
		)
		(stroke
			(width 0)
			(type solid)
		)
		(fill yes)
		(layer "In13.Cu")
		(net "M_H_CPU1_SB_DQS_DN<8>")
	)
	(gr_poly
		(pts
			(xy 136.144762 -289.67811) (xy 136.044686 -289.578034) (xy 135.94461 -289.67811) (xy 135.94461 -289.72256)
			(xy 136.144762 -289.72256)
		)
		(stroke
			(width 0)
			(type solid)
		)
		(fill yes)
		(layer "In13.Cu")
		(net "M_H_CPU1_SB_DQ<25>")
	)
	(gr_poly
		(pts
			(xy 136.144762 -288.058098) (xy 136.044686 -287.958022) (xy 135.94461 -288.058098) (xy 135.94461 -288.102548)
			(xy 136.144762 -288.102548)
		)
		(stroke
			(width 0)
			(type solid)
		)
		(fill yes)
		(layer "In13.Cu")
		(net "M_H_CPU1_SB_DQ<21>")
	)
	(gr_poly
		(pts
			(xy 136.144762 -286.438086) (xy 136.044686 -286.33801) (xy 135.94461 -286.438086) (xy 135.94461 -286.485838)
			(xy 136.144762 -286.485838)
		)
		(stroke
			(width 0)
			(type solid)
		)
		(fill yes)
		(layer "In13.Cu")
		(net "M_H_CPU1_SB_DQS_DN<7>")
	)
	(gr_poly
		(pts
			(xy 136.144762 -284.818328) (xy 136.044686 -284.718252) (xy 135.94461 -284.818328) (xy 135.94461 -284.862778)
			(xy 136.144762 -284.862778)
		)
		(stroke
			(width 0)
			(type solid)
		)
		(fill yes)
		(layer "In13.Cu")
		(net "M_H_CPU1_SB_DQ<17>")
	)
	(gr_poly
		(pts
			(xy 136.144762 -283.198316) (xy 136.044686 -283.09824) (xy 135.94461 -283.198316) (xy 135.94461 -283.242766)
			(xy 136.144762 -283.242766)
		)
		(stroke
			(width 0)
			(type solid)
		)
		(fill yes)
		(layer "In13.Cu")
		(net "M_H_CPU1_SB_DQ<13>")
	)
	(gr_poly
		(pts
			(xy 136.144762 -281.57805) (xy 136.044686 -281.478228) (xy 135.94461 -281.57805) (xy 135.94461 -281.625802)
			(xy 136.144762 -281.625802)
		)
		(stroke
			(width 0)
			(type solid)
		)
		(fill yes)
		(layer "In13.Cu")
		(net "M_H_CPU1_SB_DQS_DN<6>")
	)
	(gr_poly
		(pts
			(xy 136.144762 -279.958292) (xy 136.044686 -279.858216) (xy 135.94461 -279.958292) (xy 135.94461 -280.002742)
			(xy 136.144762 -280.002742)
		)
		(stroke
			(width 0)
			(type solid)
		)
		(fill yes)
		(layer "In13.Cu")
		(net "M_H_CPU1_SB_DQ<9>")
	)
	(gr_poly
		(pts
			(xy 136.144762 -278.33828) (xy 136.044686 -278.238204) (xy 135.94461 -278.33828) (xy 135.94461 -278.38273)
			(xy 136.144762 -278.38273)
		)
		(stroke
			(width 0)
			(type solid)
		)
		(fill yes)
		(layer "In13.Cu")
		(net "M_H_CPU1_SB_DQ<5>")
	)
	(gr_poly
		(pts
			(xy 136.144762 -276.718014) (xy 136.044686 -276.618192) (xy 135.94461 -276.718014) (xy 135.94461 -276.765766)
			(xy 136.144762 -276.765766)
		)
		(stroke
			(width 0)
			(type solid)
		)
		(fill yes)
		(layer "In13.Cu")
		(net "M_H_CPU1_SB_DQS_DN<5>")
	)
	(gr_poly
		(pts
			(xy 136.144762 -275.098256) (xy 136.044686 -274.99818) (xy 135.94461 -275.098256) (xy 135.94461 -275.142706)
			(xy 136.144762 -275.142706)
		)
		(stroke
			(width 0)
			(type solid)
		)
		(fill yes)
		(layer "In13.Cu")
		(net "M_H_CPU1_SB_DQ<1>")
	)
	(gr_poly
		(pts
			(xy 136.144762 -273.478244) (xy 136.044686 -273.378168) (xy 135.94461 -273.478244) (xy 135.94461 -273.522694)
			(xy 136.144762 -273.522694)
		)
		(stroke
			(width 0)
			(type solid)
		)
		(fill yes)
		(layer "In13.Cu")
		(net "M_H_CPU1_SB_CB<1>")
	)
	(gr_poly
		(pts
			(xy 136.144762 -271.857978) (xy 136.044686 -271.758156) (xy 135.94461 -271.857978) (xy 135.94461 -271.90573)
			(xy 136.144762 -271.90573)
		)
		(stroke
			(width 0)
			(type solid)
		)
		(fill yes)
		(layer "In13.Cu")
		(net "M_H_CPU1_SB_DQS_DN<4>")
	)
	(gr_poly
		(pts
			(xy 136.144762 -270.23822) (xy 136.044686 -270.138144) (xy 135.94461 -270.23822) (xy 135.94461 -270.28267)
			(xy 136.144762 -270.28267)
		)
		(stroke
			(width 0)
			(type solid)
		)
		(fill yes)
		(layer "In13.Cu")
		(net "M_H_CPU1_SB_CB<5>")
	)
	(gr_poly
		(pts
			(xy 136.144762 -266.998196) (xy 136.044686 -266.89812) (xy 135.94461 -266.998196) (xy 135.94461 -267.042646)
			(xy 136.144762 -267.042646)
		)
		(stroke
			(width 0)
			(type solid)
		)
		(fill yes)
		(layer "In13.Cu")
		(net "M_H_CPU1_SA_RSP<0>")
	)
	(gr_poly
		(pts
			(xy 136.144762 -265.378184) (xy 136.044686 -265.278108) (xy 135.94461 -265.378184) (xy 135.94461 -265.422634)
			(xy 136.144762 -265.422634)
		)
		(stroke
			(width 0)
			(type solid)
		)
		(fill yes)
		(layer "In13.Cu")
		(net "M_H_CPU1_SB_PAR")
	)
	(gr_poly
		(pts
			(xy 136.144762 -263.758172) (xy 136.044686 -263.658096) (xy 135.94461 -263.758172) (xy 135.94461 -263.802622)
			(xy 136.144762 -263.802622)
		)
		(stroke
			(width 0)
			(type solid)
		)
		(fill yes)
		(layer "In13.Cu")
		(net "M_H_CPU1_SB_CA<4>")
	)
	(gr_poly
		(pts
			(xy 136.144762 -262.13816) (xy 136.044686 -262.038084) (xy 135.94461 -262.13816) (xy 135.94461 -262.18261)
			(xy 136.144762 -262.18261)
		)
		(stroke
			(width 0)
			(type solid)
		)
		(fill yes)
		(layer "In13.Cu")
		(net "M_H_CPU1_SB_CA<0>")
	)
	(gr_poly
		(pts
			(xy 136.314942 -256.432812) (xy 136.314942 -256.38506) (xy 136.11479 -256.38506) (xy 136.11479 -256.432812)
			(xy 136.214866 -256.532634)
		)
		(stroke
			(width 0)
			(type solid)
		)
		(fill yes)
		(layer "In13.Cu")
		(net "M_H_CPU1_CLK_DN<0>")
	)
	(gr_poly
		(pts
			(xy 136.314942 -255.216406) (xy 136.214866 -255.11633) (xy 136.11479 -255.216406) (xy 136.11479 -255.260856)
			(xy 136.314942 -255.260856)
		)
		(stroke
			(width 0)
			(type solid)
		)
		(fill yes)
		(layer "In13.Cu")
		(net "M_H_CPU1_SA_CA<6>")
	)
	(gr_poly
		(pts
			(xy 136.314942 -254.812546) (xy 136.314942 -254.768096) (xy 136.11479 -254.768096) (xy 136.11479 -254.812546)
			(xy 136.214866 -254.912622)
		)
		(stroke
			(width 0)
			(type solid)
		)
		(fill yes)
		(layer "In13.Cu")
		(net "M_H_CPU1_SA_CA<5>")
	)
	(gr_poly
		(pts
			(xy 136.314942 -253.596394) (xy 136.214866 -253.496318) (xy 136.11479 -253.596394) (xy 136.11479 -253.640844)
			(xy 136.314942 -253.640844)
		)
		(stroke
			(width 0)
			(type solid)
		)
		(fill yes)
		(layer "In13.Cu")
		(net "M_H_CPU1_SA_CA<2>")
	)
	(gr_poly
		(pts
			(xy 136.314942 -253.192534) (xy 136.314942 -253.148084) (xy 136.11479 -253.148084) (xy 136.11479 -253.192534)
			(xy 136.214866 -253.29261)
		)
		(stroke
			(width 0)
			(type solid)
		)
		(fill yes)
		(layer "In13.Cu")
		(net "M_H_CPU1_SA_CA<1>")
	)
	(gr_poly
		(pts
			(xy 136.314942 -251.976382) (xy 136.214866 -251.876306) (xy 136.11479 -251.976382) (xy 136.11479 -252.020832)
			(xy 136.314942 -252.020832)
		)
		(stroke
			(width 0)
			(type solid)
		)
		(fill yes)
		(layer "In13.Cu")
		(net "M_H_CPU1_SA_CS_N<1>")
	)
	(gr_poly
		(pts
			(xy 136.314942 -250.35637) (xy 136.214866 -250.256294) (xy 136.11479 -250.35637) (xy 136.11479 -250.40082)
			(xy 136.314942 -250.40082)
		)
		(stroke
			(width 0)
			(type solid)
		)
		(fill yes)
		(layer "In13.Cu")
		(net "M_H_CPU1_ALERT_R_N")
	)
	(gr_poly
		(pts
			(xy 136.314942 -248.736358) (xy 136.214866 -248.636282) (xy 136.11479 -248.736358) (xy 136.11479 -248.780808)
			(xy 136.314942 -248.780808)
		)
		(stroke
			(width 0)
			(type solid)
		)
		(fill yes)
		(layer "In13.Cu")
		(net "M_H_CPU1_SA_CB<5>")
	)
	(gr_poly
		(pts
			(xy 136.314942 -248.332498) (xy 136.314942 -248.288048) (xy 136.11479 -248.288048) (xy 136.11479 -248.332498)
			(xy 136.214866 -248.432574)
		)
		(stroke
			(width 0)
			(type solid)
		)
		(fill yes)
		(layer "In13.Cu")
		(net "M_H_CPU1_SA_CB<6>")
	)
	(gr_poly
		(pts
			(xy 136.314942 -247.116092) (xy 136.214866 -247.01627) (xy 136.11479 -247.116092) (xy 136.11479 -247.163844)
			(xy 136.314942 -247.163844)
		)
		(stroke
			(width 0)
			(type solid)
		)
		(fill yes)
		(layer "In13.Cu")
		(net "M_H_CPU1_SA_DQS_DN<9>")
	)
	(gr_poly
		(pts
			(xy 136.314942 -246.71274) (xy 136.314942 -246.664988) (xy 136.11479 -246.664988) (xy 136.11479 -246.71274)
			(xy 136.214866 -246.812562)
		)
		(stroke
			(width 0)
			(type solid)
		)
		(fill yes)
		(layer "In13.Cu")
		(net "M_H_CPU1_SA_DQS_DN<4>")
	)
	(gr_poly
		(pts
			(xy 136.314942 -245.496334) (xy 136.214866 -245.396258) (xy 136.11479 -245.496334) (xy 136.11479 -245.540784)
			(xy 136.314942 -245.540784)
		)
		(stroke
			(width 0)
			(type solid)
		)
		(fill yes)
		(layer "In13.Cu")
		(net "M_H_CPU1_SA_CB<1>")
	)
	(gr_poly
		(pts
			(xy 136.314942 -245.092474) (xy 136.314942 -245.048024) (xy 136.11479 -245.048024) (xy 136.11479 -245.092474)
			(xy 136.214866 -245.19255)
		)
		(stroke
			(width 0)
			(type solid)
		)
		(fill yes)
		(layer "In13.Cu")
		(net "M_H_CPU1_SA_CB<2>")
	)
	(gr_poly
		(pts
			(xy 136.314942 -243.876322) (xy 136.214866 -243.776246) (xy 136.11479 -243.876322) (xy 136.11479 -243.920772)
			(xy 136.314942 -243.920772)
		)
		(stroke
			(width 0)
			(type solid)
		)
		(fill yes)
		(layer "In13.Cu")
		(net "M_H_CPU1_SA_DQ<29>")
	)
	(gr_poly
		(pts
			(xy 136.314942 -243.472462) (xy 136.314942 -243.428012) (xy 136.11479 -243.428012) (xy 136.11479 -243.472462)
			(xy 136.214866 -243.572538)
		)
		(stroke
			(width 0)
			(type solid)
		)
		(fill yes)
		(layer "In13.Cu")
		(net "M_H_CPU1_SA_DQ<30>")
	)
	(gr_poly
		(pts
			(xy 136.314942 -242.256056) (xy 136.214866 -242.156234) (xy 136.11479 -242.256056) (xy 136.11479 -242.303808)
			(xy 136.314942 -242.303808)
		)
		(stroke
			(width 0)
			(type solid)
		)
		(fill yes)
		(layer "In13.Cu")
		(net "M_H_CPU1_SA_DQS_DN<8>")
	)
	(gr_poly
		(pts
			(xy 136.314942 -241.852704) (xy 136.314942 -241.804952) (xy 136.11479 -241.804952) (xy 136.11479 -241.852704)
			(xy 136.214866 -241.952526)
		)
		(stroke
			(width 0)
			(type solid)
		)
		(fill yes)
		(layer "In13.Cu")
		(net "M_H_CPU1_SA_DQS_DN<3>")
	)
	(gr_poly
		(pts
			(xy 136.314942 -240.636298) (xy 136.214866 -240.536222) (xy 136.11479 -240.636298) (xy 136.11479 -240.680748)
			(xy 136.314942 -240.680748)
		)
		(stroke
			(width 0)
			(type solid)
		)
		(fill yes)
		(layer "In13.Cu")
		(net "M_H_CPU1_SA_DQ<25>")
	)
	(gr_poly
		(pts
			(xy 136.314942 -240.232438) (xy 136.314942 -240.187988) (xy 136.11479 -240.187988) (xy 136.11479 -240.232438)
			(xy 136.214866 -240.332514)
		)
		(stroke
			(width 0)
			(type solid)
		)
		(fill yes)
		(layer "In13.Cu")
		(net "M_H_CPU1_SA_DQ<26>")
	)
	(gr_poly
		(pts
			(xy 136.314942 -239.016286) (xy 136.214866 -238.91621) (xy 136.11479 -239.016286) (xy 136.11479 -239.060736)
			(xy 136.314942 -239.060736)
		)
		(stroke
			(width 0)
			(type solid)
		)
		(fill yes)
		(layer "In13.Cu")
		(net "M_H_CPU1_SA_DQ<21>")
	)
	(gr_poly
		(pts
			(xy 136.314942 -238.612426) (xy 136.314942 -238.567976) (xy 136.11479 -238.567976) (xy 136.11479 -238.612426)
			(xy 136.214866 -238.712502)
		)
		(stroke
			(width 0)
			(type solid)
		)
		(fill yes)
		(layer "In13.Cu")
		(net "M_H_CPU1_SA_DQ<22>")
	)
	(gr_poly
		(pts
			(xy 136.314942 -237.39602) (xy 136.214866 -237.296198) (xy 136.11479 -237.39602) (xy 136.11479 -237.443772)
			(xy 136.314942 -237.443772)
		)
		(stroke
			(width 0)
			(type solid)
		)
		(fill yes)
		(layer "In13.Cu")
		(net "M_H_CPU1_SA_DQS_DN<7>")
	)
	(gr_poly
		(pts
			(xy 136.314942 -236.992668) (xy 136.314942 -236.944916) (xy 136.11479 -236.944916) (xy 136.11479 -236.992668)
			(xy 136.214866 -237.09249)
		)
		(stroke
			(width 0)
			(type solid)
		)
		(fill yes)
		(layer "In13.Cu")
		(net "M_H_CPU1_SA_DQS_DN<2>")
	)
	(gr_poly
		(pts
			(xy 136.314942 -235.776262) (xy 136.214866 -235.676186) (xy 136.11479 -235.776262) (xy 136.11479 -235.820712)
			(xy 136.314942 -235.820712)
		)
		(stroke
			(width 0)
			(type solid)
		)
		(fill yes)
		(layer "In13.Cu")
		(net "M_H_CPU1_SA_DQ<17>")
	)
	(gr_poly
		(pts
			(xy 136.314942 -235.372402) (xy 136.314942 -235.327952) (xy 136.11479 -235.327952) (xy 136.11479 -235.372402)
			(xy 136.214866 -235.472478)
		)
		(stroke
			(width 0)
			(type solid)
		)
		(fill yes)
		(layer "In13.Cu")
		(net "M_H_CPU1_SA_DQ<18>")
	)
	(gr_poly
		(pts
			(xy 136.314942 -234.15625) (xy 136.214866 -234.056174) (xy 136.11479 -234.15625) (xy 136.11479 -234.2007)
			(xy 136.314942 -234.2007)
		)
		(stroke
			(width 0)
			(type solid)
		)
		(fill yes)
		(layer "In13.Cu")
		(net "M_H_CPU1_SA_DQ<13>")
	)
	(gr_poly
		(pts
			(xy 136.314942 -233.75239) (xy 136.314942 -233.70794) (xy 136.11479 -233.70794) (xy 136.11479 -233.75239)
			(xy 136.214866 -233.852466)
		)
		(stroke
			(width 0)
			(type solid)
		)
		(fill yes)
		(layer "In13.Cu")
		(net "M_H_CPU1_SA_DQ<14>")
	)
	(gr_poly
		(pts
			(xy 136.314942 -232.535984) (xy 136.214866 -232.436162) (xy 136.11479 -232.535984) (xy 136.11479 -232.583736)
			(xy 136.314942 -232.583736)
		)
		(stroke
			(width 0)
			(type solid)
		)
		(fill yes)
		(layer "In13.Cu")
		(net "M_H_CPU1_SA_DQS_DN<6>")
	)
	(gr_poly
		(pts
			(xy 136.314942 -232.132632) (xy 136.314942 -232.08488) (xy 136.11479 -232.08488) (xy 136.11479 -232.132632)
			(xy 136.214866 -232.232454)
		)
		(stroke
			(width 0)
			(type solid)
		)
		(fill yes)
		(layer "In13.Cu")
		(net "M_H_CPU1_SA_DQS_DN<1>")
	)
	(gr_poly
		(pts
			(xy 136.314942 -230.916226) (xy 136.214866 -230.81615) (xy 136.11479 -230.916226) (xy 136.11479 -230.960676)
			(xy 136.314942 -230.960676)
		)
		(stroke
			(width 0)
			(type solid)
		)
		(fill yes)
		(layer "In13.Cu")
		(net "M_H_CPU1_SA_DQ<9>")
	)
	(gr_poly
		(pts
			(xy 136.314942 -230.51262) (xy 136.314942 -230.46817) (xy 136.11479 -230.46817) (xy 136.11479 -230.51262)
			(xy 136.214866 -230.612696)
		)
		(stroke
			(width 0)
			(type solid)
		)
		(fill yes)
		(layer "In13.Cu")
		(net "M_H_CPU1_SA_DQ<10>")
	)
	(gr_poly
		(pts
			(xy 136.314942 -229.296214) (xy 136.214866 -229.196138) (xy 136.11479 -229.296214) (xy 136.11479 -229.340664)
			(xy 136.314942 -229.340664)
		)
		(stroke
			(width 0)
			(type solid)
		)
		(fill yes)
		(layer "In13.Cu")
		(net "M_H_CPU1_SA_DQ<5>")
	)
	(gr_poly
		(pts
			(xy 136.314942 -228.892608) (xy 136.314942 -228.848158) (xy 136.11479 -228.848158) (xy 136.11479 -228.892608)
			(xy 136.214866 -228.992684)
		)
		(stroke
			(width 0)
			(type solid)
		)
		(fill yes)
		(layer "In13.Cu")
		(net "M_H_CPU1_SA_DQ<6>")
	)
	(gr_poly
		(pts
			(xy 136.314942 -227.676202) (xy 136.214866 -227.57638) (xy 136.11479 -227.676202) (xy 136.11479 -227.723954)
			(xy 136.314942 -227.723954)
		)
		(stroke
			(width 0)
			(type solid)
		)
		(fill yes)
		(layer "In13.Cu")
		(net "M_H_CPU1_SA_DQS_DN<5>")
	)
	(gr_poly
		(pts
			(xy 136.314942 -227.27285) (xy 136.314942 -227.225098) (xy 136.11479 -227.225098) (xy 136.11479 -227.27285)
			(xy 136.214866 -227.372672)
		)
		(stroke
			(width 0)
			(type solid)
		)
		(fill yes)
		(layer "In13.Cu")
		(net "M_H_CPU1_SA_DQS_DN<0>")
	)
	(gr_poly
		(pts
			(xy 136.314942 -226.056444) (xy 136.214866 -225.956368) (xy 136.11479 -226.056444) (xy 136.11479 -226.100894)
			(xy 136.314942 -226.100894)
		)
		(stroke
			(width 0)
			(type solid)
		)
		(fill yes)
		(layer "In13.Cu")
		(net "M_H_CPU1_SA_DQ<1>")
	)
	(gr_poly
		(pts
			(xy 136.314942 -225.652584) (xy 136.314942 -225.608134) (xy 136.11479 -225.608134) (xy 136.11479 -225.652584)
			(xy 136.214866 -225.75266)
		)
		(stroke
			(width 0)
			(type solid)
		)
		(fill yes)
		(layer "In13.Cu")
		(net "M_H_CPU1_SA_DQ<2>")
	)
	(gr_poly
		(pts
			(xy 136.614916 -293.32428) (xy 136.614916 -293.27983) (xy 136.414764 -293.27983) (xy 136.414764 -293.32428)
			(xy 136.51484 -293.424356)
		)
		(stroke
			(width 0)
			(type solid)
		)
		(fill yes)
		(layer "In13.Cu")
		(net "M_H_CPU1_SB_DQ<31>")
	)
	(gr_poly
		(pts
			(xy 136.614916 -292.108128) (xy 136.51484 -292.008052) (xy 136.414764 -292.108128) (xy 136.414764 -292.152578)
			(xy 136.614916 -292.152578)
		)
		(stroke
			(width 0)
			(type solid)
		)
		(fill yes)
		(layer "In13.Cu")
		(net "M_H_CPU1_SB_DQ<28>")
	)
	(gr_poly
		(pts
			(xy 136.614916 -291.704522) (xy 136.614916 -291.65677) (xy 136.414764 -291.65677) (xy 136.414764 -291.704522)
			(xy 136.51484 -291.804344)
		)
		(stroke
			(width 0)
			(type solid)
		)
		(fill yes)
		(layer "In13.Cu")
		(net "M_H_CPU1_SB_DQS_DP<8>")
	)
	(gr_poly
		(pts
			(xy 136.614916 -290.487862) (xy 136.51484 -290.38804) (xy 136.414764 -290.487862) (xy 136.414764 -290.535614)
			(xy 136.614916 -290.535614)
		)
		(stroke
			(width 0)
			(type solid)
		)
		(fill yes)
		(layer "In13.Cu")
		(net "M_H_CPU1_SB_DQS_DP<3>")
	)
	(gr_poly
		(pts
			(xy 136.614916 -290.084256) (xy 136.614916 -290.039806) (xy 136.414764 -290.039806) (xy 136.414764 -290.084256)
			(xy 136.51484 -290.184332)
		)
		(stroke
			(width 0)
			(type solid)
		)
		(fill yes)
		(layer "In13.Cu")
		(net "M_H_CPU1_SB_DQ<27>")
	)
	(gr_poly
		(pts
			(xy 136.614916 -288.868104) (xy 136.51484 -288.768028) (xy 136.414764 -288.868104) (xy 136.414764 -288.912554)
			(xy 136.614916 -288.912554)
		)
		(stroke
			(width 0)
			(type solid)
		)
		(fill yes)
		(layer "In13.Cu")
		(net "M_H_CPU1_SB_DQ<24>")
	)
	(gr_poly
		(pts
			(xy 136.614916 -288.464498) (xy 136.614916 -288.420048) (xy 136.414764 -288.420048) (xy 136.414764 -288.464498)
			(xy 136.51484 -288.564574)
		)
		(stroke
			(width 0)
			(type solid)
		)
		(fill yes)
		(layer "In13.Cu")
		(net "M_H_CPU1_SB_DQ<23>")
	)
	(gr_poly
		(pts
			(xy 136.614916 -287.248092) (xy 136.51484 -287.148016) (xy 136.414764 -287.248092) (xy 136.414764 -287.292542)
			(xy 136.614916 -287.292542)
		)
		(stroke
			(width 0)
			(type solid)
		)
		(fill yes)
		(layer "In13.Cu")
		(net "M_H_CPU1_SB_DQ<20>")
	)
	(gr_poly
		(pts
			(xy 136.614916 -286.844486) (xy 136.614916 -286.796734) (xy 136.414764 -286.796734) (xy 136.414764 -286.844486)
			(xy 136.51484 -286.944562)
		)
		(stroke
			(width 0)
			(type solid)
		)
		(fill yes)
		(layer "In13.Cu")
		(net "M_H_CPU1_SB_DQS_DP<7>")
	)
	(gr_poly
		(pts
			(xy 136.614916 -285.62808) (xy 136.51484 -285.528258) (xy 136.414764 -285.62808) (xy 136.414764 -285.675832)
			(xy 136.614916 -285.675832)
		)
		(stroke
			(width 0)
			(type solid)
		)
		(fill yes)
		(layer "In13.Cu")
		(net "M_H_CPU1_SB_DQS_DP<2>")
	)
	(gr_poly
		(pts
			(xy 136.614916 -285.224474) (xy 136.614916 -285.180024) (xy 136.414764 -285.180024) (xy 136.414764 -285.224474)
			(xy 136.51484 -285.32455)
		)
		(stroke
			(width 0)
			(type solid)
		)
		(fill yes)
		(layer "In13.Cu")
		(net "M_H_CPU1_SB_DQ<19>")
	)
	(gr_poly
		(pts
			(xy 136.614916 -284.008322) (xy 136.51484 -283.908246) (xy 136.414764 -284.008322) (xy 136.414764 -284.052772)
			(xy 136.614916 -284.052772)
		)
		(stroke
			(width 0)
			(type solid)
		)
		(fill yes)
		(layer "In13.Cu")
		(net "M_H_CPU1_SB_DQ<16>")
	)
	(gr_poly
		(pts
			(xy 136.614916 -283.604462) (xy 136.614916 -283.560012) (xy 136.414764 -283.560012) (xy 136.414764 -283.604462)
			(xy 136.51484 -283.704538)
		)
		(stroke
			(width 0)
			(type solid)
		)
		(fill yes)
		(layer "In13.Cu")
		(net "M_H_CPU1_SB_DQ<15>")
	)
	(gr_poly
		(pts
			(xy 136.614916 -282.38831) (xy 136.51484 -282.288234) (xy 136.414764 -282.38831) (xy 136.414764 -282.43276)
			(xy 136.614916 -282.43276)
		)
		(stroke
			(width 0)
			(type solid)
		)
		(fill yes)
		(layer "In13.Cu")
		(net "M_H_CPU1_SB_DQ<12>")
	)
	(gr_poly
		(pts
			(xy 136.614916 -281.984704) (xy 136.614916 -281.936952) (xy 136.414764 -281.936952) (xy 136.414764 -281.984704)
			(xy 136.51484 -282.084526)
		)
		(stroke
			(width 0)
			(type solid)
		)
		(fill yes)
		(layer "In13.Cu")
		(net "M_H_CPU1_SB_DQS_DP<6>")
	)
	(gr_poly
		(pts
			(xy 136.614916 -280.768044) (xy 136.51484 -280.668222) (xy 136.414764 -280.768044) (xy 136.414764 -280.815796)
			(xy 136.614916 -280.815796)
		)
		(stroke
			(width 0)
			(type solid)
		)
		(fill yes)
		(layer "In13.Cu")
		(net "M_H_CPU1_SB_DQS_DP<1>")
	)
	(gr_poly
		(pts
			(xy 136.614916 -280.364438) (xy 136.614916 -280.319988) (xy 136.414764 -280.319988) (xy 136.414764 -280.364438)
			(xy 136.51484 -280.464514)
		)
		(stroke
			(width 0)
			(type solid)
		)
		(fill yes)
		(layer "In13.Cu")
		(net "M_H_CPU1_SB_DQ<11>")
	)
	(gr_poly
		(pts
			(xy 136.614916 -279.148286) (xy 136.51484 -279.04821) (xy 136.414764 -279.148286) (xy 136.414764 -279.192736)
			(xy 136.614916 -279.192736)
		)
		(stroke
			(width 0)
			(type solid)
		)
		(fill yes)
		(layer "In13.Cu")
		(net "M_H_CPU1_SB_DQ<8>")
	)
	(gr_poly
		(pts
			(xy 136.614916 -278.744426) (xy 136.614916 -278.699976) (xy 136.414764 -278.699976) (xy 136.414764 -278.744426)
			(xy 136.51484 -278.844502)
		)
		(stroke
			(width 0)
			(type solid)
		)
		(fill yes)
		(layer "In13.Cu")
		(net "M_H_CPU1_SB_DQ<7>")
	)
	(gr_poly
		(pts
			(xy 136.614916 -277.528274) (xy 136.51484 -277.428198) (xy 136.414764 -277.528274) (xy 136.414764 -277.572724)
			(xy 136.614916 -277.572724)
		)
		(stroke
			(width 0)
			(type solid)
		)
		(fill yes)
		(layer "In13.Cu")
		(net "M_H_CPU1_SB_DQ<4>")
	)
	(gr_poly
		(pts
			(xy 136.614916 -277.124668) (xy 136.614916 -277.076916) (xy 136.414764 -277.076916) (xy 136.414764 -277.124668)
			(xy 136.51484 -277.22449)
		)
		(stroke
			(width 0)
			(type solid)
		)
		(fill yes)
		(layer "In13.Cu")
		(net "M_H_CPU1_SB_DQS_DP<5>")
	)
	(gr_poly
		(pts
			(xy 136.614916 -275.908008) (xy 136.51484 -275.808186) (xy 136.414764 -275.908008) (xy 136.414764 -275.95576)
			(xy 136.614916 -275.95576)
		)
		(stroke
			(width 0)
			(type solid)
		)
		(fill yes)
		(layer "In13.Cu")
		(net "M_H_CPU1_SB_DQS_DP<0>")
	)
	(gr_poly
		(pts
			(xy 136.614916 -275.504402) (xy 136.614916 -275.459952) (xy 136.414764 -275.459952) (xy 136.414764 -275.504402)
			(xy 136.51484 -275.604478)
		)
		(stroke
			(width 0)
			(type solid)
		)
		(fill yes)
		(layer "In13.Cu")
		(net "M_H_CPU1_SB_DQ<3>")
	)
	(gr_poly
		(pts
			(xy 136.614916 -274.28825) (xy 136.51484 -274.188174) (xy 136.414764 -274.28825) (xy 136.414764 -274.3327)
			(xy 136.614916 -274.3327)
		)
		(stroke
			(width 0)
			(type solid)
		)
		(fill yes)
		(layer "In13.Cu")
		(net "M_H_CPU1_SB_DQ<0>")
	)
	(gr_poly
		(pts
			(xy 136.614916 -273.88439) (xy 136.614916 -273.83994) (xy 136.414764 -273.83994) (xy 136.414764 -273.88439)
			(xy 136.51484 -273.984466)
		)
		(stroke
			(width 0)
			(type solid)
		)
		(fill yes)
		(layer "In13.Cu")
		(net "M_H_CPU1_SB_CB<3>")
	)
	(gr_poly
		(pts
			(xy 136.614916 -272.668238) (xy 136.51484 -272.568162) (xy 136.414764 -272.668238) (xy 136.414764 -272.712688)
			(xy 136.614916 -272.712688)
		)
		(stroke
			(width 0)
			(type solid)
		)
		(fill yes)
		(layer "In13.Cu")
		(net "M_H_CPU1_SB_CB<0>")
	)
	(gr_poly
		(pts
			(xy 136.614916 -272.264632) (xy 136.614916 -272.21688) (xy 136.414764 -272.21688) (xy 136.414764 -272.264632)
			(xy 136.51484 -272.364454)
		)
		(stroke
			(width 0)
			(type solid)
		)
		(fill yes)
		(layer "In13.Cu")
		(net "M_H_CPU1_SB_DQS_DP<4>")
	)
	(gr_poly
		(pts
			(xy 136.614916 -271.047972) (xy 136.51484 -270.94815) (xy 136.414764 -271.047972) (xy 136.414764 -271.095724)
			(xy 136.614916 -271.095724)
		)
		(stroke
			(width 0)
			(type solid)
		)
		(fill yes)
		(layer "In13.Cu")
		(net "M_H_CPU1_SB_DQS_DP<9>")
	)
	(gr_poly
		(pts
			(xy 136.614916 -270.644366) (xy 136.614916 -270.599916) (xy 136.414764 -270.599916) (xy 136.414764 -270.644366)
			(xy 136.51484 -270.744442)
		)
		(stroke
			(width 0)
			(type solid)
		)
		(fill yes)
		(layer "In13.Cu")
		(net "M_H_CPU1_SB_CB<7>")
	)
	(gr_poly
		(pts
			(xy 136.614916 -269.428214) (xy 136.51484 -269.328138) (xy 136.414764 -269.428214) (xy 136.414764 -269.472664)
			(xy 136.614916 -269.472664)
		)
		(stroke
			(width 0)
			(type solid)
		)
		(fill yes)
		(layer "In13.Cu")
		(net "M_H_CPU1_SB_CB<4>")
	)
	(gr_poly
		(pts
			(xy 136.614916 -267.808202) (xy 136.51484 -267.708126) (xy 136.414764 -267.808202) (xy 136.414764 -267.852652)
			(xy 136.614916 -267.852652)
		)
		(stroke
			(width 0)
			(type solid)
		)
		(fill yes)
		(layer "In13.Cu")
		(net "M_H_CPU1_SB_RSP<0>")
	)
	(gr_poly
		(pts
			(xy 136.614916 -265.78433) (xy 136.614916 -265.73988) (xy 136.414764 -265.73988) (xy 136.414764 -265.78433)
			(xy 136.51484 -265.884406)
		)
		(stroke
			(width 0)
			(type solid)
		)
		(fill yes)
		(layer "In13.Cu")
		(net "M_H_CPU1_SB_CS_N<0>")
	)
	(gr_poly
		(pts
			(xy 136.614916 -264.568178) (xy 136.51484 -264.468102) (xy 136.414764 -264.568178) (xy 136.414764 -264.612628)
			(xy 136.614916 -264.612628)
		)
		(stroke
			(width 0)
			(type solid)
		)
		(fill yes)
		(layer "In13.Cu")
		(net "M_H_CPU1_SB_CA<6>")
	)
	(gr_poly
		(pts
			(xy 136.614916 -264.164318) (xy 136.614916 -264.119868) (xy 136.414764 -264.119868) (xy 136.414764 -264.164318)
			(xy 136.51484 -264.264394)
		)
		(stroke
			(width 0)
			(type solid)
		)
		(fill yes)
		(layer "In13.Cu")
		(net "M_H_CPU1_SB_CA<5>")
	)
	(gr_poly
		(pts
			(xy 136.614916 -262.948166) (xy 136.51484 -262.84809) (xy 136.414764 -262.948166) (xy 136.414764 -262.992616)
			(xy 136.614916 -262.992616)
		)
		(stroke
			(width 0)
			(type solid)
		)
		(fill yes)
		(layer "In13.Cu")
		(net "M_H_CPU1_SB_CA<2>")
	)
	(gr_poly
		(pts
			(xy 136.614916 -262.544306) (xy 136.614916 -262.499856) (xy 136.414764 -262.499856) (xy 136.414764 -262.544306)
			(xy 136.51484 -262.644382)
		)
		(stroke
			(width 0)
			(type solid)
		)
		(fill yes)
		(layer "In13.Cu")
		(net "M_H_CPU1_SB_CA<1>")
	)
	(gr_poly
		(pts
			(xy 136.784842 -256.026158) (xy 136.684766 -255.926336) (xy 136.58469 -256.026158) (xy 136.58469 -256.07391)
			(xy 136.784842 -256.07391)
		)
		(stroke
			(width 0)
			(type solid)
		)
		(fill yes)
		(layer "In13.Cu")
		(net "M_H_CPU1_CLK_DP<0>")
	)
	(gr_poly
		(pts
			(xy 136.784842 -255.622552) (xy 136.784842 -255.578102) (xy 136.58469 -255.578102) (xy 136.58469 -255.622552)
			(xy 136.684766 -255.722628)
		)
		(stroke
			(width 0)
			(type solid)
		)
		(fill yes)
		(layer "In13.Cu")
		(net "M_H_CPU1_SA_PAR")
	)
	(gr_poly
		(pts
			(xy 136.784842 -254.4064) (xy 136.684766 -254.306324) (xy 136.58469 -254.4064) (xy 136.58469 -254.45085)
			(xy 136.784842 -254.45085)
		)
		(stroke
			(width 0)
			(type solid)
		)
		(fill yes)
		(layer "In13.Cu")
		(net "M_H_CPU1_SA_CA<4>")
	)
	(gr_poly
		(pts
			(xy 136.784842 -254.00254) (xy 136.784842 -253.95809) (xy 136.58469 -253.95809) (xy 136.58469 -254.00254)
			(xy 136.684766 -254.102616)
		)
		(stroke
			(width 0)
			(type solid)
		)
		(fill yes)
		(layer "In13.Cu")
		(net "M_H_CPU1_SA_CA<3>")
	)
	(gr_poly
		(pts
			(xy 136.784842 -252.786388) (xy 136.684766 -252.686312) (xy 136.58469 -252.786388) (xy 136.58469 -252.830838)
			(xy 136.784842 -252.830838)
		)
		(stroke
			(width 0)
			(type solid)
		)
		(fill yes)
		(layer "In13.Cu")
		(net "M_H_CPU1_SA_CA<0>")
	)
	(gr_poly
		(pts
			(xy 136.784842 -251.166376) (xy 136.684766 -251.0663) (xy 136.58469 -251.166376) (xy 136.58469 -251.210826)
			(xy 136.784842 -251.210826)
		)
		(stroke
			(width 0)
			(type solid)
		)
		(fill yes)
		(layer "In13.Cu")
		(net "M_H_CPU1_SA_CS_N<0>")
	)
	(gr_poly
		(pts
			(xy 136.784842 -250.762516) (xy 136.784842 -250.718066) (xy 136.58469 -250.718066) (xy 136.58469 -250.762516)
			(xy 136.684766 -250.862592)
		)
		(stroke
			(width 0)
			(type solid)
		)
		(fill yes)
		(layer "In13.Cu")
		(net "M_H_CPU1_RESET_N")
	)
	(gr_poly
		(pts
			(xy 136.784842 -249.142504) (xy 136.784842 -249.098054) (xy 136.58469 -249.098054) (xy 136.58469 -249.142504)
			(xy 136.684766 -249.24258)
		)
		(stroke
			(width 0)
			(type solid)
		)
		(fill yes)
		(layer "In13.Cu")
		(net "M_H_CPU1_SA_CB<7>")
	)
	(gr_poly
		(pts
			(xy 136.784842 -247.926352) (xy 136.684766 -247.826276) (xy 136.58469 -247.926352) (xy 136.58469 -247.970802)
			(xy 136.784842 -247.970802)
		)
		(stroke
			(width 0)
			(type solid)
		)
		(fill yes)
		(layer "In13.Cu")
		(net "M_H_CPU1_SA_CB<4>")
	)
	(gr_poly
		(pts
			(xy 136.784842 -247.522746) (xy 136.784842 -247.474994) (xy 136.58469 -247.474994) (xy 136.58469 -247.522746)
			(xy 136.684766 -247.622568)
		)
		(stroke
			(width 0)
			(type solid)
		)
		(fill yes)
		(layer "In13.Cu")
		(net "M_H_CPU1_SA_DQS_DP<9>")
	)
	(gr_poly
		(pts
			(xy 136.784842 -246.306086) (xy 136.684766 -246.206264) (xy 136.58469 -246.306086) (xy 136.58469 -246.353838)
			(xy 136.784842 -246.353838)
		)
		(stroke
			(width 0)
			(type solid)
		)
		(fill yes)
		(layer "In13.Cu")
		(net "M_H_CPU1_SA_DQS_DP<4>")
	)
	(gr_poly
		(pts
			(xy 136.784842 -245.90248) (xy 136.784842 -245.85803) (xy 136.58469 -245.85803) (xy 136.58469 -245.90248)
			(xy 136.684766 -246.002556)
		)
		(stroke
			(width 0)
			(type solid)
		)
		(fill yes)
		(layer "In13.Cu")
		(net "M_H_CPU1_SA_CB<3>")
	)
	(gr_poly
		(pts
			(xy 136.784842 -244.686328) (xy 136.684766 -244.586252) (xy 136.58469 -244.686328) (xy 136.58469 -244.730778)
			(xy 136.784842 -244.730778)
		)
		(stroke
			(width 0)
			(type solid)
		)
		(fill yes)
		(layer "In13.Cu")
		(net "M_H_CPU1_SA_CB<0>")
	)
	(gr_poly
		(pts
			(xy 136.784842 -244.282468) (xy 136.784842 -244.238018) (xy 136.58469 -244.238018) (xy 136.58469 -244.282468)
			(xy 136.684766 -244.382544)
		)
		(stroke
			(width 0)
			(type solid)
		)
		(fill yes)
		(layer "In13.Cu")
		(net "M_H_CPU1_SA_DQ<31>")
	)
	(gr_poly
		(pts
			(xy 136.784842 -243.066316) (xy 136.684766 -242.96624) (xy 136.58469 -243.066316) (xy 136.58469 -243.110766)
			(xy 136.784842 -243.110766)
		)
		(stroke
			(width 0)
			(type solid)
		)
		(fill yes)
		(layer "In13.Cu")
		(net "M_H_CPU1_SA_DQ<28>")
	)
	(gr_poly
		(pts
			(xy 136.784842 -242.66271) (xy 136.784842 -242.614958) (xy 136.58469 -242.614958) (xy 136.58469 -242.66271)
			(xy 136.684766 -242.762532)
		)
		(stroke
			(width 0)
			(type solid)
		)
		(fill yes)
		(layer "In13.Cu")
		(net "M_H_CPU1_SA_DQS_DP<8>")
	)
	(gr_poly
		(pts
			(xy 136.784842 -241.44605) (xy 136.684766 -241.346228) (xy 136.58469 -241.44605) (xy 136.58469 -241.493802)
			(xy 136.784842 -241.493802)
		)
		(stroke
			(width 0)
			(type solid)
		)
		(fill yes)
		(layer "In13.Cu")
		(net "M_H_CPU1_SA_DQS_DP<3>")
	)
	(gr_poly
		(pts
			(xy 136.784842 -241.042444) (xy 136.784842 -240.997994) (xy 136.58469 -240.997994) (xy 136.58469 -241.042444)
			(xy 136.684766 -241.14252)
		)
		(stroke
			(width 0)
			(type solid)
		)
		(fill yes)
		(layer "In13.Cu")
		(net "M_H_CPU1_SA_DQ<27>")
	)
	(gr_poly
		(pts
			(xy 136.784842 -239.826292) (xy 136.684766 -239.726216) (xy 136.58469 -239.826292) (xy 136.58469 -239.870742)
			(xy 136.784842 -239.870742)
		)
		(stroke
			(width 0)
			(type solid)
		)
		(fill yes)
		(layer "In13.Cu")
		(net "M_H_CPU1_SA_DQ<24>")
	)
	(gr_poly
		(pts
			(xy 136.784842 -239.422432) (xy 136.784842 -239.377982) (xy 136.58469 -239.377982) (xy 136.58469 -239.422432)
			(xy 136.684766 -239.522508)
		)
		(stroke
			(width 0)
			(type solid)
		)
		(fill yes)
		(layer "In13.Cu")
		(net "M_H_CPU1_SA_DQ<23>")
	)
	(gr_poly
		(pts
			(xy 136.784842 -238.20628) (xy 136.684766 -238.106204) (xy 136.58469 -238.20628) (xy 136.58469 -238.25073)
			(xy 136.784842 -238.25073)
		)
		(stroke
			(width 0)
			(type solid)
		)
		(fill yes)
		(layer "In13.Cu")
		(net "M_H_CPU1_SA_DQ<20>")
	)
	(gr_poly
		(pts
			(xy 136.784842 -237.802674) (xy 136.784842 -237.754922) (xy 136.58469 -237.754922) (xy 136.58469 -237.802674)
			(xy 136.684766 -237.902496)
		)
		(stroke
			(width 0)
			(type solid)
		)
		(fill yes)
		(layer "In13.Cu")
		(net "M_H_CPU1_SA_DQS_DP<7>")
	)
	(gr_poly
		(pts
			(xy 136.784842 -236.586014) (xy 136.684766 -236.486192) (xy 136.58469 -236.586014) (xy 136.58469 -236.633766)
			(xy 136.784842 -236.633766)
		)
		(stroke
			(width 0)
			(type solid)
		)
		(fill yes)
		(layer "In13.Cu")
		(net "M_H_CPU1_SA_DQS_DP<2>")
	)
	(gr_poly
		(pts
			(xy 136.784842 -236.182408) (xy 136.784842 -236.137958) (xy 136.58469 -236.137958) (xy 136.58469 -236.182408)
			(xy 136.684766 -236.282484)
		)
		(stroke
			(width 0)
			(type solid)
		)
		(fill yes)
		(layer "In13.Cu")
		(net "M_H_CPU1_SA_DQ<19>")
	)
	(gr_poly
		(pts
			(xy 136.784842 -234.966256) (xy 136.684766 -234.86618) (xy 136.58469 -234.966256) (xy 136.58469 -235.010706)
			(xy 136.784842 -235.010706)
		)
		(stroke
			(width 0)
			(type solid)
		)
		(fill yes)
		(layer "In13.Cu")
		(net "M_H_CPU1_SA_DQ<16>")
	)
	(gr_poly
		(pts
			(xy 136.784842 -234.562396) (xy 136.784842 -234.517946) (xy 136.58469 -234.517946) (xy 136.58469 -234.562396)
			(xy 136.684766 -234.662472)
		)
		(stroke
			(width 0)
			(type solid)
		)
		(fill yes)
		(layer "In13.Cu")
		(net "M_H_CPU1_SA_DQ<15>")
	)
	(gr_poly
		(pts
			(xy 136.784842 -233.346244) (xy 136.684766 -233.246168) (xy 136.58469 -233.346244) (xy 136.58469 -233.390694)
			(xy 136.784842 -233.390694)
		)
		(stroke
			(width 0)
			(type solid)
		)
		(fill yes)
		(layer "In13.Cu")
		(net "M_H_CPU1_SA_DQ<12>")
	)
	(gr_poly
		(pts
			(xy 136.784842 -232.942638) (xy 136.784842 -232.894886) (xy 136.58469 -232.894886) (xy 136.58469 -232.942638)
			(xy 136.684766 -233.04246)
		)
		(stroke
			(width 0)
			(type solid)
		)
		(fill yes)
		(layer "In13.Cu")
		(net "M_H_CPU1_SA_DQS_DP<6>")
	)
	(gr_poly
		(pts
			(xy 136.784842 -231.725978) (xy 136.684766 -231.626156) (xy 136.58469 -231.725978) (xy 136.58469 -231.77373)
			(xy 136.784842 -231.77373)
		)
		(stroke
			(width 0)
			(type solid)
		)
		(fill yes)
		(layer "In13.Cu")
		(net "M_H_CPU1_SA_DQS_DP<1>")
	)
	(gr_poly
		(pts
			(xy 136.784842 -231.322626) (xy 136.784842 -231.278176) (xy 136.58469 -231.278176) (xy 136.58469 -231.322626)
			(xy 136.684766 -231.422702)
		)
		(stroke
			(width 0)
			(type solid)
		)
		(fill yes)
		(layer "In13.Cu")
		(net "M_H_CPU1_SA_DQ<11>")
	)
	(gr_poly
		(pts
			(xy 136.784842 -230.10622) (xy 136.684766 -230.006144) (xy 136.58469 -230.10622) (xy 136.58469 -230.15067)
			(xy 136.784842 -230.15067)
		)
		(stroke
			(width 0)
			(type solid)
		)
		(fill yes)
		(layer "In13.Cu")
		(net "M_H_CPU1_SA_DQ<8>")
	)
	(gr_poly
		(pts
			(xy 136.784842 -229.702614) (xy 136.784842 -229.658164) (xy 136.58469 -229.658164) (xy 136.58469 -229.702614)
			(xy 136.684766 -229.80269)
		)
		(stroke
			(width 0)
			(type solid)
		)
		(fill yes)
		(layer "In13.Cu")
		(net "M_H_CPU1_SA_DQ<7>")
	)
	(gr_poly
		(pts
			(xy 136.784842 -228.486462) (xy 136.684766 -228.386386) (xy 136.58469 -228.486462) (xy 136.58469 -228.530912)
			(xy 136.784842 -228.530912)
		)
		(stroke
			(width 0)
			(type solid)
		)
		(fill yes)
		(layer "In13.Cu")
		(net "M_H_CPU1_SA_DQ<4>")
	)
	(gr_poly
		(pts
			(xy 136.784842 -228.082856) (xy 136.784842 -228.035104) (xy 136.58469 -228.035104) (xy 136.58469 -228.082856)
			(xy 136.684766 -228.182678)
		)
		(stroke
			(width 0)
			(type solid)
		)
		(fill yes)
		(layer "In13.Cu")
		(net "M_H_CPU1_SA_DQS_DP<5>")
	)
	(gr_poly
		(pts
			(xy 136.784842 -226.866196) (xy 136.684766 -226.766374) (xy 136.58469 -226.866196) (xy 136.58469 -226.913948)
			(xy 136.784842 -226.913948)
		)
		(stroke
			(width 0)
			(type solid)
		)
		(fill yes)
		(layer "In13.Cu")
		(net "M_H_CPU1_SA_DQS_DP<0>")
	)
	(gr_poly
		(pts
			(xy 136.784842 -226.46259) (xy 136.784842 -226.41814) (xy 136.58469 -226.41814) (xy 136.58469 -226.46259)
			(xy 136.684766 -226.562666)
		)
		(stroke
			(width 0)
			(type solid)
		)
		(fill yes)
		(layer "In13.Cu")
		(net "M_H_CPU1_SA_DQ<3>")
	)
	(gr_poly
		(pts
			(xy 136.784842 -225.246438) (xy 136.684766 -225.146362) (xy 136.58469 -225.246438) (xy 136.58469 -225.290888)
			(xy 136.784842 -225.290888)
		)
		(stroke
			(width 0)
			(type solid)
		)
		(fill yes)
		(layer "In13.Cu")
		(net "M_H_CPU1_SA_DQ<0>")
	)
	(gr_poly
		(pts
			(xy 137.084816 -292.918134) (xy 136.98474 -292.818058) (xy 136.884664 -292.918134) (xy 136.884664 -292.962584)
			(xy 137.084816 -292.962584)
		)
		(stroke
			(width 0)
			(type solid)
		)
		(fill yes)
		(layer "In13.Cu")
		(net "M_H_CPU1_SB_DQ<29>")
	)
	(gr_poly
		(pts
			(xy 137.084816 -292.514274) (xy 137.084816 -292.469824) (xy 136.884664 -292.469824) (xy 136.884664 -292.514274)
			(xy 136.98474 -292.61435)
		)
		(stroke
			(width 0)
			(type solid)
		)
		(fill yes)
		(layer "In13.Cu")
		(net "M_H_CPU1_SB_DQ<30>")
	)
	(gr_poly
		(pts
			(xy 137.084816 -291.297868) (xy 136.98474 -291.198046) (xy 136.884664 -291.297868) (xy 136.884664 -291.34562)
			(xy 137.084816 -291.34562)
		)
		(stroke
			(width 0)
			(type solid)
		)
		(fill yes)
		(layer "In13.Cu")
		(net "M_H_CPU1_SB_DQS_DN<8>")
	)
	(gr_poly
		(pts
			(xy 137.084816 -290.894516) (xy 137.084816 -290.846764) (xy 136.884664 -290.846764) (xy 136.884664 -290.894516)
			(xy 136.98474 -290.994338)
		)
		(stroke
			(width 0)
			(type solid)
		)
		(fill yes)
		(layer "In13.Cu")
		(net "M_H_CPU1_SB_DQS_DN<3>")
	)
	(gr_poly
		(pts
			(xy 137.084816 -289.67811) (xy 136.98474 -289.578034) (xy 136.884664 -289.67811) (xy 136.884664 -289.72256)
			(xy 137.084816 -289.72256)
		)
		(stroke
			(width 0)
			(type solid)
		)
		(fill yes)
		(layer "In13.Cu")
		(net "M_H_CPU1_SB_DQ<25>")
	)
	(gr_poly
		(pts
			(xy 137.084816 -289.27425) (xy 137.084816 -289.2298) (xy 136.884664 -289.2298) (xy 136.884664 -289.27425)
			(xy 136.98474 -289.374326)
		)
		(stroke
			(width 0)
			(type solid)
		)
		(fill yes)
		(layer "In13.Cu")
		(net "M_H_CPU1_SB_DQ<26>")
	)
	(gr_poly
		(pts
			(xy 137.084816 -288.058098) (xy 136.98474 -287.958022) (xy 136.884664 -288.058098) (xy 136.884664 -288.102548)
			(xy 137.084816 -288.102548)
		)
		(stroke
			(width 0)
			(type solid)
		)
		(fill yes)
		(layer "In13.Cu")
		(net "M_H_CPU1_SB_DQ<21>")
	)
	(gr_poly
		(pts
			(xy 137.084816 -287.654492) (xy 137.084816 -287.610042) (xy 136.884664 -287.610042) (xy 136.884664 -287.654492)
			(xy 136.98474 -287.754568)
		)
		(stroke
			(width 0)
			(type solid)
		)
		(fill yes)
		(layer "In13.Cu")
		(net "M_H_CPU1_SB_DQ<22>")
	)
	(gr_poly
		(pts
			(xy 137.084816 -286.438086) (xy 136.98474 -286.33801) (xy 136.884664 -286.438086) (xy 136.884664 -286.485838)
			(xy 137.084816 -286.485838)
		)
		(stroke
			(width 0)
			(type solid)
		)
		(fill yes)
		(layer "In13.Cu")
		(net "M_H_CPU1_SB_DQS_DN<7>")
	)
	(gr_poly
		(pts
			(xy 137.084816 -286.034734) (xy 137.084816 -285.986982) (xy 136.884664 -285.986982) (xy 136.884664 -286.034734)
			(xy 136.98474 -286.134556)
		)
		(stroke
			(width 0)
			(type solid)
		)
		(fill yes)
		(layer "In13.Cu")
		(net "M_H_CPU1_SB_DQS_DN<2>")
	)
	(gr_poly
		(pts
			(xy 137.084816 -284.818328) (xy 136.98474 -284.718252) (xy 136.884664 -284.818328) (xy 136.884664 -284.862778)
			(xy 137.084816 -284.862778)
		)
		(stroke
			(width 0)
			(type solid)
		)
		(fill yes)
		(layer "In13.Cu")
		(net "M_H_CPU1_SB_DQ<17>")
	)
	(gr_poly
		(pts
			(xy 137.084816 -284.414468) (xy 137.084816 -284.370018) (xy 136.884664 -284.370018) (xy 136.884664 -284.414468)
			(xy 136.98474 -284.514544)
		)
		(stroke
			(width 0)
			(type solid)
		)
		(fill yes)
		(layer "In13.Cu")
		(net "M_H_CPU1_SB_DQ<18>")
	)
	(gr_poly
		(pts
			(xy 137.084816 -283.198316) (xy 136.98474 -283.09824) (xy 136.884664 -283.198316) (xy 136.884664 -283.242766)
			(xy 137.084816 -283.242766)
		)
		(stroke
			(width 0)
			(type solid)
		)
		(fill yes)
		(layer "In13.Cu")
		(net "M_H_CPU1_SB_DQ<13>")
	)
	(gr_poly
		(pts
			(xy 137.084816 -282.794456) (xy 137.084816 -282.750006) (xy 136.884664 -282.750006) (xy 136.884664 -282.794456)
			(xy 136.98474 -282.894532)
		)
		(stroke
			(width 0)
			(type solid)
		)
		(fill yes)
		(layer "In13.Cu")
		(net "M_H_CPU1_SB_DQ<14>")
	)
	(gr_poly
		(pts
			(xy 137.084816 -281.57805) (xy 136.98474 -281.478228) (xy 136.884664 -281.57805) (xy 136.884664 -281.625802)
			(xy 137.084816 -281.625802)
		)
		(stroke
			(width 0)
			(type solid)
		)
		(fill yes)
		(layer "In13.Cu")
		(net "M_H_CPU1_SB_DQS_DN<6>")
	)
	(gr_poly
		(pts
			(xy 137.084816 -281.174698) (xy 137.084816 -281.126946) (xy 136.884664 -281.126946) (xy 136.884664 -281.174698)
			(xy 136.98474 -281.27452)
		)
		(stroke
			(width 0)
			(type solid)
		)
		(fill yes)
		(layer "In13.Cu")
		(net "M_H_CPU1_SB_DQS_DN<1>")
	)
	(gr_poly
		(pts
			(xy 137.084816 -279.958292) (xy 136.98474 -279.858216) (xy 136.884664 -279.958292) (xy 136.884664 -280.002742)
			(xy 137.084816 -280.002742)
		)
		(stroke
			(width 0)
			(type solid)
		)
		(fill yes)
		(layer "In13.Cu")
		(net "M_H_CPU1_SB_DQ<9>")
	)
	(gr_poly
		(pts
			(xy 137.084816 -279.554432) (xy 137.084816 -279.509982) (xy 136.884664 -279.509982) (xy 136.884664 -279.554432)
			(xy 136.98474 -279.654508)
		)
		(stroke
			(width 0)
			(type solid)
		)
		(fill yes)
		(layer "In13.Cu")
		(net "M_H_CPU1_SB_DQ<10>")
	)
	(gr_poly
		(pts
			(xy 137.084816 -278.33828) (xy 136.98474 -278.238204) (xy 136.884664 -278.33828) (xy 136.884664 -278.38273)
			(xy 137.084816 -278.38273)
		)
		(stroke
			(width 0)
			(type solid)
		)
		(fill yes)
		(layer "In13.Cu")
		(net "M_H_CPU1_SB_DQ<5>")
	)
	(gr_poly
		(pts
			(xy 137.084816 -277.93442) (xy 137.084816 -277.88997) (xy 136.884664 -277.88997) (xy 136.884664 -277.93442)
			(xy 136.98474 -278.034496)
		)
		(stroke
			(width 0)
			(type solid)
		)
		(fill yes)
		(layer "In13.Cu")
		(net "M_H_CPU1_SB_DQ<6>")
	)
	(gr_poly
		(pts
			(xy 137.084816 -276.718014) (xy 136.98474 -276.618192) (xy 136.884664 -276.718014) (xy 136.884664 -276.765766)
			(xy 137.084816 -276.765766)
		)
		(stroke
			(width 0)
			(type solid)
		)
		(fill yes)
		(layer "In13.Cu")
		(net "M_H_CPU1_SB_DQS_DN<5>")
	)
	(gr_poly
		(pts
			(xy 137.084816 -276.314662) (xy 137.084816 -276.26691) (xy 136.884664 -276.26691) (xy 136.884664 -276.314662)
			(xy 136.98474 -276.414484)
		)
		(stroke
			(width 0)
			(type solid)
		)
		(fill yes)
		(layer "In13.Cu")
		(net "M_H_CPU1_SB_DQS_DN<0>")
	)
	(gr_poly
		(pts
			(xy 137.084816 -275.098256) (xy 136.98474 -274.99818) (xy 136.884664 -275.098256) (xy 136.884664 -275.142706)
			(xy 137.084816 -275.142706)
		)
		(stroke
			(width 0)
			(type solid)
		)
		(fill yes)
		(layer "In13.Cu")
		(net "M_H_CPU1_SB_DQ<1>")
	)
	(gr_poly
		(pts
			(xy 137.084816 -274.694396) (xy 137.084816 -274.649946) (xy 136.884664 -274.649946) (xy 136.884664 -274.694396)
			(xy 136.98474 -274.794472)
		)
		(stroke
			(width 0)
			(type solid)
		)
		(fill yes)
		(layer "In13.Cu")
		(net "M_H_CPU1_SB_DQ<2>")
	)
	(gr_poly
		(pts
			(xy 137.084816 -273.478244) (xy 136.98474 -273.378168) (xy 136.884664 -273.478244) (xy 136.884664 -273.522694)
			(xy 137.084816 -273.522694)
		)
		(stroke
			(width 0)
			(type solid)
		)
		(fill yes)
		(layer "In13.Cu")
		(net "M_H_CPU1_SB_CB<1>")
	)
	(gr_poly
		(pts
			(xy 137.084816 -273.074384) (xy 137.084816 -273.029934) (xy 136.884664 -273.029934) (xy 136.884664 -273.074384)
			(xy 136.98474 -273.17446)
		)
		(stroke
			(width 0)
			(type solid)
		)
		(fill yes)
		(layer "In13.Cu")
		(net "M_H_CPU1_SB_CB<2>")
	)
	(gr_poly
		(pts
			(xy 137.084816 -271.857978) (xy 136.98474 -271.758156) (xy 136.884664 -271.857978) (xy 136.884664 -271.90573)
			(xy 137.084816 -271.90573)
		)
		(stroke
			(width 0)
			(type solid)
		)
		(fill yes)
		(layer "In13.Cu")
		(net "M_H_CPU1_SB_DQS_DN<4>")
	)
	(gr_poly
		(pts
			(xy 137.084816 -271.454626) (xy 137.084816 -271.406874) (xy 136.884664 -271.406874) (xy 136.884664 -271.454626)
			(xy 136.98474 -271.554448)
		)
		(stroke
			(width 0)
			(type solid)
		)
		(fill yes)
		(layer "In13.Cu")
		(net "M_H_CPU1_SB_DQS_DN<9>")
	)
	(gr_poly
		(pts
			(xy 137.084816 -270.23822) (xy 136.98474 -270.138144) (xy 136.884664 -270.23822) (xy 136.884664 -270.28267)
			(xy 137.084816 -270.28267)
		)
		(stroke
			(width 0)
			(type solid)
		)
		(fill yes)
		(layer "In13.Cu")
		(net "M_H_CPU1_SB_CB<5>")
	)
	(gr_poly
		(pts
			(xy 137.084816 -269.83436) (xy 137.084816 -269.78991) (xy 136.884664 -269.78991) (xy 136.884664 -269.83436)
			(xy 136.98474 -269.934436)
		)
		(stroke
			(width 0)
			(type solid)
		)
		(fill yes)
		(layer "In13.Cu")
		(net "M_H_CPU1_SB_CB<6>")
	)
	(gr_poly
		(pts
			(xy 137.084816 -266.998196) (xy 136.98474 -266.89812) (xy 136.884664 -266.998196) (xy 136.884664 -267.042646)
			(xy 137.084816 -267.042646)
		)
		(stroke
			(width 0)
			(type solid)
		)
		(fill yes)
		(layer "In13.Cu")
		(net "M_H_CPU1_SA_RSP<0>")
	)
	(gr_poly
		(pts
			(xy 137.084816 -266.594336) (xy 137.084816 -266.549886) (xy 136.884664 -266.549886) (xy 136.884664 -266.594336)
			(xy 136.98474 -266.694412)
		)
		(stroke
			(width 0)
			(type solid)
		)
		(fill yes)
		(layer "In13.Cu")
		(net "M_H_CPU1_SB_CS_N<1>")
	)
	(gr_poly
		(pts
			(xy 137.084816 -265.378184) (xy 136.98474 -265.278108) (xy 136.884664 -265.378184) (xy 136.884664 -265.422634)
			(xy 137.084816 -265.422634)
		)
		(stroke
			(width 0)
			(type solid)
		)
		(fill yes)
		(layer "In13.Cu")
		(net "M_H_CPU1_SB_PAR")
	)
	(gr_poly
		(pts
			(xy 137.084816 -263.758172) (xy 136.98474 -263.658096) (xy 136.884664 -263.758172) (xy 136.884664 -263.802622)
			(xy 137.084816 -263.802622)
		)
		(stroke
			(width 0)
			(type solid)
		)
		(fill yes)
		(layer "In13.Cu")
		(net "M_H_CPU1_SB_CA<4>")
	)
	(gr_poly
		(pts
			(xy 137.084816 -263.354312) (xy 137.084816 -263.309862) (xy 136.884664 -263.309862) (xy 136.884664 -263.354312)
			(xy 136.98474 -263.454388)
		)
		(stroke
			(width 0)
			(type solid)
		)
		(fill yes)
		(layer "In13.Cu")
		(net "M_H_CPU1_SB_CA<3>")
	)
	(gr_poly
		(pts
			(xy 137.084816 -262.13816) (xy 136.98474 -262.038084) (xy 136.884664 -262.13816) (xy 136.884664 -262.18261)
			(xy 137.084816 -262.18261)
		)
		(stroke
			(width 0)
			(type solid)
		)
		(fill yes)
		(layer "In13.Cu")
		(net "M_H_CPU1_SB_CA<0>")
	)
	(gr_poly
		(pts
			(xy 137.254742 -256.432812) (xy 137.254742 -256.38506) (xy 137.05459 -256.38506) (xy 137.05459 -256.432812)
			(xy 137.154666 -256.532634)
		)
		(stroke
			(width 0)
			(type solid)
		)
		(fill yes)
		(layer "In13.Cu")
		(net "M_H_CPU1_CLK_DN<0>")
	)
	(gr_poly
		(pts
			(xy 137.254742 -255.216406) (xy 137.154666 -255.11633) (xy 137.05459 -255.216406) (xy 137.05459 -255.260856)
			(xy 137.254742 -255.260856)
		)
		(stroke
			(width 0)
			(type solid)
		)
		(fill yes)
		(layer "In13.Cu")
		(net "M_H_CPU1_SA_CA<6>")
	)
	(gr_poly
		(pts
			(xy 137.254742 -254.812546) (xy 137.254742 -254.768096) (xy 137.05459 -254.768096) (xy 137.05459 -254.812546)
			(xy 137.154666 -254.912622)
		)
		(stroke
			(width 0)
			(type solid)
		)
		(fill yes)
		(layer "In13.Cu")
		(net "M_H_CPU1_SA_CA<5>")
	)
	(gr_poly
		(pts
			(xy 137.254742 -253.596394) (xy 137.154666 -253.496318) (xy 137.05459 -253.596394) (xy 137.05459 -253.640844)
			(xy 137.254742 -253.640844)
		)
		(stroke
			(width 0)
			(type solid)
		)
		(fill yes)
		(layer "In13.Cu")
		(net "M_H_CPU1_SA_CA<2>")
	)
	(gr_poly
		(pts
			(xy 137.254742 -253.192534) (xy 137.254742 -253.148084) (xy 137.05459 -253.148084) (xy 137.05459 -253.192534)
			(xy 137.154666 -253.29261)
		)
		(stroke
			(width 0)
			(type solid)
		)
		(fill yes)
		(layer "In13.Cu")
		(net "M_H_CPU1_SA_CA<1>")
	)
	(gr_poly
		(pts
			(xy 137.254742 -251.976382) (xy 137.154666 -251.876306) (xy 137.05459 -251.976382) (xy 137.05459 -252.020832)
			(xy 137.254742 -252.020832)
		)
		(stroke
			(width 0)
			(type solid)
		)
		(fill yes)
		(layer "In13.Cu")
		(net "M_H_CPU1_SA_CS_N<1>")
	)
	(gr_poly
		(pts
			(xy 137.254742 -250.35637) (xy 137.154666 -250.256294) (xy 137.05459 -250.35637) (xy 137.05459 -250.40082)
			(xy 137.254742 -250.40082)
		)
		(stroke
			(width 0)
			(type solid)
		)
		(fill yes)
		(layer "In13.Cu")
		(net "M_H_CPU1_ALERT_R_N")
	)
	(gr_poly
		(pts
			(xy 137.254742 -248.736358) (xy 137.154666 -248.636282) (xy 137.05459 -248.736358) (xy 137.05459 -248.780808)
			(xy 137.254742 -248.780808)
		)
		(stroke
			(width 0)
			(type solid)
		)
		(fill yes)
		(layer "In13.Cu")
		(net "M_H_CPU1_SA_CB<5>")
	)
	(gr_poly
		(pts
			(xy 137.254742 -248.332498) (xy 137.254742 -248.288048) (xy 137.05459 -248.288048) (xy 137.05459 -248.332498)
			(xy 137.154666 -248.432574)
		)
		(stroke
			(width 0)
			(type solid)
		)
		(fill yes)
		(layer "In13.Cu")
		(net "M_H_CPU1_SA_CB<6>")
	)
	(gr_poly
		(pts
			(xy 137.254742 -247.116092) (xy 137.154666 -247.01627) (xy 137.05459 -247.116092) (xy 137.05459 -247.163844)
			(xy 137.254742 -247.163844)
		)
		(stroke
			(width 0)
			(type solid)
		)
		(fill yes)
		(layer "In13.Cu")
		(net "M_H_CPU1_SA_DQS_DN<9>")
	)
	(gr_poly
		(pts
			(xy 137.254742 -246.71274) (xy 137.254742 -246.664988) (xy 137.05459 -246.664988) (xy 137.05459 -246.71274)
			(xy 137.154666 -246.812562)
		)
		(stroke
			(width 0)
			(type solid)
		)
		(fill yes)
		(layer "In13.Cu")
		(net "M_H_CPU1_SA_DQS_DN<4>")
	)
	(gr_poly
		(pts
			(xy 137.254742 -245.496334) (xy 137.154666 -245.396258) (xy 137.05459 -245.496334) (xy 137.05459 -245.540784)
			(xy 137.254742 -245.540784)
		)
		(stroke
			(width 0)
			(type solid)
		)
		(fill yes)
		(layer "In13.Cu")
		(net "M_H_CPU1_SA_CB<1>")
	)
	(gr_poly
		(pts
			(xy 137.254742 -245.092474) (xy 137.254742 -245.048024) (xy 137.05459 -245.048024) (xy 137.05459 -245.092474)
			(xy 137.154666 -245.19255)
		)
		(stroke
			(width 0)
			(type solid)
		)
		(fill yes)
		(layer "In13.Cu")
		(net "M_H_CPU1_SA_CB<2>")
	)
	(gr_poly
		(pts
			(xy 137.254742 -243.876322) (xy 137.154666 -243.776246) (xy 137.05459 -243.876322) (xy 137.05459 -243.920772)
			(xy 137.254742 -243.920772)
		)
		(stroke
			(width 0)
			(type solid)
		)
		(fill yes)
		(layer "In13.Cu")
		(net "M_H_CPU1_SA_DQ<29>")
	)
	(gr_poly
		(pts
			(xy 137.254742 -243.472462) (xy 137.254742 -243.428012) (xy 137.05459 -243.428012) (xy 137.05459 -243.472462)
			(xy 137.154666 -243.572538)
		)
		(stroke
			(width 0)
			(type solid)
		)
		(fill yes)
		(layer "In13.Cu")
		(net "M_H_CPU1_SA_DQ<30>")
	)
	(gr_poly
		(pts
			(xy 137.254742 -242.256056) (xy 137.154666 -242.156234) (xy 137.05459 -242.256056) (xy 137.05459 -242.303808)
			(xy 137.254742 -242.303808)
		)
		(stroke
			(width 0)
			(type solid)
		)
		(fill yes)
		(layer "In13.Cu")
		(net "M_H_CPU1_SA_DQS_DN<8>")
	)
	(gr_poly
		(pts
			(xy 137.254742 -241.852704) (xy 137.254742 -241.804952) (xy 137.05459 -241.804952) (xy 137.05459 -241.852704)
			(xy 137.154666 -241.952526)
		)
		(stroke
			(width 0)
			(type solid)
		)
		(fill yes)
		(layer "In13.Cu")
		(net "M_H_CPU1_SA_DQS_DN<3>")
	)
	(gr_poly
		(pts
			(xy 137.254742 -240.636298) (xy 137.154666 -240.536222) (xy 137.05459 -240.636298) (xy 137.05459 -240.680748)
			(xy 137.254742 -240.680748)
		)
		(stroke
			(width 0)
			(type solid)
		)
		(fill yes)
		(layer "In13.Cu")
		(net "M_H_CPU1_SA_DQ<25>")
	)
	(gr_poly
		(pts
			(xy 137.254742 -240.232438) (xy 137.254742 -240.187988) (xy 137.05459 -240.187988) (xy 137.05459 -240.232438)
			(xy 137.154666 -240.332514)
		)
		(stroke
			(width 0)
			(type solid)
		)
		(fill yes)
		(layer "In13.Cu")
		(net "M_H_CPU1_SA_DQ<26>")
	)
	(gr_poly
		(pts
			(xy 137.254742 -239.016286) (xy 137.154666 -238.91621) (xy 137.05459 -239.016286) (xy 137.05459 -239.060736)
			(xy 137.254742 -239.060736)
		)
		(stroke
			(width 0)
			(type solid)
		)
		(fill yes)
		(layer "In13.Cu")
		(net "M_H_CPU1_SA_DQ<21>")
	)
	(gr_poly
		(pts
			(xy 137.254742 -238.612426) (xy 137.254742 -238.567976) (xy 137.05459 -238.567976) (xy 137.05459 -238.612426)
			(xy 137.154666 -238.712502)
		)
		(stroke
			(width 0)
			(type solid)
		)
		(fill yes)
		(layer "In13.Cu")
		(net "M_H_CPU1_SA_DQ<22>")
	)
	(gr_poly
		(pts
			(xy 137.254742 -237.39602) (xy 137.154666 -237.296198) (xy 137.05459 -237.39602) (xy 137.05459 -237.443772)
			(xy 137.254742 -237.443772)
		)
		(stroke
			(width 0)
			(type solid)
		)
		(fill yes)
		(layer "In13.Cu")
		(net "M_H_CPU1_SA_DQS_DN<7>")
	)
	(gr_poly
		(pts
			(xy 137.254742 -236.992668) (xy 137.254742 -236.944916) (xy 137.05459 -236.944916) (xy 137.05459 -236.992668)
			(xy 137.154666 -237.09249)
		)
		(stroke
			(width 0)
			(type solid)
		)
		(fill yes)
		(layer "In13.Cu")
		(net "M_H_CPU1_SA_DQS_DN<2>")
	)
	(gr_poly
		(pts
			(xy 137.254742 -235.776262) (xy 137.154666 -235.676186) (xy 137.05459 -235.776262) (xy 137.05459 -235.820712)
			(xy 137.254742 -235.820712)
		)
		(stroke
			(width 0)
			(type solid)
		)
		(fill yes)
		(layer "In13.Cu")
		(net "M_H_CPU1_SA_DQ<17>")
	)
	(gr_poly
		(pts
			(xy 137.254742 -235.372402) (xy 137.254742 -235.327952) (xy 137.05459 -235.327952) (xy 137.05459 -235.372402)
			(xy 137.154666 -235.472478)
		)
		(stroke
			(width 0)
			(type solid)
		)
		(fill yes)
		(layer "In13.Cu")
		(net "M_H_CPU1_SA_DQ<18>")
	)
	(gr_poly
		(pts
			(xy 137.254742 -234.15625) (xy 137.154666 -234.056174) (xy 137.05459 -234.15625) (xy 137.05459 -234.2007)
			(xy 137.254742 -234.2007)
		)
		(stroke
			(width 0)
			(type solid)
		)
		(fill yes)
		(layer "In13.Cu")
		(net "M_H_CPU1_SA_DQ<13>")
	)
	(gr_poly
		(pts
			(xy 137.254742 -233.75239) (xy 137.254742 -233.70794) (xy 137.05459 -233.70794) (xy 137.05459 -233.75239)
			(xy 137.154666 -233.852466)
		)
		(stroke
			(width 0)
			(type solid)
		)
		(fill yes)
		(layer "In13.Cu")
		(net "M_H_CPU1_SA_DQ<14>")
	)
	(gr_poly
		(pts
			(xy 137.254742 -232.535984) (xy 137.154666 -232.436162) (xy 137.05459 -232.535984) (xy 137.05459 -232.583736)
			(xy 137.254742 -232.583736)
		)
		(stroke
			(width 0)
			(type solid)
		)
		(fill yes)
		(layer "In13.Cu")
		(net "M_H_CPU1_SA_DQS_DN<6>")
	)
	(gr_poly
		(pts
			(xy 137.254742 -232.132632) (xy 137.254742 -232.08488) (xy 137.05459 -232.08488) (xy 137.05459 -232.132632)
			(xy 137.154666 -232.232454)
		)
		(stroke
			(width 0)
			(type solid)
		)
		(fill yes)
		(layer "In13.Cu")
		(net "M_H_CPU1_SA_DQS_DN<1>")
	)
	(gr_poly
		(pts
			(xy 137.254742 -230.916226) (xy 137.154666 -230.81615) (xy 137.05459 -230.916226) (xy 137.05459 -230.960676)
			(xy 137.254742 -230.960676)
		)
		(stroke
			(width 0)
			(type solid)
		)
		(fill yes)
		(layer "In13.Cu")
		(net "M_H_CPU1_SA_DQ<9>")
	)
	(gr_poly
		(pts
			(xy 137.254742 -230.51262) (xy 137.254742 -230.46817) (xy 137.05459 -230.46817) (xy 137.05459 -230.51262)
			(xy 137.154666 -230.612696)
		)
		(stroke
			(width 0)
			(type solid)
		)
		(fill yes)
		(layer "In13.Cu")
		(net "M_H_CPU1_SA_DQ<10>")
	)
	(gr_poly
		(pts
			(xy 137.254742 -229.296214) (xy 137.154666 -229.196138) (xy 137.05459 -229.296214) (xy 137.05459 -229.340664)
			(xy 137.254742 -229.340664)
		)
		(stroke
			(width 0)
			(type solid)
		)
		(fill yes)
		(layer "In13.Cu")
		(net "M_H_CPU1_SA_DQ<5>")
	)
	(gr_poly
		(pts
			(xy 137.254742 -228.892608) (xy 137.254742 -228.848158) (xy 137.05459 -228.848158) (xy 137.05459 -228.892608)
			(xy 137.154666 -228.992684)
		)
		(stroke
			(width 0)
			(type solid)
		)
		(fill yes)
		(layer "In13.Cu")
		(net "M_H_CPU1_SA_DQ<6>")
	)
	(gr_poly
		(pts
			(xy 137.254742 -227.676202) (xy 137.154666 -227.57638) (xy 137.05459 -227.676202) (xy 137.05459 -227.723954)
			(xy 137.254742 -227.723954)
		)
		(stroke
			(width 0)
			(type solid)
		)
		(fill yes)
		(layer "In13.Cu")
		(net "M_H_CPU1_SA_DQS_DN<5>")
	)
	(gr_poly
		(pts
			(xy 137.254742 -227.27285) (xy 137.254742 -227.225098) (xy 137.05459 -227.225098) (xy 137.05459 -227.27285)
			(xy 137.154666 -227.372672)
		)
		(stroke
			(width 0)
			(type solid)
		)
		(fill yes)
		(layer "In13.Cu")
		(net "M_H_CPU1_SA_DQS_DN<0>")
	)
	(gr_poly
		(pts
			(xy 137.254742 -226.056444) (xy 137.154666 -225.956368) (xy 137.05459 -226.056444) (xy 137.05459 -226.100894)
			(xy 137.254742 -226.100894)
		)
		(stroke
			(width 0)
			(type solid)
		)
		(fill yes)
		(layer "In13.Cu")
		(net "M_H_CPU1_SA_DQ<1>")
	)
	(gr_poly
		(pts
			(xy 137.254742 -225.652584) (xy 137.254742 -225.608134) (xy 137.05459 -225.608134) (xy 137.05459 -225.652584)
			(xy 137.154666 -225.75266)
		)
		(stroke
			(width 0)
			(type solid)
		)
		(fill yes)
		(layer "In13.Cu")
		(net "M_H_CPU1_SA_DQ<2>")
	)
	(gr_poly
		(pts
			(xy 137.554716 -293.32428) (xy 137.554716 -293.27983) (xy 137.354564 -293.27983) (xy 137.354564 -293.32428)
			(xy 137.45464 -293.424356)
		)
		(stroke
			(width 0)
			(type solid)
		)
		(fill yes)
		(layer "In13.Cu")
		(net "M_H_CPU1_SB_DQ<31>")
	)
	(gr_poly
		(pts
			(xy 137.554716 -292.108128) (xy 137.45464 -292.008052) (xy 137.354564 -292.108128) (xy 137.354564 -292.152578)
			(xy 137.554716 -292.152578)
		)
		(stroke
			(width 0)
			(type solid)
		)
		(fill yes)
		(layer "In13.Cu")
		(net "M_H_CPU1_SB_DQ<28>")
	)
	(gr_poly
		(pts
			(xy 137.554716 -291.704522) (xy 137.554716 -291.65677) (xy 137.354564 -291.65677) (xy 137.354564 -291.704522)
			(xy 137.45464 -291.804344)
		)
		(stroke
			(width 0)
			(type solid)
		)
		(fill yes)
		(layer "In13.Cu")
		(net "M_H_CPU1_SB_DQS_DP<8>")
	)
	(gr_poly
		(pts
			(xy 137.554716 -290.487862) (xy 137.45464 -290.38804) (xy 137.354564 -290.487862) (xy 137.354564 -290.535614)
			(xy 137.554716 -290.535614)
		)
		(stroke
			(width 0)
			(type solid)
		)
		(fill yes)
		(layer "In13.Cu")
		(net "M_H_CPU1_SB_DQS_DP<3>")
	)
	(gr_poly
		(pts
			(xy 137.554716 -290.084256) (xy 137.554716 -290.039806) (xy 137.354564 -290.039806) (xy 137.354564 -290.084256)
			(xy 137.45464 -290.184332)
		)
		(stroke
			(width 0)
			(type solid)
		)
		(fill yes)
		(layer "In13.Cu")
		(net "M_H_CPU1_SB_DQ<27>")
	)
	(gr_poly
		(pts
			(xy 137.554716 -288.868104) (xy 137.45464 -288.768028) (xy 137.354564 -288.868104) (xy 137.354564 -288.912554)
			(xy 137.554716 -288.912554)
		)
		(stroke
			(width 0)
			(type solid)
		)
		(fill yes)
		(layer "In13.Cu")
		(net "M_H_CPU1_SB_DQ<24>")
	)
	(gr_poly
		(pts
			(xy 137.554716 -288.464498) (xy 137.554716 -288.420048) (xy 137.354564 -288.420048) (xy 137.354564 -288.464498)
			(xy 137.45464 -288.564574)
		)
		(stroke
			(width 0)
			(type solid)
		)
		(fill yes)
		(layer "In13.Cu")
		(net "M_H_CPU1_SB_DQ<23>")
	)
	(gr_poly
		(pts
			(xy 137.554716 -287.248092) (xy 137.45464 -287.148016) (xy 137.354564 -287.248092) (xy 137.354564 -287.292542)
			(xy 137.554716 -287.292542)
		)
		(stroke
			(width 0)
			(type solid)
		)
		(fill yes)
		(layer "In13.Cu")
		(net "M_H_CPU1_SB_DQ<20>")
	)
	(gr_poly
		(pts
			(xy 137.554716 -286.844486) (xy 137.554716 -286.796734) (xy 137.354564 -286.796734) (xy 137.354564 -286.844486)
			(xy 137.45464 -286.944562)
		)
		(stroke
			(width 0)
			(type solid)
		)
		(fill yes)
		(layer "In13.Cu")
		(net "M_H_CPU1_SB_DQS_DP<7>")
	)
	(gr_poly
		(pts
			(xy 137.554716 -285.62808) (xy 137.45464 -285.528258) (xy 137.354564 -285.62808) (xy 137.354564 -285.675832)
			(xy 137.554716 -285.675832)
		)
		(stroke
			(width 0)
			(type solid)
		)
		(fill yes)
		(layer "In13.Cu")
		(net "M_H_CPU1_SB_DQS_DP<2>")
	)
	(gr_poly
		(pts
			(xy 137.554716 -285.224474) (xy 137.554716 -285.180024) (xy 137.354564 -285.180024) (xy 137.354564 -285.224474)
			(xy 137.45464 -285.32455)
		)
		(stroke
			(width 0)
			(type solid)
		)
		(fill yes)
		(layer "In13.Cu")
		(net "M_H_CPU1_SB_DQ<19>")
	)
	(gr_poly
		(pts
			(xy 137.554716 -284.008322) (xy 137.45464 -283.908246) (xy 137.354564 -284.008322) (xy 137.354564 -284.052772)
			(xy 137.554716 -284.052772)
		)
		(stroke
			(width 0)
			(type solid)
		)
		(fill yes)
		(layer "In13.Cu")
		(net "M_H_CPU1_SB_DQ<16>")
	)
	(gr_poly
		(pts
			(xy 137.554716 -283.604462) (xy 137.554716 -283.560012) (xy 137.354564 -283.560012) (xy 137.354564 -283.604462)
			(xy 137.45464 -283.704538)
		)
		(stroke
			(width 0)
			(type solid)
		)
		(fill yes)
		(layer "In13.Cu")
		(net "M_H_CPU1_SB_DQ<15>")
	)
	(gr_poly
		(pts
			(xy 137.554716 -282.38831) (xy 137.45464 -282.288234) (xy 137.354564 -282.38831) (xy 137.354564 -282.43276)
			(xy 137.554716 -282.43276)
		)
		(stroke
			(width 0)
			(type solid)
		)
		(fill yes)
		(layer "In13.Cu")
		(net "M_H_CPU1_SB_DQ<12>")
	)
	(gr_poly
		(pts
			(xy 137.554716 -281.984704) (xy 137.554716 -281.936952) (xy 137.354564 -281.936952) (xy 137.354564 -281.984704)
			(xy 137.45464 -282.084526)
		)
		(stroke
			(width 0)
			(type solid)
		)
		(fill yes)
		(layer "In13.Cu")
		(net "M_H_CPU1_SB_DQS_DP<6>")
	)
	(gr_poly
		(pts
			(xy 137.554716 -280.768044) (xy 137.45464 -280.668222) (xy 137.354564 -280.768044) (xy 137.354564 -280.815796)
			(xy 137.554716 -280.815796)
		)
		(stroke
			(width 0)
			(type solid)
		)
		(fill yes)
		(layer "In13.Cu")
		(net "M_H_CPU1_SB_DQS_DP<1>")
	)
	(gr_poly
		(pts
			(xy 137.554716 -280.364438) (xy 137.554716 -280.319988) (xy 137.354564 -280.319988) (xy 137.354564 -280.364438)
			(xy 137.45464 -280.464514)
		)
		(stroke
			(width 0)
			(type solid)
		)
		(fill yes)
		(layer "In13.Cu")
		(net "M_H_CPU1_SB_DQ<11>")
	)
	(gr_poly
		(pts
			(xy 137.554716 -279.148286) (xy 137.45464 -279.04821) (xy 137.354564 -279.148286) (xy 137.354564 -279.192736)
			(xy 137.554716 -279.192736)
		)
		(stroke
			(width 0)
			(type solid)
		)
		(fill yes)
		(layer "In13.Cu")
		(net "M_H_CPU1_SB_DQ<8>")
	)
	(gr_poly
		(pts
			(xy 137.554716 -278.744426) (xy 137.554716 -278.699976) (xy 137.354564 -278.699976) (xy 137.354564 -278.744426)
			(xy 137.45464 -278.844502)
		)
		(stroke
			(width 0)
			(type solid)
		)
		(fill yes)
		(layer "In13.Cu")
		(net "M_H_CPU1_SB_DQ<7>")
	)
	(gr_poly
		(pts
			(xy 137.554716 -277.528274) (xy 137.45464 -277.428198) (xy 137.354564 -277.528274) (xy 137.354564 -277.572724)
			(xy 137.554716 -277.572724)
		)
		(stroke
			(width 0)
			(type solid)
		)
		(fill yes)
		(layer "In13.Cu")
		(net "M_H_CPU1_SB_DQ<4>")
	)
	(gr_poly
		(pts
			(xy 137.554716 -277.124668) (xy 137.554716 -277.076916) (xy 137.354564 -277.076916) (xy 137.354564 -277.124668)
			(xy 137.45464 -277.22449)
		)
		(stroke
			(width 0)
			(type solid)
		)
		(fill yes)
		(layer "In13.Cu")
		(net "M_H_CPU1_SB_DQS_DP<5>")
	)
	(gr_poly
		(pts
			(xy 137.554716 -275.908008) (xy 137.45464 -275.808186) (xy 137.354564 -275.908008) (xy 137.354564 -275.95576)
			(xy 137.554716 -275.95576)
		)
		(stroke
			(width 0)
			(type solid)
		)
		(fill yes)
		(layer "In13.Cu")
		(net "M_H_CPU1_SB_DQS_DP<0>")
	)
	(gr_poly
		(pts
			(xy 137.554716 -275.504402) (xy 137.554716 -275.459952) (xy 137.354564 -275.459952) (xy 137.354564 -275.504402)
			(xy 137.45464 -275.604478)
		)
		(stroke
			(width 0)
			(type solid)
		)
		(fill yes)
		(layer "In13.Cu")
		(net "M_H_CPU1_SB_DQ<3>")
	)
	(gr_poly
		(pts
			(xy 137.554716 -274.28825) (xy 137.45464 -274.188174) (xy 137.354564 -274.28825) (xy 137.354564 -274.3327)
			(xy 137.554716 -274.3327)
		)
		(stroke
			(width 0)
			(type solid)
		)
		(fill yes)
		(layer "In13.Cu")
		(net "M_H_CPU1_SB_DQ<0>")
	)
	(gr_poly
		(pts
			(xy 137.554716 -273.88439) (xy 137.554716 -273.83994) (xy 137.354564 -273.83994) (xy 137.354564 -273.88439)
			(xy 137.45464 -273.984466)
		)
		(stroke
			(width 0)
			(type solid)
		)
		(fill yes)
		(layer "In13.Cu")
		(net "M_H_CPU1_SB_CB<3>")
	)
	(gr_poly
		(pts
			(xy 137.554716 -272.668238) (xy 137.45464 -272.568162) (xy 137.354564 -272.668238) (xy 137.354564 -272.712688)
			(xy 137.554716 -272.712688)
		)
		(stroke
			(width 0)
			(type solid)
		)
		(fill yes)
		(layer "In13.Cu")
		(net "M_H_CPU1_SB_CB<0>")
	)
	(gr_poly
		(pts
			(xy 137.554716 -272.264632) (xy 137.554716 -272.21688) (xy 137.354564 -272.21688) (xy 137.354564 -272.264632)
			(xy 137.45464 -272.364454)
		)
		(stroke
			(width 0)
			(type solid)
		)
		(fill yes)
		(layer "In13.Cu")
		(net "M_H_CPU1_SB_DQS_DP<4>")
	)
	(gr_poly
		(pts
			(xy 137.554716 -271.047972) (xy 137.45464 -270.94815) (xy 137.354564 -271.047972) (xy 137.354564 -271.095724)
			(xy 137.554716 -271.095724)
		)
		(stroke
			(width 0)
			(type solid)
		)
		(fill yes)
		(layer "In13.Cu")
		(net "M_H_CPU1_SB_DQS_DP<9>")
	)
	(gr_poly
		(pts
			(xy 137.554716 -270.644366) (xy 137.554716 -270.599916) (xy 137.354564 -270.599916) (xy 137.354564 -270.644366)
			(xy 137.45464 -270.744442)
		)
		(stroke
			(width 0)
			(type solid)
		)
		(fill yes)
		(layer "In13.Cu")
		(net "M_H_CPU1_SB_CB<7>")
	)
	(gr_poly
		(pts
			(xy 137.554716 -269.428214) (xy 137.45464 -269.328138) (xy 137.354564 -269.428214) (xy 137.354564 -269.472664)
			(xy 137.554716 -269.472664)
		)
		(stroke
			(width 0)
			(type solid)
		)
		(fill yes)
		(layer "In13.Cu")
		(net "M_H_CPU1_SB_CB<4>")
	)
	(gr_poly
		(pts
			(xy 137.554716 -267.808202) (xy 137.45464 -267.708126) (xy 137.354564 -267.808202) (xy 137.354564 -267.852652)
			(xy 137.554716 -267.852652)
		)
		(stroke
			(width 0)
			(type solid)
		)
		(fill yes)
		(layer "In13.Cu")
		(net "M_H_CPU1_SB_RSP<0>")
	)
	(gr_poly
		(pts
			(xy 137.554716 -265.78433) (xy 137.554716 -265.73988) (xy 137.354564 -265.73988) (xy 137.354564 -265.78433)
			(xy 137.45464 -265.884406)
		)
		(stroke
			(width 0)
			(type solid)
		)
		(fill yes)
		(layer "In13.Cu")
		(net "M_H_CPU1_SB_CS_N<0>")
	)
	(gr_poly
		(pts
			(xy 137.554716 -264.568178) (xy 137.45464 -264.468102) (xy 137.354564 -264.568178) (xy 137.354564 -264.612628)
			(xy 137.554716 -264.612628)
		)
		(stroke
			(width 0)
			(type solid)
		)
		(fill yes)
		(layer "In13.Cu")
		(net "M_H_CPU1_SB_CA<6>")
	)
	(gr_poly
		(pts
			(xy 137.554716 -264.164318) (xy 137.554716 -264.119868) (xy 137.354564 -264.119868) (xy 137.354564 -264.164318)
			(xy 137.45464 -264.264394)
		)
		(stroke
			(width 0)
			(type solid)
		)
		(fill yes)
		(layer "In13.Cu")
		(net "M_H_CPU1_SB_CA<5>")
	)
	(gr_poly
		(pts
			(xy 137.554716 -262.948166) (xy 137.45464 -262.84809) (xy 137.354564 -262.948166) (xy 137.354564 -262.992616)
			(xy 137.554716 -262.992616)
		)
		(stroke
			(width 0)
			(type solid)
		)
		(fill yes)
		(layer "In13.Cu")
		(net "M_H_CPU1_SB_CA<2>")
	)
	(gr_poly
		(pts
			(xy 137.554716 -262.544306) (xy 137.554716 -262.499856) (xy 137.354564 -262.499856) (xy 137.354564 -262.544306)
			(xy 137.45464 -262.644382)
		)
		(stroke
			(width 0)
			(type solid)
		)
		(fill yes)
		(layer "In13.Cu")
		(net "M_H_CPU1_SB_CA<1>")
	)
	(gr_poly
		(pts
			(xy 137.724896 -256.026158) (xy 137.62482 -255.926336) (xy 137.524744 -256.026158) (xy 137.524744 -256.07391)
			(xy 137.724896 -256.07391)
		)
		(stroke
			(width 0)
			(type solid)
		)
		(fill yes)
		(layer "In13.Cu")
		(net "M_H_CPU1_CLK_DP<0>")
	)
	(gr_poly
		(pts
			(xy 137.724896 -255.622552) (xy 137.724896 -255.578102) (xy 137.524744 -255.578102) (xy 137.524744 -255.622552)
			(xy 137.62482 -255.722628)
		)
		(stroke
			(width 0)
			(type solid)
		)
		(fill yes)
		(layer "In13.Cu")
		(net "M_H_CPU1_SA_PAR")
	)
	(gr_poly
		(pts
			(xy 137.724896 -254.4064) (xy 137.62482 -254.306324) (xy 137.524744 -254.4064) (xy 137.524744 -254.45085)
			(xy 137.724896 -254.45085)
		)
		(stroke
			(width 0)
			(type solid)
		)
		(fill yes)
		(layer "In13.Cu")
		(net "M_H_CPU1_SA_CA<4>")
	)
	(gr_poly
		(pts
			(xy 137.724896 -254.00254) (xy 137.724896 -253.95809) (xy 137.524744 -253.95809) (xy 137.524744 -254.00254)
			(xy 137.62482 -254.102616)
		)
		(stroke
			(width 0)
			(type solid)
		)
		(fill yes)
		(layer "In13.Cu")
		(net "M_H_CPU1_SA_CA<3>")
	)
	(gr_poly
		(pts
			(xy 137.724896 -252.786388) (xy 137.62482 -252.686312) (xy 137.524744 -252.786388) (xy 137.524744 -252.830838)
			(xy 137.724896 -252.830838)
		)
		(stroke
			(width 0)
			(type solid)
		)
		(fill yes)
		(layer "In13.Cu")
		(net "M_H_CPU1_SA_CA<0>")
	)
	(gr_poly
		(pts
			(xy 137.724896 -251.166376) (xy 137.62482 -251.0663) (xy 137.524744 -251.166376) (xy 137.524744 -251.210826)
			(xy 137.724896 -251.210826)
		)
		(stroke
			(width 0)
			(type solid)
		)
		(fill yes)
		(layer "In13.Cu")
		(net "M_H_CPU1_SA_CS_N<0>")
	)
	(gr_poly
		(pts
			(xy 137.724896 -250.762516) (xy 137.724896 -250.718066) (xy 137.524744 -250.718066) (xy 137.524744 -250.762516)
			(xy 137.62482 -250.862592)
		)
		(stroke
			(width 0)
			(type solid)
		)
		(fill yes)
		(layer "In13.Cu")
		(net "M_H_CPU1_RESET_N")
	)
	(gr_poly
		(pts
			(xy 137.724896 -249.142504) (xy 137.724896 -249.098054) (xy 137.524744 -249.098054) (xy 137.524744 -249.142504)
			(xy 137.62482 -249.24258)
		)
		(stroke
			(width 0)
			(type solid)
		)
		(fill yes)
		(layer "In13.Cu")
		(net "M_H_CPU1_SA_CB<7>")
	)
	(gr_poly
		(pts
			(xy 137.724896 -247.926352) (xy 137.62482 -247.826276) (xy 137.524744 -247.926352) (xy 137.524744 -247.970802)
			(xy 137.724896 -247.970802)
		)
		(stroke
			(width 0)
			(type solid)
		)
		(fill yes)
		(layer "In13.Cu")
		(net "M_H_CPU1_SA_CB<4>")
	)
	(gr_poly
		(pts
			(xy 137.724896 -247.522746) (xy 137.724896 -247.474994) (xy 137.524744 -247.474994) (xy 137.524744 -247.522746)
			(xy 137.62482 -247.622568)
		)
		(stroke
			(width 0)
			(type solid)
		)
		(fill yes)
		(layer "In13.Cu")
		(net "M_H_CPU1_SA_DQS_DP<9>")
	)
	(gr_poly
		(pts
			(xy 137.724896 -246.306086) (xy 137.62482 -246.206264) (xy 137.524744 -246.306086) (xy 137.524744 -246.353838)
			(xy 137.724896 -246.353838)
		)
		(stroke
			(width 0)
			(type solid)
		)
		(fill yes)
		(layer "In13.Cu")
		(net "M_H_CPU1_SA_DQS_DP<4>")
	)
	(gr_poly
		(pts
			(xy 137.724896 -245.90248) (xy 137.724896 -245.85803) (xy 137.524744 -245.85803) (xy 137.524744 -245.90248)
			(xy 137.62482 -246.002556)
		)
		(stroke
			(width 0)
			(type solid)
		)
		(fill yes)
		(layer "In13.Cu")
		(net "M_H_CPU1_SA_CB<3>")
	)
	(gr_poly
		(pts
			(xy 137.724896 -244.686328) (xy 137.62482 -244.586252) (xy 137.524744 -244.686328) (xy 137.524744 -244.730778)
			(xy 137.724896 -244.730778)
		)
		(stroke
			(width 0)
			(type solid)
		)
		(fill yes)
		(layer "In13.Cu")
		(net "M_H_CPU1_SA_CB<0>")
	)
	(gr_poly
		(pts
			(xy 137.724896 -244.282468) (xy 137.724896 -244.238018) (xy 137.524744 -244.238018) (xy 137.524744 -244.282468)
			(xy 137.62482 -244.382544)
		)
		(stroke
			(width 0)
			(type solid)
		)
		(fill yes)
		(layer "In13.Cu")
		(net "M_H_CPU1_SA_DQ<31>")
	)
	(gr_poly
		(pts
			(xy 137.724896 -243.066316) (xy 137.62482 -242.96624) (xy 137.524744 -243.066316) (xy 137.524744 -243.110766)
			(xy 137.724896 -243.110766)
		)
		(stroke
			(width 0)
			(type solid)
		)
		(fill yes)
		(layer "In13.Cu")
		(net "M_H_CPU1_SA_DQ<28>")
	)
	(gr_poly
		(pts
			(xy 137.724896 -242.66271) (xy 137.724896 -242.614958) (xy 137.524744 -242.614958) (xy 137.524744 -242.66271)
			(xy 137.62482 -242.762532)
		)
		(stroke
			(width 0)
			(type solid)
		)
		(fill yes)
		(layer "In13.Cu")
		(net "M_H_CPU1_SA_DQS_DP<8>")
	)
	(gr_poly
		(pts
			(xy 137.724896 -241.44605) (xy 137.62482 -241.346228) (xy 137.524744 -241.44605) (xy 137.524744 -241.493802)
			(xy 137.724896 -241.493802)
		)
		(stroke
			(width 0)
			(type solid)
		)
		(fill yes)
		(layer "In13.Cu")
		(net "M_H_CPU1_SA_DQS_DP<3>")
	)
	(gr_poly
		(pts
			(xy 137.724896 -241.042444) (xy 137.724896 -240.997994) (xy 137.524744 -240.997994) (xy 137.524744 -241.042444)
			(xy 137.62482 -241.14252)
		)
		(stroke
			(width 0)
			(type solid)
		)
		(fill yes)
		(layer "In13.Cu")
		(net "M_H_CPU1_SA_DQ<27>")
	)
	(gr_poly
		(pts
			(xy 137.724896 -239.826292) (xy 137.62482 -239.726216) (xy 137.524744 -239.826292) (xy 137.524744 -239.870742)
			(xy 137.724896 -239.870742)
		)
		(stroke
			(width 0)
			(type solid)
		)
		(fill yes)
		(layer "In13.Cu")
		(net "M_H_CPU1_SA_DQ<24>")
	)
	(gr_poly
		(pts
			(xy 137.724896 -239.422432) (xy 137.724896 -239.377982) (xy 137.524744 -239.377982) (xy 137.524744 -239.422432)
			(xy 137.62482 -239.522508)
		)
		(stroke
			(width 0)
			(type solid)
		)
		(fill yes)
		(layer "In13.Cu")
		(net "M_H_CPU1_SA_DQ<23>")
	)
	(gr_poly
		(pts
			(xy 137.724896 -238.20628) (xy 137.62482 -238.106204) (xy 137.524744 -238.20628) (xy 137.524744 -238.25073)
			(xy 137.724896 -238.25073)
		)
		(stroke
			(width 0)
			(type solid)
		)
		(fill yes)
		(layer "In13.Cu")
		(net "M_H_CPU1_SA_DQ<20>")
	)
	(gr_poly
		(pts
			(xy 137.724896 -237.802674) (xy 137.724896 -237.754922) (xy 137.524744 -237.754922) (xy 137.524744 -237.802674)
			(xy 137.62482 -237.902496)
		)
		(stroke
			(width 0)
			(type solid)
		)
		(fill yes)
		(layer "In13.Cu")
		(net "M_H_CPU1_SA_DQS_DP<7>")
	)
	(gr_poly
		(pts
			(xy 137.724896 -236.586014) (xy 137.62482 -236.486192) (xy 137.524744 -236.586014) (xy 137.524744 -236.633766)
			(xy 137.724896 -236.633766)
		)
		(stroke
			(width 0)
			(type solid)
		)
		(fill yes)
		(layer "In13.Cu")
		(net "M_H_CPU1_SA_DQS_DP<2>")
	)
	(gr_poly
		(pts
			(xy 137.724896 -236.182408) (xy 137.724896 -236.137958) (xy 137.524744 -236.137958) (xy 137.524744 -236.182408)
			(xy 137.62482 -236.282484)
		)
		(stroke
			(width 0)
			(type solid)
		)
		(fill yes)
		(layer "In13.Cu")
		(net "M_H_CPU1_SA_DQ<19>")
	)
	(gr_poly
		(pts
			(xy 137.724896 -234.966256) (xy 137.62482 -234.86618) (xy 137.524744 -234.966256) (xy 137.524744 -235.010706)
			(xy 137.724896 -235.010706)
		)
		(stroke
			(width 0)
			(type solid)
		)
		(fill yes)
		(layer "In13.Cu")
		(net "M_H_CPU1_SA_DQ<16>")
	)
	(gr_poly
		(pts
			(xy 137.724896 -234.562396) (xy 137.724896 -234.517946) (xy 137.524744 -234.517946) (xy 137.524744 -234.562396)
			(xy 137.62482 -234.662472)
		)
		(stroke
			(width 0)
			(type solid)
		)
		(fill yes)
		(layer "In13.Cu")
		(net "M_H_CPU1_SA_DQ<15>")
	)
	(gr_poly
		(pts
			(xy 137.724896 -233.346244) (xy 137.62482 -233.246168) (xy 137.524744 -233.346244) (xy 137.524744 -233.390694)
			(xy 137.724896 -233.390694)
		)
		(stroke
			(width 0)
			(type solid)
		)
		(fill yes)
		(layer "In13.Cu")
		(net "M_H_CPU1_SA_DQ<12>")
	)
	(gr_poly
		(pts
			(xy 137.724896 -232.942638) (xy 137.724896 -232.894886) (xy 137.524744 -232.894886) (xy 137.524744 -232.942638)
			(xy 137.62482 -233.04246)
		)
		(stroke
			(width 0)
			(type solid)
		)
		(fill yes)
		(layer "In13.Cu")
		(net "M_H_CPU1_SA_DQS_DP<6>")
	)
	(gr_poly
		(pts
			(xy 137.724896 -231.725978) (xy 137.62482 -231.626156) (xy 137.524744 -231.725978) (xy 137.524744 -231.77373)
			(xy 137.724896 -231.77373)
		)
		(stroke
			(width 0)
			(type solid)
		)
		(fill yes)
		(layer "In13.Cu")
		(net "M_H_CPU1_SA_DQS_DP<1>")
	)
	(gr_poly
		(pts
			(xy 137.724896 -231.322626) (xy 137.724896 -231.278176) (xy 137.524744 -231.278176) (xy 137.524744 -231.322626)
			(xy 137.62482 -231.422702)
		)
		(stroke
			(width 0)
			(type solid)
		)
		(fill yes)
		(layer "In13.Cu")
		(net "M_H_CPU1_SA_DQ<11>")
	)
	(gr_poly
		(pts
			(xy 137.724896 -230.10622) (xy 137.62482 -230.006144) (xy 137.524744 -230.10622) (xy 137.524744 -230.15067)
			(xy 137.724896 -230.15067)
		)
		(stroke
			(width 0)
			(type solid)
		)
		(fill yes)
		(layer "In13.Cu")
		(net "M_H_CPU1_SA_DQ<8>")
	)
	(gr_poly
		(pts
			(xy 137.724896 -229.702614) (xy 137.724896 -229.658164) (xy 137.524744 -229.658164) (xy 137.524744 -229.702614)
			(xy 137.62482 -229.80269)
		)
		(stroke
			(width 0)
			(type solid)
		)
		(fill yes)
		(layer "In13.Cu")
		(net "M_H_CPU1_SA_DQ<7>")
	)
	(gr_poly
		(pts
			(xy 137.724896 -228.486462) (xy 137.62482 -228.386386) (xy 137.524744 -228.486462) (xy 137.524744 -228.530912)
			(xy 137.724896 -228.530912)
		)
		(stroke
			(width 0)
			(type solid)
		)
		(fill yes)
		(layer "In13.Cu")
		(net "M_H_CPU1_SA_DQ<4>")
	)
	(gr_poly
		(pts
			(xy 137.724896 -228.082856) (xy 137.724896 -228.035104) (xy 137.524744 -228.035104) (xy 137.524744 -228.082856)
			(xy 137.62482 -228.182678)
		)
		(stroke
			(width 0)
			(type solid)
		)
		(fill yes)
		(layer "In13.Cu")
		(net "M_H_CPU1_SA_DQS_DP<5>")
	)
	(gr_poly
		(pts
			(xy 137.724896 -226.866196) (xy 137.62482 -226.766374) (xy 137.524744 -226.866196) (xy 137.524744 -226.913948)
			(xy 137.724896 -226.913948)
		)
		(stroke
			(width 0)
			(type solid)
		)
		(fill yes)
		(layer "In13.Cu")
		(net "M_H_CPU1_SA_DQS_DP<0>")
	)
	(gr_poly
		(pts
			(xy 137.724896 -226.46259) (xy 137.724896 -226.41814) (xy 137.524744 -226.41814) (xy 137.524744 -226.46259)
			(xy 137.62482 -226.562666)
		)
		(stroke
			(width 0)
			(type solid)
		)
		(fill yes)
		(layer "In13.Cu")
		(net "M_H_CPU1_SA_DQ<3>")
	)
	(gr_poly
		(pts
			(xy 137.724896 -225.246438) (xy 137.62482 -225.146362) (xy 137.524744 -225.246438) (xy 137.524744 -225.290888)
			(xy 137.724896 -225.290888)
		)
		(stroke
			(width 0)
			(type solid)
		)
		(fill yes)
		(layer "In13.Cu")
		(net "M_H_CPU1_SA_DQ<0>")
	)
	(gr_poly
		(pts
			(xy 138.02487 -292.918134) (xy 137.924794 -292.818058) (xy 137.824718 -292.918134) (xy 137.824718 -292.962584)
			(xy 138.02487 -292.962584)
		)
		(stroke
			(width 0)
			(type solid)
		)
		(fill yes)
		(layer "In13.Cu")
		(net "M_H_CPU1_SB_DQ<29>")
	)
	(gr_poly
		(pts
			(xy 138.02487 -292.514274) (xy 138.02487 -292.469824) (xy 137.824718 -292.469824) (xy 137.824718 -292.514274)
			(xy 137.924794 -292.61435)
		)
		(stroke
			(width 0)
			(type solid)
		)
		(fill yes)
		(layer "In13.Cu")
		(net "M_H_CPU1_SB_DQ<30>")
	)
	(gr_poly
		(pts
			(xy 138.02487 -291.297868) (xy 137.924794 -291.198046) (xy 137.824718 -291.297868) (xy 137.824718 -291.34562)
			(xy 138.02487 -291.34562)
		)
		(stroke
			(width 0)
			(type solid)
		)
		(fill yes)
		(layer "In13.Cu")
		(net "M_H_CPU1_SB_DQS_DN<8>")
	)
	(gr_poly
		(pts
			(xy 138.02487 -290.894516) (xy 138.02487 -290.846764) (xy 137.824718 -290.846764) (xy 137.824718 -290.894516)
			(xy 137.924794 -290.994338)
		)
		(stroke
			(width 0)
			(type solid)
		)
		(fill yes)
		(layer "In13.Cu")
		(net "M_H_CPU1_SB_DQS_DN<3>")
	)
	(gr_poly
		(pts
			(xy 138.02487 -289.67811) (xy 137.924794 -289.578034) (xy 137.824718 -289.67811) (xy 137.824718 -289.72256)
			(xy 138.02487 -289.72256)
		)
		(stroke
			(width 0)
			(type solid)
		)
		(fill yes)
		(layer "In13.Cu")
		(net "M_H_CPU1_SB_DQ<25>")
	)
	(gr_poly
		(pts
			(xy 138.02487 -289.27425) (xy 138.02487 -289.2298) (xy 137.824718 -289.2298) (xy 137.824718 -289.27425)
			(xy 137.924794 -289.374326)
		)
		(stroke
			(width 0)
			(type solid)
		)
		(fill yes)
		(layer "In13.Cu")
		(net "M_H_CPU1_SB_DQ<26>")
	)
	(gr_poly
		(pts
			(xy 138.02487 -288.058098) (xy 137.924794 -287.958022) (xy 137.824718 -288.058098) (xy 137.824718 -288.102548)
			(xy 138.02487 -288.102548)
		)
		(stroke
			(width 0)
			(type solid)
		)
		(fill yes)
		(layer "In13.Cu")
		(net "M_H_CPU1_SB_DQ<21>")
	)
	(gr_poly
		(pts
			(xy 138.02487 -287.654492) (xy 138.02487 -287.610042) (xy 137.824718 -287.610042) (xy 137.824718 -287.654492)
			(xy 137.924794 -287.754568)
		)
		(stroke
			(width 0)
			(type solid)
		)
		(fill yes)
		(layer "In13.Cu")
		(net "M_H_CPU1_SB_DQ<22>")
	)
	(gr_poly
		(pts
			(xy 138.02487 -286.438086) (xy 137.924794 -286.33801) (xy 137.824718 -286.438086) (xy 137.824718 -286.485838)
			(xy 138.02487 -286.485838)
		)
		(stroke
			(width 0)
			(type solid)
		)
		(fill yes)
		(layer "In13.Cu")
		(net "M_H_CPU1_SB_DQS_DN<7>")
	)
	(gr_poly
		(pts
			(xy 138.02487 -286.034734) (xy 138.02487 -285.986982) (xy 137.824718 -285.986982) (xy 137.824718 -286.034734)
			(xy 137.924794 -286.134556)
		)
		(stroke
			(width 0)
			(type solid)
		)
		(fill yes)
		(layer "In13.Cu")
		(net "M_H_CPU1_SB_DQS_DN<2>")
	)
	(gr_poly
		(pts
			(xy 138.02487 -284.818328) (xy 137.924794 -284.718252) (xy 137.824718 -284.818328) (xy 137.824718 -284.862778)
			(xy 138.02487 -284.862778)
		)
		(stroke
			(width 0)
			(type solid)
		)
		(fill yes)
		(layer "In13.Cu")
		(net "M_H_CPU1_SB_DQ<17>")
	)
	(gr_poly
		(pts
			(xy 138.02487 -284.414468) (xy 138.02487 -284.370018) (xy 137.824718 -284.370018) (xy 137.824718 -284.414468)
			(xy 137.924794 -284.514544)
		)
		(stroke
			(width 0)
			(type solid)
		)
		(fill yes)
		(layer "In13.Cu")
		(net "M_H_CPU1_SB_DQ<18>")
	)
	(gr_poly
		(pts
			(xy 138.02487 -283.198316) (xy 137.924794 -283.09824) (xy 137.824718 -283.198316) (xy 137.824718 -283.242766)
			(xy 138.02487 -283.242766)
		)
		(stroke
			(width 0)
			(type solid)
		)
		(fill yes)
		(layer "In13.Cu")
		(net "M_H_CPU1_SB_DQ<13>")
	)
	(gr_poly
		(pts
			(xy 138.02487 -282.794456) (xy 138.02487 -282.750006) (xy 137.824718 -282.750006) (xy 137.824718 -282.794456)
			(xy 137.924794 -282.894532)
		)
		(stroke
			(width 0)
			(type solid)
		)
		(fill yes)
		(layer "In13.Cu")
		(net "M_H_CPU1_SB_DQ<14>")
	)
	(gr_poly
		(pts
			(xy 138.02487 -281.57805) (xy 137.924794 -281.478228) (xy 137.824718 -281.57805) (xy 137.824718 -281.625802)
			(xy 138.02487 -281.625802)
		)
		(stroke
			(width 0)
			(type solid)
		)
		(fill yes)
		(layer "In13.Cu")
		(net "M_H_CPU1_SB_DQS_DN<6>")
	)
	(gr_poly
		(pts
			(xy 138.02487 -281.174698) (xy 138.02487 -281.126946) (xy 137.824718 -281.126946) (xy 137.824718 -281.174698)
			(xy 137.924794 -281.27452)
		)
		(stroke
			(width 0)
			(type solid)
		)
		(fill yes)
		(layer "In13.Cu")
		(net "M_H_CPU1_SB_DQS_DN<1>")
	)
	(gr_poly
		(pts
			(xy 138.02487 -279.958292) (xy 137.924794 -279.858216) (xy 137.824718 -279.958292) (xy 137.824718 -280.002742)
			(xy 138.02487 -280.002742)
		)
		(stroke
			(width 0)
			(type solid)
		)
		(fill yes)
		(layer "In13.Cu")
		(net "M_H_CPU1_SB_DQ<9>")
	)
	(gr_poly
		(pts
			(xy 138.02487 -279.554432) (xy 138.02487 -279.509982) (xy 137.824718 -279.509982) (xy 137.824718 -279.554432)
			(xy 137.924794 -279.654508)
		)
		(stroke
			(width 0)
			(type solid)
		)
		(fill yes)
		(layer "In13.Cu")
		(net "M_H_CPU1_SB_DQ<10>")
	)
	(gr_poly
		(pts
			(xy 138.02487 -278.33828) (xy 137.924794 -278.238204) (xy 137.824718 -278.33828) (xy 137.824718 -278.38273)
			(xy 138.02487 -278.38273)
		)
		(stroke
			(width 0)
			(type solid)
		)
		(fill yes)
		(layer "In13.Cu")
		(net "M_H_CPU1_SB_DQ<5>")
	)
	(gr_poly
		(pts
			(xy 138.02487 -277.93442) (xy 138.02487 -277.88997) (xy 137.824718 -277.88997) (xy 137.824718 -277.93442)
			(xy 137.924794 -278.034496)
		)
		(stroke
			(width 0)
			(type solid)
		)
		(fill yes)
		(layer "In13.Cu")
		(net "M_H_CPU1_SB_DQ<6>")
	)
	(gr_poly
		(pts
			(xy 138.02487 -276.718014) (xy 137.924794 -276.618192) (xy 137.824718 -276.718014) (xy 137.824718 -276.765766)
			(xy 138.02487 -276.765766)
		)
		(stroke
			(width 0)
			(type solid)
		)
		(fill yes)
		(layer "In13.Cu")
		(net "M_H_CPU1_SB_DQS_DN<5>")
	)
	(gr_poly
		(pts
			(xy 138.02487 -276.314662) (xy 138.02487 -276.26691) (xy 137.824718 -276.26691) (xy 137.824718 -276.314662)
			(xy 137.924794 -276.414484)
		)
		(stroke
			(width 0)
			(type solid)
		)
		(fill yes)
		(layer "In13.Cu")
		(net "M_H_CPU1_SB_DQS_DN<0>")
	)
	(gr_poly
		(pts
			(xy 138.02487 -275.098256) (xy 137.924794 -274.99818) (xy 137.824718 -275.098256) (xy 137.824718 -275.142706)
			(xy 138.02487 -275.142706)
		)
		(stroke
			(width 0)
			(type solid)
		)
		(fill yes)
		(layer "In13.Cu")
		(net "M_H_CPU1_SB_DQ<1>")
	)
	(gr_poly
		(pts
			(xy 138.02487 -274.694396) (xy 138.02487 -274.649946) (xy 137.824718 -274.649946) (xy 137.824718 -274.694396)
			(xy 137.924794 -274.794472)
		)
		(stroke
			(width 0)
			(type solid)
		)
		(fill yes)
		(layer "In13.Cu")
		(net "M_H_CPU1_SB_DQ<2>")
	)
	(gr_poly
		(pts
			(xy 138.02487 -273.478244) (xy 137.924794 -273.378168) (xy 137.824718 -273.478244) (xy 137.824718 -273.522694)
			(xy 138.02487 -273.522694)
		)
		(stroke
			(width 0)
			(type solid)
		)
		(fill yes)
		(layer "In13.Cu")
		(net "M_H_CPU1_SB_CB<1>")
	)
	(gr_poly
		(pts
			(xy 138.02487 -273.074384) (xy 138.02487 -273.029934) (xy 137.824718 -273.029934) (xy 137.824718 -273.074384)
			(xy 137.924794 -273.17446)
		)
		(stroke
			(width 0)
			(type solid)
		)
		(fill yes)
		(layer "In13.Cu")
		(net "M_H_CPU1_SB_CB<2>")
	)
	(gr_poly
		(pts
			(xy 138.02487 -271.857978) (xy 137.924794 -271.758156) (xy 137.824718 -271.857978) (xy 137.824718 -271.90573)
			(xy 138.02487 -271.90573)
		)
		(stroke
			(width 0)
			(type solid)
		)
		(fill yes)
		(layer "In13.Cu")
		(net "M_H_CPU1_SB_DQS_DN<4>")
	)
	(gr_poly
		(pts
			(xy 138.02487 -271.454626) (xy 138.02487 -271.406874) (xy 137.824718 -271.406874) (xy 137.824718 -271.454626)
			(xy 137.924794 -271.554448)
		)
		(stroke
			(width 0)
			(type solid)
		)
		(fill yes)
		(layer "In13.Cu")
		(net "M_H_CPU1_SB_DQS_DN<9>")
	)
	(gr_poly
		(pts
			(xy 138.02487 -270.23822) (xy 137.924794 -270.138144) (xy 137.824718 -270.23822) (xy 137.824718 -270.28267)
			(xy 138.02487 -270.28267)
		)
		(stroke
			(width 0)
			(type solid)
		)
		(fill yes)
		(layer "In13.Cu")
		(net "M_H_CPU1_SB_CB<5>")
	)
	(gr_poly
		(pts
			(xy 138.02487 -269.83436) (xy 138.02487 -269.78991) (xy 137.824718 -269.78991) (xy 137.824718 -269.83436)
			(xy 137.924794 -269.934436)
		)
		(stroke
			(width 0)
			(type solid)
		)
		(fill yes)
		(layer "In13.Cu")
		(net "M_H_CPU1_SB_CB<6>")
	)
	(gr_poly
		(pts
			(xy 138.02487 -266.998196) (xy 137.924794 -266.89812) (xy 137.824718 -266.998196) (xy 137.824718 -267.042646)
			(xy 138.02487 -267.042646)
		)
		(stroke
			(width 0)
			(type solid)
		)
		(fill yes)
		(layer "In13.Cu")
		(net "M_H_CPU1_SA_RSP<0>")
	)
	(gr_poly
		(pts
			(xy 138.02487 -266.594336) (xy 138.02487 -266.549886) (xy 137.824718 -266.549886) (xy 137.824718 -266.594336)
			(xy 137.924794 -266.694412)
		)
		(stroke
			(width 0)
			(type solid)
		)
		(fill yes)
		(layer "In13.Cu")
		(net "M_H_CPU1_SB_CS_N<1>")
	)
	(gr_poly
		(pts
			(xy 138.02487 -265.378184) (xy 137.924794 -265.278108) (xy 137.824718 -265.378184) (xy 137.824718 -265.422634)
			(xy 138.02487 -265.422634)
		)
		(stroke
			(width 0)
			(type solid)
		)
		(fill yes)
		(layer "In13.Cu")
		(net "M_H_CPU1_SB_PAR")
	)
	(gr_poly
		(pts
			(xy 138.02487 -263.758172) (xy 137.924794 -263.658096) (xy 137.824718 -263.758172) (xy 137.824718 -263.802622)
			(xy 138.02487 -263.802622)
		)
		(stroke
			(width 0)
			(type solid)
		)
		(fill yes)
		(layer "In13.Cu")
		(net "M_H_CPU1_SB_CA<4>")
	)
	(gr_poly
		(pts
			(xy 138.02487 -263.354312) (xy 138.02487 -263.309862) (xy 137.824718 -263.309862) (xy 137.824718 -263.354312)
			(xy 137.924794 -263.454388)
		)
		(stroke
			(width 0)
			(type solid)
		)
		(fill yes)
		(layer "In13.Cu")
		(net "M_H_CPU1_SB_CA<3>")
	)
	(gr_poly
		(pts
			(xy 138.02487 -262.13816) (xy 137.924794 -262.038084) (xy 137.824718 -262.13816) (xy 137.824718 -262.18261)
			(xy 138.02487 -262.18261)
		)
		(stroke
			(width 0)
			(type solid)
		)
		(fill yes)
		(layer "In13.Cu")
		(net "M_H_CPU1_SB_CA<0>")
	)
	(gr_poly
		(pts
			(xy 138.194796 -256.432812) (xy 138.194796 -256.38506) (xy 137.994644 -256.38506) (xy 137.994644 -256.432812)
			(xy 138.09472 -256.532634)
		)
		(stroke
			(width 0)
			(type solid)
		)
		(fill yes)
		(layer "In13.Cu")
		(net "M_H_CPU1_CLK_DN<0>")
	)
	(gr_poly
		(pts
			(xy 138.194796 -255.216406) (xy 138.09472 -255.11633) (xy 137.994644 -255.216406) (xy 137.994644 -255.260856)
			(xy 138.194796 -255.260856)
		)
		(stroke
			(width 0)
			(type solid)
		)
		(fill yes)
		(layer "In13.Cu")
		(net "M_H_CPU1_SA_CA<6>")
	)
	(gr_poly
		(pts
			(xy 138.194796 -254.812546) (xy 138.194796 -254.768096) (xy 137.994644 -254.768096) (xy 137.994644 -254.812546)
			(xy 138.09472 -254.912622)
		)
		(stroke
			(width 0)
			(type solid)
		)
		(fill yes)
		(layer "In13.Cu")
		(net "M_H_CPU1_SA_CA<5>")
	)
	(gr_poly
		(pts
			(xy 138.194796 -253.596394) (xy 138.09472 -253.496318) (xy 137.994644 -253.596394) (xy 137.994644 -253.640844)
			(xy 138.194796 -253.640844)
		)
		(stroke
			(width 0)
			(type solid)
		)
		(fill yes)
		(layer "In13.Cu")
		(net "M_H_CPU1_SA_CA<2>")
	)
	(gr_poly
		(pts
			(xy 138.194796 -253.192534) (xy 138.194796 -253.148084) (xy 137.994644 -253.148084) (xy 137.994644 -253.192534)
			(xy 138.09472 -253.29261)
		)
		(stroke
			(width 0)
			(type solid)
		)
		(fill yes)
		(layer "In13.Cu")
		(net "M_H_CPU1_SA_CA<1>")
	)
	(gr_poly
		(pts
			(xy 138.194796 -251.976382) (xy 138.09472 -251.876306) (xy 137.994644 -251.976382) (xy 137.994644 -252.020832)
			(xy 138.194796 -252.020832)
		)
		(stroke
			(width 0)
			(type solid)
		)
		(fill yes)
		(layer "In13.Cu")
		(net "M_H_CPU1_SA_CS_N<1>")
	)
	(gr_poly
		(pts
			(xy 138.194796 -250.35637) (xy 138.09472 -250.256294) (xy 137.994644 -250.35637) (xy 137.994644 -250.40082)
			(xy 138.194796 -250.40082)
		)
		(stroke
			(width 0)
			(type solid)
		)
		(fill yes)
		(layer "In13.Cu")
		(net "M_H_CPU1_ALERT_R_N")
	)
	(gr_poly
		(pts
			(xy 138.194796 -248.736358) (xy 138.09472 -248.636282) (xy 137.994644 -248.736358) (xy 137.994644 -248.780808)
			(xy 138.194796 -248.780808)
		)
		(stroke
			(width 0)
			(type solid)
		)
		(fill yes)
		(layer "In13.Cu")
		(net "M_H_CPU1_SA_CB<5>")
	)
	(gr_poly
		(pts
			(xy 138.194796 -248.332498) (xy 138.194796 -248.288048) (xy 137.994644 -248.288048) (xy 137.994644 -248.332498)
			(xy 138.09472 -248.432574)
		)
		(stroke
			(width 0)
			(type solid)
		)
		(fill yes)
		(layer "In13.Cu")
		(net "M_H_CPU1_SA_CB<6>")
	)
	(gr_poly
		(pts
			(xy 138.194796 -247.116092) (xy 138.09472 -247.01627) (xy 137.994644 -247.116092) (xy 137.994644 -247.163844)
			(xy 138.194796 -247.163844)
		)
		(stroke
			(width 0)
			(type solid)
		)
		(fill yes)
		(layer "In13.Cu")
		(net "M_H_CPU1_SA_DQS_DN<9>")
	)
	(gr_poly
		(pts
			(xy 138.194796 -246.71274) (xy 138.194796 -246.664988) (xy 137.994644 -246.664988) (xy 137.994644 -246.71274)
			(xy 138.09472 -246.812562)
		)
		(stroke
			(width 0)
			(type solid)
		)
		(fill yes)
		(layer "In13.Cu")
		(net "M_H_CPU1_SA_DQS_DN<4>")
	)
	(gr_poly
		(pts
			(xy 138.194796 -245.496334) (xy 138.09472 -245.396258) (xy 137.994644 -245.496334) (xy 137.994644 -245.540784)
			(xy 138.194796 -245.540784)
		)
		(stroke
			(width 0)
			(type solid)
		)
		(fill yes)
		(layer "In13.Cu")
		(net "M_H_CPU1_SA_CB<1>")
	)
	(gr_poly
		(pts
			(xy 138.194796 -245.092474) (xy 138.194796 -245.048024) (xy 137.994644 -245.048024) (xy 137.994644 -245.092474)
			(xy 138.09472 -245.19255)
		)
		(stroke
			(width 0)
			(type solid)
		)
		(fill yes)
		(layer "In13.Cu")
		(net "M_H_CPU1_SA_CB<2>")
	)
	(gr_poly
		(pts
			(xy 138.194796 -243.876322) (xy 138.09472 -243.776246) (xy 137.994644 -243.876322) (xy 137.994644 -243.920772)
			(xy 138.194796 -243.920772)
		)
		(stroke
			(width 0)
			(type solid)
		)
		(fill yes)
		(layer "In13.Cu")
		(net "M_H_CPU1_SA_DQ<29>")
	)
	(gr_poly
		(pts
			(xy 138.194796 -243.472462) (xy 138.194796 -243.428012) (xy 137.994644 -243.428012) (xy 137.994644 -243.472462)
			(xy 138.09472 -243.572538)
		)
		(stroke
			(width 0)
			(type solid)
		)
		(fill yes)
		(layer "In13.Cu")
		(net "M_H_CPU1_SA_DQ<30>")
	)
	(gr_poly
		(pts
			(xy 138.194796 -242.256056) (xy 138.09472 -242.156234) (xy 137.994644 -242.256056) (xy 137.994644 -242.303808)
			(xy 138.194796 -242.303808)
		)
		(stroke
			(width 0)
			(type solid)
		)
		(fill yes)
		(layer "In13.Cu")
		(net "M_H_CPU1_SA_DQS_DN<8>")
	)
	(gr_poly
		(pts
			(xy 138.194796 -241.852704) (xy 138.194796 -241.804952) (xy 137.994644 -241.804952) (xy 137.994644 -241.852704)
			(xy 138.09472 -241.952526)
		)
		(stroke
			(width 0)
			(type solid)
		)
		(fill yes)
		(layer "In13.Cu")
		(net "M_H_CPU1_SA_DQS_DN<3>")
	)
	(gr_poly
		(pts
			(xy 138.194796 -240.636298) (xy 138.09472 -240.536222) (xy 137.994644 -240.636298) (xy 137.994644 -240.680748)
			(xy 138.194796 -240.680748)
		)
		(stroke
			(width 0)
			(type solid)
		)
		(fill yes)
		(layer "In13.Cu")
		(net "M_H_CPU1_SA_DQ<25>")
	)
	(gr_poly
		(pts
			(xy 138.194796 -240.232438) (xy 138.194796 -240.187988) (xy 137.994644 -240.187988) (xy 137.994644 -240.232438)
			(xy 138.09472 -240.332514)
		)
		(stroke
			(width 0)
			(type solid)
		)
		(fill yes)
		(layer "In13.Cu")
		(net "M_H_CPU1_SA_DQ<26>")
	)
	(gr_poly
		(pts
			(xy 138.194796 -239.016286) (xy 138.09472 -238.91621) (xy 137.994644 -239.016286) (xy 137.994644 -239.060736)
			(xy 138.194796 -239.060736)
		)
		(stroke
			(width 0)
			(type solid)
		)
		(fill yes)
		(layer "In13.Cu")
		(net "M_H_CPU1_SA_DQ<21>")
	)
	(gr_poly
		(pts
			(xy 138.194796 -238.612426) (xy 138.194796 -238.567976) (xy 137.994644 -238.567976) (xy 137.994644 -238.612426)
			(xy 138.09472 -238.712502)
		)
		(stroke
			(width 0)
			(type solid)
		)
		(fill yes)
		(layer "In13.Cu")
		(net "M_H_CPU1_SA_DQ<22>")
	)
	(gr_poly
		(pts
			(xy 138.194796 -237.39602) (xy 138.09472 -237.296198) (xy 137.994644 -237.39602) (xy 137.994644 -237.443772)
			(xy 138.194796 -237.443772)
		)
		(stroke
			(width 0)
			(type solid)
		)
		(fill yes)
		(layer "In13.Cu")
		(net "M_H_CPU1_SA_DQS_DN<7>")
	)
	(gr_poly
		(pts
			(xy 138.194796 -236.992668) (xy 138.194796 -236.944916) (xy 137.994644 -236.944916) (xy 137.994644 -236.992668)
			(xy 138.09472 -237.09249)
		)
		(stroke
			(width 0)
			(type solid)
		)
		(fill yes)
		(layer "In13.Cu")
		(net "M_H_CPU1_SA_DQS_DN<2>")
	)
	(gr_poly
		(pts
			(xy 138.194796 -235.776262) (xy 138.09472 -235.676186) (xy 137.994644 -235.776262) (xy 137.994644 -235.820712)
			(xy 138.194796 -235.820712)
		)
		(stroke
			(width 0)
			(type solid)
		)
		(fill yes)
		(layer "In13.Cu")
		(net "M_H_CPU1_SA_DQ<17>")
	)
	(gr_poly
		(pts
			(xy 138.194796 -235.372402) (xy 138.194796 -235.327952) (xy 137.994644 -235.327952) (xy 137.994644 -235.372402)
			(xy 138.09472 -235.472478)
		)
		(stroke
			(width 0)
			(type solid)
		)
		(fill yes)
		(layer "In13.Cu")
		(net "M_H_CPU1_SA_DQ<18>")
	)
	(gr_poly
		(pts
			(xy 138.194796 -234.15625) (xy 138.09472 -234.056174) (xy 137.994644 -234.15625) (xy 137.994644 -234.2007)
			(xy 138.194796 -234.2007)
		)
		(stroke
			(width 0)
			(type solid)
		)
		(fill yes)
		(layer "In13.Cu")
		(net "M_H_CPU1_SA_DQ<13>")
	)
	(gr_poly
		(pts
			(xy 138.194796 -233.75239) (xy 138.194796 -233.70794) (xy 137.994644 -233.70794) (xy 137.994644 -233.75239)
			(xy 138.09472 -233.852466)
		)
		(stroke
			(width 0)
			(type solid)
		)
		(fill yes)
		(layer "In13.Cu")
		(net "M_H_CPU1_SA_DQ<14>")
	)
	(gr_poly
		(pts
			(xy 138.194796 -232.535984) (xy 138.09472 -232.436162) (xy 137.994644 -232.535984) (xy 137.994644 -232.583736)
			(xy 138.194796 -232.583736)
		)
		(stroke
			(width 0)
			(type solid)
		)
		(fill yes)
		(layer "In13.Cu")
		(net "M_H_CPU1_SA_DQS_DN<6>")
	)
	(gr_poly
		(pts
			(xy 138.194796 -232.132632) (xy 138.194796 -232.08488) (xy 137.994644 -232.08488) (xy 137.994644 -232.132632)
			(xy 138.09472 -232.232454)
		)
		(stroke
			(width 0)
			(type solid)
		)
		(fill yes)
		(layer "In13.Cu")
		(net "M_H_CPU1_SA_DQS_DN<1>")
	)
	(gr_poly
		(pts
			(xy 138.194796 -230.916226) (xy 138.09472 -230.81615) (xy 137.994644 -230.916226) (xy 137.994644 -230.960676)
			(xy 138.194796 -230.960676)
		)
		(stroke
			(width 0)
			(type solid)
		)
		(fill yes)
		(layer "In13.Cu")
		(net "M_H_CPU1_SA_DQ<9>")
	)
	(gr_poly
		(pts
			(xy 138.194796 -230.51262) (xy 138.194796 -230.46817) (xy 137.994644 -230.46817) (xy 137.994644 -230.51262)
			(xy 138.09472 -230.612696)
		)
		(stroke
			(width 0)
			(type solid)
		)
		(fill yes)
		(layer "In13.Cu")
		(net "M_H_CPU1_SA_DQ<10>")
	)
	(gr_poly
		(pts
			(xy 138.194796 -229.296214) (xy 138.09472 -229.196138) (xy 137.994644 -229.296214) (xy 137.994644 -229.340664)
			(xy 138.194796 -229.340664)
		)
		(stroke
			(width 0)
			(type solid)
		)
		(fill yes)
		(layer "In13.Cu")
		(net "M_H_CPU1_SA_DQ<5>")
	)
	(gr_poly
		(pts
			(xy 138.194796 -228.892608) (xy 138.194796 -228.848158) (xy 137.994644 -228.848158) (xy 137.994644 -228.892608)
			(xy 138.09472 -228.992684)
		)
		(stroke
			(width 0)
			(type solid)
		)
		(fill yes)
		(layer "In13.Cu")
		(net "M_H_CPU1_SA_DQ<6>")
	)
	(gr_poly
		(pts
			(xy 138.194796 -227.676202) (xy 138.09472 -227.57638) (xy 137.994644 -227.676202) (xy 137.994644 -227.723954)
			(xy 138.194796 -227.723954)
		)
		(stroke
			(width 0)
			(type solid)
		)
		(fill yes)
		(layer "In13.Cu")
		(net "M_H_CPU1_SA_DQS_DN<5>")
	)
	(gr_poly
		(pts
			(xy 138.194796 -227.27285) (xy 138.194796 -227.225098) (xy 137.994644 -227.225098) (xy 137.994644 -227.27285)
			(xy 138.09472 -227.372672)
		)
		(stroke
			(width 0)
			(type solid)
		)
		(fill yes)
		(layer "In13.Cu")
		(net "M_H_CPU1_SA_DQS_DN<0>")
	)
	(gr_poly
		(pts
			(xy 138.194796 -226.056444) (xy 138.09472 -225.956368) (xy 137.994644 -226.056444) (xy 137.994644 -226.100894)
			(xy 138.194796 -226.100894)
		)
		(stroke
			(width 0)
			(type solid)
		)
		(fill yes)
		(layer "In13.Cu")
		(net "M_H_CPU1_SA_DQ<1>")
	)
	(gr_poly
		(pts
			(xy 138.194796 -225.652584) (xy 138.194796 -225.608134) (xy 137.994644 -225.608134) (xy 137.994644 -225.652584)
			(xy 138.09472 -225.75266)
		)
		(stroke
			(width 0)
			(type solid)
		)
		(fill yes)
		(layer "In13.Cu")
		(net "M_H_CPU1_SA_DQ<2>")
	)
	(gr_poly
		(pts
			(xy 138.49477 -293.32428) (xy 138.49477 -293.27983) (xy 138.294618 -293.27983) (xy 138.294618 -293.32428)
			(xy 138.394694 -293.424356)
		)
		(stroke
			(width 0)
			(type solid)
		)
		(fill yes)
		(layer "In13.Cu")
		(net "M_H_CPU1_SB_DQ<31>")
	)
	(gr_poly
		(pts
			(xy 138.49477 -292.108128) (xy 138.394694 -292.008052) (xy 138.294618 -292.108128) (xy 138.294618 -292.152578)
			(xy 138.49477 -292.152578)
		)
		(stroke
			(width 0)
			(type solid)
		)
		(fill yes)
		(layer "In13.Cu")
		(net "M_H_CPU1_SB_DQ<28>")
	)
	(gr_poly
		(pts
			(xy 138.49477 -291.704522) (xy 138.49477 -291.65677) (xy 138.294618 -291.65677) (xy 138.294618 -291.704522)
			(xy 138.394694 -291.804344)
		)
		(stroke
			(width 0)
			(type solid)
		)
		(fill yes)
		(layer "In13.Cu")
		(net "M_H_CPU1_SB_DQS_DP<8>")
	)
	(gr_poly
		(pts
			(xy 138.49477 -290.487862) (xy 138.394694 -290.38804) (xy 138.294618 -290.487862) (xy 138.294618 -290.535614)
			(xy 138.49477 -290.535614)
		)
		(stroke
			(width 0)
			(type solid)
		)
		(fill yes)
		(layer "In13.Cu")
		(net "M_H_CPU1_SB_DQS_DP<3>")
	)
	(gr_poly
		(pts
			(xy 138.49477 -290.084256) (xy 138.49477 -290.039806) (xy 138.294618 -290.039806) (xy 138.294618 -290.084256)
			(xy 138.394694 -290.184332)
		)
		(stroke
			(width 0)
			(type solid)
		)
		(fill yes)
		(layer "In13.Cu")
		(net "M_H_CPU1_SB_DQ<27>")
	)
	(gr_poly
		(pts
			(xy 138.49477 -288.868104) (xy 138.394694 -288.768028) (xy 138.294618 -288.868104) (xy 138.294618 -288.912554)
			(xy 138.49477 -288.912554)
		)
		(stroke
			(width 0)
			(type solid)
		)
		(fill yes)
		(layer "In13.Cu")
		(net "M_H_CPU1_SB_DQ<24>")
	)
	(gr_poly
		(pts
			(xy 138.49477 -288.464498) (xy 138.49477 -288.420048) (xy 138.294618 -288.420048) (xy 138.294618 -288.464498)
			(xy 138.394694 -288.564574)
		)
		(stroke
			(width 0)
			(type solid)
		)
		(fill yes)
		(layer "In13.Cu")
		(net "M_H_CPU1_SB_DQ<23>")
	)
	(gr_poly
		(pts
			(xy 138.49477 -287.248092) (xy 138.394694 -287.148016) (xy 138.294618 -287.248092) (xy 138.294618 -287.292542)
			(xy 138.49477 -287.292542)
		)
		(stroke
			(width 0)
			(type solid)
		)
		(fill yes)
		(layer "In13.Cu")
		(net "M_H_CPU1_SB_DQ<20>")
	)
	(gr_poly
		(pts
			(xy 138.49477 -286.844486) (xy 138.49477 -286.796734) (xy 138.294618 -286.796734) (xy 138.294618 -286.844486)
			(xy 138.394694 -286.944562)
		)
		(stroke
			(width 0)
			(type solid)
		)
		(fill yes)
		(layer "In13.Cu")
		(net "M_H_CPU1_SB_DQS_DP<7>")
	)
	(gr_poly
		(pts
			(xy 138.49477 -285.62808) (xy 138.394694 -285.528258) (xy 138.294618 -285.62808) (xy 138.294618 -285.675832)
			(xy 138.49477 -285.675832)
		)
		(stroke
			(width 0)
			(type solid)
		)
		(fill yes)
		(layer "In13.Cu")
		(net "M_H_CPU1_SB_DQS_DP<2>")
	)
	(gr_poly
		(pts
			(xy 138.49477 -285.224474) (xy 138.49477 -285.180024) (xy 138.294618 -285.180024) (xy 138.294618 -285.224474)
			(xy 138.394694 -285.32455)
		)
		(stroke
			(width 0)
			(type solid)
		)
		(fill yes)
		(layer "In13.Cu")
		(net "M_H_CPU1_SB_DQ<19>")
	)
	(gr_poly
		(pts
			(xy 138.49477 -284.008322) (xy 138.394694 -283.908246) (xy 138.294618 -284.008322) (xy 138.294618 -284.052772)
			(xy 138.49477 -284.052772)
		)
		(stroke
			(width 0)
			(type solid)
		)
		(fill yes)
		(layer "In13.Cu")
		(net "M_H_CPU1_SB_DQ<16>")
	)
	(gr_poly
		(pts
			(xy 138.49477 -283.604462) (xy 138.49477 -283.560012) (xy 138.294618 -283.560012) (xy 138.294618 -283.604462)
			(xy 138.394694 -283.704538)
		)
		(stroke
			(width 0)
			(type solid)
		)
		(fill yes)
		(layer "In13.Cu")
		(net "M_H_CPU1_SB_DQ<15>")
	)
	(gr_poly
		(pts
			(xy 138.49477 -282.38831) (xy 138.394694 -282.288234) (xy 138.294618 -282.38831) (xy 138.294618 -282.43276)
			(xy 138.49477 -282.43276)
		)
		(stroke
			(width 0)
			(type solid)
		)
		(fill yes)
		(layer "In13.Cu")
		(net "M_H_CPU1_SB_DQ<12>")
	)
	(gr_poly
		(pts
			(xy 138.49477 -281.984704) (xy 138.49477 -281.936952) (xy 138.294618 -281.936952) (xy 138.294618 -281.984704)
			(xy 138.394694 -282.084526)
		)
		(stroke
			(width 0)
			(type solid)
		)
		(fill yes)
		(layer "In13.Cu")
		(net "M_H_CPU1_SB_DQS_DP<6>")
	)
	(gr_poly
		(pts
			(xy 138.49477 -280.768044) (xy 138.394694 -280.668222) (xy 138.294618 -280.768044) (xy 138.294618 -280.815796)
			(xy 138.49477 -280.815796)
		)
		(stroke
			(width 0)
			(type solid)
		)
		(fill yes)
		(layer "In13.Cu")
		(net "M_H_CPU1_SB_DQS_DP<1>")
	)
	(gr_poly
		(pts
			(xy 138.49477 -280.364438) (xy 138.49477 -280.319988) (xy 138.294618 -280.319988) (xy 138.294618 -280.364438)
			(xy 138.394694 -280.464514)
		)
		(stroke
			(width 0)
			(type solid)
		)
		(fill yes)
		(layer "In13.Cu")
		(net "M_H_CPU1_SB_DQ<11>")
	)
	(gr_poly
		(pts
			(xy 138.49477 -279.148286) (xy 138.394694 -279.04821) (xy 138.294618 -279.148286) (xy 138.294618 -279.192736)
			(xy 138.49477 -279.192736)
		)
		(stroke
			(width 0)
			(type solid)
		)
		(fill yes)
		(layer "In13.Cu")
		(net "M_H_CPU1_SB_DQ<8>")
	)
	(gr_poly
		(pts
			(xy 138.49477 -278.744426) (xy 138.49477 -278.699976) (xy 138.294618 -278.699976) (xy 138.294618 -278.744426)
			(xy 138.394694 -278.844502)
		)
		(stroke
			(width 0)
			(type solid)
		)
		(fill yes)
		(layer "In13.Cu")
		(net "M_H_CPU1_SB_DQ<7>")
	)
	(gr_poly
		(pts
			(xy 138.49477 -277.528274) (xy 138.394694 -277.428198) (xy 138.294618 -277.528274) (xy 138.294618 -277.572724)
			(xy 138.49477 -277.572724)
		)
		(stroke
			(width 0)
			(type solid)
		)
		(fill yes)
		(layer "In13.Cu")
		(net "M_H_CPU1_SB_DQ<4>")
	)
	(gr_poly
		(pts
			(xy 138.49477 -277.124668) (xy 138.49477 -277.076916) (xy 138.294618 -277.076916) (xy 138.294618 -277.124668)
			(xy 138.394694 -277.22449)
		)
		(stroke
			(width 0)
			(type solid)
		)
		(fill yes)
		(layer "In13.Cu")
		(net "M_H_CPU1_SB_DQS_DP<5>")
	)
	(gr_poly
		(pts
			(xy 138.49477 -275.908008) (xy 138.394694 -275.808186) (xy 138.294618 -275.908008) (xy 138.294618 -275.95576)
			(xy 138.49477 -275.95576)
		)
		(stroke
			(width 0)
			(type solid)
		)
		(fill yes)
		(layer "In13.Cu")
		(net "M_H_CPU1_SB_DQS_DP<0>")
	)
	(gr_poly
		(pts
			(xy 138.49477 -275.504402) (xy 138.49477 -275.459952) (xy 138.294618 -275.459952) (xy 138.294618 -275.504402)
			(xy 138.394694 -275.604478)
		)
		(stroke
			(width 0)
			(type solid)
		)
		(fill yes)
		(layer "In13.Cu")
		(net "M_H_CPU1_SB_DQ<3>")
	)
	(gr_poly
		(pts
			(xy 138.49477 -274.28825) (xy 138.394694 -274.188174) (xy 138.294618 -274.28825) (xy 138.294618 -274.3327)
			(xy 138.49477 -274.3327)
		)
		(stroke
			(width 0)
			(type solid)
		)
		(fill yes)
		(layer "In13.Cu")
		(net "M_H_CPU1_SB_DQ<0>")
	)
	(gr_poly
		(pts
			(xy 138.49477 -273.88439) (xy 138.49477 -273.83994) (xy 138.294618 -273.83994) (xy 138.294618 -273.88439)
			(xy 138.394694 -273.984466)
		)
		(stroke
			(width 0)
			(type solid)
		)
		(fill yes)
		(layer "In13.Cu")
		(net "M_H_CPU1_SB_CB<3>")
	)
	(gr_poly
		(pts
			(xy 138.49477 -272.668238) (xy 138.394694 -272.568162) (xy 138.294618 -272.668238) (xy 138.294618 -272.712688)
			(xy 138.49477 -272.712688)
		)
		(stroke
			(width 0)
			(type solid)
		)
		(fill yes)
		(layer "In13.Cu")
		(net "M_H_CPU1_SB_CB<0>")
	)
	(gr_poly
		(pts
			(xy 138.49477 -272.264632) (xy 138.49477 -272.21688) (xy 138.294618 -272.21688) (xy 138.294618 -272.264632)
			(xy 138.394694 -272.364454)
		)
		(stroke
			(width 0)
			(type solid)
		)
		(fill yes)
		(layer "In13.Cu")
		(net "M_H_CPU1_SB_DQS_DP<4>")
	)
	(gr_poly
		(pts
			(xy 138.49477 -271.047972) (xy 138.394694 -270.94815) (xy 138.294618 -271.047972) (xy 138.294618 -271.095724)
			(xy 138.49477 -271.095724)
		)
		(stroke
			(width 0)
			(type solid)
		)
		(fill yes)
		(layer "In13.Cu")
		(net "M_H_CPU1_SB_DQS_DP<9>")
	)
	(gr_poly
		(pts
			(xy 138.49477 -270.644366) (xy 138.49477 -270.599916) (xy 138.294618 -270.599916) (xy 138.294618 -270.644366)
			(xy 138.394694 -270.744442)
		)
		(stroke
			(width 0)
			(type solid)
		)
		(fill yes)
		(layer "In13.Cu")
		(net "M_H_CPU1_SB_CB<7>")
	)
	(gr_poly
		(pts
			(xy 138.49477 -269.428214) (xy 138.394694 -269.328138) (xy 138.294618 -269.428214) (xy 138.294618 -269.472664)
			(xy 138.49477 -269.472664)
		)
		(stroke
			(width 0)
			(type solid)
		)
		(fill yes)
		(layer "In13.Cu")
		(net "M_H_CPU1_SB_CB<4>")
	)
	(gr_poly
		(pts
			(xy 138.49477 -267.808202) (xy 138.394694 -267.708126) (xy 138.294618 -267.808202) (xy 138.294618 -267.852652)
			(xy 138.49477 -267.852652)
		)
		(stroke
			(width 0)
			(type solid)
		)
		(fill yes)
		(layer "In13.Cu")
		(net "M_H_CPU1_SB_RSP<0>")
	)
	(gr_poly
		(pts
			(xy 138.49477 -265.78433) (xy 138.49477 -265.73988) (xy 138.294618 -265.73988) (xy 138.294618 -265.78433)
			(xy 138.394694 -265.884406)
		)
		(stroke
			(width 0)
			(type solid)
		)
		(fill yes)
		(layer "In13.Cu")
		(net "M_H_CPU1_SB_CS_N<0>")
	)
	(gr_poly
		(pts
			(xy 138.49477 -264.568178) (xy 138.394694 -264.468102) (xy 138.294618 -264.568178) (xy 138.294618 -264.612628)
			(xy 138.49477 -264.612628)
		)
		(stroke
			(width 0)
			(type solid)
		)
		(fill yes)
		(layer "In13.Cu")
		(net "M_H_CPU1_SB_CA<6>")
	)
	(gr_poly
		(pts
			(xy 138.49477 -264.164318) (xy 138.49477 -264.119868) (xy 138.294618 -264.119868) (xy 138.294618 -264.164318)
			(xy 138.394694 -264.264394)
		)
		(stroke
			(width 0)
			(type solid)
		)
		(fill yes)
		(layer "In13.Cu")
		(net "M_H_CPU1_SB_CA<5>")
	)
	(gr_poly
		(pts
			(xy 138.49477 -262.948166) (xy 138.394694 -262.84809) (xy 138.294618 -262.948166) (xy 138.294618 -262.992616)
			(xy 138.49477 -262.992616)
		)
		(stroke
			(width 0)
			(type solid)
		)
		(fill yes)
		(layer "In13.Cu")
		(net "M_H_CPU1_SB_CA<2>")
	)
	(gr_poly
		(pts
			(xy 138.49477 -262.544306) (xy 138.49477 -262.499856) (xy 138.294618 -262.499856) (xy 138.294618 -262.544306)
			(xy 138.394694 -262.644382)
		)
		(stroke
			(width 0)
			(type solid)
		)
		(fill yes)
		(layer "In13.Cu")
		(net "M_H_CPU1_SB_CA<1>")
	)
	(gr_poly
		(pts
			(xy 138.66495 -256.026158) (xy 138.564874 -255.926336) (xy 138.464798 -256.026158) (xy 138.464798 -256.07391)
			(xy 138.66495 -256.07391)
		)
		(stroke
			(width 0)
			(type solid)
		)
		(fill yes)
		(layer "In13.Cu")
		(net "M_H_CPU1_CLK_DP<0>")
	)
	(gr_poly
		(pts
			(xy 138.66495 -255.622552) (xy 138.66495 -255.578102) (xy 138.464798 -255.578102) (xy 138.464798 -255.622552)
			(xy 138.564874 -255.722628)
		)
		(stroke
			(width 0)
			(type solid)
		)
		(fill yes)
		(layer "In13.Cu")
		(net "M_H_CPU1_SA_PAR")
	)
	(gr_poly
		(pts
			(xy 138.66495 -254.4064) (xy 138.564874 -254.306324) (xy 138.464798 -254.4064) (xy 138.464798 -254.45085)
			(xy 138.66495 -254.45085)
		)
		(stroke
			(width 0)
			(type solid)
		)
		(fill yes)
		(layer "In13.Cu")
		(net "M_H_CPU1_SA_CA<4>")
	)
	(gr_poly
		(pts
			(xy 138.66495 -254.00254) (xy 138.66495 -253.95809) (xy 138.464798 -253.95809) (xy 138.464798 -254.00254)
			(xy 138.564874 -254.102616)
		)
		(stroke
			(width 0)
			(type solid)
		)
		(fill yes)
		(layer "In13.Cu")
		(net "M_H_CPU1_SA_CA<3>")
	)
	(gr_poly
		(pts
			(xy 138.66495 -252.786388) (xy 138.564874 -252.686312) (xy 138.464798 -252.786388) (xy 138.464798 -252.830838)
			(xy 138.66495 -252.830838)
		)
		(stroke
			(width 0)
			(type solid)
		)
		(fill yes)
		(layer "In13.Cu")
		(net "M_H_CPU1_SA_CA<0>")
	)
	(gr_poly
		(pts
			(xy 138.66495 -251.166376) (xy 138.564874 -251.0663) (xy 138.464798 -251.166376) (xy 138.464798 -251.210826)
			(xy 138.66495 -251.210826)
		)
		(stroke
			(width 0)
			(type solid)
		)
		(fill yes)
		(layer "In13.Cu")
		(net "M_H_CPU1_SA_CS_N<0>")
	)
	(gr_poly
		(pts
			(xy 138.66495 -250.762516) (xy 138.66495 -250.718066) (xy 138.464798 -250.718066) (xy 138.464798 -250.762516)
			(xy 138.564874 -250.862592)
		)
		(stroke
			(width 0)
			(type solid)
		)
		(fill yes)
		(layer "In13.Cu")
		(net "M_H_CPU1_RESET_N")
	)
	(gr_poly
		(pts
			(xy 138.66495 -249.142504) (xy 138.66495 -249.098054) (xy 138.464798 -249.098054) (xy 138.464798 -249.142504)
			(xy 138.564874 -249.24258)
		)
		(stroke
			(width 0)
			(type solid)
		)
		(fill yes)
		(layer "In13.Cu")
		(net "M_H_CPU1_SA_CB<7>")
	)
	(gr_poly
		(pts
			(xy 138.66495 -247.926352) (xy 138.564874 -247.826276) (xy 138.464798 -247.926352) (xy 138.464798 -247.970802)
			(xy 138.66495 -247.970802)
		)
		(stroke
			(width 0)
			(type solid)
		)
		(fill yes)
		(layer "In13.Cu")
		(net "M_H_CPU1_SA_CB<4>")
	)
	(gr_poly
		(pts
			(xy 138.66495 -247.522746) (xy 138.66495 -247.474994) (xy 138.464798 -247.474994) (xy 138.464798 -247.522746)
			(xy 138.564874 -247.622568)
		)
		(stroke
			(width 0)
			(type solid)
		)
		(fill yes)
		(layer "In13.Cu")
		(net "M_H_CPU1_SA_DQS_DP<9>")
	)
	(gr_poly
		(pts
			(xy 138.66495 -246.306086) (xy 138.564874 -246.206264) (xy 138.464798 -246.306086) (xy 138.464798 -246.353838)
			(xy 138.66495 -246.353838)
		)
		(stroke
			(width 0)
			(type solid)
		)
		(fill yes)
		(layer "In13.Cu")
		(net "M_H_CPU1_SA_DQS_DP<4>")
	)
	(gr_poly
		(pts
			(xy 138.66495 -245.90248) (xy 138.66495 -245.85803) (xy 138.464798 -245.85803) (xy 138.464798 -245.90248)
			(xy 138.564874 -246.002556)
		)
		(stroke
			(width 0)
			(type solid)
		)
		(fill yes)
		(layer "In13.Cu")
		(net "M_H_CPU1_SA_CB<3>")
	)
	(gr_poly
		(pts
			(xy 138.66495 -244.686328) (xy 138.564874 -244.586252) (xy 138.464798 -244.686328) (xy 138.464798 -244.730778)
			(xy 138.66495 -244.730778)
		)
		(stroke
			(width 0)
			(type solid)
		)
		(fill yes)
		(layer "In13.Cu")
		(net "M_H_CPU1_SA_CB<0>")
	)
	(gr_poly
		(pts
			(xy 138.66495 -244.282468) (xy 138.66495 -244.238018) (xy 138.464798 -244.238018) (xy 138.464798 -244.282468)
			(xy 138.564874 -244.382544)
		)
		(stroke
			(width 0)
			(type solid)
		)
		(fill yes)
		(layer "In13.Cu")
		(net "M_H_CPU1_SA_DQ<31>")
	)
	(gr_poly
		(pts
			(xy 138.66495 -243.066316) (xy 138.564874 -242.96624) (xy 138.464798 -243.066316) (xy 138.464798 -243.110766)
			(xy 138.66495 -243.110766)
		)
		(stroke
			(width 0)
			(type solid)
		)
		(fill yes)
		(layer "In13.Cu")
		(net "M_H_CPU1_SA_DQ<28>")
	)
	(gr_poly
		(pts
			(xy 138.66495 -242.66271) (xy 138.66495 -242.614958) (xy 138.464798 -242.614958) (xy 138.464798 -242.66271)
			(xy 138.564874 -242.762532)
		)
		(stroke
			(width 0)
			(type solid)
		)
		(fill yes)
		(layer "In13.Cu")
		(net "M_H_CPU1_SA_DQS_DP<8>")
	)
	(gr_poly
		(pts
			(xy 138.66495 -241.44605) (xy 138.564874 -241.346228) (xy 138.464798 -241.44605) (xy 138.464798 -241.493802)
			(xy 138.66495 -241.493802)
		)
		(stroke
			(width 0)
			(type solid)
		)
		(fill yes)
		(layer "In13.Cu")
		(net "M_H_CPU1_SA_DQS_DP<3>")
	)
	(gr_poly
		(pts
			(xy 138.66495 -241.042444) (xy 138.66495 -240.997994) (xy 138.464798 -240.997994) (xy 138.464798 -241.042444)
			(xy 138.564874 -241.14252)
		)
		(stroke
			(width 0)
			(type solid)
		)
		(fill yes)
		(layer "In13.Cu")
		(net "M_H_CPU1_SA_DQ<27>")
	)
	(gr_poly
		(pts
			(xy 138.66495 -239.826292) (xy 138.564874 -239.726216) (xy 138.464798 -239.826292) (xy 138.464798 -239.870742)
			(xy 138.66495 -239.870742)
		)
		(stroke
			(width 0)
			(type solid)
		)
		(fill yes)
		(layer "In13.Cu")
		(net "M_H_CPU1_SA_DQ<24>")
	)
	(gr_poly
		(pts
			(xy 138.66495 -239.422432) (xy 138.66495 -239.377982) (xy 138.464798 -239.377982) (xy 138.464798 -239.422432)
			(xy 138.564874 -239.522508)
		)
		(stroke
			(width 0)
			(type solid)
		)
		(fill yes)
		(layer "In13.Cu")
		(net "M_H_CPU1_SA_DQ<23>")
	)
	(gr_poly
		(pts
			(xy 138.66495 -238.20628) (xy 138.564874 -238.106204) (xy 138.464798 -238.20628) (xy 138.464798 -238.25073)
			(xy 138.66495 -238.25073)
		)
		(stroke
			(width 0)
			(type solid)
		)
		(fill yes)
		(layer "In13.Cu")
		(net "M_H_CPU1_SA_DQ<20>")
	)
	(gr_poly
		(pts
			(xy 138.66495 -237.802674) (xy 138.66495 -237.754922) (xy 138.464798 -237.754922) (xy 138.464798 -237.802674)
			(xy 138.564874 -237.902496)
		)
		(stroke
			(width 0)
			(type solid)
		)
		(fill yes)
		(layer "In13.Cu")
		(net "M_H_CPU1_SA_DQS_DP<7>")
	)
	(gr_poly
		(pts
			(xy 138.66495 -236.586014) (xy 138.564874 -236.486192) (xy 138.464798 -236.586014) (xy 138.464798 -236.633766)
			(xy 138.66495 -236.633766)
		)
		(stroke
			(width 0)
			(type solid)
		)
		(fill yes)
		(layer "In13.Cu")
		(net "M_H_CPU1_SA_DQS_DP<2>")
	)
	(gr_poly
		(pts
			(xy 138.66495 -236.182408) (xy 138.66495 -236.137958) (xy 138.464798 -236.137958) (xy 138.464798 -236.182408)
			(xy 138.564874 -236.282484)
		)
		(stroke
			(width 0)
			(type solid)
		)
		(fill yes)
		(layer "In13.Cu")
		(net "M_H_CPU1_SA_DQ<19>")
	)
	(gr_poly
		(pts
			(xy 138.66495 -234.966256) (xy 138.564874 -234.86618) (xy 138.464798 -234.966256) (xy 138.464798 -235.010706)
			(xy 138.66495 -235.010706)
		)
		(stroke
			(width 0)
			(type solid)
		)
		(fill yes)
		(layer "In13.Cu")
		(net "M_H_CPU1_SA_DQ<16>")
	)
	(gr_poly
		(pts
			(xy 138.66495 -234.562396) (xy 138.66495 -234.517946) (xy 138.464798 -234.517946) (xy 138.464798 -234.562396)
			(xy 138.564874 -234.662472)
		)
		(stroke
			(width 0)
			(type solid)
		)
		(fill yes)
		(layer "In13.Cu")
		(net "M_H_CPU1_SA_DQ<15>")
	)
	(gr_poly
		(pts
			(xy 138.66495 -233.346244) (xy 138.564874 -233.246168) (xy 138.464798 -233.346244) (xy 138.464798 -233.390694)
			(xy 138.66495 -233.390694)
		)
		(stroke
			(width 0)
			(type solid)
		)
		(fill yes)
		(layer "In13.Cu")
		(net "M_H_CPU1_SA_DQ<12>")
	)
	(gr_poly
		(pts
			(xy 138.66495 -232.942638) (xy 138.66495 -232.894886) (xy 138.464798 -232.894886) (xy 138.464798 -232.942638)
			(xy 138.564874 -233.04246)
		)
		(stroke
			(width 0)
			(type solid)
		)
		(fill yes)
		(layer "In13.Cu")
		(net "M_H_CPU1_SA_DQS_DP<6>")
	)
	(gr_poly
		(pts
			(xy 138.66495 -231.725978) (xy 138.564874 -231.626156) (xy 138.464798 -231.725978) (xy 138.464798 -231.77373)
			(xy 138.66495 -231.77373)
		)
		(stroke
			(width 0)
			(type solid)
		)
		(fill yes)
		(layer "In13.Cu")
		(net "M_H_CPU1_SA_DQS_DP<1>")
	)
	(gr_poly
		(pts
			(xy 138.66495 -231.322626) (xy 138.66495 -231.278176) (xy 138.464798 -231.278176) (xy 138.464798 -231.322626)
			(xy 138.564874 -231.422702)
		)
		(stroke
			(width 0)
			(type solid)
		)
		(fill yes)
		(layer "In13.Cu")
		(net "M_H_CPU1_SA_DQ<11>")
	)
	(gr_poly
		(pts
			(xy 138.66495 -230.10622) (xy 138.564874 -230.006144) (xy 138.464798 -230.10622) (xy 138.464798 -230.15067)
			(xy 138.66495 -230.15067)
		)
		(stroke
			(width 0)
			(type solid)
		)
		(fill yes)
		(layer "In13.Cu")
		(net "M_H_CPU1_SA_DQ<8>")
	)
	(gr_poly
		(pts
			(xy 138.66495 -229.702614) (xy 138.66495 -229.658164) (xy 138.464798 -229.658164) (xy 138.464798 -229.702614)
			(xy 138.564874 -229.80269)
		)
		(stroke
			(width 0)
			(type solid)
		)
		(fill yes)
		(layer "In13.Cu")
		(net "M_H_CPU1_SA_DQ<7>")
	)
	(gr_poly
		(pts
			(xy 138.66495 -228.486462) (xy 138.564874 -228.386386) (xy 138.464798 -228.486462) (xy 138.464798 -228.530912)
			(xy 138.66495 -228.530912)
		)
		(stroke
			(width 0)
			(type solid)
		)
		(fill yes)
		(layer "In13.Cu")
		(net "M_H_CPU1_SA_DQ<4>")
	)
	(gr_poly
		(pts
			(xy 138.66495 -228.082856) (xy 138.66495 -228.035104) (xy 138.464798 -228.035104) (xy 138.464798 -228.082856)
			(xy 138.564874 -228.182678)
		)
		(stroke
			(width 0)
			(type solid)
		)
		(fill yes)
		(layer "In13.Cu")
		(net "M_H_CPU1_SA_DQS_DP<5>")
	)
	(gr_poly
		(pts
			(xy 138.66495 -226.866196) (xy 138.564874 -226.766374) (xy 138.464798 -226.866196) (xy 138.464798 -226.913948)
			(xy 138.66495 -226.913948)
		)
		(stroke
			(width 0)
			(type solid)
		)
		(fill yes)
		(layer "In13.Cu")
		(net "M_H_CPU1_SA_DQS_DP<0>")
	)
	(gr_poly
		(pts
			(xy 138.66495 -226.46259) (xy 138.66495 -226.41814) (xy 138.464798 -226.41814) (xy 138.464798 -226.46259)
			(xy 138.564874 -226.562666)
		)
		(stroke
			(width 0)
			(type solid)
		)
		(fill yes)
		(layer "In13.Cu")
		(net "M_H_CPU1_SA_DQ<3>")
	)
	(gr_poly
		(pts
			(xy 138.66495 -225.246438) (xy 138.564874 -225.146362) (xy 138.464798 -225.246438) (xy 138.464798 -225.290888)
			(xy 138.66495 -225.290888)
		)
		(stroke
			(width 0)
			(type solid)
		)
		(fill yes)
		(layer "In13.Cu")
		(net "M_H_CPU1_SA_DQ<0>")
	)
	(gr_poly
		(pts
			(xy 138.964924 -292.918134) (xy 138.864848 -292.818058) (xy 138.764772 -292.918134) (xy 138.764772 -292.962584)
			(xy 138.964924 -292.962584)
		)
		(stroke
			(width 0)
			(type solid)
		)
		(fill yes)
		(layer "In13.Cu")
		(net "M_H_CPU1_SB_DQ<29>")
	)
	(gr_poly
		(pts
			(xy 138.964924 -292.514274) (xy 138.964924 -292.469824) (xy 138.764772 -292.469824) (xy 138.764772 -292.514274)
			(xy 138.864848 -292.61435)
		)
		(stroke
			(width 0)
			(type solid)
		)
		(fill yes)
		(layer "In13.Cu")
		(net "M_H_CPU1_SB_DQ<30>")
	)
	(gr_poly
		(pts
			(xy 138.964924 -291.297868) (xy 138.864848 -291.198046) (xy 138.764772 -291.297868) (xy 138.764772 -291.34562)
			(xy 138.964924 -291.34562)
		)
		(stroke
			(width 0)
			(type solid)
		)
		(fill yes)
		(layer "In13.Cu")
		(net "M_H_CPU1_SB_DQS_DN<8>")
	)
	(gr_poly
		(pts
			(xy 138.964924 -290.894516) (xy 138.964924 -290.846764) (xy 138.764772 -290.846764) (xy 138.764772 -290.894516)
			(xy 138.864848 -290.994338)
		)
		(stroke
			(width 0)
			(type solid)
		)
		(fill yes)
		(layer "In13.Cu")
		(net "M_H_CPU1_SB_DQS_DN<3>")
	)
	(gr_poly
		(pts
			(xy 138.964924 -289.67811) (xy 138.864848 -289.578034) (xy 138.764772 -289.67811) (xy 138.764772 -289.72256)
			(xy 138.964924 -289.72256)
		)
		(stroke
			(width 0)
			(type solid)
		)
		(fill yes)
		(layer "In13.Cu")
		(net "M_H_CPU1_SB_DQ<25>")
	)
	(gr_poly
		(pts
			(xy 138.964924 -289.27425) (xy 138.964924 -289.2298) (xy 138.764772 -289.2298) (xy 138.764772 -289.27425)
			(xy 138.864848 -289.374326)
		)
		(stroke
			(width 0)
			(type solid)
		)
		(fill yes)
		(layer "In13.Cu")
		(net "M_H_CPU1_SB_DQ<26>")
	)
	(gr_poly
		(pts
			(xy 138.964924 -288.058098) (xy 138.864848 -287.958022) (xy 138.764772 -288.058098) (xy 138.764772 -288.102548)
			(xy 138.964924 -288.102548)
		)
		(stroke
			(width 0)
			(type solid)
		)
		(fill yes)
		(layer "In13.Cu")
		(net "M_H_CPU1_SB_DQ<21>")
	)
	(gr_poly
		(pts
			(xy 138.964924 -287.654492) (xy 138.964924 -287.610042) (xy 138.764772 -287.610042) (xy 138.764772 -287.654492)
			(xy 138.864848 -287.754568)
		)
		(stroke
			(width 0)
			(type solid)
		)
		(fill yes)
		(layer "In13.Cu")
		(net "M_H_CPU1_SB_DQ<22>")
	)
	(gr_poly
		(pts
			(xy 138.964924 -286.438086) (xy 138.864848 -286.33801) (xy 138.764772 -286.438086) (xy 138.764772 -286.485838)
			(xy 138.964924 -286.485838)
		)
		(stroke
			(width 0)
			(type solid)
		)
		(fill yes)
		(layer "In13.Cu")
		(net "M_H_CPU1_SB_DQS_DN<7>")
	)
	(gr_poly
		(pts
			(xy 138.964924 -286.034734) (xy 138.964924 -285.986982) (xy 138.764772 -285.986982) (xy 138.764772 -286.034734)
			(xy 138.864848 -286.134556)
		)
		(stroke
			(width 0)
			(type solid)
		)
		(fill yes)
		(layer "In13.Cu")
		(net "M_H_CPU1_SB_DQS_DN<2>")
	)
	(gr_poly
		(pts
			(xy 138.964924 -284.818328) (xy 138.864848 -284.718252) (xy 138.764772 -284.818328) (xy 138.764772 -284.862778)
			(xy 138.964924 -284.862778)
		)
		(stroke
			(width 0)
			(type solid)
		)
		(fill yes)
		(layer "In13.Cu")
		(net "M_H_CPU1_SB_DQ<17>")
	)
	(gr_poly
		(pts
			(xy 138.964924 -284.414468) (xy 138.964924 -284.370018) (xy 138.764772 -284.370018) (xy 138.764772 -284.414468)
			(xy 138.864848 -284.514544)
		)
		(stroke
			(width 0)
			(type solid)
		)
		(fill yes)
		(layer "In13.Cu")
		(net "M_H_CPU1_SB_DQ<18>")
	)
	(gr_poly
		(pts
			(xy 138.964924 -283.198316) (xy 138.864848 -283.09824) (xy 138.764772 -283.198316) (xy 138.764772 -283.242766)
			(xy 138.964924 -283.242766)
		)
		(stroke
			(width 0)
			(type solid)
		)
		(fill yes)
		(layer "In13.Cu")
		(net "M_H_CPU1_SB_DQ<13>")
	)
	(gr_poly
		(pts
			(xy 138.964924 -282.794456) (xy 138.964924 -282.750006) (xy 138.764772 -282.750006) (xy 138.764772 -282.794456)
			(xy 138.864848 -282.894532)
		)
		(stroke
			(width 0)
			(type solid)
		)
		(fill yes)
		(layer "In13.Cu")
		(net "M_H_CPU1_SB_DQ<14>")
	)
	(gr_poly
		(pts
			(xy 138.964924 -281.57805) (xy 138.864848 -281.478228) (xy 138.764772 -281.57805) (xy 138.764772 -281.625802)
			(xy 138.964924 -281.625802)
		)
		(stroke
			(width 0)
			(type solid)
		)
		(fill yes)
		(layer "In13.Cu")
		(net "M_H_CPU1_SB_DQS_DN<6>")
	)
	(gr_poly
		(pts
			(xy 138.964924 -281.174698) (xy 138.964924 -281.126946) (xy 138.764772 -281.126946) (xy 138.764772 -281.174698)
			(xy 138.864848 -281.27452)
		)
		(stroke
			(width 0)
			(type solid)
		)
		(fill yes)
		(layer "In13.Cu")
		(net "M_H_CPU1_SB_DQS_DN<1>")
	)
	(gr_poly
		(pts
			(xy 138.964924 -279.958292) (xy 138.864848 -279.858216) (xy 138.764772 -279.958292) (xy 138.764772 -280.002742)
			(xy 138.964924 -280.002742)
		)
		(stroke
			(width 0)
			(type solid)
		)
		(fill yes)
		(layer "In13.Cu")
		(net "M_H_CPU1_SB_DQ<9>")
	)
	(gr_poly
		(pts
			(xy 138.964924 -279.554432) (xy 138.964924 -279.509982) (xy 138.764772 -279.509982) (xy 138.764772 -279.554432)
			(xy 138.864848 -279.654508)
		)
		(stroke
			(width 0)
			(type solid)
		)
		(fill yes)
		(layer "In13.Cu")
		(net "M_H_CPU1_SB_DQ<10>")
	)
	(gr_poly
		(pts
			(xy 138.964924 -278.33828) (xy 138.864848 -278.238204) (xy 138.764772 -278.33828) (xy 138.764772 -278.38273)
			(xy 138.964924 -278.38273)
		)
		(stroke
			(width 0)
			(type solid)
		)
		(fill yes)
		(layer "In13.Cu")
		(net "M_H_CPU1_SB_DQ<5>")
	)
	(gr_poly
		(pts
			(xy 138.964924 -277.93442) (xy 138.964924 -277.88997) (xy 138.764772 -277.88997) (xy 138.764772 -277.93442)
			(xy 138.864848 -278.034496)
		)
		(stroke
			(width 0)
			(type solid)
		)
		(fill yes)
		(layer "In13.Cu")
		(net "M_H_CPU1_SB_DQ<6>")
	)
	(gr_poly
		(pts
			(xy 138.964924 -276.718014) (xy 138.864848 -276.618192) (xy 138.764772 -276.718014) (xy 138.764772 -276.765766)
			(xy 138.964924 -276.765766)
		)
		(stroke
			(width 0)
			(type solid)
		)
		(fill yes)
		(layer "In13.Cu")
		(net "M_H_CPU1_SB_DQS_DN<5>")
	)
	(gr_poly
		(pts
			(xy 138.964924 -276.314662) (xy 138.964924 -276.26691) (xy 138.764772 -276.26691) (xy 138.764772 -276.314662)
			(xy 138.864848 -276.414484)
		)
		(stroke
			(width 0)
			(type solid)
		)
		(fill yes)
		(layer "In13.Cu")
		(net "M_H_CPU1_SB_DQS_DN<0>")
	)
	(gr_poly
		(pts
			(xy 138.964924 -275.098256) (xy 138.864848 -274.99818) (xy 138.764772 -275.098256) (xy 138.764772 -275.142706)
			(xy 138.964924 -275.142706)
		)
		(stroke
			(width 0)
			(type solid)
		)
		(fill yes)
		(layer "In13.Cu")
		(net "M_H_CPU1_SB_DQ<1>")
	)
	(gr_poly
		(pts
			(xy 138.964924 -274.694396) (xy 138.964924 -274.649946) (xy 138.764772 -274.649946) (xy 138.764772 -274.694396)
			(xy 138.864848 -274.794472)
		)
		(stroke
			(width 0)
			(type solid)
		)
		(fill yes)
		(layer "In13.Cu")
		(net "M_H_CPU1_SB_DQ<2>")
	)
	(gr_poly
		(pts
			(xy 138.964924 -273.478244) (xy 138.864848 -273.378168) (xy 138.764772 -273.478244) (xy 138.764772 -273.522694)
			(xy 138.964924 -273.522694)
		)
		(stroke
			(width 0)
			(type solid)
		)
		(fill yes)
		(layer "In13.Cu")
		(net "M_H_CPU1_SB_CB<1>")
	)
	(gr_poly
		(pts
			(xy 138.964924 -273.074384) (xy 138.964924 -273.029934) (xy 138.764772 -273.029934) (xy 138.764772 -273.074384)
			(xy 138.864848 -273.17446)
		)
		(stroke
			(width 0)
			(type solid)
		)
		(fill yes)
		(layer "In13.Cu")
		(net "M_H_CPU1_SB_CB<2>")
	)
	(gr_poly
		(pts
			(xy 138.964924 -271.857978) (xy 138.864848 -271.758156) (xy 138.764772 -271.857978) (xy 138.764772 -271.90573)
			(xy 138.964924 -271.90573)
		)
		(stroke
			(width 0)
			(type solid)
		)
		(fill yes)
		(layer "In13.Cu")
		(net "M_H_CPU1_SB_DQS_DN<4>")
	)
	(gr_poly
		(pts
			(xy 138.964924 -271.454626) (xy 138.964924 -271.406874) (xy 138.764772 -271.406874) (xy 138.764772 -271.454626)
			(xy 138.864848 -271.554448)
		)
		(stroke
			(width 0)
			(type solid)
		)
		(fill yes)
		(layer "In13.Cu")
		(net "M_H_CPU1_SB_DQS_DN<9>")
	)
	(gr_poly
		(pts
			(xy 138.964924 -270.23822) (xy 138.864848 -270.138144) (xy 138.764772 -270.23822) (xy 138.764772 -270.28267)
			(xy 138.964924 -270.28267)
		)
		(stroke
			(width 0)
			(type solid)
		)
		(fill yes)
		(layer "In13.Cu")
		(net "M_H_CPU1_SB_CB<5>")
	)
	(gr_poly
		(pts
			(xy 138.964924 -269.83436) (xy 138.964924 -269.78991) (xy 138.764772 -269.78991) (xy 138.764772 -269.83436)
			(xy 138.864848 -269.934436)
		)
		(stroke
			(width 0)
			(type solid)
		)
		(fill yes)
		(layer "In13.Cu")
		(net "M_H_CPU1_SB_CB<6>")
	)
	(gr_poly
		(pts
			(xy 138.964924 -266.998196) (xy 138.864848 -266.89812) (xy 138.764772 -266.998196) (xy 138.764772 -267.042646)
			(xy 138.964924 -267.042646)
		)
		(stroke
			(width 0)
			(type solid)
		)
		(fill yes)
		(layer "In13.Cu")
		(net "M_H_CPU1_SA_RSP<0>")
	)
	(gr_poly
		(pts
			(xy 138.964924 -266.594336) (xy 138.964924 -266.549886) (xy 138.764772 -266.549886) (xy 138.764772 -266.594336)
			(xy 138.864848 -266.694412)
		)
		(stroke
			(width 0)
			(type solid)
		)
		(fill yes)
		(layer "In13.Cu")
		(net "M_H_CPU1_SB_CS_N<1>")
	)
	(gr_poly
		(pts
			(xy 138.964924 -265.378184) (xy 138.864848 -265.278108) (xy 138.764772 -265.378184) (xy 138.764772 -265.422634)
			(xy 138.964924 -265.422634)
		)
		(stroke
			(width 0)
			(type solid)
		)
		(fill yes)
		(layer "In13.Cu")
		(net "M_H_CPU1_SB_PAR")
	)
	(gr_poly
		(pts
			(xy 138.964924 -263.758172) (xy 138.864848 -263.658096) (xy 138.764772 -263.758172) (xy 138.764772 -263.802622)
			(xy 138.964924 -263.802622)
		)
		(stroke
			(width 0)
			(type solid)
		)
		(fill yes)
		(layer "In13.Cu")
		(net "M_H_CPU1_SB_CA<4>")
	)
	(gr_poly
		(pts
			(xy 138.964924 -263.354312) (xy 138.964924 -263.309862) (xy 138.764772 -263.309862) (xy 138.764772 -263.354312)
			(xy 138.864848 -263.454388)
		)
		(stroke
			(width 0)
			(type solid)
		)
		(fill yes)
		(layer "In13.Cu")
		(net "M_H_CPU1_SB_CA<3>")
	)
	(gr_poly
		(pts
			(xy 138.964924 -262.13816) (xy 138.864848 -262.038084) (xy 138.764772 -262.13816) (xy 138.764772 -262.18261)
			(xy 138.964924 -262.18261)
		)
		(stroke
			(width 0)
			(type solid)
		)
		(fill yes)
		(layer "In13.Cu")
		(net "M_H_CPU1_SB_CA<0>")
	)
	(gr_poly
		(pts
			(xy 139.13485 -256.432812) (xy 139.13485 -256.38506) (xy 138.934698 -256.38506) (xy 138.934698 -256.432812)
			(xy 139.034774 -256.532634)
		)
		(stroke
			(width 0)
			(type solid)
		)
		(fill yes)
		(layer "In13.Cu")
		(net "M_H_CPU1_CLK_DN<0>")
	)
	(gr_poly
		(pts
			(xy 139.13485 -255.216406) (xy 139.034774 -255.11633) (xy 138.934698 -255.216406) (xy 138.934698 -255.260856)
			(xy 139.13485 -255.260856)
		)
		(stroke
			(width 0)
			(type solid)
		)
		(fill yes)
		(layer "In13.Cu")
		(net "M_H_CPU1_SA_CA<6>")
	)
	(gr_poly
		(pts
			(xy 139.13485 -254.812546) (xy 139.13485 -254.768096) (xy 138.934698 -254.768096) (xy 138.934698 -254.812546)
			(xy 139.034774 -254.912622)
		)
		(stroke
			(width 0)
			(type solid)
		)
		(fill yes)
		(layer "In13.Cu")
		(net "M_H_CPU1_SA_CA<5>")
	)
	(gr_poly
		(pts
			(xy 139.13485 -253.596394) (xy 139.034774 -253.496318) (xy 138.934698 -253.596394) (xy 138.934698 -253.640844)
			(xy 139.13485 -253.640844)
		)
		(stroke
			(width 0)
			(type solid)
		)
		(fill yes)
		(layer "In13.Cu")
		(net "M_H_CPU1_SA_CA<2>")
	)
	(gr_poly
		(pts
			(xy 139.13485 -253.192534) (xy 139.13485 -253.148084) (xy 138.934698 -253.148084) (xy 138.934698 -253.192534)
			(xy 139.034774 -253.29261)
		)
		(stroke
			(width 0)
			(type solid)
		)
		(fill yes)
		(layer "In13.Cu")
		(net "M_H_CPU1_SA_CA<1>")
	)
	(gr_poly
		(pts
			(xy 139.13485 -251.976382) (xy 139.034774 -251.876306) (xy 138.934698 -251.976382) (xy 138.934698 -252.020832)
			(xy 139.13485 -252.020832)
		)
		(stroke
			(width 0)
			(type solid)
		)
		(fill yes)
		(layer "In13.Cu")
		(net "M_H_CPU1_SA_CS_N<1>")
	)
	(gr_poly
		(pts
			(xy 139.13485 -250.35637) (xy 139.034774 -250.256294) (xy 138.934698 -250.35637) (xy 138.934698 -250.40082)
			(xy 139.13485 -250.40082)
		)
		(stroke
			(width 0)
			(type solid)
		)
		(fill yes)
		(layer "In13.Cu")
		(net "M_H_CPU1_ALERT_R_N")
	)
	(gr_poly
		(pts
			(xy 139.13485 -248.736358) (xy 139.034774 -248.636282) (xy 138.934698 -248.736358) (xy 138.934698 -248.780808)
			(xy 139.13485 -248.780808)
		)
		(stroke
			(width 0)
			(type solid)
		)
		(fill yes)
		(layer "In13.Cu")
		(net "M_H_CPU1_SA_CB<5>")
	)
	(gr_poly
		(pts
			(xy 139.13485 -248.332498) (xy 139.13485 -248.288048) (xy 138.934698 -248.288048) (xy 138.934698 -248.332498)
			(xy 139.034774 -248.432574)
		)
		(stroke
			(width 0)
			(type solid)
		)
		(fill yes)
		(layer "In13.Cu")
		(net "M_H_CPU1_SA_CB<6>")
	)
	(gr_poly
		(pts
			(xy 139.13485 -247.116092) (xy 139.034774 -247.01627) (xy 138.934698 -247.116092) (xy 138.934698 -247.163844)
			(xy 139.13485 -247.163844)
		)
		(stroke
			(width 0)
			(type solid)
		)
		(fill yes)
		(layer "In13.Cu")
		(net "M_H_CPU1_SA_DQS_DN<9>")
	)
	(gr_poly
		(pts
			(xy 139.13485 -246.71274) (xy 139.13485 -246.664988) (xy 138.934698 -246.664988) (xy 138.934698 -246.71274)
			(xy 139.034774 -246.812562)
		)
		(stroke
			(width 0)
			(type solid)
		)
		(fill yes)
		(layer "In13.Cu")
		(net "M_H_CPU1_SA_DQS_DN<4>")
	)
	(gr_poly
		(pts
			(xy 139.13485 -245.496334) (xy 139.034774 -245.396258) (xy 138.934698 -245.496334) (xy 138.934698 -245.540784)
			(xy 139.13485 -245.540784)
		)
		(stroke
			(width 0)
			(type solid)
		)
		(fill yes)
		(layer "In13.Cu")
		(net "M_H_CPU1_SA_CB<1>")
	)
	(gr_poly
		(pts
			(xy 139.13485 -245.092474) (xy 139.13485 -245.048024) (xy 138.934698 -245.048024) (xy 138.934698 -245.092474)
			(xy 139.034774 -245.19255)
		)
		(stroke
			(width 0)
			(type solid)
		)
		(fill yes)
		(layer "In13.Cu")
		(net "M_H_CPU1_SA_CB<2>")
	)
	(gr_poly
		(pts
			(xy 139.13485 -243.876322) (xy 139.034774 -243.776246) (xy 138.934698 -243.876322) (xy 138.934698 -243.920772)
			(xy 139.13485 -243.920772)
		)
		(stroke
			(width 0)
			(type solid)
		)
		(fill yes)
		(layer "In13.Cu")
		(net "M_H_CPU1_SA_DQ<29>")
	)
	(gr_poly
		(pts
			(xy 139.13485 -243.472462) (xy 139.13485 -243.428012) (xy 138.934698 -243.428012) (xy 138.934698 -243.472462)
			(xy 139.034774 -243.572538)
		)
		(stroke
			(width 0)
			(type solid)
		)
		(fill yes)
		(layer "In13.Cu")
		(net "M_H_CPU1_SA_DQ<30>")
	)
	(gr_poly
		(pts
			(xy 139.13485 -242.256056) (xy 139.034774 -242.156234) (xy 138.934698 -242.256056) (xy 138.934698 -242.303808)
			(xy 139.13485 -242.303808)
		)
		(stroke
			(width 0)
			(type solid)
		)
		(fill yes)
		(layer "In13.Cu")
		(net "M_H_CPU1_SA_DQS_DN<8>")
	)
	(gr_poly
		(pts
			(xy 139.13485 -241.852704) (xy 139.13485 -241.804952) (xy 138.934698 -241.804952) (xy 138.934698 -241.852704)
			(xy 139.034774 -241.952526)
		)
		(stroke
			(width 0)
			(type solid)
		)
		(fill yes)
		(layer "In13.Cu")
		(net "M_H_CPU1_SA_DQS_DN<3>")
	)
	(gr_poly
		(pts
			(xy 139.13485 -240.636298) (xy 139.034774 -240.536222) (xy 138.934698 -240.636298) (xy 138.934698 -240.680748)
			(xy 139.13485 -240.680748)
		)
		(stroke
			(width 0)
			(type solid)
		)
		(fill yes)
		(layer "In13.Cu")
		(net "M_H_CPU1_SA_DQ<25>")
	)
	(gr_poly
		(pts
			(xy 139.13485 -240.232438) (xy 139.13485 -240.187988) (xy 138.934698 -240.187988) (xy 138.934698 -240.232438)
			(xy 139.034774 -240.332514)
		)
		(stroke
			(width 0)
			(type solid)
		)
		(fill yes)
		(layer "In13.Cu")
		(net "M_H_CPU1_SA_DQ<26>")
	)
	(gr_poly
		(pts
			(xy 139.13485 -239.016286) (xy 139.034774 -238.91621) (xy 138.934698 -239.016286) (xy 138.934698 -239.060736)
			(xy 139.13485 -239.060736)
		)
		(stroke
			(width 0)
			(type solid)
		)
		(fill yes)
		(layer "In13.Cu")
		(net "M_H_CPU1_SA_DQ<21>")
	)
	(gr_poly
		(pts
			(xy 139.13485 -238.612426) (xy 139.13485 -238.567976) (xy 138.934698 -238.567976) (xy 138.934698 -238.612426)
			(xy 139.034774 -238.712502)
		)
		(stroke
			(width 0)
			(type solid)
		)
		(fill yes)
		(layer "In13.Cu")
		(net "M_H_CPU1_SA_DQ<22>")
	)
	(gr_poly
		(pts
			(xy 139.13485 -237.39602) (xy 139.034774 -237.296198) (xy 138.934698 -237.39602) (xy 138.934698 -237.443772)
			(xy 139.13485 -237.443772)
		)
		(stroke
			(width 0)
			(type solid)
		)
		(fill yes)
		(layer "In13.Cu")
		(net "M_H_CPU1_SA_DQS_DN<7>")
	)
	(gr_poly
		(pts
			(xy 139.13485 -236.992668) (xy 139.13485 -236.944916) (xy 138.934698 -236.944916) (xy 138.934698 -236.992668)
			(xy 139.034774 -237.09249)
		)
		(stroke
			(width 0)
			(type solid)
		)
		(fill yes)
		(layer "In13.Cu")
		(net "M_H_CPU1_SA_DQS_DN<2>")
	)
	(gr_poly
		(pts
			(xy 139.13485 -235.776262) (xy 139.034774 -235.676186) (xy 138.934698 -235.776262) (xy 138.934698 -235.820712)
			(xy 139.13485 -235.820712)
		)
		(stroke
			(width 0)
			(type solid)
		)
		(fill yes)
		(layer "In13.Cu")
		(net "M_H_CPU1_SA_DQ<17>")
	)
	(gr_poly
		(pts
			(xy 139.13485 -235.372402) (xy 139.13485 -235.327952) (xy 138.934698 -235.327952) (xy 138.934698 -235.372402)
			(xy 139.034774 -235.472478)
		)
		(stroke
			(width 0)
			(type solid)
		)
		(fill yes)
		(layer "In13.Cu")
		(net "M_H_CPU1_SA_DQ<18>")
	)
	(gr_poly
		(pts
			(xy 139.13485 -234.15625) (xy 139.034774 -234.056174) (xy 138.934698 -234.15625) (xy 138.934698 -234.2007)
			(xy 139.13485 -234.2007)
		)
		(stroke
			(width 0)
			(type solid)
		)
		(fill yes)
		(layer "In13.Cu")
		(net "M_H_CPU1_SA_DQ<13>")
	)
	(gr_poly
		(pts
			(xy 139.13485 -233.75239) (xy 139.13485 -233.70794) (xy 138.934698 -233.70794) (xy 138.934698 -233.75239)
			(xy 139.034774 -233.852466)
		)
		(stroke
			(width 0)
			(type solid)
		)
		(fill yes)
		(layer "In13.Cu")
		(net "M_H_CPU1_SA_DQ<14>")
	)
	(gr_poly
		(pts
			(xy 139.13485 -232.535984) (xy 139.034774 -232.436162) (xy 138.934698 -232.535984) (xy 138.934698 -232.583736)
			(xy 139.13485 -232.583736)
		)
		(stroke
			(width 0)
			(type solid)
		)
		(fill yes)
		(layer "In13.Cu")
		(net "M_H_CPU1_SA_DQS_DN<6>")
	)
	(gr_poly
		(pts
			(xy 139.13485 -232.132632) (xy 139.13485 -232.08488) (xy 138.934698 -232.08488) (xy 138.934698 -232.132632)
			(xy 139.034774 -232.232454)
		)
		(stroke
			(width 0)
			(type solid)
		)
		(fill yes)
		(layer "In13.Cu")
		(net "M_H_CPU1_SA_DQS_DN<1>")
	)
	(gr_poly
		(pts
			(xy 139.13485 -230.916226) (xy 139.034774 -230.81615) (xy 138.934698 -230.916226) (xy 138.934698 -230.960676)
			(xy 139.13485 -230.960676)
		)
		(stroke
			(width 0)
			(type solid)
		)
		(fill yes)
		(layer "In13.Cu")
		(net "M_H_CPU1_SA_DQ<9>")
	)
	(gr_poly
		(pts
			(xy 139.13485 -230.51262) (xy 139.13485 -230.46817) (xy 138.934698 -230.46817) (xy 138.934698 -230.51262)
			(xy 139.034774 -230.612696)
		)
		(stroke
			(width 0)
			(type solid)
		)
		(fill yes)
		(layer "In13.Cu")
		(net "M_H_CPU1_SA_DQ<10>")
	)
	(gr_poly
		(pts
			(xy 139.13485 -229.296214) (xy 139.034774 -229.196138) (xy 138.934698 -229.296214) (xy 138.934698 -229.340664)
			(xy 139.13485 -229.340664)
		)
		(stroke
			(width 0)
			(type solid)
		)
		(fill yes)
		(layer "In13.Cu")
		(net "M_H_CPU1_SA_DQ<5>")
	)
	(gr_poly
		(pts
			(xy 139.13485 -228.892608) (xy 139.13485 -228.848158) (xy 138.934698 -228.848158) (xy 138.934698 -228.892608)
			(xy 139.034774 -228.992684)
		)
		(stroke
			(width 0)
			(type solid)
		)
		(fill yes)
		(layer "In13.Cu")
		(net "M_H_CPU1_SA_DQ<6>")
	)
	(gr_poly
		(pts
			(xy 139.13485 -227.676202) (xy 139.034774 -227.57638) (xy 138.934698 -227.676202) (xy 138.934698 -227.723954)
			(xy 139.13485 -227.723954)
		)
		(stroke
			(width 0)
			(type solid)
		)
		(fill yes)
		(layer "In13.Cu")
		(net "M_H_CPU1_SA_DQS_DN<5>")
	)
	(gr_poly
		(pts
			(xy 139.13485 -227.27285) (xy 139.13485 -227.225098) (xy 138.934698 -227.225098) (xy 138.934698 -227.27285)
			(xy 139.034774 -227.372672)
		)
		(stroke
			(width 0)
			(type solid)
		)
		(fill yes)
		(layer "In13.Cu")
		(net "M_H_CPU1_SA_DQS_DN<0>")
	)
	(gr_poly
		(pts
			(xy 139.13485 -226.056444) (xy 139.034774 -225.956368) (xy 138.934698 -226.056444) (xy 138.934698 -226.100894)
			(xy 139.13485 -226.100894)
		)
		(stroke
			(width 0)
			(type solid)
		)
		(fill yes)
		(layer "In13.Cu")
		(net "M_H_CPU1_SA_DQ<1>")
	)
	(gr_poly
		(pts
			(xy 139.13485 -225.652584) (xy 139.13485 -225.608134) (xy 138.934698 -225.608134) (xy 138.934698 -225.652584)
			(xy 139.034774 -225.75266)
		)
		(stroke
			(width 0)
			(type solid)
		)
		(fill yes)
		(layer "In13.Cu")
		(net "M_H_CPU1_SA_DQ<2>")
	)
	(gr_poly
		(pts
			(xy 139.434824 -293.32428) (xy 139.434824 -293.27983) (xy 139.234672 -293.27983) (xy 139.234672 -293.32428)
			(xy 139.334748 -293.424356)
		)
		(stroke
			(width 0)
			(type solid)
		)
		(fill yes)
		(layer "In13.Cu")
		(net "M_H_CPU1_SB_DQ<31>")
	)
	(gr_poly
		(pts
			(xy 139.434824 -292.108128) (xy 139.334748 -292.008052) (xy 139.234672 -292.108128) (xy 139.234672 -292.152578)
			(xy 139.434824 -292.152578)
		)
		(stroke
			(width 0)
			(type solid)
		)
		(fill yes)
		(layer "In13.Cu")
		(net "M_H_CPU1_SB_DQ<28>")
	)
	(gr_poly
		(pts
			(xy 139.434824 -291.704522) (xy 139.434824 -291.65677) (xy 139.234672 -291.65677) (xy 139.234672 -291.704522)
			(xy 139.334748 -291.804344)
		)
		(stroke
			(width 0)
			(type solid)
		)
		(fill yes)
		(layer "In13.Cu")
		(net "M_H_CPU1_SB_DQS_DP<8>")
	)
	(gr_poly
		(pts
			(xy 139.434824 -290.487862) (xy 139.334748 -290.38804) (xy 139.234672 -290.487862) (xy 139.234672 -290.535614)
			(xy 139.434824 -290.535614)
		)
		(stroke
			(width 0)
			(type solid)
		)
		(fill yes)
		(layer "In13.Cu")
		(net "M_H_CPU1_SB_DQS_DP<3>")
	)
	(gr_poly
		(pts
			(xy 139.434824 -290.084256) (xy 139.434824 -290.039806) (xy 139.234672 -290.039806) (xy 139.234672 -290.084256)
			(xy 139.334748 -290.184332)
		)
		(stroke
			(width 0)
			(type solid)
		)
		(fill yes)
		(layer "In13.Cu")
		(net "M_H_CPU1_SB_DQ<27>")
	)
	(gr_poly
		(pts
			(xy 139.434824 -288.868104) (xy 139.334748 -288.768028) (xy 139.234672 -288.868104) (xy 139.234672 -288.912554)
			(xy 139.434824 -288.912554)
		)
		(stroke
			(width 0)
			(type solid)
		)
		(fill yes)
		(layer "In13.Cu")
		(net "M_H_CPU1_SB_DQ<24>")
	)
	(gr_poly
		(pts
			(xy 139.434824 -288.464498) (xy 139.434824 -288.420048) (xy 139.234672 -288.420048) (xy 139.234672 -288.464498)
			(xy 139.334748 -288.564574)
		)
		(stroke
			(width 0)
			(type solid)
		)
		(fill yes)
		(layer "In13.Cu")
		(net "M_H_CPU1_SB_DQ<23>")
	)
	(gr_poly
		(pts
			(xy 139.434824 -287.248092) (xy 139.334748 -287.148016) (xy 139.234672 -287.248092) (xy 139.234672 -287.292542)
			(xy 139.434824 -287.292542)
		)
		(stroke
			(width 0)
			(type solid)
		)
		(fill yes)
		(layer "In13.Cu")
		(net "M_H_CPU1_SB_DQ<20>")
	)
	(gr_poly
		(pts
			(xy 139.434824 -286.844486) (xy 139.434824 -286.796734) (xy 139.234672 -286.796734) (xy 139.234672 -286.844486)
			(xy 139.334748 -286.944562)
		)
		(stroke
			(width 0)
			(type solid)
		)
		(fill yes)
		(layer "In13.Cu")
		(net "M_H_CPU1_SB_DQS_DP<7>")
	)
	(gr_poly
		(pts
			(xy 139.434824 -285.62808) (xy 139.334748 -285.528258) (xy 139.234672 -285.62808) (xy 139.234672 -285.675832)
			(xy 139.434824 -285.675832)
		)
		(stroke
			(width 0)
			(type solid)
		)
		(fill yes)
		(layer "In13.Cu")
		(net "M_H_CPU1_SB_DQS_DP<2>")
	)
	(gr_poly
		(pts
			(xy 139.434824 -285.224474) (xy 139.434824 -285.180024) (xy 139.234672 -285.180024) (xy 139.234672 -285.224474)
			(xy 139.334748 -285.32455)
		)
		(stroke
			(width 0)
			(type solid)
		)
		(fill yes)
		(layer "In13.Cu")
		(net "M_H_CPU1_SB_DQ<19>")
	)
	(gr_poly
		(pts
			(xy 139.434824 -284.008322) (xy 139.334748 -283.908246) (xy 139.234672 -284.008322) (xy 139.234672 -284.052772)
			(xy 139.434824 -284.052772)
		)
		(stroke
			(width 0)
			(type solid)
		)
		(fill yes)
		(layer "In13.Cu")
		(net "M_H_CPU1_SB_DQ<16>")
	)
	(gr_poly
		(pts
			(xy 139.434824 -283.604462) (xy 139.434824 -283.560012) (xy 139.234672 -283.560012) (xy 139.234672 -283.604462)
			(xy 139.334748 -283.704538)
		)
		(stroke
			(width 0)
			(type solid)
		)
		(fill yes)
		(layer "In13.Cu")
		(net "M_H_CPU1_SB_DQ<15>")
	)
	(gr_poly
		(pts
			(xy 139.434824 -282.38831) (xy 139.334748 -282.288234) (xy 139.234672 -282.38831) (xy 139.234672 -282.43276)
			(xy 139.434824 -282.43276)
		)
		(stroke
			(width 0)
			(type solid)
		)
		(fill yes)
		(layer "In13.Cu")
		(net "M_H_CPU1_SB_DQ<12>")
	)
	(gr_poly
		(pts
			(xy 139.434824 -281.984704) (xy 139.434824 -281.936952) (xy 139.234672 -281.936952) (xy 139.234672 -281.984704)
			(xy 139.334748 -282.084526)
		)
		(stroke
			(width 0)
			(type solid)
		)
		(fill yes)
		(layer "In13.Cu")
		(net "M_H_CPU1_SB_DQS_DP<6>")
	)
	(gr_poly
		(pts
			(xy 139.434824 -280.768044) (xy 139.334748 -280.668222) (xy 139.234672 -280.768044) (xy 139.234672 -280.815796)
			(xy 139.434824 -280.815796)
		)
		(stroke
			(width 0)
			(type solid)
		)
		(fill yes)
		(layer "In13.Cu")
		(net "M_H_CPU1_SB_DQS_DP<1>")
	)
	(gr_poly
		(pts
			(xy 139.434824 -280.364438) (xy 139.434824 -280.319988) (xy 139.234672 -280.319988) (xy 139.234672 -280.364438)
			(xy 139.334748 -280.464514)
		)
		(stroke
			(width 0)
			(type solid)
		)
		(fill yes)
		(layer "In13.Cu")
		(net "M_H_CPU1_SB_DQ<11>")
	)
	(gr_poly
		(pts
			(xy 139.434824 -279.148286) (xy 139.334748 -279.04821) (xy 139.234672 -279.148286) (xy 139.234672 -279.192736)
			(xy 139.434824 -279.192736)
		)
		(stroke
			(width 0)
			(type solid)
		)
		(fill yes)
		(layer "In13.Cu")
		(net "M_H_CPU1_SB_DQ<8>")
	)
	(gr_poly
		(pts
			(xy 139.434824 -278.744426) (xy 139.434824 -278.699976) (xy 139.234672 -278.699976) (xy 139.234672 -278.744426)
			(xy 139.334748 -278.844502)
		)
		(stroke
			(width 0)
			(type solid)
		)
		(fill yes)
		(layer "In13.Cu")
		(net "M_H_CPU1_SB_DQ<7>")
	)
	(gr_poly
		(pts
			(xy 139.434824 -277.528274) (xy 139.334748 -277.428198) (xy 139.234672 -277.528274) (xy 139.234672 -277.572724)
			(xy 139.434824 -277.572724)
		)
		(stroke
			(width 0)
			(type solid)
		)
		(fill yes)
		(layer "In13.Cu")
		(net "M_H_CPU1_SB_DQ<4>")
	)
	(gr_poly
		(pts
			(xy 139.434824 -277.124668) (xy 139.434824 -277.076916) (xy 139.234672 -277.076916) (xy 139.234672 -277.124668)
			(xy 139.334748 -277.22449)
		)
		(stroke
			(width 0)
			(type solid)
		)
		(fill yes)
		(layer "In13.Cu")
		(net "M_H_CPU1_SB_DQS_DP<5>")
	)
	(gr_poly
		(pts
			(xy 139.434824 -275.908008) (xy 139.334748 -275.808186) (xy 139.234672 -275.908008) (xy 139.234672 -275.95576)
			(xy 139.434824 -275.95576)
		)
		(stroke
			(width 0)
			(type solid)
		)
		(fill yes)
		(layer "In13.Cu")
		(net "M_H_CPU1_SB_DQS_DP<0>")
	)
	(gr_poly
		(pts
			(xy 139.434824 -275.504402) (xy 139.434824 -275.459952) (xy 139.234672 -275.459952) (xy 139.234672 -275.504402)
			(xy 139.334748 -275.604478)
		)
		(stroke
			(width 0)
			(type solid)
		)
		(fill yes)
		(layer "In13.Cu")
		(net "M_H_CPU1_SB_DQ<3>")
	)
	(gr_poly
		(pts
			(xy 139.434824 -274.28825) (xy 139.334748 -274.188174) (xy 139.234672 -274.28825) (xy 139.234672 -274.3327)
			(xy 139.434824 -274.3327)
		)
		(stroke
			(width 0)
			(type solid)
		)
		(fill yes)
		(layer "In13.Cu")
		(net "M_H_CPU1_SB_DQ<0>")
	)
	(gr_poly
		(pts
			(xy 139.434824 -273.88439) (xy 139.434824 -273.83994) (xy 139.234672 -273.83994) (xy 139.234672 -273.88439)
			(xy 139.334748 -273.984466)
		)
		(stroke
			(width 0)
			(type solid)
		)
		(fill yes)
		(layer "In13.Cu")
		(net "M_H_CPU1_SB_CB<3>")
	)
	(gr_poly
		(pts
			(xy 139.434824 -272.668238) (xy 139.334748 -272.568162) (xy 139.234672 -272.668238) (xy 139.234672 -272.712688)
			(xy 139.434824 -272.712688)
		)
		(stroke
			(width 0)
			(type solid)
		)
		(fill yes)
		(layer "In13.Cu")
		(net "M_H_CPU1_SB_CB<0>")
	)
	(gr_poly
		(pts
			(xy 139.434824 -272.264632) (xy 139.434824 -272.21688) (xy 139.234672 -272.21688) (xy 139.234672 -272.264632)
			(xy 139.334748 -272.364454)
		)
		(stroke
			(width 0)
			(type solid)
		)
		(fill yes)
		(layer "In13.Cu")
		(net "M_H_CPU1_SB_DQS_DP<4>")
	)
	(gr_poly
		(pts
			(xy 139.434824 -271.047972) (xy 139.334748 -270.94815) (xy 139.234672 -271.047972) (xy 139.234672 -271.095724)
			(xy 139.434824 -271.095724)
		)
		(stroke
			(width 0)
			(type solid)
		)
		(fill yes)
		(layer "In13.Cu")
		(net "M_H_CPU1_SB_DQS_DP<9>")
	)
	(gr_poly
		(pts
			(xy 139.434824 -270.644366) (xy 139.434824 -270.599916) (xy 139.234672 -270.599916) (xy 139.234672 -270.644366)
			(xy 139.334748 -270.744442)
		)
		(stroke
			(width 0)
			(type solid)
		)
		(fill yes)
		(layer "In13.Cu")
		(net "M_H_CPU1_SB_CB<7>")
	)
	(gr_poly
		(pts
			(xy 139.434824 -269.428214) (xy 139.334748 -269.328138) (xy 139.234672 -269.428214) (xy 139.234672 -269.472664)
			(xy 139.434824 -269.472664)
		)
		(stroke
			(width 0)
			(type solid)
		)
		(fill yes)
		(layer "In13.Cu")
		(net "M_H_CPU1_SB_CB<4>")
	)
	(gr_poly
		(pts
			(xy 139.434824 -267.808202) (xy 139.334748 -267.708126) (xy 139.234672 -267.808202) (xy 139.234672 -267.852652)
			(xy 139.434824 -267.852652)
		)
		(stroke
			(width 0)
			(type solid)
		)
		(fill yes)
		(layer "In13.Cu")
		(net "M_H_CPU1_SB_RSP<0>")
	)
	(gr_poly
		(pts
			(xy 139.434824 -265.78433) (xy 139.434824 -265.73988) (xy 139.234672 -265.73988) (xy 139.234672 -265.78433)
			(xy 139.334748 -265.884406)
		)
		(stroke
			(width 0)
			(type solid)
		)
		(fill yes)
		(layer "In13.Cu")
		(net "M_H_CPU1_SB_CS_N<0>")
	)
	(gr_poly
		(pts
			(xy 139.434824 -264.568178) (xy 139.334748 -264.468102) (xy 139.234672 -264.568178) (xy 139.234672 -264.612628)
			(xy 139.434824 -264.612628)
		)
		(stroke
			(width 0)
			(type solid)
		)
		(fill yes)
		(layer "In13.Cu")
		(net "M_H_CPU1_SB_CA<6>")
	)
	(gr_poly
		(pts
			(xy 139.434824 -264.164318) (xy 139.434824 -264.119868) (xy 139.234672 -264.119868) (xy 139.234672 -264.164318)
			(xy 139.334748 -264.264394)
		)
		(stroke
			(width 0)
			(type solid)
		)
		(fill yes)
		(layer "In13.Cu")
		(net "M_H_CPU1_SB_CA<5>")
	)
	(gr_poly
		(pts
			(xy 139.434824 -262.948166) (xy 139.334748 -262.84809) (xy 139.234672 -262.948166) (xy 139.234672 -262.992616)
			(xy 139.434824 -262.992616)
		)
		(stroke
			(width 0)
			(type solid)
		)
		(fill yes)
		(layer "In13.Cu")
		(net "M_H_CPU1_SB_CA<2>")
	)
	(gr_poly
		(pts
			(xy 139.434824 -262.544306) (xy 139.434824 -262.499856) (xy 139.234672 -262.499856) (xy 139.234672 -262.544306)
			(xy 139.334748 -262.644382)
		)
		(stroke
			(width 0)
			(type solid)
		)
		(fill yes)
		(layer "In13.Cu")
		(net "M_H_CPU1_SB_CA<1>")
	)
	(gr_poly
		(pts
			(xy 139.60475 -256.026158) (xy 139.504674 -255.926336) (xy 139.404598 -256.026158) (xy 139.404598 -256.07391)
			(xy 139.60475 -256.07391)
		)
		(stroke
			(width 0)
			(type solid)
		)
		(fill yes)
		(layer "In13.Cu")
		(net "M_H_CPU1_CLK_DP<0>")
	)
	(gr_poly
		(pts
			(xy 139.60475 -255.622552) (xy 139.60475 -255.578102) (xy 139.404598 -255.578102) (xy 139.404598 -255.622552)
			(xy 139.504674 -255.722628)
		)
		(stroke
			(width 0)
			(type solid)
		)
		(fill yes)
		(layer "In13.Cu")
		(net "M_H_CPU1_SA_PAR")
	)
	(gr_poly
		(pts
			(xy 139.60475 -254.4064) (xy 139.504674 -254.306324) (xy 139.404598 -254.4064) (xy 139.404598 -254.45085)
			(xy 139.60475 -254.45085)
		)
		(stroke
			(width 0)
			(type solid)
		)
		(fill yes)
		(layer "In13.Cu")
		(net "M_H_CPU1_SA_CA<4>")
	)
	(gr_poly
		(pts
			(xy 139.60475 -254.00254) (xy 139.60475 -253.95809) (xy 139.404598 -253.95809) (xy 139.404598 -254.00254)
			(xy 139.504674 -254.102616)
		)
		(stroke
			(width 0)
			(type solid)
		)
		(fill yes)
		(layer "In13.Cu")
		(net "M_H_CPU1_SA_CA<3>")
	)
	(gr_poly
		(pts
			(xy 139.60475 -252.786388) (xy 139.504674 -252.686312) (xy 139.404598 -252.786388) (xy 139.404598 -252.830838)
			(xy 139.60475 -252.830838)
		)
		(stroke
			(width 0)
			(type solid)
		)
		(fill yes)
		(layer "In13.Cu")
		(net "M_H_CPU1_SA_CA<0>")
	)
	(gr_poly
		(pts
			(xy 139.60475 -251.166376) (xy 139.504674 -251.0663) (xy 139.404598 -251.166376) (xy 139.404598 -251.210826)
			(xy 139.60475 -251.210826)
		)
		(stroke
			(width 0)
			(type solid)
		)
		(fill yes)
		(layer "In13.Cu")
		(net "M_H_CPU1_SA_CS_N<0>")
	)
	(gr_poly
		(pts
			(xy 139.60475 -250.762516) (xy 139.60475 -250.718066) (xy 139.404598 -250.718066) (xy 139.404598 -250.762516)
			(xy 139.504674 -250.862592)
		)
		(stroke
			(width 0)
			(type solid)
		)
		(fill yes)
		(layer "In13.Cu")
		(net "M_H_CPU1_RESET_N")
	)
	(gr_poly
		(pts
			(xy 139.60475 -249.142504) (xy 139.60475 -249.098054) (xy 139.404598 -249.098054) (xy 139.404598 -249.142504)
			(xy 139.504674 -249.24258)
		)
		(stroke
			(width 0)
			(type solid)
		)
		(fill yes)
		(layer "In13.Cu")
		(net "M_H_CPU1_SA_CB<7>")
	)
	(gr_poly
		(pts
			(xy 139.60475 -247.926352) (xy 139.504674 -247.826276) (xy 139.404598 -247.926352) (xy 139.404598 -247.970802)
			(xy 139.60475 -247.970802)
		)
		(stroke
			(width 0)
			(type solid)
		)
		(fill yes)
		(layer "In13.Cu")
		(net "M_H_CPU1_SA_CB<4>")
	)
	(gr_poly
		(pts
			(xy 139.60475 -247.522746) (xy 139.60475 -247.474994) (xy 139.404598 -247.474994) (xy 139.404598 -247.522746)
			(xy 139.504674 -247.622568)
		)
		(stroke
			(width 0)
			(type solid)
		)
		(fill yes)
		(layer "In13.Cu")
		(net "M_H_CPU1_SA_DQS_DP<9>")
	)
	(gr_poly
		(pts
			(xy 139.60475 -246.306086) (xy 139.504674 -246.206264) (xy 139.404598 -246.306086) (xy 139.404598 -246.353838)
			(xy 139.60475 -246.353838)
		)
		(stroke
			(width 0)
			(type solid)
		)
		(fill yes)
		(layer "In13.Cu")
		(net "M_H_CPU1_SA_DQS_DP<4>")
	)
	(gr_poly
		(pts
			(xy 139.60475 -245.90248) (xy 139.60475 -245.85803) (xy 139.404598 -245.85803) (xy 139.404598 -245.90248)
			(xy 139.504674 -246.002556)
		)
		(stroke
			(width 0)
			(type solid)
		)
		(fill yes)
		(layer "In13.Cu")
		(net "M_H_CPU1_SA_CB<3>")
	)
	(gr_poly
		(pts
			(xy 139.60475 -244.686328) (xy 139.504674 -244.586252) (xy 139.404598 -244.686328) (xy 139.404598 -244.730778)
			(xy 139.60475 -244.730778)
		)
		(stroke
			(width 0)
			(type solid)
		)
		(fill yes)
		(layer "In13.Cu")
		(net "M_H_CPU1_SA_CB<0>")
	)
	(gr_poly
		(pts
			(xy 139.60475 -244.282468) (xy 139.60475 -244.238018) (xy 139.404598 -244.238018) (xy 139.404598 -244.282468)
			(xy 139.504674 -244.382544)
		)
		(stroke
			(width 0)
			(type solid)
		)
		(fill yes)
		(layer "In13.Cu")
		(net "M_H_CPU1_SA_DQ<31>")
	)
	(gr_poly
		(pts
			(xy 139.60475 -243.066316) (xy 139.504674 -242.96624) (xy 139.404598 -243.066316) (xy 139.404598 -243.110766)
			(xy 139.60475 -243.110766)
		)
		(stroke
			(width 0)
			(type solid)
		)
		(fill yes)
		(layer "In13.Cu")
		(net "M_H_CPU1_SA_DQ<28>")
	)
	(gr_poly
		(pts
			(xy 139.60475 -242.66271) (xy 139.60475 -242.614958) (xy 139.404598 -242.614958) (xy 139.404598 -242.66271)
			(xy 139.504674 -242.762532)
		)
		(stroke
			(width 0)
			(type solid)
		)
		(fill yes)
		(layer "In13.Cu")
		(net "M_H_CPU1_SA_DQS_DP<8>")
	)
	(gr_poly
		(pts
			(xy 139.60475 -241.44605) (xy 139.504674 -241.346228) (xy 139.404598 -241.44605) (xy 139.404598 -241.493802)
			(xy 139.60475 -241.493802)
		)
		(stroke
			(width 0)
			(type solid)
		)
		(fill yes)
		(layer "In13.Cu")
		(net "M_H_CPU1_SA_DQS_DP<3>")
	)
	(gr_poly
		(pts
			(xy 139.60475 -241.042444) (xy 139.60475 -240.997994) (xy 139.404598 -240.997994) (xy 139.404598 -241.042444)
			(xy 139.504674 -241.14252)
		)
		(stroke
			(width 0)
			(type solid)
		)
		(fill yes)
		(layer "In13.Cu")
		(net "M_H_CPU1_SA_DQ<27>")
	)
	(gr_poly
		(pts
			(xy 139.60475 -239.826292) (xy 139.504674 -239.726216) (xy 139.404598 -239.826292) (xy 139.404598 -239.870742)
			(xy 139.60475 -239.870742)
		)
		(stroke
			(width 0)
			(type solid)
		)
		(fill yes)
		(layer "In13.Cu")
		(net "M_H_CPU1_SA_DQ<24>")
	)
	(gr_poly
		(pts
			(xy 139.60475 -239.422432) (xy 139.60475 -239.377982) (xy 139.404598 -239.377982) (xy 139.404598 -239.422432)
			(xy 139.504674 -239.522508)
		)
		(stroke
			(width 0)
			(type solid)
		)
		(fill yes)
		(layer "In13.Cu")
		(net "M_H_CPU1_SA_DQ<23>")
	)
	(gr_poly
		(pts
			(xy 139.60475 -238.20628) (xy 139.504674 -238.106204) (xy 139.404598 -238.20628) (xy 139.404598 -238.25073)
			(xy 139.60475 -238.25073)
		)
		(stroke
			(width 0)
			(type solid)
		)
		(fill yes)
		(layer "In13.Cu")
		(net "M_H_CPU1_SA_DQ<20>")
	)
	(gr_poly
		(pts
			(xy 139.60475 -237.802674) (xy 139.60475 -237.754922) (xy 139.404598 -237.754922) (xy 139.404598 -237.802674)
			(xy 139.504674 -237.902496)
		)
		(stroke
			(width 0)
			(type solid)
		)
		(fill yes)
		(layer "In13.Cu")
		(net "M_H_CPU1_SA_DQS_DP<7>")
	)
	(gr_poly
		(pts
			(xy 139.60475 -236.586014) (xy 139.504674 -236.486192) (xy 139.404598 -236.586014) (xy 139.404598 -236.633766)
			(xy 139.60475 -236.633766)
		)
		(stroke
			(width 0)
			(type solid)
		)
		(fill yes)
		(layer "In13.Cu")
		(net "M_H_CPU1_SA_DQS_DP<2>")
	)
	(gr_poly
		(pts
			(xy 139.60475 -236.182408) (xy 139.60475 -236.137958) (xy 139.404598 -236.137958) (xy 139.404598 -236.182408)
			(xy 139.504674 -236.282484)
		)
		(stroke
			(width 0)
			(type solid)
		)
		(fill yes)
		(layer "In13.Cu")
		(net "M_H_CPU1_SA_DQ<19>")
	)
	(gr_poly
		(pts
			(xy 139.60475 -234.966256) (xy 139.504674 -234.86618) (xy 139.404598 -234.966256) (xy 139.404598 -235.010706)
			(xy 139.60475 -235.010706)
		)
		(stroke
			(width 0)
			(type solid)
		)
		(fill yes)
		(layer "In13.Cu")
		(net "M_H_CPU1_SA_DQ<16>")
	)
	(gr_poly
		(pts
			(xy 139.60475 -234.562396) (xy 139.60475 -234.517946) (xy 139.404598 -234.517946) (xy 139.404598 -234.562396)
			(xy 139.504674 -234.662472)
		)
		(stroke
			(width 0)
			(type solid)
		)
		(fill yes)
		(layer "In13.Cu")
		(net "M_H_CPU1_SA_DQ<15>")
	)
	(gr_poly
		(pts
			(xy 139.60475 -233.346244) (xy 139.504674 -233.246168) (xy 139.404598 -233.346244) (xy 139.404598 -233.390694)
			(xy 139.60475 -233.390694)
		)
		(stroke
			(width 0)
			(type solid)
		)
		(fill yes)
		(layer "In13.Cu")
		(net "M_H_CPU1_SA_DQ<12>")
	)
	(gr_poly
		(pts
			(xy 139.60475 -232.942638) (xy 139.60475 -232.894886) (xy 139.404598 -232.894886) (xy 139.404598 -232.942638)
			(xy 139.504674 -233.04246)
		)
		(stroke
			(width 0)
			(type solid)
		)
		(fill yes)
		(layer "In13.Cu")
		(net "M_H_CPU1_SA_DQS_DP<6>")
	)
	(gr_poly
		(pts
			(xy 139.60475 -231.725978) (xy 139.504674 -231.626156) (xy 139.404598 -231.725978) (xy 139.404598 -231.77373)
			(xy 139.60475 -231.77373)
		)
		(stroke
			(width 0)
			(type solid)
		)
		(fill yes)
		(layer "In13.Cu")
		(net "M_H_CPU1_SA_DQS_DP<1>")
	)
	(gr_poly
		(pts
			(xy 139.60475 -231.322626) (xy 139.60475 -231.278176) (xy 139.404598 -231.278176) (xy 139.404598 -231.322626)
			(xy 139.504674 -231.422702)
		)
		(stroke
			(width 0)
			(type solid)
		)
		(fill yes)
		(layer "In13.Cu")
		(net "M_H_CPU1_SA_DQ<11>")
	)
	(gr_poly
		(pts
			(xy 139.60475 -230.10622) (xy 139.504674 -230.006144) (xy 139.404598 -230.10622) (xy 139.404598 -230.15067)
			(xy 139.60475 -230.15067)
		)
		(stroke
			(width 0)
			(type solid)
		)
		(fill yes)
		(layer "In13.Cu")
		(net "M_H_CPU1_SA_DQ<8>")
	)
	(gr_poly
		(pts
			(xy 139.60475 -229.702614) (xy 139.60475 -229.658164) (xy 139.404598 -229.658164) (xy 139.404598 -229.702614)
			(xy 139.504674 -229.80269)
		)
		(stroke
			(width 0)
			(type solid)
		)
		(fill yes)
		(layer "In13.Cu")
		(net "M_H_CPU1_SA_DQ<7>")
	)
	(gr_poly
		(pts
			(xy 139.60475 -228.486462) (xy 139.504674 -228.386386) (xy 139.404598 -228.486462) (xy 139.404598 -228.530912)
			(xy 139.60475 -228.530912)
		)
		(stroke
			(width 0)
			(type solid)
		)
		(fill yes)
		(layer "In13.Cu")
		(net "M_H_CPU1_SA_DQ<4>")
	)
	(gr_poly
		(pts
			(xy 139.60475 -228.082856) (xy 139.60475 -228.035104) (xy 139.404598 -228.035104) (xy 139.404598 -228.082856)
			(xy 139.504674 -228.182678)
		)
		(stroke
			(width 0)
			(type solid)
		)
		(fill yes)
		(layer "In13.Cu")
		(net "M_H_CPU1_SA_DQS_DP<5>")
	)
	(gr_poly
		(pts
			(xy 139.60475 -226.866196) (xy 139.504674 -226.766374) (xy 139.404598 -226.866196) (xy 139.404598 -226.913948)
			(xy 139.60475 -226.913948)
		)
		(stroke
			(width 0)
			(type solid)
		)
		(fill yes)
		(layer "In13.Cu")
		(net "M_H_CPU1_SA_DQS_DP<0>")
	)
	(gr_poly
		(pts
			(xy 139.60475 -226.46259) (xy 139.60475 -226.41814) (xy 139.404598 -226.41814) (xy 139.404598 -226.46259)
			(xy 139.504674 -226.562666)
		)
		(stroke
			(width 0)
			(type solid)
		)
		(fill yes)
		(layer "In13.Cu")
		(net "M_H_CPU1_SA_DQ<3>")
	)
	(gr_poly
		(pts
			(xy 139.60475 -225.246438) (xy 139.504674 -225.146362) (xy 139.404598 -225.246438) (xy 139.404598 -225.290888)
			(xy 139.60475 -225.290888)
		)
		(stroke
			(width 0)
			(type solid)
		)
		(fill yes)
		(layer "In13.Cu")
		(net "M_H_CPU1_SA_DQ<0>")
	)
	(gr_poly
		(pts
			(xy 139.904724 -292.918134) (xy 139.804648 -292.818058) (xy 139.704572 -292.918134) (xy 139.704572 -292.962584)
			(xy 139.904724 -292.962584)
		)
		(stroke
			(width 0)
			(type solid)
		)
		(fill yes)
		(layer "In13.Cu")
		(net "M_H_CPU1_SB_DQ<29>")
	)
	(gr_poly
		(pts
			(xy 139.904724 -292.514274) (xy 139.904724 -292.469824) (xy 139.704572 -292.469824) (xy 139.704572 -292.514274)
			(xy 139.804648 -292.61435)
		)
		(stroke
			(width 0)
			(type solid)
		)
		(fill yes)
		(layer "In13.Cu")
		(net "M_H_CPU1_SB_DQ<30>")
	)
	(gr_poly
		(pts
			(xy 139.904724 -291.297868) (xy 139.804648 -291.198046) (xy 139.704572 -291.297868) (xy 139.704572 -291.34562)
			(xy 139.904724 -291.34562)
		)
		(stroke
			(width 0)
			(type solid)
		)
		(fill yes)
		(layer "In13.Cu")
		(net "M_H_CPU1_SB_DQS_DN<8>")
	)
	(gr_poly
		(pts
			(xy 139.904724 -290.894516) (xy 139.904724 -290.846764) (xy 139.704572 -290.846764) (xy 139.704572 -290.894516)
			(xy 139.804648 -290.994338)
		)
		(stroke
			(width 0)
			(type solid)
		)
		(fill yes)
		(layer "In13.Cu")
		(net "M_H_CPU1_SB_DQS_DN<3>")
	)
	(gr_poly
		(pts
			(xy 139.904724 -289.67811) (xy 139.804648 -289.578034) (xy 139.704572 -289.67811) (xy 139.704572 -289.72256)
			(xy 139.904724 -289.72256)
		)
		(stroke
			(width 0)
			(type solid)
		)
		(fill yes)
		(layer "In13.Cu")
		(net "M_H_CPU1_SB_DQ<25>")
	)
	(gr_poly
		(pts
			(xy 139.904724 -289.27425) (xy 139.904724 -289.2298) (xy 139.704572 -289.2298) (xy 139.704572 -289.27425)
			(xy 139.804648 -289.374326)
		)
		(stroke
			(width 0)
			(type solid)
		)
		(fill yes)
		(layer "In13.Cu")
		(net "M_H_CPU1_SB_DQ<26>")
	)
	(gr_poly
		(pts
			(xy 139.904724 -288.058098) (xy 139.804648 -287.958022) (xy 139.704572 -288.058098) (xy 139.704572 -288.102548)
			(xy 139.904724 -288.102548)
		)
		(stroke
			(width 0)
			(type solid)
		)
		(fill yes)
		(layer "In13.Cu")
		(net "M_H_CPU1_SB_DQ<21>")
	)
	(gr_poly
		(pts
			(xy 139.904724 -287.654492) (xy 139.904724 -287.610042) (xy 139.704572 -287.610042) (xy 139.704572 -287.654492)
			(xy 139.804648 -287.754568)
		)
		(stroke
			(width 0)
			(type solid)
		)
		(fill yes)
		(layer "In13.Cu")
		(net "M_H_CPU1_SB_DQ<22>")
	)
	(gr_poly
		(pts
			(xy 139.904724 -286.438086) (xy 139.804648 -286.33801) (xy 139.704572 -286.438086) (xy 139.704572 -286.485838)
			(xy 139.904724 -286.485838)
		)
		(stroke
			(width 0)
			(type solid)
		)
		(fill yes)
		(layer "In13.Cu")
		(net "M_H_CPU1_SB_DQS_DN<7>")
	)
	(gr_poly
		(pts
			(xy 139.904724 -286.034734) (xy 139.904724 -285.986982) (xy 139.704572 -285.986982) (xy 139.704572 -286.034734)
			(xy 139.804648 -286.134556)
		)
		(stroke
			(width 0)
			(type solid)
		)
		(fill yes)
		(layer "In13.Cu")
		(net "M_H_CPU1_SB_DQS_DN<2>")
	)
	(gr_poly
		(pts
			(xy 139.904724 -284.818328) (xy 139.804648 -284.718252) (xy 139.704572 -284.818328) (xy 139.704572 -284.862778)
			(xy 139.904724 -284.862778)
		)
		(stroke
			(width 0)
			(type solid)
		)
		(fill yes)
		(layer "In13.Cu")
		(net "M_H_CPU1_SB_DQ<17>")
	)
	(gr_poly
		(pts
			(xy 139.904724 -284.414468) (xy 139.904724 -284.370018) (xy 139.704572 -284.370018) (xy 139.704572 -284.414468)
			(xy 139.804648 -284.514544)
		)
		(stroke
			(width 0)
			(type solid)
		)
		(fill yes)
		(layer "In13.Cu")
		(net "M_H_CPU1_SB_DQ<18>")
	)
	(gr_poly
		(pts
			(xy 139.904724 -283.198316) (xy 139.804648 -283.09824) (xy 139.704572 -283.198316) (xy 139.704572 -283.242766)
			(xy 139.904724 -283.242766)
		)
		(stroke
			(width 0)
			(type solid)
		)
		(fill yes)
		(layer "In13.Cu")
		(net "M_H_CPU1_SB_DQ<13>")
	)
	(gr_poly
		(pts
			(xy 139.904724 -282.794456) (xy 139.904724 -282.750006) (xy 139.704572 -282.750006) (xy 139.704572 -282.794456)
			(xy 139.804648 -282.894532)
		)
		(stroke
			(width 0)
			(type solid)
		)
		(fill yes)
		(layer "In13.Cu")
		(net "M_H_CPU1_SB_DQ<14>")
	)
	(gr_poly
		(pts
			(xy 139.904724 -281.57805) (xy 139.804648 -281.478228) (xy 139.704572 -281.57805) (xy 139.704572 -281.625802)
			(xy 139.904724 -281.625802)
		)
		(stroke
			(width 0)
			(type solid)
		)
		(fill yes)
		(layer "In13.Cu")
		(net "M_H_CPU1_SB_DQS_DN<6>")
	)
	(gr_poly
		(pts
			(xy 139.904724 -281.174698) (xy 139.904724 -281.126946) (xy 139.704572 -281.126946) (xy 139.704572 -281.174698)
			(xy 139.804648 -281.27452)
		)
		(stroke
			(width 0)
			(type solid)
		)
		(fill yes)
		(layer "In13.Cu")
		(net "M_H_CPU1_SB_DQS_DN<1>")
	)
	(gr_poly
		(pts
			(xy 139.904724 -279.958292) (xy 139.804648 -279.858216) (xy 139.704572 -279.958292) (xy 139.704572 -280.002742)
			(xy 139.904724 -280.002742)
		)
		(stroke
			(width 0)
			(type solid)
		)
		(fill yes)
		(layer "In13.Cu")
		(net "M_H_CPU1_SB_DQ<9>")
	)
	(gr_poly
		(pts
			(xy 139.904724 -279.554432) (xy 139.904724 -279.509982) (xy 139.704572 -279.509982) (xy 139.704572 -279.554432)
			(xy 139.804648 -279.654508)
		)
		(stroke
			(width 0)
			(type solid)
		)
		(fill yes)
		(layer "In13.Cu")
		(net "M_H_CPU1_SB_DQ<10>")
	)
	(gr_poly
		(pts
			(xy 139.904724 -278.33828) (xy 139.804648 -278.238204) (xy 139.704572 -278.33828) (xy 139.704572 -278.38273)
			(xy 139.904724 -278.38273)
		)
		(stroke
			(width 0)
			(type solid)
		)
		(fill yes)
		(layer "In13.Cu")
		(net "M_H_CPU1_SB_DQ<5>")
	)
	(gr_poly
		(pts
			(xy 139.904724 -277.93442) (xy 139.904724 -277.88997) (xy 139.704572 -277.88997) (xy 139.704572 -277.93442)
			(xy 139.804648 -278.034496)
		)
		(stroke
			(width 0)
			(type solid)
		)
		(fill yes)
		(layer "In13.Cu")
		(net "M_H_CPU1_SB_DQ<6>")
	)
	(gr_poly
		(pts
			(xy 139.904724 -276.718014) (xy 139.804648 -276.618192) (xy 139.704572 -276.718014) (xy 139.704572 -276.765766)
			(xy 139.904724 -276.765766)
		)
		(stroke
			(width 0)
			(type solid)
		)
		(fill yes)
		(layer "In13.Cu")
		(net "M_H_CPU1_SB_DQS_DN<5>")
	)
	(gr_poly
		(pts
			(xy 139.904724 -276.314662) (xy 139.904724 -276.26691) (xy 139.704572 -276.26691) (xy 139.704572 -276.314662)
			(xy 139.804648 -276.414484)
		)
		(stroke
			(width 0)
			(type solid)
		)
		(fill yes)
		(layer "In13.Cu")
		(net "M_H_CPU1_SB_DQS_DN<0>")
	)
	(gr_poly
		(pts
			(xy 139.904724 -275.098256) (xy 139.804648 -274.99818) (xy 139.704572 -275.098256) (xy 139.704572 -275.142706)
			(xy 139.904724 -275.142706)
		)
		(stroke
			(width 0)
			(type solid)
		)
		(fill yes)
		(layer "In13.Cu")
		(net "M_H_CPU1_SB_DQ<1>")
	)
	(gr_poly
		(pts
			(xy 139.904724 -274.694396) (xy 139.904724 -274.649946) (xy 139.704572 -274.649946) (xy 139.704572 -274.694396)
			(xy 139.804648 -274.794472)
		)
		(stroke
			(width 0)
			(type solid)
		)
		(fill yes)
		(layer "In13.Cu")
		(net "M_H_CPU1_SB_DQ<2>")
	)
	(gr_poly
		(pts
			(xy 139.904724 -273.478244) (xy 139.804648 -273.378168) (xy 139.704572 -273.478244) (xy 139.704572 -273.522694)
			(xy 139.904724 -273.522694)
		)
		(stroke
			(width 0)
			(type solid)
		)
		(fill yes)
		(layer "In13.Cu")
		(net "M_H_CPU1_SB_CB<1>")
	)
	(gr_poly
		(pts
			(xy 139.904724 -273.074384) (xy 139.904724 -273.029934) (xy 139.704572 -273.029934) (xy 139.704572 -273.074384)
			(xy 139.804648 -273.17446)
		)
		(stroke
			(width 0)
			(type solid)
		)
		(fill yes)
		(layer "In13.Cu")
		(net "M_H_CPU1_SB_CB<2>")
	)
	(gr_poly
		(pts
			(xy 139.904724 -271.857978) (xy 139.804648 -271.758156) (xy 139.704572 -271.857978) (xy 139.704572 -271.90573)
			(xy 139.904724 -271.90573)
		)
		(stroke
			(width 0)
			(type solid)
		)
		(fill yes)
		(layer "In13.Cu")
		(net "M_H_CPU1_SB_DQS_DN<4>")
	)
	(gr_poly
		(pts
			(xy 139.904724 -271.454626) (xy 139.904724 -271.406874) (xy 139.704572 -271.406874) (xy 139.704572 -271.454626)
			(xy 139.804648 -271.554448)
		)
		(stroke
			(width 0)
			(type solid)
		)
		(fill yes)
		(layer "In13.Cu")
		(net "M_H_CPU1_SB_DQS_DN<9>")
	)
	(gr_poly
		(pts
			(xy 139.904724 -270.23822) (xy 139.804648 -270.138144) (xy 139.704572 -270.23822) (xy 139.704572 -270.28267)
			(xy 139.904724 -270.28267)
		)
		(stroke
			(width 0)
			(type solid)
		)
		(fill yes)
		(layer "In13.Cu")
		(net "M_H_CPU1_SB_CB<5>")
	)
	(gr_poly
		(pts
			(xy 139.904724 -269.83436) (xy 139.904724 -269.78991) (xy 139.704572 -269.78991) (xy 139.704572 -269.83436)
			(xy 139.804648 -269.934436)
		)
		(stroke
			(width 0)
			(type solid)
		)
		(fill yes)
		(layer "In13.Cu")
		(net "M_H_CPU1_SB_CB<6>")
	)
	(gr_poly
		(pts
			(xy 139.904724 -266.998196) (xy 139.804648 -266.89812) (xy 139.704572 -266.998196) (xy 139.704572 -267.042646)
			(xy 139.904724 -267.042646)
		)
		(stroke
			(width 0)
			(type solid)
		)
		(fill yes)
		(layer "In13.Cu")
		(net "M_H_CPU1_SA_RSP<0>")
	)
	(gr_poly
		(pts
			(xy 139.904724 -266.594336) (xy 139.904724 -266.549886) (xy 139.704572 -266.549886) (xy 139.704572 -266.594336)
			(xy 139.804648 -266.694412)
		)
		(stroke
			(width 0)
			(type solid)
		)
		(fill yes)
		(layer "In13.Cu")
		(net "M_H_CPU1_SB_CS_N<1>")
	)
	(gr_poly
		(pts
			(xy 139.904724 -265.378184) (xy 139.804648 -265.278108) (xy 139.704572 -265.378184) (xy 139.704572 -265.422634)
			(xy 139.904724 -265.422634)
		)
		(stroke
			(width 0)
			(type solid)
		)
		(fill yes)
		(layer "In13.Cu")
		(net "M_H_CPU1_SB_PAR")
	)
	(gr_poly
		(pts
			(xy 139.904724 -263.758172) (xy 139.804648 -263.658096) (xy 139.704572 -263.758172) (xy 139.704572 -263.802622)
			(xy 139.904724 -263.802622)
		)
		(stroke
			(width 0)
			(type solid)
		)
		(fill yes)
		(layer "In13.Cu")
		(net "M_H_CPU1_SB_CA<4>")
	)
	(gr_poly
		(pts
			(xy 139.904724 -263.354312) (xy 139.904724 -263.309862) (xy 139.704572 -263.309862) (xy 139.704572 -263.354312)
			(xy 139.804648 -263.454388)
		)
		(stroke
			(width 0)
			(type solid)
		)
		(fill yes)
		(layer "In13.Cu")
		(net "M_H_CPU1_SB_CA<3>")
	)
	(gr_poly
		(pts
			(xy 139.904724 -262.13816) (xy 139.804648 -262.038084) (xy 139.704572 -262.13816) (xy 139.704572 -262.18261)
			(xy 139.904724 -262.18261)
		)
		(stroke
			(width 0)
			(type solid)
		)
		(fill yes)
		(layer "In13.Cu")
		(net "M_H_CPU1_SB_CA<0>")
	)
	(gr_poly
		(pts
			(xy 140.074904 -256.432812) (xy 140.074904 -256.38506) (xy 139.874752 -256.38506) (xy 139.874752 -256.432812)
			(xy 139.974828 -256.532634)
		)
		(stroke
			(width 0)
			(type solid)
		)
		(fill yes)
		(layer "In13.Cu")
		(net "M_H_CPU1_CLK_DN<0>")
	)
	(gr_poly
		(pts
			(xy 140.074904 -255.216406) (xy 139.974828 -255.11633) (xy 139.874752 -255.216406) (xy 139.874752 -255.260856)
			(xy 140.074904 -255.260856)
		)
		(stroke
			(width 0)
			(type solid)
		)
		(fill yes)
		(layer "In13.Cu")
		(net "M_H_CPU1_SA_CA<6>")
	)
	(gr_poly
		(pts
			(xy 140.074904 -254.812546) (xy 140.074904 -254.768096) (xy 139.874752 -254.768096) (xy 139.874752 -254.812546)
			(xy 139.974828 -254.912622)
		)
		(stroke
			(width 0)
			(type solid)
		)
		(fill yes)
		(layer "In13.Cu")
		(net "M_H_CPU1_SA_CA<5>")
	)
	(gr_poly
		(pts
			(xy 140.074904 -253.596394) (xy 139.974828 -253.496318) (xy 139.874752 -253.596394) (xy 139.874752 -253.640844)
			(xy 140.074904 -253.640844)
		)
		(stroke
			(width 0)
			(type solid)
		)
		(fill yes)
		(layer "In13.Cu")
		(net "M_H_CPU1_SA_CA<2>")
	)
	(gr_poly
		(pts
			(xy 140.074904 -253.192534) (xy 140.074904 -253.148084) (xy 139.874752 -253.148084) (xy 139.874752 -253.192534)
			(xy 139.974828 -253.29261)
		)
		(stroke
			(width 0)
			(type solid)
		)
		(fill yes)
		(layer "In13.Cu")
		(net "M_H_CPU1_SA_CA<1>")
	)
	(gr_poly
		(pts
			(xy 140.074904 -251.976382) (xy 139.974828 -251.876306) (xy 139.874752 -251.976382) (xy 139.874752 -252.020832)
			(xy 140.074904 -252.020832)
		)
		(stroke
			(width 0)
			(type solid)
		)
		(fill yes)
		(layer "In13.Cu")
		(net "M_H_CPU1_SA_CS_N<1>")
	)
	(gr_poly
		(pts
			(xy 140.074904 -250.35637) (xy 139.974828 -250.256294) (xy 139.874752 -250.35637) (xy 139.874752 -250.40082)
			(xy 140.074904 -250.40082)
		)
		(stroke
			(width 0)
			(type solid)
		)
		(fill yes)
		(layer "In13.Cu")
		(net "M_H_CPU1_ALERT_R_N")
	)
	(gr_poly
		(pts
			(xy 140.074904 -248.736358) (xy 139.974828 -248.636282) (xy 139.874752 -248.736358) (xy 139.874752 -248.780808)
			(xy 140.074904 -248.780808)
		)
		(stroke
			(width 0)
			(type solid)
		)
		(fill yes)
		(layer "In13.Cu")
		(net "M_H_CPU1_SA_CB<5>")
	)
	(gr_poly
		(pts
			(xy 140.074904 -248.332498) (xy 140.074904 -248.288048) (xy 139.874752 -248.288048) (xy 139.874752 -248.332498)
			(xy 139.974828 -248.432574)
		)
		(stroke
			(width 0)
			(type solid)
		)
		(fill yes)
		(layer "In13.Cu")
		(net "M_H_CPU1_SA_CB<6>")
	)
	(gr_poly
		(pts
			(xy 140.074904 -247.116092) (xy 139.974828 -247.01627) (xy 139.874752 -247.116092) (xy 139.874752 -247.163844)
			(xy 140.074904 -247.163844)
		)
		(stroke
			(width 0)
			(type solid)
		)
		(fill yes)
		(layer "In13.Cu")
		(net "M_H_CPU1_SA_DQS_DN<9>")
	)
	(gr_poly
		(pts
			(xy 140.074904 -246.71274) (xy 140.074904 -246.664988) (xy 139.874752 -246.664988) (xy 139.874752 -246.71274)
			(xy 139.974828 -246.812562)
		)
		(stroke
			(width 0)
			(type solid)
		)
		(fill yes)
		(layer "In13.Cu")
		(net "M_H_CPU1_SA_DQS_DN<4>")
	)
	(gr_poly
		(pts
			(xy 140.074904 -245.496334) (xy 139.974828 -245.396258) (xy 139.874752 -245.496334) (xy 139.874752 -245.540784)
			(xy 140.074904 -245.540784)
		)
		(stroke
			(width 0)
			(type solid)
		)
		(fill yes)
		(layer "In13.Cu")
		(net "M_H_CPU1_SA_CB<1>")
	)
	(gr_poly
		(pts
			(xy 140.074904 -245.092474) (xy 140.074904 -245.048024) (xy 139.874752 -245.048024) (xy 139.874752 -245.092474)
			(xy 139.974828 -245.19255)
		)
		(stroke
			(width 0)
			(type solid)
		)
		(fill yes)
		(layer "In13.Cu")
		(net "M_H_CPU1_SA_CB<2>")
	)
	(gr_poly
		(pts
			(xy 140.074904 -243.876322) (xy 139.974828 -243.776246) (xy 139.874752 -243.876322) (xy 139.874752 -243.920772)
			(xy 140.074904 -243.920772)
		)
		(stroke
			(width 0)
			(type solid)
		)
		(fill yes)
		(layer "In13.Cu")
		(net "M_H_CPU1_SA_DQ<29>")
	)
	(gr_poly
		(pts
			(xy 140.074904 -243.472462) (xy 140.074904 -243.428012) (xy 139.874752 -243.428012) (xy 139.874752 -243.472462)
			(xy 139.974828 -243.572538)
		)
		(stroke
			(width 0)
			(type solid)
		)
		(fill yes)
		(layer "In13.Cu")
		(net "M_H_CPU1_SA_DQ<30>")
	)
	(gr_poly
		(pts
			(xy 140.074904 -242.256056) (xy 139.974828 -242.156234) (xy 139.874752 -242.256056) (xy 139.874752 -242.303808)
			(xy 140.074904 -242.303808)
		)
		(stroke
			(width 0)
			(type solid)
		)
		(fill yes)
		(layer "In13.Cu")
		(net "M_H_CPU1_SA_DQS_DN<8>")
	)
	(gr_poly
		(pts
			(xy 140.074904 -241.852704) (xy 140.074904 -241.804952) (xy 139.874752 -241.804952) (xy 139.874752 -241.852704)
			(xy 139.974828 -241.952526)
		)
		(stroke
			(width 0)
			(type solid)
		)
		(fill yes)
		(layer "In13.Cu")
		(net "M_H_CPU1_SA_DQS_DN<3>")
	)
	(gr_poly
		(pts
			(xy 140.074904 -240.636298) (xy 139.974828 -240.536222) (xy 139.874752 -240.636298) (xy 139.874752 -240.680748)
			(xy 140.074904 -240.680748)
		)
		(stroke
			(width 0)
			(type solid)
		)
		(fill yes)
		(layer "In13.Cu")
		(net "M_H_CPU1_SA_DQ<25>")
	)
	(gr_poly
		(pts
			(xy 140.074904 -240.232438) (xy 140.074904 -240.187988) (xy 139.874752 -240.187988) (xy 139.874752 -240.232438)
			(xy 139.974828 -240.332514)
		)
		(stroke
			(width 0)
			(type solid)
		)
		(fill yes)
		(layer "In13.Cu")
		(net "M_H_CPU1_SA_DQ<26>")
	)
	(gr_poly
		(pts
			(xy 140.074904 -239.016286) (xy 139.974828 -238.91621) (xy 139.874752 -239.016286) (xy 139.874752 -239.060736)
			(xy 140.074904 -239.060736)
		)
		(stroke
			(width 0)
			(type solid)
		)
		(fill yes)
		(layer "In13.Cu")
		(net "M_H_CPU1_SA_DQ<21>")
	)
	(gr_poly
		(pts
			(xy 140.074904 -238.612426) (xy 140.074904 -238.567976) (xy 139.874752 -238.567976) (xy 139.874752 -238.612426)
			(xy 139.974828 -238.712502)
		)
		(stroke
			(width 0)
			(type solid)
		)
		(fill yes)
		(layer "In13.Cu")
		(net "M_H_CPU1_SA_DQ<22>")
	)
	(gr_poly
		(pts
			(xy 140.074904 -237.39602) (xy 139.974828 -237.296198) (xy 139.874752 -237.39602) (xy 139.874752 -237.443772)
			(xy 140.074904 -237.443772)
		)
		(stroke
			(width 0)
			(type solid)
		)
		(fill yes)
		(layer "In13.Cu")
		(net "M_H_CPU1_SA_DQS_DN<7>")
	)
	(gr_poly
		(pts
			(xy 140.074904 -236.992668) (xy 140.074904 -236.944916) (xy 139.874752 -236.944916) (xy 139.874752 -236.992668)
			(xy 139.974828 -237.09249)
		)
		(stroke
			(width 0)
			(type solid)
		)
		(fill yes)
		(layer "In13.Cu")
		(net "M_H_CPU1_SA_DQS_DN<2>")
	)
	(gr_poly
		(pts
			(xy 140.074904 -235.776262) (xy 139.974828 -235.676186) (xy 139.874752 -235.776262) (xy 139.874752 -235.820712)
			(xy 140.074904 -235.820712)
		)
		(stroke
			(width 0)
			(type solid)
		)
		(fill yes)
		(layer "In13.Cu")
		(net "M_H_CPU1_SA_DQ<17>")
	)
	(gr_poly
		(pts
			(xy 140.074904 -235.372402) (xy 140.074904 -235.327952) (xy 139.874752 -235.327952) (xy 139.874752 -235.372402)
			(xy 139.974828 -235.472478)
		)
		(stroke
			(width 0)
			(type solid)
		)
		(fill yes)
		(layer "In13.Cu")
		(net "M_H_CPU1_SA_DQ<18>")
	)
	(gr_poly
		(pts
			(xy 140.074904 -234.15625) (xy 139.974828 -234.056174) (xy 139.874752 -234.15625) (xy 139.874752 -234.2007)
			(xy 140.074904 -234.2007)
		)
		(stroke
			(width 0)
			(type solid)
		)
		(fill yes)
		(layer "In13.Cu")
		(net "M_H_CPU1_SA_DQ<13>")
	)
	(gr_poly
		(pts
			(xy 140.074904 -233.75239) (xy 140.074904 -233.70794) (xy 139.874752 -233.70794) (xy 139.874752 -233.75239)
			(xy 139.974828 -233.852466)
		)
		(stroke
			(width 0)
			(type solid)
		)
		(fill yes)
		(layer "In13.Cu")
		(net "M_H_CPU1_SA_DQ<14>")
	)
	(gr_poly
		(pts
			(xy 140.074904 -232.535984) (xy 139.974828 -232.436162) (xy 139.874752 -232.535984) (xy 139.874752 -232.583736)
			(xy 140.074904 -232.583736)
		)
		(stroke
			(width 0)
			(type solid)
		)
		(fill yes)
		(layer "In13.Cu")
		(net "M_H_CPU1_SA_DQS_DN<6>")
	)
	(gr_poly
		(pts
			(xy 140.074904 -232.132632) (xy 140.074904 -232.08488) (xy 139.874752 -232.08488) (xy 139.874752 -232.132632)
			(xy 139.974828 -232.232454)
		)
		(stroke
			(width 0)
			(type solid)
		)
		(fill yes)
		(layer "In13.Cu")
		(net "M_H_CPU1_SA_DQS_DN<1>")
	)
	(gr_poly
		(pts
			(xy 140.074904 -230.916226) (xy 139.974828 -230.81615) (xy 139.874752 -230.916226) (xy 139.874752 -230.960676)
			(xy 140.074904 -230.960676)
		)
		(stroke
			(width 0)
			(type solid)
		)
		(fill yes)
		(layer "In13.Cu")
		(net "M_H_CPU1_SA_DQ<9>")
	)
	(gr_poly
		(pts
			(xy 140.074904 -230.51262) (xy 140.074904 -230.46817) (xy 139.874752 -230.46817) (xy 139.874752 -230.51262)
			(xy 139.974828 -230.612696)
		)
		(stroke
			(width 0)
			(type solid)
		)
		(fill yes)
		(layer "In13.Cu")
		(net "M_H_CPU1_SA_DQ<10>")
	)
	(gr_poly
		(pts
			(xy 140.074904 -229.296214) (xy 139.974828 -229.196138) (xy 139.874752 -229.296214) (xy 139.874752 -229.340664)
			(xy 140.074904 -229.340664)
		)
		(stroke
			(width 0)
			(type solid)
		)
		(fill yes)
		(layer "In13.Cu")
		(net "M_H_CPU1_SA_DQ<5>")
	)
	(gr_poly
		(pts
			(xy 140.074904 -228.892608) (xy 140.074904 -228.848158) (xy 139.874752 -228.848158) (xy 139.874752 -228.892608)
			(xy 139.974828 -228.992684)
		)
		(stroke
			(width 0)
			(type solid)
		)
		(fill yes)
		(layer "In13.Cu")
		(net "M_H_CPU1_SA_DQ<6>")
	)
	(gr_poly
		(pts
			(xy 140.074904 -227.676202) (xy 139.974828 -227.57638) (xy 139.874752 -227.676202) (xy 139.874752 -227.723954)
			(xy 140.074904 -227.723954)
		)
		(stroke
			(width 0)
			(type solid)
		)
		(fill yes)
		(layer "In13.Cu")
		(net "M_H_CPU1_SA_DQS_DN<5>")
	)
	(gr_poly
		(pts
			(xy 140.074904 -227.27285) (xy 140.074904 -227.225098) (xy 139.874752 -227.225098) (xy 139.874752 -227.27285)
			(xy 139.974828 -227.372672)
		)
		(stroke
			(width 0)
			(type solid)
		)
		(fill yes)
		(layer "In13.Cu")
		(net "M_H_CPU1_SA_DQS_DN<0>")
	)
	(gr_poly
		(pts
			(xy 140.074904 -226.056444) (xy 139.974828 -225.956368) (xy 139.874752 -226.056444) (xy 139.874752 -226.100894)
			(xy 140.074904 -226.100894)
		)
		(stroke
			(width 0)
			(type solid)
		)
		(fill yes)
		(layer "In13.Cu")
		(net "M_H_CPU1_SA_DQ<1>")
	)
	(gr_poly
		(pts
			(xy 140.074904 -225.652584) (xy 140.074904 -225.608134) (xy 139.874752 -225.608134) (xy 139.874752 -225.652584)
			(xy 139.974828 -225.75266)
		)
		(stroke
			(width 0)
			(type solid)
		)
		(fill yes)
		(layer "In13.Cu")
		(net "M_H_CPU1_SA_DQ<2>")
	)
	(gr_poly
		(pts
			(xy 140.374878 -293.32428) (xy 140.374878 -293.27983) (xy 140.174726 -293.27983) (xy 140.174726 -293.32428)
			(xy 140.274802 -293.424356)
		)
		(stroke
			(width 0)
			(type solid)
		)
		(fill yes)
		(layer "In13.Cu")
		(net "M_H_CPU1_SB_DQ<31>")
	)
	(gr_poly
		(pts
			(xy 140.374878 -292.108128) (xy 140.274802 -292.008052) (xy 140.174726 -292.108128) (xy 140.174726 -292.152578)
			(xy 140.374878 -292.152578)
		)
		(stroke
			(width 0)
			(type solid)
		)
		(fill yes)
		(layer "In13.Cu")
		(net "M_H_CPU1_SB_DQ<28>")
	)
	(gr_poly
		(pts
			(xy 140.374878 -291.704522) (xy 140.374878 -291.65677) (xy 140.174726 -291.65677) (xy 140.174726 -291.704522)
			(xy 140.274802 -291.804344)
		)
		(stroke
			(width 0)
			(type solid)
		)
		(fill yes)
		(layer "In13.Cu")
		(net "M_H_CPU1_SB_DQS_DP<8>")
	)
	(gr_poly
		(pts
			(xy 140.374878 -290.487862) (xy 140.274802 -290.38804) (xy 140.174726 -290.487862) (xy 140.174726 -290.535614)
			(xy 140.374878 -290.535614)
		)
		(stroke
			(width 0)
			(type solid)
		)
		(fill yes)
		(layer "In13.Cu")
		(net "M_H_CPU1_SB_DQS_DP<3>")
	)
	(gr_poly
		(pts
			(xy 140.374878 -290.084256) (xy 140.374878 -290.039806) (xy 140.174726 -290.039806) (xy 140.174726 -290.084256)
			(xy 140.274802 -290.184332)
		)
		(stroke
			(width 0)
			(type solid)
		)
		(fill yes)
		(layer "In13.Cu")
		(net "M_H_CPU1_SB_DQ<27>")
	)
	(gr_poly
		(pts
			(xy 140.374878 -288.868104) (xy 140.274802 -288.768028) (xy 140.174726 -288.868104) (xy 140.174726 -288.912554)
			(xy 140.374878 -288.912554)
		)
		(stroke
			(width 0)
			(type solid)
		)
		(fill yes)
		(layer "In13.Cu")
		(net "M_H_CPU1_SB_DQ<24>")
	)
	(gr_poly
		(pts
			(xy 140.374878 -288.464498) (xy 140.374878 -288.420048) (xy 140.174726 -288.420048) (xy 140.174726 -288.464498)
			(xy 140.274802 -288.564574)
		)
		(stroke
			(width 0)
			(type solid)
		)
		(fill yes)
		(layer "In13.Cu")
		(net "M_H_CPU1_SB_DQ<23>")
	)
	(gr_poly
		(pts
			(xy 140.374878 -287.248092) (xy 140.274802 -287.148016) (xy 140.174726 -287.248092) (xy 140.174726 -287.292542)
			(xy 140.374878 -287.292542)
		)
		(stroke
			(width 0)
			(type solid)
		)
		(fill yes)
		(layer "In13.Cu")
		(net "M_H_CPU1_SB_DQ<20>")
	)
	(gr_poly
		(pts
			(xy 140.374878 -286.844486) (xy 140.374878 -286.796734) (xy 140.174726 -286.796734) (xy 140.174726 -286.844486)
			(xy 140.274802 -286.944562)
		)
		(stroke
			(width 0)
			(type solid)
		)
		(fill yes)
		(layer "In13.Cu")
		(net "M_H_CPU1_SB_DQS_DP<7>")
	)
	(gr_poly
		(pts
			(xy 140.374878 -285.62808) (xy 140.274802 -285.528258) (xy 140.174726 -285.62808) (xy 140.174726 -285.675832)
			(xy 140.374878 -285.675832)
		)
		(stroke
			(width 0)
			(type solid)
		)
		(fill yes)
		(layer "In13.Cu")
		(net "M_H_CPU1_SB_DQS_DP<2>")
	)
	(gr_poly
		(pts
			(xy 140.374878 -285.224474) (xy 140.374878 -285.180024) (xy 140.174726 -285.180024) (xy 140.174726 -285.224474)
			(xy 140.274802 -285.32455)
		)
		(stroke
			(width 0)
			(type solid)
		)
		(fill yes)
		(layer "In13.Cu")
		(net "M_H_CPU1_SB_DQ<19>")
	)
	(gr_poly
		(pts
			(xy 140.374878 -284.008322) (xy 140.274802 -283.908246) (xy 140.174726 -284.008322) (xy 140.174726 -284.052772)
			(xy 140.374878 -284.052772)
		)
		(stroke
			(width 0)
			(type solid)
		)
		(fill yes)
		(layer "In13.Cu")
		(net "M_H_CPU1_SB_DQ<16>")
	)
	(gr_poly
		(pts
			(xy 140.374878 -283.604462) (xy 140.374878 -283.560012) (xy 140.174726 -283.560012) (xy 140.174726 -283.604462)
			(xy 140.274802 -283.704538)
		)
		(stroke
			(width 0)
			(type solid)
		)
		(fill yes)
		(layer "In13.Cu")
		(net "M_H_CPU1_SB_DQ<15>")
	)
	(gr_poly
		(pts
			(xy 140.374878 -282.38831) (xy 140.274802 -282.288234) (xy 140.174726 -282.38831) (xy 140.174726 -282.43276)
			(xy 140.374878 -282.43276)
		)
		(stroke
			(width 0)
			(type solid)
		)
		(fill yes)
		(layer "In13.Cu")
		(net "M_H_CPU1_SB_DQ<12>")
	)
	(gr_poly
		(pts
			(xy 140.374878 -281.984704) (xy 140.374878 -281.936952) (xy 140.174726 -281.936952) (xy 140.174726 -281.984704)
			(xy 140.274802 -282.084526)
		)
		(stroke
			(width 0)
			(type solid)
		)
		(fill yes)
		(layer "In13.Cu")
		(net "M_H_CPU1_SB_DQS_DP<6>")
	)
	(gr_poly
		(pts
			(xy 140.374878 -280.768044) (xy 140.274802 -280.668222) (xy 140.174726 -280.768044) (xy 140.174726 -280.815796)
			(xy 140.374878 -280.815796)
		)
		(stroke
			(width 0)
			(type solid)
		)
		(fill yes)
		(layer "In13.Cu")
		(net "M_H_CPU1_SB_DQS_DP<1>")
	)
	(gr_poly
		(pts
			(xy 140.374878 -280.364438) (xy 140.374878 -280.319988) (xy 140.174726 -280.319988) (xy 140.174726 -280.364438)
			(xy 140.274802 -280.464514)
		)
		(stroke
			(width 0)
			(type solid)
		)
		(fill yes)
		(layer "In13.Cu")
		(net "M_H_CPU1_SB_DQ<11>")
	)
	(gr_poly
		(pts
			(xy 140.374878 -279.148286) (xy 140.274802 -279.04821) (xy 140.174726 -279.148286) (xy 140.174726 -279.192736)
			(xy 140.374878 -279.192736)
		)
		(stroke
			(width 0)
			(type solid)
		)
		(fill yes)
		(layer "In13.Cu")
		(net "M_H_CPU1_SB_DQ<8>")
	)
	(gr_poly
		(pts
			(xy 140.374878 -278.744426) (xy 140.374878 -278.699976) (xy 140.174726 -278.699976) (xy 140.174726 -278.744426)
			(xy 140.274802 -278.844502)
		)
		(stroke
			(width 0)
			(type solid)
		)
		(fill yes)
		(layer "In13.Cu")
		(net "M_H_CPU1_SB_DQ<7>")
	)
	(gr_poly
		(pts
			(xy 140.374878 -277.528274) (xy 140.274802 -277.428198) (xy 140.174726 -277.528274) (xy 140.174726 -277.572724)
			(xy 140.374878 -277.572724)
		)
		(stroke
			(width 0)
			(type solid)
		)
		(fill yes)
		(layer "In13.Cu")
		(net "M_H_CPU1_SB_DQ<4>")
	)
	(gr_poly
		(pts
			(xy 140.374878 -277.124668) (xy 140.374878 -277.076916) (xy 140.174726 -277.076916) (xy 140.174726 -277.124668)
			(xy 140.274802 -277.22449)
		)
		(stroke
			(width 0)
			(type solid)
		)
		(fill yes)
		(layer "In13.Cu")
		(net "M_H_CPU1_SB_DQS_DP<5>")
	)
	(gr_poly
		(pts
			(xy 140.374878 -275.908008) (xy 140.274802 -275.808186) (xy 140.174726 -275.908008) (xy 140.174726 -275.95576)
			(xy 140.374878 -275.95576)
		)
		(stroke
			(width 0)
			(type solid)
		)
		(fill yes)
		(layer "In13.Cu")
		(net "M_H_CPU1_SB_DQS_DP<0>")
	)
	(gr_poly
		(pts
			(xy 140.374878 -275.504402) (xy 140.374878 -275.459952) (xy 140.174726 -275.459952) (xy 140.174726 -275.504402)
			(xy 140.274802 -275.604478)
		)
		(stroke
			(width 0)
			(type solid)
		)
		(fill yes)
		(layer "In13.Cu")
		(net "M_H_CPU1_SB_DQ<3>")
	)
	(gr_poly
		(pts
			(xy 140.374878 -274.28825) (xy 140.274802 -274.188174) (xy 140.174726 -274.28825) (xy 140.174726 -274.3327)
			(xy 140.374878 -274.3327)
		)
		(stroke
			(width 0)
			(type solid)
		)
		(fill yes)
		(layer "In13.Cu")
		(net "M_H_CPU1_SB_DQ<0>")
	)
	(gr_poly
		(pts
			(xy 140.374878 -273.88439) (xy 140.374878 -273.83994) (xy 140.174726 -273.83994) (xy 140.174726 -273.88439)
			(xy 140.274802 -273.984466)
		)
		(stroke
			(width 0)
			(type solid)
		)
		(fill yes)
		(layer "In13.Cu")
		(net "M_H_CPU1_SB_CB<3>")
	)
	(gr_poly
		(pts
			(xy 140.374878 -272.668238) (xy 140.274802 -272.568162) (xy 140.174726 -272.668238) (xy 140.174726 -272.712688)
			(xy 140.374878 -272.712688)
		)
		(stroke
			(width 0)
			(type solid)
		)
		(fill yes)
		(layer "In13.Cu")
		(net "M_H_CPU1_SB_CB<0>")
	)
	(gr_poly
		(pts
			(xy 140.374878 -272.264632) (xy 140.374878 -272.21688) (xy 140.174726 -272.21688) (xy 140.174726 -272.264632)
			(xy 140.274802 -272.364454)
		)
		(stroke
			(width 0)
			(type solid)
		)
		(fill yes)
		(layer "In13.Cu")
		(net "M_H_CPU1_SB_DQS_DP<4>")
	)
	(gr_poly
		(pts
			(xy 140.374878 -271.047972) (xy 140.274802 -270.94815) (xy 140.174726 -271.047972) (xy 140.174726 -271.095724)
			(xy 140.374878 -271.095724)
		)
		(stroke
			(width 0)
			(type solid)
		)
		(fill yes)
		(layer "In13.Cu")
		(net "M_H_CPU1_SB_DQS_DP<9>")
	)
	(gr_poly
		(pts
			(xy 140.374878 -270.644366) (xy 140.374878 -270.599916) (xy 140.174726 -270.599916) (xy 140.174726 -270.644366)
			(xy 140.274802 -270.744442)
		)
		(stroke
			(width 0)
			(type solid)
		)
		(fill yes)
		(layer "In13.Cu")
		(net "M_H_CPU1_SB_CB<7>")
	)
	(gr_poly
		(pts
			(xy 140.374878 -269.428214) (xy 140.274802 -269.328138) (xy 140.174726 -269.428214) (xy 140.174726 -269.472664)
			(xy 140.374878 -269.472664)
		)
		(stroke
			(width 0)
			(type solid)
		)
		(fill yes)
		(layer "In13.Cu")
		(net "M_H_CPU1_SB_CB<4>")
	)
	(gr_poly
		(pts
			(xy 140.374878 -267.808202) (xy 140.274802 -267.708126) (xy 140.174726 -267.808202) (xy 140.174726 -267.852652)
			(xy 140.374878 -267.852652)
		)
		(stroke
			(width 0)
			(type solid)
		)
		(fill yes)
		(layer "In13.Cu")
		(net "M_H_CPU1_SB_RSP<0>")
	)
	(gr_poly
		(pts
			(xy 140.374878 -265.78433) (xy 140.374878 -265.73988) (xy 140.174726 -265.73988) (xy 140.174726 -265.78433)
			(xy 140.274802 -265.884406)
		)
		(stroke
			(width 0)
			(type solid)
		)
		(fill yes)
		(layer "In13.Cu")
		(net "M_H_CPU1_SB_CS_N<0>")
	)
	(gr_poly
		(pts
			(xy 140.374878 -264.568178) (xy 140.274802 -264.468102) (xy 140.174726 -264.568178) (xy 140.174726 -264.612628)
			(xy 140.374878 -264.612628)
		)
		(stroke
			(width 0)
			(type solid)
		)
		(fill yes)
		(layer "In13.Cu")
		(net "M_H_CPU1_SB_CA<6>")
	)
	(gr_poly
		(pts
			(xy 140.374878 -264.164318) (xy 140.374878 -264.119868) (xy 140.174726 -264.119868) (xy 140.174726 -264.164318)
			(xy 140.274802 -264.264394)
		)
		(stroke
			(width 0)
			(type solid)
		)
		(fill yes)
		(layer "In13.Cu")
		(net "M_H_CPU1_SB_CA<5>")
	)
	(gr_poly
		(pts
			(xy 140.374878 -262.948166) (xy 140.274802 -262.84809) (xy 140.174726 -262.948166) (xy 140.174726 -262.992616)
			(xy 140.374878 -262.992616)
		)
		(stroke
			(width 0)
			(type solid)
		)
		(fill yes)
		(layer "In13.Cu")
		(net "M_H_CPU1_SB_CA<2>")
	)
	(gr_poly
		(pts
			(xy 140.374878 -262.544306) (xy 140.374878 -262.499856) (xy 140.174726 -262.499856) (xy 140.174726 -262.544306)
			(xy 140.274802 -262.644382)
		)
		(stroke
			(width 0)
			(type solid)
		)
		(fill yes)
		(layer "In13.Cu")
		(net "M_H_CPU1_SB_CA<1>")
	)
	(gr_poly
		(pts
			(xy 140.464032 -224.695766) (xy 140.425424 -224.673414) (xy 140.289026 -224.70999) (xy 140.325602 -224.846642)
			(xy 140.363956 -224.868994)
		)
		(stroke
			(width 0)
			(type solid)
		)
		(fill yes)
		(layer "In13.Cu")
		(net "M_H_CPU1_SA_DQ<0>")
	)
	(gr_poly
		(pts
			(xy 140.544804 -256.026158) (xy 140.444728 -255.926336) (xy 140.344652 -256.026158) (xy 140.344652 -256.07391)
			(xy 140.544804 -256.07391)
		)
		(stroke
			(width 0)
			(type solid)
		)
		(fill yes)
		(layer "In13.Cu")
		(net "M_H_CPU1_CLK_DP<0>")
	)
	(gr_poly
		(pts
			(xy 140.544804 -255.622552) (xy 140.544804 -255.578102) (xy 140.344652 -255.578102) (xy 140.344652 -255.622552)
			(xy 140.444728 -255.722628)
		)
		(stroke
			(width 0)
			(type solid)
		)
		(fill yes)
		(layer "In13.Cu")
		(net "M_H_CPU1_SA_PAR")
	)
	(gr_poly
		(pts
			(xy 140.544804 -254.4064) (xy 140.444728 -254.306324) (xy 140.344652 -254.4064) (xy 140.344652 -254.45085)
			(xy 140.544804 -254.45085)
		)
		(stroke
			(width 0)
			(type solid)
		)
		(fill yes)
		(layer "In13.Cu")
		(net "M_H_CPU1_SA_CA<4>")
	)
	(gr_poly
		(pts
			(xy 140.544804 -254.00254) (xy 140.544804 -253.95809) (xy 140.344652 -253.95809) (xy 140.344652 -254.00254)
			(xy 140.444728 -254.102616)
		)
		(stroke
			(width 0)
			(type solid)
		)
		(fill yes)
		(layer "In13.Cu")
		(net "M_H_CPU1_SA_CA<3>")
	)
	(gr_poly
		(pts
			(xy 140.544804 -252.786388) (xy 140.444728 -252.686312) (xy 140.344652 -252.786388) (xy 140.344652 -252.830838)
			(xy 140.544804 -252.830838)
		)
		(stroke
			(width 0)
			(type solid)
		)
		(fill yes)
		(layer "In13.Cu")
		(net "M_H_CPU1_SA_CA<0>")
	)
	(gr_poly
		(pts
			(xy 140.544804 -251.166376) (xy 140.444728 -251.0663) (xy 140.344652 -251.166376) (xy 140.344652 -251.210826)
			(xy 140.544804 -251.210826)
		)
		(stroke
			(width 0)
			(type solid)
		)
		(fill yes)
		(layer "In13.Cu")
		(net "M_H_CPU1_SA_CS_N<0>")
	)
	(gr_poly
		(pts
			(xy 140.544804 -250.762516) (xy 140.544804 -250.718066) (xy 140.344652 -250.718066) (xy 140.344652 -250.762516)
			(xy 140.444728 -250.862592)
		)
		(stroke
			(width 0)
			(type solid)
		)
		(fill yes)
		(layer "In13.Cu")
		(net "M_H_CPU1_RESET_N")
	)
	(gr_poly
		(pts
			(xy 140.544804 -249.142504) (xy 140.544804 -249.098054) (xy 140.344652 -249.098054) (xy 140.344652 -249.142504)
			(xy 140.444728 -249.24258)
		)
		(stroke
			(width 0)
			(type solid)
		)
		(fill yes)
		(layer "In13.Cu")
		(net "M_H_CPU1_SA_CB<7>")
	)
	(gr_poly
		(pts
			(xy 140.544804 -247.926352) (xy 140.444728 -247.826276) (xy 140.344652 -247.926352) (xy 140.344652 -247.970802)
			(xy 140.544804 -247.970802)
		)
		(stroke
			(width 0)
			(type solid)
		)
		(fill yes)
		(layer "In13.Cu")
		(net "M_H_CPU1_SA_CB<4>")
	)
	(gr_poly
		(pts
			(xy 140.544804 -247.522746) (xy 140.544804 -247.474994) (xy 140.344652 -247.474994) (xy 140.344652 -247.522746)
			(xy 140.444728 -247.622568)
		)
		(stroke
			(width 0)
			(type solid)
		)
		(fill yes)
		(layer "In13.Cu")
		(net "M_H_CPU1_SA_DQS_DP<9>")
	)
	(gr_poly
		(pts
			(xy 140.544804 -246.306086) (xy 140.444728 -246.206264) (xy 140.344652 -246.306086) (xy 140.344652 -246.353838)
			(xy 140.544804 -246.353838)
		)
		(stroke
			(width 0)
			(type solid)
		)
		(fill yes)
		(layer "In13.Cu")
		(net "M_H_CPU1_SA_DQS_DP<4>")
	)
	(gr_poly
		(pts
			(xy 140.544804 -245.90248) (xy 140.544804 -245.85803) (xy 140.344652 -245.85803) (xy 140.344652 -245.90248)
			(xy 140.444728 -246.002556)
		)
		(stroke
			(width 0)
			(type solid)
		)
		(fill yes)
		(layer "In13.Cu")
		(net "M_H_CPU1_SA_CB<3>")
	)
	(gr_poly
		(pts
			(xy 140.544804 -244.686328) (xy 140.444728 -244.586252) (xy 140.344652 -244.686328) (xy 140.344652 -244.730778)
			(xy 140.544804 -244.730778)
		)
		(stroke
			(width 0)
			(type solid)
		)
		(fill yes)
		(layer "In13.Cu")
		(net "M_H_CPU1_SA_CB<0>")
	)
	(gr_poly
		(pts
			(xy 140.544804 -244.282468) (xy 140.544804 -244.238018) (xy 140.344652 -244.238018) (xy 140.344652 -244.282468)
			(xy 140.444728 -244.382544)
		)
		(stroke
			(width 0)
			(type solid)
		)
		(fill yes)
		(layer "In13.Cu")
		(net "M_H_CPU1_SA_DQ<31>")
	)
	(gr_poly
		(pts
			(xy 140.544804 -243.066316) (xy 140.444728 -242.96624) (xy 140.344652 -243.066316) (xy 140.344652 -243.110766)
			(xy 140.544804 -243.110766)
		)
		(stroke
			(width 0)
			(type solid)
		)
		(fill yes)
		(layer "In13.Cu")
		(net "M_H_CPU1_SA_DQ<28>")
	)
	(gr_poly
		(pts
			(xy 140.544804 -242.66271) (xy 140.544804 -242.614958) (xy 140.344652 -242.614958) (xy 140.344652 -242.66271)
			(xy 140.444728 -242.762532)
		)
		(stroke
			(width 0)
			(type solid)
		)
		(fill yes)
		(layer "In13.Cu")
		(net "M_H_CPU1_SA_DQS_DP<8>")
	)
	(gr_poly
		(pts
			(xy 140.544804 -241.44605) (xy 140.444728 -241.346228) (xy 140.344652 -241.44605) (xy 140.344652 -241.493802)
			(xy 140.544804 -241.493802)
		)
		(stroke
			(width 0)
			(type solid)
		)
		(fill yes)
		(layer "In13.Cu")
		(net "M_H_CPU1_SA_DQS_DP<3>")
	)
	(gr_poly
		(pts
			(xy 140.544804 -241.042444) (xy 140.544804 -240.997994) (xy 140.344652 -240.997994) (xy 140.344652 -241.042444)
			(xy 140.444728 -241.14252)
		)
		(stroke
			(width 0)
			(type solid)
		)
		(fill yes)
		(layer "In13.Cu")
		(net "M_H_CPU1_SA_DQ<27>")
	)
	(gr_poly
		(pts
			(xy 140.544804 -239.826292) (xy 140.444728 -239.726216) (xy 140.344652 -239.826292) (xy 140.344652 -239.870742)
			(xy 140.544804 -239.870742)
		)
		(stroke
			(width 0)
			(type solid)
		)
		(fill yes)
		(layer "In13.Cu")
		(net "M_H_CPU1_SA_DQ<24>")
	)
	(gr_poly
		(pts
			(xy 140.544804 -239.422432) (xy 140.544804 -239.377982) (xy 140.344652 -239.377982) (xy 140.344652 -239.422432)
			(xy 140.444728 -239.522508)
		)
		(stroke
			(width 0)
			(type solid)
		)
		(fill yes)
		(layer "In13.Cu")
		(net "M_H_CPU1_SA_DQ<23>")
	)
	(gr_poly
		(pts
			(xy 140.544804 -238.20628) (xy 140.444728 -238.106204) (xy 140.344652 -238.20628) (xy 140.344652 -238.25073)
			(xy 140.544804 -238.25073)
		)
		(stroke
			(width 0)
			(type solid)
		)
		(fill yes)
		(layer "In13.Cu")
		(net "M_H_CPU1_SA_DQ<20>")
	)
	(gr_poly
		(pts
			(xy 140.544804 -237.802674) (xy 140.544804 -237.754922) (xy 140.344652 -237.754922) (xy 140.344652 -237.802674)
			(xy 140.444728 -237.902496)
		)
		(stroke
			(width 0)
			(type solid)
		)
		(fill yes)
		(layer "In13.Cu")
		(net "M_H_CPU1_SA_DQS_DP<7>")
	)
	(gr_poly
		(pts
			(xy 140.544804 -236.586014) (xy 140.444728 -236.486192) (xy 140.344652 -236.586014) (xy 140.344652 -236.633766)
			(xy 140.544804 -236.633766)
		)
		(stroke
			(width 0)
			(type solid)
		)
		(fill yes)
		(layer "In13.Cu")
		(net "M_H_CPU1_SA_DQS_DP<2>")
	)
	(gr_poly
		(pts
			(xy 140.544804 -236.182408) (xy 140.544804 -236.137958) (xy 140.344652 -236.137958) (xy 140.344652 -236.182408)
			(xy 140.444728 -236.282484)
		)
		(stroke
			(width 0)
			(type solid)
		)
		(fill yes)
		(layer "In13.Cu")
		(net "M_H_CPU1_SA_DQ<19>")
	)
	(gr_poly
		(pts
			(xy 140.544804 -234.966256) (xy 140.444728 -234.86618) (xy 140.344652 -234.966256) (xy 140.344652 -235.010706)
			(xy 140.544804 -235.010706)
		)
		(stroke
			(width 0)
			(type solid)
		)
		(fill yes)
		(layer "In13.Cu")
		(net "M_H_CPU1_SA_DQ<16>")
	)
	(gr_poly
		(pts
			(xy 140.544804 -234.562396) (xy 140.544804 -234.517946) (xy 140.344652 -234.517946) (xy 140.344652 -234.562396)
			(xy 140.444728 -234.662472)
		)
		(stroke
			(width 0)
			(type solid)
		)
		(fill yes)
		(layer "In13.Cu")
		(net "M_H_CPU1_SA_DQ<15>")
	)
	(gr_poly
		(pts
			(xy 140.544804 -233.346244) (xy 140.444728 -233.246168) (xy 140.344652 -233.346244) (xy 140.344652 -233.390694)
			(xy 140.544804 -233.390694)
		)
		(stroke
			(width 0)
			(type solid)
		)
		(fill yes)
		(layer "In13.Cu")
		(net "M_H_CPU1_SA_DQ<12>")
	)
	(gr_poly
		(pts
			(xy 140.544804 -232.942638) (xy 140.544804 -232.894886) (xy 140.344652 -232.894886) (xy 140.344652 -232.942638)
			(xy 140.444728 -233.04246)
		)
		(stroke
			(width 0)
			(type solid)
		)
		(fill yes)
		(layer "In13.Cu")
		(net "M_H_CPU1_SA_DQS_DP<6>")
	)
	(gr_poly
		(pts
			(xy 140.544804 -231.725978) (xy 140.444728 -231.626156) (xy 140.344652 -231.725978) (xy 140.344652 -231.77373)
			(xy 140.544804 -231.77373)
		)
		(stroke
			(width 0)
			(type solid)
		)
		(fill yes)
		(layer "In13.Cu")
		(net "M_H_CPU1_SA_DQS_DP<1>")
	)
	(gr_poly
		(pts
			(xy 140.544804 -231.322626) (xy 140.544804 -231.278176) (xy 140.344652 -231.278176) (xy 140.344652 -231.322626)
			(xy 140.444728 -231.422702)
		)
		(stroke
			(width 0)
			(type solid)
		)
		(fill yes)
		(layer "In13.Cu")
		(net "M_H_CPU1_SA_DQ<11>")
	)
	(gr_poly
		(pts
			(xy 140.544804 -230.10622) (xy 140.444728 -230.006144) (xy 140.344652 -230.10622) (xy 140.344652 -230.15067)
			(xy 140.544804 -230.15067)
		)
		(stroke
			(width 0)
			(type solid)
		)
		(fill yes)
		(layer "In13.Cu")
		(net "M_H_CPU1_SA_DQ<8>")
	)
	(gr_poly
		(pts
			(xy 140.544804 -229.702614) (xy 140.544804 -229.658164) (xy 140.344652 -229.658164) (xy 140.344652 -229.702614)
			(xy 140.444728 -229.80269)
		)
		(stroke
			(width 0)
			(type solid)
		)
		(fill yes)
		(layer "In13.Cu")
		(net "M_H_CPU1_SA_DQ<7>")
	)
	(gr_poly
		(pts
			(xy 140.544804 -228.486462) (xy 140.444728 -228.386386) (xy 140.344652 -228.486462) (xy 140.344652 -228.530912)
			(xy 140.544804 -228.530912)
		)
		(stroke
			(width 0)
			(type solid)
		)
		(fill yes)
		(layer "In13.Cu")
		(net "M_H_CPU1_SA_DQ<4>")
	)
	(gr_poly
		(pts
			(xy 140.544804 -228.082856) (xy 140.544804 -228.035104) (xy 140.344652 -228.035104) (xy 140.344652 -228.082856)
			(xy 140.444728 -228.182678)
		)
		(stroke
			(width 0)
			(type solid)
		)
		(fill yes)
		(layer "In13.Cu")
		(net "M_H_CPU1_SA_DQS_DP<5>")
	)
	(gr_poly
		(pts
			(xy 140.544804 -226.866196) (xy 140.444728 -226.766374) (xy 140.344652 -226.866196) (xy 140.344652 -226.913948)
			(xy 140.544804 -226.913948)
		)
		(stroke
			(width 0)
			(type solid)
		)
		(fill yes)
		(layer "In13.Cu")
		(net "M_H_CPU1_SA_DQS_DP<0>")
	)
	(gr_poly
		(pts
			(xy 140.544804 -226.46259) (xy 140.544804 -226.41814) (xy 140.344652 -226.41814) (xy 140.344652 -226.46259)
			(xy 140.444728 -226.562666)
		)
		(stroke
			(width 0)
			(type solid)
		)
		(fill yes)
		(layer "In13.Cu")
		(net "M_H_CPU1_SA_DQ<3>")
	)
	(gr_poly
		(pts
			(xy 140.600938 -225.379026) (xy 140.564108 -225.242374) (xy 140.525754 -225.220022) (xy 140.425678 -225.39325)
			(xy 140.464286 -225.415602)
		)
		(stroke
			(width 0)
			(type solid)
		)
		(fill yes)
		(layer "In13.Cu")
		(net "M_H_CPU1_SA_DQ<2>")
	)
	(gr_poly
		(pts
			(xy 140.844778 -292.918134) (xy 140.744702 -292.818058) (xy 140.644626 -292.918134) (xy 140.644626 -292.962584)
			(xy 140.844778 -292.962584)
		)
		(stroke
			(width 0)
			(type solid)
		)
		(fill yes)
		(layer "In13.Cu")
		(net "M_H_CPU1_SB_DQ<29>")
	)
	(gr_poly
		(pts
			(xy 140.844778 -292.514274) (xy 140.844778 -292.469824) (xy 140.644626 -292.469824) (xy 140.644626 -292.514274)
			(xy 140.744702 -292.61435)
		)
		(stroke
			(width 0)
			(type solid)
		)
		(fill yes)
		(layer "In13.Cu")
		(net "M_H_CPU1_SB_DQ<30>")
	)
	(gr_poly
		(pts
			(xy 140.844778 -291.297868) (xy 140.744702 -291.198046) (xy 140.644626 -291.297868) (xy 140.644626 -291.34562)
			(xy 140.844778 -291.34562)
		)
		(stroke
			(width 0)
			(type solid)
		)
		(fill yes)
		(layer "In13.Cu")
		(net "M_H_CPU1_SB_DQS_DN<8>")
	)
	(gr_poly
		(pts
			(xy 140.844778 -290.894516) (xy 140.844778 -290.846764) (xy 140.644626 -290.846764) (xy 140.644626 -290.894516)
			(xy 140.744702 -290.994338)
		)
		(stroke
			(width 0)
			(type solid)
		)
		(fill yes)
		(layer "In13.Cu")
		(net "M_H_CPU1_SB_DQS_DN<3>")
	)
	(gr_poly
		(pts
			(xy 140.844778 -289.67811) (xy 140.744702 -289.578034) (xy 140.644626 -289.67811) (xy 140.644626 -289.72256)
			(xy 140.844778 -289.72256)
		)
		(stroke
			(width 0)
			(type solid)
		)
		(fill yes)
		(layer "In13.Cu")
		(net "M_H_CPU1_SB_DQ<25>")
	)
	(gr_poly
		(pts
			(xy 140.844778 -289.27425) (xy 140.844778 -289.2298) (xy 140.644626 -289.2298) (xy 140.644626 -289.27425)
			(xy 140.744702 -289.374326)
		)
		(stroke
			(width 0)
			(type solid)
		)
		(fill yes)
		(layer "In13.Cu")
		(net "M_H_CPU1_SB_DQ<26>")
	)
	(gr_poly
		(pts
			(xy 140.844778 -288.058098) (xy 140.744702 -287.958022) (xy 140.644626 -288.058098) (xy 140.644626 -288.102548)
			(xy 140.844778 -288.102548)
		)
		(stroke
			(width 0)
			(type solid)
		)
		(fill yes)
		(layer "In13.Cu")
		(net "M_H_CPU1_SB_DQ<21>")
	)
	(gr_poly
		(pts
			(xy 140.844778 -287.654492) (xy 140.844778 -287.610042) (xy 140.644626 -287.610042) (xy 140.644626 -287.654492)
			(xy 140.744702 -287.754568)
		)
		(stroke
			(width 0)
			(type solid)
		)
		(fill yes)
		(layer "In13.Cu")
		(net "M_H_CPU1_SB_DQ<22>")
	)
	(gr_poly
		(pts
			(xy 140.844778 -286.438086) (xy 140.744702 -286.33801) (xy 140.644626 -286.438086) (xy 140.644626 -286.485838)
			(xy 140.844778 -286.485838)
		)
		(stroke
			(width 0)
			(type solid)
		)
		(fill yes)
		(layer "In13.Cu")
		(net "M_H_CPU1_SB_DQS_DN<7>")
	)
	(gr_poly
		(pts
			(xy 140.844778 -286.034734) (xy 140.844778 -285.986982) (xy 140.644626 -285.986982) (xy 140.644626 -286.034734)
			(xy 140.744702 -286.134556)
		)
		(stroke
			(width 0)
			(type solid)
		)
		(fill yes)
		(layer "In13.Cu")
		(net "M_H_CPU1_SB_DQS_DN<2>")
	)
	(gr_poly
		(pts
			(xy 140.844778 -284.818328) (xy 140.744702 -284.718252) (xy 140.644626 -284.818328) (xy 140.644626 -284.862778)
			(xy 140.844778 -284.862778)
		)
		(stroke
			(width 0)
			(type solid)
		)
		(fill yes)
		(layer "In13.Cu")
		(net "M_H_CPU1_SB_DQ<17>")
	)
	(gr_poly
		(pts
			(xy 140.844778 -284.414468) (xy 140.844778 -284.370018) (xy 140.644626 -284.370018) (xy 140.644626 -284.414468)
			(xy 140.744702 -284.514544)
		)
		(stroke
			(width 0)
			(type solid)
		)
		(fill yes)
		(layer "In13.Cu")
		(net "M_H_CPU1_SB_DQ<18>")
	)
	(gr_poly
		(pts
			(xy 140.844778 -283.198316) (xy 140.744702 -283.09824) (xy 140.644626 -283.198316) (xy 140.644626 -283.242766)
			(xy 140.844778 -283.242766)
		)
		(stroke
			(width 0)
			(type solid)
		)
		(fill yes)
		(layer "In13.Cu")
		(net "M_H_CPU1_SB_DQ<13>")
	)
	(gr_poly
		(pts
			(xy 140.844778 -282.794456) (xy 140.844778 -282.750006) (xy 140.644626 -282.750006) (xy 140.644626 -282.794456)
			(xy 140.744702 -282.894532)
		)
		(stroke
			(width 0)
			(type solid)
		)
		(fill yes)
		(layer "In13.Cu")
		(net "M_H_CPU1_SB_DQ<14>")
	)
	(gr_poly
		(pts
			(xy 140.844778 -281.57805) (xy 140.744702 -281.478228) (xy 140.644626 -281.57805) (xy 140.644626 -281.625802)
			(xy 140.844778 -281.625802)
		)
		(stroke
			(width 0)
			(type solid)
		)
		(fill yes)
		(layer "In13.Cu")
		(net "M_H_CPU1_SB_DQS_DN<6>")
	)
	(gr_poly
		(pts
			(xy 140.844778 -281.174698) (xy 140.844778 -281.126946) (xy 140.644626 -281.126946) (xy 140.644626 -281.174698)
			(xy 140.744702 -281.27452)
		)
		(stroke
			(width 0)
			(type solid)
		)
		(fill yes)
		(layer "In13.Cu")
		(net "M_H_CPU1_SB_DQS_DN<1>")
	)
	(gr_poly
		(pts
			(xy 140.844778 -279.958292) (xy 140.744702 -279.858216) (xy 140.644626 -279.958292) (xy 140.644626 -280.002742)
			(xy 140.844778 -280.002742)
		)
		(stroke
			(width 0)
			(type solid)
		)
		(fill yes)
		(layer "In13.Cu")
		(net "M_H_CPU1_SB_DQ<9>")
	)
	(gr_poly
		(pts
			(xy 140.844778 -279.554432) (xy 140.844778 -279.509982) (xy 140.644626 -279.509982) (xy 140.644626 -279.554432)
			(xy 140.744702 -279.654508)
		)
		(stroke
			(width 0)
			(type solid)
		)
		(fill yes)
		(layer "In13.Cu")
		(net "M_H_CPU1_SB_DQ<10>")
	)
	(gr_poly
		(pts
			(xy 140.844778 -278.33828) (xy 140.744702 -278.238204) (xy 140.644626 -278.33828) (xy 140.644626 -278.38273)
			(xy 140.844778 -278.38273)
		)
		(stroke
			(width 0)
			(type solid)
		)
		(fill yes)
		(layer "In13.Cu")
		(net "M_H_CPU1_SB_DQ<5>")
	)
	(gr_poly
		(pts
			(xy 140.844778 -277.93442) (xy 140.844778 -277.88997) (xy 140.644626 -277.88997) (xy 140.644626 -277.93442)
			(xy 140.744702 -278.034496)
		)
		(stroke
			(width 0)
			(type solid)
		)
		(fill yes)
		(layer "In13.Cu")
		(net "M_H_CPU1_SB_DQ<6>")
	)
	(gr_poly
		(pts
			(xy 140.844778 -276.718014) (xy 140.744702 -276.618192) (xy 140.644626 -276.718014) (xy 140.644626 -276.765766)
			(xy 140.844778 -276.765766)
		)
		(stroke
			(width 0)
			(type solid)
		)
		(fill yes)
		(layer "In13.Cu")
		(net "M_H_CPU1_SB_DQS_DN<5>")
	)
	(gr_poly
		(pts
			(xy 140.844778 -276.314662) (xy 140.844778 -276.26691) (xy 140.644626 -276.26691) (xy 140.644626 -276.314662)
			(xy 140.744702 -276.414484)
		)
		(stroke
			(width 0)
			(type solid)
		)
		(fill yes)
		(layer "In13.Cu")
		(net "M_H_CPU1_SB_DQS_DN<0>")
	)
	(gr_poly
		(pts
			(xy 140.844778 -275.098256) (xy 140.744702 -274.99818) (xy 140.644626 -275.098256) (xy 140.644626 -275.142706)
			(xy 140.844778 -275.142706)
		)
		(stroke
			(width 0)
			(type solid)
		)
		(fill yes)
		(layer "In13.Cu")
		(net "M_H_CPU1_SB_DQ<1>")
	)
	(gr_poly
		(pts
			(xy 140.844778 -274.694396) (xy 140.844778 -274.649946) (xy 140.644626 -274.649946) (xy 140.644626 -274.694396)
			(xy 140.744702 -274.794472)
		)
		(stroke
			(width 0)
			(type solid)
		)
		(fill yes)
		(layer "In13.Cu")
		(net "M_H_CPU1_SB_DQ<2>")
	)
	(gr_poly
		(pts
			(xy 140.844778 -273.478244) (xy 140.744702 -273.378168) (xy 140.644626 -273.478244) (xy 140.644626 -273.522694)
			(xy 140.844778 -273.522694)
		)
		(stroke
			(width 0)
			(type solid)
		)
		(fill yes)
		(layer "In13.Cu")
		(net "M_H_CPU1_SB_CB<1>")
	)
	(gr_poly
		(pts
			(xy 140.844778 -273.074384) (xy 140.844778 -273.029934) (xy 140.644626 -273.029934) (xy 140.644626 -273.074384)
			(xy 140.744702 -273.17446)
		)
		(stroke
			(width 0)
			(type solid)
		)
		(fill yes)
		(layer "In13.Cu")
		(net "M_H_CPU1_SB_CB<2>")
	)
	(gr_poly
		(pts
			(xy 140.844778 -271.857978) (xy 140.744702 -271.758156) (xy 140.644626 -271.857978) (xy 140.644626 -271.90573)
			(xy 140.844778 -271.90573)
		)
		(stroke
			(width 0)
			(type solid)
		)
		(fill yes)
		(layer "In13.Cu")
		(net "M_H_CPU1_SB_DQS_DN<4>")
	)
	(gr_poly
		(pts
			(xy 140.844778 -271.454626) (xy 140.844778 -271.406874) (xy 140.644626 -271.406874) (xy 140.644626 -271.454626)
			(xy 140.744702 -271.554448)
		)
		(stroke
			(width 0)
			(type solid)
		)
		(fill yes)
		(layer "In13.Cu")
		(net "M_H_CPU1_SB_DQS_DN<9>")
	)
	(gr_poly
		(pts
			(xy 140.844778 -270.23822) (xy 140.744702 -270.138144) (xy 140.644626 -270.23822) (xy 140.644626 -270.28267)
			(xy 140.844778 -270.28267)
		)
		(stroke
			(width 0)
			(type solid)
		)
		(fill yes)
		(layer "In13.Cu")
		(net "M_H_CPU1_SB_CB<5>")
	)
	(gr_poly
		(pts
			(xy 140.844778 -269.83436) (xy 140.844778 -269.78991) (xy 140.644626 -269.78991) (xy 140.644626 -269.83436)
			(xy 140.744702 -269.934436)
		)
		(stroke
			(width 0)
			(type solid)
		)
		(fill yes)
		(layer "In13.Cu")
		(net "M_H_CPU1_SB_CB<6>")
	)
	(gr_poly
		(pts
			(xy 140.844778 -266.998196) (xy 140.744702 -266.89812) (xy 140.644626 -266.998196) (xy 140.644626 -267.042646)
			(xy 140.844778 -267.042646)
		)
		(stroke
			(width 0)
			(type solid)
		)
		(fill yes)
		(layer "In13.Cu")
		(net "M_H_CPU1_SA_RSP<0>")
	)
	(gr_poly
		(pts
			(xy 140.844778 -266.594336) (xy 140.844778 -266.549886) (xy 140.644626 -266.549886) (xy 140.644626 -266.594336)
			(xy 140.744702 -266.694412)
		)
		(stroke
			(width 0)
			(type solid)
		)
		(fill yes)
		(layer "In13.Cu")
		(net "M_H_CPU1_SB_CS_N<1>")
	)
	(gr_poly
		(pts
			(xy 140.844778 -265.378184) (xy 140.744702 -265.278108) (xy 140.644626 -265.378184) (xy 140.644626 -265.422634)
			(xy 140.844778 -265.422634)
		)
		(stroke
			(width 0)
			(type solid)
		)
		(fill yes)
		(layer "In13.Cu")
		(net "M_H_CPU1_SB_PAR")
	)
	(gr_poly
		(pts
			(xy 140.844778 -263.758172) (xy 140.744702 -263.658096) (xy 140.644626 -263.758172) (xy 140.644626 -263.802622)
			(xy 140.844778 -263.802622)
		)
		(stroke
			(width 0)
			(type solid)
		)
		(fill yes)
		(layer "In13.Cu")
		(net "M_H_CPU1_SB_CA<4>")
	)
	(gr_poly
		(pts
			(xy 140.844778 -263.354312) (xy 140.844778 -263.309862) (xy 140.644626 -263.309862) (xy 140.644626 -263.354312)
			(xy 140.744702 -263.454388)
		)
		(stroke
			(width 0)
			(type solid)
		)
		(fill yes)
		(layer "In13.Cu")
		(net "M_H_CPU1_SB_CA<3>")
	)
	(gr_poly
		(pts
			(xy 140.844778 -262.13816) (xy 140.744702 -262.038084) (xy 140.644626 -262.13816) (xy 140.644626 -262.18261)
			(xy 140.844778 -262.18261)
		)
		(stroke
			(width 0)
			(type solid)
		)
		(fill yes)
		(layer "In13.Cu")
		(net "M_H_CPU1_SB_CA<0>")
	)
	(gr_poly
		(pts
			(xy 140.933932 -225.505772) (xy 140.895324 -225.48342) (xy 140.758926 -225.519996) (xy 140.795502 -225.656648)
			(xy 140.833856 -225.679)
		)
		(stroke
			(width 0)
			(type solid)
		)
		(fill yes)
		(layer "In13.Cu")
		(net "M_H_CPU1_SA_DQ<1>")
	)
	(gr_poly
		(pts
			(xy 140.93444 -223.884998) (xy 140.896086 -223.862646) (xy 140.759434 -223.899222) (xy 140.79601 -224.035874)
			(xy 140.834618 -224.058226)
		)
		(stroke
			(width 0)
			(type solid)
		)
		(fill yes)
		(layer "In13.Cu")
		(net "M_H_CPU1_SA_DQ<0>")
	)
	(gr_poly
		(pts
			(xy 141.014958 -256.432812) (xy 141.014958 -256.38506) (xy 140.814806 -256.38506) (xy 140.814806 -256.432812)
			(xy 140.914882 -256.532634)
		)
		(stroke
			(width 0)
			(type solid)
		)
		(fill yes)
		(layer "In13.Cu")
		(net "M_H_CPU1_CLK_DN<0>")
	)
	(gr_poly
		(pts
			(xy 141.014958 -255.216406) (xy 140.914882 -255.11633) (xy 140.814806 -255.216406) (xy 140.814806 -255.260856)
			(xy 141.014958 -255.260856)
		)
		(stroke
			(width 0)
			(type solid)
		)
		(fill yes)
		(layer "In13.Cu")
		(net "M_H_CPU1_SA_CA<6>")
	)
	(gr_poly
		(pts
			(xy 141.014958 -254.812546) (xy 141.014958 -254.768096) (xy 140.814806 -254.768096) (xy 140.814806 -254.812546)
			(xy 140.914882 -254.912622)
		)
		(stroke
			(width 0)
			(type solid)
		)
		(fill yes)
		(layer "In13.Cu")
		(net "M_H_CPU1_SA_CA<5>")
	)
	(gr_poly
		(pts
			(xy 141.014958 -253.596394) (xy 140.914882 -253.496318) (xy 140.814806 -253.596394) (xy 140.814806 -253.640844)
			(xy 141.014958 -253.640844)
		)
		(stroke
			(width 0)
			(type solid)
		)
		(fill yes)
		(layer "In13.Cu")
		(net "M_H_CPU1_SA_CA<2>")
	)
	(gr_poly
		(pts
			(xy 141.014958 -253.192534) (xy 141.014958 -253.148084) (xy 140.814806 -253.148084) (xy 140.814806 -253.192534)
			(xy 140.914882 -253.29261)
		)
		(stroke
			(width 0)
			(type solid)
		)
		(fill yes)
		(layer "In13.Cu")
		(net "M_H_CPU1_SA_CA<1>")
	)
	(gr_poly
		(pts
			(xy 141.014958 -251.976382) (xy 140.914882 -251.876306) (xy 140.814806 -251.976382) (xy 140.814806 -252.020832)
			(xy 141.014958 -252.020832)
		)
		(stroke
			(width 0)
			(type solid)
		)
		(fill yes)
		(layer "In13.Cu")
		(net "M_H_CPU1_SA_CS_N<1>")
	)
	(gr_poly
		(pts
			(xy 141.014958 -250.35637) (xy 140.914882 -250.256294) (xy 140.814806 -250.35637) (xy 140.814806 -250.40082)
			(xy 141.014958 -250.40082)
		)
		(stroke
			(width 0)
			(type solid)
		)
		(fill yes)
		(layer "In13.Cu")
		(net "M_H_CPU1_ALERT_R_N")
	)
	(gr_poly
		(pts
			(xy 141.014958 -248.736358) (xy 140.914882 -248.636282) (xy 140.814806 -248.736358) (xy 140.814806 -248.780808)
			(xy 141.014958 -248.780808)
		)
		(stroke
			(width 0)
			(type solid)
		)
		(fill yes)
		(layer "In13.Cu")
		(net "M_H_CPU1_SA_CB<5>")
	)
	(gr_poly
		(pts
			(xy 141.014958 -248.332498) (xy 141.014958 -248.288048) (xy 140.814806 -248.288048) (xy 140.814806 -248.332498)
			(xy 140.914882 -248.432574)
		)
		(stroke
			(width 0)
			(type solid)
		)
		(fill yes)
		(layer "In13.Cu")
		(net "M_H_CPU1_SA_CB<6>")
	)
	(gr_poly
		(pts
			(xy 141.014958 -247.116092) (xy 140.914882 -247.01627) (xy 140.814806 -247.116092) (xy 140.814806 -247.163844)
			(xy 141.014958 -247.163844)
		)
		(stroke
			(width 0)
			(type solid)
		)
		(fill yes)
		(layer "In13.Cu")
		(net "M_H_CPU1_SA_DQS_DN<9>")
	)
	(gr_poly
		(pts
			(xy 141.014958 -246.71274) (xy 141.014958 -246.664988) (xy 140.814806 -246.664988) (xy 140.814806 -246.71274)
			(xy 140.914882 -246.812562)
		)
		(stroke
			(width 0)
			(type solid)
		)
		(fill yes)
		(layer "In13.Cu")
		(net "M_H_CPU1_SA_DQS_DN<4>")
	)
	(gr_poly
		(pts
			(xy 141.014958 -245.496334) (xy 140.914882 -245.396258) (xy 140.814806 -245.496334) (xy 140.814806 -245.540784)
			(xy 141.014958 -245.540784)
		)
		(stroke
			(width 0)
			(type solid)
		)
		(fill yes)
		(layer "In13.Cu")
		(net "M_H_CPU1_SA_CB<1>")
	)
	(gr_poly
		(pts
			(xy 141.014958 -245.092474) (xy 141.014958 -245.048024) (xy 140.814806 -245.048024) (xy 140.814806 -245.092474)
			(xy 140.914882 -245.19255)
		)
		(stroke
			(width 0)
			(type solid)
		)
		(fill yes)
		(layer "In13.Cu")
		(net "M_H_CPU1_SA_CB<2>")
	)
	(gr_poly
		(pts
			(xy 141.014958 -243.876322) (xy 140.914882 -243.776246) (xy 140.814806 -243.876322) (xy 140.814806 -243.920772)
			(xy 141.014958 -243.920772)
		)
		(stroke
			(width 0)
			(type solid)
		)
		(fill yes)
		(layer "In13.Cu")
		(net "M_H_CPU1_SA_DQ<29>")
	)
	(gr_poly
		(pts
			(xy 141.014958 -243.472462) (xy 141.014958 -243.428012) (xy 140.814806 -243.428012) (xy 140.814806 -243.472462)
			(xy 140.914882 -243.572538)
		)
		(stroke
			(width 0)
			(type solid)
		)
		(fill yes)
		(layer "In13.Cu")
		(net "M_H_CPU1_SA_DQ<30>")
	)
	(gr_poly
		(pts
			(xy 141.014958 -242.256056) (xy 140.914882 -242.156234) (xy 140.814806 -242.256056) (xy 140.814806 -242.303808)
			(xy 141.014958 -242.303808)
		)
		(stroke
			(width 0)
			(type solid)
		)
		(fill yes)
		(layer "In13.Cu")
		(net "M_H_CPU1_SA_DQS_DN<8>")
	)
	(gr_poly
		(pts
			(xy 141.014958 -241.852704) (xy 141.014958 -241.804952) (xy 140.814806 -241.804952) (xy 140.814806 -241.852704)
			(xy 140.914882 -241.952526)
		)
		(stroke
			(width 0)
			(type solid)
		)
		(fill yes)
		(layer "In13.Cu")
		(net "M_H_CPU1_SA_DQS_DN<3>")
	)
	(gr_poly
		(pts
			(xy 141.014958 -240.636298) (xy 140.914882 -240.536222) (xy 140.814806 -240.636298) (xy 140.814806 -240.680748)
			(xy 141.014958 -240.680748)
		)
		(stroke
			(width 0)
			(type solid)
		)
		(fill yes)
		(layer "In13.Cu")
		(net "M_H_CPU1_SA_DQ<25>")
	)
	(gr_poly
		(pts
			(xy 141.014958 -240.232438) (xy 141.014958 -240.187988) (xy 140.814806 -240.187988) (xy 140.814806 -240.232438)
			(xy 140.914882 -240.332514)
		)
		(stroke
			(width 0)
			(type solid)
		)
		(fill yes)
		(layer "In13.Cu")
		(net "M_H_CPU1_SA_DQ<26>")
	)
	(gr_poly
		(pts
			(xy 141.014958 -239.016286) (xy 140.914882 -238.91621) (xy 140.814806 -239.016286) (xy 140.814806 -239.060736)
			(xy 141.014958 -239.060736)
		)
		(stroke
			(width 0)
			(type solid)
		)
		(fill yes)
		(layer "In13.Cu")
		(net "M_H_CPU1_SA_DQ<21>")
	)
	(gr_poly
		(pts
			(xy 141.014958 -238.612426) (xy 141.014958 -238.567976) (xy 140.814806 -238.567976) (xy 140.814806 -238.612426)
			(xy 140.914882 -238.712502)
		)
		(stroke
			(width 0)
			(type solid)
		)
		(fill yes)
		(layer "In13.Cu")
		(net "M_H_CPU1_SA_DQ<22>")
	)
	(gr_poly
		(pts
			(xy 141.014958 -237.39602) (xy 140.914882 -237.296198) (xy 140.814806 -237.39602) (xy 140.814806 -237.443772)
			(xy 141.014958 -237.443772)
		)
		(stroke
			(width 0)
			(type solid)
		)
		(fill yes)
		(layer "In13.Cu")
		(net "M_H_CPU1_SA_DQS_DN<7>")
	)
	(gr_poly
		(pts
			(xy 141.014958 -236.992668) (xy 141.014958 -236.944916) (xy 140.814806 -236.944916) (xy 140.814806 -236.992668)
			(xy 140.914882 -237.09249)
		)
		(stroke
			(width 0)
			(type solid)
		)
		(fill yes)
		(layer "In13.Cu")
		(net "M_H_CPU1_SA_DQS_DN<2>")
	)
	(gr_poly
		(pts
			(xy 141.014958 -235.776262) (xy 140.914882 -235.676186) (xy 140.814806 -235.776262) (xy 140.814806 -235.820712)
			(xy 141.014958 -235.820712)
		)
		(stroke
			(width 0)
			(type solid)
		)
		(fill yes)
		(layer "In13.Cu")
		(net "M_H_CPU1_SA_DQ<17>")
	)
	(gr_poly
		(pts
			(xy 141.014958 -235.372402) (xy 141.014958 -235.327952) (xy 140.814806 -235.327952) (xy 140.814806 -235.372402)
			(xy 140.914882 -235.472478)
		)
		(stroke
			(width 0)
			(type solid)
		)
		(fill yes)
		(layer "In13.Cu")
		(net "M_H_CPU1_SA_DQ<18>")
	)
	(gr_poly
		(pts
			(xy 141.014958 -234.15625) (xy 140.914882 -234.056174) (xy 140.814806 -234.15625) (xy 140.814806 -234.2007)
			(xy 141.014958 -234.2007)
		)
		(stroke
			(width 0)
			(type solid)
		)
		(fill yes)
		(layer "In13.Cu")
		(net "M_H_CPU1_SA_DQ<13>")
	)
	(gr_poly
		(pts
			(xy 141.014958 -233.75239) (xy 141.014958 -233.70794) (xy 140.814806 -233.70794) (xy 140.814806 -233.75239)
			(xy 140.914882 -233.852466)
		)
		(stroke
			(width 0)
			(type solid)
		)
		(fill yes)
		(layer "In13.Cu")
		(net "M_H_CPU1_SA_DQ<14>")
	)
	(gr_poly
		(pts
			(xy 141.014958 -232.535984) (xy 140.914882 -232.436162) (xy 140.814806 -232.535984) (xy 140.814806 -232.583736)
			(xy 141.014958 -232.583736)
		)
		(stroke
			(width 0)
			(type solid)
		)
		(fill yes)
		(layer "In13.Cu")
		(net "M_H_CPU1_SA_DQS_DN<6>")
	)
	(gr_poly
		(pts
			(xy 141.014958 -232.132632) (xy 141.014958 -232.08488) (xy 140.814806 -232.08488) (xy 140.814806 -232.132632)
			(xy 140.914882 -232.232454)
		)
		(stroke
			(width 0)
			(type solid)
		)
		(fill yes)
		(layer "In13.Cu")
		(net "M_H_CPU1_SA_DQS_DN<1>")
	)
	(gr_poly
		(pts
			(xy 141.014958 -230.916226) (xy 140.914882 -230.81615) (xy 140.814806 -230.916226) (xy 140.814806 -230.960676)
			(xy 141.014958 -230.960676)
		)
		(stroke
			(width 0)
			(type solid)
		)
		(fill yes)
		(layer "In13.Cu")
		(net "M_H_CPU1_SA_DQ<9>")
	)
	(gr_poly
		(pts
			(xy 141.014958 -230.51262) (xy 141.014958 -230.46817) (xy 140.814806 -230.46817) (xy 140.814806 -230.51262)
			(xy 140.914882 -230.612696)
		)
		(stroke
			(width 0)
			(type solid)
		)
		(fill yes)
		(layer "In13.Cu")
		(net "M_H_CPU1_SA_DQ<10>")
	)
	(gr_poly
		(pts
			(xy 141.014958 -229.296214) (xy 140.914882 -229.196138) (xy 140.814806 -229.296214) (xy 140.814806 -229.340664)
			(xy 141.014958 -229.340664)
		)
		(stroke
			(width 0)
			(type solid)
		)
		(fill yes)
		(layer "In13.Cu")
		(net "M_H_CPU1_SA_DQ<5>")
	)
	(gr_poly
		(pts
			(xy 141.014958 -228.892608) (xy 141.014958 -228.848158) (xy 140.814806 -228.848158) (xy 140.814806 -228.892608)
			(xy 140.914882 -228.992684)
		)
		(stroke
			(width 0)
			(type solid)
		)
		(fill yes)
		(layer "In13.Cu")
		(net "M_H_CPU1_SA_DQ<6>")
	)
	(gr_poly
		(pts
			(xy 141.014958 -227.676202) (xy 140.914882 -227.57638) (xy 140.814806 -227.676202) (xy 140.814806 -227.723954)
			(xy 141.014958 -227.723954)
		)
		(stroke
			(width 0)
			(type solid)
		)
		(fill yes)
		(layer "In13.Cu")
		(net "M_H_CPU1_SA_DQS_DN<5>")
	)
	(gr_poly
		(pts
			(xy 141.014958 -227.27285) (xy 141.014958 -227.225098) (xy 140.814806 -227.225098) (xy 140.814806 -227.27285)
			(xy 140.914882 -227.372672)
		)
		(stroke
			(width 0)
			(type solid)
		)
		(fill yes)
		(layer "In13.Cu")
		(net "M_H_CPU1_SA_DQS_DN<0>")
	)
	(gr_poly
		(pts
			(xy 141.070076 -224.57029) (xy 141.0335 -224.433638) (xy 140.994892 -224.41154) (xy 140.894816 -224.584768)
			(xy 140.933424 -224.606866)
		)
		(stroke
			(width 0)
			(type solid)
		)
		(fill yes)
		(layer "In13.Cu")
		(net "M_H_CPU1_SA_DQ<2>")
	)
	(gr_poly
		(pts
			(xy 141.070838 -226.189032) (xy 141.034008 -226.05238) (xy 140.995654 -226.030028) (xy 140.895578 -226.203256)
			(xy 140.934186 -226.225608)
		)
		(stroke
			(width 0)
			(type solid)
		)
		(fill yes)
		(layer "In13.Cu")
		(net "M_H_CPU1_SA_DQ<3>")
	)
	(gr_poly
		(pts
			(xy 141.314932 -293.32428) (xy 141.314932 -293.27983) (xy 141.11478 -293.27983) (xy 141.11478 -293.32428)
			(xy 141.214856 -293.424356)
		)
		(stroke
			(width 0)
			(type solid)
		)
		(fill yes)
		(layer "In13.Cu")
		(net "M_H_CPU1_SB_DQ<31>")
	)
	(gr_poly
		(pts
			(xy 141.314932 -292.108128) (xy 141.214856 -292.008052) (xy 141.11478 -292.108128) (xy 141.11478 -292.152578)
			(xy 141.314932 -292.152578)
		)
		(stroke
			(width 0)
			(type solid)
		)
		(fill yes)
		(layer "In13.Cu")
		(net "M_H_CPU1_SB_DQ<28>")
	)
	(gr_poly
		(pts
			(xy 141.314932 -291.704522) (xy 141.314932 -291.65677) (xy 141.11478 -291.65677) (xy 141.11478 -291.704522)
			(xy 141.214856 -291.804344)
		)
		(stroke
			(width 0)
			(type solid)
		)
		(fill yes)
		(layer "In13.Cu")
		(net "M_H_CPU1_SB_DQS_DP<8>")
	)
	(gr_poly
		(pts
			(xy 141.314932 -290.487862) (xy 141.214856 -290.38804) (xy 141.11478 -290.487862) (xy 141.11478 -290.535614)
			(xy 141.314932 -290.535614)
		)
		(stroke
			(width 0)
			(type solid)
		)
		(fill yes)
		(layer "In13.Cu")
		(net "M_H_CPU1_SB_DQS_DP<3>")
	)
	(gr_poly
		(pts
			(xy 141.314932 -290.084256) (xy 141.314932 -290.039806) (xy 141.11478 -290.039806) (xy 141.11478 -290.084256)
			(xy 141.214856 -290.184332)
		)
		(stroke
			(width 0)
			(type solid)
		)
		(fill yes)
		(layer "In13.Cu")
		(net "M_H_CPU1_SB_DQ<27>")
	)
	(gr_poly
		(pts
			(xy 141.314932 -288.868104) (xy 141.214856 -288.768028) (xy 141.11478 -288.868104) (xy 141.11478 -288.912554)
			(xy 141.314932 -288.912554)
		)
		(stroke
			(width 0)
			(type solid)
		)
		(fill yes)
		(layer "In13.Cu")
		(net "M_H_CPU1_SB_DQ<24>")
	)
	(gr_poly
		(pts
			(xy 141.314932 -288.464498) (xy 141.314932 -288.420048) (xy 141.11478 -288.420048) (xy 141.11478 -288.464498)
			(xy 141.214856 -288.564574)
		)
		(stroke
			(width 0)
			(type solid)
		)
		(fill yes)
		(layer "In13.Cu")
		(net "M_H_CPU1_SB_DQ<23>")
	)
	(gr_poly
		(pts
			(xy 141.314932 -287.248092) (xy 141.214856 -287.148016) (xy 141.11478 -287.248092) (xy 141.11478 -287.292542)
			(xy 141.314932 -287.292542)
		)
		(stroke
			(width 0)
			(type solid)
		)
		(fill yes)
		(layer "In13.Cu")
		(net "M_H_CPU1_SB_DQ<20>")
	)
	(gr_poly
		(pts
			(xy 141.314932 -286.844486) (xy 141.314932 -286.796734) (xy 141.11478 -286.796734) (xy 141.11478 -286.844486)
			(xy 141.214856 -286.944562)
		)
		(stroke
			(width 0)
			(type solid)
		)
		(fill yes)
		(layer "In13.Cu")
		(net "M_H_CPU1_SB_DQS_DP<7>")
	)
	(gr_poly
		(pts
			(xy 141.314932 -285.62808) (xy 141.214856 -285.528258) (xy 141.11478 -285.62808) (xy 141.11478 -285.675832)
			(xy 141.314932 -285.675832)
		)
		(stroke
			(width 0)
			(type solid)
		)
		(fill yes)
		(layer "In13.Cu")
		(net "M_H_CPU1_SB_DQS_DP<2>")
	)
	(gr_poly
		(pts
			(xy 141.314932 -285.224474) (xy 141.314932 -285.180024) (xy 141.11478 -285.180024) (xy 141.11478 -285.224474)
			(xy 141.214856 -285.32455)
		)
		(stroke
			(width 0)
			(type solid)
		)
		(fill yes)
		(layer "In13.Cu")
		(net "M_H_CPU1_SB_DQ<19>")
	)
	(gr_poly
		(pts
			(xy 141.314932 -284.008322) (xy 141.214856 -283.908246) (xy 141.11478 -284.008322) (xy 141.11478 -284.052772)
			(xy 141.314932 -284.052772)
		)
		(stroke
			(width 0)
			(type solid)
		)
		(fill yes)
		(layer "In13.Cu")
		(net "M_H_CPU1_SB_DQ<16>")
	)
	(gr_poly
		(pts
			(xy 141.314932 -283.604462) (xy 141.314932 -283.560012) (xy 141.11478 -283.560012) (xy 141.11478 -283.604462)
			(xy 141.214856 -283.704538)
		)
		(stroke
			(width 0)
			(type solid)
		)
		(fill yes)
		(layer "In13.Cu")
		(net "M_H_CPU1_SB_DQ<15>")
	)
	(gr_poly
		(pts
			(xy 141.314932 -282.38831) (xy 141.214856 -282.288234) (xy 141.11478 -282.38831) (xy 141.11478 -282.43276)
			(xy 141.314932 -282.43276)
		)
		(stroke
			(width 0)
			(type solid)
		)
		(fill yes)
		(layer "In13.Cu")
		(net "M_H_CPU1_SB_DQ<12>")
	)
	(gr_poly
		(pts
			(xy 141.314932 -281.984704) (xy 141.314932 -281.936952) (xy 141.11478 -281.936952) (xy 141.11478 -281.984704)
			(xy 141.214856 -282.084526)
		)
		(stroke
			(width 0)
			(type solid)
		)
		(fill yes)
		(layer "In13.Cu")
		(net "M_H_CPU1_SB_DQS_DP<6>")
	)
	(gr_poly
		(pts
			(xy 141.314932 -280.768044) (xy 141.214856 -280.668222) (xy 141.11478 -280.768044) (xy 141.11478 -280.815796)
			(xy 141.314932 -280.815796)
		)
		(stroke
			(width 0)
			(type solid)
		)
		(fill yes)
		(layer "In13.Cu")
		(net "M_H_CPU1_SB_DQS_DP<1>")
	)
	(gr_poly
		(pts
			(xy 141.314932 -280.364438) (xy 141.314932 -280.319988) (xy 141.11478 -280.319988) (xy 141.11478 -280.364438)
			(xy 141.214856 -280.464514)
		)
		(stroke
			(width 0)
			(type solid)
		)
		(fill yes)
		(layer "In13.Cu")
		(net "M_H_CPU1_SB_DQ<11>")
	)
	(gr_poly
		(pts
			(xy 141.314932 -279.148286) (xy 141.214856 -279.04821) (xy 141.11478 -279.148286) (xy 141.11478 -279.192736)
			(xy 141.314932 -279.192736)
		)
		(stroke
			(width 0)
			(type solid)
		)
		(fill yes)
		(layer "In13.Cu")
		(net "M_H_CPU1_SB_DQ<8>")
	)
	(gr_poly
		(pts
			(xy 141.314932 -278.744426) (xy 141.314932 -278.699976) (xy 141.11478 -278.699976) (xy 141.11478 -278.744426)
			(xy 141.214856 -278.844502)
		)
		(stroke
			(width 0)
			(type solid)
		)
		(fill yes)
		(layer "In13.Cu")
		(net "M_H_CPU1_SB_DQ<7>")
	)
	(gr_poly
		(pts
			(xy 141.314932 -277.528274) (xy 141.214856 -277.428198) (xy 141.11478 -277.528274) (xy 141.11478 -277.572724)
			(xy 141.314932 -277.572724)
		)
		(stroke
			(width 0)
			(type solid)
		)
		(fill yes)
		(layer "In13.Cu")
		(net "M_H_CPU1_SB_DQ<4>")
	)
	(gr_poly
		(pts
			(xy 141.314932 -277.124668) (xy 141.314932 -277.076916) (xy 141.11478 -277.076916) (xy 141.11478 -277.124668)
			(xy 141.214856 -277.22449)
		)
		(stroke
			(width 0)
			(type solid)
		)
		(fill yes)
		(layer "In13.Cu")
		(net "M_H_CPU1_SB_DQS_DP<5>")
	)
	(gr_poly
		(pts
			(xy 141.314932 -275.908008) (xy 141.214856 -275.808186) (xy 141.11478 -275.908008) (xy 141.11478 -275.95576)
			(xy 141.314932 -275.95576)
		)
		(stroke
			(width 0)
			(type solid)
		)
		(fill yes)
		(layer "In13.Cu")
		(net "M_H_CPU1_SB_DQS_DP<0>")
	)
	(gr_poly
		(pts
			(xy 141.314932 -275.504402) (xy 141.314932 -275.459952) (xy 141.11478 -275.459952) (xy 141.11478 -275.504402)
			(xy 141.214856 -275.604478)
		)
		(stroke
			(width 0)
			(type solid)
		)
		(fill yes)
		(layer "In13.Cu")
		(net "M_H_CPU1_SB_DQ<3>")
	)
	(gr_poly
		(pts
			(xy 141.314932 -274.28825) (xy 141.214856 -274.188174) (xy 141.11478 -274.28825) (xy 141.11478 -274.3327)
			(xy 141.314932 -274.3327)
		)
		(stroke
			(width 0)
			(type solid)
		)
		(fill yes)
		(layer "In13.Cu")
		(net "M_H_CPU1_SB_DQ<0>")
	)
	(gr_poly
		(pts
			(xy 141.314932 -273.88439) (xy 141.314932 -273.83994) (xy 141.11478 -273.83994) (xy 141.11478 -273.88439)
			(xy 141.214856 -273.984466)
		)
		(stroke
			(width 0)
			(type solid)
		)
		(fill yes)
		(layer "In13.Cu")
		(net "M_H_CPU1_SB_CB<3>")
	)
	(gr_poly
		(pts
			(xy 141.314932 -272.668238) (xy 141.214856 -272.568162) (xy 141.11478 -272.668238) (xy 141.11478 -272.712688)
			(xy 141.314932 -272.712688)
		)
		(stroke
			(width 0)
			(type solid)
		)
		(fill yes)
		(layer "In13.Cu")
		(net "M_H_CPU1_SB_CB<0>")
	)
	(gr_poly
		(pts
			(xy 141.314932 -272.264632) (xy 141.314932 -272.21688) (xy 141.11478 -272.21688) (xy 141.11478 -272.264632)
			(xy 141.214856 -272.364454)
		)
		(stroke
			(width 0)
			(type solid)
		)
		(fill yes)
		(layer "In13.Cu")
		(net "M_H_CPU1_SB_DQS_DP<4>")
	)
	(gr_poly
		(pts
			(xy 141.314932 -271.047972) (xy 141.214856 -270.94815) (xy 141.11478 -271.047972) (xy 141.11478 -271.095724)
			(xy 141.314932 -271.095724)
		)
		(stroke
			(width 0)
			(type solid)
		)
		(fill yes)
		(layer "In13.Cu")
		(net "M_H_CPU1_SB_DQS_DP<9>")
	)
	(gr_poly
		(pts
			(xy 141.314932 -270.644366) (xy 141.314932 -270.599916) (xy 141.11478 -270.599916) (xy 141.11478 -270.644366)
			(xy 141.214856 -270.744442)
		)
		(stroke
			(width 0)
			(type solid)
		)
		(fill yes)
		(layer "In13.Cu")
		(net "M_H_CPU1_SB_CB<7>")
	)
	(gr_poly
		(pts
			(xy 141.314932 -269.428214) (xy 141.214856 -269.328138) (xy 141.11478 -269.428214) (xy 141.11478 -269.472664)
			(xy 141.314932 -269.472664)
		)
		(stroke
			(width 0)
			(type solid)
		)
		(fill yes)
		(layer "In13.Cu")
		(net "M_H_CPU1_SB_CB<4>")
	)
	(gr_poly
		(pts
			(xy 141.314932 -267.808202) (xy 141.214856 -267.708126) (xy 141.11478 -267.808202) (xy 141.11478 -267.852652)
			(xy 141.314932 -267.852652)
		)
		(stroke
			(width 0)
			(type solid)
		)
		(fill yes)
		(layer "In13.Cu")
		(net "M_H_CPU1_SB_RSP<0>")
	)
	(gr_poly
		(pts
			(xy 141.314932 -265.78433) (xy 141.314932 -265.73988) (xy 141.11478 -265.73988) (xy 141.11478 -265.78433)
			(xy 141.214856 -265.884406)
		)
		(stroke
			(width 0)
			(type solid)
		)
		(fill yes)
		(layer "In13.Cu")
		(net "M_H_CPU1_SB_CS_N<0>")
	)
	(gr_poly
		(pts
			(xy 141.314932 -264.568178) (xy 141.214856 -264.468102) (xy 141.11478 -264.568178) (xy 141.11478 -264.612628)
			(xy 141.314932 -264.612628)
		)
		(stroke
			(width 0)
			(type solid)
		)
		(fill yes)
		(layer "In13.Cu")
		(net "M_H_CPU1_SB_CA<6>")
	)
	(gr_poly
		(pts
			(xy 141.314932 -264.164318) (xy 141.314932 -264.119868) (xy 141.11478 -264.119868) (xy 141.11478 -264.164318)
			(xy 141.214856 -264.264394)
		)
		(stroke
			(width 0)
			(type solid)
		)
		(fill yes)
		(layer "In13.Cu")
		(net "M_H_CPU1_SB_CA<5>")
	)
	(gr_poly
		(pts
			(xy 141.314932 -262.948166) (xy 141.214856 -262.84809) (xy 141.11478 -262.948166) (xy 141.11478 -262.992616)
			(xy 141.314932 -262.992616)
		)
		(stroke
			(width 0)
			(type solid)
		)
		(fill yes)
		(layer "In13.Cu")
		(net "M_H_CPU1_SB_CA<2>")
	)
	(gr_poly
		(pts
			(xy 141.314932 -262.544306) (xy 141.314932 -262.499856) (xy 141.11478 -262.499856) (xy 141.11478 -262.544306)
			(xy 141.214856 -262.644382)
		)
		(stroke
			(width 0)
			(type solid)
		)
		(fill yes)
		(layer "In13.Cu")
		(net "M_H_CPU1_SB_CA<1>")
	)
	(gr_poly
		(pts
			(xy 141.404594 -223.074992) (xy 141.36624 -223.05264) (xy 141.229588 -223.089216) (xy 141.266164 -223.225868)
			(xy 141.304518 -223.24822)
		)
		(stroke
			(width 0)
			(type solid)
		)
		(fill yes)
		(layer "In13.Cu")
		(net "M_H_CPU1_SA_DQ<0>")
	)
	(gr_poly
		(pts
			(xy 141.404848 -224.694242) (xy 141.36624 -224.672144) (xy 141.229588 -224.70872) (xy 141.266164 -224.845372)
			(xy 141.304772 -224.86747)
		)
		(stroke
			(width 0)
			(type solid)
		)
		(fill yes)
		(layer "In13.Cu")
		(net "M_H_CPU1_SA_DQ<1>")
	)
	(gr_poly
		(pts
			(xy 141.407896 -226.31527) (xy 141.366494 -226.291394) (xy 141.229842 -226.32797) (xy 141.266672 -226.464622)
			(xy 141.30782 -226.488498)
		)
		(stroke
			(width 0)
			(type solid)
		)
		(fill yes)
		(layer "In13.Cu")
		(net "M_H_CPU1_SA_DQS_DP<0>")
	)
	(gr_poly
		(pts
			(xy 141.484858 -256.026158) (xy 141.384782 -255.926336) (xy 141.284706 -256.026158) (xy 141.284706 -256.07391)
			(xy 141.484858 -256.07391)
		)
		(stroke
			(width 0)
			(type solid)
		)
		(fill yes)
		(layer "In13.Cu")
		(net "M_H_CPU1_CLK_DP<0>")
	)
	(gr_poly
		(pts
			(xy 141.484858 -255.622552) (xy 141.484858 -255.578102) (xy 141.284706 -255.578102) (xy 141.284706 -255.622552)
			(xy 141.384782 -255.722628)
		)
		(stroke
			(width 0)
			(type solid)
		)
		(fill yes)
		(layer "In13.Cu")
		(net "M_H_CPU1_SA_PAR")
	)
	(gr_poly
		(pts
			(xy 141.484858 -254.4064) (xy 141.384782 -254.306324) (xy 141.284706 -254.4064) (xy 141.284706 -254.45085)
			(xy 141.484858 -254.45085)
		)
		(stroke
			(width 0)
			(type solid)
		)
		(fill yes)
		(layer "In13.Cu")
		(net "M_H_CPU1_SA_CA<4>")
	)
	(gr_poly
		(pts
			(xy 141.484858 -254.00254) (xy 141.484858 -253.95809) (xy 141.284706 -253.95809) (xy 141.284706 -254.00254)
			(xy 141.384782 -254.102616)
		)
		(stroke
			(width 0)
			(type solid)
		)
		(fill yes)
		(layer "In13.Cu")
		(net "M_H_CPU1_SA_CA<3>")
	)
	(gr_poly
		(pts
			(xy 141.484858 -252.786388) (xy 141.384782 -252.686312) (xy 141.284706 -252.786388) (xy 141.284706 -252.830838)
			(xy 141.484858 -252.830838)
		)
		(stroke
			(width 0)
			(type solid)
		)
		(fill yes)
		(layer "In13.Cu")
		(net "M_H_CPU1_SA_CA<0>")
	)
	(gr_poly
		(pts
			(xy 141.484858 -251.166376) (xy 141.384782 -251.0663) (xy 141.284706 -251.166376) (xy 141.284706 -251.210826)
			(xy 141.484858 -251.210826)
		)
		(stroke
			(width 0)
			(type solid)
		)
		(fill yes)
		(layer "In13.Cu")
		(net "M_H_CPU1_SA_CS_N<0>")
	)
	(gr_poly
		(pts
			(xy 141.484858 -250.762516) (xy 141.484858 -250.718066) (xy 141.284706 -250.718066) (xy 141.284706 -250.762516)
			(xy 141.384782 -250.862592)
		)
		(stroke
			(width 0)
			(type solid)
		)
		(fill yes)
		(layer "In13.Cu")
		(net "M_H_CPU1_RESET_N")
	)
	(gr_poly
		(pts
			(xy 141.484858 -249.142504) (xy 141.484858 -249.098054) (xy 141.284706 -249.098054) (xy 141.284706 -249.142504)
			(xy 141.384782 -249.24258)
		)
		(stroke
			(width 0)
			(type solid)
		)
		(fill yes)
		(layer "In13.Cu")
		(net "M_H_CPU1_SA_CB<7>")
	)
	(gr_poly
		(pts
			(xy 141.484858 -247.926352) (xy 141.384782 -247.826276) (xy 141.284706 -247.926352) (xy 141.284706 -247.970802)
			(xy 141.484858 -247.970802)
		)
		(stroke
			(width 0)
			(type solid)
		)
		(fill yes)
		(layer "In13.Cu")
		(net "M_H_CPU1_SA_CB<4>")
	)
	(gr_poly
		(pts
			(xy 141.484858 -247.522746) (xy 141.484858 -247.474994) (xy 141.284706 -247.474994) (xy 141.284706 -247.522746)
			(xy 141.384782 -247.622568)
		)
		(stroke
			(width 0)
			(type solid)
		)
		(fill yes)
		(layer "In13.Cu")
		(net "M_H_CPU1_SA_DQS_DP<9>")
	)
	(gr_poly
		(pts
			(xy 141.484858 -246.306086) (xy 141.384782 -246.206264) (xy 141.284706 -246.306086) (xy 141.284706 -246.353838)
			(xy 141.484858 -246.353838)
		)
		(stroke
			(width 0)
			(type solid)
		)
		(fill yes)
		(layer "In13.Cu")
		(net "M_H_CPU1_SA_DQS_DP<4>")
	)
	(gr_poly
		(pts
			(xy 141.484858 -245.90248) (xy 141.484858 -245.85803) (xy 141.284706 -245.85803) (xy 141.284706 -245.90248)
			(xy 141.384782 -246.002556)
		)
		(stroke
			(width 0)
			(type solid)
		)
		(fill yes)
		(layer "In13.Cu")
		(net "M_H_CPU1_SA_CB<3>")
	)
	(gr_poly
		(pts
			(xy 141.484858 -244.686328) (xy 141.384782 -244.586252) (xy 141.284706 -244.686328) (xy 141.284706 -244.730778)
			(xy 141.484858 -244.730778)
		)
		(stroke
			(width 0)
			(type solid)
		)
		(fill yes)
		(layer "In13.Cu")
		(net "M_H_CPU1_SA_CB<0>")
	)
	(gr_poly
		(pts
			(xy 141.484858 -244.282468) (xy 141.484858 -244.238018) (xy 141.284706 -244.238018) (xy 141.284706 -244.282468)
			(xy 141.384782 -244.382544)
		)
		(stroke
			(width 0)
			(type solid)
		)
		(fill yes)
		(layer "In13.Cu")
		(net "M_H_CPU1_SA_DQ<31>")
	)
	(gr_poly
		(pts
			(xy 141.484858 -243.066316) (xy 141.384782 -242.96624) (xy 141.284706 -243.066316) (xy 141.284706 -243.110766)
			(xy 141.484858 -243.110766)
		)
		(stroke
			(width 0)
			(type solid)
		)
		(fill yes)
		(layer "In13.Cu")
		(net "M_H_CPU1_SA_DQ<28>")
	)
	(gr_poly
		(pts
			(xy 141.484858 -242.66271) (xy 141.484858 -242.614958) (xy 141.284706 -242.614958) (xy 141.284706 -242.66271)
			(xy 141.384782 -242.762532)
		)
		(stroke
			(width 0)
			(type solid)
		)
		(fill yes)
		(layer "In13.Cu")
		(net "M_H_CPU1_SA_DQS_DP<8>")
	)
	(gr_poly
		(pts
			(xy 141.484858 -241.44605) (xy 141.384782 -241.346228) (xy 141.284706 -241.44605) (xy 141.284706 -241.493802)
			(xy 141.484858 -241.493802)
		)
		(stroke
			(width 0)
			(type solid)
		)
		(fill yes)
		(layer "In13.Cu")
		(net "M_H_CPU1_SA_DQS_DP<3>")
	)
	(gr_poly
		(pts
			(xy 141.484858 -241.042444) (xy 141.484858 -240.997994) (xy 141.284706 -240.997994) (xy 141.284706 -241.042444)
			(xy 141.384782 -241.14252)
		)
		(stroke
			(width 0)
			(type solid)
		)
		(fill yes)
		(layer "In13.Cu")
		(net "M_H_CPU1_SA_DQ<27>")
	)
	(gr_poly
		(pts
			(xy 141.484858 -239.826292) (xy 141.384782 -239.726216) (xy 141.284706 -239.826292) (xy 141.284706 -239.870742)
			(xy 141.484858 -239.870742)
		)
		(stroke
			(width 0)
			(type solid)
		)
		(fill yes)
		(layer "In13.Cu")
		(net "M_H_CPU1_SA_DQ<24>")
	)
	(gr_poly
		(pts
			(xy 141.484858 -239.422432) (xy 141.484858 -239.377982) (xy 141.284706 -239.377982) (xy 141.284706 -239.422432)
			(xy 141.384782 -239.522508)
		)
		(stroke
			(width 0)
			(type solid)
		)
		(fill yes)
		(layer "In13.Cu")
		(net "M_H_CPU1_SA_DQ<23>")
	)
	(gr_poly
		(pts
			(xy 141.484858 -238.20628) (xy 141.384782 -238.106204) (xy 141.284706 -238.20628) (xy 141.284706 -238.25073)
			(xy 141.484858 -238.25073)
		)
		(stroke
			(width 0)
			(type solid)
		)
		(fill yes)
		(layer "In13.Cu")
		(net "M_H_CPU1_SA_DQ<20>")
	)
	(gr_poly
		(pts
			(xy 141.484858 -237.802674) (xy 141.484858 -237.754922) (xy 141.284706 -237.754922) (xy 141.284706 -237.802674)
			(xy 141.384782 -237.902496)
		)
		(stroke
			(width 0)
			(type solid)
		)
		(fill yes)
		(layer "In13.Cu")
		(net "M_H_CPU1_SA_DQS_DP<7>")
	)
	(gr_poly
		(pts
			(xy 141.484858 -236.586014) (xy 141.384782 -236.486192) (xy 141.284706 -236.586014) (xy 141.284706 -236.633766)
			(xy 141.484858 -236.633766)
		)
		(stroke
			(width 0)
			(type solid)
		)
		(fill yes)
		(layer "In13.Cu")
		(net "M_H_CPU1_SA_DQS_DP<2>")
	)
	(gr_poly
		(pts
			(xy 141.484858 -236.182408) (xy 141.484858 -236.137958) (xy 141.284706 -236.137958) (xy 141.284706 -236.182408)
			(xy 141.384782 -236.282484)
		)
		(stroke
			(width 0)
			(type solid)
		)
		(fill yes)
		(layer "In13.Cu")
		(net "M_H_CPU1_SA_DQ<19>")
	)
	(gr_poly
		(pts
			(xy 141.484858 -234.966256) (xy 141.384782 -234.86618) (xy 141.284706 -234.966256) (xy 141.284706 -235.010706)
			(xy 141.484858 -235.010706)
		)
		(stroke
			(width 0)
			(type solid)
		)
		(fill yes)
		(layer "In13.Cu")
		(net "M_H_CPU1_SA_DQ<16>")
	)
	(gr_poly
		(pts
			(xy 141.484858 -234.562396) (xy 141.484858 -234.517946) (xy 141.284706 -234.517946) (xy 141.284706 -234.562396)
			(xy 141.384782 -234.662472)
		)
		(stroke
			(width 0)
			(type solid)
		)
		(fill yes)
		(layer "In13.Cu")
		(net "M_H_CPU1_SA_DQ<15>")
	)
	(gr_poly
		(pts
			(xy 141.484858 -233.346244) (xy 141.384782 -233.246168) (xy 141.284706 -233.346244) (xy 141.284706 -233.390694)
			(xy 141.484858 -233.390694)
		)
		(stroke
			(width 0)
			(type solid)
		)
		(fill yes)
		(layer "In13.Cu")
		(net "M_H_CPU1_SA_DQ<12>")
	)
	(gr_poly
		(pts
			(xy 141.484858 -232.942638) (xy 141.484858 -232.894886) (xy 141.284706 -232.894886) (xy 141.284706 -232.942638)
			(xy 141.384782 -233.04246)
		)
		(stroke
			(width 0)
			(type solid)
		)
		(fill yes)
		(layer "In13.Cu")
		(net "M_H_CPU1_SA_DQS_DP<6>")
	)
	(gr_poly
		(pts
			(xy 141.484858 -231.725978) (xy 141.384782 -231.626156) (xy 141.284706 -231.725978) (xy 141.284706 -231.77373)
			(xy 141.484858 -231.77373)
		)
		(stroke
			(width 0)
			(type solid)
		)
		(fill yes)
		(layer "In13.Cu")
		(net "M_H_CPU1_SA_DQS_DP<1>")
	)
	(gr_poly
		(pts
			(xy 141.484858 -231.322626) (xy 141.484858 -231.278176) (xy 141.284706 -231.278176) (xy 141.284706 -231.322626)
			(xy 141.384782 -231.422702)
		)
		(stroke
			(width 0)
			(type solid)
		)
		(fill yes)
		(layer "In13.Cu")
		(net "M_H_CPU1_SA_DQ<11>")
	)
	(gr_poly
		(pts
			(xy 141.484858 -230.10622) (xy 141.384782 -230.006144) (xy 141.284706 -230.10622) (xy 141.284706 -230.15067)
			(xy 141.484858 -230.15067)
		)
		(stroke
			(width 0)
			(type solid)
		)
		(fill yes)
		(layer "In13.Cu")
		(net "M_H_CPU1_SA_DQ<8>")
	)
	(gr_poly
		(pts
			(xy 141.484858 -229.702614) (xy 141.484858 -229.658164) (xy 141.284706 -229.658164) (xy 141.284706 -229.702614)
			(xy 141.384782 -229.80269)
		)
		(stroke
			(width 0)
			(type solid)
		)
		(fill yes)
		(layer "In13.Cu")
		(net "M_H_CPU1_SA_DQ<7>")
	)
	(gr_poly
		(pts
			(xy 141.484858 -228.486462) (xy 141.384782 -228.386386) (xy 141.284706 -228.486462) (xy 141.284706 -228.530912)
			(xy 141.484858 -228.530912)
		)
		(stroke
			(width 0)
			(type solid)
		)
		(fill yes)
		(layer "In13.Cu")
		(net "M_H_CPU1_SA_DQ<4>")
	)
	(gr_poly
		(pts
			(xy 141.484858 -228.082856) (xy 141.484858 -228.035104) (xy 141.284706 -228.035104) (xy 141.284706 -228.082856)
			(xy 141.384782 -228.182678)
		)
		(stroke
			(width 0)
			(type solid)
		)
		(fill yes)
		(layer "In13.Cu")
		(net "M_H_CPU1_SA_DQS_DP<5>")
	)
	(gr_poly
		(pts
			(xy 141.539722 -227.00107) (xy 141.502892 -226.864418) (xy 141.461744 -226.840542) (xy 141.361668 -227.01377)
			(xy 141.40307 -227.037646)
		)
		(stroke
			(width 0)
			(type solid)
		)
		(fill yes)
		(layer "In13.Cu")
		(net "M_H_CPU1_SA_DQS_DN<0>")
	)
	(gr_poly
		(pts
			(xy 141.539976 -225.380296) (xy 141.5034 -225.243644) (xy 141.464792 -225.221546) (xy 141.364716 -225.394774)
			(xy 141.403324 -225.416872)
		)
		(stroke
			(width 0)
			(type solid)
		)
		(fill yes)
		(layer "In13.Cu")
		(net "M_H_CPU1_SA_DQ<3>")
	)
	(gr_poly
		(pts
			(xy 141.541246 -223.758252) (xy 141.50467 -223.6216) (xy 141.466316 -223.599502) (xy 141.36624 -223.77273)
			(xy 141.404848 -223.794828)
		)
		(stroke
			(width 0)
			(type solid)
		)
		(fill yes)
		(layer "In13.Cu")
		(net "M_H_CPU1_SA_DQ<2>")
	)
	(gr_poly
		(pts
			(xy 141.784832 -292.918134) (xy 141.684756 -292.818058) (xy 141.58468 -292.918134) (xy 141.58468 -292.962584)
			(xy 141.784832 -292.962584)
		)
		(stroke
			(width 0)
			(type solid)
		)
		(fill yes)
		(layer "In13.Cu")
		(net "M_H_CPU1_SB_DQ<29>")
	)
	(gr_poly
		(pts
			(xy 141.784832 -292.514274) (xy 141.784832 -292.469824) (xy 141.58468 -292.469824) (xy 141.58468 -292.514274)
			(xy 141.684756 -292.61435)
		)
		(stroke
			(width 0)
			(type solid)
		)
		(fill yes)
		(layer "In13.Cu")
		(net "M_H_CPU1_SB_DQ<30>")
	)
	(gr_poly
		(pts
			(xy 141.784832 -291.297868) (xy 141.684756 -291.198046) (xy 141.58468 -291.297868) (xy 141.58468 -291.34562)
			(xy 141.784832 -291.34562)
		)
		(stroke
			(width 0)
			(type solid)
		)
		(fill yes)
		(layer "In13.Cu")
		(net "M_H_CPU1_SB_DQS_DN<8>")
	)
	(gr_poly
		(pts
			(xy 141.784832 -290.894516) (xy 141.784832 -290.846764) (xy 141.58468 -290.846764) (xy 141.58468 -290.894516)
			(xy 141.684756 -290.994338)
		)
		(stroke
			(width 0)
			(type solid)
		)
		(fill yes)
		(layer "In13.Cu")
		(net "M_H_CPU1_SB_DQS_DN<3>")
	)
	(gr_poly
		(pts
			(xy 141.784832 -289.67811) (xy 141.684756 -289.578034) (xy 141.58468 -289.67811) (xy 141.58468 -289.72256)
			(xy 141.784832 -289.72256)
		)
		(stroke
			(width 0)
			(type solid)
		)
		(fill yes)
		(layer "In13.Cu")
		(net "M_H_CPU1_SB_DQ<25>")
	)
	(gr_poly
		(pts
			(xy 141.784832 -289.27425) (xy 141.784832 -289.2298) (xy 141.58468 -289.2298) (xy 141.58468 -289.27425)
			(xy 141.684756 -289.374326)
		)
		(stroke
			(width 0)
			(type solid)
		)
		(fill yes)
		(layer "In13.Cu")
		(net "M_H_CPU1_SB_DQ<26>")
	)
	(gr_poly
		(pts
			(xy 141.784832 -288.058098) (xy 141.684756 -287.958022) (xy 141.58468 -288.058098) (xy 141.58468 -288.102548)
			(xy 141.784832 -288.102548)
		)
		(stroke
			(width 0)
			(type solid)
		)
		(fill yes)
		(layer "In13.Cu")
		(net "M_H_CPU1_SB_DQ<21>")
	)
	(gr_poly
		(pts
			(xy 141.784832 -287.654492) (xy 141.784832 -287.610042) (xy 141.58468 -287.610042) (xy 141.58468 -287.654492)
			(xy 141.684756 -287.754568)
		)
		(stroke
			(width 0)
			(type solid)
		)
		(fill yes)
		(layer "In13.Cu")
		(net "M_H_CPU1_SB_DQ<22>")
	)
	(gr_poly
		(pts
			(xy 141.784832 -286.438086) (xy 141.684756 -286.33801) (xy 141.58468 -286.438086) (xy 141.58468 -286.485838)
			(xy 141.784832 -286.485838)
		)
		(stroke
			(width 0)
			(type solid)
		)
		(fill yes)
		(layer "In13.Cu")
		(net "M_H_CPU1_SB_DQS_DN<7>")
	)
	(gr_poly
		(pts
			(xy 141.784832 -286.034734) (xy 141.784832 -285.986982) (xy 141.58468 -285.986982) (xy 141.58468 -286.034734)
			(xy 141.684756 -286.134556)
		)
		(stroke
			(width 0)
			(type solid)
		)
		(fill yes)
		(layer "In13.Cu")
		(net "M_H_CPU1_SB_DQS_DN<2>")
	)
	(gr_poly
		(pts
			(xy 141.784832 -284.818328) (xy 141.684756 -284.718252) (xy 141.58468 -284.818328) (xy 141.58468 -284.862778)
			(xy 141.784832 -284.862778)
		)
		(stroke
			(width 0)
			(type solid)
		)
		(fill yes)
		(layer "In13.Cu")
		(net "M_H_CPU1_SB_DQ<17>")
	)
	(gr_poly
		(pts
			(xy 141.784832 -284.414468) (xy 141.784832 -284.370018) (xy 141.58468 -284.370018) (xy 141.58468 -284.414468)
			(xy 141.684756 -284.514544)
		)
		(stroke
			(width 0)
			(type solid)
		)
		(fill yes)
		(layer "In13.Cu")
		(net "M_H_CPU1_SB_DQ<18>")
	)
	(gr_poly
		(pts
			(xy 141.784832 -283.198316) (xy 141.684756 -283.09824) (xy 141.58468 -283.198316) (xy 141.58468 -283.242766)
			(xy 141.784832 -283.242766)
		)
		(stroke
			(width 0)
			(type solid)
		)
		(fill yes)
		(layer "In13.Cu")
		(net "M_H_CPU1_SB_DQ<13>")
	)
	(gr_poly
		(pts
			(xy 141.784832 -282.794456) (xy 141.784832 -282.750006) (xy 141.58468 -282.750006) (xy 141.58468 -282.794456)
			(xy 141.684756 -282.894532)
		)
		(stroke
			(width 0)
			(type solid)
		)
		(fill yes)
		(layer "In13.Cu")
		(net "M_H_CPU1_SB_DQ<14>")
	)
	(gr_poly
		(pts
			(xy 141.784832 -281.57805) (xy 141.684756 -281.478228) (xy 141.58468 -281.57805) (xy 141.58468 -281.625802)
			(xy 141.784832 -281.625802)
		)
		(stroke
			(width 0)
			(type solid)
		)
		(fill yes)
		(layer "In13.Cu")
		(net "M_H_CPU1_SB_DQS_DN<6>")
	)
	(gr_poly
		(pts
			(xy 141.784832 -281.174698) (xy 141.784832 -281.126946) (xy 141.58468 -281.126946) (xy 141.58468 -281.174698)
			(xy 141.684756 -281.27452)
		)
		(stroke
			(width 0)
			(type solid)
		)
		(fill yes)
		(layer "In13.Cu")
		(net "M_H_CPU1_SB_DQS_DN<1>")
	)
	(gr_poly
		(pts
			(xy 141.784832 -279.958292) (xy 141.684756 -279.858216) (xy 141.58468 -279.958292) (xy 141.58468 -280.002742)
			(xy 141.784832 -280.002742)
		)
		(stroke
			(width 0)
			(type solid)
		)
		(fill yes)
		(layer "In13.Cu")
		(net "M_H_CPU1_SB_DQ<9>")
	)
	(gr_poly
		(pts
			(xy 141.784832 -279.554432) (xy 141.784832 -279.509982) (xy 141.58468 -279.509982) (xy 141.58468 -279.554432)
			(xy 141.684756 -279.654508)
		)
		(stroke
			(width 0)
			(type solid)
		)
		(fill yes)
		(layer "In13.Cu")
		(net "M_H_CPU1_SB_DQ<10>")
	)
	(gr_poly
		(pts
			(xy 141.784832 -278.33828) (xy 141.684756 -278.238204) (xy 141.58468 -278.33828) (xy 141.58468 -278.38273)
			(xy 141.784832 -278.38273)
		)
		(stroke
			(width 0)
			(type solid)
		)
		(fill yes)
		(layer "In13.Cu")
		(net "M_H_CPU1_SB_DQ<5>")
	)
	(gr_poly
		(pts
			(xy 141.784832 -277.93442) (xy 141.784832 -277.88997) (xy 141.58468 -277.88997) (xy 141.58468 -277.93442)
			(xy 141.684756 -278.034496)
		)
		(stroke
			(width 0)
			(type solid)
		)
		(fill yes)
		(layer "In13.Cu")
		(net "M_H_CPU1_SB_DQ<6>")
	)
	(gr_poly
		(pts
			(xy 141.784832 -276.718014) (xy 141.684756 -276.618192) (xy 141.58468 -276.718014) (xy 141.58468 -276.765766)
			(xy 141.784832 -276.765766)
		)
		(stroke
			(width 0)
			(type solid)
		)
		(fill yes)
		(layer "In13.Cu")
		(net "M_H_CPU1_SB_DQS_DN<5>")
	)
	(gr_poly
		(pts
			(xy 141.784832 -276.314662) (xy 141.784832 -276.26691) (xy 141.58468 -276.26691) (xy 141.58468 -276.314662)
			(xy 141.684756 -276.414484)
		)
		(stroke
			(width 0)
			(type solid)
		)
		(fill yes)
		(layer "In13.Cu")
		(net "M_H_CPU1_SB_DQS_DN<0>")
	)
	(gr_poly
		(pts
			(xy 141.784832 -275.098256) (xy 141.684756 -274.99818) (xy 141.58468 -275.098256) (xy 141.58468 -275.142706)
			(xy 141.784832 -275.142706)
		)
		(stroke
			(width 0)
			(type solid)
		)
		(fill yes)
		(layer "In13.Cu")
		(net "M_H_CPU1_SB_DQ<1>")
	)
	(gr_poly
		(pts
			(xy 141.784832 -274.694396) (xy 141.784832 -274.649946) (xy 141.58468 -274.649946) (xy 141.58468 -274.694396)
			(xy 141.684756 -274.794472)
		)
		(stroke
			(width 0)
			(type solid)
		)
		(fill yes)
		(layer "In13.Cu")
		(net "M_H_CPU1_SB_DQ<2>")
	)
	(gr_poly
		(pts
			(xy 141.784832 -273.478244) (xy 141.684756 -273.378168) (xy 141.58468 -273.478244) (xy 141.58468 -273.522694)
			(xy 141.784832 -273.522694)
		)
		(stroke
			(width 0)
			(type solid)
		)
		(fill yes)
		(layer "In13.Cu")
		(net "M_H_CPU1_SB_CB<1>")
	)
	(gr_poly
		(pts
			(xy 141.784832 -273.074384) (xy 141.784832 -273.029934) (xy 141.58468 -273.029934) (xy 141.58468 -273.074384)
			(xy 141.684756 -273.17446)
		)
		(stroke
			(width 0)
			(type solid)
		)
		(fill yes)
		(layer "In13.Cu")
		(net "M_H_CPU1_SB_CB<2>")
	)
	(gr_poly
		(pts
			(xy 141.784832 -271.857978) (xy 141.684756 -271.758156) (xy 141.58468 -271.857978) (xy 141.58468 -271.90573)
			(xy 141.784832 -271.90573)
		)
		(stroke
			(width 0)
			(type solid)
		)
		(fill yes)
		(layer "In13.Cu")
		(net "M_H_CPU1_SB_DQS_DN<4>")
	)
	(gr_poly
		(pts
			(xy 141.784832 -271.454626) (xy 141.784832 -271.406874) (xy 141.58468 -271.406874) (xy 141.58468 -271.454626)
			(xy 141.684756 -271.554448)
		)
		(stroke
			(width 0)
			(type solid)
		)
		(fill yes)
		(layer "In13.Cu")
		(net "M_H_CPU1_SB_DQS_DN<9>")
	)
	(gr_poly
		(pts
			(xy 141.784832 -270.23822) (xy 141.684756 -270.138144) (xy 141.58468 -270.23822) (xy 141.58468 -270.28267)
			(xy 141.784832 -270.28267)
		)
		(stroke
			(width 0)
			(type solid)
		)
		(fill yes)
		(layer "In13.Cu")
		(net "M_H_CPU1_SB_CB<5>")
	)
	(gr_poly
		(pts
			(xy 141.784832 -269.83436) (xy 141.784832 -269.78991) (xy 141.58468 -269.78991) (xy 141.58468 -269.83436)
			(xy 141.684756 -269.934436)
		)
		(stroke
			(width 0)
			(type solid)
		)
		(fill yes)
		(layer "In13.Cu")
		(net "M_H_CPU1_SB_CB<6>")
	)
	(gr_poly
		(pts
			(xy 141.784832 -266.998196) (xy 141.684756 -266.89812) (xy 141.58468 -266.998196) (xy 141.58468 -267.042646)
			(xy 141.784832 -267.042646)
		)
		(stroke
			(width 0)
			(type solid)
		)
		(fill yes)
		(layer "In13.Cu")
		(net "M_H_CPU1_SA_RSP<0>")
	)
	(gr_poly
		(pts
			(xy 141.784832 -266.594336) (xy 141.784832 -266.549886) (xy 141.58468 -266.549886) (xy 141.58468 -266.594336)
			(xy 141.684756 -266.694412)
		)
		(stroke
			(width 0)
			(type solid)
		)
		(fill yes)
		(layer "In13.Cu")
		(net "M_H_CPU1_SB_CS_N<1>")
	)
	(gr_poly
		(pts
			(xy 141.784832 -265.378184) (xy 141.684756 -265.278108) (xy 141.58468 -265.378184) (xy 141.58468 -265.422634)
			(xy 141.784832 -265.422634)
		)
		(stroke
			(width 0)
			(type solid)
		)
		(fill yes)
		(layer "In13.Cu")
		(net "M_H_CPU1_SB_PAR")
	)
	(gr_poly
		(pts
			(xy 141.784832 -263.758172) (xy 141.684756 -263.658096) (xy 141.58468 -263.758172) (xy 141.58468 -263.802622)
			(xy 141.784832 -263.802622)
		)
		(stroke
			(width 0)
			(type solid)
		)
		(fill yes)
		(layer "In13.Cu")
		(net "M_H_CPU1_SB_CA<4>")
	)
	(gr_poly
		(pts
			(xy 141.784832 -263.354312) (xy 141.784832 -263.309862) (xy 141.58468 -263.309862) (xy 141.58468 -263.354312)
			(xy 141.684756 -263.454388)
		)
		(stroke
			(width 0)
			(type solid)
		)
		(fill yes)
		(layer "In13.Cu")
		(net "M_H_CPU1_SB_CA<3>")
	)
	(gr_poly
		(pts
			(xy 141.784832 -262.13816) (xy 141.684756 -262.038084) (xy 141.58468 -262.13816) (xy 141.58468 -262.18261)
			(xy 141.784832 -262.18261)
		)
		(stroke
			(width 0)
			(type solid)
		)
		(fill yes)
		(layer "In13.Cu")
		(net "M_H_CPU1_SB_CA<0>")
	)
	(gr_poly
		(pts
			(xy 141.873732 -223.886268) (xy 141.835124 -223.86417) (xy 141.698726 -223.900746) (xy 141.735302 -224.037144)
			(xy 141.773656 -224.059496)
		)
		(stroke
			(width 0)
			(type solid)
		)
		(fill yes)
		(layer "In13.Cu")
		(net "M_H_CPU1_SA_DQ<1>")
	)
	(gr_poly
		(pts
			(xy 141.87678 -227.126546) (xy 141.835632 -227.10267) (xy 141.69898 -227.1395) (xy 141.735556 -227.275898)
			(xy 141.776958 -227.299774)
		)
		(stroke
			(width 0)
			(type solid)
		)
		(fill yes)
		(layer "In13.Cu")
		(net "M_H_CPU1_SA_DQS_DN<5>")
	)
	(gr_poly
		(pts
			(xy 141.87678 -225.506534) (xy 141.835632 -225.482912) (xy 141.69898 -225.519488) (xy 141.735556 -225.655886)
			(xy 141.776958 -225.679762)
		)
		(stroke
			(width 0)
			(type solid)
		)
		(fill yes)
		(layer "In13.Cu")
		(net "M_H_CPU1_SA_DQS_DP<0>")
	)
	(gr_poly
		(pts
			(xy 141.954758 -256.432812) (xy 141.954758 -256.38506) (xy 141.754606 -256.38506) (xy 141.754606 -256.432812)
			(xy 141.854682 -256.532634)
		)
		(stroke
			(width 0)
			(type solid)
		)
		(fill yes)
		(layer "In13.Cu")
		(net "M_H_CPU1_CLK_DN<0>")
	)
	(gr_poly
		(pts
			(xy 141.954758 -255.216406) (xy 141.854682 -255.11633) (xy 141.754606 -255.216406) (xy 141.754606 -255.260856)
			(xy 141.954758 -255.260856)
		)
		(stroke
			(width 0)
			(type solid)
		)
		(fill yes)
		(layer "In13.Cu")
		(net "M_H_CPU1_SA_CA<6>")
	)
	(gr_poly
		(pts
			(xy 141.954758 -254.812546) (xy 141.954758 -254.768096) (xy 141.754606 -254.768096) (xy 141.754606 -254.812546)
			(xy 141.854682 -254.912622)
		)
		(stroke
			(width 0)
			(type solid)
		)
		(fill yes)
		(layer "In13.Cu")
		(net "M_H_CPU1_SA_CA<5>")
	)
	(gr_poly
		(pts
			(xy 141.954758 -253.596394) (xy 141.854682 -253.496318) (xy 141.754606 -253.596394) (xy 141.754606 -253.640844)
			(xy 141.954758 -253.640844)
		)
		(stroke
			(width 0)
			(type solid)
		)
		(fill yes)
		(layer "In13.Cu")
		(net "M_H_CPU1_SA_CA<2>")
	)
	(gr_poly
		(pts
			(xy 141.954758 -253.192534) (xy 141.954758 -253.148084) (xy 141.754606 -253.148084) (xy 141.754606 -253.192534)
			(xy 141.854682 -253.29261)
		)
		(stroke
			(width 0)
			(type solid)
		)
		(fill yes)
		(layer "In13.Cu")
		(net "M_H_CPU1_SA_CA<1>")
	)
	(gr_poly
		(pts
			(xy 141.954758 -251.976382) (xy 141.854682 -251.876306) (xy 141.754606 -251.976382) (xy 141.754606 -252.020832)
			(xy 141.954758 -252.020832)
		)
		(stroke
			(width 0)
			(type solid)
		)
		(fill yes)
		(layer "In13.Cu")
		(net "M_H_CPU1_SA_CS_N<1>")
	)
	(gr_poly
		(pts
			(xy 141.954758 -250.35637) (xy 141.854682 -250.256294) (xy 141.754606 -250.35637) (xy 141.754606 -250.40082)
			(xy 141.954758 -250.40082)
		)
		(stroke
			(width 0)
			(type solid)
		)
		(fill yes)
		(layer "In13.Cu")
		(net "M_H_CPU1_ALERT_R_N")
	)
	(gr_poly
		(pts
			(xy 141.954758 -248.736358) (xy 141.854682 -248.636282) (xy 141.754606 -248.736358) (xy 141.754606 -248.780808)
			(xy 141.954758 -248.780808)
		)
		(stroke
			(width 0)
			(type solid)
		)
		(fill yes)
		(layer "In13.Cu")
		(net "M_H_CPU1_SA_CB<5>")
	)
	(gr_poly
		(pts
			(xy 141.954758 -248.332498) (xy 141.954758 -248.288048) (xy 141.754606 -248.288048) (xy 141.754606 -248.332498)
			(xy 141.854682 -248.432574)
		)
		(stroke
			(width 0)
			(type solid)
		)
		(fill yes)
		(layer "In13.Cu")
		(net "M_H_CPU1_SA_CB<6>")
	)
	(gr_poly
		(pts
			(xy 141.954758 -247.116092) (xy 141.854682 -247.01627) (xy 141.754606 -247.116092) (xy 141.754606 -247.163844)
			(xy 141.954758 -247.163844)
		)
		(stroke
			(width 0)
			(type solid)
		)
		(fill yes)
		(layer "In13.Cu")
		(net "M_H_CPU1_SA_DQS_DN<9>")
	)
	(gr_poly
		(pts
			(xy 141.954758 -246.71274) (xy 141.954758 -246.664988) (xy 141.754606 -246.664988) (xy 141.754606 -246.71274)
			(xy 141.854682 -246.812562)
		)
		(stroke
			(width 0)
			(type solid)
		)
		(fill yes)
		(layer "In13.Cu")
		(net "M_H_CPU1_SA_DQS_DN<4>")
	)
	(gr_poly
		(pts
			(xy 141.954758 -245.496334) (xy 141.854682 -245.396258) (xy 141.754606 -245.496334) (xy 141.754606 -245.540784)
			(xy 141.954758 -245.540784)
		)
		(stroke
			(width 0)
			(type solid)
		)
		(fill yes)
		(layer "In13.Cu")
		(net "M_H_CPU1_SA_CB<1>")
	)
	(gr_poly
		(pts
			(xy 141.954758 -245.092474) (xy 141.954758 -245.048024) (xy 141.754606 -245.048024) (xy 141.754606 -245.092474)
			(xy 141.854682 -245.19255)
		)
		(stroke
			(width 0)
			(type solid)
		)
		(fill yes)
		(layer "In13.Cu")
		(net "M_H_CPU1_SA_CB<2>")
	)
	(gr_poly
		(pts
			(xy 141.954758 -243.876322) (xy 141.854682 -243.776246) (xy 141.754606 -243.876322) (xy 141.754606 -243.920772)
			(xy 141.954758 -243.920772)
		)
		(stroke
			(width 0)
			(type solid)
		)
		(fill yes)
		(layer "In13.Cu")
		(net "M_H_CPU1_SA_DQ<29>")
	)
	(gr_poly
		(pts
			(xy 141.954758 -243.472462) (xy 141.954758 -243.428012) (xy 141.754606 -243.428012) (xy 141.754606 -243.472462)
			(xy 141.854682 -243.572538)
		)
		(stroke
			(width 0)
			(type solid)
		)
		(fill yes)
		(layer "In13.Cu")
		(net "M_H_CPU1_SA_DQ<30>")
	)
	(gr_poly
		(pts
			(xy 141.954758 -242.256056) (xy 141.854682 -242.156234) (xy 141.754606 -242.256056) (xy 141.754606 -242.303808)
			(xy 141.954758 -242.303808)
		)
		(stroke
			(width 0)
			(type solid)
		)
		(fill yes)
		(layer "In13.Cu")
		(net "M_H_CPU1_SA_DQS_DN<8>")
	)
	(gr_poly
		(pts
			(xy 141.954758 -241.852704) (xy 141.954758 -241.804952) (xy 141.754606 -241.804952) (xy 141.754606 -241.852704)
			(xy 141.854682 -241.952526)
		)
		(stroke
			(width 0)
			(type solid)
		)
		(fill yes)
		(layer "In13.Cu")
		(net "M_H_CPU1_SA_DQS_DN<3>")
	)
	(gr_poly
		(pts
			(xy 141.954758 -240.636298) (xy 141.854682 -240.536222) (xy 141.754606 -240.636298) (xy 141.754606 -240.680748)
			(xy 141.954758 -240.680748)
		)
		(stroke
			(width 0)
			(type solid)
		)
		(fill yes)
		(layer "In13.Cu")
		(net "M_H_CPU1_SA_DQ<25>")
	)
	(gr_poly
		(pts
			(xy 141.954758 -240.232438) (xy 141.954758 -240.187988) (xy 141.754606 -240.187988) (xy 141.754606 -240.232438)
			(xy 141.854682 -240.332514)
		)
		(stroke
			(width 0)
			(type solid)
		)
		(fill yes)
		(layer "In13.Cu")
		(net "M_H_CPU1_SA_DQ<26>")
	)
	(gr_poly
		(pts
			(xy 141.954758 -239.016286) (xy 141.854682 -238.91621) (xy 141.754606 -239.016286) (xy 141.754606 -239.060736)
			(xy 141.954758 -239.060736)
		)
		(stroke
			(width 0)
			(type solid)
		)
		(fill yes)
		(layer "In13.Cu")
		(net "M_H_CPU1_SA_DQ<21>")
	)
	(gr_poly
		(pts
			(xy 141.954758 -238.612426) (xy 141.954758 -238.567976) (xy 141.754606 -238.567976) (xy 141.754606 -238.612426)
			(xy 141.854682 -238.712502)
		)
		(stroke
			(width 0)
			(type solid)
		)
		(fill yes)
		(layer "In13.Cu")
		(net "M_H_CPU1_SA_DQ<22>")
	)
	(gr_poly
		(pts
			(xy 141.954758 -237.39602) (xy 141.854682 -237.296198) (xy 141.754606 -237.39602) (xy 141.754606 -237.443772)
			(xy 141.954758 -237.443772)
		)
		(stroke
			(width 0)
			(type solid)
		)
		(fill yes)
		(layer "In13.Cu")
		(net "M_H_CPU1_SA_DQS_DN<7>")
	)
	(gr_poly
		(pts
			(xy 141.954758 -236.992668) (xy 141.954758 -236.944916) (xy 141.754606 -236.944916) (xy 141.754606 -236.992668)
			(xy 141.854682 -237.09249)
		)
		(stroke
			(width 0)
			(type solid)
		)
		(fill yes)
		(layer "In13.Cu")
		(net "M_H_CPU1_SA_DQS_DN<2>")
	)
	(gr_poly
		(pts
			(xy 141.954758 -235.776262) (xy 141.854682 -235.676186) (xy 141.754606 -235.776262) (xy 141.754606 -235.820712)
			(xy 141.954758 -235.820712)
		)
		(stroke
			(width 0)
			(type solid)
		)
		(fill yes)
		(layer "In13.Cu")
		(net "M_H_CPU1_SA_DQ<17>")
	)
	(gr_poly
		(pts
			(xy 141.954758 -235.372402) (xy 141.954758 -235.327952) (xy 141.754606 -235.327952) (xy 141.754606 -235.372402)
			(xy 141.854682 -235.472478)
		)
		(stroke
			(width 0)
			(type solid)
		)
		(fill yes)
		(layer "In13.Cu")
		(net "M_H_CPU1_SA_DQ<18>")
	)
	(gr_poly
		(pts
			(xy 141.954758 -234.15625) (xy 141.854682 -234.056174) (xy 141.754606 -234.15625) (xy 141.754606 -234.2007)
			(xy 141.954758 -234.2007)
		)
		(stroke
			(width 0)
			(type solid)
		)
		(fill yes)
		(layer "In13.Cu")
		(net "M_H_CPU1_SA_DQ<13>")
	)
	(gr_poly
		(pts
			(xy 141.954758 -233.75239) (xy 141.954758 -233.70794) (xy 141.754606 -233.70794) (xy 141.754606 -233.75239)
			(xy 141.854682 -233.852466)
		)
		(stroke
			(width 0)
			(type solid)
		)
		(fill yes)
		(layer "In13.Cu")
		(net "M_H_CPU1_SA_DQ<14>")
	)
	(gr_poly
		(pts
			(xy 141.954758 -232.535984) (xy 141.854682 -232.436162) (xy 141.754606 -232.535984) (xy 141.754606 -232.583736)
			(xy 141.954758 -232.583736)
		)
		(stroke
			(width 0)
			(type solid)
		)
		(fill yes)
		(layer "In13.Cu")
		(net "M_H_CPU1_SA_DQS_DN<6>")
	)
	(gr_poly
		(pts
			(xy 141.954758 -232.132632) (xy 141.954758 -232.08488) (xy 141.754606 -232.08488) (xy 141.754606 -232.132632)
			(xy 141.854682 -232.232454)
		)
		(stroke
			(width 0)
			(type solid)
		)
		(fill yes)
		(layer "In13.Cu")
		(net "M_H_CPU1_SA_DQS_DN<1>")
	)
	(gr_poly
		(pts
			(xy 141.954758 -230.916226) (xy 141.854682 -230.81615) (xy 141.754606 -230.916226) (xy 141.754606 -230.960676)
			(xy 141.954758 -230.960676)
		)
		(stroke
			(width 0)
			(type solid)
		)
		(fill yes)
		(layer "In13.Cu")
		(net "M_H_CPU1_SA_DQ<9>")
	)
	(gr_poly
		(pts
			(xy 141.954758 -230.51262) (xy 141.954758 -230.46817) (xy 141.754606 -230.46817) (xy 141.754606 -230.51262)
			(xy 141.854682 -230.612696)
		)
		(stroke
			(width 0)
			(type solid)
		)
		(fill yes)
		(layer "In13.Cu")
		(net "M_H_CPU1_SA_DQ<10>")
	)
	(gr_poly
		(pts
			(xy 141.954758 -229.296214) (xy 141.854682 -229.196138) (xy 141.754606 -229.296214) (xy 141.754606 -229.340664)
			(xy 141.954758 -229.340664)
		)
		(stroke
			(width 0)
			(type solid)
		)
		(fill yes)
		(layer "In13.Cu")
		(net "M_H_CPU1_SA_DQ<5>")
	)
	(gr_poly
		(pts
			(xy 141.954758 -228.892608) (xy 141.954758 -228.848158) (xy 141.754606 -228.848158) (xy 141.754606 -228.892608)
			(xy 141.854682 -228.992684)
		)
		(stroke
			(width 0)
			(type solid)
		)
		(fill yes)
		(layer "In13.Cu")
		(net "M_H_CPU1_SA_DQ<6>")
	)
	(gr_poly
		(pts
			(xy 142.010638 -227.809552) (xy 141.974062 -227.673154) (xy 141.93266 -227.649278) (xy 141.832838 -227.822506)
			(xy 141.873986 -227.846128)
		)
		(stroke
			(width 0)
			(type solid)
		)
		(fill yes)
		(layer "In13.Cu")
		(net "M_H_CPU1_SA_DQS_DP<5>")
	)
	(gr_poly
		(pts
			(xy 142.010638 -226.18954) (xy 141.974062 -226.053142) (xy 141.93266 -226.029266) (xy 141.832838 -226.202494)
			(xy 141.873986 -226.22637)
		)
		(stroke
			(width 0)
			(type solid)
		)
		(fill yes)
		(layer "In13.Cu")
		(net "M_H_CPU1_SA_DQS_DN<0>")
	)
	(gr_poly
		(pts
			(xy 142.010638 -224.56902) (xy 141.974062 -224.432368) (xy 141.935708 -224.410016) (xy 141.835632 -224.583244)
			(xy 141.87424 -224.605596)
		)
		(stroke
			(width 0)
			(type solid)
		)
		(fill yes)
		(layer "In13.Cu")
		(net "M_H_CPU1_SA_DQ<3>")
	)
	(gr_poly
		(pts
			(xy 142.0114 -222.948246) (xy 141.974824 -222.811594) (xy 141.936216 -222.789496) (xy 141.836394 -222.962724)
			(xy 141.874748 -222.984822)
		)
		(stroke
			(width 0)
			(type solid)
		)
		(fill yes)
		(layer "In13.Cu")
		(net "M_H_CPU1_SA_DQ<2>")
	)
	(gr_poly
		(pts
			(xy 142.254732 -293.32428) (xy 142.254732 -293.27983) (xy 142.05458 -293.27983) (xy 142.05458 -293.32428)
			(xy 142.154656 -293.424356)
		)
		(stroke
			(width 0)
			(type solid)
		)
		(fill yes)
		(layer "In13.Cu")
		(net "M_H_CPU1_SB_DQ<31>")
	)
	(gr_poly
		(pts
			(xy 142.254732 -292.108128) (xy 142.154656 -292.008052) (xy 142.05458 -292.108128) (xy 142.05458 -292.152578)
			(xy 142.254732 -292.152578)
		)
		(stroke
			(width 0)
			(type solid)
		)
		(fill yes)
		(layer "In13.Cu")
		(net "M_H_CPU1_SB_DQ<28>")
	)
	(gr_poly
		(pts
			(xy 142.254732 -291.704522) (xy 142.254732 -291.65677) (xy 142.05458 -291.65677) (xy 142.05458 -291.704522)
			(xy 142.154656 -291.804344)
		)
		(stroke
			(width 0)
			(type solid)
		)
		(fill yes)
		(layer "In13.Cu")
		(net "M_H_CPU1_SB_DQS_DP<8>")
	)
	(gr_poly
		(pts
			(xy 142.254732 -290.487862) (xy 142.154656 -290.38804) (xy 142.05458 -290.487862) (xy 142.05458 -290.535614)
			(xy 142.254732 -290.535614)
		)
		(stroke
			(width 0)
			(type solid)
		)
		(fill yes)
		(layer "In13.Cu")
		(net "M_H_CPU1_SB_DQS_DP<3>")
	)
	(gr_poly
		(pts
			(xy 142.254732 -290.084256) (xy 142.254732 -290.039806) (xy 142.05458 -290.039806) (xy 142.05458 -290.084256)
			(xy 142.154656 -290.184332)
		)
		(stroke
			(width 0)
			(type solid)
		)
		(fill yes)
		(layer "In13.Cu")
		(net "M_H_CPU1_SB_DQ<27>")
	)
	(gr_poly
		(pts
			(xy 142.254732 -288.868104) (xy 142.154656 -288.768028) (xy 142.05458 -288.868104) (xy 142.05458 -288.912554)
			(xy 142.254732 -288.912554)
		)
		(stroke
			(width 0)
			(type solid)
		)
		(fill yes)
		(layer "In13.Cu")
		(net "M_H_CPU1_SB_DQ<24>")
	)
	(gr_poly
		(pts
			(xy 142.254732 -288.464498) (xy 142.254732 -288.420048) (xy 142.05458 -288.420048) (xy 142.05458 -288.464498)
			(xy 142.154656 -288.564574)
		)
		(stroke
			(width 0)
			(type solid)
		)
		(fill yes)
		(layer "In13.Cu")
		(net "M_H_CPU1_SB_DQ<23>")
	)
	(gr_poly
		(pts
			(xy 142.254732 -287.248092) (xy 142.154656 -287.148016) (xy 142.05458 -287.248092) (xy 142.05458 -287.292542)
			(xy 142.254732 -287.292542)
		)
		(stroke
			(width 0)
			(type solid)
		)
		(fill yes)
		(layer "In13.Cu")
		(net "M_H_CPU1_SB_DQ<20>")
	)
	(gr_poly
		(pts
			(xy 142.254732 -286.844486) (xy 142.254732 -286.796734) (xy 142.05458 -286.796734) (xy 142.05458 -286.844486)
			(xy 142.154656 -286.944562)
		)
		(stroke
			(width 0)
			(type solid)
		)
		(fill yes)
		(layer "In13.Cu")
		(net "M_H_CPU1_SB_DQS_DP<7>")
	)
	(gr_poly
		(pts
			(xy 142.254732 -285.62808) (xy 142.154656 -285.528258) (xy 142.05458 -285.62808) (xy 142.05458 -285.675832)
			(xy 142.254732 -285.675832)
		)
		(stroke
			(width 0)
			(type solid)
		)
		(fill yes)
		(layer "In13.Cu")
		(net "M_H_CPU1_SB_DQS_DP<2>")
	)
	(gr_poly
		(pts
			(xy 142.254732 -285.224474) (xy 142.254732 -285.180024) (xy 142.05458 -285.180024) (xy 142.05458 -285.224474)
			(xy 142.154656 -285.32455)
		)
		(stroke
			(width 0)
			(type solid)
		)
		(fill yes)
		(layer "In13.Cu")
		(net "M_H_CPU1_SB_DQ<19>")
	)
	(gr_poly
		(pts
			(xy 142.254732 -284.008322) (xy 142.154656 -283.908246) (xy 142.05458 -284.008322) (xy 142.05458 -284.052772)
			(xy 142.254732 -284.052772)
		)
		(stroke
			(width 0)
			(type solid)
		)
		(fill yes)
		(layer "In13.Cu")
		(net "M_H_CPU1_SB_DQ<16>")
	)
	(gr_poly
		(pts
			(xy 142.254732 -283.604462) (xy 142.254732 -283.560012) (xy 142.05458 -283.560012) (xy 142.05458 -283.604462)
			(xy 142.154656 -283.704538)
		)
		(stroke
			(width 0)
			(type solid)
		)
		(fill yes)
		(layer "In13.Cu")
		(net "M_H_CPU1_SB_DQ<15>")
	)
	(gr_poly
		(pts
			(xy 142.254732 -282.38831) (xy 142.154656 -282.288234) (xy 142.05458 -282.38831) (xy 142.05458 -282.43276)
			(xy 142.254732 -282.43276)
		)
		(stroke
			(width 0)
			(type solid)
		)
		(fill yes)
		(layer "In13.Cu")
		(net "M_H_CPU1_SB_DQ<12>")
	)
	(gr_poly
		(pts
			(xy 142.254732 -281.984704) (xy 142.254732 -281.936952) (xy 142.05458 -281.936952) (xy 142.05458 -281.984704)
			(xy 142.154656 -282.084526)
		)
		(stroke
			(width 0)
			(type solid)
		)
		(fill yes)
		(layer "In13.Cu")
		(net "M_H_CPU1_SB_DQS_DP<6>")
	)
	(gr_poly
		(pts
			(xy 142.254732 -280.768044) (xy 142.154656 -280.668222) (xy 142.05458 -280.768044) (xy 142.05458 -280.815796)
			(xy 142.254732 -280.815796)
		)
		(stroke
			(width 0)
			(type solid)
		)
		(fill yes)
		(layer "In13.Cu")
		(net "M_H_CPU1_SB_DQS_DP<1>")
	)
	(gr_poly
		(pts
			(xy 142.254732 -280.364438) (xy 142.254732 -280.319988) (xy 142.05458 -280.319988) (xy 142.05458 -280.364438)
			(xy 142.154656 -280.464514)
		)
		(stroke
			(width 0)
			(type solid)
		)
		(fill yes)
		(layer "In13.Cu")
		(net "M_H_CPU1_SB_DQ<11>")
	)
	(gr_poly
		(pts
			(xy 142.254732 -279.148286) (xy 142.154656 -279.04821) (xy 142.05458 -279.148286) (xy 142.05458 -279.192736)
			(xy 142.254732 -279.192736)
		)
		(stroke
			(width 0)
			(type solid)
		)
		(fill yes)
		(layer "In13.Cu")
		(net "M_H_CPU1_SB_DQ<8>")
	)
	(gr_poly
		(pts
			(xy 142.254732 -278.744426) (xy 142.254732 -278.699976) (xy 142.05458 -278.699976) (xy 142.05458 -278.744426)
			(xy 142.154656 -278.844502)
		)
		(stroke
			(width 0)
			(type solid)
		)
		(fill yes)
		(layer "In13.Cu")
		(net "M_H_CPU1_SB_DQ<7>")
	)
	(gr_poly
		(pts
			(xy 142.254732 -277.528274) (xy 142.154656 -277.428198) (xy 142.05458 -277.528274) (xy 142.05458 -277.572724)
			(xy 142.254732 -277.572724)
		)
		(stroke
			(width 0)
			(type solid)
		)
		(fill yes)
		(layer "In13.Cu")
		(net "M_H_CPU1_SB_DQ<4>")
	)
	(gr_poly
		(pts
			(xy 142.254732 -277.124668) (xy 142.254732 -277.076916) (xy 142.05458 -277.076916) (xy 142.05458 -277.124668)
			(xy 142.154656 -277.22449)
		)
		(stroke
			(width 0)
			(type solid)
		)
		(fill yes)
		(layer "In13.Cu")
		(net "M_H_CPU1_SB_DQS_DP<5>")
	)
	(gr_poly
		(pts
			(xy 142.254732 -275.908008) (xy 142.154656 -275.808186) (xy 142.05458 -275.908008) (xy 142.05458 -275.95576)
			(xy 142.254732 -275.95576)
		)
		(stroke
			(width 0)
			(type solid)
		)
		(fill yes)
		(layer "In13.Cu")
		(net "M_H_CPU1_SB_DQS_DP<0>")
	)
	(gr_poly
		(pts
			(xy 142.254732 -275.504402) (xy 142.254732 -275.459952) (xy 142.05458 -275.459952) (xy 142.05458 -275.504402)
			(xy 142.154656 -275.604478)
		)
		(stroke
			(width 0)
			(type solid)
		)
		(fill yes)
		(layer "In13.Cu")
		(net "M_H_CPU1_SB_DQ<3>")
	)
	(gr_poly
		(pts
			(xy 142.254732 -274.28825) (xy 142.154656 -274.188174) (xy 142.05458 -274.28825) (xy 142.05458 -274.3327)
			(xy 142.254732 -274.3327)
		)
		(stroke
			(width 0)
			(type solid)
		)
		(fill yes)
		(layer "In13.Cu")
		(net "M_H_CPU1_SB_DQ<0>")
	)
	(gr_poly
		(pts
			(xy 142.254732 -273.88439) (xy 142.254732 -273.83994) (xy 142.05458 -273.83994) (xy 142.05458 -273.88439)
			(xy 142.154656 -273.984466)
		)
		(stroke
			(width 0)
			(type solid)
		)
		(fill yes)
		(layer "In13.Cu")
		(net "M_H_CPU1_SB_CB<3>")
	)
	(gr_poly
		(pts
			(xy 142.254732 -272.668238) (xy 142.154656 -272.568162) (xy 142.05458 -272.668238) (xy 142.05458 -272.712688)
			(xy 142.254732 -272.712688)
		)
		(stroke
			(width 0)
			(type solid)
		)
		(fill yes)
		(layer "In13.Cu")
		(net "M_H_CPU1_SB_CB<0>")
	)
	(gr_poly
		(pts
			(xy 142.254732 -272.264632) (xy 142.254732 -272.21688) (xy 142.05458 -272.21688) (xy 142.05458 -272.264632)
			(xy 142.154656 -272.364454)
		)
		(stroke
			(width 0)
			(type solid)
		)
		(fill yes)
		(layer "In13.Cu")
		(net "M_H_CPU1_SB_DQS_DP<4>")
	)
	(gr_poly
		(pts
			(xy 142.254732 -271.047972) (xy 142.154656 -270.94815) (xy 142.05458 -271.047972) (xy 142.05458 -271.095724)
			(xy 142.254732 -271.095724)
		)
		(stroke
			(width 0)
			(type solid)
		)
		(fill yes)
		(layer "In13.Cu")
		(net "M_H_CPU1_SB_DQS_DP<9>")
	)
	(gr_poly
		(pts
			(xy 142.254732 -270.644366) (xy 142.254732 -270.599916) (xy 142.05458 -270.599916) (xy 142.05458 -270.644366)
			(xy 142.154656 -270.744442)
		)
		(stroke
			(width 0)
			(type solid)
		)
		(fill yes)
		(layer "In13.Cu")
		(net "M_H_CPU1_SB_CB<7>")
	)
	(gr_poly
		(pts
			(xy 142.254732 -269.428214) (xy 142.154656 -269.328138) (xy 142.05458 -269.428214) (xy 142.05458 -269.472664)
			(xy 142.254732 -269.472664)
		)
		(stroke
			(width 0)
			(type solid)
		)
		(fill yes)
		(layer "In13.Cu")
		(net "M_H_CPU1_SB_CB<4>")
	)
	(gr_poly
		(pts
			(xy 142.254732 -267.808202) (xy 142.154656 -267.708126) (xy 142.05458 -267.808202) (xy 142.05458 -267.852652)
			(xy 142.254732 -267.852652)
		)
		(stroke
			(width 0)
			(type solid)
		)
		(fill yes)
		(layer "In13.Cu")
		(net "M_H_CPU1_SB_RSP<0>")
	)
	(gr_poly
		(pts
			(xy 142.254732 -265.78433) (xy 142.254732 -265.73988) (xy 142.05458 -265.73988) (xy 142.05458 -265.78433)
			(xy 142.154656 -265.884406)
		)
		(stroke
			(width 0)
			(type solid)
		)
		(fill yes)
		(layer "In13.Cu")
		(net "M_H_CPU1_SB_CS_N<0>")
	)
	(gr_poly
		(pts
			(xy 142.254732 -264.568178) (xy 142.154656 -264.468102) (xy 142.05458 -264.568178) (xy 142.05458 -264.612628)
			(xy 142.254732 -264.612628)
		)
		(stroke
			(width 0)
			(type solid)
		)
		(fill yes)
		(layer "In13.Cu")
		(net "M_H_CPU1_SB_CA<6>")
	)
	(gr_poly
		(pts
			(xy 142.254732 -264.164318) (xy 142.254732 -264.119868) (xy 142.05458 -264.119868) (xy 142.05458 -264.164318)
			(xy 142.154656 -264.264394)
		)
		(stroke
			(width 0)
			(type solid)
		)
		(fill yes)
		(layer "In13.Cu")
		(net "M_H_CPU1_SB_CA<5>")
	)
	(gr_poly
		(pts
			(xy 142.254732 -262.948166) (xy 142.154656 -262.84809) (xy 142.05458 -262.948166) (xy 142.05458 -262.992616)
			(xy 142.254732 -262.992616)
		)
		(stroke
			(width 0)
			(type solid)
		)
		(fill yes)
		(layer "In13.Cu")
		(net "M_H_CPU1_SB_CA<2>")
	)
	(gr_poly
		(pts
			(xy 142.254732 -262.544306) (xy 142.254732 -262.499856) (xy 142.05458 -262.499856) (xy 142.05458 -262.544306)
			(xy 142.154656 -262.644382)
		)
		(stroke
			(width 0)
			(type solid)
		)
		(fill yes)
		(layer "In13.Cu")
		(net "M_H_CPU1_SB_CA<1>")
	)
	(gr_poly
		(pts
			(xy 142.343886 -227.93579) (xy 142.305278 -227.913438) (xy 142.168626 -227.950014) (xy 142.205456 -228.086666)
			(xy 142.24381 -228.109018)
		)
		(stroke
			(width 0)
			(type solid)
		)
		(fill yes)
		(layer "In13.Cu")
		(net "M_H_CPU1_SA_DQ<4>")
	)
	(gr_poly
		(pts
			(xy 142.345918 -223.072706) (xy 142.30731 -223.050608) (xy 142.170912 -223.087184) (xy 142.207488 -223.223836)
			(xy 142.245842 -223.245934)
		)
		(stroke
			(width 0)
			(type solid)
		)
		(fill yes)
		(layer "In13.Cu")
		(net "M_H_CPU1_SA_DQ<1>")
	)
	(gr_poly
		(pts
			(xy 142.34668 -226.31654) (xy 142.305532 -226.292664) (xy 142.16888 -226.329494) (xy 142.205456 -226.465892)
			(xy 142.246858 -226.489768)
		)
		(stroke
			(width 0)
			(type solid)
		)
		(fill yes)
		(layer "In13.Cu")
		(net "M_H_CPU1_SA_DQS_DN<5>")
	)
	(gr_poly
		(pts
			(xy 142.34668 -224.696528) (xy 142.305532 -224.672652) (xy 142.16888 -224.709482) (xy 142.205456 -224.84588)
			(xy 142.246858 -224.869756)
		)
		(stroke
			(width 0)
			(type solid)
		)
		(fill yes)
		(layer "In13.Cu")
		(net "M_H_CPU1_SA_DQS_DP<0>")
	)
	(gr_poly
		(pts
			(xy 142.424912 -256.026158) (xy 142.324836 -255.926336) (xy 142.22476 -256.026158) (xy 142.22476 -256.07391)
			(xy 142.424912 -256.07391)
		)
		(stroke
			(width 0)
			(type solid)
		)
		(fill yes)
		(layer "In13.Cu")
		(net "M_H_CPU1_CLK_DP<0>")
	)
	(gr_poly
		(pts
			(xy 142.424912 -255.622552) (xy 142.424912 -255.578102) (xy 142.22476 -255.578102) (xy 142.22476 -255.622552)
			(xy 142.324836 -255.722628)
		)
		(stroke
			(width 0)
			(type solid)
		)
		(fill yes)
		(layer "In13.Cu")
		(net "M_H_CPU1_SA_PAR")
	)
	(gr_poly
		(pts
			(xy 142.424912 -254.4064) (xy 142.324836 -254.306324) (xy 142.22476 -254.4064) (xy 142.22476 -254.45085)
			(xy 142.424912 -254.45085)
		)
		(stroke
			(width 0)
			(type solid)
		)
		(fill yes)
		(layer "In13.Cu")
		(net "M_H_CPU1_SA_CA<4>")
	)
	(gr_poly
		(pts
			(xy 142.424912 -254.00254) (xy 142.424912 -253.95809) (xy 142.22476 -253.95809) (xy 142.22476 -254.00254)
			(xy 142.324836 -254.102616)
		)
		(stroke
			(width 0)
			(type solid)
		)
		(fill yes)
		(layer "In13.Cu")
		(net "M_H_CPU1_SA_CA<3>")
	)
	(gr_poly
		(pts
			(xy 142.424912 -252.786388) (xy 142.324836 -252.686312) (xy 142.22476 -252.786388) (xy 142.22476 -252.830838)
			(xy 142.424912 -252.830838)
		)
		(stroke
			(width 0)
			(type solid)
		)
		(fill yes)
		(layer "In13.Cu")
		(net "M_H_CPU1_SA_CA<0>")
	)
	(gr_poly
		(pts
			(xy 142.424912 -251.166376) (xy 142.324836 -251.0663) (xy 142.22476 -251.166376) (xy 142.22476 -251.210826)
			(xy 142.424912 -251.210826)
		)
		(stroke
			(width 0)
			(type solid)
		)
		(fill yes)
		(layer "In13.Cu")
		(net "M_H_CPU1_SA_CS_N<0>")
	)
	(gr_poly
		(pts
			(xy 142.424912 -250.762516) (xy 142.424912 -250.718066) (xy 142.22476 -250.718066) (xy 142.22476 -250.762516)
			(xy 142.324836 -250.862592)
		)
		(stroke
			(width 0)
			(type solid)
		)
		(fill yes)
		(layer "In13.Cu")
		(net "M_H_CPU1_RESET_N")
	)
	(gr_poly
		(pts
			(xy 142.424912 -249.142504) (xy 142.424912 -249.098054) (xy 142.22476 -249.098054) (xy 142.22476 -249.142504)
			(xy 142.324836 -249.24258)
		)
		(stroke
			(width 0)
			(type solid)
		)
		(fill yes)
		(layer "In13.Cu")
		(net "M_H_CPU1_SA_CB<7>")
	)
	(gr_poly
		(pts
			(xy 142.424912 -247.926352) (xy 142.324836 -247.826276) (xy 142.22476 -247.926352) (xy 142.22476 -247.970802)
			(xy 142.424912 -247.970802)
		)
		(stroke
			(width 0)
			(type solid)
		)
		(fill yes)
		(layer "In13.Cu")
		(net "M_H_CPU1_SA_CB<4>")
	)
	(gr_poly
		(pts
			(xy 142.424912 -247.522746) (xy 142.424912 -247.474994) (xy 142.22476 -247.474994) (xy 142.22476 -247.522746)
			(xy 142.324836 -247.622568)
		)
		(stroke
			(width 0)
			(type solid)
		)
		(fill yes)
		(layer "In13.Cu")
		(net "M_H_CPU1_SA_DQS_DP<9>")
	)
	(gr_poly
		(pts
			(xy 142.424912 -246.306086) (xy 142.324836 -246.206264) (xy 142.22476 -246.306086) (xy 142.22476 -246.353838)
			(xy 142.424912 -246.353838)
		)
		(stroke
			(width 0)
			(type solid)
		)
		(fill yes)
		(layer "In13.Cu")
		(net "M_H_CPU1_SA_DQS_DP<4>")
	)
	(gr_poly
		(pts
			(xy 142.424912 -245.90248) (xy 142.424912 -245.85803) (xy 142.22476 -245.85803) (xy 142.22476 -245.90248)
			(xy 142.324836 -246.002556)
		)
		(stroke
			(width 0)
			(type solid)
		)
		(fill yes)
		(layer "In13.Cu")
		(net "M_H_CPU1_SA_CB<3>")
	)
	(gr_poly
		(pts
			(xy 142.424912 -244.686328) (xy 142.324836 -244.586252) (xy 142.22476 -244.686328) (xy 142.22476 -244.730778)
			(xy 142.424912 -244.730778)
		)
		(stroke
			(width 0)
			(type solid)
		)
		(fill yes)
		(layer "In13.Cu")
		(net "M_H_CPU1_SA_CB<0>")
	)
	(gr_poly
		(pts
			(xy 142.424912 -244.282468) (xy 142.424912 -244.238018) (xy 142.22476 -244.238018) (xy 142.22476 -244.282468)
			(xy 142.324836 -244.382544)
		)
		(stroke
			(width 0)
			(type solid)
		)
		(fill yes)
		(layer "In13.Cu")
		(net "M_H_CPU1_SA_DQ<31>")
	)
	(gr_poly
		(pts
			(xy 142.424912 -243.066316) (xy 142.324836 -242.96624) (xy 142.22476 -243.066316) (xy 142.22476 -243.110766)
			(xy 142.424912 -243.110766)
		)
		(stroke
			(width 0)
			(type solid)
		)
		(fill yes)
		(layer "In13.Cu")
		(net "M_H_CPU1_SA_DQ<28>")
	)
	(gr_poly
		(pts
			(xy 142.424912 -242.66271) (xy 142.424912 -242.614958) (xy 142.22476 -242.614958) (xy 142.22476 -242.66271)
			(xy 142.324836 -242.762532)
		)
		(stroke
			(width 0)
			(type solid)
		)
		(fill yes)
		(layer "In13.Cu")
		(net "M_H_CPU1_SA_DQS_DP<8>")
	)
	(gr_poly
		(pts
			(xy 142.424912 -241.44605) (xy 142.324836 -241.346228) (xy 142.22476 -241.44605) (xy 142.22476 -241.493802)
			(xy 142.424912 -241.493802)
		)
		(stroke
			(width 0)
			(type solid)
		)
		(fill yes)
		(layer "In13.Cu")
		(net "M_H_CPU1_SA_DQS_DP<3>")
	)
	(gr_poly
		(pts
			(xy 142.424912 -241.042444) (xy 142.424912 -240.997994) (xy 142.22476 -240.997994) (xy 142.22476 -241.042444)
			(xy 142.324836 -241.14252)
		)
		(stroke
			(width 0)
			(type solid)
		)
		(fill yes)
		(layer "In13.Cu")
		(net "M_H_CPU1_SA_DQ<27>")
	)
	(gr_poly
		(pts
			(xy 142.424912 -239.826292) (xy 142.324836 -239.726216) (xy 142.22476 -239.826292) (xy 142.22476 -239.870742)
			(xy 142.424912 -239.870742)
		)
		(stroke
			(width 0)
			(type solid)
		)
		(fill yes)
		(layer "In13.Cu")
		(net "M_H_CPU1_SA_DQ<24>")
	)
	(gr_poly
		(pts
			(xy 142.424912 -239.422432) (xy 142.424912 -239.377982) (xy 142.22476 -239.377982) (xy 142.22476 -239.422432)
			(xy 142.324836 -239.522508)
		)
		(stroke
			(width 0)
			(type solid)
		)
		(fill yes)
		(layer "In13.Cu")
		(net "M_H_CPU1_SA_DQ<23>")
	)
	(gr_poly
		(pts
			(xy 142.424912 -238.20628) (xy 142.324836 -238.106204) (xy 142.22476 -238.20628) (xy 142.22476 -238.25073)
			(xy 142.424912 -238.25073)
		)
		(stroke
			(width 0)
			(type solid)
		)
		(fill yes)
		(layer "In13.Cu")
		(net "M_H_CPU1_SA_DQ<20>")
	)
	(gr_poly
		(pts
			(xy 142.424912 -237.802674) (xy 142.424912 -237.754922) (xy 142.22476 -237.754922) (xy 142.22476 -237.802674)
			(xy 142.324836 -237.902496)
		)
		(stroke
			(width 0)
			(type solid)
		)
		(fill yes)
		(layer "In13.Cu")
		(net "M_H_CPU1_SA_DQS_DP<7>")
	)
	(gr_poly
		(pts
			(xy 142.424912 -236.586014) (xy 142.324836 -236.486192) (xy 142.22476 -236.586014) (xy 142.22476 -236.633766)
			(xy 142.424912 -236.633766)
		)
		(stroke
			(width 0)
			(type solid)
		)
		(fill yes)
		(layer "In13.Cu")
		(net "M_H_CPU1_SA_DQS_DP<2>")
	)
	(gr_poly
		(pts
			(xy 142.424912 -236.182408) (xy 142.424912 -236.137958) (xy 142.22476 -236.137958) (xy 142.22476 -236.182408)
			(xy 142.324836 -236.282484)
		)
		(stroke
			(width 0)
			(type solid)
		)
		(fill yes)
		(layer "In13.Cu")
		(net "M_H_CPU1_SA_DQ<19>")
	)
	(gr_poly
		(pts
			(xy 142.424912 -234.966256) (xy 142.324836 -234.86618) (xy 142.22476 -234.966256) (xy 142.22476 -235.010706)
			(xy 142.424912 -235.010706)
		)
		(stroke
			(width 0)
			(type solid)
		)
		(fill yes)
		(layer "In13.Cu")
		(net "M_H_CPU1_SA_DQ<16>")
	)
	(gr_poly
		(pts
			(xy 142.424912 -234.562396) (xy 142.424912 -234.517946) (xy 142.22476 -234.517946) (xy 142.22476 -234.562396)
			(xy 142.324836 -234.662472)
		)
		(stroke
			(width 0)
			(type solid)
		)
		(fill yes)
		(layer "In13.Cu")
		(net "M_H_CPU1_SA_DQ<15>")
	)
	(gr_poly
		(pts
			(xy 142.424912 -233.346244) (xy 142.324836 -233.246168) (xy 142.22476 -233.346244) (xy 142.22476 -233.390694)
			(xy 142.424912 -233.390694)
		)
		(stroke
			(width 0)
			(type solid)
		)
		(fill yes)
		(layer "In13.Cu")
		(net "M_H_CPU1_SA_DQ<12>")
	)
	(gr_poly
		(pts
			(xy 142.424912 -232.942638) (xy 142.424912 -232.894886) (xy 142.22476 -232.894886) (xy 142.22476 -232.942638)
			(xy 142.324836 -233.04246)
		)
		(stroke
			(width 0)
			(type solid)
		)
		(fill yes)
		(layer "In13.Cu")
		(net "M_H_CPU1_SA_DQS_DP<6>")
	)
	(gr_poly
		(pts
			(xy 142.424912 -231.725978) (xy 142.324836 -231.626156) (xy 142.22476 -231.725978) (xy 142.22476 -231.77373)
			(xy 142.424912 -231.77373)
		)
		(stroke
			(width 0)
			(type solid)
		)
		(fill yes)
		(layer "In13.Cu")
		(net "M_H_CPU1_SA_DQS_DP<1>")
	)
	(gr_poly
		(pts
			(xy 142.424912 -231.322626) (xy 142.424912 -231.278176) (xy 142.22476 -231.278176) (xy 142.22476 -231.322626)
			(xy 142.324836 -231.422702)
		)
		(stroke
			(width 0)
			(type solid)
		)
		(fill yes)
		(layer "In13.Cu")
		(net "M_H_CPU1_SA_DQ<11>")
	)
	(gr_poly
		(pts
			(xy 142.424912 -230.10622) (xy 142.324836 -230.006144) (xy 142.22476 -230.10622) (xy 142.22476 -230.15067)
			(xy 142.424912 -230.15067)
		)
		(stroke
			(width 0)
			(type solid)
		)
		(fill yes)
		(layer "In13.Cu")
		(net "M_H_CPU1_SA_DQ<8>")
	)
	(gr_poly
		(pts
			(xy 142.424912 -229.702614) (xy 142.424912 -229.658164) (xy 142.22476 -229.658164) (xy 142.22476 -229.702614)
			(xy 142.324836 -229.80269)
		)
		(stroke
			(width 0)
			(type solid)
		)
		(fill yes)
		(layer "In13.Cu")
		(net "M_H_CPU1_SA_DQ<7>")
	)
	(gr_poly
		(pts
			(xy 142.479776 -223.761046) (xy 142.4432 -223.624394) (xy 142.404592 -223.602296) (xy 142.30477 -223.77527)
			(xy 142.343124 -223.797622)
		)
		(stroke
			(width 0)
			(type solid)
		)
		(fill yes)
		(layer "In13.Cu")
		(net "M_H_CPU1_SA_DQ<3>")
	)
	(gr_poly
		(pts
			(xy 142.480538 -228.61905) (xy 142.443962 -228.482398) (xy 142.405608 -228.460046) (xy 142.305532 -228.633274)
			(xy 142.34414 -228.655626)
		)
		(stroke
			(width 0)
			(type solid)
		)
		(fill yes)
		(layer "In13.Cu")
		(net "M_H_CPU1_SA_DQ<6>")
	)
	(gr_poly
		(pts
			(xy 142.480538 -226.999546) (xy 142.443962 -226.863148) (xy 142.40256 -226.839272) (xy 142.302738 -227.0125)
			(xy 142.343886 -227.036376)
		)
		(stroke
			(width 0)
			(type solid)
		)
		(fill yes)
		(layer "In13.Cu")
		(net "M_H_CPU1_SA_DQS_DP<5>")
	)
	(gr_poly
		(pts
			(xy 142.480538 -225.379534) (xy 142.443962 -225.243136) (xy 142.40256 -225.21926) (xy 142.302738 -225.392488)
			(xy 142.343886 -225.416364)
		)
		(stroke
			(width 0)
			(type solid)
		)
		(fill yes)
		(layer "In13.Cu")
		(net "M_H_CPU1_SA_DQS_DN<0>")
	)
	(gr_poly
		(pts
			(xy 142.724886 -292.918134) (xy 142.62481 -292.818058) (xy 142.524734 -292.918134) (xy 142.524734 -292.962584)
			(xy 142.724886 -292.962584)
		)
		(stroke
			(width 0)
			(type solid)
		)
		(fill yes)
		(layer "In13.Cu")
		(net "M_H_CPU1_SB_DQ<29>")
	)
	(gr_poly
		(pts
			(xy 142.724886 -292.514274) (xy 142.724886 -292.469824) (xy 142.524734 -292.469824) (xy 142.524734 -292.514274)
			(xy 142.62481 -292.61435)
		)
		(stroke
			(width 0)
			(type solid)
		)
		(fill yes)
		(layer "In13.Cu")
		(net "M_H_CPU1_SB_DQ<30>")
	)
	(gr_poly
		(pts
			(xy 142.724886 -291.297868) (xy 142.62481 -291.198046) (xy 142.524734 -291.297868) (xy 142.524734 -291.34562)
			(xy 142.724886 -291.34562)
		)
		(stroke
			(width 0)
			(type solid)
		)
		(fill yes)
		(layer "In13.Cu")
		(net "M_H_CPU1_SB_DQS_DN<8>")
	)
	(gr_poly
		(pts
			(xy 142.724886 -290.894516) (xy 142.724886 -290.846764) (xy 142.524734 -290.846764) (xy 142.524734 -290.894516)
			(xy 142.62481 -290.994338)
		)
		(stroke
			(width 0)
			(type solid)
		)
		(fill yes)
		(layer "In13.Cu")
		(net "M_H_CPU1_SB_DQS_DN<3>")
	)
	(gr_poly
		(pts
			(xy 142.724886 -289.67811) (xy 142.62481 -289.578034) (xy 142.524734 -289.67811) (xy 142.524734 -289.72256)
			(xy 142.724886 -289.72256)
		)
		(stroke
			(width 0)
			(type solid)
		)
		(fill yes)
		(layer "In13.Cu")
		(net "M_H_CPU1_SB_DQ<25>")
	)
	(gr_poly
		(pts
			(xy 142.724886 -289.27425) (xy 142.724886 -289.2298) (xy 142.524734 -289.2298) (xy 142.524734 -289.27425)
			(xy 142.62481 -289.374326)
		)
		(stroke
			(width 0)
			(type solid)
		)
		(fill yes)
		(layer "In13.Cu")
		(net "M_H_CPU1_SB_DQ<26>")
	)
	(gr_poly
		(pts
			(xy 142.724886 -288.058098) (xy 142.62481 -287.958022) (xy 142.524734 -288.058098) (xy 142.524734 -288.102548)
			(xy 142.724886 -288.102548)
		)
		(stroke
			(width 0)
			(type solid)
		)
		(fill yes)
		(layer "In13.Cu")
		(net "M_H_CPU1_SB_DQ<21>")
	)
	(gr_poly
		(pts
			(xy 142.724886 -287.654492) (xy 142.724886 -287.610042) (xy 142.524734 -287.610042) (xy 142.524734 -287.654492)
			(xy 142.62481 -287.754568)
		)
		(stroke
			(width 0)
			(type solid)
		)
		(fill yes)
		(layer "In13.Cu")
		(net "M_H_CPU1_SB_DQ<22>")
	)
	(gr_poly
		(pts
			(xy 142.724886 -286.438086) (xy 142.62481 -286.33801) (xy 142.524734 -286.438086) (xy 142.524734 -286.485838)
			(xy 142.724886 -286.485838)
		)
		(stroke
			(width 0)
			(type solid)
		)
		(fill yes)
		(layer "In13.Cu")
		(net "M_H_CPU1_SB_DQS_DN<7>")
	)
	(gr_poly
		(pts
			(xy 142.724886 -286.034734) (xy 142.724886 -285.986982) (xy 142.524734 -285.986982) (xy 142.524734 -286.034734)
			(xy 142.62481 -286.134556)
		)
		(stroke
			(width 0)
			(type solid)
		)
		(fill yes)
		(layer "In13.Cu")
		(net "M_H_CPU1_SB_DQS_DN<2>")
	)
	(gr_poly
		(pts
			(xy 142.724886 -284.818328) (xy 142.62481 -284.718252) (xy 142.524734 -284.818328) (xy 142.524734 -284.862778)
			(xy 142.724886 -284.862778)
		)
		(stroke
			(width 0)
			(type solid)
		)
		(fill yes)
		(layer "In13.Cu")
		(net "M_H_CPU1_SB_DQ<17>")
	)
	(gr_poly
		(pts
			(xy 142.724886 -284.414468) (xy 142.724886 -284.370018) (xy 142.524734 -284.370018) (xy 142.524734 -284.414468)
			(xy 142.62481 -284.514544)
		)
		(stroke
			(width 0)
			(type solid)
		)
		(fill yes)
		(layer "In13.Cu")
		(net "M_H_CPU1_SB_DQ<18>")
	)
	(gr_poly
		(pts
			(xy 142.724886 -283.198316) (xy 142.62481 -283.09824) (xy 142.524734 -283.198316) (xy 142.524734 -283.242766)
			(xy 142.724886 -283.242766)
		)
		(stroke
			(width 0)
			(type solid)
		)
		(fill yes)
		(layer "In13.Cu")
		(net "M_H_CPU1_SB_DQ<13>")
	)
	(gr_poly
		(pts
			(xy 142.724886 -282.794456) (xy 142.724886 -282.750006) (xy 142.524734 -282.750006) (xy 142.524734 -282.794456)
			(xy 142.62481 -282.894532)
		)
		(stroke
			(width 0)
			(type solid)
		)
		(fill yes)
		(layer "In13.Cu")
		(net "M_H_CPU1_SB_DQ<14>")
	)
	(gr_poly
		(pts
			(xy 142.724886 -281.57805) (xy 142.62481 -281.478228) (xy 142.524734 -281.57805) (xy 142.524734 -281.625802)
			(xy 142.724886 -281.625802)
		)
		(stroke
			(width 0)
			(type solid)
		)
		(fill yes)
		(layer "In13.Cu")
		(net "M_H_CPU1_SB_DQS_DN<6>")
	)
	(gr_poly
		(pts
			(xy 142.724886 -281.174698) (xy 142.724886 -281.126946) (xy 142.524734 -281.126946) (xy 142.524734 -281.174698)
			(xy 142.62481 -281.27452)
		)
		(stroke
			(width 0)
			(type solid)
		)
		(fill yes)
		(layer "In13.Cu")
		(net "M_H_CPU1_SB_DQS_DN<1>")
	)
	(gr_poly
		(pts
			(xy 142.724886 -279.958292) (xy 142.62481 -279.858216) (xy 142.524734 -279.958292) (xy 142.524734 -280.002742)
			(xy 142.724886 -280.002742)
		)
		(stroke
			(width 0)
			(type solid)
		)
		(fill yes)
		(layer "In13.Cu")
		(net "M_H_CPU1_SB_DQ<9>")
	)
	(gr_poly
		(pts
			(xy 142.724886 -279.554432) (xy 142.724886 -279.509982) (xy 142.524734 -279.509982) (xy 142.524734 -279.554432)
			(xy 142.62481 -279.654508)
		)
		(stroke
			(width 0)
			(type solid)
		)
		(fill yes)
		(layer "In13.Cu")
		(net "M_H_CPU1_SB_DQ<10>")
	)
	(gr_poly
		(pts
			(xy 142.724886 -278.33828) (xy 142.62481 -278.238204) (xy 142.524734 -278.33828) (xy 142.524734 -278.38273)
			(xy 142.724886 -278.38273)
		)
		(stroke
			(width 0)
			(type solid)
		)
		(fill yes)
		(layer "In13.Cu")
		(net "M_H_CPU1_SB_DQ<5>")
	)
	(gr_poly
		(pts
			(xy 142.724886 -277.93442) (xy 142.724886 -277.88997) (xy 142.524734 -277.88997) (xy 142.524734 -277.93442)
			(xy 142.62481 -278.034496)
		)
		(stroke
			(width 0)
			(type solid)
		)
		(fill yes)
		(layer "In13.Cu")
		(net "M_H_CPU1_SB_DQ<6>")
	)
	(gr_poly
		(pts
			(xy 142.724886 -276.718014) (xy 142.62481 -276.618192) (xy 142.524734 -276.718014) (xy 142.524734 -276.765766)
			(xy 142.724886 -276.765766)
		)
		(stroke
			(width 0)
			(type solid)
		)
		(fill yes)
		(layer "In13.Cu")
		(net "M_H_CPU1_SB_DQS_DN<5>")
	)
	(gr_poly
		(pts
			(xy 142.724886 -276.314662) (xy 142.724886 -276.26691) (xy 142.524734 -276.26691) (xy 142.524734 -276.314662)
			(xy 142.62481 -276.414484)
		)
		(stroke
			(width 0)
			(type solid)
		)
		(fill yes)
		(layer "In13.Cu")
		(net "M_H_CPU1_SB_DQS_DN<0>")
	)
	(gr_poly
		(pts
			(xy 142.724886 -275.098256) (xy 142.62481 -274.99818) (xy 142.524734 -275.098256) (xy 142.524734 -275.142706)
			(xy 142.724886 -275.142706)
		)
		(stroke
			(width 0)
			(type solid)
		)
		(fill yes)
		(layer "In13.Cu")
		(net "M_H_CPU1_SB_DQ<1>")
	)
	(gr_poly
		(pts
			(xy 142.724886 -274.694396) (xy 142.724886 -274.649946) (xy 142.524734 -274.649946) (xy 142.524734 -274.694396)
			(xy 142.62481 -274.794472)
		)
		(stroke
			(width 0)
			(type solid)
		)
		(fill yes)
		(layer "In13.Cu")
		(net "M_H_CPU1_SB_DQ<2>")
	)
	(gr_poly
		(pts
			(xy 142.724886 -273.478244) (xy 142.62481 -273.378168) (xy 142.524734 -273.478244) (xy 142.524734 -273.522694)
			(xy 142.724886 -273.522694)
		)
		(stroke
			(width 0)
			(type solid)
		)
		(fill yes)
		(layer "In13.Cu")
		(net "M_H_CPU1_SB_CB<1>")
	)
	(gr_poly
		(pts
			(xy 142.724886 -273.074384) (xy 142.724886 -273.029934) (xy 142.524734 -273.029934) (xy 142.524734 -273.074384)
			(xy 142.62481 -273.17446)
		)
		(stroke
			(width 0)
			(type solid)
		)
		(fill yes)
		(layer "In13.Cu")
		(net "M_H_CPU1_SB_CB<2>")
	)
	(gr_poly
		(pts
			(xy 142.724886 -271.857978) (xy 142.62481 -271.758156) (xy 142.524734 -271.857978) (xy 142.524734 -271.90573)
			(xy 142.724886 -271.90573)
		)
		(stroke
			(width 0)
			(type solid)
		)
		(fill yes)
		(layer "In13.Cu")
		(net "M_H_CPU1_SB_DQS_DN<4>")
	)
	(gr_poly
		(pts
			(xy 142.724886 -271.454626) (xy 142.724886 -271.406874) (xy 142.524734 -271.406874) (xy 142.524734 -271.454626)
			(xy 142.62481 -271.554448)
		)
		(stroke
			(width 0)
			(type solid)
		)
		(fill yes)
		(layer "In13.Cu")
		(net "M_H_CPU1_SB_DQS_DN<9>")
	)
	(gr_poly
		(pts
			(xy 142.724886 -270.23822) (xy 142.62481 -270.138144) (xy 142.524734 -270.23822) (xy 142.524734 -270.28267)
			(xy 142.724886 -270.28267)
		)
		(stroke
			(width 0)
			(type solid)
		)
		(fill yes)
		(layer "In13.Cu")
		(net "M_H_CPU1_SB_CB<5>")
	)
	(gr_poly
		(pts
			(xy 142.724886 -269.83436) (xy 142.724886 -269.78991) (xy 142.524734 -269.78991) (xy 142.524734 -269.83436)
			(xy 142.62481 -269.934436)
		)
		(stroke
			(width 0)
			(type solid)
		)
		(fill yes)
		(layer "In13.Cu")
		(net "M_H_CPU1_SB_CB<6>")
	)
	(gr_poly
		(pts
			(xy 142.724886 -266.998196) (xy 142.62481 -266.89812) (xy 142.524734 -266.998196) (xy 142.524734 -267.042646)
			(xy 142.724886 -267.042646)
		)
		(stroke
			(width 0)
			(type solid)
		)
		(fill yes)
		(layer "In13.Cu")
		(net "M_H_CPU1_SA_RSP<0>")
	)
	(gr_poly
		(pts
			(xy 142.724886 -266.594336) (xy 142.724886 -266.549886) (xy 142.524734 -266.549886) (xy 142.524734 -266.594336)
			(xy 142.62481 -266.694412)
		)
		(stroke
			(width 0)
			(type solid)
		)
		(fill yes)
		(layer "In13.Cu")
		(net "M_H_CPU1_SB_CS_N<1>")
	)
	(gr_poly
		(pts
			(xy 142.724886 -265.378184) (xy 142.62481 -265.278108) (xy 142.524734 -265.378184) (xy 142.524734 -265.422634)
			(xy 142.724886 -265.422634)
		)
		(stroke
			(width 0)
			(type solid)
		)
		(fill yes)
		(layer "In13.Cu")
		(net "M_H_CPU1_SB_PAR")
	)
	(gr_poly
		(pts
			(xy 142.724886 -263.758172) (xy 142.62481 -263.658096) (xy 142.524734 -263.758172) (xy 142.524734 -263.802622)
			(xy 142.724886 -263.802622)
		)
		(stroke
			(width 0)
			(type solid)
		)
		(fill yes)
		(layer "In13.Cu")
		(net "M_H_CPU1_SB_CA<4>")
	)
	(gr_poly
		(pts
			(xy 142.724886 -263.354312) (xy 142.724886 -263.309862) (xy 142.524734 -263.309862) (xy 142.524734 -263.354312)
			(xy 142.62481 -263.454388)
		)
		(stroke
			(width 0)
			(type solid)
		)
		(fill yes)
		(layer "In13.Cu")
		(net "M_H_CPU1_SB_CA<3>")
	)
	(gr_poly
		(pts
			(xy 142.724886 -262.13816) (xy 142.62481 -262.038084) (xy 142.524734 -262.13816) (xy 142.524734 -262.18261)
			(xy 142.724886 -262.18261)
		)
		(stroke
			(width 0)
			(type solid)
		)
		(fill yes)
		(layer "In13.Cu")
		(net "M_H_CPU1_SB_CA<0>")
	)
	(gr_poly
		(pts
			(xy 142.814802 -228.744272) (xy 142.776194 -228.722174) (xy 142.639542 -228.75875) (xy 142.676118 -228.895402)
			(xy 142.714726 -228.9175)
		)
		(stroke
			(width 0)
			(type solid)
		)
		(fill yes)
		(layer "In13.Cu")
		(net "M_H_CPU1_SA_DQ<5>")
	)
	(gr_poly
		(pts
			(xy 142.814802 -227.12426) (xy 142.776194 -227.102162) (xy 142.639542 -227.138738) (xy 142.676118 -227.27539)
			(xy 142.714726 -227.297488)
		)
		(stroke
			(width 0)
			(type solid)
		)
		(fill yes)
		(layer "In13.Cu")
		(net "M_H_CPU1_SA_DQ<4>")
	)
	(gr_poly
		(pts
			(xy 142.81531 -222.263462) (xy 142.776956 -222.241364) (xy 142.640304 -222.27794) (xy 142.67688 -222.414592)
			(xy 142.715488 -222.43669)
		)
		(stroke
			(width 0)
			(type solid)
		)
		(fill yes)
		(layer "In13.Cu")
		(net "M_H_CPU1_SA_DQ<1>")
	)
	(gr_poly
		(pts
			(xy 142.87119 -236.99216) (xy 142.87119 -236.944408) (xy 142.671038 -236.944408) (xy 142.671038 -236.99216)
			(xy 142.771114 -237.092236)
		)
		(stroke
			(width 0)
			(type solid)
		)
		(fill yes)
		(layer "In13.Cu")
		(net "M_H_CPU1_SA_DQS_DN<2>")
	)
	(gr_poly
		(pts
			(xy 142.894812 -256.432812) (xy 142.894812 -256.38506) (xy 142.69466 -256.38506) (xy 142.69466 -256.432812)
			(xy 142.794736 -256.532634)
		)
		(stroke
			(width 0)
			(type solid)
		)
		(fill yes)
		(layer "In13.Cu")
		(net "M_H_CPU1_CLK_DN<0>")
	)
	(gr_poly
		(pts
			(xy 142.894812 -255.216406) (xy 142.794736 -255.11633) (xy 142.69466 -255.216406) (xy 142.69466 -255.260856)
			(xy 142.894812 -255.260856)
		)
		(stroke
			(width 0)
			(type solid)
		)
		(fill yes)
		(layer "In13.Cu")
		(net "M_H_CPU1_SA_CA<6>")
	)
	(gr_poly
		(pts
			(xy 142.894812 -254.812546) (xy 142.894812 -254.768096) (xy 142.69466 -254.768096) (xy 142.69466 -254.812546)
			(xy 142.794736 -254.912622)
		)
		(stroke
			(width 0)
			(type solid)
		)
		(fill yes)
		(layer "In13.Cu")
		(net "M_H_CPU1_SA_CA<5>")
	)
	(gr_poly
		(pts
			(xy 142.894812 -253.596394) (xy 142.794736 -253.496318) (xy 142.69466 -253.596394) (xy 142.69466 -253.640844)
			(xy 142.894812 -253.640844)
		)
		(stroke
			(width 0)
			(type solid)
		)
		(fill yes)
		(layer "In13.Cu")
		(net "M_H_CPU1_SA_CA<2>")
	)
	(gr_poly
		(pts
			(xy 142.894812 -253.192534) (xy 142.894812 -253.148084) (xy 142.69466 -253.148084) (xy 142.69466 -253.192534)
			(xy 142.794736 -253.29261)
		)
		(stroke
			(width 0)
			(type solid)
		)
		(fill yes)
		(layer "In13.Cu")
		(net "M_H_CPU1_SA_CA<1>")
	)
	(gr_poly
		(pts
			(xy 142.894812 -251.976382) (xy 142.794736 -251.876306) (xy 142.69466 -251.976382) (xy 142.69466 -252.020832)
			(xy 142.894812 -252.020832)
		)
		(stroke
			(width 0)
			(type solid)
		)
		(fill yes)
		(layer "In13.Cu")
		(net "M_H_CPU1_SA_CS_N<1>")
	)
	(gr_poly
		(pts
			(xy 142.894812 -250.35637) (xy 142.794736 -250.256294) (xy 142.69466 -250.35637) (xy 142.69466 -250.40082)
			(xy 142.894812 -250.40082)
		)
		(stroke
			(width 0)
			(type solid)
		)
		(fill yes)
		(layer "In13.Cu")
		(net "M_H_CPU1_ALERT_R_N")
	)
	(gr_poly
		(pts
			(xy 142.894812 -248.736358) (xy 142.794736 -248.636282) (xy 142.69466 -248.736358) (xy 142.69466 -248.780808)
			(xy 142.894812 -248.780808)
		)
		(stroke
			(width 0)
			(type solid)
		)
		(fill yes)
		(layer "In13.Cu")
		(net "M_H_CPU1_SA_CB<5>")
	)
	(gr_poly
		(pts
			(xy 142.894812 -248.332498) (xy 142.894812 -248.288048) (xy 142.69466 -248.288048) (xy 142.69466 -248.332498)
			(xy 142.794736 -248.432574)
		)
		(stroke
			(width 0)
			(type solid)
		)
		(fill yes)
		(layer "In13.Cu")
		(net "M_H_CPU1_SA_CB<6>")
	)
	(gr_poly
		(pts
			(xy 142.894812 -247.116092) (xy 142.794736 -247.01627) (xy 142.69466 -247.116092) (xy 142.69466 -247.163844)
			(xy 142.894812 -247.163844)
		)
		(stroke
			(width 0)
			(type solid)
		)
		(fill yes)
		(layer "In13.Cu")
		(net "M_H_CPU1_SA_DQS_DN<9>")
	)
	(gr_poly
		(pts
			(xy 142.894812 -246.71274) (xy 142.894812 -246.664988) (xy 142.69466 -246.664988) (xy 142.69466 -246.71274)
			(xy 142.794736 -246.812562)
		)
		(stroke
			(width 0)
			(type solid)
		)
		(fill yes)
		(layer "In13.Cu")
		(net "M_H_CPU1_SA_DQS_DN<4>")
	)
	(gr_poly
		(pts
			(xy 142.894812 -245.496334) (xy 142.794736 -245.396258) (xy 142.69466 -245.496334) (xy 142.69466 -245.540784)
			(xy 142.894812 -245.540784)
		)
		(stroke
			(width 0)
			(type solid)
		)
		(fill yes)
		(layer "In13.Cu")
		(net "M_H_CPU1_SA_CB<1>")
	)
	(gr_poly
		(pts
			(xy 142.894812 -245.092474) (xy 142.894812 -245.048024) (xy 142.69466 -245.048024) (xy 142.69466 -245.092474)
			(xy 142.794736 -245.19255)
		)
		(stroke
			(width 0)
			(type solid)
		)
		(fill yes)
		(layer "In13.Cu")
		(net "M_H_CPU1_SA_CB<2>")
	)
	(gr_poly
		(pts
			(xy 142.894812 -243.876322) (xy 142.794736 -243.776246) (xy 142.69466 -243.876322) (xy 142.69466 -243.920772)
			(xy 142.894812 -243.920772)
		)
		(stroke
			(width 0)
			(type solid)
		)
		(fill yes)
		(layer "In13.Cu")
		(net "M_H_CPU1_SA_DQ<29>")
	)
	(gr_poly
		(pts
			(xy 142.894812 -243.472462) (xy 142.894812 -243.428012) (xy 142.69466 -243.428012) (xy 142.69466 -243.472462)
			(xy 142.794736 -243.572538)
		)
		(stroke
			(width 0)
			(type solid)
		)
		(fill yes)
		(layer "In13.Cu")
		(net "M_H_CPU1_SA_DQ<30>")
	)
	(gr_poly
		(pts
			(xy 142.894812 -242.256056) (xy 142.794736 -242.156234) (xy 142.69466 -242.256056) (xy 142.69466 -242.303808)
			(xy 142.894812 -242.303808)
		)
		(stroke
			(width 0)
			(type solid)
		)
		(fill yes)
		(layer "In13.Cu")
		(net "M_H_CPU1_SA_DQS_DN<8>")
	)
	(gr_poly
		(pts
			(xy 142.894812 -241.852704) (xy 142.894812 -241.804952) (xy 142.69466 -241.804952) (xy 142.69466 -241.852704)
			(xy 142.794736 -241.952526)
		)
		(stroke
			(width 0)
			(type solid)
		)
		(fill yes)
		(layer "In13.Cu")
		(net "M_H_CPU1_SA_DQS_DN<3>")
	)
	(gr_poly
		(pts
			(xy 142.894812 -240.636298) (xy 142.794736 -240.536222) (xy 142.69466 -240.636298) (xy 142.69466 -240.680748)
			(xy 142.894812 -240.680748)
		)
		(stroke
			(width 0)
			(type solid)
		)
		(fill yes)
		(layer "In13.Cu")
		(net "M_H_CPU1_SA_DQ<25>")
	)
	(gr_poly
		(pts
			(xy 142.894812 -240.232438) (xy 142.894812 -240.187988) (xy 142.69466 -240.187988) (xy 142.69466 -240.232438)
			(xy 142.794736 -240.332514)
		)
		(stroke
			(width 0)
			(type solid)
		)
		(fill yes)
		(layer "In13.Cu")
		(net "M_H_CPU1_SA_DQ<26>")
	)
	(gr_poly
		(pts
			(xy 142.894812 -239.016286) (xy 142.794736 -238.91621) (xy 142.69466 -239.016286) (xy 142.69466 -239.060736)
			(xy 142.894812 -239.060736)
		)
		(stroke
			(width 0)
			(type solid)
		)
		(fill yes)
		(layer "In13.Cu")
		(net "M_H_CPU1_SA_DQ<21>")
	)
	(gr_poly
		(pts
			(xy 142.894812 -238.612426) (xy 142.894812 -238.567976) (xy 142.69466 -238.567976) (xy 142.69466 -238.612426)
			(xy 142.794736 -238.712502)
		)
		(stroke
			(width 0)
			(type solid)
		)
		(fill yes)
		(layer "In13.Cu")
		(net "M_H_CPU1_SA_DQ<22>")
	)
	(gr_poly
		(pts
			(xy 142.894812 -237.39602) (xy 142.794736 -237.296198) (xy 142.69466 -237.39602) (xy 142.69466 -237.443772)
			(xy 142.894812 -237.443772)
		)
		(stroke
			(width 0)
			(type solid)
		)
		(fill yes)
		(layer "In13.Cu")
		(net "M_H_CPU1_SA_DQS_DN<7>")
	)
	(gr_poly
		(pts
			(xy 142.894812 -235.776262) (xy 142.794736 -235.676186) (xy 142.69466 -235.776262) (xy 142.69466 -235.820712)
			(xy 142.894812 -235.820712)
		)
		(stroke
			(width 0)
			(type solid)
		)
		(fill yes)
		(layer "In13.Cu")
		(net "M_H_CPU1_SA_DQ<17>")
	)
	(gr_poly
		(pts
			(xy 142.894812 -235.372402) (xy 142.894812 -235.327952) (xy 142.69466 -235.327952) (xy 142.69466 -235.372402)
			(xy 142.794736 -235.472478)
		)
		(stroke
			(width 0)
			(type solid)
		)
		(fill yes)
		(layer "In13.Cu")
		(net "M_H_CPU1_SA_DQ<18>")
	)
	(gr_poly
		(pts
			(xy 142.894812 -234.15625) (xy 142.794736 -234.056174) (xy 142.69466 -234.15625) (xy 142.69466 -234.2007)
			(xy 142.894812 -234.2007)
		)
		(stroke
			(width 0)
			(type solid)
		)
		(fill yes)
		(layer "In13.Cu")
		(net "M_H_CPU1_SA_DQ<13>")
	)
	(gr_poly
		(pts
			(xy 142.894812 -233.75239) (xy 142.894812 -233.70794) (xy 142.69466 -233.70794) (xy 142.69466 -233.75239)
			(xy 142.794736 -233.852466)
		)
		(stroke
			(width 0)
			(type solid)
		)
		(fill yes)
		(layer "In13.Cu")
		(net "M_H_CPU1_SA_DQ<14>")
	)
	(gr_poly
		(pts
			(xy 142.894812 -232.535984) (xy 142.794736 -232.436162) (xy 142.69466 -232.535984) (xy 142.69466 -232.583736)
			(xy 142.894812 -232.583736)
		)
		(stroke
			(width 0)
			(type solid)
		)
		(fill yes)
		(layer "In13.Cu")
		(net "M_H_CPU1_SA_DQS_DN<6>")
	)
	(gr_poly
		(pts
			(xy 142.894812 -232.132632) (xy 142.894812 -232.08488) (xy 142.69466 -232.08488) (xy 142.69466 -232.132632)
			(xy 142.794736 -232.232454)
		)
		(stroke
			(width 0)
			(type solid)
		)
		(fill yes)
		(layer "In13.Cu")
		(net "M_H_CPU1_SA_DQS_DN<1>")
	)
	(gr_poly
		(pts
			(xy 142.894812 -230.916226) (xy 142.794736 -230.81615) (xy 142.69466 -230.916226) (xy 142.69466 -230.960676)
			(xy 142.894812 -230.960676)
		)
		(stroke
			(width 0)
			(type solid)
		)
		(fill yes)
		(layer "In13.Cu")
		(net "M_H_CPU1_SA_DQ<9>")
	)
	(gr_poly
		(pts
			(xy 142.894812 -230.51262) (xy 142.894812 -230.46817) (xy 142.69466 -230.46817) (xy 142.69466 -230.51262)
			(xy 142.794736 -230.612696)
		)
		(stroke
			(width 0)
			(type solid)
		)
		(fill yes)
		(layer "In13.Cu")
		(net "M_H_CPU1_SA_DQ<10>")
	)
	(gr_poly
		(pts
			(xy 142.949422 -222.951802) (xy 142.912846 -222.81515) (xy 142.874492 -222.793052) (xy 142.774416 -222.96628)
			(xy 142.81277 -222.988378)
		)
		(stroke
			(width 0)
			(type solid)
		)
		(fill yes)
		(layer "In13.Cu")
		(net "M_H_CPU1_SA_DQ<3>")
	)
	(gr_poly
		(pts
			(xy 142.94993 -229.430326) (xy 142.913354 -229.293674) (xy 142.874746 -229.271576) (xy 142.77467 -229.444804)
			(xy 142.813278 -229.466902)
		)
		(stroke
			(width 0)
			(type solid)
		)
		(fill yes)
		(layer "In13.Cu")
		(net "M_H_CPU1_SA_DQ<7>")
	)
	(gr_poly
		(pts
			(xy 142.94993 -227.810314) (xy 142.913354 -227.673662) (xy 142.874746 -227.651564) (xy 142.77467 -227.824792)
			(xy 142.813278 -227.84689)
		)
		(stroke
			(width 0)
			(type solid)
		)
		(fill yes)
		(layer "In13.Cu")
		(net "M_H_CPU1_SA_DQ<6>")
	)
	(gr_poly
		(pts
			(xy 143.194786 -293.32428) (xy 143.194786 -293.27983) (xy 142.994634 -293.27983) (xy 142.994634 -293.32428)
			(xy 143.09471 -293.424356)
		)
		(stroke
			(width 0)
			(type solid)
		)
		(fill yes)
		(layer "In13.Cu")
		(net "M_H_CPU1_SB_DQ<31>")
	)
	(gr_poly
		(pts
			(xy 143.194786 -292.108128) (xy 143.09471 -292.008052) (xy 142.994634 -292.108128) (xy 142.994634 -292.152578)
			(xy 143.194786 -292.152578)
		)
		(stroke
			(width 0)
			(type solid)
		)
		(fill yes)
		(layer "In13.Cu")
		(net "M_H_CPU1_SB_DQ<28>")
	)
	(gr_poly
		(pts
			(xy 143.194786 -291.704522) (xy 143.194786 -291.65677) (xy 142.994634 -291.65677) (xy 142.994634 -291.704522)
			(xy 143.09471 -291.804344)
		)
		(stroke
			(width 0)
			(type solid)
		)
		(fill yes)
		(layer "In13.Cu")
		(net "M_H_CPU1_SB_DQS_DP<8>")
	)
	(gr_poly
		(pts
			(xy 143.194786 -290.487862) (xy 143.09471 -290.38804) (xy 142.994634 -290.487862) (xy 142.994634 -290.535614)
			(xy 143.194786 -290.535614)
		)
		(stroke
			(width 0)
			(type solid)
		)
		(fill yes)
		(layer "In13.Cu")
		(net "M_H_CPU1_SB_DQS_DP<3>")
	)
	(gr_poly
		(pts
			(xy 143.194786 -290.084256) (xy 143.194786 -290.039806) (xy 142.994634 -290.039806) (xy 142.994634 -290.084256)
			(xy 143.09471 -290.184332)
		)
		(stroke
			(width 0)
			(type solid)
		)
		(fill yes)
		(layer "In13.Cu")
		(net "M_H_CPU1_SB_DQ<27>")
	)
	(gr_poly
		(pts
			(xy 143.194786 -288.868104) (xy 143.09471 -288.768028) (xy 142.994634 -288.868104) (xy 142.994634 -288.912554)
			(xy 143.194786 -288.912554)
		)
		(stroke
			(width 0)
			(type solid)
		)
		(fill yes)
		(layer "In13.Cu")
		(net "M_H_CPU1_SB_DQ<24>")
	)
	(gr_poly
		(pts
			(xy 143.194786 -288.464498) (xy 143.194786 -288.420048) (xy 142.994634 -288.420048) (xy 142.994634 -288.464498)
			(xy 143.09471 -288.564574)
		)
		(stroke
			(width 0)
			(type solid)
		)
		(fill yes)
		(layer "In13.Cu")
		(net "M_H_CPU1_SB_DQ<23>")
	)
	(gr_poly
		(pts
			(xy 143.194786 -287.248092) (xy 143.09471 -287.148016) (xy 142.994634 -287.248092) (xy 142.994634 -287.292542)
			(xy 143.194786 -287.292542)
		)
		(stroke
			(width 0)
			(type solid)
		)
		(fill yes)
		(layer "In13.Cu")
		(net "M_H_CPU1_SB_DQ<20>")
	)
	(gr_poly
		(pts
			(xy 143.194786 -286.844486) (xy 143.194786 -286.796734) (xy 142.994634 -286.796734) (xy 142.994634 -286.844486)
			(xy 143.09471 -286.944562)
		)
		(stroke
			(width 0)
			(type solid)
		)
		(fill yes)
		(layer "In13.Cu")
		(net "M_H_CPU1_SB_DQS_DP<7>")
	)
	(gr_poly
		(pts
			(xy 143.194786 -285.62808) (xy 143.09471 -285.528258) (xy 142.994634 -285.62808) (xy 142.994634 -285.675832)
			(xy 143.194786 -285.675832)
		)
		(stroke
			(width 0)
			(type solid)
		)
		(fill yes)
		(layer "In13.Cu")
		(net "M_H_CPU1_SB_DQS_DP<2>")
	)
	(gr_poly
		(pts
			(xy 143.194786 -285.224474) (xy 143.194786 -285.180024) (xy 142.994634 -285.180024) (xy 142.994634 -285.224474)
			(xy 143.09471 -285.32455)
		)
		(stroke
			(width 0)
			(type solid)
		)
		(fill yes)
		(layer "In13.Cu")
		(net "M_H_CPU1_SB_DQ<19>")
	)
	(gr_poly
		(pts
			(xy 143.194786 -284.008322) (xy 143.09471 -283.908246) (xy 142.994634 -284.008322) (xy 142.994634 -284.052772)
			(xy 143.194786 -284.052772)
		)
		(stroke
			(width 0)
			(type solid)
		)
		(fill yes)
		(layer "In13.Cu")
		(net "M_H_CPU1_SB_DQ<16>")
	)
	(gr_poly
		(pts
			(xy 143.194786 -283.604462) (xy 143.194786 -283.560012) (xy 142.994634 -283.560012) (xy 142.994634 -283.604462)
			(xy 143.09471 -283.704538)
		)
		(stroke
			(width 0)
			(type solid)
		)
		(fill yes)
		(layer "In13.Cu")
		(net "M_H_CPU1_SB_DQ<15>")
	)
	(gr_poly
		(pts
			(xy 143.194786 -282.38831) (xy 143.09471 -282.288234) (xy 142.994634 -282.38831) (xy 142.994634 -282.43276)
			(xy 143.194786 -282.43276)
		)
		(stroke
			(width 0)
			(type solid)
		)
		(fill yes)
		(layer "In13.Cu")
		(net "M_H_CPU1_SB_DQ<12>")
	)
	(gr_poly
		(pts
			(xy 143.194786 -281.984704) (xy 143.194786 -281.936952) (xy 142.994634 -281.936952) (xy 142.994634 -281.984704)
			(xy 143.09471 -282.084526)
		)
		(stroke
			(width 0)
			(type solid)
		)
		(fill yes)
		(layer "In13.Cu")
		(net "M_H_CPU1_SB_DQS_DP<6>")
	)
	(gr_poly
		(pts
			(xy 143.194786 -280.768044) (xy 143.09471 -280.668222) (xy 142.994634 -280.768044) (xy 142.994634 -280.815796)
			(xy 143.194786 -280.815796)
		)
		(stroke
			(width 0)
			(type solid)
		)
		(fill yes)
		(layer "In13.Cu")
		(net "M_H_CPU1_SB_DQS_DP<1>")
	)
	(gr_poly
		(pts
			(xy 143.194786 -280.364438) (xy 143.194786 -280.319988) (xy 142.994634 -280.319988) (xy 142.994634 -280.364438)
			(xy 143.09471 -280.464514)
		)
		(stroke
			(width 0)
			(type solid)
		)
		(fill yes)
		(layer "In13.Cu")
		(net "M_H_CPU1_SB_DQ<11>")
	)
	(gr_poly
		(pts
			(xy 143.194786 -279.148286) (xy 143.09471 -279.04821) (xy 142.994634 -279.148286) (xy 142.994634 -279.192736)
			(xy 143.194786 -279.192736)
		)
		(stroke
			(width 0)
			(type solid)
		)
		(fill yes)
		(layer "In13.Cu")
		(net "M_H_CPU1_SB_DQ<8>")
	)
	(gr_poly
		(pts
			(xy 143.194786 -278.744426) (xy 143.194786 -278.699976) (xy 142.994634 -278.699976) (xy 142.994634 -278.744426)
			(xy 143.09471 -278.844502)
		)
		(stroke
			(width 0)
			(type solid)
		)
		(fill yes)
		(layer "In13.Cu")
		(net "M_H_CPU1_SB_DQ<7>")
	)
	(gr_poly
		(pts
			(xy 143.194786 -277.528274) (xy 143.09471 -277.428198) (xy 142.994634 -277.528274) (xy 142.994634 -277.572724)
			(xy 143.194786 -277.572724)
		)
		(stroke
			(width 0)
			(type solid)
		)
		(fill yes)
		(layer "In13.Cu")
		(net "M_H_CPU1_SB_DQ<4>")
	)
	(gr_poly
		(pts
			(xy 143.194786 -277.124668) (xy 143.194786 -277.076916) (xy 142.994634 -277.076916) (xy 142.994634 -277.124668)
			(xy 143.09471 -277.22449)
		)
		(stroke
			(width 0)
			(type solid)
		)
		(fill yes)
		(layer "In13.Cu")
		(net "M_H_CPU1_SB_DQS_DP<5>")
	)
	(gr_poly
		(pts
			(xy 143.194786 -275.908008) (xy 143.09471 -275.808186) (xy 142.994634 -275.908008) (xy 142.994634 -275.95576)
			(xy 143.194786 -275.95576)
		)
		(stroke
			(width 0)
			(type solid)
		)
		(fill yes)
		(layer "In13.Cu")
		(net "M_H_CPU1_SB_DQS_DP<0>")
	)
	(gr_poly
		(pts
			(xy 143.194786 -275.504402) (xy 143.194786 -275.459952) (xy 142.994634 -275.459952) (xy 142.994634 -275.504402)
			(xy 143.09471 -275.604478)
		)
		(stroke
			(width 0)
			(type solid)
		)
		(fill yes)
		(layer "In13.Cu")
		(net "M_H_CPU1_SB_DQ<3>")
	)
	(gr_poly
		(pts
			(xy 143.194786 -274.28825) (xy 143.09471 -274.188174) (xy 142.994634 -274.28825) (xy 142.994634 -274.3327)
			(xy 143.194786 -274.3327)
		)
		(stroke
			(width 0)
			(type solid)
		)
		(fill yes)
		(layer "In13.Cu")
		(net "M_H_CPU1_SB_DQ<0>")
	)
	(gr_poly
		(pts
			(xy 143.194786 -273.88439) (xy 143.194786 -273.83994) (xy 142.994634 -273.83994) (xy 142.994634 -273.88439)
			(xy 143.09471 -273.984466)
		)
		(stroke
			(width 0)
			(type solid)
		)
		(fill yes)
		(layer "In13.Cu")
		(net "M_H_CPU1_SB_CB<3>")
	)
	(gr_poly
		(pts
			(xy 143.194786 -272.668238) (xy 143.09471 -272.568162) (xy 142.994634 -272.668238) (xy 142.994634 -272.712688)
			(xy 143.194786 -272.712688)
		)
		(stroke
			(width 0)
			(type solid)
		)
		(fill yes)
		(layer "In13.Cu")
		(net "M_H_CPU1_SB_CB<0>")
	)
	(gr_poly
		(pts
			(xy 143.194786 -272.264632) (xy 143.194786 -272.21688) (xy 142.994634 -272.21688) (xy 142.994634 -272.264632)
			(xy 143.09471 -272.364454)
		)
		(stroke
			(width 0)
			(type solid)
		)
		(fill yes)
		(layer "In13.Cu")
		(net "M_H_CPU1_SB_DQS_DP<4>")
	)
	(gr_poly
		(pts
			(xy 143.194786 -271.047972) (xy 143.09471 -270.94815) (xy 142.994634 -271.047972) (xy 142.994634 -271.095724)
			(xy 143.194786 -271.095724)
		)
		(stroke
			(width 0)
			(type solid)
		)
		(fill yes)
		(layer "In13.Cu")
		(net "M_H_CPU1_SB_DQS_DP<9>")
	)
	(gr_poly
		(pts
			(xy 143.194786 -270.644366) (xy 143.194786 -270.599916) (xy 142.994634 -270.599916) (xy 142.994634 -270.644366)
			(xy 143.09471 -270.744442)
		)
		(stroke
			(width 0)
			(type solid)
		)
		(fill yes)
		(layer "In13.Cu")
		(net "M_H_CPU1_SB_CB<7>")
	)
	(gr_poly
		(pts
			(xy 143.194786 -269.428214) (xy 143.09471 -269.328138) (xy 142.994634 -269.428214) (xy 142.994634 -269.472664)
			(xy 143.194786 -269.472664)
		)
		(stroke
			(width 0)
			(type solid)
		)
		(fill yes)
		(layer "In13.Cu")
		(net "M_H_CPU1_SB_CB<4>")
	)
	(gr_poly
		(pts
			(xy 143.194786 -267.808202) (xy 143.09471 -267.708126) (xy 142.994634 -267.808202) (xy 142.994634 -267.852652)
			(xy 143.194786 -267.852652)
		)
		(stroke
			(width 0)
			(type solid)
		)
		(fill yes)
		(layer "In13.Cu")
		(net "M_H_CPU1_SB_RSP<0>")
	)
	(gr_poly
		(pts
			(xy 143.194786 -265.78433) (xy 143.194786 -265.73988) (xy 142.994634 -265.73988) (xy 142.994634 -265.78433)
			(xy 143.09471 -265.884406)
		)
		(stroke
			(width 0)
			(type solid)
		)
		(fill yes)
		(layer "In13.Cu")
		(net "M_H_CPU1_SB_CS_N<0>")
	)
	(gr_poly
		(pts
			(xy 143.194786 -264.568178) (xy 143.09471 -264.468102) (xy 142.994634 -264.568178) (xy 142.994634 -264.612628)
			(xy 143.194786 -264.612628)
		)
		(stroke
			(width 0)
			(type solid)
		)
		(fill yes)
		(layer "In13.Cu")
		(net "M_H_CPU1_SB_CA<6>")
	)
	(gr_poly
		(pts
			(xy 143.194786 -264.164318) (xy 143.194786 -264.119868) (xy 142.994634 -264.119868) (xy 142.994634 -264.164318)
			(xy 143.09471 -264.264394)
		)
		(stroke
			(width 0)
			(type solid)
		)
		(fill yes)
		(layer "In13.Cu")
		(net "M_H_CPU1_SB_CA<5>")
	)
	(gr_poly
		(pts
			(xy 143.194786 -262.948166) (xy 143.09471 -262.84809) (xy 142.994634 -262.948166) (xy 142.994634 -262.992616)
			(xy 143.194786 -262.992616)
		)
		(stroke
			(width 0)
			(type solid)
		)
		(fill yes)
		(layer "In13.Cu")
		(net "M_H_CPU1_SB_CA<2>")
	)
	(gr_poly
		(pts
			(xy 143.194786 -262.544306) (xy 143.194786 -262.499856) (xy 142.994634 -262.499856) (xy 142.994634 -262.544306)
			(xy 143.09471 -262.644382)
		)
		(stroke
			(width 0)
			(type solid)
		)
		(fill yes)
		(layer "In13.Cu")
		(net "M_H_CPU1_SB_CA<1>")
	)
	(gr_poly
		(pts
			(xy 143.28394 -229.555548) (xy 143.245332 -229.533196) (xy 143.108934 -229.569772) (xy 143.14551 -229.706424)
			(xy 143.183864 -229.728776)
		)
		(stroke
			(width 0)
			(type solid)
		)
		(fill yes)
		(layer "In13.Cu")
		(net "M_H_CPU1_SA_DQ<8>")
	)
	(gr_poly
		(pts
			(xy 143.28394 -227.93579) (xy 143.245332 -227.913438) (xy 143.108934 -227.950014) (xy 143.14551 -228.086666)
			(xy 143.183864 -228.109018)
		)
		(stroke
			(width 0)
			(type solid)
		)
		(fill yes)
		(layer "In13.Cu")
		(net "M_H_CPU1_SA_DQ<5>")
	)
	(gr_poly
		(pts
			(xy 143.28394 -226.315778) (xy 143.245332 -226.293426) (xy 143.108934 -226.330002) (xy 143.14551 -226.466654)
			(xy 143.183864 -226.489006)
		)
		(stroke
			(width 0)
			(type solid)
		)
		(fill yes)
		(layer "In13.Cu")
		(net "M_H_CPU1_SA_DQ<4>")
	)
	(gr_poly
		(pts
			(xy 143.286734 -224.696528) (xy 143.245586 -224.672652) (xy 143.108934 -224.709482) (xy 143.14551 -224.84588)
			(xy 143.186912 -224.869756)
		)
		(stroke
			(width 0)
			(type solid)
		)
		(fill yes)
		(layer "In13.Cu")
		(net "M_H_CPU1_SA_DQS_DN<5>")
	)
	(gr_poly
		(pts
			(xy 143.286734 -223.076516) (xy 143.245586 -223.05264) (xy 143.108934 -223.08947) (xy 143.14551 -223.225868)
			(xy 143.186912 -223.249744)
		)
		(stroke
			(width 0)
			(type solid)
		)
		(fill yes)
		(layer "In13.Cu")
		(net "M_H_CPU1_SA_DQS_DP<0>")
	)
	(gr_poly
		(pts
			(xy 143.340836 -236.586522) (xy 143.24076 -236.486446) (xy 143.140938 -236.586522) (xy 143.140938 -236.63402)
			(xy 143.340836 -236.63402)
		)
		(stroke
			(width 0)
			(type solid)
		)
		(fill yes)
		(layer "In13.Cu")
		(net "M_H_CPU1_SA_DQS_DP<2>")
	)
	(gr_poly
		(pts
			(xy 143.364712 -256.026158) (xy 143.264636 -255.926336) (xy 143.16456 -256.026158) (xy 143.16456 -256.07391)
			(xy 143.364712 -256.07391)
		)
		(stroke
			(width 0)
			(type solid)
		)
		(fill yes)
		(layer "In13.Cu")
		(net "M_H_CPU1_CLK_DP<0>")
	)
	(gr_poly
		(pts
			(xy 143.364712 -255.622552) (xy 143.364712 -255.578102) (xy 143.16456 -255.578102) (xy 143.16456 -255.622552)
			(xy 143.264636 -255.722628)
		)
		(stroke
			(width 0)
			(type solid)
		)
		(fill yes)
		(layer "In13.Cu")
		(net "M_H_CPU1_SA_PAR")
	)
	(gr_poly
		(pts
			(xy 143.364712 -254.4064) (xy 143.264636 -254.306324) (xy 143.16456 -254.4064) (xy 143.16456 -254.45085)
			(xy 143.364712 -254.45085)
		)
		(stroke
			(width 0)
			(type solid)
		)
		(fill yes)
		(layer "In13.Cu")
		(net "M_H_CPU1_SA_CA<4>")
	)
	(gr_poly
		(pts
			(xy 143.364712 -254.00254) (xy 143.364712 -253.95809) (xy 143.16456 -253.95809) (xy 143.16456 -254.00254)
			(xy 143.264636 -254.102616)
		)
		(stroke
			(width 0)
			(type solid)
		)
		(fill yes)
		(layer "In13.Cu")
		(net "M_H_CPU1_SA_CA<3>")
	)
	(gr_poly
		(pts
			(xy 143.364712 -252.786388) (xy 143.264636 -252.686312) (xy 143.16456 -252.786388) (xy 143.16456 -252.830838)
			(xy 143.364712 -252.830838)
		)
		(stroke
			(width 0)
			(type solid)
		)
		(fill yes)
		(layer "In13.Cu")
		(net "M_H_CPU1_SA_CA<0>")
	)
	(gr_poly
		(pts
			(xy 143.364712 -251.166376) (xy 143.264636 -251.0663) (xy 143.16456 -251.166376) (xy 143.16456 -251.210826)
			(xy 143.364712 -251.210826)
		)
		(stroke
			(width 0)
			(type solid)
		)
		(fill yes)
		(layer "In13.Cu")
		(net "M_H_CPU1_SA_CS_N<0>")
	)
	(gr_poly
		(pts
			(xy 143.364712 -250.762516) (xy 143.364712 -250.718066) (xy 143.16456 -250.718066) (xy 143.16456 -250.762516)
			(xy 143.264636 -250.862592)
		)
		(stroke
			(width 0)
			(type solid)
		)
		(fill yes)
		(layer "In13.Cu")
		(net "M_H_CPU1_RESET_N")
	)
	(gr_poly
		(pts
			(xy 143.364712 -249.142504) (xy 143.364712 -249.098054) (xy 143.16456 -249.098054) (xy 143.16456 -249.142504)
			(xy 143.264636 -249.24258)
		)
		(stroke
			(width 0)
			(type solid)
		)
		(fill yes)
		(layer "In13.Cu")
		(net "M_H_CPU1_SA_CB<7>")
	)
	(gr_poly
		(pts
			(xy 143.364712 -247.926352) (xy 143.264636 -247.826276) (xy 143.16456 -247.926352) (xy 143.16456 -247.970802)
			(xy 143.364712 -247.970802)
		)
		(stroke
			(width 0)
			(type solid)
		)
		(fill yes)
		(layer "In13.Cu")
		(net "M_H_CPU1_SA_CB<4>")
	)
	(gr_poly
		(pts
			(xy 143.364712 -247.522746) (xy 143.364712 -247.474994) (xy 143.16456 -247.474994) (xy 143.16456 -247.522746)
			(xy 143.264636 -247.622568)
		)
		(stroke
			(width 0)
			(type solid)
		)
		(fill yes)
		(layer "In13.Cu")
		(net "M_H_CPU1_SA_DQS_DP<9>")
	)
	(gr_poly
		(pts
			(xy 143.364712 -246.306086) (xy 143.264636 -246.206264) (xy 143.16456 -246.306086) (xy 143.16456 -246.353838)
			(xy 143.364712 -246.353838)
		)
		(stroke
			(width 0)
			(type solid)
		)
		(fill yes)
		(layer "In13.Cu")
		(net "M_H_CPU1_SA_DQS_DP<4>")
	)
	(gr_poly
		(pts
			(xy 143.364712 -245.90248) (xy 143.364712 -245.85803) (xy 143.16456 -245.85803) (xy 143.16456 -245.90248)
			(xy 143.264636 -246.002556)
		)
		(stroke
			(width 0)
			(type solid)
		)
		(fill yes)
		(layer "In13.Cu")
		(net "M_H_CPU1_SA_CB<3>")
	)
	(gr_poly
		(pts
			(xy 143.364712 -244.686328) (xy 143.264636 -244.586252) (xy 143.16456 -244.686328) (xy 143.16456 -244.730778)
			(xy 143.364712 -244.730778)
		)
		(stroke
			(width 0)
			(type solid)
		)
		(fill yes)
		(layer "In13.Cu")
		(net "M_H_CPU1_SA_CB<0>")
	)
	(gr_poly
		(pts
			(xy 143.364712 -244.282468) (xy 143.364712 -244.238018) (xy 143.16456 -244.238018) (xy 143.16456 -244.282468)
			(xy 143.264636 -244.382544)
		)
		(stroke
			(width 0)
			(type solid)
		)
		(fill yes)
		(layer "In13.Cu")
		(net "M_H_CPU1_SA_DQ<31>")
	)
	(gr_poly
		(pts
			(xy 143.364712 -243.066316) (xy 143.264636 -242.96624) (xy 143.16456 -243.066316) (xy 143.16456 -243.110766)
			(xy 143.364712 -243.110766)
		)
		(stroke
			(width 0)
			(type solid)
		)
		(fill yes)
		(layer "In13.Cu")
		(net "M_H_CPU1_SA_DQ<28>")
	)
	(gr_poly
		(pts
			(xy 143.364712 -242.66271) (xy 143.364712 -242.614958) (xy 143.16456 -242.614958) (xy 143.16456 -242.66271)
			(xy 143.264636 -242.762532)
		)
		(stroke
			(width 0)
			(type solid)
		)
		(fill yes)
		(layer "In13.Cu")
		(net "M_H_CPU1_SA_DQS_DP<8>")
	)
	(gr_poly
		(pts
			(xy 143.364712 -241.44605) (xy 143.264636 -241.346228) (xy 143.16456 -241.44605) (xy 143.16456 -241.493802)
			(xy 143.364712 -241.493802)
		)
		(stroke
			(width 0)
			(type solid)
		)
		(fill yes)
		(layer "In13.Cu")
		(net "M_H_CPU1_SA_DQS_DP<3>")
	)
	(gr_poly
		(pts
			(xy 143.364712 -241.042444) (xy 143.364712 -240.997994) (xy 143.16456 -240.997994) (xy 143.16456 -241.042444)
			(xy 143.264636 -241.14252)
		)
		(stroke
			(width 0)
			(type solid)
		)
		(fill yes)
		(layer "In13.Cu")
		(net "M_H_CPU1_SA_DQ<27>")
	)
	(gr_poly
		(pts
			(xy 143.364712 -239.826292) (xy 143.264636 -239.726216) (xy 143.16456 -239.826292) (xy 143.16456 -239.870742)
			(xy 143.364712 -239.870742)
		)
		(stroke
			(width 0)
			(type solid)
		)
		(fill yes)
		(layer "In13.Cu")
		(net "M_H_CPU1_SA_DQ<24>")
	)
	(gr_poly
		(pts
			(xy 143.364712 -239.422432) (xy 143.364712 -239.377982) (xy 143.16456 -239.377982) (xy 143.16456 -239.422432)
			(xy 143.264636 -239.522508)
		)
		(stroke
			(width 0)
			(type solid)
		)
		(fill yes)
		(layer "In13.Cu")
		(net "M_H_CPU1_SA_DQ<23>")
	)
	(gr_poly
		(pts
			(xy 143.364712 -238.20628) (xy 143.264636 -238.106204) (xy 143.16456 -238.20628) (xy 143.16456 -238.25073)
			(xy 143.364712 -238.25073)
		)
		(stroke
			(width 0)
			(type solid)
		)
		(fill yes)
		(layer "In13.Cu")
		(net "M_H_CPU1_SA_DQ<20>")
	)
	(gr_poly
		(pts
			(xy 143.364712 -237.802674) (xy 143.364712 -237.754922) (xy 143.16456 -237.754922) (xy 143.16456 -237.802674)
			(xy 143.264636 -237.902496)
		)
		(stroke
			(width 0)
			(type solid)
		)
		(fill yes)
		(layer "In13.Cu")
		(net "M_H_CPU1_SA_DQS_DP<7>")
	)
	(gr_poly
		(pts
			(xy 143.364712 -236.182408) (xy 143.364712 -236.137958) (xy 143.16456 -236.137958) (xy 143.16456 -236.182408)
			(xy 143.264636 -236.282484)
		)
		(stroke
			(width 0)
			(type solid)
		)
		(fill yes)
		(layer "In13.Cu")
		(net "M_H_CPU1_SA_DQ<19>")
	)
	(gr_poly
		(pts
			(xy 143.364712 -234.966256) (xy 143.264636 -234.86618) (xy 143.16456 -234.966256) (xy 143.16456 -235.010706)
			(xy 143.364712 -235.010706)
		)
		(stroke
			(width 0)
			(type solid)
		)
		(fill yes)
		(layer "In13.Cu")
		(net "M_H_CPU1_SA_DQ<16>")
	)
	(gr_poly
		(pts
			(xy 143.364712 -234.562396) (xy 143.364712 -234.517946) (xy 143.16456 -234.517946) (xy 143.16456 -234.562396)
			(xy 143.264636 -234.662472)
		)
		(stroke
			(width 0)
			(type solid)
		)
		(fill yes)
		(layer "In13.Cu")
		(net "M_H_CPU1_SA_DQ<15>")
	)
	(gr_poly
		(pts
			(xy 143.364712 -233.346244) (xy 143.264636 -233.246168) (xy 143.16456 -233.346244) (xy 143.16456 -233.390694)
			(xy 143.364712 -233.390694)
		)
		(stroke
			(width 0)
			(type solid)
		)
		(fill yes)
		(layer "In13.Cu")
		(net "M_H_CPU1_SA_DQ<12>")
	)
	(gr_poly
		(pts
			(xy 143.364712 -232.942638) (xy 143.364712 -232.894886) (xy 143.16456 -232.894886) (xy 143.16456 -232.942638)
			(xy 143.264636 -233.04246)
		)
		(stroke
			(width 0)
			(type solid)
		)
		(fill yes)
		(layer "In13.Cu")
		(net "M_H_CPU1_SA_DQS_DP<6>")
	)
	(gr_poly
		(pts
			(xy 143.364712 -231.725978) (xy 143.264636 -231.626156) (xy 143.16456 -231.725978) (xy 143.16456 -231.77373)
			(xy 143.364712 -231.77373)
		)
		(stroke
			(width 0)
			(type solid)
		)
		(fill yes)
		(layer "In13.Cu")
		(net "M_H_CPU1_SA_DQS_DP<1>")
	)
	(gr_poly
		(pts
			(xy 143.364712 -231.322626) (xy 143.364712 -231.278176) (xy 143.16456 -231.278176) (xy 143.16456 -231.322626)
			(xy 143.264636 -231.422702)
		)
		(stroke
			(width 0)
			(type solid)
		)
		(fill yes)
		(layer "In13.Cu")
		(net "M_H_CPU1_SA_DQ<11>")
	)
	(gr_poly
		(pts
			(xy 143.420084 -230.240078) (xy 143.383508 -230.103426) (xy 143.3449 -230.081328) (xy 143.244824 -230.254556)
			(xy 143.283432 -230.276654)
		)
		(stroke
			(width 0)
			(type solid)
		)
		(fill yes)
		(layer "In13.Cu")
		(net "M_H_CPU1_SA_DQ<10>")
	)
	(gr_poly
		(pts
			(xy 143.420592 -225.379534) (xy 143.384016 -225.243136) (xy 143.342614 -225.21926) (xy 143.242792 -225.392488)
			(xy 143.28394 -225.416364)
		)
		(stroke
			(width 0)
			(type solid)
		)
		(fill yes)
		(layer "In13.Cu")
		(net "M_H_CPU1_SA_DQS_DP<5>")
	)
	(gr_poly
		(pts
			(xy 143.420592 -223.759522) (xy 143.384016 -223.623124) (xy 143.342614 -223.599248) (xy 143.242792 -223.772476)
			(xy 143.28394 -223.796352)
		)
		(stroke
			(width 0)
			(type solid)
		)
		(fill yes)
		(layer "In13.Cu")
		(net "M_H_CPU1_SA_DQS_DN<0>")
	)
	(gr_poly
		(pts
			(xy 143.420846 -228.61905) (xy 143.384016 -228.482398) (xy 143.345662 -228.460046) (xy 143.245586 -228.633274)
			(xy 143.284194 -228.655626)
		)
		(stroke
			(width 0)
			(type solid)
		)
		(fill yes)
		(layer "In13.Cu")
		(net "M_H_CPU1_SA_DQ<7>")
	)
	(gr_poly
		(pts
			(xy 143.420846 -226.999038) (xy 143.384016 -226.862386) (xy 143.345662 -226.840034) (xy 143.245586 -227.013262)
			(xy 143.284194 -227.035614)
		)
		(stroke
			(width 0)
			(type solid)
		)
		(fill yes)
		(layer "In13.Cu")
		(net "M_H_CPU1_SA_DQ<6>")
	)
	(gr_poly
		(pts
			(xy 143.422116 -222.138494) (xy 143.385286 -222.001842) (xy 143.346932 -221.979744) (xy 143.246856 -222.152972)
			(xy 143.285464 -222.17507)
		)
		(stroke
			(width 0)
			(type solid)
		)
		(fill yes)
		(layer "In13.Cu")
		(net "M_H_CPU1_SA_DQ<3>")
	)
	(gr_poly
		(pts
			(xy 143.664686 -292.918134) (xy 143.56461 -292.818058) (xy 143.464534 -292.918134) (xy 143.464534 -292.962584)
			(xy 143.664686 -292.962584)
		)
		(stroke
			(width 0)
			(type solid)
		)
		(fill yes)
		(layer "In13.Cu")
		(net "M_H_CPU1_SB_DQ<29>")
	)
	(gr_poly
		(pts
			(xy 143.664686 -292.514274) (xy 143.664686 -292.469824) (xy 143.464534 -292.469824) (xy 143.464534 -292.514274)
			(xy 143.56461 -292.61435)
		)
		(stroke
			(width 0)
			(type solid)
		)
		(fill yes)
		(layer "In13.Cu")
		(net "M_H_CPU1_SB_DQ<30>")
	)
	(gr_poly
		(pts
			(xy 143.664686 -291.297868) (xy 143.56461 -291.198046) (xy 143.464534 -291.297868) (xy 143.464534 -291.34562)
			(xy 143.664686 -291.34562)
		)
		(stroke
			(width 0)
			(type solid)
		)
		(fill yes)
		(layer "In13.Cu")
		(net "M_H_CPU1_SB_DQS_DN<8>")
	)
	(gr_poly
		(pts
			(xy 143.664686 -290.894516) (xy 143.664686 -290.846764) (xy 143.464534 -290.846764) (xy 143.464534 -290.894516)
			(xy 143.56461 -290.994338)
		)
		(stroke
			(width 0)
			(type solid)
		)
		(fill yes)
		(layer "In13.Cu")
		(net "M_H_CPU1_SB_DQS_DN<3>")
	)
	(gr_poly
		(pts
			(xy 143.664686 -289.67811) (xy 143.56461 -289.578034) (xy 143.464534 -289.67811) (xy 143.464534 -289.72256)
			(xy 143.664686 -289.72256)
		)
		(stroke
			(width 0)
			(type solid)
		)
		(fill yes)
		(layer "In13.Cu")
		(net "M_H_CPU1_SB_DQ<25>")
	)
	(gr_poly
		(pts
			(xy 143.664686 -289.27425) (xy 143.664686 -289.2298) (xy 143.464534 -289.2298) (xy 143.464534 -289.27425)
			(xy 143.56461 -289.374326)
		)
		(stroke
			(width 0)
			(type solid)
		)
		(fill yes)
		(layer "In13.Cu")
		(net "M_H_CPU1_SB_DQ<26>")
	)
	(gr_poly
		(pts
			(xy 143.664686 -288.058098) (xy 143.56461 -287.958022) (xy 143.464534 -288.058098) (xy 143.464534 -288.102548)
			(xy 143.664686 -288.102548)
		)
		(stroke
			(width 0)
			(type solid)
		)
		(fill yes)
		(layer "In13.Cu")
		(net "M_H_CPU1_SB_DQ<21>")
	)
	(gr_poly
		(pts
			(xy 143.664686 -287.654492) (xy 143.664686 -287.610042) (xy 143.464534 -287.610042) (xy 143.464534 -287.654492)
			(xy 143.56461 -287.754568)
		)
		(stroke
			(width 0)
			(type solid)
		)
		(fill yes)
		(layer "In13.Cu")
		(net "M_H_CPU1_SB_DQ<22>")
	)
	(gr_poly
		(pts
			(xy 143.664686 -286.438086) (xy 143.56461 -286.33801) (xy 143.464534 -286.438086) (xy 143.464534 -286.485838)
			(xy 143.664686 -286.485838)
		)
		(stroke
			(width 0)
			(type solid)
		)
		(fill yes)
		(layer "In13.Cu")
		(net "M_H_CPU1_SB_DQS_DN<7>")
	)
	(gr_poly
		(pts
			(xy 143.664686 -286.034734) (xy 143.664686 -285.986982) (xy 143.464534 -285.986982) (xy 143.464534 -286.034734)
			(xy 143.56461 -286.134556)
		)
		(stroke
			(width 0)
			(type solid)
		)
		(fill yes)
		(layer "In13.Cu")
		(net "M_H_CPU1_SB_DQS_DN<2>")
	)
	(gr_poly
		(pts
			(xy 143.664686 -284.818328) (xy 143.56461 -284.718252) (xy 143.464534 -284.818328) (xy 143.464534 -284.862778)
			(xy 143.664686 -284.862778)
		)
		(stroke
			(width 0)
			(type solid)
		)
		(fill yes)
		(layer "In13.Cu")
		(net "M_H_CPU1_SB_DQ<17>")
	)
	(gr_poly
		(pts
			(xy 143.664686 -284.414468) (xy 143.664686 -284.370018) (xy 143.464534 -284.370018) (xy 143.464534 -284.414468)
			(xy 143.56461 -284.514544)
		)
		(stroke
			(width 0)
			(type solid)
		)
		(fill yes)
		(layer "In13.Cu")
		(net "M_H_CPU1_SB_DQ<18>")
	)
	(gr_poly
		(pts
			(xy 143.664686 -283.198316) (xy 143.56461 -283.09824) (xy 143.464534 -283.198316) (xy 143.464534 -283.242766)
			(xy 143.664686 -283.242766)
		)
		(stroke
			(width 0)
			(type solid)
		)
		(fill yes)
		(layer "In13.Cu")
		(net "M_H_CPU1_SB_DQ<13>")
	)
	(gr_poly
		(pts
			(xy 143.664686 -282.794456) (xy 143.664686 -282.750006) (xy 143.464534 -282.750006) (xy 143.464534 -282.794456)
			(xy 143.56461 -282.894532)
		)
		(stroke
			(width 0)
			(type solid)
		)
		(fill yes)
		(layer "In13.Cu")
		(net "M_H_CPU1_SB_DQ<14>")
	)
	(gr_poly
		(pts
			(xy 143.664686 -281.57805) (xy 143.56461 -281.478228) (xy 143.464534 -281.57805) (xy 143.464534 -281.625802)
			(xy 143.664686 -281.625802)
		)
		(stroke
			(width 0)
			(type solid)
		)
		(fill yes)
		(layer "In13.Cu")
		(net "M_H_CPU1_SB_DQS_DN<6>")
	)
	(gr_poly
		(pts
			(xy 143.664686 -281.174698) (xy 143.664686 -281.126946) (xy 143.464534 -281.126946) (xy 143.464534 -281.174698)
			(xy 143.56461 -281.27452)
		)
		(stroke
			(width 0)
			(type solid)
		)
		(fill yes)
		(layer "In13.Cu")
		(net "M_H_CPU1_SB_DQS_DN<1>")
	)
	(gr_poly
		(pts
			(xy 143.664686 -279.958292) (xy 143.56461 -279.858216) (xy 143.464534 -279.958292) (xy 143.464534 -280.002742)
			(xy 143.664686 -280.002742)
		)
		(stroke
			(width 0)
			(type solid)
		)
		(fill yes)
		(layer "In13.Cu")
		(net "M_H_CPU1_SB_DQ<9>")
	)
	(gr_poly
		(pts
			(xy 143.664686 -279.554432) (xy 143.664686 -279.509982) (xy 143.464534 -279.509982) (xy 143.464534 -279.554432)
			(xy 143.56461 -279.654508)
		)
		(stroke
			(width 0)
			(type solid)
		)
		(fill yes)
		(layer "In13.Cu")
		(net "M_H_CPU1_SB_DQ<10>")
	)
	(gr_poly
		(pts
			(xy 143.664686 -278.33828) (xy 143.56461 -278.238204) (xy 143.464534 -278.33828) (xy 143.464534 -278.38273)
			(xy 143.664686 -278.38273)
		)
		(stroke
			(width 0)
			(type solid)
		)
		(fill yes)
		(layer "In13.Cu")
		(net "M_H_CPU1_SB_DQ<5>")
	)
	(gr_poly
		(pts
			(xy 143.664686 -277.93442) (xy 143.664686 -277.88997) (xy 143.464534 -277.88997) (xy 143.464534 -277.93442)
			(xy 143.56461 -278.034496)
		)
		(stroke
			(width 0)
			(type solid)
		)
		(fill yes)
		(layer "In13.Cu")
		(net "M_H_CPU1_SB_DQ<6>")
	)
	(gr_poly
		(pts
			(xy 143.664686 -276.718014) (xy 143.56461 -276.618192) (xy 143.464534 -276.718014) (xy 143.464534 -276.765766)
			(xy 143.664686 -276.765766)
		)
		(stroke
			(width 0)
			(type solid)
		)
		(fill yes)
		(layer "In13.Cu")
		(net "M_H_CPU1_SB_DQS_DN<5>")
	)
	(gr_poly
		(pts
			(xy 143.664686 -276.314662) (xy 143.664686 -276.26691) (xy 143.464534 -276.26691) (xy 143.464534 -276.314662)
			(xy 143.56461 -276.414484)
		)
		(stroke
			(width 0)
			(type solid)
		)
		(fill yes)
		(layer "In13.Cu")
		(net "M_H_CPU1_SB_DQS_DN<0>")
	)
	(gr_poly
		(pts
			(xy 143.664686 -275.098256) (xy 143.56461 -274.99818) (xy 143.464534 -275.098256) (xy 143.464534 -275.142706)
			(xy 143.664686 -275.142706)
		)
		(stroke
			(width 0)
			(type solid)
		)
		(fill yes)
		(layer "In13.Cu")
		(net "M_H_CPU1_SB_DQ<1>")
	)
	(gr_poly
		(pts
			(xy 143.664686 -274.694396) (xy 143.664686 -274.649946) (xy 143.464534 -274.649946) (xy 143.464534 -274.694396)
			(xy 143.56461 -274.794472)
		)
		(stroke
			(width 0)
			(type solid)
		)
		(fill yes)
		(layer "In13.Cu")
		(net "M_H_CPU1_SB_DQ<2>")
	)
	(gr_poly
		(pts
			(xy 143.664686 -273.478244) (xy 143.56461 -273.378168) (xy 143.464534 -273.478244) (xy 143.464534 -273.522694)
			(xy 143.664686 -273.522694)
		)
		(stroke
			(width 0)
			(type solid)
		)
		(fill yes)
		(layer "In13.Cu")
		(net "M_H_CPU1_SB_CB<1>")
	)
	(gr_poly
		(pts
			(xy 143.664686 -273.074384) (xy 143.664686 -273.029934) (xy 143.464534 -273.029934) (xy 143.464534 -273.074384)
			(xy 143.56461 -273.17446)
		)
		(stroke
			(width 0)
			(type solid)
		)
		(fill yes)
		(layer "In13.Cu")
		(net "M_H_CPU1_SB_CB<2>")
	)
	(gr_poly
		(pts
			(xy 143.664686 -271.857978) (xy 143.56461 -271.758156) (xy 143.464534 -271.857978) (xy 143.464534 -271.90573)
			(xy 143.664686 -271.90573)
		)
		(stroke
			(width 0)
			(type solid)
		)
		(fill yes)
		(layer "In13.Cu")
		(net "M_H_CPU1_SB_DQS_DN<4>")
	)
	(gr_poly
		(pts
			(xy 143.664686 -271.454626) (xy 143.664686 -271.406874) (xy 143.464534 -271.406874) (xy 143.464534 -271.454626)
			(xy 143.56461 -271.554448)
		)
		(stroke
			(width 0)
			(type solid)
		)
		(fill yes)
		(layer "In13.Cu")
		(net "M_H_CPU1_SB_DQS_DN<9>")
	)
	(gr_poly
		(pts
			(xy 143.664686 -270.23822) (xy 143.56461 -270.138144) (xy 143.464534 -270.23822) (xy 143.464534 -270.28267)
			(xy 143.664686 -270.28267)
		)
		(stroke
			(width 0)
			(type solid)
		)
		(fill yes)
		(layer "In13.Cu")
		(net "M_H_CPU1_SB_CB<5>")
	)
	(gr_poly
		(pts
			(xy 143.664686 -269.83436) (xy 143.664686 -269.78991) (xy 143.464534 -269.78991) (xy 143.464534 -269.83436)
			(xy 143.56461 -269.934436)
		)
		(stroke
			(width 0)
			(type solid)
		)
		(fill yes)
		(layer "In13.Cu")
		(net "M_H_CPU1_SB_CB<6>")
	)
	(gr_poly
		(pts
			(xy 143.664686 -266.998196) (xy 143.56461 -266.89812) (xy 143.464534 -266.998196) (xy 143.464534 -267.042646)
			(xy 143.664686 -267.042646)
		)
		(stroke
			(width 0)
			(type solid)
		)
		(fill yes)
		(layer "In13.Cu")
		(net "M_H_CPU1_SA_RSP<0>")
	)
	(gr_poly
		(pts
			(xy 143.664686 -266.594336) (xy 143.664686 -266.549886) (xy 143.464534 -266.549886) (xy 143.464534 -266.594336)
			(xy 143.56461 -266.694412)
		)
		(stroke
			(width 0)
			(type solid)
		)
		(fill yes)
		(layer "In13.Cu")
		(net "M_H_CPU1_SB_CS_N<1>")
	)
	(gr_poly
		(pts
			(xy 143.664686 -265.378184) (xy 143.56461 -265.278108) (xy 143.464534 -265.378184) (xy 143.464534 -265.422634)
			(xy 143.664686 -265.422634)
		)
		(stroke
			(width 0)
			(type solid)
		)
		(fill yes)
		(layer "In13.Cu")
		(net "M_H_CPU1_SB_PAR")
	)
	(gr_poly
		(pts
			(xy 143.664686 -263.758172) (xy 143.56461 -263.658096) (xy 143.464534 -263.758172) (xy 143.464534 -263.802622)
			(xy 143.664686 -263.802622)
		)
		(stroke
			(width 0)
			(type solid)
		)
		(fill yes)
		(layer "In13.Cu")
		(net "M_H_CPU1_SB_CA<4>")
	)
	(gr_poly
		(pts
			(xy 143.664686 -263.354312) (xy 143.664686 -263.309862) (xy 143.464534 -263.309862) (xy 143.464534 -263.354312)
			(xy 143.56461 -263.454388)
		)
		(stroke
			(width 0)
			(type solid)
		)
		(fill yes)
		(layer "In13.Cu")
		(net "M_H_CPU1_SB_CA<3>")
	)
	(gr_poly
		(pts
			(xy 143.664686 -262.13816) (xy 143.56461 -262.038084) (xy 143.464534 -262.13816) (xy 143.464534 -262.18261)
			(xy 143.664686 -262.18261)
		)
		(stroke
			(width 0)
			(type solid)
		)
		(fill yes)
		(layer "In13.Cu")
		(net "M_H_CPU1_SB_CA<0>")
	)
	(gr_poly
		(pts
			(xy 143.75384 -225.505772) (xy 143.715232 -225.48342) (xy 143.578834 -225.519996) (xy 143.61541 -225.656648)
			(xy 143.653764 -225.679)
		)
		(stroke
			(width 0)
			(type solid)
		)
		(fill yes)
		(layer "In13.Cu")
		(net "M_H_CPU1_SA_DQ<4>")
	)
	(gr_poly
		(pts
			(xy 143.754856 -230.364284) (xy 143.716248 -230.342186) (xy 143.579596 -230.378762) (xy 143.616172 -230.515414)
			(xy 143.65478 -230.537512)
		)
		(stroke
			(width 0)
			(type solid)
		)
		(fill yes)
		(layer "In13.Cu")
		(net "M_H_CPU1_SA_DQ<9>")
	)
	(gr_poly
		(pts
			(xy 143.756634 -223.886522) (xy 143.715486 -223.8629) (xy 143.578834 -223.899476) (xy 143.61541 -224.035874)
			(xy 143.656812 -224.05975)
		)
		(stroke
			(width 0)
			(type solid)
		)
		(fill yes)
		(layer "In13.Cu")
		(net "M_H_CPU1_SA_DQS_DN<5>")
	)
	(gr_poly
		(pts
			(xy 143.757142 -222.266002) (xy 143.71574 -222.242126) (xy 143.579342 -222.278702) (xy 143.615918 -222.415354)
			(xy 143.657066 -222.43923)
		)
		(stroke
			(width 0)
			(type solid)
		)
		(fill yes)
		(layer "In13.Cu")
		(net "M_H_CPU1_SA_DQS_DP<0>")
	)
	(gr_poly
		(pts
			(xy 143.801084 -235.381292) (xy 143.804894 -235.337096) (xy 143.605758 -235.31957) (xy 143.601948 -235.36402)
			(xy 143.69288 -235.472224)
		)
		(stroke
			(width 0)
			(type solid)
		)
		(fill yes)
		(layer "In13.Cu")
		(net "M_H_CPU1_SA_DQ<18>")
	)
	(gr_poly
		(pts
			(xy 143.82877 -237.39602) (xy 143.728694 -237.296198) (xy 143.628618 -237.39602) (xy 143.628618 -237.443772)
			(xy 143.82877 -237.443772)
		)
		(stroke
			(width 0)
			(type solid)
		)
		(fill yes)
		(layer "In13.Cu")
		(net "M_H_CPU1_SA_DQS_DN<7>")
	)
	(gr_poly
		(pts
			(xy 143.82877 -232.132632) (xy 143.82877 -232.08488) (xy 143.628618 -232.08488) (xy 143.628618 -232.132632)
			(xy 143.728694 -232.232454)
		)
		(stroke
			(width 0)
			(type solid)
		)
		(fill yes)
		(layer "In13.Cu")
		(net "M_H_CPU1_SA_DQS_DN<1>")
	)
	(gr_poly
		(pts
			(xy 143.834866 -256.432812) (xy 143.834866 -256.38506) (xy 143.634714 -256.38506) (xy 143.634714 -256.432812)
			(xy 143.73479 -256.532634)
		)
		(stroke
			(width 0)
			(type solid)
		)
		(fill yes)
		(layer "In13.Cu")
		(net "M_H_CPU1_CLK_DN<0>")
	)
	(gr_poly
		(pts
			(xy 143.840962 -254.812546) (xy 143.840962 -254.768096) (xy 143.64081 -254.768096) (xy 143.64081 -254.812546)
			(xy 143.740886 -254.912622)
		)
		(stroke
			(width 0)
			(type solid)
		)
		(fill yes)
		(layer "In13.Cu")
		(net "M_H_CPU1_SA_CA<5>")
	)
	(gr_poly
		(pts
			(xy 143.840962 -253.192534) (xy 143.840962 -253.148084) (xy 143.64081 -253.148084) (xy 143.64081 -253.192534)
			(xy 143.740886 -253.29261)
		)
		(stroke
			(width 0)
			(type solid)
		)
		(fill yes)
		(layer "In13.Cu")
		(net "M_H_CPU1_SA_CA<1>")
	)
	(gr_poly
		(pts
			(xy 143.840962 -248.332498) (xy 143.840962 -248.288048) (xy 143.64081 -248.288048) (xy 143.64081 -248.332498)
			(xy 143.740886 -248.432574)
		)
		(stroke
			(width 0)
			(type solid)
		)
		(fill yes)
		(layer "In13.Cu")
		(net "M_H_CPU1_SA_CB<6>")
	)
	(gr_poly
		(pts
			(xy 143.840962 -246.71274) (xy 143.840962 -246.665242) (xy 143.64081 -246.665242) (xy 143.64081 -246.71274)
			(xy 143.740886 -246.812816)
		)
		(stroke
			(width 0)
			(type solid)
		)
		(fill yes)
		(layer "In13.Cu")
		(net "M_H_CPU1_SA_DQS_DN<4>")
	)
	(gr_poly
		(pts
			(xy 143.840962 -245.092474) (xy 143.840962 -245.048024) (xy 143.64081 -245.048024) (xy 143.64081 -245.092474)
			(xy 143.740886 -245.19255)
		)
		(stroke
			(width 0)
			(type solid)
		)
		(fill yes)
		(layer "In13.Cu")
		(net "M_H_CPU1_SA_CB<2>")
	)
	(gr_poly
		(pts
			(xy 143.840962 -243.472462) (xy 143.840962 -243.428012) (xy 143.64081 -243.428012) (xy 143.64081 -243.472462)
			(xy 143.740886 -243.572538)
		)
		(stroke
			(width 0)
			(type solid)
		)
		(fill yes)
		(layer "In13.Cu")
		(net "M_H_CPU1_SA_DQ<30>")
	)
	(gr_poly
		(pts
			(xy 143.840962 -241.852704) (xy 143.840962 -241.805206) (xy 143.64081 -241.805206) (xy 143.64081 -241.852704)
			(xy 143.740886 -241.95278)
		)
		(stroke
			(width 0)
			(type solid)
		)
		(fill yes)
		(layer "In13.Cu")
		(net "M_H_CPU1_SA_DQS_DN<3>")
	)
	(gr_poly
		(pts
			(xy 143.840962 -240.232438) (xy 143.840962 -240.187988) (xy 143.64081 -240.187988) (xy 143.64081 -240.232438)
			(xy 143.740886 -240.332514)
		)
		(stroke
			(width 0)
			(type solid)
		)
		(fill yes)
		(layer "In13.Cu")
		(net "M_H_CPU1_SA_DQ<26>")
	)
	(gr_poly
		(pts
			(xy 143.840962 -238.612426) (xy 143.840962 -238.567976) (xy 143.64081 -238.567976) (xy 143.64081 -238.612426)
			(xy 143.740886 -238.712502)
		)
		(stroke
			(width 0)
			(type solid)
		)
		(fill yes)
		(layer "In13.Cu")
		(net "M_H_CPU1_SA_DQ<22>")
	)
	(gr_poly
		(pts
			(xy 143.840962 -233.75239) (xy 143.840962 -233.70794) (xy 143.64081 -233.70794) (xy 143.64081 -233.75239)
			(xy 143.740886 -233.852466)
		)
		(stroke
			(width 0)
			(type solid)
		)
		(fill yes)
		(layer "In13.Cu")
		(net "M_H_CPU1_SA_DQ<14>")
	)
	(gr_poly
		(pts
			(xy 143.843502 -255.216152) (xy 143.743426 -255.116076) (xy 143.643604 -255.216152) (xy 143.643604 -255.260602)
			(xy 143.843502 -255.260602)
		)
		(stroke
			(width 0)
			(type solid)
		)
		(fill yes)
		(layer "In13.Cu")
		(net "M_H_CPU1_SA_CA<6>")
	)
	(gr_poly
		(pts
			(xy 143.843502 -253.59614) (xy 143.743426 -253.496064) (xy 143.643604 -253.59614) (xy 143.643604 -253.64059)
			(xy 143.843502 -253.64059)
		)
		(stroke
			(width 0)
			(type solid)
		)
		(fill yes)
		(layer "In13.Cu")
		(net "M_H_CPU1_SA_CA<2>")
	)
	(gr_poly
		(pts
			(xy 143.843502 -251.976128) (xy 143.743426 -251.876052) (xy 143.643604 -251.976128) (xy 143.643604 -252.020578)
			(xy 143.843502 -252.020578)
		)
		(stroke
			(width 0)
			(type solid)
		)
		(fill yes)
		(layer "In13.Cu")
		(net "M_H_CPU1_SA_CS_N<1>")
	)
	(gr_poly
		(pts
			(xy 143.843502 -250.356116) (xy 143.743426 -250.25604) (xy 143.643604 -250.356116) (xy 143.643604 -250.400566)
			(xy 143.843502 -250.400566)
		)
		(stroke
			(width 0)
			(type solid)
		)
		(fill yes)
		(layer "In13.Cu")
		(net "M_H_CPU1_ALERT_R_N")
	)
	(gr_poly
		(pts
			(xy 143.843502 -248.736104) (xy 143.743426 -248.636028) (xy 143.643604 -248.736104) (xy 143.643604 -248.780554)
			(xy 143.843502 -248.780554)
		)
		(stroke
			(width 0)
			(type solid)
		)
		(fill yes)
		(layer "In13.Cu")
		(net "M_H_CPU1_SA_CB<5>")
	)
	(gr_poly
		(pts
			(xy 143.843502 -247.115838) (xy 143.743426 -247.016016) (xy 143.643604 -247.115838) (xy 143.643604 -247.16359)
			(xy 143.843502 -247.16359)
		)
		(stroke
			(width 0)
			(type solid)
		)
		(fill yes)
		(layer "In13.Cu")
		(net "M_H_CPU1_SA_DQS_DN<9>")
	)
	(gr_poly
		(pts
			(xy 143.843502 -245.49608) (xy 143.743426 -245.396004) (xy 143.643604 -245.49608) (xy 143.643604 -245.54053)
			(xy 143.843502 -245.54053)
		)
		(stroke
			(width 0)
			(type solid)
		)
		(fill yes)
		(layer "In13.Cu")
		(net "M_H_CPU1_SA_CB<1>")
	)
	(gr_poly
		(pts
			(xy 143.843502 -243.876068) (xy 143.743426 -243.775992) (xy 143.643604 -243.876068) (xy 143.643604 -243.920518)
			(xy 143.843502 -243.920518)
		)
		(stroke
			(width 0)
			(type solid)
		)
		(fill yes)
		(layer "In13.Cu")
		(net "M_H_CPU1_SA_DQ<29>")
	)
	(gr_poly
		(pts
			(xy 143.843502 -242.255802) (xy 143.743426 -242.15598) (xy 143.643604 -242.255802) (xy 143.643604 -242.303554)
			(xy 143.843502 -242.303554)
		)
		(stroke
			(width 0)
			(type solid)
		)
		(fill yes)
		(layer "In13.Cu")
		(net "M_H_CPU1_SA_DQS_DN<8>")
	)
	(gr_poly
		(pts
			(xy 143.843502 -240.636044) (xy 143.743426 -240.535968) (xy 143.643604 -240.636044) (xy 143.643604 -240.680494)
			(xy 143.843502 -240.680494)
		)
		(stroke
			(width 0)
			(type solid)
		)
		(fill yes)
		(layer "In13.Cu")
		(net "M_H_CPU1_SA_DQ<25>")
	)
	(gr_poly
		(pts
			(xy 143.843502 -239.016032) (xy 143.743426 -238.915956) (xy 143.643604 -239.016032) (xy 143.643604 -239.060482)
			(xy 143.843502 -239.060482)
		)
		(stroke
			(width 0)
			(type solid)
		)
		(fill yes)
		(layer "In13.Cu")
		(net "M_H_CPU1_SA_DQ<21>")
	)
	(gr_poly
		(pts
			(xy 143.843502 -235.776008) (xy 143.743426 -235.675932) (xy 143.643604 -235.776008) (xy 143.643604 -235.820458)
			(xy 143.843502 -235.820458)
		)
		(stroke
			(width 0)
			(type solid)
		)
		(fill yes)
		(layer "In13.Cu")
		(net "M_H_CPU1_SA_DQ<17>")
	)
	(gr_poly
		(pts
			(xy 143.852392 -236.99216) (xy 143.852392 -236.944662) (xy 143.652494 -236.944662) (xy 143.652494 -236.99216)
			(xy 143.75257 -237.092236)
		)
		(stroke
			(width 0)
			(type solid)
		)
		(fill yes)
		(layer "In13.Cu")
		(net "M_H_CPU1_SA_DQS_DN<2>")
	)
	(gr_poly
		(pts
			(xy 143.890492 -224.569528) (xy 143.853916 -224.43313) (xy 143.812514 -224.409254) (xy 143.712692 -224.582482)
			(xy 143.75384 -224.606104)
		)
		(stroke
			(width 0)
			(type solid)
		)
		(fill yes)
		(layer "In13.Cu")
		(net "M_H_CPU1_SA_DQS_DP<5>")
	)
	(gr_poly
		(pts
			(xy 143.890492 -222.949516) (xy 143.853916 -222.813118) (xy 143.812514 -222.789242) (xy 143.712692 -222.96247)
			(xy 143.75384 -222.986092)
		)
		(stroke
			(width 0)
			(type solid)
		)
		(fill yes)
		(layer "In13.Cu")
		(net "M_H_CPU1_SA_DQS_DN<0>")
	)
	(gr_poly
		(pts
			(xy 143.890746 -231.049068) (xy 143.853916 -230.912416) (xy 143.815562 -230.890064) (xy 143.715486 -231.063292)
			(xy 143.754094 -231.085644)
		)
		(stroke
			(width 0)
			(type solid)
		)
		(fill yes)
		(layer "In13.Cu")
		(net "M_H_CPU1_SA_DQ<11>")
	)
	(gr_poly
		(pts
			(xy 143.890746 -226.189032) (xy 143.853916 -226.05238) (xy 143.815562 -226.030028) (xy 143.715486 -226.203256)
			(xy 143.754094 -226.225608)
		)
		(stroke
			(width 0)
			(type solid)
		)
		(fill yes)
		(layer "In13.Cu")
		(net "M_H_CPU1_SA_DQ<6>")
	)
	(gr_poly
		(pts
			(xy 144.053814 -293.874952) (xy 143.953738 -293.701724) (xy 143.915384 -293.724076) (xy 143.878554 -293.860728)
			(xy 144.015206 -293.897304)
		)
		(stroke
			(width 0)
			(type solid)
		)
		(fill yes)
		(layer "In13.Cu")
		(net "M_H_CPU1_SB_DQ<31>")
	)
	(gr_poly
		(pts
			(xy 144.053814 -268.877542) (xy 144.015206 -268.85519) (xy 143.878554 -268.891766) (xy 143.915384 -269.028418)
			(xy 143.953738 -269.05077)
		)
		(stroke
			(width 0)
			(type solid)
		)
		(fill yes)
		(layer "In13.Cu")
		(net "M_H_CPU1_SB_CB<4>")
	)
	(gr_poly
		(pts
			(xy 144.119346 -290.488116) (xy 144.019524 -290.38804) (xy 143.919448 -290.488116) (xy 143.919448 -290.535614)
			(xy 144.119346 -290.535614)
		)
		(stroke
			(width 0)
			(type solid)
		)
		(fill yes)
		(layer "In13.Cu")
		(net "M_H_CPU1_SB_DQS_DP<3>")
	)
	(gr_poly
		(pts
			(xy 144.119346 -285.628334) (xy 144.019524 -285.528258) (xy 143.919448 -285.628334) (xy 143.919448 -285.675832)
			(xy 144.119346 -285.675832)
		)
		(stroke
			(width 0)
			(type solid)
		)
		(fill yes)
		(layer "In13.Cu")
		(net "M_H_CPU1_SB_DQS_DP<2>")
	)
	(gr_poly
		(pts
			(xy 144.119346 -280.768298) (xy 144.019524 -280.668222) (xy 143.919448 -280.768298) (xy 143.919448 -280.815796)
			(xy 144.119346 -280.815796)
		)
		(stroke
			(width 0)
			(type solid)
		)
		(fill yes)
		(layer "In13.Cu")
		(net "M_H_CPU1_SB_DQS_DP<1>")
	)
	(gr_poly
		(pts
			(xy 144.119346 -275.908262) (xy 144.019524 -275.808186) (xy 143.919448 -275.908262) (xy 143.919448 -275.95576)
			(xy 144.119346 -275.95576)
		)
		(stroke
			(width 0)
			(type solid)
		)
		(fill yes)
		(layer "In13.Cu")
		(net "M_H_CPU1_SB_DQS_DP<0>")
	)
	(gr_poly
		(pts
			(xy 144.119346 -271.048226) (xy 144.019524 -270.94815) (xy 143.919448 -271.048226) (xy 143.919448 -271.095724)
			(xy 144.119346 -271.095724)
		)
		(stroke
			(width 0)
			(type solid)
		)
		(fill yes)
		(layer "In13.Cu")
		(net "M_H_CPU1_SB_DQS_DP<9>")
	)
	(gr_poly
		(pts
			(xy 144.121632 -288.868358) (xy 144.021556 -288.768282) (xy 143.92148 -288.868358) (xy 143.92148 -288.912808)
			(xy 144.121632 -288.912808)
		)
		(stroke
			(width 0)
			(type solid)
		)
		(fill yes)
		(layer "In13.Cu")
		(net "M_H_CPU1_SB_DQ<24>")
	)
	(gr_poly
		(pts
			(xy 144.121632 -284.008576) (xy 144.021556 -283.9085) (xy 143.92148 -284.008576) (xy 143.92148 -284.053026)
			(xy 144.121632 -284.053026)
		)
		(stroke
			(width 0)
			(type solid)
		)
		(fill yes)
		(layer "In13.Cu")
		(net "M_H_CPU1_SB_DQ<16>")
	)
	(gr_poly
		(pts
			(xy 144.121632 -282.388564) (xy 144.021556 -282.288488) (xy 143.92148 -282.388564) (xy 143.92148 -282.433014)
			(xy 144.121632 -282.433014)
		)
		(stroke
			(width 0)
			(type solid)
		)
		(fill yes)
		(layer "In13.Cu")
		(net "M_H_CPU1_SB_DQ<12>")
	)
	(gr_poly
		(pts
			(xy 144.121632 -279.14854) (xy 144.021556 -279.048464) (xy 143.92148 -279.14854) (xy 143.92148 -279.19299)
			(xy 144.121632 -279.19299)
		)
		(stroke
			(width 0)
			(type solid)
		)
		(fill yes)
		(layer "In13.Cu")
		(net "M_H_CPU1_SB_DQ<8>")
	)
	(gr_poly
		(pts
			(xy 144.121632 -277.528528) (xy 144.021556 -277.428452) (xy 143.92148 -277.528528) (xy 143.92148 -277.572978)
			(xy 144.121632 -277.572978)
		)
		(stroke
			(width 0)
			(type solid)
		)
		(fill yes)
		(layer "In13.Cu")
		(net "M_H_CPU1_SB_DQ<4>")
	)
	(gr_poly
		(pts
			(xy 144.121632 -274.288504) (xy 144.021556 -274.188428) (xy 143.92148 -274.288504) (xy 143.92148 -274.332954)
			(xy 144.121632 -274.332954)
		)
		(stroke
			(width 0)
			(type solid)
		)
		(fill yes)
		(layer "In13.Cu")
		(net "M_H_CPU1_SB_DQ<0>")
	)
	(gr_poly
		(pts
			(xy 144.121632 -272.668492) (xy 144.021556 -272.568416) (xy 143.92148 -272.668492) (xy 143.92148 -272.712942)
			(xy 144.121632 -272.712942)
		)
		(stroke
			(width 0)
			(type solid)
		)
		(fill yes)
		(layer "In13.Cu")
		(net "M_H_CPU1_SB_CB<0>")
	)
	(gr_poly
		(pts
			(xy 144.121632 -267.808456) (xy 144.021556 -267.70838) (xy 143.92148 -267.808456) (xy 143.92148 -267.852906)
			(xy 144.121632 -267.852906)
		)
		(stroke
			(width 0)
			(type solid)
		)
		(fill yes)
		(layer "In13.Cu")
		(net "M_H_CPU1_SB_RSP<0>")
	)
	(gr_poly
		(pts
			(xy 144.121632 -264.568432) (xy 144.021556 -264.468356) (xy 143.92148 -264.568432) (xy 143.92148 -264.612882)
			(xy 144.121632 -264.612882)
		)
		(stroke
			(width 0)
			(type solid)
		)
		(fill yes)
		(layer "In13.Cu")
		(net "M_H_CPU1_SB_CA<6>")
	)
	(gr_poly
		(pts
			(xy 144.121632 -262.94842) (xy 144.021556 -262.848344) (xy 143.92148 -262.94842) (xy 143.92148 -262.99287)
			(xy 144.121632 -262.99287)
		)
		(stroke
			(width 0)
			(type solid)
		)
		(fill yes)
		(layer "In13.Cu")
		(net "M_H_CPU1_SB_CA<2>")
	)
	(gr_poly
		(pts
			(xy 144.13484 -292.108128) (xy 144.034764 -292.008052) (xy 143.934688 -292.108128) (xy 143.934688 -292.152578)
			(xy 144.13484 -292.152578)
		)
		(stroke
			(width 0)
			(type solid)
		)
		(fill yes)
		(layer "In13.Cu")
		(net "M_H_CPU1_SB_DQ<28>")
	)
	(gr_poly
		(pts
			(xy 144.13484 -291.704522) (xy 144.13484 -291.65677) (xy 143.934688 -291.65677) (xy 143.934688 -291.704522)
			(xy 144.034764 -291.804344)
		)
		(stroke
			(width 0)
			(type solid)
		)
		(fill yes)
		(layer "In13.Cu")
		(net "M_H_CPU1_SB_DQS_DP<8>")
	)
	(gr_poly
		(pts
			(xy 144.13484 -270.644366) (xy 144.13484 -270.599916) (xy 143.934688 -270.599916) (xy 143.934688 -270.644366)
			(xy 144.034764 -270.744442)
		)
		(stroke
			(width 0)
			(type solid)
		)
		(fill yes)
		(layer "In13.Cu")
		(net "M_H_CPU1_SB_CB<7>")
	)
	(gr_poly
		(pts
			(xy 144.140936 -286.844486) (xy 144.140936 -286.796988) (xy 143.941038 -286.796988) (xy 143.941038 -286.844486)
			(xy 144.04086 -286.944562)
		)
		(stroke
			(width 0)
			(type solid)
		)
		(fill yes)
		(layer "In13.Cu")
		(net "M_H_CPU1_SB_DQS_DP<7>")
	)
	(gr_poly
		(pts
			(xy 144.140936 -285.224474) (xy 144.140936 -285.180024) (xy 143.941038 -285.180024) (xy 143.941038 -285.224474)
			(xy 144.04086 -285.32455)
		)
		(stroke
			(width 0)
			(type solid)
		)
		(fill yes)
		(layer "In13.Cu")
		(net "M_H_CPU1_SB_DQ<19>")
	)
	(gr_poly
		(pts
			(xy 144.140936 -283.604462) (xy 144.140936 -283.560012) (xy 143.941038 -283.560012) (xy 143.941038 -283.604462)
			(xy 144.04086 -283.704538)
		)
		(stroke
			(width 0)
			(type solid)
		)
		(fill yes)
		(layer "In13.Cu")
		(net "M_H_CPU1_SB_DQ<15>")
	)
	(gr_poly
		(pts
			(xy 144.140936 -281.984704) (xy 144.140936 -281.937206) (xy 143.941038 -281.937206) (xy 143.941038 -281.984704)
			(xy 144.04086 -282.08478)
		)
		(stroke
			(width 0)
			(type solid)
		)
		(fill yes)
		(layer "In13.Cu")
		(net "M_H_CPU1_SB_DQS_DP<6>")
	)
	(gr_poly
		(pts
			(xy 144.140936 -280.364438) (xy 144.140936 -280.319988) (xy 143.941038 -280.319988) (xy 143.941038 -280.364438)
			(xy 144.04086 -280.464514)
		)
		(stroke
			(width 0)
			(type solid)
		)
		(fill yes)
		(layer "In13.Cu")
		(net "M_H_CPU1_SB_DQ<11>")
	)
	(gr_poly
		(pts
			(xy 144.140936 -278.744426) (xy 144.140936 -278.699976) (xy 143.941038 -278.699976) (xy 143.941038 -278.744426)
			(xy 144.04086 -278.844502)
		)
		(stroke
			(width 0)
			(type solid)
		)
		(fill yes)
		(layer "In13.Cu")
		(net "M_H_CPU1_SB_DQ<7>")
	)
	(gr_poly
		(pts
			(xy 144.140936 -277.124668) (xy 144.140936 -277.07717) (xy 143.941038 -277.07717) (xy 143.941038 -277.124668)
			(xy 144.04086 -277.224744)
		)
		(stroke
			(width 0)
			(type solid)
		)
		(fill yes)
		(layer "In13.Cu")
		(net "M_H_CPU1_SB_DQS_DP<5>")
	)
	(gr_poly
		(pts
			(xy 144.140936 -275.504402) (xy 144.140936 -275.459952) (xy 143.941038 -275.459952) (xy 143.941038 -275.504402)
			(xy 144.04086 -275.604478)
		)
		(stroke
			(width 0)
			(type solid)
		)
		(fill yes)
		(layer "In13.Cu")
		(net "M_H_CPU1_SB_DQ<3>")
	)
	(gr_poly
		(pts
			(xy 144.140936 -273.88439) (xy 144.140936 -273.83994) (xy 143.941038 -273.83994) (xy 143.941038 -273.88439)
			(xy 144.04086 -273.984466)
		)
		(stroke
			(width 0)
			(type solid)
		)
		(fill yes)
		(layer "In13.Cu")
		(net "M_H_CPU1_SB_CB<3>")
	)
	(gr_poly
		(pts
			(xy 144.140936 -272.264632) (xy 144.140936 -272.217134) (xy 143.941038 -272.217134) (xy 143.941038 -272.264632)
			(xy 144.04086 -272.364708)
		)
		(stroke
			(width 0)
			(type solid)
		)
		(fill yes)
		(layer "In13.Cu")
		(net "M_H_CPU1_SB_DQS_DP<4>")
	)
	(gr_poly
		(pts
			(xy 144.140936 -265.78433) (xy 144.140936 -265.73988) (xy 143.941038 -265.73988) (xy 143.941038 -265.78433)
			(xy 144.04086 -265.884406)
		)
		(stroke
			(width 0)
			(type solid)
		)
		(fill yes)
		(layer "In13.Cu")
		(net "M_H_CPU1_SB_CS_N<0>")
	)
	(gr_poly
		(pts
			(xy 144.140936 -264.164318) (xy 144.140936 -264.119868) (xy 143.941038 -264.119868) (xy 143.941038 -264.164318)
			(xy 144.04086 -264.264394)
		)
		(stroke
			(width 0)
			(type solid)
		)
		(fill yes)
		(layer "In13.Cu")
		(net "M_H_CPU1_SB_CA<5>")
	)
	(gr_poly
		(pts
			(xy 144.140936 -262.544306) (xy 144.140936 -262.499856) (xy 143.941038 -262.499856) (xy 143.941038 -262.544306)
			(xy 144.04086 -262.644382)
		)
		(stroke
			(width 0)
			(type solid)
		)
		(fill yes)
		(layer "In13.Cu")
		(net "M_H_CPU1_SB_CA<1>")
	)
	(gr_poly
		(pts
			(xy 144.15389 -293.328344) (xy 144.190466 -293.191692) (xy 144.054068 -293.155116) (xy 144.01546 -293.177468)
			(xy 144.115536 -293.350696)
		)
		(stroke
			(width 0)
			(type solid)
		)
		(fill yes)
		(layer "In13.Cu")
		(net "M_H_CPU1_SB_DQ<29>")
	)
	(gr_poly
		(pts
			(xy 144.190466 -269.560802) (xy 144.15389 -269.42415) (xy 144.115536 -269.401798) (xy 144.01546 -269.575026)
			(xy 144.054068 -269.597378)
		)
		(stroke
			(width 0)
			(type solid)
		)
		(fill yes)
		(layer "In13.Cu")
		(net "M_H_CPU1_SB_CB<6>")
	)
	(gr_poly
		(pts
			(xy 144.223994 -224.695766) (xy 144.185386 -224.673414) (xy 144.048734 -224.70999) (xy 144.085564 -224.846642)
			(xy 144.123918 -224.868994)
		)
		(stroke
			(width 0)
			(type solid)
		)
		(fill yes)
		(layer "In13.Cu")
		(net "M_H_CPU1_SA_DQ<4>")
	)
	(gr_poly
		(pts
			(xy 144.226788 -223.076516) (xy 144.18564 -223.05264) (xy 144.048988 -223.08947) (xy 144.085564 -223.225868)
			(xy 144.126966 -223.249744)
		)
		(stroke
			(width 0)
			(type solid)
		)
		(fill yes)
		(layer "In13.Cu")
		(net "M_H_CPU1_SA_DQS_DN<5>")
	)
	(gr_poly
		(pts
			(xy 144.286732 -236.586522) (xy 144.186656 -236.486446) (xy 144.086834 -236.586522) (xy 144.086834 -236.63402)
			(xy 144.286732 -236.63402)
		)
		(stroke
			(width 0)
			(type solid)
		)
		(fill yes)
		(layer "In13.Cu")
		(net "M_H_CPU1_SA_DQS_DP<2>")
	)
	(gr_poly
		(pts
			(xy 144.296892 -255.622806) (xy 144.296892 -255.578356) (xy 144.096994 -255.578356) (xy 144.096994 -255.622806)
			(xy 144.19707 -255.722628)
		)
		(stroke
			(width 0)
			(type solid)
		)
		(fill yes)
		(layer "In13.Cu")
		(net "M_H_CPU1_SA_PAR")
	)
	(gr_poly
		(pts
			(xy 144.296892 -254.002794) (xy 144.296892 -253.958344) (xy 144.096994 -253.958344) (xy 144.096994 -254.002794)
			(xy 144.19707 -254.10287)
		)
		(stroke
			(width 0)
			(type solid)
		)
		(fill yes)
		(layer "In13.Cu")
		(net "M_H_CPU1_SA_CA<3>")
	)
	(gr_poly
		(pts
			(xy 144.296892 -250.76277) (xy 144.296892 -250.71832) (xy 144.096994 -250.71832) (xy 144.096994 -250.76277)
			(xy 144.19707 -250.862592)
		)
		(stroke
			(width 0)
			(type solid)
		)
		(fill yes)
		(layer "In13.Cu")
		(net "M_H_CPU1_RESET_N")
	)
	(gr_poly
		(pts
			(xy 144.296892 -249.142758) (xy 144.296892 -249.098308) (xy 144.096994 -249.098308) (xy 144.096994 -249.142758)
			(xy 144.19707 -249.242834)
		)
		(stroke
			(width 0)
			(type solid)
		)
		(fill yes)
		(layer "In13.Cu")
		(net "M_H_CPU1_SA_CB<7>")
	)
	(gr_poly
		(pts
			(xy 144.296892 -247.523) (xy 144.296892 -247.475248) (xy 144.096994 -247.475248) (xy 144.096994 -247.523)
			(xy 144.19707 -247.622822)
		)
		(stroke
			(width 0)
			(type solid)
		)
		(fill yes)
		(layer "In13.Cu")
		(net "M_H_CPU1_SA_DQS_DP<9>")
	)
	(gr_poly
		(pts
			(xy 144.296892 -245.902734) (xy 144.296892 -245.858284) (xy 144.096994 -245.858284) (xy 144.096994 -245.902734)
			(xy 144.19707 -246.002556)
		)
		(stroke
			(width 0)
			(type solid)
		)
		(fill yes)
		(layer "In13.Cu")
		(net "M_H_CPU1_SA_CB<3>")
	)
	(gr_poly
		(pts
			(xy 144.296892 -244.282722) (xy 144.296892 -244.238272) (xy 144.096994 -244.238272) (xy 144.096994 -244.282722)
			(xy 144.19707 -244.382544)
		)
		(stroke
			(width 0)
			(type solid)
		)
		(fill yes)
		(layer "In13.Cu")
		(net "M_H_CPU1_SA_DQ<31>")
	)
	(gr_poly
		(pts
			(xy 144.296892 -241.042698) (xy 144.296892 -240.998248) (xy 144.096994 -240.998248) (xy 144.096994 -241.042698)
			(xy 144.19707 -241.14252)
		)
		(stroke
			(width 0)
			(type solid)
		)
		(fill yes)
		(layer "In13.Cu")
		(net "M_H_CPU1_SA_DQ<27>")
	)
	(gr_poly
		(pts
			(xy 144.296892 -239.422686) (xy 144.296892 -239.378236) (xy 144.096994 -239.378236) (xy 144.096994 -239.422686)
			(xy 144.19707 -239.522508)
		)
		(stroke
			(width 0)
			(type solid)
		)
		(fill yes)
		(layer "In13.Cu")
		(net "M_H_CPU1_SA_DQ<23>")
	)
	(gr_poly
		(pts
			(xy 144.299178 -254.4064) (xy 144.199356 -254.306324) (xy 144.09928 -254.4064) (xy 144.09928 -254.45085)
			(xy 144.299178 -254.45085)
		)
		(stroke
			(width 0)
			(type solid)
		)
		(fill yes)
		(layer "In13.Cu")
		(net "M_H_CPU1_SA_CA<4>")
	)
	(gr_poly
		(pts
			(xy 144.299178 -252.786388) (xy 144.199356 -252.686312) (xy 144.09928 -252.786388) (xy 144.09928 -252.830838)
			(xy 144.299178 -252.830838)
		)
		(stroke
			(width 0)
			(type solid)
		)
		(fill yes)
		(layer "In13.Cu")
		(net "M_H_CPU1_SA_CA<0>")
	)
	(gr_poly
		(pts
			(xy 144.299178 -251.166376) (xy 144.199356 -251.0663) (xy 144.09928 -251.166376) (xy 144.09928 -251.210826)
			(xy 144.299178 -251.210826)
		)
		(stroke
			(width 0)
			(type solid)
		)
		(fill yes)
		(layer "In13.Cu")
		(net "M_H_CPU1_SA_CS_N<0>")
	)
	(gr_poly
		(pts
			(xy 144.299178 -247.926352) (xy 144.199356 -247.826276) (xy 144.09928 -247.926352) (xy 144.09928 -247.970802)
			(xy 144.299178 -247.970802)
		)
		(stroke
			(width 0)
			(type solid)
		)
		(fill yes)
		(layer "In13.Cu")
		(net "M_H_CPU1_SA_CB<4>")
	)
	(gr_poly
		(pts
			(xy 144.299178 -246.306086) (xy 144.199356 -246.20601) (xy 144.09928 -246.306086) (xy 144.09928 -246.353584)
			(xy 144.299178 -246.353584)
		)
		(stroke
			(width 0)
			(type solid)
		)
		(fill yes)
		(layer "In13.Cu")
		(net "M_H_CPU1_SA_DQS_DP<4>")
	)
	(gr_poly
		(pts
			(xy 144.299178 -244.686328) (xy 144.199356 -244.586252) (xy 144.09928 -244.686328) (xy 144.09928 -244.730778)
			(xy 144.299178 -244.730778)
		)
		(stroke
			(width 0)
			(type solid)
		)
		(fill yes)
		(layer "In13.Cu")
		(net "M_H_CPU1_SA_CB<0>")
	)
	(gr_poly
		(pts
			(xy 144.299178 -243.066316) (xy 144.199356 -242.96624) (xy 144.09928 -243.066316) (xy 144.09928 -243.110766)
			(xy 144.299178 -243.110766)
		)
		(stroke
			(width 0)
			(type solid)
		)
		(fill yes)
		(layer "In13.Cu")
		(net "M_H_CPU1_SA_DQ<28>")
	)
	(gr_poly
		(pts
			(xy 144.299178 -241.44605) (xy 144.199356 -241.345974) (xy 144.09928 -241.44605) (xy 144.09928 -241.493548)
			(xy 144.299178 -241.493548)
		)
		(stroke
			(width 0)
			(type solid)
		)
		(fill yes)
		(layer "In13.Cu")
		(net "M_H_CPU1_SA_DQS_DP<3>")
	)
	(gr_poly
		(pts
			(xy 144.299178 -239.826292) (xy 144.199356 -239.726216) (xy 144.09928 -239.826292) (xy 144.09928 -239.870742)
			(xy 144.299178 -239.870742)
		)
		(stroke
			(width 0)
			(type solid)
		)
		(fill yes)
		(layer "In13.Cu")
		(net "M_H_CPU1_SA_DQ<24>")
	)
	(gr_poly
		(pts
			(xy 144.299178 -238.20628) (xy 144.199356 -238.106204) (xy 144.09928 -238.20628) (xy 144.09928 -238.25073)
			(xy 144.299178 -238.25073)
		)
		(stroke
			(width 0)
			(type solid)
		)
		(fill yes)
		(layer "In13.Cu")
		(net "M_H_CPU1_SA_DQ<20>")
	)
	(gr_poly
		(pts
			(xy 144.310608 -237.802674) (xy 144.310608 -237.754922) (xy 144.11071 -237.754922) (xy 144.11071 -237.802674)
			(xy 144.210532 -237.902496)
		)
		(stroke
			(width 0)
			(type solid)
		)
		(fill yes)
		(layer "In13.Cu")
		(net "M_H_CPU1_SA_DQS_DP<7>")
	)
	(gr_poly
		(pts
			(xy 144.313402 -256.025904) (xy 144.213326 -255.926082) (xy 144.113504 -256.025904) (xy 144.113504 -256.073656)
			(xy 144.313402 -256.073656)
		)
		(stroke
			(width 0)
			(type solid)
		)
		(fill yes)
		(layer "In13.Cu")
		(net "M_H_CPU1_CLK_DP<0>")
	)
	(gr_poly
		(pts
			(xy 144.360646 -225.379026) (xy 144.32407 -225.242374) (xy 144.285716 -225.220022) (xy 144.18564 -225.39325)
			(xy 144.224248 -225.415602)
		)
		(stroke
			(width 0)
			(type solid)
		)
		(fill yes)
		(layer "In13.Cu")
		(net "M_H_CPU1_SA_DQ<6>")
	)
	(gr_poly
		(pts
			(xy 144.360646 -223.759522) (xy 144.32407 -223.623124) (xy 144.282668 -223.599248) (xy 144.182846 -223.772476)
			(xy 144.223994 -223.796352)
		)
		(stroke
			(width 0)
			(type solid)
		)
		(fill yes)
		(layer "In13.Cu")
		(net "M_H_CPU1_SA_DQS_DP<5>")
	)
	(gr_poly
		(pts
			(xy 144.360646 -222.139002) (xy 144.32407 -222.00235) (xy 144.282922 -221.978474) (xy 144.182846 -222.151702)
			(xy 144.223994 -222.175578)
		)
		(stroke
			(width 0)
			(type solid)
		)
		(fill yes)
		(layer "In13.Cu")
		(net "M_H_CPU1_SA_DQS_DN<0>")
	)
	(gr_poly
		(pts
			(xy 144.523714 -294.684958) (xy 144.423638 -294.51173) (xy 144.385284 -294.534082) (xy 144.348454 -294.670734)
			(xy 144.485106 -294.70731)
		)
		(stroke
			(width 0)
			(type solid)
		)
		(fill yes)
		(layer "In13.Cu")
		(net "M_H_CPU1_SB_DQ<31>")
	)
	(gr_poly
		(pts
			(xy 144.523968 -293.064946) (xy 144.423892 -292.891718) (xy 144.385538 -292.91407) (xy 144.348962 -293.050722)
			(xy 144.48536 -293.087298)
		)
		(stroke
			(width 0)
			(type solid)
		)
		(fill yes)
		(layer "In13.Cu")
		(net "M_H_CPU1_SB_DQ<30>")
	)
	(gr_poly
		(pts
			(xy 144.523968 -269.687548) (xy 144.48536 -269.665196) (xy 144.348962 -269.701772) (xy 144.385538 -269.838424)
			(xy 144.423892 -269.860776)
		)
		(stroke
			(width 0)
			(type solid)
		)
		(fill yes)
		(layer "In13.Cu")
		(net "M_H_CPU1_SB_CB<5>")
	)
	(gr_poly
		(pts
			(xy 144.599406 -284.818328) (xy 144.49933 -284.718252) (xy 144.399254 -284.818328) (xy 144.399254 -284.862778)
			(xy 144.599406 -284.862778)
		)
		(stroke
			(width 0)
			(type solid)
		)
		(fill yes)
		(layer "In13.Cu")
		(net "M_H_CPU1_SB_DQ<17>")
	)
	(gr_poly
		(pts
			(xy 144.599406 -283.198316) (xy 144.49933 -283.09824) (xy 144.399254 -283.198316) (xy 144.399254 -283.242766)
			(xy 144.599406 -283.242766)
		)
		(stroke
			(width 0)
			(type solid)
		)
		(fill yes)
		(layer "In13.Cu")
		(net "M_H_CPU1_SB_DQ<13>")
	)
	(gr_poly
		(pts
			(xy 144.599406 -281.57805) (xy 144.49933 -281.477974) (xy 144.399254 -281.57805) (xy 144.399254 -281.625548)
			(xy 144.599406 -281.625548)
		)
		(stroke
			(width 0)
			(type solid)
		)
		(fill yes)
		(layer "In13.Cu")
		(net "M_H_CPU1_SB_DQS_DN<6>")
	)
	(gr_poly
		(pts
			(xy 144.599406 -279.958292) (xy 144.49933 -279.858216) (xy 144.399254 -279.958292) (xy 144.399254 -280.002742)
			(xy 144.599406 -280.002742)
		)
		(stroke
			(width 0)
			(type solid)
		)
		(fill yes)
		(layer "In13.Cu")
		(net "M_H_CPU1_SB_DQ<9>")
	)
	(gr_poly
		(pts
			(xy 144.599406 -278.33828) (xy 144.49933 -278.238204) (xy 144.399254 -278.33828) (xy 144.399254 -278.38273)
			(xy 144.599406 -278.38273)
		)
		(stroke
			(width 0)
			(type solid)
		)
		(fill yes)
		(layer "In13.Cu")
		(net "M_H_CPU1_SB_DQ<5>")
	)
	(gr_poly
		(pts
			(xy 144.599406 -276.718014) (xy 144.49933 -276.617938) (xy 144.399254 -276.718014) (xy 144.399254 -276.765512)
			(xy 144.599406 -276.765512)
		)
		(stroke
			(width 0)
			(type solid)
		)
		(fill yes)
		(layer "In13.Cu")
		(net "M_H_CPU1_SB_DQS_DN<5>")
	)
	(gr_poly
		(pts
			(xy 144.599406 -275.098256) (xy 144.49933 -274.99818) (xy 144.399254 -275.098256) (xy 144.399254 -275.142706)
			(xy 144.599406 -275.142706)
		)
		(stroke
			(width 0)
			(type solid)
		)
		(fill yes)
		(layer "In13.Cu")
		(net "M_H_CPU1_SB_DQ<1>")
	)
	(gr_poly
		(pts
			(xy 144.599406 -273.478244) (xy 144.49933 -273.378168) (xy 144.399254 -273.478244) (xy 144.399254 -273.522694)
			(xy 144.599406 -273.522694)
		)
		(stroke
			(width 0)
			(type solid)
		)
		(fill yes)
		(layer "In13.Cu")
		(net "M_H_CPU1_SB_CB<1>")
	)
	(gr_poly
		(pts
			(xy 144.599406 -266.998196) (xy 144.49933 -266.89812) (xy 144.399254 -266.998196) (xy 144.399254 -267.042646)
			(xy 144.599406 -267.042646)
		)
		(stroke
			(width 0)
			(type solid)
		)
		(fill yes)
		(layer "In13.Cu")
		(net "M_H_CPU1_SA_RSP<0>")
	)
	(gr_poly
		(pts
			(xy 144.599406 -265.378184) (xy 144.49933 -265.278108) (xy 144.399254 -265.378184) (xy 144.399254 -265.422634)
			(xy 144.599406 -265.422634)
		)
		(stroke
			(width 0)
			(type solid)
		)
		(fill yes)
		(layer "In13.Cu")
		(net "M_H_CPU1_SB_PAR")
	)
	(gr_poly
		(pts
			(xy 144.599406 -263.758172) (xy 144.49933 -263.658096) (xy 144.399254 -263.758172) (xy 144.399254 -263.802622)
			(xy 144.599406 -263.802622)
		)
		(stroke
			(width 0)
			(type solid)
		)
		(fill yes)
		(layer "In13.Cu")
		(net "M_H_CPU1_SB_CA<4>")
	)
	(gr_poly
		(pts
			(xy 144.599406 -262.13816) (xy 144.49933 -262.038084) (xy 144.399254 -262.13816) (xy 144.399254 -262.18261)
			(xy 144.599406 -262.18261)
		)
		(stroke
			(width 0)
			(type solid)
		)
		(fill yes)
		(layer "In13.Cu")
		(net "M_H_CPU1_SB_CA<0>")
	)
	(gr_poly
		(pts
			(xy 144.60474 -291.297868) (xy 144.504664 -291.198046) (xy 144.404588 -291.297868) (xy 144.404588 -291.34562)
			(xy 144.60474 -291.34562)
		)
		(stroke
			(width 0)
			(type solid)
		)
		(fill yes)
		(layer "In13.Cu")
		(net "M_H_CPU1_SB_DQS_DN<8>")
	)
	(gr_poly
		(pts
			(xy 144.60474 -271.454626) (xy 144.60474 -271.406874) (xy 144.404588 -271.406874) (xy 144.404588 -271.454626)
			(xy 144.504664 -271.554448)
		)
		(stroke
			(width 0)
			(type solid)
		)
		(fill yes)
		(layer "In13.Cu")
		(net "M_H_CPU1_SB_DQS_DN<9>")
	)
	(gr_poly
		(pts
			(xy 144.60474 -268.618208) (xy 144.504664 -268.518132) (xy 144.404588 -268.618208) (xy 144.404588 -268.662658)
			(xy 144.60474 -268.662658)
		)
		(stroke
			(width 0)
			(type solid)
		)
		(fill yes)
		(layer "In13.Cu")
		(net "M_H_CPU1_SB_CB<4>")
	)
	(gr_poly
		(pts
			(xy 144.615662 -284.414214) (xy 144.615662 -284.369764) (xy 144.41551 -284.369764) (xy 144.41551 -284.414214)
			(xy 144.515586 -284.51429)
		)
		(stroke
			(width 0)
			(type solid)
		)
		(fill yes)
		(layer "In13.Cu")
		(net "M_H_CPU1_SB_DQ<18>")
	)
	(gr_poly
		(pts
			(xy 144.615662 -282.794202) (xy 144.615662 -282.749752) (xy 144.41551 -282.749752) (xy 144.41551 -282.794202)
			(xy 144.515586 -282.894278)
		)
		(stroke
			(width 0)
			(type solid)
		)
		(fill yes)
		(layer "In13.Cu")
		(net "M_H_CPU1_SB_DQ<14>")
	)
	(gr_poly
		(pts
			(xy 144.615662 -279.554178) (xy 144.615662 -279.509728) (xy 144.41551 -279.509728) (xy 144.41551 -279.554178)
			(xy 144.515586 -279.654254)
		)
		(stroke
			(width 0)
			(type solid)
		)
		(fill yes)
		(layer "In13.Cu")
		(net "M_H_CPU1_SB_DQ<10>")
	)
	(gr_poly
		(pts
			(xy 144.615662 -277.934166) (xy 144.615662 -277.889716) (xy 144.41551 -277.889716) (xy 144.41551 -277.934166)
			(xy 144.515586 -278.034242)
		)
		(stroke
			(width 0)
			(type solid)
		)
		(fill yes)
		(layer "In13.Cu")
		(net "M_H_CPU1_SB_DQ<6>")
	)
	(gr_poly
		(pts
			(xy 144.615662 -274.694142) (xy 144.615662 -274.649692) (xy 144.41551 -274.649692) (xy 144.41551 -274.694142)
			(xy 144.515586 -274.794218)
		)
		(stroke
			(width 0)
			(type solid)
		)
		(fill yes)
		(layer "In13.Cu")
		(net "M_H_CPU1_SB_DQ<2>")
	)
	(gr_poly
		(pts
			(xy 144.615662 -273.07413) (xy 144.615662 -273.02968) (xy 144.41551 -273.02968) (xy 144.41551 -273.07413)
			(xy 144.515586 -273.174206)
		)
		(stroke
			(width 0)
			(type solid)
		)
		(fill yes)
		(layer "In13.Cu")
		(net "M_H_CPU1_SB_CB<2>")
	)
	(gr_poly
		(pts
			(xy 144.615662 -266.594082) (xy 144.615662 -266.549632) (xy 144.41551 -266.549632) (xy 144.41551 -266.594082)
			(xy 144.515586 -266.694158)
		)
		(stroke
			(width 0)
			(type solid)
		)
		(fill yes)
		(layer "In13.Cu")
		(net "M_H_CPU1_SB_CS_N<1>")
	)
	(gr_poly
		(pts
			(xy 144.615662 -263.354058) (xy 144.615662 -263.309608) (xy 144.41551 -263.309608) (xy 144.41551 -263.354058)
			(xy 144.515586 -263.454134)
		)
		(stroke
			(width 0)
			(type solid)
		)
		(fill yes)
		(layer "In13.Cu")
		(net "M_H_CPU1_SB_CA<3>")
	)
	(gr_poly
		(pts
			(xy 144.617694 -290.894262) (xy 144.617694 -290.846764) (xy 144.417796 -290.846764) (xy 144.417796 -290.894262)
			(xy 144.517618 -290.994338)
		)
		(stroke
			(width 0)
			(type solid)
		)
		(fill yes)
		(layer "In13.Cu")
		(net "M_H_CPU1_SB_DQS_DN<3>")
	)
	(gr_poly
		(pts
			(xy 144.617694 -286.03448) (xy 144.617694 -285.986982) (xy 144.417796 -285.986982) (xy 144.417796 -286.03448)
			(xy 144.517618 -286.134556)
		)
		(stroke
			(width 0)
			(type solid)
		)
		(fill yes)
		(layer "In13.Cu")
		(net "M_H_CPU1_SB_DQS_DN<2>")
	)
	(gr_poly
		(pts
			(xy 144.617694 -281.174444) (xy 144.617694 -281.126946) (xy 144.417796 -281.126946) (xy 144.417796 -281.174444)
			(xy 144.517618 -281.27452)
		)
		(stroke
			(width 0)
			(type solid)
		)
		(fill yes)
		(layer "In13.Cu")
		(net "M_H_CPU1_SB_DQS_DN<1>")
	)
	(gr_poly
		(pts
			(xy 144.617694 -276.314408) (xy 144.617694 -276.26691) (xy 144.417796 -276.26691) (xy 144.417796 -276.314408)
			(xy 144.517618 -276.414484)
		)
		(stroke
			(width 0)
			(type solid)
		)
		(fill yes)
		(layer "In13.Cu")
		(net "M_H_CPU1_SB_DQS_DN<0>")
	)
	(gr_poly
		(pts
			(xy 144.62379 -294.13835) (xy 144.660366 -294.001698) (xy 144.523968 -293.965122) (xy 144.48536 -293.987474)
			(xy 144.585436 -294.160702)
		)
		(stroke
			(width 0)
			(type solid)
		)
		(fill yes)
		(layer "In13.Cu")
		(net "M_H_CPU1_SB_DQ<29>")
	)
	(gr_poly
		(pts
			(xy 144.624044 -292.518338) (xy 144.660874 -292.381686) (xy 144.524222 -292.34511) (xy 144.485614 -292.367462)
			(xy 144.58569 -292.54069)
		)
		(stroke
			(width 0)
			(type solid)
		)
		(fill yes)
		(layer "In13.Cu")
		(net "M_H_CPU1_SB_DQ<28>")
	)
	(gr_poly
		(pts
			(xy 144.660874 -270.370808) (xy 144.624044 -270.234156) (xy 144.58569 -270.211804) (xy 144.485614 -270.385032)
			(xy 144.524222 -270.407384)
		)
		(stroke
			(width 0)
			(type solid)
		)
		(fill yes)
		(layer "In13.Cu")
		(net "M_H_CPU1_SB_CB<7>")
	)
	(gr_poly
		(pts
			(xy 144.693894 -223.88576) (xy 144.655286 -223.863408) (xy 144.518634 -223.899984) (xy 144.555464 -224.036636)
			(xy 144.593818 -224.058988)
		)
		(stroke
			(width 0)
			(type solid)
		)
		(fill yes)
		(layer "In13.Cu")
		(net "M_H_CPU1_SA_DQ<4>")
	)
	(gr_poly
		(pts
			(xy 144.696688 -222.266764) (xy 144.65554 -222.243142) (xy 144.518888 -222.279718) (xy 144.555464 -222.41637)
			(xy 144.596612 -222.439992)
		)
		(stroke
			(width 0)
			(type solid)
		)
		(fill yes)
		(layer "In13.Cu")
		(net "M_H_CPU1_SA_DQS_DN<5>")
	)
	(gr_poly
		(pts
			(xy 144.762982 -256.432812) (xy 144.762982 -256.385314) (xy 144.563084 -256.385314) (xy 144.563084 -256.432812)
			(xy 144.66316 -256.532888)
		)
		(stroke
			(width 0)
			(type solid)
		)
		(fill yes)
		(layer "In13.Cu")
		(net "M_H_CPU1_CLK_DN<0>")
	)
	(gr_poly
		(pts
			(xy 144.766792 -247.116092) (xy 144.66697 -247.01627) (xy 144.566894 -247.116092) (xy 144.566894 -247.163844)
			(xy 144.766792 -247.163844)
		)
		(stroke
			(width 0)
			(type solid)
		)
		(fill yes)
		(layer "In13.Cu")
		(net "M_H_CPU1_SA_DQS_DN<9>")
	)
	(gr_poly
		(pts
			(xy 144.766792 -246.71274) (xy 144.766792 -246.664988) (xy 144.566894 -246.664988) (xy 144.566894 -246.71274)
			(xy 144.66697 -246.812562)
		)
		(stroke
			(width 0)
			(type solid)
		)
		(fill yes)
		(layer "In13.Cu")
		(net "M_H_CPU1_SA_DQS_DN<4>")
	)
	(gr_poly
		(pts
			(xy 144.766792 -241.852704) (xy 144.766792 -241.804952) (xy 144.566894 -241.804952) (xy 144.566894 -241.852704)
			(xy 144.66697 -241.952526)
		)
		(stroke
			(width 0)
			(type solid)
		)
		(fill yes)
		(layer "In13.Cu")
		(net "M_H_CPU1_SA_DQS_DN<3>")
	)
	(gr_poly
		(pts
			(xy 144.772126 -255.216406) (xy 144.67205 -255.11633) (xy 144.571974 -255.216406) (xy 144.571974 -255.260856)
			(xy 144.772126 -255.260856)
		)
		(stroke
			(width 0)
			(type solid)
		)
		(fill yes)
		(layer "In13.Cu")
		(net "M_H_CPU1_SA_CA<6>")
	)
	(gr_poly
		(pts
			(xy 144.772126 -254.812546) (xy 144.772126 -254.768096) (xy 144.571974 -254.768096) (xy 144.571974 -254.812546)
			(xy 144.67205 -254.912622)
		)
		(stroke
			(width 0)
			(type solid)
		)
		(fill yes)
		(layer "In13.Cu")
		(net "M_H_CPU1_SA_CA<5>")
	)
	(gr_poly
		(pts
			(xy 144.772126 -253.596394) (xy 144.67205 -253.496318) (xy 144.571974 -253.596394) (xy 144.571974 -253.640844)
			(xy 144.772126 -253.640844)
		)
		(stroke
			(width 0)
			(type solid)
		)
		(fill yes)
		(layer "In13.Cu")
		(net "M_H_CPU1_SA_CA<2>")
	)
	(gr_poly
		(pts
			(xy 144.772126 -253.192534) (xy 144.772126 -253.148084) (xy 144.571974 -253.148084) (xy 144.571974 -253.192534)
			(xy 144.67205 -253.29261)
		)
		(stroke
			(width 0)
			(type solid)
		)
		(fill yes)
		(layer "In13.Cu")
		(net "M_H_CPU1_SA_CA<1>")
	)
	(gr_poly
		(pts
			(xy 144.772126 -251.976382) (xy 144.67205 -251.876306) (xy 144.571974 -251.976382) (xy 144.571974 -252.020832)
			(xy 144.772126 -252.020832)
		)
		(stroke
			(width 0)
			(type solid)
		)
		(fill yes)
		(layer "In13.Cu")
		(net "M_H_CPU1_SA_CS_N<1>")
	)
	(gr_poly
		(pts
			(xy 144.772126 -250.35637) (xy 144.67205 -250.256294) (xy 144.571974 -250.35637) (xy 144.571974 -250.40082)
			(xy 144.772126 -250.40082)
		)
		(stroke
			(width 0)
			(type solid)
		)
		(fill yes)
		(layer "In13.Cu")
		(net "M_H_CPU1_ALERT_R_N")
	)
	(gr_poly
		(pts
			(xy 144.772126 -248.736358) (xy 144.67205 -248.636282) (xy 144.571974 -248.736358) (xy 144.571974 -248.780808)
			(xy 144.772126 -248.780808)
		)
		(stroke
			(width 0)
			(type solid)
		)
		(fill yes)
		(layer "In13.Cu")
		(net "M_H_CPU1_SA_CB<5>")
	)
	(gr_poly
		(pts
			(xy 144.772126 -248.332498) (xy 144.772126 -248.288048) (xy 144.571974 -248.288048) (xy 144.571974 -248.332498)
			(xy 144.67205 -248.432574)
		)
		(stroke
			(width 0)
			(type solid)
		)
		(fill yes)
		(layer "In13.Cu")
		(net "M_H_CPU1_SA_CB<6>")
	)
	(gr_poly
		(pts
			(xy 144.772126 -245.496334) (xy 144.67205 -245.396258) (xy 144.571974 -245.496334) (xy 144.571974 -245.540784)
			(xy 144.772126 -245.540784)
		)
		(stroke
			(width 0)
			(type solid)
		)
		(fill yes)
		(layer "In13.Cu")
		(net "M_H_CPU1_SA_CB<1>")
	)
	(gr_poly
		(pts
			(xy 144.772126 -245.092474) (xy 144.772126 -245.048024) (xy 144.571974 -245.048024) (xy 144.571974 -245.092474)
			(xy 144.67205 -245.19255)
		)
		(stroke
			(width 0)
			(type solid)
		)
		(fill yes)
		(layer "In13.Cu")
		(net "M_H_CPU1_SA_CB<2>")
	)
	(gr_poly
		(pts
			(xy 144.772126 -243.876322) (xy 144.67205 -243.776246) (xy 144.571974 -243.876322) (xy 144.571974 -243.920772)
			(xy 144.772126 -243.920772)
		)
		(stroke
			(width 0)
			(type solid)
		)
		(fill yes)
		(layer "In13.Cu")
		(net "M_H_CPU1_SA_DQ<29>")
	)
	(gr_poly
		(pts
			(xy 144.772126 -243.472462) (xy 144.772126 -243.428012) (xy 144.571974 -243.428012) (xy 144.571974 -243.472462)
			(xy 144.67205 -243.572538)
		)
		(stroke
			(width 0)
			(type solid)
		)
		(fill yes)
		(layer "In13.Cu")
		(net "M_H_CPU1_SA_DQ<30>")
	)
	(gr_poly
		(pts
			(xy 144.772126 -240.636298) (xy 144.67205 -240.536222) (xy 144.571974 -240.636298) (xy 144.571974 -240.680748)
			(xy 144.772126 -240.680748)
		)
		(stroke
			(width 0)
			(type solid)
		)
		(fill yes)
		(layer "In13.Cu")
		(net "M_H_CPU1_SA_DQ<25>")
	)
	(gr_poly
		(pts
			(xy 144.772126 -240.232438) (xy 144.772126 -240.187988) (xy 144.571974 -240.187988) (xy 144.571974 -240.232438)
			(xy 144.67205 -240.332514)
		)
		(stroke
			(width 0)
			(type solid)
		)
		(fill yes)
		(layer "In13.Cu")
		(net "M_H_CPU1_SA_DQ<26>")
	)
	(gr_poly
		(pts
			(xy 144.772126 -239.016286) (xy 144.67205 -238.91621) (xy 144.571974 -239.016286) (xy 144.571974 -239.060736)
			(xy 144.772126 -239.060736)
		)
		(stroke
			(width 0)
			(type solid)
		)
		(fill yes)
		(layer "In13.Cu")
		(net "M_H_CPU1_SA_DQ<21>")
	)
	(gr_poly
		(pts
			(xy 144.772126 -238.612426) (xy 144.772126 -238.567976) (xy 144.571974 -238.567976) (xy 144.571974 -238.612426)
			(xy 144.67205 -238.712502)
		)
		(stroke
			(width 0)
			(type solid)
		)
		(fill yes)
		(layer "In13.Cu")
		(net "M_H_CPU1_SA_DQ<22>")
	)
	(gr_poly
		(pts
			(xy 144.780508 -237.39602) (xy 144.680432 -237.295944) (xy 144.58061 -237.39602) (xy 144.58061 -237.443518)
			(xy 144.780508 -237.443518)
		)
		(stroke
			(width 0)
			(type solid)
		)
		(fill yes)
		(layer "In13.Cu")
		(net "M_H_CPU1_SA_DQS_DN<7>")
	)
	(gr_poly
		(pts
			(xy 144.798796 -236.991906) (xy 144.798796 -236.944408) (xy 144.598898 -236.944408) (xy 144.598898 -236.991906)
			(xy 144.698974 -237.091982)
		)
		(stroke
			(width 0)
			(type solid)
		)
		(fill yes)
		(layer "In13.Cu")
		(net "M_H_CPU1_SA_DQS_DN<2>")
	)
	(gr_poly
		(pts
			(xy 144.828514 -222.952564) (xy 144.791938 -222.815912) (xy 144.750536 -222.792036) (xy 144.65046 -222.965264)
			(xy 144.691862 -222.98914)
		)
		(stroke
			(width 0)
			(type solid)
		)
		(fill yes)
		(layer "In13.Cu")
		(net "M_H_CPU1_SA_DQS_DP<5>")
	)
	(gr_poly
		(pts
			(xy 144.830546 -224.56902) (xy 144.79397 -224.432368) (xy 144.755616 -224.410016) (xy 144.65554 -224.583244)
			(xy 144.694148 -224.605596)
		)
		(stroke
			(width 0)
			(type solid)
		)
		(fill yes)
		(layer "In13.Cu")
		(net "M_H_CPU1_SA_DQ<6>")
	)
	(gr_poly
		(pts
			(xy 144.993868 -295.494964) (xy 144.893792 -295.321736) (xy 144.855438 -295.344088) (xy 144.818862 -295.48074)
			(xy 144.95526 -295.517316)
		)
		(stroke
			(width 0)
			(type solid)
		)
		(fill yes)
		(layer "In13.Cu")
		(net "M_H_CPU1_SB_DQ<31>")
	)
	(gr_poly
		(pts
			(xy 144.993868 -293.874952) (xy 144.893792 -293.701724) (xy 144.855438 -293.724076) (xy 144.818862 -293.860728)
			(xy 144.95526 -293.897304)
		)
		(stroke
			(width 0)
			(type solid)
		)
		(fill yes)
		(layer "In13.Cu")
		(net "M_H_CPU1_SB_DQ<30>")
	)
	(gr_poly
		(pts
			(xy 144.996662 -270.498316) (xy 144.955514 -270.47444) (xy 144.818862 -270.51127) (xy 144.855438 -270.647668)
			(xy 144.89684 -270.671544)
		)
		(stroke
			(width 0)
			(type solid)
		)
		(fill yes)
		(layer "In13.Cu")
		(net "M_H_CPU1_SB_DQS_DP<9>")
	)
	(gr_poly
		(pts
			(xy 145.056098 -277.12162) (xy 145.056098 -277.074122) (xy 144.855946 -277.074122) (xy 144.855946 -277.12162)
			(xy 144.956022 -277.221696)
		)
		(stroke
			(width 0)
			(type solid)
		)
		(fill yes)
		(layer "In13.Cu")
		(net "M_H_CPU1_SB_DQS_DP<5>")
	)
	(gr_poly
		(pts
			(xy 145.066766 -281.984704) (xy 145.066766 -281.936952) (xy 144.866868 -281.936952) (xy 144.866868 -281.984704)
			(xy 144.966944 -282.084526)
		)
		(stroke
			(width 0)
			(type solid)
		)
		(fill yes)
		(layer "In13.Cu")
		(net "M_H_CPU1_SB_DQS_DP<6>")
	)
	(gr_poly
		(pts
			(xy 145.0721 -285.224474) (xy 145.0721 -285.180024) (xy 144.871948 -285.180024) (xy 144.871948 -285.224474)
			(xy 144.972024 -285.32455)
		)
		(stroke
			(width 0)
			(type solid)
		)
		(fill yes)
		(layer "In13.Cu")
		(net "M_H_CPU1_SB_DQ<19>")
	)
	(gr_poly
		(pts
			(xy 145.0721 -283.604462) (xy 145.0721 -283.560012) (xy 144.871948 -283.560012) (xy 144.871948 -283.604462)
			(xy 144.972024 -283.704538)
		)
		(stroke
			(width 0)
			(type solid)
		)
		(fill yes)
		(layer "In13.Cu")
		(net "M_H_CPU1_SB_DQ<15>")
	)
	(gr_poly
		(pts
			(xy 145.0721 -280.364438) (xy 145.0721 -280.319988) (xy 144.871948 -280.319988) (xy 144.871948 -280.364438)
			(xy 144.972024 -280.464514)
		)
		(stroke
			(width 0)
			(type solid)
		)
		(fill yes)
		(layer "In13.Cu")
		(net "M_H_CPU1_SB_DQ<11>")
	)
	(gr_poly
		(pts
			(xy 145.0721 -278.744426) (xy 145.0721 -278.699976) (xy 144.871948 -278.699976) (xy 144.871948 -278.744426)
			(xy 144.972024 -278.844502)
		)
		(stroke
			(width 0)
			(type solid)
		)
		(fill yes)
		(layer "In13.Cu")
		(net "M_H_CPU1_SB_DQ<7>")
	)
	(gr_poly
		(pts
			(xy 145.0721 -275.504402) (xy 145.0721 -275.459952) (xy 144.871948 -275.459952) (xy 144.871948 -275.504402)
			(xy 144.972024 -275.604478)
		)
		(stroke
			(width 0)
			(type solid)
		)
		(fill yes)
		(layer "In13.Cu")
		(net "M_H_CPU1_SB_DQ<3>")
	)
	(gr_poly
		(pts
			(xy 145.0721 -273.88439) (xy 145.0721 -273.83994) (xy 144.871948 -273.83994) (xy 144.871948 -273.88439)
			(xy 144.972024 -273.984466)
		)
		(stroke
			(width 0)
			(type solid)
		)
		(fill yes)
		(layer "In13.Cu")
		(net "M_H_CPU1_SB_CB<3>")
	)
	(gr_poly
		(pts
			(xy 145.0721 -265.78433) (xy 145.0721 -265.73988) (xy 144.871948 -265.73988) (xy 144.871948 -265.78433)
			(xy 144.972024 -265.884406)
		)
		(stroke
			(width 0)
			(type solid)
		)
		(fill yes)
		(layer "In13.Cu")
		(net "M_H_CPU1_SB_CS_N<0>")
	)
	(gr_poly
		(pts
			(xy 145.0721 -264.164318) (xy 145.0721 -264.119868) (xy 144.871948 -264.119868) (xy 144.871948 -264.164318)
			(xy 144.972024 -264.264394)
		)
		(stroke
			(width 0)
			(type solid)
		)
		(fill yes)
		(layer "In13.Cu")
		(net "M_H_CPU1_SB_CA<5>")
	)
	(gr_poly
		(pts
			(xy 145.0721 -262.544306) (xy 145.0721 -262.499856) (xy 144.871948 -262.499856) (xy 144.871948 -262.544306)
			(xy 144.972024 -262.644382)
		)
		(stroke
			(width 0)
			(type solid)
		)
		(fill yes)
		(layer "In13.Cu")
		(net "M_H_CPU1_SB_CA<1>")
	)
	(gr_poly
		(pts
			(xy 145.074894 -269.428214) (xy 144.974818 -269.328138) (xy 144.874742 -269.428214) (xy 144.874742 -269.472664)
			(xy 145.074894 -269.472664)
		)
		(stroke
			(width 0)
			(type solid)
		)
		(fill yes)
		(layer "In13.Cu")
		(net "M_H_CPU1_SB_CB<5>")
	)
	(gr_poly
		(pts
			(xy 145.074894 -269.024354) (xy 145.074894 -268.979904) (xy 144.874742 -268.979904) (xy 144.874742 -269.024354)
			(xy 144.974818 -269.12443)
		)
		(stroke
			(width 0)
			(type solid)
		)
		(fill yes)
		(layer "In13.Cu")
		(net "M_H_CPU1_SB_CB<6>")
	)
	(gr_poly
		(pts
			(xy 145.086324 -290.487608) (xy 144.986248 -290.387532) (xy 144.886426 -290.487608) (xy 144.886426 -290.535106)
			(xy 145.086324 -290.535106)
		)
		(stroke
			(width 0)
			(type solid)
		)
		(fill yes)
		(layer "In13.Cu")
		(net "M_H_CPU1_SB_DQS_DP<3>")
	)
	(gr_poly
		(pts
			(xy 145.086324 -285.627826) (xy 144.986248 -285.52775) (xy 144.886426 -285.627826) (xy 144.886426 -285.675324)
			(xy 145.086324 -285.675324)
		)
		(stroke
			(width 0)
			(type solid)
		)
		(fill yes)
		(layer "In13.Cu")
		(net "M_H_CPU1_SB_DQS_DP<2>")
	)
	(gr_poly
		(pts
			(xy 145.086324 -284.007814) (xy 144.986248 -283.907738) (xy 144.886426 -284.007814) (xy 144.886426 -284.052264)
			(xy 145.086324 -284.052264)
		)
		(stroke
			(width 0)
			(type solid)
		)
		(fill yes)
		(layer "In13.Cu")
		(net "M_H_CPU1_SB_DQ<16>")
	)
	(gr_poly
		(pts
			(xy 145.086324 -282.387802) (xy 144.986248 -282.287726) (xy 144.886426 -282.387802) (xy 144.886426 -282.432252)
			(xy 145.086324 -282.432252)
		)
		(stroke
			(width 0)
			(type solid)
		)
		(fill yes)
		(layer "In13.Cu")
		(net "M_H_CPU1_SB_DQ<12>")
	)
	(gr_poly
		(pts
			(xy 145.086324 -280.76779) (xy 144.986248 -280.667714) (xy 144.886426 -280.76779) (xy 144.886426 -280.815288)
			(xy 145.086324 -280.815288)
		)
		(stroke
			(width 0)
			(type solid)
		)
		(fill yes)
		(layer "In13.Cu")
		(net "M_H_CPU1_SB_DQS_DP<1>")
	)
	(gr_poly
		(pts
			(xy 145.086324 -279.147778) (xy 144.986248 -279.047702) (xy 144.886426 -279.147778) (xy 144.886426 -279.192228)
			(xy 145.086324 -279.192228)
		)
		(stroke
			(width 0)
			(type solid)
		)
		(fill yes)
		(layer "In13.Cu")
		(net "M_H_CPU1_SB_DQ<8>")
	)
	(gr_poly
		(pts
			(xy 145.086324 -277.527766) (xy 144.986248 -277.42769) (xy 144.886426 -277.527766) (xy 144.886426 -277.572216)
			(xy 145.086324 -277.572216)
		)
		(stroke
			(width 0)
			(type solid)
		)
		(fill yes)
		(layer "In13.Cu")
		(net "M_H_CPU1_SB_DQ<4>")
	)
	(gr_poly
		(pts
			(xy 145.086324 -275.907754) (xy 144.986248 -275.807678) (xy 144.886426 -275.907754) (xy 144.886426 -275.955252)
			(xy 145.086324 -275.955252)
		)
		(stroke
			(width 0)
			(type solid)
		)
		(fill yes)
		(layer "In13.Cu")
		(net "M_H_CPU1_SB_DQS_DP<0>")
	)
	(gr_poly
		(pts
			(xy 145.086324 -274.287742) (xy 144.986248 -274.187666) (xy 144.886426 -274.287742) (xy 144.886426 -274.332192)
			(xy 145.086324 -274.332192)
		)
		(stroke
			(width 0)
			(type solid)
		)
		(fill yes)
		(layer "In13.Cu")
		(net "M_H_CPU1_SB_DQ<0>")
	)
	(gr_poly
		(pts
			(xy 145.086324 -272.66773) (xy 144.986248 -272.567654) (xy 144.886426 -272.66773) (xy 144.886426 -272.71218)
			(xy 145.086324 -272.71218)
		)
		(stroke
			(width 0)
			(type solid)
		)
		(fill yes)
		(layer "In13.Cu")
		(net "M_H_CPU1_SB_CB<0>")
	)
	(gr_poly
		(pts
			(xy 145.086324 -267.807694) (xy 144.986248 -267.707618) (xy 144.886426 -267.807694) (xy 144.886426 -267.852144)
			(xy 145.086324 -267.852144)
		)
		(stroke
			(width 0)
			(type solid)
		)
		(fill yes)
		(layer "In13.Cu")
		(net "M_H_CPU1_SB_RSP<0>")
	)
	(gr_poly
		(pts
			(xy 145.086324 -264.56767) (xy 144.986248 -264.467594) (xy 144.886426 -264.56767) (xy 144.886426 -264.61212)
			(xy 145.086324 -264.61212)
		)
		(stroke
			(width 0)
			(type solid)
		)
		(fill yes)
		(layer "In13.Cu")
		(net "M_H_CPU1_SB_CA<6>")
	)
	(gr_poly
		(pts
			(xy 145.086324 -262.947658) (xy 144.986248 -262.847582) (xy 144.886426 -262.947658) (xy 144.886426 -262.992108)
			(xy 145.086324 -262.992108)
		)
		(stroke
			(width 0)
			(type solid)
		)
		(fill yes)
		(layer "In13.Cu")
		(net "M_H_CPU1_SB_CA<2>")
	)
	(gr_poly
		(pts
			(xy 145.09369 -294.948356) (xy 145.130266 -294.811704) (xy 144.993868 -294.775128) (xy 144.95526 -294.79748)
			(xy 145.055336 -294.970708)
		)
		(stroke
			(width 0)
			(type solid)
		)
		(fill yes)
		(layer "In13.Cu")
		(net "M_H_CPU1_SB_DQ<29>")
	)
	(gr_poly
		(pts
			(xy 145.093944 -293.328344) (xy 145.130774 -293.191692) (xy 144.994122 -293.155116) (xy 144.955514 -293.177468)
			(xy 145.05559 -293.350696)
		)
		(stroke
			(width 0)
			(type solid)
		)
		(fill yes)
		(layer "In13.Cu")
		(net "M_H_CPU1_SB_DQ<28>")
	)
	(gr_poly
		(pts
			(xy 145.093944 -291.70757) (xy 145.13052 -291.571172) (xy 144.993868 -291.534596) (xy 144.95272 -291.558218)
			(xy 145.052542 -291.731446)
		)
		(stroke
			(width 0)
			(type solid)
		)
		(fill yes)
		(layer "In13.Cu")
		(net "M_H_CPU1_SB_DQS_DN<8>")
	)
	(gr_poly
		(pts
			(xy 145.13052 -271.181322) (xy 145.093944 -271.044924) (xy 145.052542 -271.021048) (xy 144.95272 -271.194276)
			(xy 144.993868 -271.218152)
		)
		(stroke
			(width 0)
			(type solid)
		)
		(fill yes)
		(layer "In13.Cu")
		(net "M_H_CPU1_SB_DQS_DN<9>")
	)
	(gr_poly
		(pts
			(xy 145.164556 -223.074738) (xy 145.125948 -223.05264) (xy 144.989296 -223.089216) (xy 145.025872 -223.225868)
			(xy 145.06448 -223.24822)
		)
		(stroke
			(width 0)
			(type solid)
		)
		(fill yes)
		(layer "In13.Cu")
		(net "M_H_CPU1_SA_DQ<4>")
	)
	(gr_poly
		(pts
			(xy 145.23593 -237.802674) (xy 145.23593 -237.755176) (xy 145.036032 -237.755176) (xy 145.036032 -237.802674)
			(xy 145.136108 -237.90275)
		)
		(stroke
			(width 0)
			(type solid)
		)
		(fill yes)
		(layer "In13.Cu")
		(net "M_H_CPU1_SA_DQS_DP<7>")
	)
	(gr_poly
		(pts
			(xy 145.254218 -254.406146) (xy 145.154396 -254.306324) (xy 145.05432 -254.406146) (xy 145.05432 -254.450596)
			(xy 145.254218 -254.450596)
		)
		(stroke
			(width 0)
			(type solid)
		)
		(fill yes)
		(layer "In13.Cu")
		(net "M_H_CPU1_SA_CA<4>")
	)
	(gr_poly
		(pts
			(xy 145.254218 -254.002794) (xy 145.254218 -253.958344) (xy 145.05432 -253.958344) (xy 145.05432 -254.002794)
			(xy 145.154396 -254.102616)
		)
		(stroke
			(width 0)
			(type solid)
		)
		(fill yes)
		(layer "In13.Cu")
		(net "M_H_CPU1_SA_CA<3>")
	)
	(gr_poly
		(pts
			(xy 145.254218 -252.786134) (xy 145.154396 -252.686312) (xy 145.05432 -252.786134) (xy 145.05432 -252.830584)
			(xy 145.254218 -252.830584)
		)
		(stroke
			(width 0)
			(type solid)
		)
		(fill yes)
		(layer "In13.Cu")
		(net "M_H_CPU1_SA_CA<0>")
	)
	(gr_poly
		(pts
			(xy 145.254218 -251.166122) (xy 145.154396 -251.0663) (xy 145.05432 -251.166122) (xy 145.05432 -251.210572)
			(xy 145.254218 -251.210572)
		)
		(stroke
			(width 0)
			(type solid)
		)
		(fill yes)
		(layer "In13.Cu")
		(net "M_H_CPU1_SA_CS_N<0>")
	)
	(gr_poly
		(pts
			(xy 145.254218 -249.142758) (xy 145.254218 -249.098308) (xy 145.05432 -249.098308) (xy 145.05432 -249.142758)
			(xy 145.154396 -249.24258)
		)
		(stroke
			(width 0)
			(type solid)
		)
		(fill yes)
		(layer "In13.Cu")
		(net "M_H_CPU1_SA_CB<7>")
	)
	(gr_poly
		(pts
			(xy 145.254218 -247.926098) (xy 145.154396 -247.826276) (xy 145.05432 -247.926098) (xy 145.05432 -247.970548)
			(xy 145.254218 -247.970548)
		)
		(stroke
			(width 0)
			(type solid)
		)
		(fill yes)
		(layer "In13.Cu")
		(net "M_H_CPU1_SA_CB<4>")
	)
	(gr_poly
		(pts
			(xy 145.254218 -245.902734) (xy 145.254218 -245.858284) (xy 145.05432 -245.858284) (xy 145.05432 -245.902734)
			(xy 145.154396 -246.002556)
		)
		(stroke
			(width 0)
			(type solid)
		)
		(fill yes)
		(layer "In13.Cu")
		(net "M_H_CPU1_SA_CB<3>")
	)
	(gr_poly
		(pts
			(xy 145.257266 -256.026158) (xy 145.15719 -255.926082) (xy 145.057114 -256.026158) (xy 145.057114 -256.073656)
			(xy 145.257266 -256.073656)
		)
		(stroke
			(width 0)
			(type solid)
		)
		(fill yes)
		(layer "In13.Cu")
		(net "M_H_CPU1_CLK_DP<0>")
	)
	(gr_poly
		(pts
			(xy 145.257266 -247.522746) (xy 145.257266 -247.475248) (xy 145.057114 -247.475248) (xy 145.057114 -247.522746)
			(xy 145.15719 -247.622822)
		)
		(stroke
			(width 0)
			(type solid)
		)
		(fill yes)
		(layer "In13.Cu")
		(net "M_H_CPU1_SA_DQS_DP<9>")
	)
	(gr_poly
		(pts
			(xy 145.257266 -246.306086) (xy 145.15719 -246.20601) (xy 145.057114 -246.306086) (xy 145.057114 -246.353584)
			(xy 145.257266 -246.353584)
		)
		(stroke
			(width 0)
			(type solid)
		)
		(fill yes)
		(layer "In13.Cu")
		(net "M_H_CPU1_SA_DQS_DP<4>")
	)
	(gr_poly
		(pts
			(xy 145.299938 -223.760284) (xy 145.263362 -223.623632) (xy 145.224754 -223.601534) (xy 145.124678 -223.774762)
			(xy 145.163286 -223.79686)
		)
		(stroke
			(width 0)
			(type solid)
		)
		(fill yes)
		(layer "In13.Cu")
		(net "M_H_CPU1_SA_DQ<6>")
	)
	(gr_poly
		(pts
			(xy 145.523458 -276.314916) (xy 145.523458 -276.267164) (xy 145.32356 -276.267164) (xy 145.32356 -276.314916)
			(xy 145.423636 -276.414992)
		)
		(stroke
			(width 0)
			(type solid)
		)
		(fill yes)
		(layer "In13.Cu")
		(net "M_H_CPU1_SB_DQS_DN<0>")
	)
	(gr_poly
		(pts
			(xy 145.524982 -273.074638) (xy 145.524982 -273.030188) (xy 145.325084 -273.030188) (xy 145.325084 -273.074638)
			(xy 145.42516 -273.174714)
		)
		(stroke
			(width 0)
			(type solid)
		)
		(fill yes)
		(layer "In13.Cu")
		(net "M_H_CPU1_SB_CB<2>")
	)
	(gr_poly
		(pts
			(xy 145.544794 -269.83436) (xy 145.544794 -269.78991) (xy 145.344642 -269.78991) (xy 145.344642 -269.83436)
			(xy 145.444718 -269.934436)
		)
		(stroke
			(width 0)
			(type solid)
		)
		(fill yes)
		(layer "In13.Cu")
		(net "M_H_CPU1_SB_CB<7>")
	)
	(gr_poly
		(pts
			(xy 145.563844 -294.13835) (xy 145.600674 -294.001698) (xy 145.464022 -293.965122) (xy 145.425414 -293.987474)
			(xy 145.52549 -294.160702)
		)
		(stroke
			(width 0)
			(type solid)
		)
		(fill yes)
		(layer "In13.Cu")
		(net "M_H_CPU1_SB_DQ<28>")
	)
	(gr_poly
		(pts
			(xy 145.706846 -253.59614) (xy 145.607024 -253.496064) (xy 145.506948 -253.59614) (xy 145.506948 -253.64059)
			(xy 145.706846 -253.64059)
		)
		(stroke
			(width 0)
			(type solid)
		)
		(fill yes)
		(layer "In13.Cu")
		(net "M_H_CPU1_SA_CA<2>")
	)
	(gr_poly
		(pts
			(xy 145.706846 -248.736104) (xy 145.607024 -248.636028) (xy 145.506948 -248.736104) (xy 145.506948 -248.780554)
			(xy 145.706846 -248.780554)
		)
		(stroke
			(width 0)
			(type solid)
		)
		(fill yes)
		(layer "In13.Cu")
		(net "M_H_CPU1_SA_CB<5>")
	)
	(gr_poly
		(pts
			(xy 145.706846 -245.49608) (xy 145.607024 -245.396004) (xy 145.506948 -245.49608) (xy 145.506948 -245.54053)
			(xy 145.706846 -245.54053)
		)
		(stroke
			(width 0)
			(type solid)
		)
		(fill yes)
		(layer "In13.Cu")
		(net "M_H_CPU1_SA_CB<1>")
	)
	(gr_poly
		(pts
			(xy 145.708116 -247.115838) (xy 145.608294 -247.016016) (xy 145.508218 -247.115838) (xy 145.508218 -247.16359)
			(xy 145.708116 -247.16359)
		)
		(stroke
			(width 0)
			(type solid)
		)
		(fill yes)
		(layer "In13.Cu")
		(net "M_H_CPU1_SA_DQS_DN<9>")
	)
	(gr_poly
		(pts
			(xy 326.204072 -294.781478) (xy 326.165718 -294.759126) (xy 326.029066 -294.795702) (xy 326.065642 -294.932354)
			(xy 326.10425 -294.954706)
		)
		(stroke
			(width 0)
			(type solid)
		)
		(fill yes)
		(layer "In13.Cu")
		(net "M_B_CPU0_SB_DQ<28>")
	)
	(gr_poly
		(pts
			(xy 326.325484 -223.72828) (xy 326.257158 -223.54032) (xy 326.215248 -223.55556) (xy 326.155558 -223.68383)
			(xy 326.283828 -223.74352)
		)
		(stroke
			(width 0)
			(type solid)
		)
		(fill yes)
		(layer "In13.Cu")
		(net "M_B_CPU0_SA_DQ<6>")
	)
	(gr_poly
		(pts
			(xy 326.438514 -247.522492) (xy 326.438514 -247.474994) (xy 326.238616 -247.474994) (xy 326.238616 -247.522492)
			(xy 326.338692 -247.622568)
		)
		(stroke
			(width 0)
			(type solid)
		)
		(fill yes)
		(layer "In13.Cu")
		(net "M_B_CPU0_SA_DQS_DP<9>")
	)
	(gr_poly
		(pts
			(xy 326.438514 -242.662456) (xy 326.438514 -242.614958) (xy 326.238616 -242.614958) (xy 326.238616 -242.662456)
			(xy 326.338692 -242.762532)
		)
		(stroke
			(width 0)
			(type solid)
		)
		(fill yes)
		(layer "In13.Cu")
		(net "M_B_CPU0_SA_DQS_DP<8>")
	)
	(gr_poly
		(pts
			(xy 326.441562 -254.00254) (xy 326.441562 -253.95809) (xy 326.24141 -253.95809) (xy 326.24141 -254.00254)
			(xy 326.341486 -254.102362)
		)
		(stroke
			(width 0)
			(type solid)
		)
		(fill yes)
		(layer "In13.Cu")
		(net "M_B_CPU0_SA_CA<3>")
	)
	(gr_poly
		(pts
			(xy 326.441562 -252.382528) (xy 326.441562 -252.338078) (xy 326.24141 -252.338078) (xy 326.24141 -252.382528)
			(xy 326.341486 -252.48235)
		)
		(stroke
			(width 0)
			(type solid)
		)
		(fill yes)
		(layer "In13.Cu")
		(net "M_B_CPU0_SA_CS_N<1>")
	)
	(gr_poly
		(pts
			(xy 326.441562 -249.142504) (xy 326.441562 -249.098054) (xy 326.24141 -249.098054) (xy 326.24141 -249.142504)
			(xy 326.341486 -249.242326)
		)
		(stroke
			(width 0)
			(type solid)
		)
		(fill yes)
		(layer "In13.Cu")
		(net "M_B_CPU0_SA_CB<7>")
	)
	(gr_poly
		(pts
			(xy 326.441562 -245.90248) (xy 326.441562 -245.85803) (xy 326.24141 -245.85803) (xy 326.24141 -245.90248)
			(xy 326.341486 -246.002302)
		)
		(stroke
			(width 0)
			(type solid)
		)
		(fill yes)
		(layer "In13.Cu")
		(net "M_B_CPU0_SA_CB<3>")
	)
	(gr_poly
		(pts
			(xy 326.441562 -244.282468) (xy 326.441562 -244.238018) (xy 326.24141 -244.238018) (xy 326.24141 -244.282468)
			(xy 326.341486 -244.38229)
		)
		(stroke
			(width 0)
			(type solid)
		)
		(fill yes)
		(layer "In13.Cu")
		(net "M_B_CPU0_SA_DQ<31>")
	)
	(gr_poly
		(pts
			(xy 326.468994 -223.223582) (xy 326.505824 -223.08693) (xy 326.369172 -223.050354) (xy 326.330564 -223.072706)
			(xy 326.43064 -223.245934)
		)
		(stroke
			(width 0)
			(type solid)
		)
		(fill yes)
		(layer "In13.Cu")
		(net "M_B_CPU0_SA_DQ<4>")
	)
	(gr_poly
		(pts
			(xy 326.470772 -254.405892) (xy 326.370696 -254.305816) (xy 326.270874 -254.405892) (xy 326.270874 -254.450342)
			(xy 326.470772 -254.450342)
		)
		(stroke
			(width 0)
			(type solid)
		)
		(fill yes)
		(layer "In13.Cu")
		(net "M_B_CPU0_SA_CA<4>")
	)
	(gr_poly
		(pts
			(xy 326.470772 -252.78588) (xy 326.370696 -252.685804) (xy 326.270874 -252.78588) (xy 326.270874 -252.83033)
			(xy 326.470772 -252.83033)
		)
		(stroke
			(width 0)
			(type solid)
		)
		(fill yes)
		(layer "In13.Cu")
		(net "M_B_CPU0_SA_CA<0>")
	)
	(gr_poly
		(pts
			(xy 326.470772 -247.925844) (xy 326.370696 -247.825768) (xy 326.270874 -247.925844) (xy 326.270874 -247.970294)
			(xy 326.470772 -247.970294)
		)
		(stroke
			(width 0)
			(type solid)
		)
		(fill yes)
		(layer "In13.Cu")
		(net "M_B_CPU0_SA_CB<4>")
	)
	(gr_poly
		(pts
			(xy 326.472296 -256.02565) (xy 326.37222 -255.925574) (xy 326.272398 -256.02565) (xy 326.272398 -256.073402)
			(xy 326.472296 -256.073402)
		)
		(stroke
			(width 0)
			(type solid)
		)
		(fill yes)
		(layer "In13.Cu")
		(net "M_B_CPU0_CLK_DP<0>")
	)
	(gr_poly
		(pts
			(xy 326.472296 -246.305578) (xy 326.37222 -246.205502) (xy 326.272398 -246.305578) (xy 326.272398 -246.353076)
			(xy 326.472296 -246.353076)
		)
		(stroke
			(width 0)
			(type solid)
		)
		(fill yes)
		(layer "In13.Cu")
		(net "M_B_CPU0_SA_DQS_DP<4>")
	)
	(gr_poly
		(pts
			(xy 326.670416 -293.986458) (xy 326.632062 -293.964106) (xy 326.49541 -294.000682) (xy 326.531986 -294.137334)
			(xy 326.570594 -294.159686)
		)
		(stroke
			(width 0)
			(type solid)
		)
		(fill yes)
		(layer "In13.Cu")
		(net "M_B_CPU0_SB_DQ<28>")
	)
	(gr_poly
		(pts
			(xy 326.741536 -289.677602) (xy 326.64146 -289.57778) (xy 326.541638 -289.677602) (xy 326.541638 -289.722052)
			(xy 326.741536 -289.722052)
		)
		(stroke
			(width 0)
			(type solid)
		)
		(fill yes)
		(layer "In13.Cu")
		(net "M_B_CPU0_SB_DQ<25>")
	)
	(gr_poly
		(pts
			(xy 326.741536 -286.437578) (xy 326.64146 -286.337756) (xy 326.541638 -286.437578) (xy 326.541638 -286.48533)
			(xy 326.741536 -286.48533)
		)
		(stroke
			(width 0)
			(type solid)
		)
		(fill yes)
		(layer "In13.Cu")
		(net "M_B_CPU0_SB_DQS_DN<7>")
	)
	(gr_poly
		(pts
			(xy 326.741536 -284.81782) (xy 326.64146 -284.717998) (xy 326.541638 -284.81782) (xy 326.541638 -284.86227)
			(xy 326.741536 -284.86227)
		)
		(stroke
			(width 0)
			(type solid)
		)
		(fill yes)
		(layer "In13.Cu")
		(net "M_B_CPU0_SB_DQ<17>")
	)
	(gr_poly
		(pts
			(xy 326.741536 -273.074384) (xy 326.741536 -273.029934) (xy 326.541638 -273.029934) (xy 326.541638 -273.074384)
			(xy 326.64146 -273.174206)
		)
		(stroke
			(width 0)
			(type solid)
		)
		(fill yes)
		(layer "In13.Cu")
		(net "M_B_CPU0_SB_CB<2>")
	)
	(gr_poly
		(pts
			(xy 326.741536 -269.83436) (xy 326.741536 -269.78991) (xy 326.541638 -269.78991) (xy 326.541638 -269.83436)
			(xy 326.64146 -269.934182)
		)
		(stroke
			(width 0)
			(type solid)
		)
		(fill yes)
		(layer "In13.Cu")
		(net "M_B_CPU0_SB_CB<6>")
	)
	(gr_poly
		(pts
			(xy 326.742298 -288.05759) (xy 326.642476 -287.957768) (xy 326.5424 -288.05759) (xy 326.5424 -288.10204)
			(xy 326.742298 -288.10204)
		)
		(stroke
			(width 0)
			(type solid)
		)
		(fill yes)
		(layer "In13.Cu")
		(net "M_B_CPU0_SB_DQ<21>")
	)
	(gr_poly
		(pts
			(xy 326.759824 -281.174444) (xy 326.759824 -281.126946) (xy 326.559926 -281.126946) (xy 326.559926 -281.174444)
			(xy 326.659748 -281.27452)
		)
		(stroke
			(width 0)
			(type solid)
		)
		(fill yes)
		(layer "In13.Cu")
		(net "M_B_CPU0_SB_DQS_DN<1>")
	)
	(gr_poly
		(pts
			(xy 326.840088 -224.582482) (xy 326.740266 -224.409254) (xy 326.701658 -224.431352) (xy 326.665082 -224.568004)
			(xy 326.801734 -224.60458)
		)
		(stroke
			(width 0)
			(type solid)
		)
		(fill yes)
		(layer "In13.Cu")
		(net "M_B_CPU0_SA_DQ<6>")
	)
	(gr_poly
		(pts
			(xy 326.844914 -222.964248) (xy 326.744838 -222.79102) (xy 326.70369 -222.814896) (xy 326.667114 -222.951548)
			(xy 326.803766 -222.988124)
		)
		(stroke
			(width 0)
			(type solid)
		)
		(fill yes)
		(layer "In13.Cu")
		(net "M_B_CPU0_SA_DQS_DP<5>")
	)
	(gr_poly
		(pts
			(xy 326.902318 -256.432812) (xy 326.902318 -256.38506) (xy 326.70242 -256.38506) (xy 326.70242 -256.432812)
			(xy 326.802496 -256.532888)
		)
		(stroke
			(width 0)
			(type solid)
		)
		(fill yes)
		(layer "In13.Cu")
		(net "M_B_CPU0_CLK_DN<0>")
	)
	(gr_poly
		(pts
			(xy 326.907398 -239.015524) (xy 326.807322 -238.915448) (xy 326.707246 -239.015524) (xy 326.707246 -239.059974)
			(xy 326.907398 -239.059974)
		)
		(stroke
			(width 0)
			(type solid)
		)
		(fill yes)
		(layer "In13.Cu")
		(net "M_B_CPU0_SA_DQ<21>")
	)
	(gr_poly
		(pts
			(xy 326.90943 -254.8128) (xy 326.90943 -254.76835) (xy 326.709532 -254.76835) (xy 326.709532 -254.8128)
			(xy 326.809608 -254.912876)
		)
		(stroke
			(width 0)
			(type solid)
		)
		(fill yes)
		(layer "In13.Cu")
		(net "M_B_CPU0_SA_CA<5>")
	)
	(gr_poly
		(pts
			(xy 326.90943 -253.192788) (xy 326.90943 -253.148338) (xy 326.709532 -253.148338) (xy 326.709532 -253.192788)
			(xy 326.809608 -253.292864)
		)
		(stroke
			(width 0)
			(type solid)
		)
		(fill yes)
		(layer "In13.Cu")
		(net "M_B_CPU0_SA_CA<1>")
	)
	(gr_poly
		(pts
			(xy 326.90943 -248.332752) (xy 326.90943 -248.288302) (xy 326.709532 -248.288302) (xy 326.709532 -248.332752)
			(xy 326.809608 -248.432828)
		)
		(stroke
			(width 0)
			(type solid)
		)
		(fill yes)
		(layer "In13.Cu")
		(net "M_B_CPU0_SA_CB<6>")
	)
	(gr_poly
		(pts
			(xy 326.90943 -246.71274) (xy 326.90943 -246.665242) (xy 326.709532 -246.665242) (xy 326.709532 -246.71274)
			(xy 326.809608 -246.812816)
		)
		(stroke
			(width 0)
			(type solid)
		)
		(fill yes)
		(layer "In13.Cu")
		(net "M_B_CPU0_SA_DQS_DN<4>")
	)
	(gr_poly
		(pts
			(xy 326.90943 -245.092728) (xy 326.90943 -245.048278) (xy 326.709532 -245.048278) (xy 326.709532 -245.092728)
			(xy 326.809608 -245.192804)
		)
		(stroke
			(width 0)
			(type solid)
		)
		(fill yes)
		(layer "In13.Cu")
		(net "M_B_CPU0_SA_CB<2>")
	)
	(gr_poly
		(pts
			(xy 326.90943 -243.472716) (xy 326.90943 -243.428266) (xy 326.709532 -243.428266) (xy 326.709532 -243.472716)
			(xy 326.809608 -243.572792)
		)
		(stroke
			(width 0)
			(type solid)
		)
		(fill yes)
		(layer "In13.Cu")
		(net "M_B_CPU0_SA_DQ<30>")
	)
	(gr_poly
		(pts
			(xy 326.90943 -240.232692) (xy 326.90943 -240.188242) (xy 326.709532 -240.188242) (xy 326.709532 -240.232692)
			(xy 326.809608 -240.332768)
		)
		(stroke
			(width 0)
			(type solid)
		)
		(fill yes)
		(layer "In13.Cu")
		(net "M_B_CPU0_SA_DQ<26>")
	)
	(gr_poly
		(pts
			(xy 326.90943 -238.61268) (xy 326.90943 -238.56823) (xy 326.709532 -238.56823) (xy 326.709532 -238.61268)
			(xy 326.809608 -238.712756)
		)
		(stroke
			(width 0)
			(type solid)
		)
		(fill yes)
		(layer "In13.Cu")
		(net "M_B_CPU0_SA_DQ<22>")
	)
	(gr_poly
		(pts
			(xy 326.90943 -237.395258) (xy 326.809354 -237.295182) (xy 326.709532 -237.395258) (xy 326.709532 -237.44301)
			(xy 326.90943 -237.44301)
		)
		(stroke
			(width 0)
			(type solid)
		)
		(fill yes)
		(layer "In13.Cu")
		(net "M_B_CPU0_SA_DQS_DN<7>")
	)
	(gr_poly
		(pts
			(xy 326.90943 -236.992668) (xy 326.90943 -236.94517) (xy 326.709532 -236.94517) (xy 326.709532 -236.992668)
			(xy 326.809608 -237.092744)
		)
		(stroke
			(width 0)
			(type solid)
		)
		(fill yes)
		(layer "In13.Cu")
		(net "M_B_CPU0_SA_DQS_DN<2>")
	)
	(gr_poly
		(pts
			(xy 326.915018 -251.572268) (xy 326.915018 -251.527818) (xy 326.714866 -251.527818) (xy 326.714866 -251.572268)
			(xy 326.814942 -251.672344)
		)
		(stroke
			(width 0)
			(type solid)
		)
		(fill yes)
		(layer "In13.Cu")
		(net "M_B_CPU0_SA_CS_N<0>")
	)
	(gr_poly
		(pts
			(xy 326.915018 -240.636044) (xy 326.814942 -240.535968) (xy 326.714866 -240.636044) (xy 326.714866 -240.680494)
			(xy 326.915018 -240.680494)
		)
		(stroke
			(width 0)
			(type solid)
		)
		(fill yes)
		(layer "In13.Cu")
		(net "M_B_CPU0_SA_DQ<25>")
	)
	(gr_poly
		(pts
			(xy 326.921114 -250.356116) (xy 326.821038 -250.25604) (xy 326.720962 -250.356116) (xy 326.720962 -250.400566)
			(xy 326.921114 -250.400566)
		)
		(stroke
			(width 0)
			(type solid)
		)
		(fill yes)
		(layer "In13.Cu")
		(net "M_B_CPU0_ALERT_R_N")
	)
	(gr_poly
		(pts
			(xy 326.921114 -241.85245) (xy 326.921114 -241.804698) (xy 326.720962 -241.804698) (xy 326.720962 -241.85245)
			(xy 326.821038 -241.952272)
		)
		(stroke
			(width 0)
			(type solid)
		)
		(fill yes)
		(layer "In13.Cu")
		(net "M_B_CPU0_SA_DQS_DN<3>")
	)
	(gr_poly
		(pts
			(xy 326.923908 -255.216152) (xy 326.823832 -255.116076) (xy 326.723756 -255.216152) (xy 326.723756 -255.260602)
			(xy 326.923908 -255.260602)
		)
		(stroke
			(width 0)
			(type solid)
		)
		(fill yes)
		(layer "In13.Cu")
		(net "M_B_CPU0_SA_CA<6>")
	)
	(gr_poly
		(pts
			(xy 326.923908 -253.59614) (xy 326.823832 -253.496064) (xy 326.723756 -253.59614) (xy 326.723756 -253.64059)
			(xy 326.923908 -253.64059)
		)
		(stroke
			(width 0)
			(type solid)
		)
		(fill yes)
		(layer "In13.Cu")
		(net "M_B_CPU0_SA_CA<2>")
	)
	(gr_poly
		(pts
			(xy 326.923908 -248.736104) (xy 326.823832 -248.636028) (xy 326.723756 -248.736104) (xy 326.723756 -248.780554)
			(xy 326.923908 -248.780554)
		)
		(stroke
			(width 0)
			(type solid)
		)
		(fill yes)
		(layer "In13.Cu")
		(net "M_B_CPU0_SA_CB<5>")
	)
	(gr_poly
		(pts
			(xy 326.923908 -245.49608) (xy 326.823832 -245.396004) (xy 326.723756 -245.49608) (xy 326.723756 -245.54053)
			(xy 326.923908 -245.54053)
		)
		(stroke
			(width 0)
			(type solid)
		)
		(fill yes)
		(layer "In13.Cu")
		(net "M_B_CPU0_SA_CB<1>")
	)
	(gr_poly
		(pts
			(xy 326.923908 -243.876068) (xy 326.823832 -243.775992) (xy 326.723756 -243.876068) (xy 326.723756 -243.920518)
			(xy 326.923908 -243.920518)
		)
		(stroke
			(width 0)
			(type solid)
		)
		(fill yes)
		(layer "In13.Cu")
		(net "M_B_CPU0_SA_DQ<29>")
	)
	(gr_poly
		(pts
			(xy 326.928988 -247.115838) (xy 326.828912 -247.016016) (xy 326.72909 -247.115838) (xy 326.72909 -247.16359)
			(xy 326.928988 -247.16359)
		)
		(stroke
			(width 0)
			(type solid)
		)
		(fill yes)
		(layer "In13.Cu")
		(net "M_B_CPU0_SA_DQS_DN<9>")
	)
	(gr_poly
		(pts
			(xy 326.932798 -242.255802) (xy 326.832722 -242.155726) (xy 326.732646 -242.255802) (xy 326.732646 -242.3033)
			(xy 326.932798 -242.3033)
		)
		(stroke
			(width 0)
			(type solid)
		)
		(fill yes)
		(layer "In13.Cu")
		(net "M_B_CPU0_SA_DQS_DN<8>")
	)
	(gr_poly
		(pts
			(xy 326.935592 -224.045272) (xy 326.983852 -223.912176) (xy 326.85101 -223.863916) (xy 326.810624 -223.882712)
			(xy 326.895206 -224.063814)
		)
		(stroke
			(width 0)
			(type solid)
		)
		(fill yes)
		(layer "In13.Cu")
		(net "M_B_CPU0_SA_DQ<4>")
	)
	(gr_poly
		(pts
			(xy 326.940418 -222.416116) (xy 326.976994 -222.279464) (xy 326.840342 -222.242888) (xy 326.799194 -222.26651)
			(xy 326.89927 -222.439738)
		)
		(stroke
			(width 0)
			(type solid)
		)
		(fill yes)
		(layer "In13.Cu")
		(net "M_B_CPU0_SA_DQS_DN<5>")
	)
	(gr_poly
		(pts
			(xy 326.940672 -225.656902) (xy 326.977248 -225.52025) (xy 326.840596 -225.48342) (xy 326.802242 -225.505772)
			(xy 326.902064 -225.679)
		)
		(stroke
			(width 0)
			(type solid)
		)
		(fill yes)
		(layer "In13.Cu")
		(net "M_B_CPU0_SA_DQ<5>")
	)
	(gr_poly
		(pts
			(xy 327.140316 -293.177214) (xy 327.101708 -293.154862) (xy 326.96531 -293.191438) (xy 327.001886 -293.32809)
			(xy 327.04024 -293.350442)
		)
		(stroke
			(width 0)
			(type solid)
		)
		(fill yes)
		(layer "In13.Cu")
		(net "M_B_CPU0_SB_DQ<28>")
	)
	(gr_poly
		(pts
			(xy 327.207372 -283.604716) (xy 327.207372 -283.560266) (xy 327.00722 -283.560266) (xy 327.00722 -283.604716)
			(xy 327.107296 -283.704792)
		)
		(stroke
			(width 0)
			(type solid)
		)
		(fill yes)
		(layer "In13.Cu")
		(net "M_B_CPU0_SB_DQ<15>")
	)
	(gr_poly
		(pts
			(xy 327.212198 -287.247838) (xy 327.112376 -287.148016) (xy 327.0123 -287.247838) (xy 327.0123 -287.292288)
			(xy 327.212198 -287.292288)
		)
		(stroke
			(width 0)
			(type solid)
		)
		(fill yes)
		(layer "In13.Cu")
		(net "M_B_CPU0_SB_DQ<20>")
	)
	(gr_poly
		(pts
			(xy 327.215246 -285.627826) (xy 327.115424 -285.52775) (xy 327.015348 -285.627826) (xy 327.015348 -285.675324)
			(xy 327.215246 -285.675324)
		)
		(stroke
			(width 0)
			(type solid)
		)
		(fill yes)
		(layer "In13.Cu")
		(net "M_B_CPU0_SB_DQS_DP<2>")
	)
	(gr_poly
		(pts
			(xy 327.215246 -280.76779) (xy 327.115424 -280.667714) (xy 327.015348 -280.76779) (xy 327.015348 -280.815288)
			(xy 327.215246 -280.815288)
		)
		(stroke
			(width 0)
			(type solid)
		)
		(fill yes)
		(layer "In13.Cu")
		(net "M_B_CPU0_SB_DQS_DP<1>")
	)
	(gr_poly
		(pts
			(xy 327.221088 -288.464244) (xy 327.221088 -288.419794) (xy 327.020936 -288.419794) (xy 327.020936 -288.464244)
			(xy 327.121012 -288.56432)
		)
		(stroke
			(width 0)
			(type solid)
		)
		(fill yes)
		(layer "In13.Cu")
		(net "M_B_CPU0_SB_DQ<23>")
	)
	(gr_poly
		(pts
			(xy 327.223882 -290.084002) (xy 327.223882 -290.039552) (xy 327.02373 -290.039552) (xy 327.02373 -290.084002)
			(xy 327.123806 -290.184078)
		)
		(stroke
			(width 0)
			(type solid)
		)
		(fill yes)
		(layer "In13.Cu")
		(net "M_B_CPU0_SB_DQ<27>")
	)
	(gr_poly
		(pts
			(xy 327.223882 -286.844232) (xy 327.223882 -286.79648) (xy 327.02373 -286.79648) (xy 327.02373 -286.844232)
			(xy 327.123806 -286.944308)
		)
		(stroke
			(width 0)
			(type solid)
		)
		(fill yes)
		(layer "In13.Cu")
		(net "M_B_CPU0_SB_DQS_DP<7>")
	)
	(gr_poly
		(pts
			(xy 327.223882 -285.22422) (xy 327.223882 -285.17977) (xy 327.02373 -285.17977) (xy 327.02373 -285.22422)
			(xy 327.123806 -285.324296)
		)
		(stroke
			(width 0)
			(type solid)
		)
		(fill yes)
		(layer "In13.Cu")
		(net "M_B_CPU0_SB_DQ<19>")
	)
	(gr_poly
		(pts
			(xy 327.223882 -284.008068) (xy 327.123806 -283.907992) (xy 327.02373 -284.008068) (xy 327.02373 -284.052518)
			(xy 327.223882 -284.052518)
		)
		(stroke
			(width 0)
			(type solid)
		)
		(fill yes)
		(layer "In13.Cu")
		(net "M_B_CPU0_SB_DQ<16>")
	)
	(gr_poly
		(pts
			(xy 327.223882 -282.388056) (xy 327.123806 -282.28798) (xy 327.02373 -282.388056) (xy 327.02373 -282.432506)
			(xy 327.223882 -282.432506)
		)
		(stroke
			(width 0)
			(type solid)
		)
		(fill yes)
		(layer "In13.Cu")
		(net "M_B_CPU0_SB_DQ<12>")
	)
	(gr_poly
		(pts
			(xy 327.223882 -279.148032) (xy 327.123806 -279.047956) (xy 327.02373 -279.148032) (xy 327.02373 -279.192482)
			(xy 327.223882 -279.192482)
		)
		(stroke
			(width 0)
			(type solid)
		)
		(fill yes)
		(layer "In13.Cu")
		(net "M_B_CPU0_SB_DQ<8>")
	)
	(gr_poly
		(pts
			(xy 327.223882 -277.52802) (xy 327.123806 -277.427944) (xy 327.02373 -277.52802) (xy 327.02373 -277.57247)
			(xy 327.223882 -277.57247)
		)
		(stroke
			(width 0)
			(type solid)
		)
		(fill yes)
		(layer "In13.Cu")
		(net "M_B_CPU0_SB_DQ<4>")
	)
	(gr_poly
		(pts
			(xy 327.223882 -274.287996) (xy 327.123806 -274.18792) (xy 327.02373 -274.287996) (xy 327.02373 -274.332446)
			(xy 327.223882 -274.332446)
		)
		(stroke
			(width 0)
			(type solid)
		)
		(fill yes)
		(layer "In13.Cu")
		(net "M_B_CPU0_SB_DQ<0>")
	)
	(gr_poly
		(pts
			(xy 327.223882 -273.884136) (xy 327.223882 -273.839686) (xy 327.02373 -273.839686) (xy 327.02373 -273.884136)
			(xy 327.123806 -273.984212)
		)
		(stroke
			(width 0)
			(type solid)
		)
		(fill yes)
		(layer "In13.Cu")
		(net "M_B_CPU0_SB_CB<3>")
	)
	(gr_poly
		(pts
			(xy 327.223882 -272.667984) (xy 327.123806 -272.567908) (xy 327.02373 -272.667984) (xy 327.02373 -272.712434)
			(xy 327.223882 -272.712434)
		)
		(stroke
			(width 0)
			(type solid)
		)
		(fill yes)
		(layer "In13.Cu")
		(net "M_B_CPU0_SB_CB<0>")
	)
	(gr_poly
		(pts
			(xy 327.223882 -264.567924) (xy 327.123806 -264.467848) (xy 327.02373 -264.567924) (xy 327.02373 -264.612374)
			(xy 327.223882 -264.612374)
		)
		(stroke
			(width 0)
			(type solid)
		)
		(fill yes)
		(layer "In13.Cu")
		(net "M_B_CPU0_SB_CA<6>")
	)
	(gr_poly
		(pts
			(xy 327.229978 -288.867596) (xy 327.129902 -288.767774) (xy 327.029826 -288.867596) (xy 327.029826 -288.912046)
			(xy 327.229978 -288.912046)
		)
		(stroke
			(width 0)
			(type solid)
		)
		(fill yes)
		(layer "In13.Cu")
		(net "M_B_CPU0_SB_DQ<24>")
	)
	(gr_poly
		(pts
			(xy 327.229978 -269.427706) (xy 327.129902 -269.327884) (xy 327.029826 -269.427706) (xy 327.029826 -269.472156)
			(xy 327.229978 -269.472156)
		)
		(stroke
			(width 0)
			(type solid)
		)
		(fill yes)
		(layer "In13.Cu")
		(net "M_B_CPU0_SB_CB<4>")
	)
	(gr_poly
		(pts
			(xy 327.235058 -267.80109) (xy 327.134982 -267.701014) (xy 327.03516 -267.80109) (xy 327.03516 -267.84554)
			(xy 327.235058 -267.84554)
		)
		(stroke
			(width 0)
			(type solid)
		)
		(fill yes)
		(layer "In13.Cu")
		(net "M_B_CPU0_SB_RSP<0>")
	)
	(gr_poly
		(pts
			(xy 327.276968 -295.481248) (xy 327.240392 -295.344596) (xy 327.201784 -295.322244) (xy 327.101962 -295.495472)
			(xy 327.140316 -295.517824)
		)
		(stroke
			(width 0)
			(type solid)
		)
		(fill yes)
		(layer "In13.Cu")
		(net "M_B_CPU0_SB_DQ<30>")
	)
	(gr_poly
		(pts
			(xy 327.309988 -225.392488) (xy 327.209912 -225.21926) (xy 327.171558 -225.241612) (xy 327.134982 -225.37801)
			(xy 327.27138 -225.41484)
		)
		(stroke
			(width 0)
			(type solid)
		)
		(fill yes)
		(layer "In13.Cu")
		(net "M_B_CPU0_SA_DQ<6>")
	)
	(gr_poly
		(pts
			(xy 327.313036 -223.77146) (xy 327.213214 -223.598232) (xy 327.171812 -223.622108) (xy 327.135236 -223.75876)
			(xy 327.271888 -223.795336)
		)
		(stroke
			(width 0)
			(type solid)
		)
		(fill yes)
		(layer "In13.Cu")
		(net "M_B_CPU0_SA_DQS_DP<5>")
	)
	(gr_poly
		(pts
			(xy 327.37806 -246.306086) (xy 327.278238 -246.20601) (xy 327.178162 -246.306086) (xy 327.178162 -246.353584)
			(xy 327.37806 -246.353584)
		)
		(stroke
			(width 0)
			(type solid)
		)
		(fill yes)
		(layer "In13.Cu")
		(net "M_B_CPU0_SA_DQS_DP<4>")
	)
	(gr_poly
		(pts
			(xy 327.37806 -236.586014) (xy 327.278238 -236.485938) (xy 327.178162 -236.586014) (xy 327.178162 -236.633512)
			(xy 327.37806 -236.633512)
		)
		(stroke
			(width 0)
			(type solid)
		)
		(fill yes)
		(layer "In13.Cu")
		(net "M_B_CPU0_SA_DQS_DP<2>")
	)
	(gr_poly
		(pts
			(xy 327.37933 -239.421924) (xy 327.37933 -239.377728) (xy 327.179432 -239.377728) (xy 327.179432 -239.421924)
			(xy 327.279254 -239.522)
		)
		(stroke
			(width 0)
			(type solid)
		)
		(fill yes)
		(layer "In13.Cu")
		(net "M_B_CPU0_SA_DQ<23>")
	)
	(gr_poly
		(pts
			(xy 327.380346 -254.4064) (xy 327.28027 -254.306324) (xy 327.180194 -254.4064) (xy 327.180194 -254.45085)
			(xy 327.380346 -254.45085)
		)
		(stroke
			(width 0)
			(type solid)
		)
		(fill yes)
		(layer "In13.Cu")
		(net "M_B_CPU0_SA_CA<4>")
	)
	(gr_poly
		(pts
			(xy 327.380346 -252.786388) (xy 327.28027 -252.686312) (xy 327.180194 -252.786388) (xy 327.180194 -252.830838)
			(xy 327.380346 -252.830838)
		)
		(stroke
			(width 0)
			(type solid)
		)
		(fill yes)
		(layer "In13.Cu")
		(net "M_B_CPU0_SA_CA<0>")
	)
	(gr_poly
		(pts
			(xy 327.380346 -247.926352) (xy 327.28027 -247.826276) (xy 327.180194 -247.926352) (xy 327.180194 -247.970802)
			(xy 327.380346 -247.970802)
		)
		(stroke
			(width 0)
			(type solid)
		)
		(fill yes)
		(layer "In13.Cu")
		(net "M_B_CPU0_SA_CB<4>")
	)
	(gr_poly
		(pts
			(xy 327.380346 -244.686328) (xy 327.28027 -244.586252) (xy 327.180194 -244.686328) (xy 327.180194 -244.730778)
			(xy 327.380346 -244.730778)
		)
		(stroke
			(width 0)
			(type solid)
		)
		(fill yes)
		(layer "In13.Cu")
		(net "M_B_CPU0_SA_CB<0>")
	)
	(gr_poly
		(pts
			(xy 327.380346 -243.066316) (xy 327.28027 -242.96624) (xy 327.180194 -243.066316) (xy 327.180194 -243.110766)
			(xy 327.380346 -243.110766)
		)
		(stroke
			(width 0)
			(type solid)
		)
		(fill yes)
		(layer "In13.Cu")
		(net "M_B_CPU0_SA_DQ<28>")
	)
	(gr_poly
		(pts
			(xy 327.380346 -239.826292) (xy 327.28027 -239.726216) (xy 327.180194 -239.826292) (xy 327.180194 -239.870742)
			(xy 327.380346 -239.870742)
		)
		(stroke
			(width 0)
			(type solid)
		)
		(fill yes)
		(layer "In13.Cu")
		(net "M_B_CPU0_SA_DQ<24>")
	)
	(gr_poly
		(pts
			(xy 327.380346 -238.20628) (xy 327.28027 -238.106204) (xy 327.180194 -238.20628) (xy 327.180194 -238.25073)
			(xy 327.380346 -238.25073)
		)
		(stroke
			(width 0)
			(type solid)
		)
		(fill yes)
		(layer "In13.Cu")
		(net "M_B_CPU0_SA_DQ<20>")
	)
	(gr_poly
		(pts
			(xy 327.382378 -242.66271) (xy 327.382378 -242.614958) (xy 327.18248 -242.614958) (xy 327.18248 -242.66271)
			(xy 327.282556 -242.762532)
		)
		(stroke
			(width 0)
			(type solid)
		)
		(fill yes)
		(layer "In13.Cu")
		(net "M_B_CPU0_SA_DQS_DP<8>")
	)
	(gr_poly
		(pts
			(xy 327.391268 -250.762262) (xy 327.391268 -250.717812) (xy 327.191116 -250.717812) (xy 327.191116 -250.762262)
			(xy 327.291192 -250.862338)
		)
		(stroke
			(width 0)
			(type solid)
		)
		(fill yes)
		(layer "In13.Cu")
		(net "M_B_CPU0_RESET_N")
	)
	(gr_poly
		(pts
			(xy 327.391268 -241.445796) (xy 327.291192 -241.345974) (xy 327.191116 -241.445796) (xy 327.191116 -241.493548)
			(xy 327.391268 -241.493548)
		)
		(stroke
			(width 0)
			(type solid)
		)
		(fill yes)
		(layer "In13.Cu")
		(net "M_B_CPU0_SA_DQS_DP<3>")
	)
	(gr_poly
		(pts
			(xy 327.396602 -255.622298) (xy 327.396602 -255.577848) (xy 327.19645 -255.577848) (xy 327.19645 -255.622298)
			(xy 327.296526 -255.722374)
		)
		(stroke
			(width 0)
			(type solid)
		)
		(fill yes)
		(layer "In13.Cu")
		(net "M_B_CPU0_SA_PAR")
	)
	(gr_poly
		(pts
			(xy 327.396602 -254.002286) (xy 327.396602 -253.957836) (xy 327.19645 -253.957836) (xy 327.19645 -254.002286)
			(xy 327.296526 -254.102362)
		)
		(stroke
			(width 0)
			(type solid)
		)
		(fill yes)
		(layer "In13.Cu")
		(net "M_B_CPU0_SA_CA<3>")
	)
	(gr_poly
		(pts
			(xy 327.396602 -252.382274) (xy 327.396602 -252.337824) (xy 327.19645 -252.337824) (xy 327.19645 -252.382274)
			(xy 327.296526 -252.48235)
		)
		(stroke
			(width 0)
			(type solid)
		)
		(fill yes)
		(layer "In13.Cu")
		(net "M_B_CPU0_SA_CS_N<1>")
	)
	(gr_poly
		(pts
			(xy 327.396602 -249.14225) (xy 327.396602 -249.0978) (xy 327.19645 -249.0978) (xy 327.19645 -249.14225)
			(xy 327.296526 -249.242326)
		)
		(stroke
			(width 0)
			(type solid)
		)
		(fill yes)
		(layer "In13.Cu")
		(net "M_B_CPU0_SA_CB<7>")
	)
	(gr_poly
		(pts
			(xy 327.396602 -247.522492) (xy 327.396602 -247.474994) (xy 327.19645 -247.474994) (xy 327.19645 -247.522492)
			(xy 327.296526 -247.622568)
		)
		(stroke
			(width 0)
			(type solid)
		)
		(fill yes)
		(layer "In13.Cu")
		(net "M_B_CPU0_SA_DQS_DP<9>")
	)
	(gr_poly
		(pts
			(xy 327.396602 -245.902226) (xy 327.396602 -245.857776) (xy 327.19645 -245.857776) (xy 327.19645 -245.902226)
			(xy 327.296526 -246.002302)
		)
		(stroke
			(width 0)
			(type solid)
		)
		(fill yes)
		(layer "In13.Cu")
		(net "M_B_CPU0_SA_CB<3>")
	)
	(gr_poly
		(pts
			(xy 327.396602 -244.282214) (xy 327.396602 -244.237764) (xy 327.19645 -244.237764) (xy 327.19645 -244.282214)
			(xy 327.296526 -244.38229)
		)
		(stroke
			(width 0)
			(type solid)
		)
		(fill yes)
		(layer "In13.Cu")
		(net "M_B_CPU0_SA_DQ<31>")
	)
	(gr_poly
		(pts
			(xy 327.399142 -241.04219) (xy 327.399142 -240.99774) (xy 327.199244 -240.99774) (xy 327.199244 -241.04219)
			(xy 327.299066 -241.142266)
		)
		(stroke
			(width 0)
			(type solid)
		)
		(fill yes)
		(layer "In13.Cu")
		(net "M_B_CPU0_SA_DQ<27>")
	)
	(gr_poly
		(pts
			(xy 327.404984 -223.235012) (xy 327.453498 -223.10217) (xy 327.320402 -223.053656) (xy 327.277476 -223.073976)
			(xy 327.361804 -223.255078)
		)
		(stroke
			(width 0)
			(type solid)
		)
		(fill yes)
		(layer "In13.Cu")
		(net "M_B_CPU0_SA_DQS_DN<5>")
	)
	(gr_poly
		(pts
			(xy 327.406508 -256.026158) (xy 327.306432 -255.926082) (xy 327.20661 -256.026158) (xy 327.20661 -256.073656)
			(xy 327.406508 -256.073656)
		)
		(stroke
			(width 0)
			(type solid)
		)
		(fill yes)
		(layer "In13.Cu")
		(net "M_B_CPU0_CLK_DP<0>")
	)
	(gr_poly
		(pts
			(xy 327.40981 -226.465638) (xy 327.446386 -226.328986) (xy 327.309734 -226.29241) (xy 327.27138 -226.314508)
			(xy 327.371456 -226.487736)
		)
		(stroke
			(width 0)
			(type solid)
		)
		(fill yes)
		(layer "In13.Cu")
		(net "M_B_CPU0_SA_DQ<5>")
	)
	(gr_poly
		(pts
			(xy 327.410064 -224.845626) (xy 327.44664 -224.708974) (xy 327.309988 -224.672398) (xy 327.271634 -224.69475)
			(xy 327.371456 -224.867978)
		)
		(stroke
			(width 0)
			(type solid)
		)
		(fill yes)
		(layer "In13.Cu")
		(net "M_B_CPU0_SA_DQ<4>")
	)
	(gr_poly
		(pts
			(xy 327.610216 -292.367208) (xy 327.571608 -292.344856) (xy 327.43521 -292.381432) (xy 327.471786 -292.518084)
			(xy 327.51014 -292.540436)
		)
		(stroke
			(width 0)
			(type solid)
		)
		(fill yes)
		(layer "In13.Cu")
		(net "M_B_CPU0_SB_DQ<28>")
	)
	(gr_poly
		(pts
			(xy 327.61047 -295.607232) (xy 327.571862 -295.58488) (xy 327.43521 -295.621456) (xy 327.47204 -295.758108)
			(xy 327.510394 -295.78046)
		)
		(stroke
			(width 0)
			(type solid)
		)
		(fill yes)
		(layer "In13.Cu")
		(net "M_B_CPU0_SB_DQ<29>")
	)
	(gr_poly
		(pts
			(xy 327.679304 -283.198316) (xy 327.579228 -283.09824) (xy 327.479406 -283.198316) (xy 327.479406 -283.242512)
			(xy 327.679304 -283.242512)
		)
		(stroke
			(width 0)
			(type solid)
		)
		(fill yes)
		(layer "In13.Cu")
		(net "M_B_CPU0_SB_DQ<13>")
	)
	(gr_poly
		(pts
			(xy 327.682352 -289.27425) (xy 327.682352 -289.2298) (xy 327.482454 -289.2298) (xy 327.482454 -289.27425)
			(xy 327.58253 -289.374072)
		)
		(stroke
			(width 0)
			(type solid)
		)
		(fill yes)
		(layer "In13.Cu")
		(net "M_B_CPU0_SB_DQ<26>")
	)
	(gr_poly
		(pts
			(xy 327.682352 -269.83436) (xy 327.682352 -269.78991) (xy 327.482454 -269.78991) (xy 327.482454 -269.83436)
			(xy 327.58253 -269.934436)
		)
		(stroke
			(width 0)
			(type solid)
		)
		(fill yes)
		(layer "In13.Cu")
		(net "M_B_CPU0_SB_CB<6>")
	)
	(gr_poly
		(pts
			(xy 327.685146 -286.03448) (xy 327.685146 -285.986728) (xy 327.485248 -285.986728) (xy 327.485248 -286.03448)
			(xy 327.585324 -286.134302)
		)
		(stroke
			(width 0)
			(type solid)
		)
		(fill yes)
		(layer "In13.Cu")
		(net "M_B_CPU0_SB_DQS_DN<2>")
	)
	(gr_poly
		(pts
			(xy 327.685146 -281.174444) (xy 327.685146 -281.126692) (xy 327.485248 -281.126692) (xy 327.485248 -281.174444)
			(xy 327.585324 -281.274266)
		)
		(stroke
			(width 0)
			(type solid)
		)
		(fill yes)
		(layer "In13.Cu")
		(net "M_B_CPU0_SB_DQS_DN<1>")
	)
	(gr_poly
		(pts
			(xy 327.691242 -288.057844) (xy 327.591166 -287.957768) (xy 327.49109 -288.057844) (xy 327.49109 -288.102294)
			(xy 327.691242 -288.102294)
		)
		(stroke
			(width 0)
			(type solid)
		)
		(fill yes)
		(layer "In13.Cu")
		(net "M_B_CPU0_SB_DQ<21>")
	)
	(gr_poly
		(pts
			(xy 327.696576 -284.414214) (xy 327.696576 -284.369764) (xy 327.496678 -284.369764) (xy 327.496678 -284.414214)
			(xy 327.5965 -284.51429)
		)
		(stroke
			(width 0)
			(type solid)
		)
		(fill yes)
		(layer "In13.Cu")
		(net "M_B_CPU0_SB_DQ<18>")
	)
	(gr_poly
		(pts
			(xy 327.696576 -282.794202) (xy 327.696576 -282.749752) (xy 327.496678 -282.749752) (xy 327.496678 -282.794202)
			(xy 327.5965 -282.894278)
		)
		(stroke
			(width 0)
			(type solid)
		)
		(fill yes)
		(layer "In13.Cu")
		(net "M_B_CPU0_SB_DQ<14>")
	)
	(gr_poly
		(pts
			(xy 327.696576 -279.554178) (xy 327.696576 -279.509728) (xy 327.496678 -279.509728) (xy 327.496678 -279.554178)
			(xy 327.5965 -279.654254)
		)
		(stroke
			(width 0)
			(type solid)
		)
		(fill yes)
		(layer "In13.Cu")
		(net "M_B_CPU0_SB_DQ<10>")
	)
	(gr_poly
		(pts
			(xy 327.696576 -277.934166) (xy 327.696576 -277.889716) (xy 327.496678 -277.889716) (xy 327.496678 -277.934166)
			(xy 327.5965 -278.034242)
		)
		(stroke
			(width 0)
			(type solid)
		)
		(fill yes)
		(layer "In13.Cu")
		(net "M_B_CPU0_SB_DQ<6>")
	)
	(gr_poly
		(pts
			(xy 327.696576 -274.694142) (xy 327.696576 -274.649692) (xy 327.496678 -274.649692) (xy 327.496678 -274.694142)
			(xy 327.5965 -274.794218)
		)
		(stroke
			(width 0)
			(type solid)
		)
		(fill yes)
		(layer "In13.Cu")
		(net "M_B_CPU0_SB_DQ<2>")
	)
	(gr_poly
		(pts
			(xy 327.696576 -273.07413) (xy 327.696576 -273.02968) (xy 327.496678 -273.02968) (xy 327.496678 -273.07413)
			(xy 327.5965 -273.174206)
		)
		(stroke
			(width 0)
			(type solid)
		)
		(fill yes)
		(layer "In13.Cu")
		(net "M_B_CPU0_SB_CB<2>")
	)
	(gr_poly
		(pts
			(xy 327.696576 -264.97407) (xy 327.696576 -264.92962) (xy 327.496678 -264.92962) (xy 327.496678 -264.97407)
			(xy 327.5965 -265.074146)
		)
		(stroke
			(width 0)
			(type solid)
		)
		(fill yes)
		(layer "In13.Cu")
		(net "M_B_CPU0_SB_PAR")
	)
	(gr_poly
		(pts
			(xy 327.698862 -289.677602) (xy 327.598786 -289.57778) (xy 327.498964 -289.677602) (xy 327.498964 -289.722052)
			(xy 327.698862 -289.722052)
		)
		(stroke
			(width 0)
			(type solid)
		)
		(fill yes)
		(layer "In13.Cu")
		(net "M_B_CPU0_SB_DQ<25>")
	)
	(gr_poly
		(pts
			(xy 327.698862 -286.437578) (xy 327.598786 -286.337756) (xy 327.498964 -286.437578) (xy 327.498964 -286.48533)
			(xy 327.698862 -286.48533)
		)
		(stroke
			(width 0)
			(type solid)
		)
		(fill yes)
		(layer "In13.Cu")
		(net "M_B_CPU0_SB_DQS_DN<7>")
	)
	(gr_poly
		(pts
			(xy 327.698862 -284.81782) (xy 327.598786 -284.717744) (xy 327.498964 -284.81782) (xy 327.498964 -284.86227)
			(xy 327.698862 -284.86227)
		)
		(stroke
			(width 0)
			(type solid)
		)
		(fill yes)
		(layer "In13.Cu")
		(net "M_B_CPU0_SB_DQ<17>")
	)
	(gr_poly
		(pts
			(xy 327.698862 -273.477736) (xy 327.598786 -273.37766) (xy 327.498964 -273.477736) (xy 327.498964 -273.522186)
			(xy 327.698862 -273.522186)
		)
		(stroke
			(width 0)
			(type solid)
		)
		(fill yes)
		(layer "In13.Cu")
		(net "M_B_CPU0_SB_CB<1>")
	)
	(gr_poly
		(pts
			(xy 327.701148 -287.654238) (xy 327.701148 -287.609788) (xy 327.50125 -287.609788) (xy 327.50125 -287.654238)
			(xy 327.601072 -287.75406)
		)
		(stroke
			(width 0)
			(type solid)
		)
		(fill yes)
		(layer "In13.Cu")
		(net "M_B_CPU0_SB_DQ<22>")
	)
	(gr_poly
		(pts
			(xy 327.746614 -294.67175) (xy 327.710038 -294.535098) (xy 327.67143 -294.513) (xy 327.571354 -294.686228)
			(xy 327.609962 -294.708326)
		)
		(stroke
			(width 0)
			(type solid)
		)
		(fill yes)
		(layer "In13.Cu")
		(net "M_B_CPU0_SB_DQ<30>")
	)
	(gr_poly
		(pts
			(xy 327.780396 -231.063038) (xy 327.68032 -230.88981) (xy 327.641966 -230.912162) (xy 327.60539 -231.048814)
			(xy 327.741788 -231.08539)
		)
		(stroke
			(width 0)
			(type solid)
		)
		(fill yes)
		(layer "In13.Cu")
		(net "M_B_CPU0_SA_DQ<11>")
	)
	(gr_poly
		(pts
			(xy 327.781412 -226.204526) (xy 327.681336 -226.031298) (xy 327.642728 -226.053396) (xy 327.606152 -226.190048)
			(xy 327.742804 -226.226624)
		)
		(stroke
			(width 0)
			(type solid)
		)
		(fill yes)
		(layer "In13.Cu")
		(net "M_B_CPU0_SA_DQ<6>")
	)
	(gr_poly
		(pts
			(xy 327.783444 -222.962216) (xy 327.683622 -222.788988) (xy 327.64222 -222.812864) (xy 327.605644 -222.949262)
			(xy 327.742296 -222.985838)
		)
		(stroke
			(width 0)
			(type solid)
		)
		(fill yes)
		(layer "In13.Cu")
		(net "M_B_CPU0_SA_DQS_DN<0>")
	)
	(gr_poly
		(pts
			(xy 327.784206 -224.583498) (xy 327.684384 -224.41027) (xy 327.642982 -224.434146) (xy 327.606406 -224.570798)
			(xy 327.743058 -224.607374)
		)
		(stroke
			(width 0)
			(type solid)
		)
		(fill yes)
		(layer "In13.Cu")
		(net "M_B_CPU0_SA_DQS_DP<5>")
	)
	(gr_poly
		(pts
			(xy 327.854818 -255.216152) (xy 327.754996 -255.116076) (xy 327.65492 -255.216152) (xy 327.65492 -255.260602)
			(xy 327.854818 -255.260602)
		)
		(stroke
			(width 0)
			(type solid)
		)
		(fill yes)
		(layer "In13.Cu")
		(net "M_B_CPU0_SA_CA<6>")
	)
	(gr_poly
		(pts
			(xy 327.854818 -253.59614) (xy 327.754996 -253.496064) (xy 327.65492 -253.59614) (xy 327.65492 -253.64059)
			(xy 327.854818 -253.64059)
		)
		(stroke
			(width 0)
			(type solid)
		)
		(fill yes)
		(layer "In13.Cu")
		(net "M_B_CPU0_SA_CA<2>")
	)
	(gr_poly
		(pts
			(xy 327.854818 -251.572268) (xy 327.854818 -251.527818) (xy 327.65492 -251.527818) (xy 327.65492 -251.572268)
			(xy 327.754996 -251.672344)
		)
		(stroke
			(width 0)
			(type solid)
		)
		(fill yes)
		(layer "In13.Cu")
		(net "M_B_CPU0_SA_CS_N<0>")
	)
	(gr_poly
		(pts
			(xy 327.854818 -248.736104) (xy 327.754996 -248.636028) (xy 327.65492 -248.736104) (xy 327.65492 -248.780554)
			(xy 327.854818 -248.780554)
		)
		(stroke
			(width 0)
			(type solid)
		)
		(fill yes)
		(layer "In13.Cu")
		(net "M_B_CPU0_SA_CB<5>")
	)
	(gr_poly
		(pts
			(xy 327.854818 -247.115838) (xy 327.754996 -247.015762) (xy 327.65492 -247.115838) (xy 327.65492 -247.163336)
			(xy 327.854818 -247.163336)
		)
		(stroke
			(width 0)
			(type solid)
		)
		(fill yes)
		(layer "In13.Cu")
		(net "M_B_CPU0_SA_DQS_DN<9>")
	)
	(gr_poly
		(pts
			(xy 327.854818 -245.49608) (xy 327.754996 -245.396004) (xy 327.65492 -245.49608) (xy 327.65492 -245.54053)
			(xy 327.854818 -245.54053)
		)
		(stroke
			(width 0)
			(type solid)
		)
		(fill yes)
		(layer "In13.Cu")
		(net "M_B_CPU0_SA_CB<1>")
	)
	(gr_poly
		(pts
			(xy 327.854818 -243.876068) (xy 327.754996 -243.775992) (xy 327.65492 -243.876068) (xy 327.65492 -243.920518)
			(xy 327.854818 -243.920518)
		)
		(stroke
			(width 0)
			(type solid)
		)
		(fill yes)
		(layer "In13.Cu")
		(net "M_B_CPU0_SA_DQ<29>")
	)
	(gr_poly
		(pts
			(xy 327.854818 -240.636044) (xy 327.754996 -240.535968) (xy 327.65492 -240.636044) (xy 327.65492 -240.680494)
			(xy 327.854818 -240.680494)
		)
		(stroke
			(width 0)
			(type solid)
		)
		(fill yes)
		(layer "In13.Cu")
		(net "M_B_CPU0_SA_DQ<25>")
	)
	(gr_poly
		(pts
			(xy 327.854818 -235.776008) (xy 327.754996 -235.675932) (xy 327.65492 -235.776008) (xy 327.65492 -235.820458)
			(xy 327.854818 -235.820458)
		)
		(stroke
			(width 0)
			(type solid)
		)
		(fill yes)
		(layer "In13.Cu")
		(net "M_B_CPU0_SA_DQ<17>")
	)
	(gr_poly
		(pts
			(xy 327.861168 -256.432558) (xy 327.861168 -256.384806) (xy 327.661016 -256.384806) (xy 327.661016 -256.432558)
			(xy 327.761092 -256.53238)
		)
		(stroke
			(width 0)
			(type solid)
		)
		(fill yes)
		(layer "In13.Cu")
		(net "M_B_CPU0_CLK_DN<0>")
	)
	(gr_poly
		(pts
			(xy 327.861168 -250.356116) (xy 327.761092 -250.25604) (xy 327.661016 -250.356116) (xy 327.661016 -250.400566)
			(xy 327.861168 -250.400566)
		)
		(stroke
			(width 0)
			(type solid)
		)
		(fill yes)
		(layer "In13.Cu")
		(net "M_B_CPU0_ALERT_R_N")
	)
	(gr_poly
		(pts
			(xy 327.861168 -242.255802) (xy 327.761092 -242.15598) (xy 327.661016 -242.255802) (xy 327.661016 -242.303554)
			(xy 327.861168 -242.303554)
		)
		(stroke
			(width 0)
			(type solid)
		)
		(fill yes)
		(layer "In13.Cu")
		(net "M_B_CPU0_SA_DQS_DN<8>")
	)
	(gr_poly
		(pts
			(xy 327.861168 -241.85245) (xy 327.861168 -241.804698) (xy 327.661016 -241.804698) (xy 327.661016 -241.85245)
			(xy 327.761092 -241.952272)
		)
		(stroke
			(width 0)
			(type solid)
		)
		(fill yes)
		(layer "In13.Cu")
		(net "M_B_CPU0_SA_DQS_DN<3>")
	)
	(gr_poly
		(pts
			(xy 327.861168 -232.132378) (xy 327.861168 -232.084626) (xy 327.661016 -232.084626) (xy 327.661016 -232.132378)
			(xy 327.761092 -232.2322)
		)
		(stroke
			(width 0)
			(type solid)
		)
		(fill yes)
		(layer "In13.Cu")
		(net "M_B_CPU0_SA_DQS_DN<1>")
	)
	(gr_poly
		(pts
			(xy 327.874376 -254.812038) (xy 327.874376 -254.767588) (xy 327.674224 -254.767588) (xy 327.674224 -254.812038)
			(xy 327.7743 -254.912114)
		)
		(stroke
			(width 0)
			(type solid)
		)
		(fill yes)
		(layer "In13.Cu")
		(net "M_B_CPU0_SA_CA<5>")
	)
	(gr_poly
		(pts
			(xy 327.874376 -253.192026) (xy 327.874376 -253.147576) (xy 327.674224 -253.147576) (xy 327.674224 -253.192026)
			(xy 327.7743 -253.292102)
		)
		(stroke
			(width 0)
			(type solid)
		)
		(fill yes)
		(layer "In13.Cu")
		(net "M_B_CPU0_SA_CA<1>")
	)
	(gr_poly
		(pts
			(xy 327.874376 -248.33199) (xy 327.874376 -248.28754) (xy 327.674224 -248.28754) (xy 327.674224 -248.33199)
			(xy 327.7743 -248.432066)
		)
		(stroke
			(width 0)
			(type solid)
		)
		(fill yes)
		(layer "In13.Cu")
		(net "M_B_CPU0_SA_CB<6>")
	)
	(gr_poly
		(pts
			(xy 327.874376 -245.091966) (xy 327.874376 -245.047516) (xy 327.674224 -245.047516) (xy 327.674224 -245.091966)
			(xy 327.7743 -245.192042)
		)
		(stroke
			(width 0)
			(type solid)
		)
		(fill yes)
		(layer "In13.Cu")
		(net "M_B_CPU0_SA_CB<2>")
	)
	(gr_poly
		(pts
			(xy 327.874376 -243.471954) (xy 327.874376 -243.427504) (xy 327.674224 -243.427504) (xy 327.674224 -243.471954)
			(xy 327.7743 -243.57203)
		)
		(stroke
			(width 0)
			(type solid)
		)
		(fill yes)
		(layer "In13.Cu")
		(net "M_B_CPU0_SA_DQ<30>")
	)
	(gr_poly
		(pts
			(xy 327.874376 -240.23193) (xy 327.874376 -240.18748) (xy 327.674224 -240.18748) (xy 327.674224 -240.23193)
			(xy 327.7743 -240.332006)
		)
		(stroke
			(width 0)
			(type solid)
		)
		(fill yes)
		(layer "In13.Cu")
		(net "M_B_CPU0_SA_DQ<26>")
	)
	(gr_poly
		(pts
			(xy 327.874376 -238.611918) (xy 327.874376 -238.567468) (xy 327.674224 -238.567468) (xy 327.674224 -238.611918)
			(xy 327.7743 -238.711994)
		)
		(stroke
			(width 0)
			(type solid)
		)
		(fill yes)
		(layer "In13.Cu")
		(net "M_B_CPU0_SA_DQ<22>")
	)
	(gr_poly
		(pts
			(xy 327.874376 -235.371894) (xy 327.874376 -235.327444) (xy 327.674224 -235.327444) (xy 327.674224 -235.371894)
			(xy 327.7743 -235.47197)
		)
		(stroke
			(width 0)
			(type solid)
		)
		(fill yes)
		(layer "In13.Cu")
		(net "M_B_CPU0_SA_DQ<18>")
	)
	(gr_poly
		(pts
			(xy 327.874376 -233.751882) (xy 327.874376 -233.707432) (xy 327.674224 -233.707432) (xy 327.674224 -233.751882)
			(xy 327.7743 -233.851958)
		)
		(stroke
			(width 0)
			(type solid)
		)
		(fill yes)
		(layer "In13.Cu")
		(net "M_B_CPU0_SA_DQ<14>")
	)
	(gr_poly
		(pts
			(xy 327.875646 -239.016032) (xy 327.775824 -238.91621) (xy 327.675748 -239.016032) (xy 327.675748 -239.060736)
			(xy 327.875646 -239.060736)
		)
		(stroke
			(width 0)
			(type solid)
		)
		(fill yes)
		(layer "In13.Cu")
		(net "M_B_CPU0_SA_DQ<21>")
	)
	(gr_poly
		(pts
			(xy 327.876408 -246.712232) (xy 327.876408 -246.664734) (xy 327.67651 -246.664734) (xy 327.67651 -246.712232)
			(xy 327.776332 -246.812308)
		)
		(stroke
			(width 0)
			(type solid)
		)
		(fill yes)
		(layer "In13.Cu")
		(net "M_B_CPU0_SA_DQS_DN<4>")
	)
	(gr_poly
		(pts
			(xy 327.876408 -236.99216) (xy 327.876408 -236.944662) (xy 327.67651 -236.944662) (xy 327.67651 -236.99216)
			(xy 327.776332 -237.092236)
		)
		(stroke
			(width 0)
			(type solid)
		)
		(fill yes)
		(layer "In13.Cu")
		(net "M_B_CPU0_SA_DQS_DN<2>")
	)
	(gr_poly
		(pts
			(xy 327.87971 -224.035366) (xy 327.91654 -223.898714) (xy 327.779888 -223.862138) (xy 327.738486 -223.886014)
			(xy 327.838562 -224.059242)
		)
		(stroke
			(width 0)
			(type solid)
		)
		(fill yes)
		(layer "In13.Cu")
		(net "M_B_CPU0_SA_DQS_DN<5>")
	)
	(gr_poly
		(pts
			(xy 327.879964 -230.51516) (xy 327.91654 -230.378508) (xy 327.779888 -230.341932) (xy 327.74128 -230.36403)
			(xy 327.841356 -230.537258)
		)
		(stroke
			(width 0)
			(type solid)
		)
		(fill yes)
		(layer "In13.Cu")
		(net "M_B_CPU0_SA_DQ<9>")
	)
	(gr_poly
		(pts
			(xy 327.880218 -225.655632) (xy 327.916794 -225.51898) (xy 327.780142 -225.482404) (xy 327.741788 -225.504756)
			(xy 327.84161 -225.677984)
		)
		(stroke
			(width 0)
			(type solid)
		)
		(fill yes)
		(layer "In13.Cu")
		(net "M_B_CPU0_SA_DQ<4>")
	)
	(gr_poly
		(pts
			(xy 327.880472 -228.896418) (xy 327.917302 -228.759766) (xy 327.78065 -228.72319) (xy 327.742042 -228.745542)
			(xy 327.842118 -228.91877)
		)
		(stroke
			(width 0)
			(type solid)
		)
		(fill yes)
		(layer "In13.Cu")
		(net "M_B_CPU0_SA_DQ<8>")
	)
	(gr_poly
		(pts
			(xy 327.88098 -222.41637) (xy 327.917556 -222.279718) (xy 327.780904 -222.243142) (xy 327.739756 -222.266764)
			(xy 327.839578 -222.439992)
		)
		(stroke
			(width 0)
			(type solid)
		)
		(fill yes)
		(layer "In13.Cu")
		(net "M_B_CPU0_SA_DQS_DP<0>")
	)
	(gr_poly
		(pts
			(xy 328.081386 -294.795702) (xy 328.042778 -294.773604) (xy 327.906126 -294.81018) (xy 327.942702 -294.946832)
			(xy 327.98131 -294.96893)
		)
		(stroke
			(width 0)
			(type solid)
		)
		(fill yes)
		(layer "In13.Cu")
		(net "M_B_CPU0_SB_DQ<29>")
	)
	(gr_poly
		(pts
			(xy 328.152252 -290.084256) (xy 328.152252 -290.039806) (xy 327.952354 -290.039806) (xy 327.952354 -290.084256)
			(xy 328.05243 -290.184332)
		)
		(stroke
			(width 0)
			(type solid)
		)
		(fill yes)
		(layer "In13.Cu")
		(net "M_B_CPU0_SB_DQ<27>")
	)
	(gr_poly
		(pts
			(xy 328.152252 -286.844486) (xy 328.152252 -286.796734) (xy 327.952354 -286.796734) (xy 327.952354 -286.844486)
			(xy 328.05243 -286.944308)
		)
		(stroke
			(width 0)
			(type solid)
		)
		(fill yes)
		(layer "In13.Cu")
		(net "M_B_CPU0_SB_DQS_DP<7>")
	)
	(gr_poly
		(pts
			(xy 328.152252 -285.224474) (xy 328.152252 -285.180024) (xy 327.952354 -285.180024) (xy 327.952354 -285.224474)
			(xy 328.05243 -285.324296)
		)
		(stroke
			(width 0)
			(type solid)
		)
		(fill yes)
		(layer "In13.Cu")
		(net "M_B_CPU0_SB_DQ<19>")
	)
	(gr_poly
		(pts
			(xy 328.152252 -280.364438) (xy 328.152252 -280.319988) (xy 327.952354 -280.319988) (xy 327.952354 -280.364438)
			(xy 328.05243 -280.46426)
		)
		(stroke
			(width 0)
			(type solid)
		)
		(fill yes)
		(layer "In13.Cu")
		(net "M_B_CPU0_SB_DQ<11>")
	)
	(gr_poly
		(pts
			(xy 328.152252 -277.124668) (xy 328.152252 -277.076916) (xy 327.952354 -277.076916) (xy 327.952354 -277.124668)
			(xy 328.05243 -277.22449)
		)
		(stroke
			(width 0)
			(type solid)
		)
		(fill yes)
		(layer "In13.Cu")
		(net "M_B_CPU0_SB_DQS_DP<5>")
	)
	(gr_poly
		(pts
			(xy 328.152252 -275.504402) (xy 328.152252 -275.459952) (xy 327.952354 -275.459952) (xy 327.952354 -275.504402)
			(xy 328.05243 -275.604224)
		)
		(stroke
			(width 0)
			(type solid)
		)
		(fill yes)
		(layer "In13.Cu")
		(net "M_B_CPU0_SB_DQ<3>")
	)
	(gr_poly
		(pts
			(xy 328.152252 -273.88439) (xy 328.152252 -273.83994) (xy 327.952354 -273.83994) (xy 327.952354 -273.88439)
			(xy 328.05243 -273.984212)
		)
		(stroke
			(width 0)
			(type solid)
		)
		(fill yes)
		(layer "In13.Cu")
		(net "M_B_CPU0_SB_CB<3>")
	)
	(gr_poly
		(pts
			(xy 328.152252 -272.264632) (xy 328.152252 -272.21688) (xy 327.952354 -272.21688) (xy 327.952354 -272.264632)
			(xy 328.05243 -272.364454)
		)
		(stroke
			(width 0)
			(type solid)
		)
		(fill yes)
		(layer "In13.Cu")
		(net "M_B_CPU0_SB_DQS_DP<4>")
	)
	(gr_poly
		(pts
			(xy 328.152252 -270.644366) (xy 328.152252 -270.599916) (xy 327.952354 -270.599916) (xy 327.952354 -270.644366)
			(xy 328.05243 -270.744188)
		)
		(stroke
			(width 0)
			(type solid)
		)
		(fill yes)
		(layer "In13.Cu")
		(net "M_B_CPU0_SB_CB<7>")
	)
	(gr_poly
		(pts
			(xy 328.152252 -265.78433) (xy 328.152252 -265.73988) (xy 327.952354 -265.73988) (xy 327.952354 -265.78433)
			(xy 328.05243 -265.884152)
		)
		(stroke
			(width 0)
			(type solid)
		)
		(fill yes)
		(layer "In13.Cu")
		(net "M_B_CPU0_SB_CS_N<0>")
	)
	(gr_poly
		(pts
			(xy 328.152252 -264.164318) (xy 328.152252 -264.119868) (xy 327.952354 -264.119868) (xy 327.952354 -264.164318)
			(xy 328.05243 -264.26414)
		)
		(stroke
			(width 0)
			(type solid)
		)
		(fill yes)
		(layer "In13.Cu")
		(net "M_B_CPU0_SB_CA<5>")
	)
	(gr_poly
		(pts
			(xy 328.152252 -262.544306) (xy 328.152252 -262.499856) (xy 327.952354 -262.499856) (xy 327.952354 -262.544306)
			(xy 328.05243 -262.644128)
		)
		(stroke
			(width 0)
			(type solid)
		)
		(fill yes)
		(layer "In13.Cu")
		(net "M_B_CPU0_SB_CA<1>")
	)
	(gr_poly
		(pts
			(xy 328.154284 -281.984196) (xy 328.154284 -281.936444) (xy 327.954386 -281.936444) (xy 327.954386 -281.984196)
			(xy 328.054208 -282.084018)
		)
		(stroke
			(width 0)
			(type solid)
		)
		(fill yes)
		(layer "In13.Cu")
		(net "M_B_CPU0_SB_DQS_DP<6>")
	)
	(gr_poly
		(pts
			(xy 328.155046 -287.247838) (xy 328.05497 -287.147762) (xy 327.954894 -287.247838) (xy 327.954894 -287.292288)
			(xy 328.155046 -287.292288)
		)
		(stroke
			(width 0)
			(type solid)
		)
		(fill yes)
		(layer "In13.Cu")
		(net "M_B_CPU0_SB_DQ<20>")
	)
	(gr_poly
		(pts
			(xy 328.155046 -284.008068) (xy 328.05497 -283.907992) (xy 327.954894 -284.008068) (xy 327.954894 -284.052518)
			(xy 328.155046 -284.052518)
		)
		(stroke
			(width 0)
			(type solid)
		)
		(fill yes)
		(layer "In13.Cu")
		(net "M_B_CPU0_SB_DQ<16>")
	)
	(gr_poly
		(pts
			(xy 328.155046 -282.388056) (xy 328.05497 -282.28798) (xy 327.954894 -282.388056) (xy 327.954894 -282.432506)
			(xy 328.155046 -282.432506)
		)
		(stroke
			(width 0)
			(type solid)
		)
		(fill yes)
		(layer "In13.Cu")
		(net "M_B_CPU0_SB_DQ<12>")
	)
	(gr_poly
		(pts
			(xy 328.155046 -279.148032) (xy 328.05497 -279.047956) (xy 327.954894 -279.148032) (xy 327.954894 -279.192482)
			(xy 328.155046 -279.192482)
		)
		(stroke
			(width 0)
			(type solid)
		)
		(fill yes)
		(layer "In13.Cu")
		(net "M_B_CPU0_SB_DQ<8>")
	)
	(gr_poly
		(pts
			(xy 328.155046 -278.744172) (xy 328.155046 -278.699722) (xy 327.954894 -278.699722) (xy 327.954894 -278.744172)
			(xy 328.05497 -278.844248)
		)
		(stroke
			(width 0)
			(type solid)
		)
		(fill yes)
		(layer "In13.Cu")
		(net "M_B_CPU0_SB_DQ<7>")
	)
	(gr_poly
		(pts
			(xy 328.155046 -277.52802) (xy 328.05497 -277.427944) (xy 327.954894 -277.52802) (xy 327.954894 -277.57247)
			(xy 328.155046 -277.57247)
		)
		(stroke
			(width 0)
			(type solid)
		)
		(fill yes)
		(layer "In13.Cu")
		(net "M_B_CPU0_SB_DQ<4>")
	)
	(gr_poly
		(pts
			(xy 328.155046 -275.9075) (xy 328.05497 -275.807678) (xy 327.954894 -275.9075) (xy 327.954894 -275.955252)
			(xy 328.155046 -275.955252)
		)
		(stroke
			(width 0)
			(type solid)
		)
		(fill yes)
		(layer "In13.Cu")
		(net "M_B_CPU0_SB_DQS_DP<0>")
	)
	(gr_poly
		(pts
			(xy 328.155046 -274.287996) (xy 328.05497 -274.18792) (xy 327.954894 -274.287996) (xy 327.954894 -274.332446)
			(xy 328.155046 -274.332446)
		)
		(stroke
			(width 0)
			(type solid)
		)
		(fill yes)
		(layer "In13.Cu")
		(net "M_B_CPU0_SB_DQ<0>")
	)
	(gr_poly
		(pts
			(xy 328.155046 -272.667984) (xy 328.05497 -272.567908) (xy 327.954894 -272.667984) (xy 327.954894 -272.712434)
			(xy 328.155046 -272.712434)
		)
		(stroke
			(width 0)
			(type solid)
		)
		(fill yes)
		(layer "In13.Cu")
		(net "M_B_CPU0_SB_CB<0>")
	)
	(gr_poly
		(pts
			(xy 328.155046 -271.047718) (xy 328.05497 -270.947642) (xy 327.954894 -271.047718) (xy 327.954894 -271.095216)
			(xy 328.155046 -271.095216)
		)
		(stroke
			(width 0)
			(type solid)
		)
		(fill yes)
		(layer "In13.Cu")
		(net "M_B_CPU0_SB_DQS_DP<9>")
	)
	(gr_poly
		(pts
			(xy 328.155046 -264.567924) (xy 328.05497 -264.467848) (xy 327.954894 -264.567924) (xy 327.954894 -264.612374)
			(xy 328.155046 -264.612374)
		)
		(stroke
			(width 0)
			(type solid)
		)
		(fill yes)
		(layer "In13.Cu")
		(net "M_B_CPU0_SB_CA<6>")
	)
	(gr_poly
		(pts
			(xy 328.155046 -262.947912) (xy 328.05497 -262.847836) (xy 327.954894 -262.947912) (xy 327.954894 -262.992362)
			(xy 328.155046 -262.992362)
		)
		(stroke
			(width 0)
			(type solid)
		)
		(fill yes)
		(layer "In13.Cu")
		(net "M_B_CPU0_SB_CA<2>")
	)
	(gr_poly
		(pts
			(xy 328.161142 -292.107874) (xy 328.061066 -292.007798) (xy 327.96099 -292.107874) (xy 327.96099 -292.152324)
			(xy 328.161142 -292.152324)
		)
		(stroke
			(width 0)
			(type solid)
		)
		(fill yes)
		(layer "In13.Cu")
		(net "M_B_CPU0_SB_DQ<28>")
	)
	(gr_poly
		(pts
			(xy 328.161142 -288.86785) (xy 328.061066 -288.767774) (xy 327.96099 -288.86785) (xy 327.96099 -288.9123)
			(xy 328.161142 -288.9123)
		)
		(stroke
			(width 0)
			(type solid)
		)
		(fill yes)
		(layer "In13.Cu")
		(net "M_B_CPU0_SB_DQ<24>")
	)
	(gr_poly
		(pts
			(xy 328.161142 -288.464244) (xy 328.161142 -288.419794) (xy 327.96099 -288.419794) (xy 327.96099 -288.464244)
			(xy 328.061066 -288.56432)
		)
		(stroke
			(width 0)
			(type solid)
		)
		(fill yes)
		(layer "In13.Cu")
		(net "M_B_CPU0_SB_DQ<23>")
	)
	(gr_poly
		(pts
			(xy 328.161142 -269.42796) (xy 328.061066 -269.327884) (xy 327.96099 -269.42796) (xy 327.96099 -269.47241)
			(xy 328.161142 -269.47241)
		)
		(stroke
			(width 0)
			(type solid)
		)
		(fill yes)
		(layer "In13.Cu")
		(net "M_B_CPU0_SB_CB<4>")
	)
	(gr_poly
		(pts
			(xy 328.167238 -285.627826) (xy 328.067162 -285.528004) (xy 327.967086 -285.627826) (xy 327.967086 -285.675578)
			(xy 328.167238 -285.675578)
		)
		(stroke
			(width 0)
			(type solid)
		)
		(fill yes)
		(layer "In13.Cu")
		(net "M_B_CPU0_SB_DQS_DP<2>")
	)
	(gr_poly
		(pts
			(xy 328.167238 -280.76779) (xy 328.067162 -280.667968) (xy 327.967086 -280.76779) (xy 327.967086 -280.815542)
			(xy 328.167238 -280.815542)
		)
		(stroke
			(width 0)
			(type solid)
		)
		(fill yes)
		(layer "In13.Cu")
		(net "M_B_CPU0_SB_DQS_DP<1>")
	)
	(gr_poly
		(pts
			(xy 328.175112 -267.801598) (xy 328.075036 -267.701522) (xy 327.975214 -267.801598) (xy 327.975214 -267.846048)
			(xy 328.175112 -267.846048)
		)
		(stroke
			(width 0)
			(type solid)
		)
		(fill yes)
		(layer "In13.Cu")
		(net "M_B_CPU0_SB_RSP<0>")
	)
	(gr_poly
		(pts
			(xy 328.17562 -283.604208) (xy 328.17562 -283.559504) (xy 327.975722 -283.559504) (xy 327.975722 -283.604208)
			(xy 328.075798 -283.70403)
		)
		(stroke
			(width 0)
			(type solid)
		)
		(fill yes)
		(layer "In13.Cu")
		(net "M_B_CPU0_SB_DQ<15>")
	)
	(gr_poly
		(pts
			(xy 328.217022 -293.860474) (xy 328.180446 -293.723822) (xy 328.142092 -293.70147) (xy 328.042016 -293.874698)
			(xy 328.080624 -293.89705)
		)
		(stroke
			(width 0)
			(type solid)
		)
		(fill yes)
		(layer "In13.Cu")
		(net "M_B_CPU0_SB_DQ<30>")
	)
	(gr_poly
		(pts
			(xy 328.250296 -228.63302) (xy 328.15022 -228.459792) (xy 328.111866 -228.482144) (xy 328.07529 -228.618796)
			(xy 328.211688 -228.655372)
		)
		(stroke
			(width 0)
			(type solid)
		)
		(fill yes)
		(layer "In13.Cu")
		(net "M_B_CPU0_SA_DQ<7>")
	)
	(gr_poly
		(pts
			(xy 328.250296 -227.013008) (xy 328.15022 -226.83978) (xy 328.111866 -226.862132) (xy 328.07529 -226.998784)
			(xy 328.211688 -227.03536)
		)
		(stroke
			(width 0)
			(type solid)
		)
		(fill yes)
		(layer "In13.Cu")
		(net "M_B_CPU0_SA_DQ<6>")
	)
	(gr_poly
		(pts
			(xy 328.251058 -230.254302) (xy 328.150982 -230.081074) (xy 328.112374 -230.103172) (xy 328.075798 -230.239824)
			(xy 328.21245 -230.2764)
		)
		(stroke
			(width 0)
			(type solid)
		)
		(fill yes)
		(layer "In13.Cu")
		(net "M_B_CPU0_SA_DQ<10>")
	)
	(gr_poly
		(pts
			(xy 328.25309 -225.392234) (xy 328.153268 -225.219006) (xy 328.111866 -225.242882) (xy 328.07529 -225.37928)
			(xy 328.211942 -225.415856)
		)
		(stroke
			(width 0)
			(type solid)
		)
		(fill yes)
		(layer "In13.Cu")
		(net "M_B_CPU0_SA_DQS_DP<5>")
	)
	(gr_poly
		(pts
			(xy 328.254106 -223.773492) (xy 328.154284 -223.600264) (xy 328.112882 -223.62414) (xy 328.076306 -223.760792)
			(xy 328.212958 -223.797368)
		)
		(stroke
			(width 0)
			(type solid)
		)
		(fill yes)
		(layer "In13.Cu")
		(net "M_B_CPU0_SA_DQS_DN<0>")
	)
	(gr_poly
		(pts
			(xy 328.331322 -256.025904) (xy 328.231246 -255.926082) (xy 328.13117 -256.025904) (xy 328.13117 -256.073656)
			(xy 328.331322 -256.073656)
		)
		(stroke
			(width 0)
			(type solid)
		)
		(fill yes)
		(layer "In13.Cu")
		(net "M_B_CPU0_CLK_DP<0>")
	)
	(gr_poly
		(pts
			(xy 328.331322 -255.622298) (xy 328.331322 -255.577848) (xy 328.13117 -255.577848) (xy 328.13117 -255.622298)
			(xy 328.231246 -255.722374)
		)
		(stroke
			(width 0)
			(type solid)
		)
		(fill yes)
		(layer "In13.Cu")
		(net "M_B_CPU0_SA_PAR")
	)
	(gr_poly
		(pts
			(xy 328.331322 -254.406146) (xy 328.231246 -254.30607) (xy 328.13117 -254.406146) (xy 328.13117 -254.450596)
			(xy 328.331322 -254.450596)
		)
		(stroke
			(width 0)
			(type solid)
		)
		(fill yes)
		(layer "In13.Cu")
		(net "M_B_CPU0_SA_CA<4>")
	)
	(gr_poly
		(pts
			(xy 328.331322 -254.002286) (xy 328.331322 -253.957836) (xy 328.13117 -253.957836) (xy 328.13117 -254.002286)
			(xy 328.231246 -254.102362)
		)
		(stroke
			(width 0)
			(type solid)
		)
		(fill yes)
		(layer "In13.Cu")
		(net "M_B_CPU0_SA_CA<3>")
	)
	(gr_poly
		(pts
			(xy 328.331322 -252.786134) (xy 328.231246 -252.686058) (xy 328.13117 -252.786134) (xy 328.13117 -252.830584)
			(xy 328.331322 -252.830584)
		)
		(stroke
			(width 0)
			(type solid)
		)
		(fill yes)
		(layer "In13.Cu")
		(net "M_B_CPU0_SA_CA<0>")
	)
	(gr_poly
		(pts
			(xy 328.331322 -252.382274) (xy 328.331322 -252.337824) (xy 328.13117 -252.337824) (xy 328.13117 -252.382274)
			(xy 328.231246 -252.48235)
		)
		(stroke
			(width 0)
			(type solid)
		)
		(fill yes)
		(layer "In13.Cu")
		(net "M_B_CPU0_SA_CS_N<1>")
	)
	(gr_poly
		(pts
			(xy 328.331322 -250.762262) (xy 328.331322 -250.717812) (xy 328.13117 -250.717812) (xy 328.13117 -250.762262)
			(xy 328.231246 -250.862338)
		)
		(stroke
			(width 0)
			(type solid)
		)
		(fill yes)
		(layer "In13.Cu")
		(net "M_B_CPU0_RESET_N")
	)
	(gr_poly
		(pts
			(xy 328.331322 -249.14225) (xy 328.331322 -249.0978) (xy 328.13117 -249.0978) (xy 328.13117 -249.14225)
			(xy 328.231246 -249.242326)
		)
		(stroke
			(width 0)
			(type solid)
		)
		(fill yes)
		(layer "In13.Cu")
		(net "M_B_CPU0_SA_CB<7>")
	)
	(gr_poly
		(pts
			(xy 328.331322 -247.926098) (xy 328.231246 -247.826022) (xy 328.13117 -247.926098) (xy 328.13117 -247.970548)
			(xy 328.331322 -247.970548)
		)
		(stroke
			(width 0)
			(type solid)
		)
		(fill yes)
		(layer "In13.Cu")
		(net "M_B_CPU0_SA_CB<4>")
	)
	(gr_poly
		(pts
			(xy 328.331322 -247.522492) (xy 328.331322 -247.47474) (xy 328.13117 -247.47474) (xy 328.13117 -247.522492)
			(xy 328.231246 -247.622314)
		)
		(stroke
			(width 0)
			(type solid)
		)
		(fill yes)
		(layer "In13.Cu")
		(net "M_B_CPU0_SA_DQS_DP<9>")
	)
	(gr_poly
		(pts
			(xy 328.331322 -246.305832) (xy 328.231246 -246.20601) (xy 328.13117 -246.305832) (xy 328.13117 -246.353584)
			(xy 328.331322 -246.353584)
		)
		(stroke
			(width 0)
			(type solid)
		)
		(fill yes)
		(layer "In13.Cu")
		(net "M_B_CPU0_SA_DQS_DP<4>")
	)
	(gr_poly
		(pts
			(xy 328.331322 -245.902226) (xy 328.331322 -245.857776) (xy 328.13117 -245.857776) (xy 328.13117 -245.902226)
			(xy 328.231246 -246.002302)
		)
		(stroke
			(width 0)
			(type solid)
		)
		(fill yes)
		(layer "In13.Cu")
		(net "M_B_CPU0_SA_CB<3>")
	)
	(gr_poly
		(pts
			(xy 328.331322 -244.686074) (xy 328.231246 -244.585998) (xy 328.13117 -244.686074) (xy 328.13117 -244.730524)
			(xy 328.331322 -244.730524)
		)
		(stroke
			(width 0)
			(type solid)
		)
		(fill yes)
		(layer "In13.Cu")
		(net "M_B_CPU0_SA_CB<0>")
	)
	(gr_poly
		(pts
			(xy 328.331322 -244.282214) (xy 328.331322 -244.237764) (xy 328.13117 -244.237764) (xy 328.13117 -244.282214)
			(xy 328.231246 -244.38229)
		)
		(stroke
			(width 0)
			(type solid)
		)
		(fill yes)
		(layer "In13.Cu")
		(net "M_B_CPU0_SA_DQ<31>")
	)
	(gr_poly
		(pts
			(xy 328.331322 -243.066062) (xy 328.231246 -242.965986) (xy 328.13117 -243.066062) (xy 328.13117 -243.110512)
			(xy 328.331322 -243.110512)
		)
		(stroke
			(width 0)
			(type solid)
		)
		(fill yes)
		(layer "In13.Cu")
		(net "M_B_CPU0_SA_DQ<28>")
	)
	(gr_poly
		(pts
			(xy 328.331322 -242.662456) (xy 328.331322 -242.614704) (xy 328.13117 -242.614704) (xy 328.13117 -242.662456)
			(xy 328.231246 -242.762278)
		)
		(stroke
			(width 0)
			(type solid)
		)
		(fill yes)
		(layer "In13.Cu")
		(net "M_B_CPU0_SA_DQS_DP<8>")
	)
	(gr_poly
		(pts
			(xy 328.331322 -241.445796) (xy 328.231246 -241.345974) (xy 328.13117 -241.445796) (xy 328.13117 -241.493548)
			(xy 328.331322 -241.493548)
		)
		(stroke
			(width 0)
			(type solid)
		)
		(fill yes)
		(layer "In13.Cu")
		(net "M_B_CPU0_SA_DQS_DP<3>")
	)
	(gr_poly
		(pts
			(xy 328.331322 -241.04219) (xy 328.331322 -240.99774) (xy 328.13117 -240.99774) (xy 328.13117 -241.04219)
			(xy 328.231246 -241.142266)
		)
		(stroke
			(width 0)
			(type solid)
		)
		(fill yes)
		(layer "In13.Cu")
		(net "M_B_CPU0_SA_DQ<27>")
	)
	(gr_poly
		(pts
			(xy 328.331322 -239.826038) (xy 328.231246 -239.725962) (xy 328.13117 -239.826038) (xy 328.13117 -239.870488)
			(xy 328.331322 -239.870488)
		)
		(stroke
			(width 0)
			(type solid)
		)
		(fill yes)
		(layer "In13.Cu")
		(net "M_B_CPU0_SA_DQ<24>")
	)
	(gr_poly
		(pts
			(xy 328.331322 -239.422178) (xy 328.331322 -239.377728) (xy 328.13117 -239.377728) (xy 328.13117 -239.422178)
			(xy 328.231246 -239.522254)
		)
		(stroke
			(width 0)
			(type solid)
		)
		(fill yes)
		(layer "In13.Cu")
		(net "M_B_CPU0_SA_DQ<23>")
	)
	(gr_poly
		(pts
			(xy 328.331322 -238.206026) (xy 328.231246 -238.10595) (xy 328.13117 -238.206026) (xy 328.13117 -238.250476)
			(xy 328.331322 -238.250476)
		)
		(stroke
			(width 0)
			(type solid)
		)
		(fill yes)
		(layer "In13.Cu")
		(net "M_B_CPU0_SA_DQ<20>")
	)
	(gr_poly
		(pts
			(xy 328.331322 -237.80242) (xy 328.331322 -237.754668) (xy 328.13117 -237.754668) (xy 328.13117 -237.80242)
			(xy 328.231246 -237.902242)
		)
		(stroke
			(width 0)
			(type solid)
		)
		(fill yes)
		(layer "In13.Cu")
		(net "M_B_CPU0_SA_DQS_DP<7>")
	)
	(gr_poly
		(pts
			(xy 328.331322 -236.58576) (xy 328.231246 -236.485938) (xy 328.13117 -236.58576) (xy 328.13117 -236.633512)
			(xy 328.331322 -236.633512)
		)
		(stroke
			(width 0)
			(type solid)
		)
		(fill yes)
		(layer "In13.Cu")
		(net "M_B_CPU0_SA_DQS_DP<2>")
	)
	(gr_poly
		(pts
			(xy 328.331322 -236.182154) (xy 328.331322 -236.137704) (xy 328.13117 -236.137704) (xy 328.13117 -236.182154)
			(xy 328.231246 -236.28223)
		)
		(stroke
			(width 0)
			(type solid)
		)
		(fill yes)
		(layer "In13.Cu")
		(net "M_B_CPU0_SA_DQ<19>")
	)
	(gr_poly
		(pts
			(xy 328.331322 -234.966002) (xy 328.231246 -234.865926) (xy 328.13117 -234.966002) (xy 328.13117 -235.010452)
			(xy 328.331322 -235.010452)
		)
		(stroke
			(width 0)
			(type solid)
		)
		(fill yes)
		(layer "In13.Cu")
		(net "M_B_CPU0_SA_DQ<16>")
	)
	(gr_poly
		(pts
			(xy 328.331322 -234.562142) (xy 328.331322 -234.517692) (xy 328.13117 -234.517692) (xy 328.13117 -234.562142)
			(xy 328.231246 -234.662218)
		)
		(stroke
			(width 0)
			(type solid)
		)
		(fill yes)
		(layer "In13.Cu")
		(net "M_B_CPU0_SA_DQ<15>")
	)
	(gr_poly
		(pts
			(xy 328.331322 -233.34599) (xy 328.231246 -233.245914) (xy 328.13117 -233.34599) (xy 328.13117 -233.39044)
			(xy 328.331322 -233.39044)
		)
		(stroke
			(width 0)
			(type solid)
		)
		(fill yes)
		(layer "In13.Cu")
		(net "M_B_CPU0_SA_DQ<12>")
	)
	(gr_poly
		(pts
			(xy 328.331322 -232.942384) (xy 328.331322 -232.894632) (xy 328.13117 -232.894632) (xy 328.13117 -232.942384)
			(xy 328.231246 -233.042206)
		)
		(stroke
			(width 0)
			(type solid)
		)
		(fill yes)
		(layer "In13.Cu")
		(net "M_B_CPU0_SA_DQS_DP<6>")
	)
	(gr_poly
		(pts
			(xy 328.331322 -231.725724) (xy 328.231246 -231.625902) (xy 328.13117 -231.725724) (xy 328.13117 -231.773476)
			(xy 328.331322 -231.773476)
		)
		(stroke
			(width 0)
			(type solid)
		)
		(fill yes)
		(layer "In13.Cu")
		(net "M_B_CPU0_SA_DQS_DP<1>")
	)
	(gr_poly
		(pts
			(xy 328.331322 -231.322372) (xy 328.331322 -231.277922) (xy 328.13117 -231.277922) (xy 328.13117 -231.322372)
			(xy 328.231246 -231.422448)
		)
		(stroke
			(width 0)
			(type solid)
		)
		(fill yes)
		(layer "In13.Cu")
		(net "M_B_CPU0_SA_DQ<11>")
	)
	(gr_poly
		(pts
			(xy 328.34961 -223.224344) (xy 328.386186 -223.087692) (xy 328.249534 -223.051116) (xy 328.208386 -223.074992)
			(xy 328.308208 -223.24822)
		)
		(stroke
			(width 0)
			(type solid)
		)
		(fill yes)
		(layer "In13.Cu")
		(net "M_B_CPU0_SA_DQS_DP<0>")
	)
	(gr_poly
		(pts
			(xy 328.350118 -224.846134) (xy 328.386694 -224.709482) (xy 328.250042 -224.672906) (xy 328.20864 -224.696782)
			(xy 328.308716 -224.87001)
		)
		(stroke
			(width 0)
			(type solid)
		)
		(fill yes)
		(layer "In13.Cu")
		(net "M_B_CPU0_SA_DQS_DN<5>")
	)
	(gr_poly
		(pts
			(xy 328.350372 -229.70617) (xy 328.387202 -229.569518) (xy 328.25055 -229.532942) (xy 328.211942 -229.555294)
			(xy 328.312018 -229.728522)
		)
		(stroke
			(width 0)
			(type solid)
		)
		(fill yes)
		(layer "In13.Cu")
		(net "M_B_CPU0_SA_DQ<8>")
	)
	(gr_poly
		(pts
			(xy 328.350372 -228.086412) (xy 328.387202 -227.94976) (xy 328.25055 -227.913184) (xy 328.211942 -227.935536)
			(xy 328.312018 -228.108764)
		)
		(stroke
			(width 0)
			(type solid)
		)
		(fill yes)
		(layer "In13.Cu")
		(net "M_B_CPU0_SA_DQ<5>")
	)
	(gr_poly
		(pts
			(xy 328.350372 -226.4664) (xy 328.387202 -226.329748) (xy 328.25055 -226.293172) (xy 328.211942 -226.315524)
			(xy 328.312018 -226.488752)
		)
		(stroke
			(width 0)
			(type solid)
		)
		(fill yes)
		(layer "In13.Cu")
		(net "M_B_CPU0_SA_DQ<4>")
	)
	(gr_poly
		(pts
			(xy 328.55027 -293.98722) (xy 328.511662 -293.964868) (xy 328.37501 -294.001444) (xy 328.41184 -294.138096)
			(xy 328.450194 -294.160448)
		)
		(stroke
			(width 0)
			(type solid)
		)
		(fill yes)
		(layer "In13.Cu")
		(net "M_B_CPU0_SB_DQ<29>")
	)
	(gr_poly
		(pts
			(xy 328.624946 -266.991592) (xy 328.52487 -266.891516) (xy 328.425048 -266.991592) (xy 328.425048 -267.036042)
			(xy 328.624946 -267.036042)
		)
		(stroke
			(width 0)
			(type solid)
		)
		(fill yes)
		(layer "In13.Cu")
		(net "M_B_CPU0_SA_RSP<0>")
	)
	(gr_poly
		(pts
			(xy 328.631296 -291.297614) (xy 328.53122 -291.197792) (xy 328.431144 -291.297614) (xy 328.431144 -291.345366)
			(xy 328.631296 -291.345366)
		)
		(stroke
			(width 0)
			(type solid)
		)
		(fill yes)
		(layer "In13.Cu")
		(net "M_B_CPU0_SB_DQS_DN<8>")
	)
	(gr_poly
		(pts
			(xy 328.631296 -290.894262) (xy 328.631296 -290.84651) (xy 328.431144 -290.84651) (xy 328.431144 -290.894262)
			(xy 328.53122 -290.994084)
		)
		(stroke
			(width 0)
			(type solid)
		)
		(fill yes)
		(layer "In13.Cu")
		(net "M_B_CPU0_SB_DQS_DN<3>")
	)
	(gr_poly
		(pts
			(xy 328.631296 -289.677856) (xy 328.53122 -289.57778) (xy 328.431144 -289.677856) (xy 328.431144 -289.722306)
			(xy 328.631296 -289.722306)
		)
		(stroke
			(width 0)
			(type solid)
		)
		(fill yes)
		(layer "In13.Cu")
		(net "M_B_CPU0_SB_DQ<25>")
	)
	(gr_poly
		(pts
			(xy 328.631296 -289.273996) (xy 328.631296 -289.229546) (xy 328.431144 -289.229546) (xy 328.431144 -289.273996)
			(xy 328.53122 -289.374072)
		)
		(stroke
			(width 0)
			(type solid)
		)
		(fill yes)
		(layer "In13.Cu")
		(net "M_B_CPU0_SB_DQ<26>")
	)
	(gr_poly
		(pts
			(xy 328.631296 -288.057844) (xy 328.53122 -287.957768) (xy 328.431144 -288.057844) (xy 328.431144 -288.102294)
			(xy 328.631296 -288.102294)
		)
		(stroke
			(width 0)
			(type solid)
		)
		(fill yes)
		(layer "In13.Cu")
		(net "M_B_CPU0_SB_DQ<21>")
	)
	(gr_poly
		(pts
			(xy 328.631296 -287.654238) (xy 328.631296 -287.609788) (xy 328.431144 -287.609788) (xy 328.431144 -287.654238)
			(xy 328.53122 -287.75406)
		)
		(stroke
			(width 0)
			(type solid)
		)
		(fill yes)
		(layer "In13.Cu")
		(net "M_B_CPU0_SB_DQ<22>")
	)
	(gr_poly
		(pts
			(xy 328.631296 -286.437832) (xy 328.53122 -286.337756) (xy 328.431144 -286.437832) (xy 328.431144 -286.485584)
			(xy 328.631296 -286.485584)
		)
		(stroke
			(width 0)
			(type solid)
		)
		(fill yes)
		(layer "In13.Cu")
		(net "M_B_CPU0_SB_DQS_DN<7>")
	)
	(gr_poly
		(pts
			(xy 328.631296 -286.03448) (xy 328.631296 -285.986728) (xy 328.431144 -285.986728) (xy 328.431144 -286.03448)
			(xy 328.53122 -286.134302)
		)
		(stroke
			(width 0)
			(type solid)
		)
		(fill yes)
		(layer "In13.Cu")
		(net "M_B_CPU0_SB_DQS_DN<2>")
	)
	(gr_poly
		(pts
			(xy 328.631296 -284.818074) (xy 328.53122 -284.717998) (xy 328.431144 -284.818074) (xy 328.431144 -284.862524)
			(xy 328.631296 -284.862524)
		)
		(stroke
			(width 0)
			(type solid)
		)
		(fill yes)
		(layer "In13.Cu")
		(net "M_B_CPU0_SB_DQ<17>")
	)
	(gr_poly
		(pts
			(xy 328.631296 -284.414214) (xy 328.631296 -284.369764) (xy 328.431144 -284.369764) (xy 328.431144 -284.414214)
			(xy 328.53122 -284.51429)
		)
		(stroke
			(width 0)
			(type solid)
		)
		(fill yes)
		(layer "In13.Cu")
		(net "M_B_CPU0_SB_DQ<18>")
	)
	(gr_poly
		(pts
			(xy 328.631296 -283.198062) (xy 328.53122 -283.097986) (xy 328.431144 -283.198062) (xy 328.431144 -283.242512)
			(xy 328.631296 -283.242512)
		)
		(stroke
			(width 0)
			(type solid)
		)
		(fill yes)
		(layer "In13.Cu")
		(net "M_B_CPU0_SB_DQ<13>")
	)
	(gr_poly
		(pts
			(xy 328.631296 -282.794202) (xy 328.631296 -282.749752) (xy 328.431144 -282.749752) (xy 328.431144 -282.794202)
			(xy 328.53122 -282.894278)
		)
		(stroke
			(width 0)
			(type solid)
		)
		(fill yes)
		(layer "In13.Cu")
		(net "M_B_CPU0_SB_DQ<14>")
	)
	(gr_poly
		(pts
			(xy 328.631296 -281.577796) (xy 328.53122 -281.477974) (xy 328.431144 -281.577796) (xy 328.431144 -281.625548)
			(xy 328.631296 -281.625548)
		)
		(stroke
			(width 0)
			(type solid)
		)
		(fill yes)
		(layer "In13.Cu")
		(net "M_B_CPU0_SB_DQS_DN<6>")
	)
	(gr_poly
		(pts
			(xy 328.631296 -281.174444) (xy 328.631296 -281.126692) (xy 328.431144 -281.126692) (xy 328.431144 -281.174444)
			(xy 328.53122 -281.274266)
		)
		(stroke
			(width 0)
			(type solid)
		)
		(fill yes)
		(layer "In13.Cu")
		(net "M_B_CPU0_SB_DQS_DN<1>")
	)
	(gr_poly
		(pts
			(xy 328.631296 -279.958038) (xy 328.53122 -279.857962) (xy 328.431144 -279.958038) (xy 328.431144 -280.002488)
			(xy 328.631296 -280.002488)
		)
		(stroke
			(width 0)
			(type solid)
		)
		(fill yes)
		(layer "In13.Cu")
		(net "M_B_CPU0_SB_DQ<9>")
	)
	(gr_poly
		(pts
			(xy 328.631296 -279.554178) (xy 328.631296 -279.509728) (xy 328.431144 -279.509728) (xy 328.431144 -279.554178)
			(xy 328.53122 -279.654254)
		)
		(stroke
			(width 0)
			(type solid)
		)
		(fill yes)
		(layer "In13.Cu")
		(net "M_B_CPU0_SB_DQ<10>")
	)
	(gr_poly
		(pts
			(xy 328.631296 -278.338026) (xy 328.53122 -278.23795) (xy 328.431144 -278.338026) (xy 328.431144 -278.382476)
			(xy 328.631296 -278.382476)
		)
		(stroke
			(width 0)
			(type solid)
		)
		(fill yes)
		(layer "In13.Cu")
		(net "M_B_CPU0_SB_DQ<5>")
	)
	(gr_poly
		(pts
			(xy 328.631296 -277.934166) (xy 328.631296 -277.889716) (xy 328.431144 -277.889716) (xy 328.431144 -277.934166)
			(xy 328.53122 -278.034242)
		)
		(stroke
			(width 0)
			(type solid)
		)
		(fill yes)
		(layer "In13.Cu")
		(net "M_B_CPU0_SB_DQ<6>")
	)
	(gr_poly
		(pts
			(xy 328.631296 -276.71776) (xy 328.53122 -276.617938) (xy 328.431144 -276.71776) (xy 328.431144 -276.765512)
			(xy 328.631296 -276.765512)
		)
		(stroke
			(width 0)
			(type solid)
		)
		(fill yes)
		(layer "In13.Cu")
		(net "M_B_CPU0_SB_DQS_DN<5>")
	)
	(gr_poly
		(pts
			(xy 328.631296 -276.314408) (xy 328.631296 -276.266656) (xy 328.431144 -276.266656) (xy 328.431144 -276.314408)
			(xy 328.53122 -276.41423)
		)
		(stroke
			(width 0)
			(type solid)
		)
		(fill yes)
		(layer "In13.Cu")
		(net "M_B_CPU0_SB_DQS_DN<0>")
	)
	(gr_poly
		(pts
			(xy 328.631296 -275.098002) (xy 328.53122 -274.997926) (xy 328.431144 -275.098002) (xy 328.431144 -275.142452)
			(xy 328.631296 -275.142452)
		)
		(stroke
			(width 0)
			(type solid)
		)
		(fill yes)
		(layer "In13.Cu")
		(net "M_B_CPU0_SB_DQ<1>")
	)
	(gr_poly
		(pts
			(xy 328.631296 -274.694142) (xy 328.631296 -274.649692) (xy 328.431144 -274.649692) (xy 328.431144 -274.694142)
			(xy 328.53122 -274.794218)
		)
		(stroke
			(width 0)
			(type solid)
		)
		(fill yes)
		(layer "In13.Cu")
		(net "M_B_CPU0_SB_DQ<2>")
	)
	(gr_poly
		(pts
			(xy 328.631296 -273.47799) (xy 328.53122 -273.377914) (xy 328.431144 -273.47799) (xy 328.431144 -273.52244)
			(xy 328.631296 -273.52244)
		)
		(stroke
			(width 0)
			(type solid)
		)
		(fill yes)
		(layer "In13.Cu")
		(net "M_B_CPU0_SB_CB<1>")
	)
	(gr_poly
		(pts
			(xy 328.631296 -273.07413) (xy 328.631296 -273.02968) (xy 328.431144 -273.02968) (xy 328.431144 -273.07413)
			(xy 328.53122 -273.174206)
		)
		(stroke
			(width 0)
			(type solid)
		)
		(fill yes)
		(layer "In13.Cu")
		(net "M_B_CPU0_SB_CB<2>")
	)
	(gr_poly
		(pts
			(xy 328.631296 -271.857724) (xy 328.53122 -271.757902) (xy 328.431144 -271.857724) (xy 328.431144 -271.905476)
			(xy 328.631296 -271.905476)
		)
		(stroke
			(width 0)
			(type solid)
		)
		(fill yes)
		(layer "In13.Cu")
		(net "M_B_CPU0_SB_DQS_DN<4>")
	)
	(gr_poly
		(pts
			(xy 328.631296 -271.454372) (xy 328.631296 -271.40662) (xy 328.431144 -271.40662) (xy 328.431144 -271.454372)
			(xy 328.53122 -271.554194)
		)
		(stroke
			(width 0)
			(type solid)
		)
		(fill yes)
		(layer "In13.Cu")
		(net "M_B_CPU0_SB_DQS_DN<9>")
	)
	(gr_poly
		(pts
			(xy 328.631296 -270.237966) (xy 328.53122 -270.13789) (xy 328.431144 -270.237966) (xy 328.431144 -270.282416)
			(xy 328.631296 -270.282416)
		)
		(stroke
			(width 0)
			(type solid)
		)
		(fill yes)
		(layer "In13.Cu")
		(net "M_B_CPU0_SB_CB<5>")
	)
	(gr_poly
		(pts
			(xy 328.631296 -269.834106) (xy 328.631296 -269.789656) (xy 328.431144 -269.789656) (xy 328.431144 -269.834106)
			(xy 328.53122 -269.934182)
		)
		(stroke
			(width 0)
			(type solid)
		)
		(fill yes)
		(layer "In13.Cu")
		(net "M_B_CPU0_SB_CB<6>")
	)
	(gr_poly
		(pts
			(xy 328.631296 -266.594082) (xy 328.631296 -266.549632) (xy 328.431144 -266.549632) (xy 328.431144 -266.594082)
			(xy 328.53122 -266.694158)
		)
		(stroke
			(width 0)
			(type solid)
		)
		(fill yes)
		(layer "In13.Cu")
		(net "M_B_CPU0_SB_CS_N<1>")
	)
	(gr_poly
		(pts
			(xy 328.631296 -264.97407) (xy 328.631296 -264.92962) (xy 328.431144 -264.92962) (xy 328.431144 -264.97407)
			(xy 328.53122 -265.074146)
		)
		(stroke
			(width 0)
			(type solid)
		)
		(fill yes)
		(layer "In13.Cu")
		(net "M_B_CPU0_SB_PAR")
	)
	(gr_poly
		(pts
			(xy 328.631296 -263.757918) (xy 328.53122 -263.657842) (xy 328.431144 -263.757918) (xy 328.431144 -263.802368)
			(xy 328.631296 -263.802368)
		)
		(stroke
			(width 0)
			(type solid)
		)
		(fill yes)
		(layer "In13.Cu")
		(net "M_B_CPU0_SB_CA<4>")
	)
	(gr_poly
		(pts
			(xy 328.631296 -263.354058) (xy 328.631296 -263.309608) (xy 328.431144 -263.309608) (xy 328.431144 -263.354058)
			(xy 328.53122 -263.454134)
		)
		(stroke
			(width 0)
			(type solid)
		)
		(fill yes)
		(layer "In13.Cu")
		(net "M_B_CPU0_SB_CA<3>")
	)
	(gr_poly
		(pts
			(xy 328.631296 -262.137906) (xy 328.53122 -262.03783) (xy 328.431144 -262.137906) (xy 328.431144 -262.182356)
			(xy 328.631296 -262.182356)
		)
		(stroke
			(width 0)
			(type solid)
		)
		(fill yes)
		(layer "In13.Cu")
		(net "M_B_CPU0_SB_CA<0>")
	)
	(gr_poly
		(pts
			(xy 328.686922 -293.050468) (xy 328.650346 -292.913816) (xy 328.611992 -292.891464) (xy 328.511916 -293.064692)
			(xy 328.550524 -293.087044)
		)
		(stroke
			(width 0)
			(type solid)
		)
		(fill yes)
		(layer "In13.Cu")
		(net "M_B_CPU0_SB_DQ<30>")
	)
	(gr_poly
		(pts
			(xy 328.68743 -296.28973) (xy 328.6506 -296.153332) (xy 328.612246 -296.13098) (xy 328.51217 -296.304208)
			(xy 328.550778 -296.32656)
		)
		(stroke
			(width 0)
			(type solid)
		)
		(fill yes)
		(layer "In13.Cu")
		(net "M_B_CPU0_SB_DQ<31>")
	)
	(gr_poly
		(pts
			(xy 328.721212 -229.44455) (xy 328.621136 -229.271322) (xy 328.582528 -229.29342) (xy 328.545952 -229.430072)
			(xy 328.682604 -229.466648)
		)
		(stroke
			(width 0)
			(type solid)
		)
		(fill yes)
		(layer "In13.Cu")
		(net "M_B_CPU0_SA_DQ<7>")
	)
	(gr_poly
		(pts
			(xy 328.721212 -227.824538) (xy 328.621136 -227.65131) (xy 328.582528 -227.673408) (xy 328.545952 -227.81006)
			(xy 328.682604 -227.846636)
		)
		(stroke
			(width 0)
			(type solid)
		)
		(fill yes)
		(layer "In13.Cu")
		(net "M_B_CPU0_SA_DQ<6>")
	)
	(gr_poly
		(pts
			(xy 328.721212 -222.964502) (xy 328.621136 -222.791274) (xy 328.582528 -222.813372) (xy 328.545952 -222.950024)
			(xy 328.682604 -222.9866)
		)
		(stroke
			(width 0)
			(type solid)
		)
		(fill yes)
		(layer "In13.Cu")
		(net "M_B_CPU0_SA_DQ<3>")
	)
	(gr_poly
		(pts
			(xy 328.724006 -226.20351) (xy 328.624184 -226.030282) (xy 328.582782 -226.054158) (xy 328.546206 -226.19081)
			(xy 328.682858 -226.227386)
		)
		(stroke
			(width 0)
			(type solid)
		)
		(fill yes)
		(layer "In13.Cu")
		(net "M_B_CPU0_SA_DQS_DP<5>")
	)
	(gr_poly
		(pts
			(xy 328.724006 -224.583498) (xy 328.624184 -224.41027) (xy 328.582782 -224.434146) (xy 328.546206 -224.570798)
			(xy 328.682858 -224.607374)
		)
		(stroke
			(width 0)
			(type solid)
		)
		(fill yes)
		(layer "In13.Cu")
		(net "M_B_CPU0_SA_DQS_DN<0>")
	)
	(gr_poly
		(pts
			(xy 328.801222 -256.432558) (xy 328.801222 -256.384806) (xy 328.60107 -256.384806) (xy 328.60107 -256.432558)
			(xy 328.701146 -256.53238)
		)
		(stroke
			(width 0)
			(type solid)
		)
		(fill yes)
		(layer "In13.Cu")
		(net "M_B_CPU0_CLK_DN<0>")
	)
	(gr_poly
		(pts
			(xy 328.801222 -255.216152) (xy 328.701146 -255.116076) (xy 328.60107 -255.216152) (xy 328.60107 -255.260602)
			(xy 328.801222 -255.260602)
		)
		(stroke
			(width 0)
			(type solid)
		)
		(fill yes)
		(layer "In13.Cu")
		(net "M_B_CPU0_SA_CA<6>")
	)
	(gr_poly
		(pts
			(xy 328.801222 -254.812292) (xy 328.801222 -254.767842) (xy 328.60107 -254.767842) (xy 328.60107 -254.812292)
			(xy 328.701146 -254.912368)
		)
		(stroke
			(width 0)
			(type solid)
		)
		(fill yes)
		(layer "In13.Cu")
		(net "M_B_CPU0_SA_CA<5>")
	)
	(gr_poly
		(pts
			(xy 328.801222 -253.59614) (xy 328.701146 -253.496064) (xy 328.60107 -253.59614) (xy 328.60107 -253.64059)
			(xy 328.801222 -253.64059)
		)
		(stroke
			(width 0)
			(type solid)
		)
		(fill yes)
		(layer "In13.Cu")
		(net "M_B_CPU0_SA_CA<2>")
	)
	(gr_poly
		(pts
			(xy 328.801222 -253.19228) (xy 328.801222 -253.14783) (xy 328.60107 -253.14783) (xy 328.60107 -253.19228)
			(xy 328.701146 -253.292356)
		)
		(stroke
			(width 0)
			(type solid)
		)
		(fill yes)
		(layer "In13.Cu")
		(net "M_B_CPU0_SA_CA<1>")
	)
	(gr_poly
		(pts
			(xy 328.801222 -251.572268) (xy 328.801222 -251.527818) (xy 328.60107 -251.527818) (xy 328.60107 -251.572268)
			(xy 328.701146 -251.672344)
		)
		(stroke
			(width 0)
			(type solid)
		)
		(fill yes)
		(layer "In13.Cu")
		(net "M_B_CPU0_SA_CS_N<0>")
	)
	(gr_poly
		(pts
			(xy 328.801222 -250.356116) (xy 328.701146 -250.25604) (xy 328.60107 -250.356116) (xy 328.60107 -250.400566)
			(xy 328.801222 -250.400566)
		)
		(stroke
			(width 0)
			(type solid)
		)
		(fill yes)
		(layer "In13.Cu")
		(net "M_B_CPU0_ALERT_R_N")
	)
	(gr_poly
		(pts
			(xy 328.801222 -248.736104) (xy 328.701146 -248.636028) (xy 328.60107 -248.736104) (xy 328.60107 -248.780554)
			(xy 328.801222 -248.780554)
		)
		(stroke
			(width 0)
			(type solid)
		)
		(fill yes)
		(layer "In13.Cu")
		(net "M_B_CPU0_SA_CB<5>")
	)
	(gr_poly
		(pts
			(xy 328.801222 -248.332244) (xy 328.801222 -248.287794) (xy 328.60107 -248.287794) (xy 328.60107 -248.332244)
			(xy 328.701146 -248.43232)
		)
		(stroke
			(width 0)
			(type solid)
		)
		(fill yes)
		(layer "In13.Cu")
		(net "M_B_CPU0_SA_CB<6>")
	)
	(gr_poly
		(pts
			(xy 328.801222 -247.115838) (xy 328.701146 -247.016016) (xy 328.60107 -247.115838) (xy 328.60107 -247.16359)
			(xy 328.801222 -247.16359)
		)
		(stroke
			(width 0)
			(type solid)
		)
		(fill yes)
		(layer "In13.Cu")
		(net "M_B_CPU0_SA_DQS_DN<9>")
	)
	(gr_poly
		(pts
			(xy 328.801222 -246.712486) (xy 328.801222 -246.664734) (xy 328.60107 -246.664734) (xy 328.60107 -246.712486)
			(xy 328.701146 -246.812308)
		)
		(stroke
			(width 0)
			(type solid)
		)
		(fill yes)
		(layer "In13.Cu")
		(net "M_B_CPU0_SA_DQS_DN<4>")
	)
	(gr_poly
		(pts
			(xy 328.801222 -245.49608) (xy 328.701146 -245.396004) (xy 328.60107 -245.49608) (xy 328.60107 -245.54053)
			(xy 328.801222 -245.54053)
		)
		(stroke
			(width 0)
			(type solid)
		)
		(fill yes)
		(layer "In13.Cu")
		(net "M_B_CPU0_SA_CB<1>")
	)
	(gr_poly
		(pts
			(xy 328.801222 -245.09222) (xy 328.801222 -245.04777) (xy 328.60107 -245.04777) (xy 328.60107 -245.09222)
			(xy 328.701146 -245.192296)
		)
		(stroke
			(width 0)
			(type solid)
		)
		(fill yes)
		(layer "In13.Cu")
		(net "M_B_CPU0_SA_CB<2>")
	)
	(gr_poly
		(pts
			(xy 328.801222 -243.876068) (xy 328.701146 -243.775992) (xy 328.60107 -243.876068) (xy 328.60107 -243.920518)
			(xy 328.801222 -243.920518)
		)
		(stroke
			(width 0)
			(type solid)
		)
		(fill yes)
		(layer "In13.Cu")
		(net "M_B_CPU0_SA_DQ<29>")
	)
	(gr_poly
		(pts
			(xy 328.801222 -243.472208) (xy 328.801222 -243.427758) (xy 328.60107 -243.427758) (xy 328.60107 -243.472208)
			(xy 328.701146 -243.572284)
		)
		(stroke
			(width 0)
			(type solid)
		)
		(fill yes)
		(layer "In13.Cu")
		(net "M_B_CPU0_SA_DQ<30>")
	)
	(gr_poly
		(pts
			(xy 328.801222 -242.255802) (xy 328.701146 -242.15598) (xy 328.60107 -242.255802) (xy 328.60107 -242.303554)
			(xy 328.801222 -242.303554)
		)
		(stroke
			(width 0)
			(type solid)
		)
		(fill yes)
		(layer "In13.Cu")
		(net "M_B_CPU0_SA_DQS_DN<8>")
	)
	(gr_poly
		(pts
			(xy 328.801222 -241.85245) (xy 328.801222 -241.804698) (xy 328.60107 -241.804698) (xy 328.60107 -241.85245)
			(xy 328.701146 -241.952272)
		)
		(stroke
			(width 0)
			(type solid)
		)
		(fill yes)
		(layer "In13.Cu")
		(net "M_B_CPU0_SA_DQS_DN<3>")
	)
	(gr_poly
		(pts
			(xy 328.801222 -240.636044) (xy 328.701146 -240.535968) (xy 328.60107 -240.636044) (xy 328.60107 -240.680494)
			(xy 328.801222 -240.680494)
		)
		(stroke
			(width 0)
			(type solid)
		)
		(fill yes)
		(layer "In13.Cu")
		(net "M_B_CPU0_SA_DQ<25>")
	)
	(gr_poly
		(pts
			(xy 328.801222 -240.232184) (xy 328.801222 -240.187734) (xy 328.60107 -240.187734) (xy 328.60107 -240.232184)
			(xy 328.701146 -240.33226)
		)
		(stroke
			(width 0)
			(type solid)
		)
		(fill yes)
		(layer "In13.Cu")
		(net "M_B_CPU0_SA_DQ<26>")
	)
	(gr_poly
		(pts
			(xy 328.801222 -239.016032) (xy 328.701146 -238.915956) (xy 328.60107 -239.016032) (xy 328.60107 -239.060482)
			(xy 328.801222 -239.060482)
		)
		(stroke
			(width 0)
			(type solid)
		)
		(fill yes)
		(layer "In13.Cu")
		(net "M_B_CPU0_SA_DQ<21>")
	)
	(gr_poly
		(pts
			(xy 328.801222 -238.612172) (xy 328.801222 -238.567722) (xy 328.60107 -238.567722) (xy 328.60107 -238.612172)
			(xy 328.701146 -238.712248)
		)
		(stroke
			(width 0)
			(type solid)
		)
		(fill yes)
		(layer "In13.Cu")
		(net "M_B_CPU0_SA_DQ<22>")
	)
	(gr_poly
		(pts
			(xy 328.801222 -237.395766) (xy 328.701146 -237.295944) (xy 328.60107 -237.395766) (xy 328.60107 -237.443518)
			(xy 328.801222 -237.443518)
		)
		(stroke
			(width 0)
			(type solid)
		)
		(fill yes)
		(layer "In13.Cu")
		(net "M_B_CPU0_SA_DQS_DN<7>")
	)
	(gr_poly
		(pts
			(xy 328.801222 -236.992414) (xy 328.801222 -236.944662) (xy 328.60107 -236.944662) (xy 328.60107 -236.992414)
			(xy 328.701146 -237.092236)
		)
		(stroke
			(width 0)
			(type solid)
		)
		(fill yes)
		(layer "In13.Cu")
		(net "M_B_CPU0_SA_DQS_DN<2>")
	)
	(gr_poly
		(pts
			(xy 328.801222 -235.776008) (xy 328.701146 -235.675932) (xy 328.60107 -235.776008) (xy 328.60107 -235.820458)
			(xy 328.801222 -235.820458)
		)
		(stroke
			(width 0)
			(type solid)
		)
		(fill yes)
		(layer "In13.Cu")
		(net "M_B_CPU0_SA_DQ<17>")
	)
	(gr_poly
		(pts
			(xy 328.801222 -235.372148) (xy 328.801222 -235.327698) (xy 328.60107 -235.327698) (xy 328.60107 -235.372148)
			(xy 328.701146 -235.472224)
		)
		(stroke
			(width 0)
			(type solid)
		)
		(fill yes)
		(layer "In13.Cu")
		(net "M_B_CPU0_SA_DQ<18>")
	)
	(gr_poly
		(pts
			(xy 328.801222 -234.155996) (xy 328.701146 -234.05592) (xy 328.60107 -234.155996) (xy 328.60107 -234.200446)
			(xy 328.801222 -234.200446)
		)
		(stroke
			(width 0)
			(type solid)
		)
		(fill yes)
		(layer "In13.Cu")
		(net "M_B_CPU0_SA_DQ<13>")
	)
	(gr_poly
		(pts
			(xy 328.801222 -233.752136) (xy 328.801222 -233.707686) (xy 328.60107 -233.707686) (xy 328.60107 -233.752136)
			(xy 328.701146 -233.852212)
		)
		(stroke
			(width 0)
			(type solid)
		)
		(fill yes)
		(layer "In13.Cu")
		(net "M_B_CPU0_SA_DQ<14>")
	)
	(gr_poly
		(pts
			(xy 328.801222 -232.53573) (xy 328.701146 -232.435908) (xy 328.60107 -232.53573) (xy 328.60107 -232.583482)
			(xy 328.801222 -232.583482)
		)
		(stroke
			(width 0)
			(type solid)
		)
		(fill yes)
		(layer "In13.Cu")
		(net "M_B_CPU0_SA_DQS_DN<6>")
	)
	(gr_poly
		(pts
			(xy 328.801222 -232.132378) (xy 328.801222 -232.084626) (xy 328.60107 -232.084626) (xy 328.60107 -232.132378)
			(xy 328.701146 -232.2322)
		)
		(stroke
			(width 0)
			(type solid)
		)
		(fill yes)
		(layer "In13.Cu")
		(net "M_B_CPU0_SA_DQS_DN<1>")
	)
	(gr_poly
		(pts
			(xy 328.801222 -230.915972) (xy 328.701146 -230.815896) (xy 328.60107 -230.915972) (xy 328.60107 -230.960422)
			(xy 328.801222 -230.960422)
		)
		(stroke
			(width 0)
			(type solid)
		)
		(fill yes)
		(layer "In13.Cu")
		(net "M_B_CPU0_SA_DQ<9>")
	)
	(gr_poly
		(pts
			(xy 328.801222 -230.512366) (xy 328.801222 -230.467916) (xy 328.60107 -230.467916) (xy 328.60107 -230.512366)
			(xy 328.701146 -230.612188)
		)
		(stroke
			(width 0)
			(type solid)
		)
		(fill yes)
		(layer "In13.Cu")
		(net "M_B_CPU0_SA_DQ<10>")
	)
	(gr_poly
		(pts
			(xy 328.81951 -224.03435) (xy 328.856086 -223.897698) (xy 328.719434 -223.861122) (xy 328.678286 -223.884998)
			(xy 328.778108 -224.058226)
		)
		(stroke
			(width 0)
			(type solid)
		)
		(fill yes)
		(layer "In13.Cu")
		(net "M_B_CPU0_SA_DQS_DP<0>")
	)
	(gr_poly
		(pts
			(xy 328.819764 -228.895148) (xy 328.85634 -228.758496) (xy 328.719688 -228.72192) (xy 328.68108 -228.744018)
			(xy 328.781156 -228.917246)
		)
		(stroke
			(width 0)
			(type solid)
		)
		(fill yes)
		(layer "In13.Cu")
		(net "M_B_CPU0_SA_DQ<5>")
	)
	(gr_poly
		(pts
			(xy 328.819764 -227.275136) (xy 328.85634 -227.138484) (xy 328.719688 -227.101908) (xy 328.68108 -227.124006)
			(xy 328.781156 -227.297234)
		)
		(stroke
			(width 0)
			(type solid)
		)
		(fill yes)
		(layer "In13.Cu")
		(net "M_B_CPU0_SA_DQ<4>")
	)
	(gr_poly
		(pts
			(xy 328.820018 -222.4151) (xy 328.856594 -222.278448) (xy 328.719942 -222.241872) (xy 328.681334 -222.26397)
			(xy 328.78141 -222.437198)
		)
		(stroke
			(width 0)
			(type solid)
		)
		(fill yes)
		(layer "In13.Cu")
		(net "M_B_CPU0_SA_DQ<1>")
	)
	(gr_poly
		(pts
			(xy 328.820526 -225.656648) (xy 328.857102 -225.519996) (xy 328.72045 -225.48342) (xy 328.679302 -225.507042)
			(xy 328.779124 -225.68027)
		)
		(stroke
			(width 0)
			(type solid)
		)
		(fill yes)
		(layer "In13.Cu")
		(net "M_B_CPU0_SA_DQS_DN<5>")
	)
	(gr_poly
		(pts
			(xy 329.021186 -293.17569) (xy 328.982578 -293.153592) (xy 328.845926 -293.190168) (xy 328.882502 -293.32682)
			(xy 328.92111 -293.348918)
		)
		(stroke
			(width 0)
			(type solid)
		)
		(fill yes)
		(layer "In13.Cu")
		(net "M_B_CPU0_SB_DQ<29>")
	)
	(gr_poly
		(pts
			(xy 329.101196 -292.107874) (xy 329.00112 -292.007798) (xy 328.901044 -292.107874) (xy 328.901044 -292.152324)
			(xy 329.101196 -292.152324)
		)
		(stroke
			(width 0)
			(type solid)
		)
		(fill yes)
		(layer "In13.Cu")
		(net "M_B_CPU0_SB_DQ<28>")
	)
	(gr_poly
		(pts
			(xy 329.101196 -291.704268) (xy 329.101196 -291.656516) (xy 328.901044 -291.656516) (xy 328.901044 -291.704268)
			(xy 329.00112 -291.80409)
		)
		(stroke
			(width 0)
			(type solid)
		)
		(fill yes)
		(layer "In13.Cu")
		(net "M_B_CPU0_SB_DQS_DP<8>")
	)
	(gr_poly
		(pts
			(xy 329.101196 -290.487608) (xy 329.00112 -290.387786) (xy 328.901044 -290.487608) (xy 328.901044 -290.53536)
			(xy 329.101196 -290.53536)
		)
		(stroke
			(width 0)
			(type solid)
		)
		(fill yes)
		(layer "In13.Cu")
		(net "M_B_CPU0_SB_DQS_DP<3>")
	)
	(gr_poly
		(pts
			(xy 329.101196 -290.084002) (xy 329.101196 -290.039552) (xy 328.901044 -290.039552) (xy 328.901044 -290.084002)
			(xy 329.00112 -290.184078)
		)
		(stroke
			(width 0)
			(type solid)
		)
		(fill yes)
		(layer "In13.Cu")
		(net "M_B_CPU0_SB_DQ<27>")
	)
	(gr_poly
		(pts
			(xy 329.101196 -288.86785) (xy 329.00112 -288.767774) (xy 328.901044 -288.86785) (xy 328.901044 -288.9123)
			(xy 329.101196 -288.9123)
		)
		(stroke
			(width 0)
			(type solid)
		)
		(fill yes)
		(layer "In13.Cu")
		(net "M_B_CPU0_SB_DQ<24>")
	)
	(gr_poly
		(pts
			(xy 329.101196 -288.464244) (xy 329.101196 -288.419794) (xy 328.901044 -288.419794) (xy 328.901044 -288.464244)
			(xy 329.00112 -288.56432)
		)
		(stroke
			(width 0)
			(type solid)
		)
		(fill yes)
		(layer "In13.Cu")
		(net "M_B_CPU0_SB_DQ<23>")
	)
	(gr_poly
		(pts
			(xy 329.101196 -287.247838) (xy 329.00112 -287.148016) (xy 328.901044 -287.247838) (xy 328.901044 -287.292288)
			(xy 329.101196 -287.292288)
		)
		(stroke
			(width 0)
			(type solid)
		)
		(fill yes)
		(layer "In13.Cu")
		(net "M_B_CPU0_SB_DQ<20>")
	)
	(gr_poly
		(pts
			(xy 329.101196 -286.844232) (xy 329.101196 -286.79648) (xy 328.901044 -286.79648) (xy 328.901044 -286.844232)
			(xy 329.00112 -286.944308)
		)
		(stroke
			(width 0)
			(type solid)
		)
		(fill yes)
		(layer "In13.Cu")
		(net "M_B_CPU0_SB_DQS_DP<7>")
	)
	(gr_poly
		(pts
			(xy 329.101196 -285.627826) (xy 329.00112 -285.528004) (xy 328.901044 -285.627826) (xy 328.901044 -285.675578)
			(xy 329.101196 -285.675578)
		)
		(stroke
			(width 0)
			(type solid)
		)
		(fill yes)
		(layer "In13.Cu")
		(net "M_B_CPU0_SB_DQS_DP<2>")
	)
	(gr_poly
		(pts
			(xy 329.101196 -285.22422) (xy 329.101196 -285.17977) (xy 328.901044 -285.17977) (xy 328.901044 -285.22422)
			(xy 329.00112 -285.324296)
		)
		(stroke
			(width 0)
			(type solid)
		)
		(fill yes)
		(layer "In13.Cu")
		(net "M_B_CPU0_SB_DQ<19>")
	)
	(gr_poly
		(pts
			(xy 329.101196 -284.008068) (xy 329.00112 -283.907992) (xy 328.901044 -284.008068) (xy 328.901044 -284.052518)
			(xy 329.101196 -284.052518)
		)
		(stroke
			(width 0)
			(type solid)
		)
		(fill yes)
		(layer "In13.Cu")
		(net "M_B_CPU0_SB_DQ<16>")
	)
	(gr_poly
		(pts
			(xy 329.101196 -283.604208) (xy 329.101196 -283.559758) (xy 328.901044 -283.559758) (xy 328.901044 -283.604208)
			(xy 329.00112 -283.704284)
		)
		(stroke
			(width 0)
			(type solid)
		)
		(fill yes)
		(layer "In13.Cu")
		(net "M_B_CPU0_SB_DQ<15>")
	)
	(gr_poly
		(pts
			(xy 329.101196 -282.388056) (xy 329.00112 -282.28798) (xy 328.901044 -282.388056) (xy 328.901044 -282.432506)
			(xy 329.101196 -282.432506)
		)
		(stroke
			(width 0)
			(type solid)
		)
		(fill yes)
		(layer "In13.Cu")
		(net "M_B_CPU0_SB_DQ<12>")
	)
	(gr_poly
		(pts
			(xy 329.101196 -281.98445) (xy 329.101196 -281.936698) (xy 328.901044 -281.936698) (xy 328.901044 -281.98445)
			(xy 329.00112 -282.084272)
		)
		(stroke
			(width 0)
			(type solid)
		)
		(fill yes)
		(layer "In13.Cu")
		(net "M_B_CPU0_SB_DQS_DP<6>")
	)
	(gr_poly
		(pts
			(xy 329.101196 -280.76779) (xy 329.00112 -280.667968) (xy 328.901044 -280.76779) (xy 328.901044 -280.815542)
			(xy 329.101196 -280.815542)
		)
		(stroke
			(width 0)
			(type solid)
		)
		(fill yes)
		(layer "In13.Cu")
		(net "M_B_CPU0_SB_DQS_DP<1>")
	)
	(gr_poly
		(pts
			(xy 329.101196 -280.364184) (xy 329.101196 -280.319734) (xy 328.901044 -280.319734) (xy 328.901044 -280.364184)
			(xy 329.00112 -280.46426)
		)
		(stroke
			(width 0)
			(type solid)
		)
		(fill yes)
		(layer "In13.Cu")
		(net "M_B_CPU0_SB_DQ<11>")
	)
	(gr_poly
		(pts
			(xy 329.101196 -279.148032) (xy 329.00112 -279.047956) (xy 328.901044 -279.148032) (xy 328.901044 -279.192482)
			(xy 329.101196 -279.192482)
		)
		(stroke
			(width 0)
			(type solid)
		)
		(fill yes)
		(layer "In13.Cu")
		(net "M_B_CPU0_SB_DQ<8>")
	)
	(gr_poly
		(pts
			(xy 329.101196 -278.744172) (xy 329.101196 -278.699722) (xy 328.901044 -278.699722) (xy 328.901044 -278.744172)
			(xy 329.00112 -278.844248)
		)
		(stroke
			(width 0)
			(type solid)
		)
		(fill yes)
		(layer "In13.Cu")
		(net "M_B_CPU0_SB_DQ<7>")
	)
	(gr_poly
		(pts
			(xy 329.101196 -277.52802) (xy 329.00112 -277.427944) (xy 328.901044 -277.52802) (xy 328.901044 -277.57247)
			(xy 329.101196 -277.57247)
		)
		(stroke
			(width 0)
			(type solid)
		)
		(fill yes)
		(layer "In13.Cu")
		(net "M_B_CPU0_SB_DQ<4>")
	)
	(gr_poly
		(pts
			(xy 329.101196 -277.12416) (xy 329.101196 -277.076662) (xy 328.901044 -277.076662) (xy 328.901044 -277.12416)
			(xy 329.00112 -277.224236)
		)
		(stroke
			(width 0)
			(type solid)
		)
		(fill yes)
		(layer "In13.Cu")
		(net "M_B_CPU0_SB_DQS_DP<5>")
	)
	(gr_poly
		(pts
			(xy 329.101196 -275.908008) (xy 329.00112 -275.807932) (xy 328.901044 -275.908008) (xy 328.901044 -275.955506)
			(xy 329.101196 -275.955506)
		)
		(stroke
			(width 0)
			(type solid)
		)
		(fill yes)
		(layer "In13.Cu")
		(net "M_B_CPU0_SB_DQS_DP<0>")
	)
	(gr_poly
		(pts
			(xy 329.101196 -275.504148) (xy 329.101196 -275.459698) (xy 328.901044 -275.459698) (xy 328.901044 -275.504148)
			(xy 329.00112 -275.604224)
		)
		(stroke
			(width 0)
			(type solid)
		)
		(fill yes)
		(layer "In13.Cu")
		(net "M_B_CPU0_SB_DQ<3>")
	)
	(gr_poly
		(pts
			(xy 329.101196 -274.287996) (xy 329.00112 -274.18792) (xy 328.901044 -274.287996) (xy 328.901044 -274.332446)
			(xy 329.101196 -274.332446)
		)
		(stroke
			(width 0)
			(type solid)
		)
		(fill yes)
		(layer "In13.Cu")
		(net "M_B_CPU0_SB_DQ<0>")
	)
	(gr_poly
		(pts
			(xy 329.101196 -273.884136) (xy 329.101196 -273.839686) (xy 328.901044 -273.839686) (xy 328.901044 -273.884136)
			(xy 329.00112 -273.984212)
		)
		(stroke
			(width 0)
			(type solid)
		)
		(fill yes)
		(layer "In13.Cu")
		(net "M_B_CPU0_SB_CB<3>")
	)
	(gr_poly
		(pts
			(xy 329.101196 -272.667984) (xy 329.00112 -272.567908) (xy 328.901044 -272.667984) (xy 328.901044 -272.712434)
			(xy 329.101196 -272.712434)
		)
		(stroke
			(width 0)
			(type solid)
		)
		(fill yes)
		(layer "In13.Cu")
		(net "M_B_CPU0_SB_CB<0>")
	)
	(gr_poly
		(pts
			(xy 329.101196 -272.264378) (xy 329.101196 -272.216626) (xy 328.901044 -272.216626) (xy 328.901044 -272.264378)
			(xy 329.00112 -272.3642)
		)
		(stroke
			(width 0)
			(type solid)
		)
		(fill yes)
		(layer "In13.Cu")
		(net "M_B_CPU0_SB_DQS_DP<4>")
	)
	(gr_poly
		(pts
			(xy 329.101196 -271.047718) (xy 329.00112 -270.947896) (xy 328.901044 -271.047718) (xy 328.901044 -271.09547)
			(xy 329.101196 -271.09547)
		)
		(stroke
			(width 0)
			(type solid)
		)
		(fill yes)
		(layer "In13.Cu")
		(net "M_B_CPU0_SB_DQS_DP<9>")
	)
	(gr_poly
		(pts
			(xy 329.101196 -270.644112) (xy 329.101196 -270.599662) (xy 328.901044 -270.599662) (xy 328.901044 -270.644112)
			(xy 329.00112 -270.744188)
		)
		(stroke
			(width 0)
			(type solid)
		)
		(fill yes)
		(layer "In13.Cu")
		(net "M_B_CPU0_SB_CB<7>")
	)
	(gr_poly
		(pts
			(xy 329.101196 -269.42796) (xy 329.00112 -269.327884) (xy 328.901044 -269.42796) (xy 328.901044 -269.47241)
			(xy 329.101196 -269.47241)
		)
		(stroke
			(width 0)
			(type solid)
		)
		(fill yes)
		(layer "In13.Cu")
		(net "M_B_CPU0_SB_CB<4>")
	)
	(gr_poly
		(pts
			(xy 329.101196 -267.801598) (xy 329.00112 -267.701522) (xy 328.901044 -267.801598) (xy 328.901044 -267.846048)
			(xy 329.101196 -267.846048)
		)
		(stroke
			(width 0)
			(type solid)
		)
		(fill yes)
		(layer "In13.Cu")
		(net "M_B_CPU0_SB_RSP<0>")
	)
	(gr_poly
		(pts
			(xy 329.101196 -265.784076) (xy 329.101196 -265.739626) (xy 328.901044 -265.739626) (xy 328.901044 -265.784076)
			(xy 329.00112 -265.884152)
		)
		(stroke
			(width 0)
			(type solid)
		)
		(fill yes)
		(layer "In13.Cu")
		(net "M_B_CPU0_SB_CS_N<0>")
	)
	(gr_poly
		(pts
			(xy 329.101196 -264.567924) (xy 329.00112 -264.467848) (xy 328.901044 -264.567924) (xy 328.901044 -264.612374)
			(xy 329.101196 -264.612374)
		)
		(stroke
			(width 0)
			(type solid)
		)
		(fill yes)
		(layer "In13.Cu")
		(net "M_B_CPU0_SB_CA<6>")
	)
	(gr_poly
		(pts
			(xy 329.101196 -264.164064) (xy 329.101196 -264.119614) (xy 328.901044 -264.119614) (xy 328.901044 -264.164064)
			(xy 329.00112 -264.26414)
		)
		(stroke
			(width 0)
			(type solid)
		)
		(fill yes)
		(layer "In13.Cu")
		(net "M_B_CPU0_SB_CA<5>")
	)
	(gr_poly
		(pts
			(xy 329.101196 -262.947912) (xy 329.00112 -262.847836) (xy 328.901044 -262.947912) (xy 328.901044 -262.992362)
			(xy 329.101196 -262.992362)
		)
		(stroke
			(width 0)
			(type solid)
		)
		(fill yes)
		(layer "In13.Cu")
		(net "M_B_CPU0_SB_CA<2>")
	)
	(gr_poly
		(pts
			(xy 329.101196 -262.544052) (xy 329.101196 -262.499602) (xy 328.901044 -262.499602) (xy 328.901044 -262.544052)
			(xy 329.00112 -262.644128)
		)
		(stroke
			(width 0)
			(type solid)
		)
		(fill yes)
		(layer "In13.Cu")
		(net "M_B_CPU0_SB_CA<1>")
	)
	(gr_poly
		(pts
			(xy 329.156822 -295.480486) (xy 329.120246 -295.343834) (xy 329.081892 -295.321482) (xy 328.981816 -295.49471)
			(xy 329.020424 -295.517062)
		)
		(stroke
			(width 0)
			(type solid)
		)
		(fill yes)
		(layer "In13.Cu")
		(net "M_B_CPU0_SB_DQ<31>")
	)
	(gr_poly
		(pts
			(xy 329.19035 -228.63302) (xy 329.090274 -228.459792) (xy 329.05192 -228.482144) (xy 329.01509 -228.618796)
			(xy 329.151742 -228.655372)
		)
		(stroke
			(width 0)
			(type solid)
		)
		(fill yes)
		(layer "In13.Cu")
		(net "M_B_CPU0_SA_DQ<6>")
	)
	(gr_poly
		(pts
			(xy 329.19035 -223.772984) (xy 329.090274 -223.599756) (xy 329.05192 -223.622108) (xy 329.01509 -223.75876)
			(xy 329.151742 -223.795336)
		)
		(stroke
			(width 0)
			(type solid)
		)
		(fill yes)
		(layer "In13.Cu")
		(net "M_B_CPU0_SA_DQ<3>")
	)
	(gr_poly
		(pts
			(xy 329.193144 -227.012246) (xy 329.093322 -226.839018) (xy 329.05192 -226.862894) (xy 329.015344 -226.999292)
			(xy 329.151996 -227.035868)
		)
		(stroke
			(width 0)
			(type solid)
		)
		(fill yes)
		(layer "In13.Cu")
		(net "M_B_CPU0_SA_DQS_DP<5>")
	)
	(gr_poly
		(pts
			(xy 329.193144 -225.392234) (xy 329.093322 -225.219006) (xy 329.05192 -225.242882) (xy 329.015344 -225.37928)
			(xy 329.151996 -225.415856)
		)
		(stroke
			(width 0)
			(type solid)
		)
		(fill yes)
		(layer "In13.Cu")
		(net "M_B_CPU0_SA_DQS_DN<0>")
	)
	(gr_poly
		(pts
			(xy 329.271122 -256.025904) (xy 329.171046 -255.926082) (xy 329.07097 -256.025904) (xy 329.07097 -256.073656)
			(xy 329.271122 -256.073656)
		)
		(stroke
			(width 0)
			(type solid)
		)
		(fill yes)
		(layer "In13.Cu")
		(net "M_B_CPU0_CLK_DP<0>")
	)
	(gr_poly
		(pts
			(xy 329.271122 -255.622298) (xy 329.271122 -255.577848) (xy 329.07097 -255.577848) (xy 329.07097 -255.622298)
			(xy 329.171046 -255.722374)
		)
		(stroke
			(width 0)
			(type solid)
		)
		(fill yes)
		(layer "In13.Cu")
		(net "M_B_CPU0_SA_PAR")
	)
	(gr_poly
		(pts
			(xy 329.271122 -254.406146) (xy 329.171046 -254.30607) (xy 329.07097 -254.406146) (xy 329.07097 -254.450596)
			(xy 329.271122 -254.450596)
		)
		(stroke
			(width 0)
			(type solid)
		)
		(fill yes)
		(layer "In13.Cu")
		(net "M_B_CPU0_SA_CA<4>")
	)
	(gr_poly
		(pts
			(xy 329.271122 -254.002286) (xy 329.271122 -253.957836) (xy 329.07097 -253.957836) (xy 329.07097 -254.002286)
			(xy 329.171046 -254.102362)
		)
		(stroke
			(width 0)
			(type solid)
		)
		(fill yes)
		(layer "In13.Cu")
		(net "M_B_CPU0_SA_CA<3>")
	)
	(gr_poly
		(pts
			(xy 329.271122 -252.786134) (xy 329.171046 -252.686058) (xy 329.07097 -252.786134) (xy 329.07097 -252.830584)
			(xy 329.271122 -252.830584)
		)
		(stroke
			(width 0)
			(type solid)
		)
		(fill yes)
		(layer "In13.Cu")
		(net "M_B_CPU0_SA_CA<0>")
	)
	(gr_poly
		(pts
			(xy 329.271122 -252.382274) (xy 329.271122 -252.337824) (xy 329.07097 -252.337824) (xy 329.07097 -252.382274)
			(xy 329.171046 -252.48235)
		)
		(stroke
			(width 0)
			(type solid)
		)
		(fill yes)
		(layer "In13.Cu")
		(net "M_B_CPU0_SA_CS_N<1>")
	)
	(gr_poly
		(pts
			(xy 329.271122 -250.762262) (xy 329.271122 -250.717812) (xy 329.07097 -250.717812) (xy 329.07097 -250.762262)
			(xy 329.171046 -250.862338)
		)
		(stroke
			(width 0)
			(type solid)
		)
		(fill yes)
		(layer "In13.Cu")
		(net "M_B_CPU0_RESET_N")
	)
	(gr_poly
		(pts
			(xy 329.271122 -249.14225) (xy 329.271122 -249.0978) (xy 329.07097 -249.0978) (xy 329.07097 -249.14225)
			(xy 329.171046 -249.242326)
		)
		(stroke
			(width 0)
			(type solid)
		)
		(fill yes)
		(layer "In13.Cu")
		(net "M_B_CPU0_SA_CB<7>")
	)
	(gr_poly
		(pts
			(xy 329.271122 -247.926098) (xy 329.171046 -247.826022) (xy 329.07097 -247.926098) (xy 329.07097 -247.970548)
			(xy 329.271122 -247.970548)
		)
		(stroke
			(width 0)
			(type solid)
		)
		(fill yes)
		(layer "In13.Cu")
		(net "M_B_CPU0_SA_CB<4>")
	)
	(gr_poly
		(pts
			(xy 329.271122 -247.522492) (xy 329.271122 -247.47474) (xy 329.07097 -247.47474) (xy 329.07097 -247.522492)
			(xy 329.171046 -247.622314)
		)
		(stroke
			(width 0)
			(type solid)
		)
		(fill yes)
		(layer "In13.Cu")
		(net "M_B_CPU0_SA_DQS_DP<9>")
	)
	(gr_poly
		(pts
			(xy 329.271122 -246.305832) (xy 329.171046 -246.20601) (xy 329.07097 -246.305832) (xy 329.07097 -246.353584)
			(xy 329.271122 -246.353584)
		)
		(stroke
			(width 0)
			(type solid)
		)
		(fill yes)
		(layer "In13.Cu")
		(net "M_B_CPU0_SA_DQS_DP<4>")
	)
	(gr_poly
		(pts
			(xy 329.271122 -245.902226) (xy 329.271122 -245.857776) (xy 329.07097 -245.857776) (xy 329.07097 -245.902226)
			(xy 329.171046 -246.002302)
		)
		(stroke
			(width 0)
			(type solid)
		)
		(fill yes)
		(layer "In13.Cu")
		(net "M_B_CPU0_SA_CB<3>")
	)
	(gr_poly
		(pts
			(xy 329.271122 -244.686074) (xy 329.171046 -244.585998) (xy 329.07097 -244.686074) (xy 329.07097 -244.730524)
			(xy 329.271122 -244.730524)
		)
		(stroke
			(width 0)
			(type solid)
		)
		(fill yes)
		(layer "In13.Cu")
		(net "M_B_CPU0_SA_CB<0>")
	)
	(gr_poly
		(pts
			(xy 329.271122 -244.282214) (xy 329.271122 -244.237764) (xy 329.07097 -244.237764) (xy 329.07097 -244.282214)
			(xy 329.171046 -244.38229)
		)
		(stroke
			(width 0)
			(type solid)
		)
		(fill yes)
		(layer "In13.Cu")
		(net "M_B_CPU0_SA_DQ<31>")
	)
	(gr_poly
		(pts
			(xy 329.271122 -243.066062) (xy 329.171046 -242.965986) (xy 329.07097 -243.066062) (xy 329.07097 -243.110512)
			(xy 329.271122 -243.110512)
		)
		(stroke
			(width 0)
			(type solid)
		)
		(fill yes)
		(layer "In13.Cu")
		(net "M_B_CPU0_SA_DQ<28>")
	)
	(gr_poly
		(pts
			(xy 329.271122 -242.662456) (xy 329.271122 -242.614704) (xy 329.07097 -242.614704) (xy 329.07097 -242.662456)
			(xy 329.171046 -242.762278)
		)
		(stroke
			(width 0)
			(type solid)
		)
		(fill yes)
		(layer "In13.Cu")
		(net "M_B_CPU0_SA_DQS_DP<8>")
	)
	(gr_poly
		(pts
			(xy 329.271122 -241.445796) (xy 329.171046 -241.345974) (xy 329.07097 -241.445796) (xy 329.07097 -241.493548)
			(xy 329.271122 -241.493548)
		)
		(stroke
			(width 0)
			(type solid)
		)
		(fill yes)
		(layer "In13.Cu")
		(net "M_B_CPU0_SA_DQS_DP<3>")
	)
	(gr_poly
		(pts
			(xy 329.271122 -241.04219) (xy 329.271122 -240.99774) (xy 329.07097 -240.99774) (xy 329.07097 -241.04219)
			(xy 329.171046 -241.142266)
		)
		(stroke
			(width 0)
			(type solid)
		)
		(fill yes)
		(layer "In13.Cu")
		(net "M_B_CPU0_SA_DQ<27>")
	)
	(gr_poly
		(pts
			(xy 329.271122 -239.826038) (xy 329.171046 -239.725962) (xy 329.07097 -239.826038) (xy 329.07097 -239.870488)
			(xy 329.271122 -239.870488)
		)
		(stroke
			(width 0)
			(type solid)
		)
		(fill yes)
		(layer "In13.Cu")
		(net "M_B_CPU0_SA_DQ<24>")
	)
	(gr_poly
		(pts
			(xy 329.271122 -239.422178) (xy 329.271122 -239.377728) (xy 329.07097 -239.377728) (xy 329.07097 -239.422178)
			(xy 329.171046 -239.522254)
		)
		(stroke
			(width 0)
			(type solid)
		)
		(fill yes)
		(layer "In13.Cu")
		(net "M_B_CPU0_SA_DQ<23>")
	)
	(gr_poly
		(pts
			(xy 329.271122 -238.206026) (xy 329.171046 -238.10595) (xy 329.07097 -238.206026) (xy 329.07097 -238.250476)
			(xy 329.271122 -238.250476)
		)
		(stroke
			(width 0)
			(type solid)
		)
		(fill yes)
		(layer "In13.Cu")
		(net "M_B_CPU0_SA_DQ<20>")
	)
	(gr_poly
		(pts
			(xy 329.271122 -237.80242) (xy 329.271122 -237.754668) (xy 329.07097 -237.754668) (xy 329.07097 -237.80242)
			(xy 329.171046 -237.902242)
		)
		(stroke
			(width 0)
			(type solid)
		)
		(fill yes)
		(layer "In13.Cu")
		(net "M_B_CPU0_SA_DQS_DP<7>")
	)
	(gr_poly
		(pts
			(xy 329.271122 -236.58576) (xy 329.171046 -236.485938) (xy 329.07097 -236.58576) (xy 329.07097 -236.633512)
			(xy 329.271122 -236.633512)
		)
		(stroke
			(width 0)
			(type solid)
		)
		(fill yes)
		(layer "In13.Cu")
		(net "M_B_CPU0_SA_DQS_DP<2>")
	)
	(gr_poly
		(pts
			(xy 329.271122 -236.182154) (xy 329.271122 -236.137704) (xy 329.07097 -236.137704) (xy 329.07097 -236.182154)
			(xy 329.171046 -236.28223)
		)
		(stroke
			(width 0)
			(type solid)
		)
		(fill yes)
		(layer "In13.Cu")
		(net "M_B_CPU0_SA_DQ<19>")
	)
	(gr_poly
		(pts
			(xy 329.271122 -234.966002) (xy 329.171046 -234.865926) (xy 329.07097 -234.966002) (xy 329.07097 -235.010452)
			(xy 329.271122 -235.010452)
		)
		(stroke
			(width 0)
			(type solid)
		)
		(fill yes)
		(layer "In13.Cu")
		(net "M_B_CPU0_SA_DQ<16>")
	)
	(gr_poly
		(pts
			(xy 329.271122 -234.562142) (xy 329.271122 -234.517692) (xy 329.07097 -234.517692) (xy 329.07097 -234.562142)
			(xy 329.171046 -234.662218)
		)
		(stroke
			(width 0)
			(type solid)
		)
		(fill yes)
		(layer "In13.Cu")
		(net "M_B_CPU0_SA_DQ<15>")
	)
	(gr_poly
		(pts
			(xy 329.271122 -233.34599) (xy 329.171046 -233.245914) (xy 329.07097 -233.34599) (xy 329.07097 -233.39044)
			(xy 329.271122 -233.39044)
		)
		(stroke
			(width 0)
			(type solid)
		)
		(fill yes)
		(layer "In13.Cu")
		(net "M_B_CPU0_SA_DQ<12>")
	)
	(gr_poly
		(pts
			(xy 329.271122 -232.942384) (xy 329.271122 -232.894632) (xy 329.07097 -232.894632) (xy 329.07097 -232.942384)
			(xy 329.171046 -233.042206)
		)
		(stroke
			(width 0)
			(type solid)
		)
		(fill yes)
		(layer "In13.Cu")
		(net "M_B_CPU0_SA_DQS_DP<6>")
	)
	(gr_poly
		(pts
			(xy 329.271122 -231.725724) (xy 329.171046 -231.625902) (xy 329.07097 -231.725724) (xy 329.07097 -231.773476)
			(xy 329.271122 -231.773476)
		)
		(stroke
			(width 0)
			(type solid)
		)
		(fill yes)
		(layer "In13.Cu")
		(net "M_B_CPU0_SA_DQS_DP<1>")
	)
	(gr_poly
		(pts
			(xy 329.271122 -231.322372) (xy 329.271122 -231.277922) (xy 329.07097 -231.277922) (xy 329.07097 -231.322372)
			(xy 329.171046 -231.422448)
		)
		(stroke
			(width 0)
			(type solid)
		)
		(fill yes)
		(layer "In13.Cu")
		(net "M_B_CPU0_SA_DQ<11>")
	)
	(gr_poly
		(pts
			(xy 329.271122 -230.105966) (xy 329.171046 -230.006144) (xy 329.07097 -230.105966) (xy 329.07097 -230.150416)
			(xy 329.271122 -230.150416)
		)
		(stroke
			(width 0)
			(type solid)
		)
		(fill yes)
		(layer "In13.Cu")
		(net "M_B_CPU0_SA_DQ<8>")
	)
	(gr_poly
		(pts
			(xy 329.271122 -229.70236) (xy 329.271122 -229.65791) (xy 329.07097 -229.65791) (xy 329.07097 -229.70236)
			(xy 329.171046 -229.802436)
		)
		(stroke
			(width 0)
			(type solid)
		)
		(fill yes)
		(layer "In13.Cu")
		(net "M_B_CPU0_SA_DQ<7>")
	)
	(gr_poly
		(pts
			(xy 329.290426 -228.086412) (xy 329.327002 -227.94976) (xy 329.190604 -227.913184) (xy 329.151996 -227.935536)
			(xy 329.252072 -228.108764)
		)
		(stroke
			(width 0)
			(type solid)
		)
		(fill yes)
		(layer "In13.Cu")
		(net "M_B_CPU0_SA_DQ<4>")
	)
	(gr_poly
		(pts
			(xy 329.290426 -226.4664) (xy 329.327002 -226.330002) (xy 329.19035 -226.293426) (xy 329.149202 -226.317048)
			(xy 329.249024 -226.490276)
		)
		(stroke
			(width 0)
			(type solid)
		)
		(fill yes)
		(layer "In13.Cu")
		(net "M_B_CPU0_SA_DQS_DN<5>")
	)
	(gr_poly
		(pts
			(xy 329.290426 -224.845626) (xy 329.327002 -224.709228) (xy 329.19035 -224.672652) (xy 329.149202 -224.696274)
			(xy 329.249024 -224.869502)
		)
		(stroke
			(width 0)
			(type solid)
		)
		(fill yes)
		(layer "In13.Cu")
		(net "M_B_CPU0_SA_DQS_DP<0>")
	)
	(gr_poly
		(pts
			(xy 329.290426 -223.226376) (xy 329.327002 -223.089724) (xy 329.190604 -223.053148) (xy 329.151996 -223.0755)
			(xy 329.252072 -223.248728)
		)
		(stroke
			(width 0)
			(type solid)
		)
		(fill yes)
		(layer "In13.Cu")
		(net "M_B_CPU0_SA_DQ<1>")
	)
	(gr_poly
		(pts
			(xy 329.571096 -292.51402) (xy 329.571096 -292.46957) (xy 329.370944 -292.46957) (xy 329.370944 -292.51402)
			(xy 329.47102 -292.614096)
		)
		(stroke
			(width 0)
			(type solid)
		)
		(fill yes)
		(layer "In13.Cu")
		(net "M_B_CPU0_SB_DQ<30>")
	)
	(gr_poly
		(pts
			(xy 329.571096 -291.297614) (xy 329.47102 -291.197792) (xy 329.370944 -291.297614) (xy 329.370944 -291.345366)
			(xy 329.571096 -291.345366)
		)
		(stroke
			(width 0)
			(type solid)
		)
		(fill yes)
		(layer "In13.Cu")
		(net "M_B_CPU0_SB_DQS_DN<8>")
	)
	(gr_poly
		(pts
			(xy 329.571096 -290.894262) (xy 329.571096 -290.84651) (xy 329.370944 -290.84651) (xy 329.370944 -290.894262)
			(xy 329.47102 -290.994084)
		)
		(stroke
			(width 0)
			(type solid)
		)
		(fill yes)
		(layer "In13.Cu")
		(net "M_B_CPU0_SB_DQS_DN<3>")
	)
	(gr_poly
		(pts
			(xy 329.571096 -289.677856) (xy 329.47102 -289.57778) (xy 329.370944 -289.677856) (xy 329.370944 -289.722306)
			(xy 329.571096 -289.722306)
		)
		(stroke
			(width 0)
			(type solid)
		)
		(fill yes)
		(layer "In13.Cu")
		(net "M_B_CPU0_SB_DQ<25>")
	)
	(gr_poly
		(pts
			(xy 329.571096 -289.273996) (xy 329.571096 -289.229546) (xy 329.370944 -289.229546) (xy 329.370944 -289.273996)
			(xy 329.47102 -289.374072)
		)
		(stroke
			(width 0)
			(type solid)
		)
		(fill yes)
		(layer "In13.Cu")
		(net "M_B_CPU0_SB_DQ<26>")
	)
	(gr_poly
		(pts
			(xy 329.571096 -288.057844) (xy 329.47102 -287.957768) (xy 329.370944 -288.057844) (xy 329.370944 -288.102294)
			(xy 329.571096 -288.102294)
		)
		(stroke
			(width 0)
			(type solid)
		)
		(fill yes)
		(layer "In13.Cu")
		(net "M_B_CPU0_SB_DQ<21>")
	)
	(gr_poly
		(pts
			(xy 329.571096 -287.654238) (xy 329.571096 -287.609788) (xy 329.370944 -287.609788) (xy 329.370944 -287.654238)
			(xy 329.47102 -287.75406)
		)
		(stroke
			(width 0)
			(type solid)
		)
		(fill yes)
		(layer "In13.Cu")
		(net "M_B_CPU0_SB_DQ<22>")
	)
	(gr_poly
		(pts
			(xy 329.571096 -286.437832) (xy 329.47102 -286.337756) (xy 329.370944 -286.437832) (xy 329.370944 -286.485584)
			(xy 329.571096 -286.485584)
		)
		(stroke
			(width 0)
			(type solid)
		)
		(fill yes)
		(layer "In13.Cu")
		(net "M_B_CPU0_SB_DQS_DN<7>")
	)
	(gr_poly
		(pts
			(xy 329.571096 -286.03448) (xy 329.571096 -285.986728) (xy 329.370944 -285.986728) (xy 329.370944 -286.03448)
			(xy 329.47102 -286.134302)
		)
		(stroke
			(width 0)
			(type solid)
		)
		(fill yes)
		(layer "In13.Cu")
		(net "M_B_CPU0_SB_DQS_DN<2>")
	)
	(gr_poly
		(pts
			(xy 329.571096 -284.818074) (xy 329.47102 -284.717998) (xy 329.370944 -284.818074) (xy 329.370944 -284.862524)
			(xy 329.571096 -284.862524)
		)
		(stroke
			(width 0)
			(type solid)
		)
		(fill yes)
		(layer "In13.Cu")
		(net "M_B_CPU0_SB_DQ<17>")
	)
	(gr_poly
		(pts
			(xy 329.571096 -284.414214) (xy 329.571096 -284.369764) (xy 329.370944 -284.369764) (xy 329.370944 -284.414214)
			(xy 329.47102 -284.51429)
		)
		(stroke
			(width 0)
			(type solid)
		)
		(fill yes)
		(layer "In13.Cu")
		(net "M_B_CPU0_SB_DQ<18>")
	)
	(gr_poly
		(pts
			(xy 329.571096 -283.198062) (xy 329.47102 -283.097986) (xy 329.370944 -283.198062) (xy 329.370944 -283.242512)
			(xy 329.571096 -283.242512)
		)
		(stroke
			(width 0)
			(type solid)
		)
		(fill yes)
		(layer "In13.Cu")
		(net "M_B_CPU0_SB_DQ<13>")
	)
	(gr_poly
		(pts
			(xy 329.571096 -282.794202) (xy 329.571096 -282.749752) (xy 329.370944 -282.749752) (xy 329.370944 -282.794202)
			(xy 329.47102 -282.894278)
		)
		(stroke
			(width 0)
			(type solid)
		)
		(fill yes)
		(layer "In13.Cu")
		(net "M_B_CPU0_SB_DQ<14>")
	)
	(gr_poly
		(pts
			(xy 329.571096 -281.577796) (xy 329.47102 -281.477974) (xy 329.370944 -281.577796) (xy 329.370944 -281.625548)
			(xy 329.571096 -281.625548)
		)
		(stroke
			(width 0)
			(type solid)
		)
		(fill yes)
		(layer "In13.Cu")
		(net "M_B_CPU0_SB_DQS_DN<6>")
	)
	(gr_poly
		(pts
			(xy 329.571096 -281.174444) (xy 329.571096 -281.126692) (xy 329.370944 -281.126692) (xy 329.370944 -281.174444)
			(xy 329.47102 -281.274266)
		)
		(stroke
			(width 0)
			(type solid)
		)
		(fill yes)
		(layer "In13.Cu")
		(net "M_B_CPU0_SB_DQS_DN<1>")
	)
	(gr_poly
		(pts
			(xy 329.571096 -279.958038) (xy 329.47102 -279.857962) (xy 329.370944 -279.958038) (xy 329.370944 -280.002488)
			(xy 329.571096 -280.002488)
		)
		(stroke
			(width 0)
			(type solid)
		)
		(fill yes)
		(layer "In13.Cu")
		(net "M_B_CPU0_SB_DQ<9>")
	)
	(gr_poly
		(pts
			(xy 329.571096 -279.554178) (xy 329.571096 -279.509728) (xy 329.370944 -279.509728) (xy 329.370944 -279.554178)
			(xy 329.47102 -279.654254)
		)
		(stroke
			(width 0)
			(type solid)
		)
		(fill yes)
		(layer "In13.Cu")
		(net "M_B_CPU0_SB_DQ<10>")
	)
	(gr_poly
		(pts
			(xy 329.571096 -278.338026) (xy 329.47102 -278.23795) (xy 329.370944 -278.338026) (xy 329.370944 -278.382476)
			(xy 329.571096 -278.382476)
		)
		(stroke
			(width 0)
			(type solid)
		)
		(fill yes)
		(layer "In13.Cu")
		(net "M_B_CPU0_SB_DQ<5>")
	)
	(gr_poly
		(pts
			(xy 329.571096 -277.934166) (xy 329.571096 -277.889716) (xy 329.370944 -277.889716) (xy 329.370944 -277.934166)
			(xy 329.47102 -278.034242)
		)
		(stroke
			(width 0)
			(type solid)
		)
		(fill yes)
		(layer "In13.Cu")
		(net "M_B_CPU0_SB_DQ<6>")
	)
	(gr_poly
		(pts
			(xy 329.571096 -275.098002) (xy 329.47102 -274.997926) (xy 329.370944 -275.098002) (xy 329.370944 -275.142452)
			(xy 329.571096 -275.142452)
		)
		(stroke
			(width 0)
			(type solid)
		)
		(fill yes)
		(layer "In13.Cu")
		(net "M_B_CPU0_SB_DQ<1>")
	)
	(gr_poly
		(pts
			(xy 329.571096 -274.694142) (xy 329.571096 -274.649692) (xy 329.370944 -274.649692) (xy 329.370944 -274.694142)
			(xy 329.47102 -274.794218)
		)
		(stroke
			(width 0)
			(type solid)
		)
		(fill yes)
		(layer "In13.Cu")
		(net "M_B_CPU0_SB_DQ<2>")
	)
	(gr_poly
		(pts
			(xy 329.571096 -273.47799) (xy 329.47102 -273.377914) (xy 329.370944 -273.47799) (xy 329.370944 -273.52244)
			(xy 329.571096 -273.52244)
		)
		(stroke
			(width 0)
			(type solid)
		)
		(fill yes)
		(layer "In13.Cu")
		(net "M_B_CPU0_SB_CB<1>")
	)
	(gr_poly
		(pts
			(xy 329.571096 -273.07413) (xy 329.571096 -273.02968) (xy 329.370944 -273.02968) (xy 329.370944 -273.07413)
			(xy 329.47102 -273.174206)
		)
		(stroke
			(width 0)
			(type solid)
		)
		(fill yes)
		(layer "In13.Cu")
		(net "M_B_CPU0_SB_CB<2>")
	)
	(gr_poly
		(pts
			(xy 329.571096 -271.857724) (xy 329.47102 -271.757902) (xy 329.370944 -271.857724) (xy 329.370944 -271.905476)
			(xy 329.571096 -271.905476)
		)
		(stroke
			(width 0)
			(type solid)
		)
		(fill yes)
		(layer "In13.Cu")
		(net "M_B_CPU0_SB_DQS_DN<4>")
	)
	(gr_poly
		(pts
			(xy 329.571096 -271.454372) (xy 329.571096 -271.40662) (xy 329.370944 -271.40662) (xy 329.370944 -271.454372)
			(xy 329.47102 -271.554194)
		)
		(stroke
			(width 0)
			(type solid)
		)
		(fill yes)
		(layer "In13.Cu")
		(net "M_B_CPU0_SB_DQS_DN<9>")
	)
	(gr_poly
		(pts
			(xy 329.571096 -270.237966) (xy 329.47102 -270.13789) (xy 329.370944 -270.237966) (xy 329.370944 -270.282416)
			(xy 329.571096 -270.282416)
		)
		(stroke
			(width 0)
			(type solid)
		)
		(fill yes)
		(layer "In13.Cu")
		(net "M_B_CPU0_SB_CB<5>")
	)
	(gr_poly
		(pts
			(xy 329.571096 -269.834106) (xy 329.571096 -269.789656) (xy 329.370944 -269.789656) (xy 329.370944 -269.834106)
			(xy 329.47102 -269.934182)
		)
		(stroke
			(width 0)
			(type solid)
		)
		(fill yes)
		(layer "In13.Cu")
		(net "M_B_CPU0_SB_CB<6>")
	)
	(gr_poly
		(pts
			(xy 329.571096 -266.594082) (xy 329.571096 -266.549632) (xy 329.370944 -266.549632) (xy 329.370944 -266.594082)
			(xy 329.47102 -266.694158)
		)
		(stroke
			(width 0)
			(type solid)
		)
		(fill yes)
		(layer "In13.Cu")
		(net "M_B_CPU0_SB_CS_N<1>")
	)
	(gr_poly
		(pts
			(xy 329.571096 -264.97407) (xy 329.571096 -264.92962) (xy 329.370944 -264.92962) (xy 329.370944 -264.97407)
			(xy 329.47102 -265.074146)
		)
		(stroke
			(width 0)
			(type solid)
		)
		(fill yes)
		(layer "In13.Cu")
		(net "M_B_CPU0_SB_PAR")
	)
	(gr_poly
		(pts
			(xy 329.571096 -263.757918) (xy 329.47102 -263.657842) (xy 329.370944 -263.757918) (xy 329.370944 -263.802368)
			(xy 329.571096 -263.802368)
		)
		(stroke
			(width 0)
			(type solid)
		)
		(fill yes)
		(layer "In13.Cu")
		(net "M_B_CPU0_SB_CA<4>")
	)
	(gr_poly
		(pts
			(xy 329.571096 -263.354058) (xy 329.571096 -263.309608) (xy 329.370944 -263.309608) (xy 329.370944 -263.354058)
			(xy 329.47102 -263.454134)
		)
		(stroke
			(width 0)
			(type solid)
		)
		(fill yes)
		(layer "In13.Cu")
		(net "M_B_CPU0_SB_CA<3>")
	)
	(gr_poly
		(pts
			(xy 329.571096 -262.137906) (xy 329.47102 -262.03783) (xy 329.370944 -262.137906) (xy 329.370944 -262.182356)
			(xy 329.571096 -262.182356)
		)
		(stroke
			(width 0)
			(type solid)
		)
		(fill yes)
		(layer "In13.Cu")
		(net "M_B_CPU0_SB_CA<0>")
	)
	(gr_poly
		(pts
			(xy 329.577192 -266.991592) (xy 329.47737 -266.891516) (xy 329.377294 -266.991592) (xy 329.377294 -267.036042)
			(xy 329.577192 -267.036042)
		)
		(stroke
			(width 0)
			(type solid)
		)
		(fill yes)
		(layer "In13.Cu")
		(net "M_B_CPU0_SA_RSP<0>")
	)
	(gr_poly
		(pts
			(xy 329.578462 -276.71776) (xy 329.478386 -276.617938) (xy 329.37831 -276.71776) (xy 329.37831 -276.765512)
			(xy 329.578462 -276.765512)
		)
		(stroke
			(width 0)
			(type solid)
		)
		(fill yes)
		(layer "In13.Cu")
		(net "M_B_CPU0_SB_DQS_DN<5>")
	)
	(gr_poly
		(pts
			(xy 329.578462 -276.314408) (xy 329.578462 -276.266656) (xy 329.37831 -276.266656) (xy 329.37831 -276.314408)
			(xy 329.478386 -276.41423)
		)
		(stroke
			(width 0)
			(type solid)
		)
		(fill yes)
		(layer "In13.Cu")
		(net "M_B_CPU0_SB_DQS_DN<0>")
	)
	(gr_poly
		(pts
			(xy 329.62723 -294.67048) (xy 329.5904 -294.533828) (xy 329.552046 -294.511476) (xy 329.45197 -294.684704)
			(xy 329.490578 -294.707056)
		)
		(stroke
			(width 0)
			(type solid)
		)
		(fill yes)
		(layer "In13.Cu")
		(net "M_B_CPU0_SB_DQ<31>")
	)
	(gr_poly
		(pts
			(xy 329.66025 -224.58299) (xy 329.560174 -224.409762) (xy 329.52182 -224.432114) (xy 329.48499 -224.568766)
			(xy 329.621642 -224.605342)
		)
		(stroke
			(width 0)
			(type solid)
		)
		(fill yes)
		(layer "In13.Cu")
		(net "M_B_CPU0_SA_DQ<3>")
	)
	(gr_poly
		(pts
			(xy 329.66025 -222.962978) (xy 329.560174 -222.78975) (xy 329.52182 -222.812102) (xy 329.48499 -222.948754)
			(xy 329.621642 -222.98533)
		)
		(stroke
			(width 0)
			(type solid)
		)
		(fill yes)
		(layer "In13.Cu")
		(net "M_B_CPU0_SA_DQ<2>")
	)
	(gr_poly
		(pts
			(xy 329.663044 -227.822252) (xy 329.563222 -227.649024) (xy 329.52182 -227.6729) (xy 329.485244 -227.809298)
			(xy 329.621896 -227.846128)
		)
		(stroke
			(width 0)
			(type solid)
		)
		(fill yes)
		(layer "In13.Cu")
		(net "M_B_CPU0_SA_DQS_DP<5>")
	)
	(gr_poly
		(pts
			(xy 329.663044 -226.20224) (xy 329.563222 -226.029012) (xy 329.52182 -226.052888) (xy 329.485244 -226.189286)
			(xy 329.621896 -226.226116)
		)
		(stroke
			(width 0)
			(type solid)
		)
		(fill yes)
		(layer "In13.Cu")
		(net "M_B_CPU0_SA_DQS_DN<0>")
	)
	(gr_poly
		(pts
			(xy 329.741276 -256.432558) (xy 329.741276 -256.384806) (xy 329.541124 -256.384806) (xy 329.541124 -256.432558)
			(xy 329.6412 -256.53238)
		)
		(stroke
			(width 0)
			(type solid)
		)
		(fill yes)
		(layer "In13.Cu")
		(net "M_B_CPU0_CLK_DN<0>")
	)
	(gr_poly
		(pts
			(xy 329.741276 -255.216152) (xy 329.6412 -255.116076) (xy 329.541124 -255.216152) (xy 329.541124 -255.260602)
			(xy 329.741276 -255.260602)
		)
		(stroke
			(width 0)
			(type solid)
		)
		(fill yes)
		(layer "In13.Cu")
		(net "M_B_CPU0_SA_CA<6>")
	)
	(gr_poly
		(pts
			(xy 329.741276 -254.812292) (xy 329.741276 -254.767842) (xy 329.541124 -254.767842) (xy 329.541124 -254.812292)
			(xy 329.6412 -254.912368)
		)
		(stroke
			(width 0)
			(type solid)
		)
		(fill yes)
		(layer "In13.Cu")
		(net "M_B_CPU0_SA_CA<5>")
	)
	(gr_poly
		(pts
			(xy 329.741276 -253.59614) (xy 329.6412 -253.496064) (xy 329.541124 -253.59614) (xy 329.541124 -253.64059)
			(xy 329.741276 -253.64059)
		)
		(stroke
			(width 0)
			(type solid)
		)
		(fill yes)
		(layer "In13.Cu")
		(net "M_B_CPU0_SA_CA<2>")
	)
	(gr_poly
		(pts
			(xy 329.741276 -253.19228) (xy 329.741276 -253.14783) (xy 329.541124 -253.14783) (xy 329.541124 -253.19228)
			(xy 329.6412 -253.292356)
		)
		(stroke
			(width 0)
			(type solid)
		)
		(fill yes)
		(layer "In13.Cu")
		(net "M_B_CPU0_SA_CA<1>")
	)
	(gr_poly
		(pts
			(xy 329.741276 -251.572268) (xy 329.741276 -251.527818) (xy 329.541124 -251.527818) (xy 329.541124 -251.572268)
			(xy 329.6412 -251.672344)
		)
		(stroke
			(width 0)
			(type solid)
		)
		(fill yes)
		(layer "In13.Cu")
		(net "M_B_CPU0_SA_CS_N<0>")
	)
	(gr_poly
		(pts
			(xy 329.741276 -250.356116) (xy 329.6412 -250.25604) (xy 329.541124 -250.356116) (xy 329.541124 -250.400566)
			(xy 329.741276 -250.400566)
		)
		(stroke
			(width 0)
			(type solid)
		)
		(fill yes)
		(layer "In13.Cu")
		(net "M_B_CPU0_ALERT_R_N")
	)
	(gr_poly
		(pts
			(xy 329.741276 -248.736104) (xy 329.6412 -248.636028) (xy 329.541124 -248.736104) (xy 329.541124 -248.780554)
			(xy 329.741276 -248.780554)
		)
		(stroke
			(width 0)
			(type solid)
		)
		(fill yes)
		(layer "In13.Cu")
		(net "M_B_CPU0_SA_CB<5>")
	)
	(gr_poly
		(pts
			(xy 329.741276 -248.332244) (xy 329.741276 -248.287794) (xy 329.541124 -248.287794) (xy 329.541124 -248.332244)
			(xy 329.6412 -248.43232)
		)
		(stroke
			(width 0)
			(type solid)
		)
		(fill yes)
		(layer "In13.Cu")
		(net "M_B_CPU0_SA_CB<6>")
	)
	(gr_poly
		(pts
			(xy 329.741276 -247.115838) (xy 329.6412 -247.016016) (xy 329.541124 -247.115838) (xy 329.541124 -247.16359)
			(xy 329.741276 -247.16359)
		)
		(stroke
			(width 0)
			(type solid)
		)
		(fill yes)
		(layer "In13.Cu")
		(net "M_B_CPU0_SA_DQS_DN<9>")
	)
	(gr_poly
		(pts
			(xy 329.741276 -246.712486) (xy 329.741276 -246.664734) (xy 329.541124 -246.664734) (xy 329.541124 -246.712486)
			(xy 329.6412 -246.812308)
		)
		(stroke
			(width 0)
			(type solid)
		)
		(fill yes)
		(layer "In13.Cu")
		(net "M_B_CPU0_SA_DQS_DN<4>")
	)
	(gr_poly
		(pts
			(xy 329.741276 -245.49608) (xy 329.6412 -245.396004) (xy 329.541124 -245.49608) (xy 329.541124 -245.54053)
			(xy 329.741276 -245.54053)
		)
		(stroke
			(width 0)
			(type solid)
		)
		(fill yes)
		(layer "In13.Cu")
		(net "M_B_CPU0_SA_CB<1>")
	)
	(gr_poly
		(pts
			(xy 329.741276 -245.09222) (xy 329.741276 -245.04777) (xy 329.541124 -245.04777) (xy 329.541124 -245.09222)
			(xy 329.6412 -245.192296)
		)
		(stroke
			(width 0)
			(type solid)
		)
		(fill yes)
		(layer "In13.Cu")
		(net "M_B_CPU0_SA_CB<2>")
	)
	(gr_poly
		(pts
			(xy 329.741276 -243.876068) (xy 329.6412 -243.775992) (xy 329.541124 -243.876068) (xy 329.541124 -243.920518)
			(xy 329.741276 -243.920518)
		)
		(stroke
			(width 0)
			(type solid)
		)
		(fill yes)
		(layer "In13.Cu")
		(net "M_B_CPU0_SA_DQ<29>")
	)
	(gr_poly
		(pts
			(xy 329.741276 -243.472208) (xy 329.741276 -243.427758) (xy 329.541124 -243.427758) (xy 329.541124 -243.472208)
			(xy 329.6412 -243.572284)
		)
		(stroke
			(width 0)
			(type solid)
		)
		(fill yes)
		(layer "In13.Cu")
		(net "M_B_CPU0_SA_DQ<30>")
	)
	(gr_poly
		(pts
			(xy 329.741276 -242.255802) (xy 329.6412 -242.15598) (xy 329.541124 -242.255802) (xy 329.541124 -242.303554)
			(xy 329.741276 -242.303554)
		)
		(stroke
			(width 0)
			(type solid)
		)
		(fill yes)
		(layer "In13.Cu")
		(net "M_B_CPU0_SA_DQS_DN<8>")
	)
	(gr_poly
		(pts
			(xy 329.741276 -241.85245) (xy 329.741276 -241.804698) (xy 329.541124 -241.804698) (xy 329.541124 -241.85245)
			(xy 329.6412 -241.952272)
		)
		(stroke
			(width 0)
			(type solid)
		)
		(fill yes)
		(layer "In13.Cu")
		(net "M_B_CPU0_SA_DQS_DN<3>")
	)
	(gr_poly
		(pts
			(xy 329.741276 -240.636044) (xy 329.6412 -240.535968) (xy 329.541124 -240.636044) (xy 329.541124 -240.680494)
			(xy 329.741276 -240.680494)
		)
		(stroke
			(width 0)
			(type solid)
		)
		(fill yes)
		(layer "In13.Cu")
		(net "M_B_CPU0_SA_DQ<25>")
	)
	(gr_poly
		(pts
			(xy 329.741276 -240.232184) (xy 329.741276 -240.187734) (xy 329.541124 -240.187734) (xy 329.541124 -240.232184)
			(xy 329.6412 -240.33226)
		)
		(stroke
			(width 0)
			(type solid)
		)
		(fill yes)
		(layer "In13.Cu")
		(net "M_B_CPU0_SA_DQ<26>")
	)
	(gr_poly
		(pts
			(xy 329.741276 -239.016032) (xy 329.6412 -238.915956) (xy 329.541124 -239.016032) (xy 329.541124 -239.060482)
			(xy 329.741276 -239.060482)
		)
		(stroke
			(width 0)
			(type solid)
		)
		(fill yes)
		(layer "In13.Cu")
		(net "M_B_CPU0_SA_DQ<21>")
	)
	(gr_poly
		(pts
			(xy 329.741276 -238.612172) (xy 329.741276 -238.567722) (xy 329.541124 -238.567722) (xy 329.541124 -238.612172)
			(xy 329.6412 -238.712248)
		)
		(stroke
			(width 0)
			(type solid)
		)
		(fill yes)
		(layer "In13.Cu")
		(net "M_B_CPU0_SA_DQ<22>")
	)
	(gr_poly
		(pts
			(xy 329.741276 -237.395766) (xy 329.6412 -237.295944) (xy 329.541124 -237.395766) (xy 329.541124 -237.443518)
			(xy 329.741276 -237.443518)
		)
		(stroke
			(width 0)
			(type solid)
		)
		(fill yes)
		(layer "In13.Cu")
		(net "M_B_CPU0_SA_DQS_DN<7>")
	)
	(gr_poly
		(pts
			(xy 329.741276 -236.992414) (xy 329.741276 -236.944662) (xy 329.541124 -236.944662) (xy 329.541124 -236.992414)
			(xy 329.6412 -237.092236)
		)
		(stroke
			(width 0)
			(type solid)
		)
		(fill yes)
		(layer "In13.Cu")
		(net "M_B_CPU0_SA_DQS_DN<2>")
	)
	(gr_poly
		(pts
			(xy 329.741276 -235.776008) (xy 329.6412 -235.675932) (xy 329.541124 -235.776008) (xy 329.541124 -235.820458)
			(xy 329.741276 -235.820458)
		)
		(stroke
			(width 0)
			(type solid)
		)
		(fill yes)
		(layer "In13.Cu")
		(net "M_B_CPU0_SA_DQ<17>")
	)
	(gr_poly
		(pts
			(xy 329.741276 -235.372148) (xy 329.741276 -235.327698) (xy 329.541124 -235.327698) (xy 329.541124 -235.372148)
			(xy 329.6412 -235.472224)
		)
		(stroke
			(width 0)
			(type solid)
		)
		(fill yes)
		(layer "In13.Cu")
		(net "M_B_CPU0_SA_DQ<18>")
	)
	(gr_poly
		(pts
			(xy 329.741276 -234.155996) (xy 329.6412 -234.05592) (xy 329.541124 -234.155996) (xy 329.541124 -234.200446)
			(xy 329.741276 -234.200446)
		)
		(stroke
			(width 0)
			(type solid)
		)
		(fill yes)
		(layer "In13.Cu")
		(net "M_B_CPU0_SA_DQ<13>")
	)
	(gr_poly
		(pts
			(xy 329.741276 -233.752136) (xy 329.741276 -233.707686) (xy 329.541124 -233.707686) (xy 329.541124 -233.752136)
			(xy 329.6412 -233.852212)
		)
		(stroke
			(width 0)
			(type solid)
		)
		(fill yes)
		(layer "In13.Cu")
		(net "M_B_CPU0_SA_DQ<14>")
	)
	(gr_poly
		(pts
			(xy 329.741276 -232.53573) (xy 329.6412 -232.435908) (xy 329.541124 -232.53573) (xy 329.541124 -232.583482)
			(xy 329.741276 -232.583482)
		)
		(stroke
			(width 0)
			(type solid)
		)
		(fill yes)
		(layer "In13.Cu")
		(net "M_B_CPU0_SA_DQS_DN<6>")
	)
	(gr_poly
		(pts
			(xy 329.741276 -232.132378) (xy 329.741276 -232.084626) (xy 329.541124 -232.084626) (xy 329.541124 -232.132378)
			(xy 329.6412 -232.2322)
		)
		(stroke
			(width 0)
			(type solid)
		)
		(fill yes)
		(layer "In13.Cu")
		(net "M_B_CPU0_SA_DQS_DN<1>")
	)
	(gr_poly
		(pts
			(xy 329.741276 -230.915972) (xy 329.6412 -230.815896) (xy 329.541124 -230.915972) (xy 329.541124 -230.960422)
			(xy 329.741276 -230.960422)
		)
		(stroke
			(width 0)
			(type solid)
		)
		(fill yes)
		(layer "In13.Cu")
		(net "M_B_CPU0_SA_DQ<9>")
	)
	(gr_poly
		(pts
			(xy 329.741276 -230.512366) (xy 329.741276 -230.467916) (xy 329.541124 -230.467916) (xy 329.541124 -230.512366)
			(xy 329.6412 -230.612188)
		)
		(stroke
			(width 0)
			(type solid)
		)
		(fill yes)
		(layer "In13.Cu")
		(net "M_B_CPU0_SA_DQ<10>")
	)
	(gr_poly
		(pts
			(xy 329.741276 -229.29596) (xy 329.6412 -229.195884) (xy 329.541124 -229.29596) (xy 329.541124 -229.34041)
			(xy 329.741276 -229.34041)
		)
		(stroke
			(width 0)
			(type solid)
		)
		(fill yes)
		(layer "In13.Cu")
		(net "M_B_CPU0_SA_DQ<5>")
	)
	(gr_poly
		(pts
			(xy 329.741276 -228.892354) (xy 329.741276 -228.847904) (xy 329.541124 -228.847904) (xy 329.541124 -228.892354)
			(xy 329.6412 -228.99243)
		)
		(stroke
			(width 0)
			(type solid)
		)
		(fill yes)
		(layer "In13.Cu")
		(net "M_B_CPU0_SA_DQ<6>")
	)
	(gr_poly
		(pts
			(xy 329.759818 -227.276152) (xy 329.796648 -227.1395) (xy 329.659996 -227.102924) (xy 329.618594 -227.1268)
			(xy 329.71867 -227.300028)
		)
		(stroke
			(width 0)
			(type solid)
		)
		(fill yes)
		(layer "In13.Cu")
		(net "M_B_CPU0_SA_DQS_DN<5>")
	)
	(gr_poly
		(pts
			(xy 329.760326 -225.655632) (xy 329.796902 -225.519234) (xy 329.66025 -225.482404) (xy 329.619102 -225.50628)
			(xy 329.718924 -225.679508)
		)
		(stroke
			(width 0)
			(type solid)
		)
		(fill yes)
		(layer "In13.Cu")
		(net "M_B_CPU0_SA_DQS_DP<0>")
	)
	(gr_poly
		(pts
			(xy 329.760326 -224.036382) (xy 329.796902 -223.89973) (xy 329.660504 -223.863154) (xy 329.621896 -223.885506)
			(xy 329.721972 -224.058734)
		)
		(stroke
			(width 0)
			(type solid)
		)
		(fill yes)
		(layer "In13.Cu")
		(net "M_B_CPU0_SA_DQ<1>")
	)
	(gr_poly
		(pts
			(xy 330.0349 -267.801598) (xy 329.934824 -267.701522) (xy 329.835002 -267.801598) (xy 329.835002 -267.846048)
			(xy 330.0349 -267.846048)
		)
		(stroke
			(width 0)
			(type solid)
		)
		(fill yes)
		(layer "In13.Cu")
		(net "M_B_CPU0_SB_RSP<0>")
	)
	(gr_poly
		(pts
			(xy 330.04125 -292.107874) (xy 329.941174 -292.007798) (xy 329.841098 -292.107874) (xy 329.841098 -292.152324)
			(xy 330.04125 -292.152324)
		)
		(stroke
			(width 0)
			(type solid)
		)
		(fill yes)
		(layer "In13.Cu")
		(net "M_B_CPU0_SB_DQ<28>")
	)
	(gr_poly
		(pts
			(xy 330.04125 -291.704268) (xy 330.04125 -291.656516) (xy 329.841098 -291.656516) (xy 329.841098 -291.704268)
			(xy 329.941174 -291.80409)
		)
		(stroke
			(width 0)
			(type solid)
		)
		(fill yes)
		(layer "In13.Cu")
		(net "M_B_CPU0_SB_DQS_DP<8>")
	)
	(gr_poly
		(pts
			(xy 330.04125 -290.487608) (xy 329.941174 -290.387786) (xy 329.841098 -290.487608) (xy 329.841098 -290.53536)
			(xy 330.04125 -290.53536)
		)
		(stroke
			(width 0)
			(type solid)
		)
		(fill yes)
		(layer "In13.Cu")
		(net "M_B_CPU0_SB_DQS_DP<3>")
	)
	(gr_poly
		(pts
			(xy 330.04125 -290.084002) (xy 330.04125 -290.039552) (xy 329.841098 -290.039552) (xy 329.841098 -290.084002)
			(xy 329.941174 -290.184078)
		)
		(stroke
			(width 0)
			(type solid)
		)
		(fill yes)
		(layer "In13.Cu")
		(net "M_B_CPU0_SB_DQ<27>")
	)
	(gr_poly
		(pts
			(xy 330.04125 -288.86785) (xy 329.941174 -288.767774) (xy 329.841098 -288.86785) (xy 329.841098 -288.9123)
			(xy 330.04125 -288.9123)
		)
		(stroke
			(width 0)
			(type solid)
		)
		(fill yes)
		(layer "In13.Cu")
		(net "M_B_CPU0_SB_DQ<24>")
	)
	(gr_poly
		(pts
			(xy 330.04125 -288.464244) (xy 330.04125 -288.419794) (xy 329.841098 -288.419794) (xy 329.841098 -288.464244)
			(xy 329.941174 -288.56432)
		)
		(stroke
			(width 0)
			(type solid)
		)
		(fill yes)
		(layer "In13.Cu")
		(net "M_B_CPU0_SB_DQ<23>")
	)
	(gr_poly
		(pts
			(xy 330.04125 -287.247838) (xy 329.941174 -287.148016) (xy 329.841098 -287.247838) (xy 329.841098 -287.292288)
			(xy 330.04125 -287.292288)
		)
		(stroke
			(width 0)
			(type solid)
		)
		(fill yes)
		(layer "In13.Cu")
		(net "M_B_CPU0_SB_DQ<20>")
	)
	(gr_poly
		(pts
			(xy 330.04125 -286.844232) (xy 330.04125 -286.79648) (xy 329.841098 -286.79648) (xy 329.841098 -286.844232)
			(xy 329.941174 -286.944308)
		)
		(stroke
			(width 0)
			(type solid)
		)
		(fill yes)
		(layer "In13.Cu")
		(net "M_B_CPU0_SB_DQS_DP<7>")
	)
	(gr_poly
		(pts
			(xy 330.04125 -285.627826) (xy 329.941174 -285.528004) (xy 329.841098 -285.627826) (xy 329.841098 -285.675578)
			(xy 330.04125 -285.675578)
		)
		(stroke
			(width 0)
			(type solid)
		)
		(fill yes)
		(layer "In13.Cu")
		(net "M_B_CPU0_SB_DQS_DP<2>")
	)
	(gr_poly
		(pts
			(xy 330.04125 -285.22422) (xy 330.04125 -285.17977) (xy 329.841098 -285.17977) (xy 329.841098 -285.22422)
			(xy 329.941174 -285.324296)
		)
		(stroke
			(width 0)
			(type solid)
		)
		(fill yes)
		(layer "In13.Cu")
		(net "M_B_CPU0_SB_DQ<19>")
	)
	(gr_poly
		(pts
			(xy 330.04125 -284.008068) (xy 329.941174 -283.907992) (xy 329.841098 -284.008068) (xy 329.841098 -284.052518)
			(xy 330.04125 -284.052518)
		)
		(stroke
			(width 0)
			(type solid)
		)
		(fill yes)
		(layer "In13.Cu")
		(net "M_B_CPU0_SB_DQ<16>")
	)
	(gr_poly
		(pts
			(xy 330.04125 -283.604208) (xy 330.04125 -283.559758) (xy 329.841098 -283.559758) (xy 329.841098 -283.604208)
			(xy 329.941174 -283.704284)
		)
		(stroke
			(width 0)
			(type solid)
		)
		(fill yes)
		(layer "In13.Cu")
		(net "M_B_CPU0_SB_DQ<15>")
	)
	(gr_poly
		(pts
			(xy 330.04125 -282.388056) (xy 329.941174 -282.28798) (xy 329.841098 -282.388056) (xy 329.841098 -282.432506)
			(xy 330.04125 -282.432506)
		)
		(stroke
			(width 0)
			(type solid)
		)
		(fill yes)
		(layer "In13.Cu")
		(net "M_B_CPU0_SB_DQ<12>")
	)
	(gr_poly
		(pts
			(xy 330.04125 -281.98445) (xy 330.04125 -281.936698) (xy 329.841098 -281.936698) (xy 329.841098 -281.98445)
			(xy 329.941174 -282.084272)
		)
		(stroke
			(width 0)
			(type solid)
		)
		(fill yes)
		(layer "In13.Cu")
		(net "M_B_CPU0_SB_DQS_DP<6>")
	)
	(gr_poly
		(pts
			(xy 330.04125 -280.76779) (xy 329.941174 -280.667968) (xy 329.841098 -280.76779) (xy 329.841098 -280.815542)
			(xy 330.04125 -280.815542)
		)
		(stroke
			(width 0)
			(type solid)
		)
		(fill yes)
		(layer "In13.Cu")
		(net "M_B_CPU0_SB_DQS_DP<1>")
	)
	(gr_poly
		(pts
			(xy 330.04125 -280.364184) (xy 330.04125 -280.319734) (xy 329.841098 -280.319734) (xy 329.841098 -280.364184)
			(xy 329.941174 -280.46426)
		)
		(stroke
			(width 0)
			(type solid)
		)
		(fill yes)
		(layer "In13.Cu")
		(net "M_B_CPU0_SB_DQ<11>")
	)
	(gr_poly
		(pts
			(xy 330.04125 -279.148032) (xy 329.941174 -279.047956) (xy 329.841098 -279.148032) (xy 329.841098 -279.192482)
			(xy 330.04125 -279.192482)
		)
		(stroke
			(width 0)
			(type solid)
		)
		(fill yes)
		(layer "In13.Cu")
		(net "M_B_CPU0_SB_DQ<8>")
	)
	(gr_poly
		(pts
			(xy 330.04125 -278.744172) (xy 330.04125 -278.699722) (xy 329.841098 -278.699722) (xy 329.841098 -278.744172)
			(xy 329.941174 -278.844248)
		)
		(stroke
			(width 0)
			(type solid)
		)
		(fill yes)
		(layer "In13.Cu")
		(net "M_B_CPU0_SB_DQ<7>")
	)
	(gr_poly
		(pts
			(xy 330.04125 -277.52802) (xy 329.941174 -277.427944) (xy 329.841098 -277.52802) (xy 329.841098 -277.57247)
			(xy 330.04125 -277.57247)
		)
		(stroke
			(width 0)
			(type solid)
		)
		(fill yes)
		(layer "In13.Cu")
		(net "M_B_CPU0_SB_DQ<4>")
	)
	(gr_poly
		(pts
			(xy 330.04125 -277.12416) (xy 330.04125 -277.076662) (xy 329.841098 -277.076662) (xy 329.841098 -277.12416)
			(xy 329.941174 -277.224236)
		)
		(stroke
			(width 0)
			(type solid)
		)
		(fill yes)
		(layer "In13.Cu")
		(net "M_B_CPU0_SB_DQS_DP<5>")
	)
	(gr_poly
		(pts
			(xy 330.04125 -275.908008) (xy 329.941174 -275.807932) (xy 329.841098 -275.908008) (xy 329.841098 -275.955506)
			(xy 330.04125 -275.955506)
		)
		(stroke
			(width 0)
			(type solid)
		)
		(fill yes)
		(layer "In13.Cu")
		(net "M_B_CPU0_SB_DQS_DP<0>")
	)
	(gr_poly
		(pts
			(xy 330.04125 -275.504148) (xy 330.04125 -275.459698) (xy 329.841098 -275.459698) (xy 329.841098 -275.504148)
			(xy 329.941174 -275.604224)
		)
		(stroke
			(width 0)
			(type solid)
		)
		(fill yes)
		(layer "In13.Cu")
		(net "M_B_CPU0_SB_DQ<3>")
	)
	(gr_poly
		(pts
			(xy 330.04125 -274.287996) (xy 329.941174 -274.18792) (xy 329.841098 -274.287996) (xy 329.841098 -274.332446)
			(xy 330.04125 -274.332446)
		)
		(stroke
			(width 0)
			(type solid)
		)
		(fill yes)
		(layer "In13.Cu")
		(net "M_B_CPU0_SB_DQ<0>")
	)
	(gr_poly
		(pts
			(xy 330.04125 -273.884136) (xy 330.04125 -273.839686) (xy 329.841098 -273.839686) (xy 329.841098 -273.884136)
			(xy 329.941174 -273.984212)
		)
		(stroke
			(width 0)
			(type solid)
		)
		(fill yes)
		(layer "In13.Cu")
		(net "M_B_CPU0_SB_CB<3>")
	)
	(gr_poly
		(pts
			(xy 330.04125 -272.667984) (xy 329.941174 -272.567908) (xy 329.841098 -272.667984) (xy 329.841098 -272.712434)
			(xy 330.04125 -272.712434)
		)
		(stroke
			(width 0)
			(type solid)
		)
		(fill yes)
		(layer "In13.Cu")
		(net "M_B_CPU0_SB_CB<0>")
	)
	(gr_poly
		(pts
			(xy 330.04125 -272.264378) (xy 330.04125 -272.216626) (xy 329.841098 -272.216626) (xy 329.841098 -272.264378)
			(xy 329.941174 -272.3642)
		)
		(stroke
			(width 0)
			(type solid)
		)
		(fill yes)
		(layer "In13.Cu")
		(net "M_B_CPU0_SB_DQS_DP<4>")
	)
	(gr_poly
		(pts
			(xy 330.04125 -271.047718) (xy 329.941174 -270.947896) (xy 329.841098 -271.047718) (xy 329.841098 -271.09547)
			(xy 330.04125 -271.09547)
		)
		(stroke
			(width 0)
			(type solid)
		)
		(fill yes)
		(layer "In13.Cu")
		(net "M_B_CPU0_SB_DQS_DP<9>")
	)
	(gr_poly
		(pts
			(xy 330.04125 -270.644112) (xy 330.04125 -270.599662) (xy 329.841098 -270.599662) (xy 329.841098 -270.644112)
			(xy 329.941174 -270.744188)
		)
		(stroke
			(width 0)
			(type solid)
		)
		(fill yes)
		(layer "In13.Cu")
		(net "M_B_CPU0_SB_CB<7>")
	)
	(gr_poly
		(pts
			(xy 330.04125 -269.42796) (xy 329.941174 -269.327884) (xy 329.841098 -269.42796) (xy 329.841098 -269.47241)
			(xy 330.04125 -269.47241)
		)
		(stroke
			(width 0)
			(type solid)
		)
		(fill yes)
		(layer "In13.Cu")
		(net "M_B_CPU0_SB_CB<4>")
	)
	(gr_poly
		(pts
			(xy 330.04125 -265.784076) (xy 330.04125 -265.739626) (xy 329.841098 -265.739626) (xy 329.841098 -265.784076)
			(xy 329.941174 -265.884152)
		)
		(stroke
			(width 0)
			(type solid)
		)
		(fill yes)
		(layer "In13.Cu")
		(net "M_B_CPU0_SB_CS_N<0>")
	)
	(gr_poly
		(pts
			(xy 330.04125 -264.567924) (xy 329.941174 -264.467848) (xy 329.841098 -264.567924) (xy 329.841098 -264.612374)
			(xy 330.04125 -264.612374)
		)
		(stroke
			(width 0)
			(type solid)
		)
		(fill yes)
		(layer "In13.Cu")
		(net "M_B_CPU0_SB_CA<6>")
	)
	(gr_poly
		(pts
			(xy 330.04125 -264.164064) (xy 330.04125 -264.119614) (xy 329.841098 -264.119614) (xy 329.841098 -264.164064)
			(xy 329.941174 -264.26414)
		)
		(stroke
			(width 0)
			(type solid)
		)
		(fill yes)
		(layer "In13.Cu")
		(net "M_B_CPU0_SB_CA<5>")
	)
	(gr_poly
		(pts
			(xy 330.04125 -262.947912) (xy 329.941174 -262.847836) (xy 329.841098 -262.947912) (xy 329.841098 -262.992362)
			(xy 330.04125 -262.992362)
		)
		(stroke
			(width 0)
			(type solid)
		)
		(fill yes)
		(layer "In13.Cu")
		(net "M_B_CPU0_SB_CA<2>")
	)
	(gr_poly
		(pts
			(xy 330.04125 -262.544052) (xy 330.04125 -262.499602) (xy 329.841098 -262.499602) (xy 329.841098 -262.544052)
			(xy 329.941174 -262.644128)
		)
		(stroke
			(width 0)
			(type solid)
		)
		(fill yes)
		(layer "In13.Cu")
		(net "M_B_CPU0_SB_CA<1>")
	)
	(gr_poly
		(pts
			(xy 330.086462 -293.878508) (xy 330.049886 -293.741856) (xy 330.011278 -293.719504) (xy 329.911456 -293.892732)
			(xy 329.94981 -293.915084)
		)
		(stroke
			(width 0)
			(type solid)
		)
		(fill yes)
		(layer "In13.Cu")
		(net "M_B_CPU0_SB_DQ<31>")
	)
	(gr_poly
		(pts
			(xy 330.131166 -225.39452) (xy 330.03109 -225.221292) (xy 329.992482 -225.24339) (xy 329.955906 -225.380042)
			(xy 330.092558 -225.416618)
		)
		(stroke
			(width 0)
			(type solid)
		)
		(fill yes)
		(layer "In13.Cu")
		(net "M_B_CPU0_SA_DQ<3>")
	)
	(gr_poly
		(pts
			(xy 330.131166 -223.774508) (xy 330.03109 -223.60128) (xy 329.992482 -223.623378) (xy 329.955906 -223.76003)
			(xy 330.092558 -223.796606)
		)
		(stroke
			(width 0)
			(type solid)
		)
		(fill yes)
		(layer "In13.Cu")
		(net "M_B_CPU0_SA_DQ<2>")
	)
	(gr_poly
		(pts
			(xy 330.13396 -227.013516) (xy 330.034138 -226.840288) (xy 329.992736 -226.864164) (xy 329.95616 -227.000816)
			(xy 330.092812 -227.037392)
		)
		(stroke
			(width 0)
			(type solid)
		)
		(fill yes)
		(layer "In13.Cu")
		(net "M_B_CPU0_SA_DQS_DN<0>")
	)
	(gr_poly
		(pts
			(xy 330.211176 -256.025904) (xy 330.1111 -255.926082) (xy 330.011024 -256.025904) (xy 330.011024 -256.073656)
			(xy 330.211176 -256.073656)
		)
		(stroke
			(width 0)
			(type solid)
		)
		(fill yes)
		(layer "In13.Cu")
		(net "M_B_CPU0_CLK_DP<0>")
	)
	(gr_poly
		(pts
			(xy 330.211176 -255.622298) (xy 330.211176 -255.577848) (xy 330.011024 -255.577848) (xy 330.011024 -255.622298)
			(xy 330.1111 -255.722374)
		)
		(stroke
			(width 0)
			(type solid)
		)
		(fill yes)
		(layer "In13.Cu")
		(net "M_B_CPU0_SA_PAR")
	)
	(gr_poly
		(pts
			(xy 330.211176 -254.406146) (xy 330.1111 -254.30607) (xy 330.011024 -254.406146) (xy 330.011024 -254.450596)
			(xy 330.211176 -254.450596)
		)
		(stroke
			(width 0)
			(type solid)
		)
		(fill yes)
		(layer "In13.Cu")
		(net "M_B_CPU0_SA_CA<4>")
	)
	(gr_poly
		(pts
			(xy 330.211176 -254.002286) (xy 330.211176 -253.957836) (xy 330.011024 -253.957836) (xy 330.011024 -254.002286)
			(xy 330.1111 -254.102362)
		)
		(stroke
			(width 0)
			(type solid)
		)
		(fill yes)
		(layer "In13.Cu")
		(net "M_B_CPU0_SA_CA<3>")
	)
	(gr_poly
		(pts
			(xy 330.211176 -252.786134) (xy 330.1111 -252.686058) (xy 330.011024 -252.786134) (xy 330.011024 -252.830584)
			(xy 330.211176 -252.830584)
		)
		(stroke
			(width 0)
			(type solid)
		)
		(fill yes)
		(layer "In13.Cu")
		(net "M_B_CPU0_SA_CA<0>")
	)
	(gr_poly
		(pts
			(xy 330.211176 -252.382274) (xy 330.211176 -252.337824) (xy 330.011024 -252.337824) (xy 330.011024 -252.382274)
			(xy 330.1111 -252.48235)
		)
		(stroke
			(width 0)
			(type solid)
		)
		(fill yes)
		(layer "In13.Cu")
		(net "M_B_CPU0_SA_CS_N<1>")
	)
	(gr_poly
		(pts
			(xy 330.211176 -250.762262) (xy 330.211176 -250.717812) (xy 330.011024 -250.717812) (xy 330.011024 -250.762262)
			(xy 330.1111 -250.862338)
		)
		(stroke
			(width 0)
			(type solid)
		)
		(fill yes)
		(layer "In13.Cu")
		(net "M_B_CPU0_RESET_N")
	)
	(gr_poly
		(pts
			(xy 330.211176 -249.14225) (xy 330.211176 -249.0978) (xy 330.011024 -249.0978) (xy 330.011024 -249.14225)
			(xy 330.1111 -249.242326)
		)
		(stroke
			(width 0)
			(type solid)
		)
		(fill yes)
		(layer "In13.Cu")
		(net "M_B_CPU0_SA_CB<7>")
	)
	(gr_poly
		(pts
			(xy 330.211176 -247.926098) (xy 330.1111 -247.826022) (xy 330.011024 -247.926098) (xy 330.011024 -247.970548)
			(xy 330.211176 -247.970548)
		)
		(stroke
			(width 0)
			(type solid)
		)
		(fill yes)
		(layer "In13.Cu")
		(net "M_B_CPU0_SA_CB<4>")
	)
	(gr_poly
		(pts
			(xy 330.211176 -247.522492) (xy 330.211176 -247.47474) (xy 330.011024 -247.47474) (xy 330.011024 -247.522492)
			(xy 330.1111 -247.622314)
		)
		(stroke
			(width 0)
			(type solid)
		)
		(fill yes)
		(layer "In13.Cu")
		(net "M_B_CPU0_SA_DQS_DP<9>")
	)
	(gr_poly
		(pts
			(xy 330.211176 -246.305832) (xy 330.1111 -246.20601) (xy 330.011024 -246.305832) (xy 330.011024 -246.353584)
			(xy 330.211176 -246.353584)
		)
		(stroke
			(width 0)
			(type solid)
		)
		(fill yes)
		(layer "In13.Cu")
		(net "M_B_CPU0_SA_DQS_DP<4>")
	)
	(gr_poly
		(pts
			(xy 330.211176 -245.902226) (xy 330.211176 -245.857776) (xy 330.011024 -245.857776) (xy 330.011024 -245.902226)
			(xy 330.1111 -246.002302)
		)
		(stroke
			(width 0)
			(type solid)
		)
		(fill yes)
		(layer "In13.Cu")
		(net "M_B_CPU0_SA_CB<3>")
	)
	(gr_poly
		(pts
			(xy 330.211176 -244.686074) (xy 330.1111 -244.585998) (xy 330.011024 -244.686074) (xy 330.011024 -244.730524)
			(xy 330.211176 -244.730524)
		)
		(stroke
			(width 0)
			(type solid)
		)
		(fill yes)
		(layer "In13.Cu")
		(net "M_B_CPU0_SA_CB<0>")
	)
	(gr_poly
		(pts
			(xy 330.211176 -244.282214) (xy 330.211176 -244.237764) (xy 330.011024 -244.237764) (xy 330.011024 -244.282214)
			(xy 330.1111 -244.38229)
		)
		(stroke
			(width 0)
			(type solid)
		)
		(fill yes)
		(layer "In13.Cu")
		(net "M_B_CPU0_SA_DQ<31>")
	)
	(gr_poly
		(pts
			(xy 330.211176 -243.066062) (xy 330.1111 -242.965986) (xy 330.011024 -243.066062) (xy 330.011024 -243.110512)
			(xy 330.211176 -243.110512)
		)
		(stroke
			(width 0)
			(type solid)
		)
		(fill yes)
		(layer "In13.Cu")
		(net "M_B_CPU0_SA_DQ<28>")
	)
	(gr_poly
		(pts
			(xy 330.211176 -242.662456) (xy 330.211176 -242.614704) (xy 330.011024 -242.614704) (xy 330.011024 -242.662456)
			(xy 330.1111 -242.762278)
		)
		(stroke
			(width 0)
			(type solid)
		)
		(fill yes)
		(layer "In13.Cu")
		(net "M_B_CPU0_SA_DQS_DP<8>")
	)
	(gr_poly
		(pts
			(xy 330.211176 -241.445796) (xy 330.1111 -241.345974) (xy 330.011024 -241.445796) (xy 330.011024 -241.493548)
			(xy 330.211176 -241.493548)
		)
		(stroke
			(width 0)
			(type solid)
		)
		(fill yes)
		(layer "In13.Cu")
		(net "M_B_CPU0_SA_DQS_DP<3>")
	)
	(gr_poly
		(pts
			(xy 330.211176 -241.04219) (xy 330.211176 -240.99774) (xy 330.011024 -240.99774) (xy 330.011024 -241.04219)
			(xy 330.1111 -241.142266)
		)
		(stroke
			(width 0)
			(type solid)
		)
		(fill yes)
		(layer "In13.Cu")
		(net "M_B_CPU0_SA_DQ<27>")
	)
	(gr_poly
		(pts
			(xy 330.211176 -239.826038) (xy 330.1111 -239.725962) (xy 330.011024 -239.826038) (xy 330.011024 -239.870488)
			(xy 330.211176 -239.870488)
		)
		(stroke
			(width 0)
			(type solid)
		)
		(fill yes)
		(layer "In13.Cu")
		(net "M_B_CPU0_SA_DQ<24>")
	)
	(gr_poly
		(pts
			(xy 330.211176 -239.422178) (xy 330.211176 -239.377728) (xy 330.011024 -239.377728) (xy 330.011024 -239.422178)
			(xy 330.1111 -239.522254)
		)
		(stroke
			(width 0)
			(type solid)
		)
		(fill yes)
		(layer "In13.Cu")
		(net "M_B_CPU0_SA_DQ<23>")
	)
	(gr_poly
		(pts
			(xy 330.211176 -238.206026) (xy 330.1111 -238.10595) (xy 330.011024 -238.206026) (xy 330.011024 -238.250476)
			(xy 330.211176 -238.250476)
		)
		(stroke
			(width 0)
			(type solid)
		)
		(fill yes)
		(layer "In13.Cu")
		(net "M_B_CPU0_SA_DQ<20>")
	)
	(gr_poly
		(pts
			(xy 330.211176 -237.80242) (xy 330.211176 -237.754668) (xy 330.011024 -237.754668) (xy 330.011024 -237.80242)
			(xy 330.1111 -237.902242)
		)
		(stroke
			(width 0)
			(type solid)
		)
		(fill yes)
		(layer "In13.Cu")
		(net "M_B_CPU0_SA_DQS_DP<7>")
	)
	(gr_poly
		(pts
			(xy 330.211176 -236.58576) (xy 330.1111 -236.485938) (xy 330.011024 -236.58576) (xy 330.011024 -236.633512)
			(xy 330.211176 -236.633512)
		)
		(stroke
			(width 0)
			(type solid)
		)
		(fill yes)
		(layer "In13.Cu")
		(net "M_B_CPU0_SA_DQS_DP<2>")
	)
	(gr_poly
		(pts
			(xy 330.211176 -236.182154) (xy 330.211176 -236.137704) (xy 330.011024 -236.137704) (xy 330.011024 -236.182154)
			(xy 330.1111 -236.28223)
		)
		(stroke
			(width 0)
			(type solid)
		)
		(fill yes)
		(layer "In13.Cu")
		(net "M_B_CPU0_SA_DQ<19>")
	)
	(gr_poly
		(pts
			(xy 330.211176 -234.966002) (xy 330.1111 -234.865926) (xy 330.011024 -234.966002) (xy 330.011024 -235.010452)
			(xy 330.211176 -235.010452)
		)
		(stroke
			(width 0)
			(type solid)
		)
		(fill yes)
		(layer "In13.Cu")
		(net "M_B_CPU0_SA_DQ<16>")
	)
	(gr_poly
		(pts
			(xy 330.211176 -234.562142) (xy 330.211176 -234.517692) (xy 330.011024 -234.517692) (xy 330.011024 -234.562142)
			(xy 330.1111 -234.662218)
		)
		(stroke
			(width 0)
			(type solid)
		)
		(fill yes)
		(layer "In13.Cu")
		(net "M_B_CPU0_SA_DQ<15>")
	)
	(gr_poly
		(pts
			(xy 330.211176 -233.34599) (xy 330.1111 -233.245914) (xy 330.011024 -233.34599) (xy 330.011024 -233.39044)
			(xy 330.211176 -233.39044)
		)
		(stroke
			(width 0)
			(type solid)
		)
		(fill yes)
		(layer "In13.Cu")
		(net "M_B_CPU0_SA_DQ<12>")
	)
	(gr_poly
		(pts
			(xy 330.211176 -232.942384) (xy 330.211176 -232.894632) (xy 330.011024 -232.894632) (xy 330.011024 -232.942384)
			(xy 330.1111 -233.042206)
		)
		(stroke
			(width 0)
			(type solid)
		)
		(fill yes)
		(layer "In13.Cu")
		(net "M_B_CPU0_SA_DQS_DP<6>")
	)
	(gr_poly
		(pts
			(xy 330.211176 -231.725724) (xy 330.1111 -231.625902) (xy 330.011024 -231.725724) (xy 330.011024 -231.773476)
			(xy 330.211176 -231.773476)
		)
		(stroke
			(width 0)
			(type solid)
		)
		(fill yes)
		(layer "In13.Cu")
		(net "M_B_CPU0_SA_DQS_DP<1>")
	)
	(gr_poly
		(pts
			(xy 330.211176 -231.322372) (xy 330.211176 -231.277922) (xy 330.011024 -231.277922) (xy 330.011024 -231.322372)
			(xy 330.1111 -231.422448)
		)
		(stroke
			(width 0)
			(type solid)
		)
		(fill yes)
		(layer "In13.Cu")
		(net "M_B_CPU0_SA_DQ<11>")
	)
	(gr_poly
		(pts
			(xy 330.211176 -230.105966) (xy 330.1111 -230.006144) (xy 330.011024 -230.105966) (xy 330.011024 -230.150416)
			(xy 330.211176 -230.150416)
		)
		(stroke
			(width 0)
			(type solid)
		)
		(fill yes)
		(layer "In13.Cu")
		(net "M_B_CPU0_SA_DQ<8>")
	)
	(gr_poly
		(pts
			(xy 330.211176 -229.70236) (xy 330.211176 -229.65791) (xy 330.011024 -229.65791) (xy 330.011024 -229.70236)
			(xy 330.1111 -229.802436)
		)
		(stroke
			(width 0)
			(type solid)
		)
		(fill yes)
		(layer "In13.Cu")
		(net "M_B_CPU0_SA_DQ<7>")
	)
	(gr_poly
		(pts
			(xy 330.211176 -228.486208) (xy 330.1111 -228.386132) (xy 330.011024 -228.486208) (xy 330.011024 -228.530658)
			(xy 330.211176 -228.530658)
		)
		(stroke
			(width 0)
			(type solid)
		)
		(fill yes)
		(layer "In13.Cu")
		(net "M_B_CPU0_SA_DQ<4>")
	)
	(gr_poly
		(pts
			(xy 330.211176 -228.082602) (xy 330.211176 -228.03485) (xy 330.011024 -228.03485) (xy 330.011024 -228.082602)
			(xy 330.1111 -228.182424)
		)
		(stroke
			(width 0)
			(type solid)
		)
		(fill yes)
		(layer "In13.Cu")
		(net "M_B_CPU0_SA_DQS_DP<5>")
	)
	(gr_poly
		(pts
			(xy 330.229464 -226.464368) (xy 330.26604 -226.327716) (xy 330.129388 -226.29114) (xy 330.08824 -226.315016)
			(xy 330.188062 -226.488244)
		)
		(stroke
			(width 0)
			(type solid)
		)
		(fill yes)
		(layer "In13.Cu")
		(net "M_B_CPU0_SA_DQS_DP<0>")
	)
	(gr_poly
		(pts
			(xy 330.229718 -224.845118) (xy 330.266294 -224.708466) (xy 330.129642 -224.67189) (xy 330.091034 -224.693988)
			(xy 330.19111 -224.867216)
		)
		(stroke
			(width 0)
			(type solid)
		)
		(fill yes)
		(layer "In13.Cu")
		(net "M_B_CPU0_SA_DQ<1>")
	)
	(gr_poly
		(pts
			(xy 330.229718 -223.225106) (xy 330.266294 -223.088454) (xy 330.129642 -223.051878) (xy 330.091034 -223.073976)
			(xy 330.19111 -223.247204)
		)
		(stroke
			(width 0)
			(type solid)
		)
		(fill yes)
		(layer "In13.Cu")
		(net "M_B_CPU0_SA_DQ<0>")
	)
	(gr_poly
		(pts
			(xy 330.51115 -292.91788) (xy 330.411074 -292.817804) (xy 330.310998 -292.91788) (xy 330.310998 -292.96233)
			(xy 330.51115 -292.96233)
		)
		(stroke
			(width 0)
			(type solid)
		)
		(fill yes)
		(layer "In13.Cu")
		(net "M_B_CPU0_SB_DQ<29>")
	)
	(gr_poly
		(pts
			(xy 330.51115 -292.51402) (xy 330.51115 -292.46957) (xy 330.310998 -292.46957) (xy 330.310998 -292.51402)
			(xy 330.411074 -292.614096)
		)
		(stroke
			(width 0)
			(type solid)
		)
		(fill yes)
		(layer "In13.Cu")
		(net "M_B_CPU0_SB_DQ<30>")
	)
	(gr_poly
		(pts
			(xy 330.51115 -291.297614) (xy 330.411074 -291.197792) (xy 330.310998 -291.297614) (xy 330.310998 -291.345366)
			(xy 330.51115 -291.345366)
		)
		(stroke
			(width 0)
			(type solid)
		)
		(fill yes)
		(layer "In13.Cu")
		(net "M_B_CPU0_SB_DQS_DN<8>")
	)
	(gr_poly
		(pts
			(xy 330.51115 -290.894262) (xy 330.51115 -290.84651) (xy 330.310998 -290.84651) (xy 330.310998 -290.894262)
			(xy 330.411074 -290.994084)
		)
		(stroke
			(width 0)
			(type solid)
		)
		(fill yes)
		(layer "In13.Cu")
		(net "M_B_CPU0_SB_DQS_DN<3>")
	)
	(gr_poly
		(pts
			(xy 330.51115 -289.677856) (xy 330.411074 -289.57778) (xy 330.310998 -289.677856) (xy 330.310998 -289.722306)
			(xy 330.51115 -289.722306)
		)
		(stroke
			(width 0)
			(type solid)
		)
		(fill yes)
		(layer "In13.Cu")
		(net "M_B_CPU0_SB_DQ<25>")
	)
	(gr_poly
		(pts
			(xy 330.51115 -289.273996) (xy 330.51115 -289.229546) (xy 330.310998 -289.229546) (xy 330.310998 -289.273996)
			(xy 330.411074 -289.374072)
		)
		(stroke
			(width 0)
			(type solid)
		)
		(fill yes)
		(layer "In13.Cu")
		(net "M_B_CPU0_SB_DQ<26>")
	)
	(gr_poly
		(pts
			(xy 330.51115 -288.057844) (xy 330.411074 -287.957768) (xy 330.310998 -288.057844) (xy 330.310998 -288.102294)
			(xy 330.51115 -288.102294)
		)
		(stroke
			(width 0)
			(type solid)
		)
		(fill yes)
		(layer "In13.Cu")
		(net "M_B_CPU0_SB_DQ<21>")
	)
	(gr_poly
		(pts
			(xy 330.51115 -287.654238) (xy 330.51115 -287.609788) (xy 330.310998 -287.609788) (xy 330.310998 -287.654238)
			(xy 330.411074 -287.75406)
		)
		(stroke
			(width 0)
			(type solid)
		)
		(fill yes)
		(layer "In13.Cu")
		(net "M_B_CPU0_SB_DQ<22>")
	)
	(gr_poly
		(pts
			(xy 330.51115 -286.437832) (xy 330.411074 -286.337756) (xy 330.310998 -286.437832) (xy 330.310998 -286.485584)
			(xy 330.51115 -286.485584)
		)
		(stroke
			(width 0)
			(type solid)
		)
		(fill yes)
		(layer "In13.Cu")
		(net "M_B_CPU0_SB_DQS_DN<7>")
	)
	(gr_poly
		(pts
			(xy 330.51115 -286.03448) (xy 330.51115 -285.986728) (xy 330.310998 -285.986728) (xy 330.310998 -286.03448)
			(xy 330.411074 -286.134302)
		)
		(stroke
			(width 0)
			(type solid)
		)
		(fill yes)
		(layer "In13.Cu")
		(net "M_B_CPU0_SB_DQS_DN<2>")
	)
	(gr_poly
		(pts
			(xy 330.51115 -284.818074) (xy 330.411074 -284.717998) (xy 330.310998 -284.818074) (xy 330.310998 -284.862524)
			(xy 330.51115 -284.862524)
		)
		(stroke
			(width 0)
			(type solid)
		)
		(fill yes)
		(layer "In13.Cu")
		(net "M_B_CPU0_SB_DQ<17>")
	)
	(gr_poly
		(pts
			(xy 330.51115 -284.414214) (xy 330.51115 -284.369764) (xy 330.310998 -284.369764) (xy 330.310998 -284.414214)
			(xy 330.411074 -284.51429)
		)
		(stroke
			(width 0)
			(type solid)
		)
		(fill yes)
		(layer "In13.Cu")
		(net "M_B_CPU0_SB_DQ<18>")
	)
	(gr_poly
		(pts
			(xy 330.51115 -283.198062) (xy 330.411074 -283.097986) (xy 330.310998 -283.198062) (xy 330.310998 -283.242512)
			(xy 330.51115 -283.242512)
		)
		(stroke
			(width 0)
			(type solid)
		)
		(fill yes)
		(layer "In13.Cu")
		(net "M_B_CPU0_SB_DQ<13>")
	)
	(gr_poly
		(pts
			(xy 330.51115 -282.794202) (xy 330.51115 -282.749752) (xy 330.310998 -282.749752) (xy 330.310998 -282.794202)
			(xy 330.411074 -282.894278)
		)
		(stroke
			(width 0)
			(type solid)
		)
		(fill yes)
		(layer "In13.Cu")
		(net "M_B_CPU0_SB_DQ<14>")
	)
	(gr_poly
		(pts
			(xy 330.51115 -281.577796) (xy 330.411074 -281.477974) (xy 330.310998 -281.577796) (xy 330.310998 -281.625548)
			(xy 330.51115 -281.625548)
		)
		(stroke
			(width 0)
			(type solid)
		)
		(fill yes)
		(layer "In13.Cu")
		(net "M_B_CPU0_SB_DQS_DN<6>")
	)
	(gr_poly
		(pts
			(xy 330.51115 -281.174444) (xy 330.51115 -281.126692) (xy 330.310998 -281.126692) (xy 330.310998 -281.174444)
			(xy 330.411074 -281.274266)
		)
		(stroke
			(width 0)
			(type solid)
		)
		(fill yes)
		(layer "In13.Cu")
		(net "M_B_CPU0_SB_DQS_DN<1>")
	)
	(gr_poly
		(pts
			(xy 330.51115 -279.958038) (xy 330.411074 -279.857962) (xy 330.310998 -279.958038) (xy 330.310998 -280.002488)
			(xy 330.51115 -280.002488)
		)
		(stroke
			(width 0)
			(type solid)
		)
		(fill yes)
		(layer "In13.Cu")
		(net "M_B_CPU0_SB_DQ<9>")
	)
	(gr_poly
		(pts
			(xy 330.51115 -279.554178) (xy 330.51115 -279.509728) (xy 330.310998 -279.509728) (xy 330.310998 -279.554178)
			(xy 330.411074 -279.654254)
		)
		(stroke
			(width 0)
			(type solid)
		)
		(fill yes)
		(layer "In13.Cu")
		(net "M_B_CPU0_SB_DQ<10>")
	)
	(gr_poly
		(pts
			(xy 330.51115 -278.338026) (xy 330.411074 -278.23795) (xy 330.310998 -278.338026) (xy 330.310998 -278.382476)
			(xy 330.51115 -278.382476)
		)
		(stroke
			(width 0)
			(type solid)
		)
		(fill yes)
		(layer "In13.Cu")
		(net "M_B_CPU0_SB_DQ<5>")
	)
	(gr_poly
		(pts
			(xy 330.51115 -277.934166) (xy 330.51115 -277.889716) (xy 330.310998 -277.889716) (xy 330.310998 -277.934166)
			(xy 330.411074 -278.034242)
		)
		(stroke
			(width 0)
			(type solid)
		)
		(fill yes)
		(layer "In13.Cu")
		(net "M_B_CPU0_SB_DQ<6>")
	)
	(gr_poly
		(pts
			(xy 330.51115 -276.71776) (xy 330.411074 -276.617938) (xy 330.310998 -276.71776) (xy 330.310998 -276.765512)
			(xy 330.51115 -276.765512)
		)
		(stroke
			(width 0)
			(type solid)
		)
		(fill yes)
		(layer "In13.Cu")
		(net "M_B_CPU0_SB_DQS_DN<5>")
	)
	(gr_poly
		(pts
			(xy 330.51115 -276.314408) (xy 330.51115 -276.266656) (xy 330.310998 -276.266656) (xy 330.310998 -276.314408)
			(xy 330.411074 -276.41423)
		)
		(stroke
			(width 0)
			(type solid)
		)
		(fill yes)
		(layer "In13.Cu")
		(net "M_B_CPU0_SB_DQS_DN<0>")
	)
	(gr_poly
		(pts
			(xy 330.51115 -275.098002) (xy 330.411074 -274.997926) (xy 330.310998 -275.098002) (xy 330.310998 -275.142452)
			(xy 330.51115 -275.142452)
		)
		(stroke
			(width 0)
			(type solid)
		)
		(fill yes)
		(layer "In13.Cu")
		(net "M_B_CPU0_SB_DQ<1>")
	)
	(gr_poly
		(pts
			(xy 330.51115 -274.694142) (xy 330.51115 -274.649692) (xy 330.310998 -274.649692) (xy 330.310998 -274.694142)
			(xy 330.411074 -274.794218)
		)
		(stroke
			(width 0)
			(type solid)
		)
		(fill yes)
		(layer "In13.Cu")
		(net "M_B_CPU0_SB_DQ<2>")
	)
	(gr_poly
		(pts
			(xy 330.51115 -273.47799) (xy 330.411074 -273.377914) (xy 330.310998 -273.47799) (xy 330.310998 -273.52244)
			(xy 330.51115 -273.52244)
		)
		(stroke
			(width 0)
			(type solid)
		)
		(fill yes)
		(layer "In13.Cu")
		(net "M_B_CPU0_SB_CB<1>")
	)
	(gr_poly
		(pts
			(xy 330.51115 -273.07413) (xy 330.51115 -273.02968) (xy 330.310998 -273.02968) (xy 330.310998 -273.07413)
			(xy 330.411074 -273.174206)
		)
		(stroke
			(width 0)
			(type solid)
		)
		(fill yes)
		(layer "In13.Cu")
		(net "M_B_CPU0_SB_CB<2>")
	)
	(gr_poly
		(pts
			(xy 330.51115 -271.857724) (xy 330.411074 -271.757902) (xy 330.310998 -271.857724) (xy 330.310998 -271.905476)
			(xy 330.51115 -271.905476)
		)
		(stroke
			(width 0)
			(type solid)
		)
		(fill yes)
		(layer "In13.Cu")
		(net "M_B_CPU0_SB_DQS_DN<4>")
	)
	(gr_poly
		(pts
			(xy 330.51115 -271.454372) (xy 330.51115 -271.40662) (xy 330.310998 -271.40662) (xy 330.310998 -271.454372)
			(xy 330.411074 -271.554194)
		)
		(stroke
			(width 0)
			(type solid)
		)
		(fill yes)
		(layer "In13.Cu")
		(net "M_B_CPU0_SB_DQS_DN<9>")
	)
	(gr_poly
		(pts
			(xy 330.51115 -270.237966) (xy 330.411074 -270.13789) (xy 330.310998 -270.237966) (xy 330.310998 -270.282416)
			(xy 330.51115 -270.282416)
		)
		(stroke
			(width 0)
			(type solid)
		)
		(fill yes)
		(layer "In13.Cu")
		(net "M_B_CPU0_SB_CB<5>")
	)
	(gr_poly
		(pts
			(xy 330.51115 -269.834106) (xy 330.51115 -269.789656) (xy 330.310998 -269.789656) (xy 330.310998 -269.834106)
			(xy 330.411074 -269.934182)
		)
		(stroke
			(width 0)
			(type solid)
		)
		(fill yes)
		(layer "In13.Cu")
		(net "M_B_CPU0_SB_CB<6>")
	)
	(gr_poly
		(pts
			(xy 330.51115 -266.991592) (xy 330.411074 -266.891516) (xy 330.310998 -266.991592) (xy 330.310998 -267.036042)
			(xy 330.51115 -267.036042)
		)
		(stroke
			(width 0)
			(type solid)
		)
		(fill yes)
		(layer "In13.Cu")
		(net "M_B_CPU0_SA_RSP<0>")
	)
	(gr_poly
		(pts
			(xy 330.51115 -266.594082) (xy 330.51115 -266.549632) (xy 330.310998 -266.549632) (xy 330.310998 -266.594082)
			(xy 330.411074 -266.694158)
		)
		(stroke
			(width 0)
			(type solid)
		)
		(fill yes)
		(layer "In13.Cu")
		(net "M_B_CPU0_SB_CS_N<1>")
	)
	(gr_poly
		(pts
			(xy 330.51115 -264.97407) (xy 330.51115 -264.92962) (xy 330.310998 -264.92962) (xy 330.310998 -264.97407)
			(xy 330.411074 -265.074146)
		)
		(stroke
			(width 0)
			(type solid)
		)
		(fill yes)
		(layer "In13.Cu")
		(net "M_B_CPU0_SB_PAR")
	)
	(gr_poly
		(pts
			(xy 330.51115 -263.757918) (xy 330.411074 -263.657842) (xy 330.310998 -263.757918) (xy 330.310998 -263.802368)
			(xy 330.51115 -263.802368)
		)
		(stroke
			(width 0)
			(type solid)
		)
		(fill yes)
		(layer "In13.Cu")
		(net "M_B_CPU0_SB_CA<4>")
	)
	(gr_poly
		(pts
			(xy 330.51115 -263.354058) (xy 330.51115 -263.309608) (xy 330.310998 -263.309608) (xy 330.310998 -263.354058)
			(xy 330.411074 -263.454134)
		)
		(stroke
			(width 0)
			(type solid)
		)
		(fill yes)
		(layer "In13.Cu")
		(net "M_B_CPU0_SB_CA<3>")
	)
	(gr_poly
		(pts
			(xy 330.51115 -262.137906) (xy 330.411074 -262.03783) (xy 330.310998 -262.137906) (xy 330.310998 -262.182356)
			(xy 330.51115 -262.182356)
		)
		(stroke
			(width 0)
			(type solid)
		)
		(fill yes)
		(layer "In13.Cu")
		(net "M_B_CPU0_SB_CA<0>")
	)
	(gr_poly
		(pts
			(xy 330.600304 -226.203002) (xy 330.500228 -226.029774) (xy 330.461874 -226.052126) (xy 330.425298 -226.188778)
			(xy 330.561696 -226.225354)
		)
		(stroke
			(width 0)
			(type solid)
		)
		(fill yes)
		(layer "In13.Cu")
		(net "M_B_CPU0_SA_DQ<3>")
	)
	(gr_poly
		(pts
			(xy 330.600304 -224.58299) (xy 330.500228 -224.409762) (xy 330.461874 -224.432114) (xy 330.425298 -224.568766)
			(xy 330.561696 -224.605342)
		)
		(stroke
			(width 0)
			(type solid)
		)
		(fill yes)
		(layer "In13.Cu")
		(net "M_B_CPU0_SA_DQ<2>")
	)
	(gr_poly
		(pts
			(xy 330.681076 -256.432558) (xy 330.681076 -256.384806) (xy 330.480924 -256.384806) (xy 330.480924 -256.432558)
			(xy 330.581 -256.53238)
		)
		(stroke
			(width 0)
			(type solid)
		)
		(fill yes)
		(layer "In13.Cu")
		(net "M_B_CPU0_CLK_DN<0>")
	)
	(gr_poly
		(pts
			(xy 330.681076 -255.216152) (xy 330.581 -255.116076) (xy 330.480924 -255.216152) (xy 330.480924 -255.260602)
			(xy 330.681076 -255.260602)
		)
		(stroke
			(width 0)
			(type solid)
		)
		(fill yes)
		(layer "In13.Cu")
		(net "M_B_CPU0_SA_CA<6>")
	)
	(gr_poly
		(pts
			(xy 330.681076 -254.812292) (xy 330.681076 -254.767842) (xy 330.480924 -254.767842) (xy 330.480924 -254.812292)
			(xy 330.581 -254.912368)
		)
		(stroke
			(width 0)
			(type solid)
		)
		(fill yes)
		(layer "In13.Cu")
		(net "M_B_CPU0_SA_CA<5>")
	)
	(gr_poly
		(pts
			(xy 330.681076 -253.59614) (xy 330.581 -253.496064) (xy 330.480924 -253.59614) (xy 330.480924 -253.64059)
			(xy 330.681076 -253.64059)
		)
		(stroke
			(width 0)
			(type solid)
		)
		(fill yes)
		(layer "In13.Cu")
		(net "M_B_CPU0_SA_CA<2>")
	)
	(gr_poly
		(pts
			(xy 330.681076 -253.19228) (xy 330.681076 -253.14783) (xy 330.480924 -253.14783) (xy 330.480924 -253.19228)
			(xy 330.581 -253.292356)
		)
		(stroke
			(width 0)
			(type solid)
		)
		(fill yes)
		(layer "In13.Cu")
		(net "M_B_CPU0_SA_CA<1>")
	)
	(gr_poly
		(pts
			(xy 330.681076 -251.572268) (xy 330.681076 -251.527818) (xy 330.480924 -251.527818) (xy 330.480924 -251.572268)
			(xy 330.581 -251.672344)
		)
		(stroke
			(width 0)
			(type solid)
		)
		(fill yes)
		(layer "In13.Cu")
		(net "M_B_CPU0_SA_CS_N<0>")
	)
	(gr_poly
		(pts
			(xy 330.681076 -250.356116) (xy 330.581 -250.25604) (xy 330.480924 -250.356116) (xy 330.480924 -250.400566)
			(xy 330.681076 -250.400566)
		)
		(stroke
			(width 0)
			(type solid)
		)
		(fill yes)
		(layer "In13.Cu")
		(net "M_B_CPU0_ALERT_R_N")
	)
	(gr_poly
		(pts
			(xy 330.681076 -248.736104) (xy 330.581 -248.636028) (xy 330.480924 -248.736104) (xy 330.480924 -248.780554)
			(xy 330.681076 -248.780554)
		)
		(stroke
			(width 0)
			(type solid)
		)
		(fill yes)
		(layer "In13.Cu")
		(net "M_B_CPU0_SA_CB<5>")
	)
	(gr_poly
		(pts
			(xy 330.681076 -248.332244) (xy 330.681076 -248.287794) (xy 330.480924 -248.287794) (xy 330.480924 -248.332244)
			(xy 330.581 -248.43232)
		)
		(stroke
			(width 0)
			(type solid)
		)
		(fill yes)
		(layer "In13.Cu")
		(net "M_B_CPU0_SA_CB<6>")
	)
	(gr_poly
		(pts
			(xy 330.681076 -247.115838) (xy 330.581 -247.016016) (xy 330.480924 -247.115838) (xy 330.480924 -247.16359)
			(xy 330.681076 -247.16359)
		)
		(stroke
			(width 0)
			(type solid)
		)
		(fill yes)
		(layer "In13.Cu")
		(net "M_B_CPU0_SA_DQS_DN<9>")
	)
	(gr_poly
		(pts
			(xy 330.681076 -246.712486) (xy 330.681076 -246.664734) (xy 330.480924 -246.664734) (xy 330.480924 -246.712486)
			(xy 330.581 -246.812308)
		)
		(stroke
			(width 0)
			(type solid)
		)
		(fill yes)
		(layer "In13.Cu")
		(net "M_B_CPU0_SA_DQS_DN<4>")
	)
	(gr_poly
		(pts
			(xy 330.681076 -245.49608) (xy 330.581 -245.396004) (xy 330.480924 -245.49608) (xy 330.480924 -245.54053)
			(xy 330.681076 -245.54053)
		)
		(stroke
			(width 0)
			(type solid)
		)
		(fill yes)
		(layer "In13.Cu")
		(net "M_B_CPU0_SA_CB<1>")
	)
	(gr_poly
		(pts
			(xy 330.681076 -245.09222) (xy 330.681076 -245.04777) (xy 330.480924 -245.04777) (xy 330.480924 -245.09222)
			(xy 330.581 -245.192296)
		)
		(stroke
			(width 0)
			(type solid)
		)
		(fill yes)
		(layer "In13.Cu")
		(net "M_B_CPU0_SA_CB<2>")
	)
	(gr_poly
		(pts
			(xy 330.681076 -243.876068) (xy 330.581 -243.775992) (xy 330.480924 -243.876068) (xy 330.480924 -243.920518)
			(xy 330.681076 -243.920518)
		)
		(stroke
			(width 0)
			(type solid)
		)
		(fill yes)
		(layer "In13.Cu")
		(net "M_B_CPU0_SA_DQ<29>")
	)
	(gr_poly
		(pts
			(xy 330.681076 -243.472208) (xy 330.681076 -243.427758) (xy 330.480924 -243.427758) (xy 330.480924 -243.472208)
			(xy 330.581 -243.572284)
		)
		(stroke
			(width 0)
			(type solid)
		)
		(fill yes)
		(layer "In13.Cu")
		(net "M_B_CPU0_SA_DQ<30>")
	)
	(gr_poly
		(pts
			(xy 330.681076 -242.255802) (xy 330.581 -242.15598) (xy 330.480924 -242.255802) (xy 330.480924 -242.303554)
			(xy 330.681076 -242.303554)
		)
		(stroke
			(width 0)
			(type solid)
		)
		(fill yes)
		(layer "In13.Cu")
		(net "M_B_CPU0_SA_DQS_DN<8>")
	)
	(gr_poly
		(pts
			(xy 330.681076 -241.85245) (xy 330.681076 -241.804698) (xy 330.480924 -241.804698) (xy 330.480924 -241.85245)
			(xy 330.581 -241.952272)
		)
		(stroke
			(width 0)
			(type solid)
		)
		(fill yes)
		(layer "In13.Cu")
		(net "M_B_CPU0_SA_DQS_DN<3>")
	)
	(gr_poly
		(pts
			(xy 330.681076 -240.636044) (xy 330.581 -240.535968) (xy 330.480924 -240.636044) (xy 330.480924 -240.680494)
			(xy 330.681076 -240.680494)
		)
		(stroke
			(width 0)
			(type solid)
		)
		(fill yes)
		(layer "In13.Cu")
		(net "M_B_CPU0_SA_DQ<25>")
	)
	(gr_poly
		(pts
			(xy 330.681076 -240.232184) (xy 330.681076 -240.187734) (xy 330.480924 -240.187734) (xy 330.480924 -240.232184)
			(xy 330.581 -240.33226)
		)
		(stroke
			(width 0)
			(type solid)
		)
		(fill yes)
		(layer "In13.Cu")
		(net "M_B_CPU0_SA_DQ<26>")
	)
	(gr_poly
		(pts
			(xy 330.681076 -239.016032) (xy 330.581 -238.915956) (xy 330.480924 -239.016032) (xy 330.480924 -239.060482)
			(xy 330.681076 -239.060482)
		)
		(stroke
			(width 0)
			(type solid)
		)
		(fill yes)
		(layer "In13.Cu")
		(net "M_B_CPU0_SA_DQ<21>")
	)
	(gr_poly
		(pts
			(xy 330.681076 -238.612172) (xy 330.681076 -238.567722) (xy 330.480924 -238.567722) (xy 330.480924 -238.612172)
			(xy 330.581 -238.712248)
		)
		(stroke
			(width 0)
			(type solid)
		)
		(fill yes)
		(layer "In13.Cu")
		(net "M_B_CPU0_SA_DQ<22>")
	)
	(gr_poly
		(pts
			(xy 330.681076 -237.395766) (xy 330.581 -237.295944) (xy 330.480924 -237.395766) (xy 330.480924 -237.443518)
			(xy 330.681076 -237.443518)
		)
		(stroke
			(width 0)
			(type solid)
		)
		(fill yes)
		(layer "In13.Cu")
		(net "M_B_CPU0_SA_DQS_DN<7>")
	)
	(gr_poly
		(pts
			(xy 330.681076 -236.992414) (xy 330.681076 -236.944662) (xy 330.480924 -236.944662) (xy 330.480924 -236.992414)
			(xy 330.581 -237.092236)
		)
		(stroke
			(width 0)
			(type solid)
		)
		(fill yes)
		(layer "In13.Cu")
		(net "M_B_CPU0_SA_DQS_DN<2>")
	)
	(gr_poly
		(pts
			(xy 330.681076 -235.776008) (xy 330.581 -235.675932) (xy 330.480924 -235.776008) (xy 330.480924 -235.820458)
			(xy 330.681076 -235.820458)
		)
		(stroke
			(width 0)
			(type solid)
		)
		(fill yes)
		(layer "In13.Cu")
		(net "M_B_CPU0_SA_DQ<17>")
	)
	(gr_poly
		(pts
			(xy 330.681076 -235.372148) (xy 330.681076 -235.327698) (xy 330.480924 -235.327698) (xy 330.480924 -235.372148)
			(xy 330.581 -235.472224)
		)
		(stroke
			(width 0)
			(type solid)
		)
		(fill yes)
		(layer "In13.Cu")
		(net "M_B_CPU0_SA_DQ<18>")
	)
	(gr_poly
		(pts
			(xy 330.681076 -234.155996) (xy 330.581 -234.05592) (xy 330.480924 -234.155996) (xy 330.480924 -234.200446)
			(xy 330.681076 -234.200446)
		)
		(stroke
			(width 0)
			(type solid)
		)
		(fill yes)
		(layer "In13.Cu")
		(net "M_B_CPU0_SA_DQ<13>")
	)
	(gr_poly
		(pts
			(xy 330.681076 -233.752136) (xy 330.681076 -233.707686) (xy 330.480924 -233.707686) (xy 330.480924 -233.752136)
			(xy 330.581 -233.852212)
		)
		(stroke
			(width 0)
			(type solid)
		)
		(fill yes)
		(layer "In13.Cu")
		(net "M_B_CPU0_SA_DQ<14>")
	)
	(gr_poly
		(pts
			(xy 330.681076 -232.53573) (xy 330.581 -232.435908) (xy 330.480924 -232.53573) (xy 330.480924 -232.583482)
			(xy 330.681076 -232.583482)
		)
		(stroke
			(width 0)
			(type solid)
		)
		(fill yes)
		(layer "In13.Cu")
		(net "M_B_CPU0_SA_DQS_DN<6>")
	)
	(gr_poly
		(pts
			(xy 330.681076 -232.132378) (xy 330.681076 -232.084626) (xy 330.480924 -232.084626) (xy 330.480924 -232.132378)
			(xy 330.581 -232.2322)
		)
		(stroke
			(width 0)
			(type solid)
		)
		(fill yes)
		(layer "In13.Cu")
		(net "M_B_CPU0_SA_DQS_DN<1>")
	)
	(gr_poly
		(pts
			(xy 330.681076 -230.915972) (xy 330.581 -230.815896) (xy 330.480924 -230.915972) (xy 330.480924 -230.960422)
			(xy 330.681076 -230.960422)
		)
		(stroke
			(width 0)
			(type solid)
		)
		(fill yes)
		(layer "In13.Cu")
		(net "M_B_CPU0_SA_DQ<9>")
	)
	(gr_poly
		(pts
			(xy 330.681076 -230.512366) (xy 330.681076 -230.467916) (xy 330.480924 -230.467916) (xy 330.480924 -230.512366)
			(xy 330.581 -230.612188)
		)
		(stroke
			(width 0)
			(type solid)
		)
		(fill yes)
		(layer "In13.Cu")
		(net "M_B_CPU0_SA_DQ<10>")
	)
	(gr_poly
		(pts
			(xy 330.681076 -229.29596) (xy 330.581 -229.195884) (xy 330.480924 -229.29596) (xy 330.480924 -229.34041)
			(xy 330.681076 -229.34041)
		)
		(stroke
			(width 0)
			(type solid)
		)
		(fill yes)
		(layer "In13.Cu")
		(net "M_B_CPU0_SA_DQ<5>")
	)
	(gr_poly
		(pts
			(xy 330.681076 -228.892354) (xy 330.681076 -228.847904) (xy 330.480924 -228.847904) (xy 330.480924 -228.892354)
			(xy 330.581 -228.99243)
		)
		(stroke
			(width 0)
			(type solid)
		)
		(fill yes)
		(layer "In13.Cu")
		(net "M_B_CPU0_SA_DQ<6>")
	)
	(gr_poly
		(pts
			(xy 330.681076 -227.272596) (xy 330.681076 -227.224844) (xy 330.480924 -227.224844) (xy 330.480924 -227.272596)
			(xy 330.581 -227.372418)
		)
		(stroke
			(width 0)
			(type solid)
		)
		(fill yes)
		(layer "In13.Cu")
		(net "M_B_CPU0_SA_DQS_DN<0>")
	)
	(gr_poly
		(pts
			(xy 330.687172 -227.676456) (xy 330.587096 -227.57638) (xy 330.487274 -227.676456) (xy 330.487274 -227.723954)
			(xy 330.687172 -227.723954)
		)
		(stroke
			(width 0)
			(type solid)
		)
		(fill yes)
		(layer "In13.Cu")
		(net "M_B_CPU0_SA_DQS_DN<5>")
	)
	(gr_poly
		(pts
			(xy 330.70038 -225.656394) (xy 330.73721 -225.519742) (xy 330.600558 -225.483166) (xy 330.56195 -225.505518)
			(xy 330.662026 -225.678746)
		)
		(stroke
			(width 0)
			(type solid)
		)
		(fill yes)
		(layer "In13.Cu")
		(net "M_B_CPU0_SA_DQ<1>")
	)
	(gr_poly
		(pts
			(xy 330.70038 -224.036382) (xy 330.73721 -223.89973) (xy 330.600558 -223.863154) (xy 330.56195 -223.885506)
			(xy 330.662026 -224.058734)
		)
		(stroke
			(width 0)
			(type solid)
		)
		(fill yes)
		(layer "In13.Cu")
		(net "M_B_CPU0_SA_DQ<0>")
	)
	(gr_poly
		(pts
			(xy 330.98105 -293.324026) (xy 330.98105 -293.279576) (xy 330.780898 -293.279576) (xy 330.780898 -293.324026)
			(xy 330.880974 -293.424102)
		)
		(stroke
			(width 0)
			(type solid)
		)
		(fill yes)
		(layer "In13.Cu")
		(net "M_B_CPU0_SB_DQ<31>")
	)
	(gr_poly
		(pts
			(xy 330.98105 -292.107874) (xy 330.880974 -292.007798) (xy 330.780898 -292.107874) (xy 330.780898 -292.152324)
			(xy 330.98105 -292.152324)
		)
		(stroke
			(width 0)
			(type solid)
		)
		(fill yes)
		(layer "In13.Cu")
		(net "M_B_CPU0_SB_DQ<28>")
	)
	(gr_poly
		(pts
			(xy 330.98105 -291.704268) (xy 330.98105 -291.656516) (xy 330.780898 -291.656516) (xy 330.780898 -291.704268)
			(xy 330.880974 -291.80409)
		)
		(stroke
			(width 0)
			(type solid)
		)
		(fill yes)
		(layer "In13.Cu")
		(net "M_B_CPU0_SB_DQS_DP<8>")
	)
	(gr_poly
		(pts
			(xy 330.98105 -290.487608) (xy 330.880974 -290.387786) (xy 330.780898 -290.487608) (xy 330.780898 -290.53536)
			(xy 330.98105 -290.53536)
		)
		(stroke
			(width 0)
			(type solid)
		)
		(fill yes)
		(layer "In13.Cu")
		(net "M_B_CPU0_SB_DQS_DP<3>")
	)
	(gr_poly
		(pts
			(xy 330.98105 -290.084002) (xy 330.98105 -290.039552) (xy 330.780898 -290.039552) (xy 330.780898 -290.084002)
			(xy 330.880974 -290.184078)
		)
		(stroke
			(width 0)
			(type solid)
		)
		(fill yes)
		(layer "In13.Cu")
		(net "M_B_CPU0_SB_DQ<27>")
	)
	(gr_poly
		(pts
			(xy 330.98105 -288.86785) (xy 330.880974 -288.767774) (xy 330.780898 -288.86785) (xy 330.780898 -288.9123)
			(xy 330.98105 -288.9123)
		)
		(stroke
			(width 0)
			(type solid)
		)
		(fill yes)
		(layer "In13.Cu")
		(net "M_B_CPU0_SB_DQ<24>")
	)
	(gr_poly
		(pts
			(xy 330.98105 -288.464244) (xy 330.98105 -288.419794) (xy 330.780898 -288.419794) (xy 330.780898 -288.464244)
			(xy 330.880974 -288.56432)
		)
		(stroke
			(width 0)
			(type solid)
		)
		(fill yes)
		(layer "In13.Cu")
		(net "M_B_CPU0_SB_DQ<23>")
	)
	(gr_poly
		(pts
			(xy 330.98105 -287.247838) (xy 330.880974 -287.148016) (xy 330.780898 -287.247838) (xy 330.780898 -287.292288)
			(xy 330.98105 -287.292288)
		)
		(stroke
			(width 0)
			(type solid)
		)
		(fill yes)
		(layer "In13.Cu")
		(net "M_B_CPU0_SB_DQ<20>")
	)
	(gr_poly
		(pts
			(xy 330.98105 -286.844232) (xy 330.98105 -286.79648) (xy 330.780898 -286.79648) (xy 330.780898 -286.844232)
			(xy 330.880974 -286.944308)
		)
		(stroke
			(width 0)
			(type solid)
		)
		(fill yes)
		(layer "In13.Cu")
		(net "M_B_CPU0_SB_DQS_DP<7>")
	)
	(gr_poly
		(pts
			(xy 330.98105 -285.627826) (xy 330.880974 -285.528004) (xy 330.780898 -285.627826) (xy 330.780898 -285.675578)
			(xy 330.98105 -285.675578)
		)
		(stroke
			(width 0)
			(type solid)
		)
		(fill yes)
		(layer "In13.Cu")
		(net "M_B_CPU0_SB_DQS_DP<2>")
	)
	(gr_poly
		(pts
			(xy 330.98105 -285.22422) (xy 330.98105 -285.17977) (xy 330.780898 -285.17977) (xy 330.780898 -285.22422)
			(xy 330.880974 -285.324296)
		)
		(stroke
			(width 0)
			(type solid)
		)
		(fill yes)
		(layer "In13.Cu")
		(net "M_B_CPU0_SB_DQ<19>")
	)
	(gr_poly
		(pts
			(xy 330.98105 -284.008068) (xy 330.880974 -283.907992) (xy 330.780898 -284.008068) (xy 330.780898 -284.052518)
			(xy 330.98105 -284.052518)
		)
		(stroke
			(width 0)
			(type solid)
		)
		(fill yes)
		(layer "In13.Cu")
		(net "M_B_CPU0_SB_DQ<16>")
	)
	(gr_poly
		(pts
			(xy 330.98105 -283.604208) (xy 330.98105 -283.559758) (xy 330.780898 -283.559758) (xy 330.780898 -283.604208)
			(xy 330.880974 -283.704284)
		)
		(stroke
			(width 0)
			(type solid)
		)
		(fill yes)
		(layer "In13.Cu")
		(net "M_B_CPU0_SB_DQ<15>")
	)
	(gr_poly
		(pts
			(xy 330.98105 -282.388056) (xy 330.880974 -282.28798) (xy 330.780898 -282.388056) (xy 330.780898 -282.432506)
			(xy 330.98105 -282.432506)
		)
		(stroke
			(width 0)
			(type solid)
		)
		(fill yes)
		(layer "In13.Cu")
		(net "M_B_CPU0_SB_DQ<12>")
	)
	(gr_poly
		(pts
			(xy 330.98105 -281.98445) (xy 330.98105 -281.936698) (xy 330.780898 -281.936698) (xy 330.780898 -281.98445)
			(xy 330.880974 -282.084272)
		)
		(stroke
			(width 0)
			(type solid)
		)
		(fill yes)
		(layer "In13.Cu")
		(net "M_B_CPU0_SB_DQS_DP<6>")
	)
	(gr_poly
		(pts
			(xy 330.98105 -280.76779) (xy 330.880974 -280.667968) (xy 330.780898 -280.76779) (xy 330.780898 -280.815542)
			(xy 330.98105 -280.815542)
		)
		(stroke
			(width 0)
			(type solid)
		)
		(fill yes)
		(layer "In13.Cu")
		(net "M_B_CPU0_SB_DQS_DP<1>")
	)
	(gr_poly
		(pts
			(xy 330.98105 -280.364184) (xy 330.98105 -280.319734) (xy 330.780898 -280.319734) (xy 330.780898 -280.364184)
			(xy 330.880974 -280.46426)
		)
		(stroke
			(width 0)
			(type solid)
		)
		(fill yes)
		(layer "In13.Cu")
		(net "M_B_CPU0_SB_DQ<11>")
	)
	(gr_poly
		(pts
			(xy 330.98105 -279.148032) (xy 330.880974 -279.047956) (xy 330.780898 -279.148032) (xy 330.780898 -279.192482)
			(xy 330.98105 -279.192482)
		)
		(stroke
			(width 0)
			(type solid)
		)
		(fill yes)
		(layer "In13.Cu")
		(net "M_B_CPU0_SB_DQ<8>")
	)
	(gr_poly
		(pts
			(xy 330.98105 -278.744172) (xy 330.98105 -278.699722) (xy 330.780898 -278.699722) (xy 330.780898 -278.744172)
			(xy 330.880974 -278.844248)
		)
		(stroke
			(width 0)
			(type solid)
		)
		(fill yes)
		(layer "In13.Cu")
		(net "M_B_CPU0_SB_DQ<7>")
	)
	(gr_poly
		(pts
			(xy 330.98105 -277.52802) (xy 330.880974 -277.427944) (xy 330.780898 -277.52802) (xy 330.780898 -277.57247)
			(xy 330.98105 -277.57247)
		)
		(stroke
			(width 0)
			(type solid)
		)
		(fill yes)
		(layer "In13.Cu")
		(net "M_B_CPU0_SB_DQ<4>")
	)
	(gr_poly
		(pts
			(xy 330.98105 -275.504148) (xy 330.98105 -275.459698) (xy 330.780898 -275.459698) (xy 330.780898 -275.504148)
			(xy 330.880974 -275.604224)
		)
		(stroke
			(width 0)
			(type solid)
		)
		(fill yes)
		(layer "In13.Cu")
		(net "M_B_CPU0_SB_DQ<3>")
	)
	(gr_poly
		(pts
			(xy 330.98105 -274.287996) (xy 330.880974 -274.18792) (xy 330.780898 -274.287996) (xy 330.780898 -274.332446)
			(xy 330.98105 -274.332446)
		)
		(stroke
			(width 0)
			(type solid)
		)
		(fill yes)
		(layer "In13.Cu")
		(net "M_B_CPU0_SB_DQ<0>")
	)
	(gr_poly
		(pts
			(xy 330.98105 -273.884136) (xy 330.98105 -273.839686) (xy 330.780898 -273.839686) (xy 330.780898 -273.884136)
			(xy 330.880974 -273.984212)
		)
		(stroke
			(width 0)
			(type solid)
		)
		(fill yes)
		(layer "In13.Cu")
		(net "M_B_CPU0_SB_CB<3>")
	)
	(gr_poly
		(pts
			(xy 330.98105 -272.667984) (xy 330.880974 -272.567908) (xy 330.780898 -272.667984) (xy 330.780898 -272.712434)
			(xy 330.98105 -272.712434)
		)
		(stroke
			(width 0)
			(type solid)
		)
		(fill yes)
		(layer "In13.Cu")
		(net "M_B_CPU0_SB_CB<0>")
	)
	(gr_poly
		(pts
			(xy 330.98105 -272.264378) (xy 330.98105 -272.216626) (xy 330.780898 -272.216626) (xy 330.780898 -272.264378)
			(xy 330.880974 -272.3642)
		)
		(stroke
			(width 0)
			(type solid)
		)
		(fill yes)
		(layer "In13.Cu")
		(net "M_B_CPU0_SB_DQS_DP<4>")
	)
	(gr_poly
		(pts
			(xy 330.98105 -271.047718) (xy 330.880974 -270.947896) (xy 330.780898 -271.047718) (xy 330.780898 -271.09547)
			(xy 330.98105 -271.09547)
		)
		(stroke
			(width 0)
			(type solid)
		)
		(fill yes)
		(layer "In13.Cu")
		(net "M_B_CPU0_SB_DQS_DP<9>")
	)
	(gr_poly
		(pts
			(xy 330.98105 -270.644112) (xy 330.98105 -270.599662) (xy 330.780898 -270.599662) (xy 330.780898 -270.644112)
			(xy 330.880974 -270.744188)
		)
		(stroke
			(width 0)
			(type solid)
		)
		(fill yes)
		(layer "In13.Cu")
		(net "M_B_CPU0_SB_CB<7>")
	)
	(gr_poly
		(pts
			(xy 330.98105 -269.42796) (xy 330.880974 -269.327884) (xy 330.780898 -269.42796) (xy 330.780898 -269.47241)
			(xy 330.98105 -269.47241)
		)
		(stroke
			(width 0)
			(type solid)
		)
		(fill yes)
		(layer "In13.Cu")
		(net "M_B_CPU0_SB_CB<4>")
	)
	(gr_poly
		(pts
			(xy 330.98105 -264.164064) (xy 330.98105 -264.119614) (xy 330.780898 -264.119614) (xy 330.780898 -264.164064)
			(xy 330.880974 -264.26414)
		)
		(stroke
			(width 0)
			(type solid)
		)
		(fill yes)
		(layer "In13.Cu")
		(net "M_B_CPU0_SB_CA<5>")
	)
	(gr_poly
		(pts
			(xy 330.98105 -262.947912) (xy 330.880974 -262.847836) (xy 330.780898 -262.947912) (xy 330.780898 -262.992362)
			(xy 330.98105 -262.992362)
		)
		(stroke
			(width 0)
			(type solid)
		)
		(fill yes)
		(layer "In13.Cu")
		(net "M_B_CPU0_SB_CA<2>")
	)
	(gr_poly
		(pts
			(xy 330.98105 -262.544052) (xy 330.98105 -262.499602) (xy 330.780898 -262.499602) (xy 330.780898 -262.544052)
			(xy 330.880974 -262.644128)
		)
		(stroke
			(width 0)
			(type solid)
		)
		(fill yes)
		(layer "In13.Cu")
		(net "M_B_CPU0_SB_CA<1>")
	)
	(gr_poly
		(pts
			(xy 330.981304 -265.784076) (xy 330.981304 -265.739626) (xy 330.781152 -265.739626) (xy 330.781152 -265.784076)
			(xy 330.881228 -265.884152)
		)
		(stroke
			(width 0)
			(type solid)
		)
		(fill yes)
		(layer "In13.Cu")
		(net "M_B_CPU0_SB_CS_N<0>")
	)
	(gr_poly
		(pts
			(xy 330.981304 -264.567924) (xy 330.881228 -264.467848) (xy 330.781152 -264.567924) (xy 330.781152 -264.612374)
			(xy 330.981304 -264.612374)
		)
		(stroke
			(width 0)
			(type solid)
		)
		(fill yes)
		(layer "In13.Cu")
		(net "M_B_CPU0_SB_CA<6>")
	)
	(gr_poly
		(pts
			(xy 330.987146 -267.801598) (xy 330.887324 -267.701522) (xy 330.787248 -267.801598) (xy 330.787248 -267.846048)
			(xy 330.987146 -267.846048)
		)
		(stroke
			(width 0)
			(type solid)
		)
		(fill yes)
		(layer "In13.Cu")
		(net "M_B_CPU0_SB_RSP<0>")
	)
	(gr_poly
		(pts
			(xy 330.988416 -277.12416) (xy 330.988416 -277.076662) (xy 330.788264 -277.076662) (xy 330.788264 -277.12416)
			(xy 330.88834 -277.224236)
		)
		(stroke
			(width 0)
			(type solid)
		)
		(fill yes)
		(layer "In13.Cu")
		(net "M_B_CPU0_SB_DQS_DP<5>")
	)
	(gr_poly
		(pts
			(xy 330.988416 -275.908008) (xy 330.88834 -275.807932) (xy 330.788264 -275.908008) (xy 330.788264 -275.955506)
			(xy 330.988416 -275.955506)
		)
		(stroke
			(width 0)
			(type solid)
		)
		(fill yes)
		(layer "In13.Cu")
		(net "M_B_CPU0_SB_DQS_DP<0>")
	)
	(gr_poly
		(pts
			(xy 331.070204 -225.392996) (xy 330.970128 -225.219768) (xy 330.931774 -225.24212) (xy 330.895198 -225.378772)
			(xy 331.031596 -225.415348)
		)
		(stroke
			(width 0)
			(type solid)
		)
		(fill yes)
		(layer "In13.Cu")
		(net "M_B_CPU0_SA_DQ<2>")
	)
	(gr_poly
		(pts
			(xy 331.15123 -256.025904) (xy 331.051154 -255.926082) (xy 330.951078 -256.025904) (xy 330.951078 -256.073656)
			(xy 331.15123 -256.073656)
		)
		(stroke
			(width 0)
			(type solid)
		)
		(fill yes)
		(layer "In13.Cu")
		(net "M_B_CPU0_CLK_DP<0>")
	)
	(gr_poly
		(pts
			(xy 331.15123 -255.622298) (xy 331.15123 -255.577848) (xy 330.951078 -255.577848) (xy 330.951078 -255.622298)
			(xy 331.051154 -255.722374)
		)
		(stroke
			(width 0)
			(type solid)
		)
		(fill yes)
		(layer "In13.Cu")
		(net "M_B_CPU0_SA_PAR")
	)
	(gr_poly
		(pts
			(xy 331.15123 -254.406146) (xy 331.051154 -254.30607) (xy 330.951078 -254.406146) (xy 330.951078 -254.450596)
			(xy 331.15123 -254.450596)
		)
		(stroke
			(width 0)
			(type solid)
		)
		(fill yes)
		(layer "In13.Cu")
		(net "M_B_CPU0_SA_CA<4>")
	)
	(gr_poly
		(pts
			(xy 331.15123 -254.002286) (xy 331.15123 -253.957836) (xy 330.951078 -253.957836) (xy 330.951078 -254.002286)
			(xy 331.051154 -254.102362)
		)
		(stroke
			(width 0)
			(type solid)
		)
		(fill yes)
		(layer "In13.Cu")
		(net "M_B_CPU0_SA_CA<3>")
	)
	(gr_poly
		(pts
			(xy 331.15123 -252.786134) (xy 331.051154 -252.686058) (xy 330.951078 -252.786134) (xy 330.951078 -252.830584)
			(xy 331.15123 -252.830584)
		)
		(stroke
			(width 0)
			(type solid)
		)
		(fill yes)
		(layer "In13.Cu")
		(net "M_B_CPU0_SA_CA<0>")
	)
	(gr_poly
		(pts
			(xy 331.15123 -252.382274) (xy 331.15123 -252.337824) (xy 330.951078 -252.337824) (xy 330.951078 -252.382274)
			(xy 331.051154 -252.48235)
		)
		(stroke
			(width 0)
			(type solid)
		)
		(fill yes)
		(layer "In13.Cu")
		(net "M_B_CPU0_SA_CS_N<1>")
	)
	(gr_poly
		(pts
			(xy 331.15123 -250.762262) (xy 331.15123 -250.717812) (xy 330.951078 -250.717812) (xy 330.951078 -250.762262)
			(xy 331.051154 -250.862338)
		)
		(stroke
			(width 0)
			(type solid)
		)
		(fill yes)
		(layer "In13.Cu")
		(net "M_B_CPU0_RESET_N")
	)
	(gr_poly
		(pts
			(xy 331.15123 -249.14225) (xy 331.15123 -249.0978) (xy 330.951078 -249.0978) (xy 330.951078 -249.14225)
			(xy 331.051154 -249.242326)
		)
		(stroke
			(width 0)
			(type solid)
		)
		(fill yes)
		(layer "In13.Cu")
		(net "M_B_CPU0_SA_CB<7>")
	)
	(gr_poly
		(pts
			(xy 331.15123 -247.926098) (xy 331.051154 -247.826022) (xy 330.951078 -247.926098) (xy 330.951078 -247.970548)
			(xy 331.15123 -247.970548)
		)
		(stroke
			(width 0)
			(type solid)
		)
		(fill yes)
		(layer "In13.Cu")
		(net "M_B_CPU0_SA_CB<4>")
	)
	(gr_poly
		(pts
			(xy 331.15123 -247.522492) (xy 331.15123 -247.47474) (xy 330.951078 -247.47474) (xy 330.951078 -247.522492)
			(xy 331.051154 -247.622314)
		)
		(stroke
			(width 0)
			(type solid)
		)
		(fill yes)
		(layer "In13.Cu")
		(net "M_B_CPU0_SA_DQS_DP<9>")
	)
	(gr_poly
		(pts
			(xy 331.15123 -246.305832) (xy 331.051154 -246.20601) (xy 330.951078 -246.305832) (xy 330.951078 -246.353584)
			(xy 331.15123 -246.353584)
		)
		(stroke
			(width 0)
			(type solid)
		)
		(fill yes)
		(layer "In13.Cu")
		(net "M_B_CPU0_SA_DQS_DP<4>")
	)
	(gr_poly
		(pts
			(xy 331.15123 -245.902226) (xy 331.15123 -245.857776) (xy 330.951078 -245.857776) (xy 330.951078 -245.902226)
			(xy 331.051154 -246.002302)
		)
		(stroke
			(width 0)
			(type solid)
		)
		(fill yes)
		(layer "In13.Cu")
		(net "M_B_CPU0_SA_CB<3>")
	)
	(gr_poly
		(pts
			(xy 331.15123 -244.686074) (xy 331.051154 -244.585998) (xy 330.951078 -244.686074) (xy 330.951078 -244.730524)
			(xy 331.15123 -244.730524)
		)
		(stroke
			(width 0)
			(type solid)
		)
		(fill yes)
		(layer "In13.Cu")
		(net "M_B_CPU0_SA_CB<0>")
	)
	(gr_poly
		(pts
			(xy 331.15123 -244.282214) (xy 331.15123 -244.237764) (xy 330.951078 -244.237764) (xy 330.951078 -244.282214)
			(xy 331.051154 -244.38229)
		)
		(stroke
			(width 0)
			(type solid)
		)
		(fill yes)
		(layer "In13.Cu")
		(net "M_B_CPU0_SA_DQ<31>")
	)
	(gr_poly
		(pts
			(xy 331.15123 -243.066062) (xy 331.051154 -242.965986) (xy 330.951078 -243.066062) (xy 330.951078 -243.110512)
			(xy 331.15123 -243.110512)
		)
		(stroke
			(width 0)
			(type solid)
		)
		(fill yes)
		(layer "In13.Cu")
		(net "M_B_CPU0_SA_DQ<28>")
	)
	(gr_poly
		(pts
			(xy 331.15123 -242.662456) (xy 331.15123 -242.614704) (xy 330.951078 -242.614704) (xy 330.951078 -242.662456)
			(xy 331.051154 -242.762278)
		)
		(stroke
			(width 0)
			(type solid)
		)
		(fill yes)
		(layer "In13.Cu")
		(net "M_B_CPU0_SA_DQS_DP<8>")
	)
	(gr_poly
		(pts
			(xy 331.15123 -241.445796) (xy 331.051154 -241.345974) (xy 330.951078 -241.445796) (xy 330.951078 -241.493548)
			(xy 331.15123 -241.493548)
		)
		(stroke
			(width 0)
			(type solid)
		)
		(fill yes)
		(layer "In13.Cu")
		(net "M_B_CPU0_SA_DQS_DP<3>")
	)
	(gr_poly
		(pts
			(xy 331.15123 -241.04219) (xy 331.15123 -240.99774) (xy 330.951078 -240.99774) (xy 330.951078 -241.04219)
			(xy 331.051154 -241.142266)
		)
		(stroke
			(width 0)
			(type solid)
		)
		(fill yes)
		(layer "In13.Cu")
		(net "M_B_CPU0_SA_DQ<27>")
	)
	(gr_poly
		(pts
			(xy 331.15123 -239.826038) (xy 331.051154 -239.725962) (xy 330.951078 -239.826038) (xy 330.951078 -239.870488)
			(xy 331.15123 -239.870488)
		)
		(stroke
			(width 0)
			(type solid)
		)
		(fill yes)
		(layer "In13.Cu")
		(net "M_B_CPU0_SA_DQ<24>")
	)
	(gr_poly
		(pts
			(xy 331.15123 -239.422178) (xy 331.15123 -239.377728) (xy 330.951078 -239.377728) (xy 330.951078 -239.422178)
			(xy 331.051154 -239.522254)
		)
		(stroke
			(width 0)
			(type solid)
		)
		(fill yes)
		(layer "In13.Cu")
		(net "M_B_CPU0_SA_DQ<23>")
	)
	(gr_poly
		(pts
			(xy 331.15123 -238.206026) (xy 331.051154 -238.10595) (xy 330.951078 -238.206026) (xy 330.951078 -238.250476)
			(xy 331.15123 -238.250476)
		)
		(stroke
			(width 0)
			(type solid)
		)
		(fill yes)
		(layer "In13.Cu")
		(net "M_B_CPU0_SA_DQ<20>")
	)
	(gr_poly
		(pts
			(xy 331.15123 -237.80242) (xy 331.15123 -237.754668) (xy 330.951078 -237.754668) (xy 330.951078 -237.80242)
			(xy 331.051154 -237.902242)
		)
		(stroke
			(width 0)
			(type solid)
		)
		(fill yes)
		(layer "In13.Cu")
		(net "M_B_CPU0_SA_DQS_DP<7>")
	)
	(gr_poly
		(pts
			(xy 331.15123 -236.58576) (xy 331.051154 -236.485938) (xy 330.951078 -236.58576) (xy 330.951078 -236.633512)
			(xy 331.15123 -236.633512)
		)
		(stroke
			(width 0)
			(type solid)
		)
		(fill yes)
		(layer "In13.Cu")
		(net "M_B_CPU0_SA_DQS_DP<2>")
	)
	(gr_poly
		(pts
			(xy 331.15123 -236.182154) (xy 331.15123 -236.137704) (xy 330.951078 -236.137704) (xy 330.951078 -236.182154)
			(xy 331.051154 -236.28223)
		)
		(stroke
			(width 0)
			(type solid)
		)
		(fill yes)
		(layer "In13.Cu")
		(net "M_B_CPU0_SA_DQ<19>")
	)
	(gr_poly
		(pts
			(xy 331.15123 -234.966002) (xy 331.051154 -234.865926) (xy 330.951078 -234.966002) (xy 330.951078 -235.010452)
			(xy 331.15123 -235.010452)
		)
		(stroke
			(width 0)
			(type solid)
		)
		(fill yes)
		(layer "In13.Cu")
		(net "M_B_CPU0_SA_DQ<16>")
	)
	(gr_poly
		(pts
			(xy 331.15123 -234.562142) (xy 331.15123 -234.517692) (xy 330.951078 -234.517692) (xy 330.951078 -234.562142)
			(xy 331.051154 -234.662218)
		)
		(stroke
			(width 0)
			(type solid)
		)
		(fill yes)
		(layer "In13.Cu")
		(net "M_B_CPU0_SA_DQ<15>")
	)
	(gr_poly
		(pts
			(xy 331.15123 -233.34599) (xy 331.051154 -233.245914) (xy 330.951078 -233.34599) (xy 330.951078 -233.39044)
			(xy 331.15123 -233.39044)
		)
		(stroke
			(width 0)
			(type solid)
		)
		(fill yes)
		(layer "In13.Cu")
		(net "M_B_CPU0_SA_DQ<12>")
	)
	(gr_poly
		(pts
			(xy 331.15123 -232.942384) (xy 331.15123 -232.894632) (xy 330.951078 -232.894632) (xy 330.951078 -232.942384)
			(xy 331.051154 -233.042206)
		)
		(stroke
			(width 0)
			(type solid)
		)
		(fill yes)
		(layer "In13.Cu")
		(net "M_B_CPU0_SA_DQS_DP<6>")
	)
	(gr_poly
		(pts
			(xy 331.15123 -231.725724) (xy 331.051154 -231.625902) (xy 330.951078 -231.725724) (xy 330.951078 -231.773476)
			(xy 331.15123 -231.773476)
		)
		(stroke
			(width 0)
			(type solid)
		)
		(fill yes)
		(layer "In13.Cu")
		(net "M_B_CPU0_SA_DQS_DP<1>")
	)
	(gr_poly
		(pts
			(xy 331.15123 -231.322372) (xy 331.15123 -231.277922) (xy 330.951078 -231.277922) (xy 330.951078 -231.322372)
			(xy 331.051154 -231.422448)
		)
		(stroke
			(width 0)
			(type solid)
		)
		(fill yes)
		(layer "In13.Cu")
		(net "M_B_CPU0_SA_DQ<11>")
	)
	(gr_poly
		(pts
			(xy 331.15123 -230.105966) (xy 331.051154 -230.006144) (xy 330.951078 -230.105966) (xy 330.951078 -230.150416)
			(xy 331.15123 -230.150416)
		)
		(stroke
			(width 0)
			(type solid)
		)
		(fill yes)
		(layer "In13.Cu")
		(net "M_B_CPU0_SA_DQ<8>")
	)
	(gr_poly
		(pts
			(xy 331.15123 -229.70236) (xy 331.15123 -229.65791) (xy 330.951078 -229.65791) (xy 330.951078 -229.70236)
			(xy 331.051154 -229.802436)
		)
		(stroke
			(width 0)
			(type solid)
		)
		(fill yes)
		(layer "In13.Cu")
		(net "M_B_CPU0_SA_DQ<7>")
	)
	(gr_poly
		(pts
			(xy 331.15123 -228.486208) (xy 331.051154 -228.386132) (xy 330.951078 -228.486208) (xy 330.951078 -228.530658)
			(xy 331.15123 -228.530658)
		)
		(stroke
			(width 0)
			(type solid)
		)
		(fill yes)
		(layer "In13.Cu")
		(net "M_B_CPU0_SA_DQ<4>")
	)
	(gr_poly
		(pts
			(xy 331.15123 -228.082602) (xy 331.15123 -228.03485) (xy 330.951078 -228.03485) (xy 330.951078 -228.082602)
			(xy 331.051154 -228.182424)
		)
		(stroke
			(width 0)
			(type solid)
		)
		(fill yes)
		(layer "In13.Cu")
		(net "M_B_CPU0_SA_DQS_DP<5>")
	)
	(gr_poly
		(pts
			(xy 331.15123 -226.865942) (xy 331.051154 -226.76612) (xy 330.951078 -226.865942) (xy 330.951078 -226.913694)
			(xy 331.15123 -226.913694)
		)
		(stroke
			(width 0)
			(type solid)
		)
		(fill yes)
		(layer "In13.Cu")
		(net "M_B_CPU0_SA_DQS_DP<0>")
	)
	(gr_poly
		(pts
			(xy 331.15123 -226.462336) (xy 331.15123 -226.417886) (xy 330.951078 -226.417886) (xy 330.951078 -226.462336)
			(xy 331.051154 -226.562412)
		)
		(stroke
			(width 0)
			(type solid)
		)
		(fill yes)
		(layer "In13.Cu")
		(net "M_B_CPU0_SA_DQ<3>")
	)
	(gr_poly
		(pts
			(xy 331.17028 -224.846388) (xy 331.20711 -224.709736) (xy 331.070458 -224.67316) (xy 331.03185 -224.695512)
			(xy 331.131926 -224.86874)
		)
		(stroke
			(width 0)
			(type solid)
		)
		(fill yes)
		(layer "In13.Cu")
		(net "M_B_CPU0_SA_DQ<0>")
	)
	(gr_poly
		(pts
			(xy 331.444854 -266.991592) (xy 331.344778 -266.891516) (xy 331.244956 -266.991592) (xy 331.244956 -267.036042)
			(xy 331.444854 -267.036042)
		)
		(stroke
			(width 0)
			(type solid)
		)
		(fill yes)
		(layer "In13.Cu")
		(net "M_B_CPU0_SA_RSP<0>")
	)
	(gr_poly
		(pts
			(xy 331.451204 -292.91788) (xy 331.351128 -292.817804) (xy 331.251052 -292.91788) (xy 331.251052 -292.96233)
			(xy 331.451204 -292.96233)
		)
		(stroke
			(width 0)
			(type solid)
		)
		(fill yes)
		(layer "In13.Cu")
		(net "M_B_CPU0_SB_DQ<29>")
	)
	(gr_poly
		(pts
			(xy 331.451204 -292.51402) (xy 331.451204 -292.46957) (xy 331.251052 -292.46957) (xy 331.251052 -292.51402)
			(xy 331.351128 -292.614096)
		)
		(stroke
			(width 0)
			(type solid)
		)
		(fill yes)
		(layer "In13.Cu")
		(net "M_B_CPU0_SB_DQ<30>")
	)
	(gr_poly
		(pts
			(xy 331.451204 -291.297614) (xy 331.351128 -291.197792) (xy 331.251052 -291.297614) (xy 331.251052 -291.345366)
			(xy 331.451204 -291.345366)
		)
		(stroke
			(width 0)
			(type solid)
		)
		(fill yes)
		(layer "In13.Cu")
		(net "M_B_CPU0_SB_DQS_DN<8>")
	)
	(gr_poly
		(pts
			(xy 331.451204 -290.894262) (xy 331.451204 -290.84651) (xy 331.251052 -290.84651) (xy 331.251052 -290.894262)
			(xy 331.351128 -290.994084)
		)
		(stroke
			(width 0)
			(type solid)
		)
		(fill yes)
		(layer "In13.Cu")
		(net "M_B_CPU0_SB_DQS_DN<3>")
	)
	(gr_poly
		(pts
			(xy 331.451204 -289.677856) (xy 331.351128 -289.57778) (xy 331.251052 -289.677856) (xy 331.251052 -289.722306)
			(xy 331.451204 -289.722306)
		)
		(stroke
			(width 0)
			(type solid)
		)
		(fill yes)
		(layer "In13.Cu")
		(net "M_B_CPU0_SB_DQ<25>")
	)
	(gr_poly
		(pts
			(xy 331.451204 -289.273996) (xy 331.451204 -289.229546) (xy 331.251052 -289.229546) (xy 331.251052 -289.273996)
			(xy 331.351128 -289.374072)
		)
		(stroke
			(width 0)
			(type solid)
		)
		(fill yes)
		(layer "In13.Cu")
		(net "M_B_CPU0_SB_DQ<26>")
	)
	(gr_poly
		(pts
			(xy 331.451204 -288.057844) (xy 331.351128 -287.957768) (xy 331.251052 -288.057844) (xy 331.251052 -288.102294)
			(xy 331.451204 -288.102294)
		)
		(stroke
			(width 0)
			(type solid)
		)
		(fill yes)
		(layer "In13.Cu")
		(net "M_B_CPU0_SB_DQ<21>")
	)
	(gr_poly
		(pts
			(xy 331.451204 -287.654238) (xy 331.451204 -287.609788) (xy 331.251052 -287.609788) (xy 331.251052 -287.654238)
			(xy 331.351128 -287.75406)
		)
		(stroke
			(width 0)
			(type solid)
		)
		(fill yes)
		(layer "In13.Cu")
		(net "M_B_CPU0_SB_DQ<22>")
	)
	(gr_poly
		(pts
			(xy 331.451204 -286.437832) (xy 331.351128 -286.337756) (xy 331.251052 -286.437832) (xy 331.251052 -286.485584)
			(xy 331.451204 -286.485584)
		)
		(stroke
			(width 0)
			(type solid)
		)
		(fill yes)
		(layer "In13.Cu")
		(net "M_B_CPU0_SB_DQS_DN<7>")
	)
	(gr_poly
		(pts
			(xy 331.451204 -286.03448) (xy 331.451204 -285.986728) (xy 331.251052 -285.986728) (xy 331.251052 -286.03448)
			(xy 331.351128 -286.134302)
		)
		(stroke
			(width 0)
			(type solid)
		)
		(fill yes)
		(layer "In13.Cu")
		(net "M_B_CPU0_SB_DQS_DN<2>")
	)
	(gr_poly
		(pts
			(xy 331.451204 -284.818074) (xy 331.351128 -284.717998) (xy 331.251052 -284.818074) (xy 331.251052 -284.862524)
			(xy 331.451204 -284.862524)
		)
		(stroke
			(width 0)
			(type solid)
		)
		(fill yes)
		(layer "In13.Cu")
		(net "M_B_CPU0_SB_DQ<17>")
	)
	(gr_poly
		(pts
			(xy 331.451204 -284.414214) (xy 331.451204 -284.369764) (xy 331.251052 -284.369764) (xy 331.251052 -284.414214)
			(xy 331.351128 -284.51429)
		)
		(stroke
			(width 0)
			(type solid)
		)
		(fill yes)
		(layer "In13.Cu")
		(net "M_B_CPU0_SB_DQ<18>")
	)
	(gr_poly
		(pts
			(xy 331.451204 -283.198062) (xy 331.351128 -283.097986) (xy 331.251052 -283.198062) (xy 331.251052 -283.242512)
			(xy 331.451204 -283.242512)
		)
		(stroke
			(width 0)
			(type solid)
		)
		(fill yes)
		(layer "In13.Cu")
		(net "M_B_CPU0_SB_DQ<13>")
	)
	(gr_poly
		(pts
			(xy 331.451204 -282.794202) (xy 331.451204 -282.749752) (xy 331.251052 -282.749752) (xy 331.251052 -282.794202)
			(xy 331.351128 -282.894278)
		)
		(stroke
			(width 0)
			(type solid)
		)
		(fill yes)
		(layer "In13.Cu")
		(net "M_B_CPU0_SB_DQ<14>")
	)
	(gr_poly
		(pts
			(xy 331.451204 -281.577796) (xy 331.351128 -281.477974) (xy 331.251052 -281.577796) (xy 331.251052 -281.625548)
			(xy 331.451204 -281.625548)
		)
		(stroke
			(width 0)
			(type solid)
		)
		(fill yes)
		(layer "In13.Cu")
		(net "M_B_CPU0_SB_DQS_DN<6>")
	)
	(gr_poly
		(pts
			(xy 331.451204 -281.174444) (xy 331.451204 -281.126692) (xy 331.251052 -281.126692) (xy 331.251052 -281.174444)
			(xy 331.351128 -281.274266)
		)
		(stroke
			(width 0)
			(type solid)
		)
		(fill yes)
		(layer "In13.Cu")
		(net "M_B_CPU0_SB_DQS_DN<1>")
	)
	(gr_poly
		(pts
			(xy 331.451204 -279.958038) (xy 331.351128 -279.857962) (xy 331.251052 -279.958038) (xy 331.251052 -280.002488)
			(xy 331.451204 -280.002488)
		)
		(stroke
			(width 0)
			(type solid)
		)
		(fill yes)
		(layer "In13.Cu")
		(net "M_B_CPU0_SB_DQ<9>")
	)
	(gr_poly
		(pts
			(xy 331.451204 -279.554178) (xy 331.451204 -279.509728) (xy 331.251052 -279.509728) (xy 331.251052 -279.554178)
			(xy 331.351128 -279.654254)
		)
		(stroke
			(width 0)
			(type solid)
		)
		(fill yes)
		(layer "In13.Cu")
		(net "M_B_CPU0_SB_DQ<10>")
	)
	(gr_poly
		(pts
			(xy 331.451204 -278.338026) (xy 331.351128 -278.23795) (xy 331.251052 -278.338026) (xy 331.251052 -278.382476)
			(xy 331.451204 -278.382476)
		)
		(stroke
			(width 0)
			(type solid)
		)
		(fill yes)
		(layer "In13.Cu")
		(net "M_B_CPU0_SB_DQ<5>")
	)
	(gr_poly
		(pts
			(xy 331.451204 -277.934166) (xy 331.451204 -277.889716) (xy 331.251052 -277.889716) (xy 331.251052 -277.934166)
			(xy 331.351128 -278.034242)
		)
		(stroke
			(width 0)
			(type solid)
		)
		(fill yes)
		(layer "In13.Cu")
		(net "M_B_CPU0_SB_DQ<6>")
	)
	(gr_poly
		(pts
			(xy 331.451204 -276.71776) (xy 331.351128 -276.617938) (xy 331.251052 -276.71776) (xy 331.251052 -276.765512)
			(xy 331.451204 -276.765512)
		)
		(stroke
			(width 0)
			(type solid)
		)
		(fill yes)
		(layer "In13.Cu")
		(net "M_B_CPU0_SB_DQS_DN<5>")
	)
	(gr_poly
		(pts
			(xy 331.451204 -276.314408) (xy 331.451204 -276.266656) (xy 331.251052 -276.266656) (xy 331.251052 -276.314408)
			(xy 331.351128 -276.41423)
		)
		(stroke
			(width 0)
			(type solid)
		)
		(fill yes)
		(layer "In13.Cu")
		(net "M_B_CPU0_SB_DQS_DN<0>")
	)
	(gr_poly
		(pts
			(xy 331.451204 -275.098002) (xy 331.351128 -274.997926) (xy 331.251052 -275.098002) (xy 331.251052 -275.142452)
			(xy 331.451204 -275.142452)
		)
		(stroke
			(width 0)
			(type solid)
		)
		(fill yes)
		(layer "In13.Cu")
		(net "M_B_CPU0_SB_DQ<1>")
	)
	(gr_poly
		(pts
			(xy 331.451204 -274.694142) (xy 331.451204 -274.649692) (xy 331.251052 -274.649692) (xy 331.251052 -274.694142)
			(xy 331.351128 -274.794218)
		)
		(stroke
			(width 0)
			(type solid)
		)
		(fill yes)
		(layer "In13.Cu")
		(net "M_B_CPU0_SB_DQ<2>")
	)
	(gr_poly
		(pts
			(xy 331.451204 -273.47799) (xy 331.351128 -273.377914) (xy 331.251052 -273.47799) (xy 331.251052 -273.52244)
			(xy 331.451204 -273.52244)
		)
		(stroke
			(width 0)
			(type solid)
		)
		(fill yes)
		(layer "In13.Cu")
		(net "M_B_CPU0_SB_CB<1>")
	)
	(gr_poly
		(pts
			(xy 331.451204 -273.07413) (xy 331.451204 -273.02968) (xy 331.251052 -273.02968) (xy 331.251052 -273.07413)
			(xy 331.351128 -273.174206)
		)
		(stroke
			(width 0)
			(type solid)
		)
		(fill yes)
		(layer "In13.Cu")
		(net "M_B_CPU0_SB_CB<2>")
	)
	(gr_poly
		(pts
			(xy 331.451204 -271.857724) (xy 331.351128 -271.757902) (xy 331.251052 -271.857724) (xy 331.251052 -271.905476)
			(xy 331.451204 -271.905476)
		)
		(stroke
			(width 0)
			(type solid)
		)
		(fill yes)
		(layer "In13.Cu")
		(net "M_B_CPU0_SB_DQS_DN<4>")
	)
	(gr_poly
		(pts
			(xy 331.451204 -271.454372) (xy 331.451204 -271.40662) (xy 331.251052 -271.40662) (xy 331.251052 -271.454372)
			(xy 331.351128 -271.554194)
		)
		(stroke
			(width 0)
			(type solid)
		)
		(fill yes)
		(layer "In13.Cu")
		(net "M_B_CPU0_SB_DQS_DN<9>")
	)
	(gr_poly
		(pts
			(xy 331.451204 -270.237966) (xy 331.351128 -270.13789) (xy 331.251052 -270.237966) (xy 331.251052 -270.282416)
			(xy 331.451204 -270.282416)
		)
		(stroke
			(width 0)
			(type solid)
		)
		(fill yes)
		(layer "In13.Cu")
		(net "M_B_CPU0_SB_CB<5>")
	)
	(gr_poly
		(pts
			(xy 331.451204 -269.834106) (xy 331.451204 -269.789656) (xy 331.251052 -269.789656) (xy 331.251052 -269.834106)
			(xy 331.351128 -269.934182)
		)
		(stroke
			(width 0)
			(type solid)
		)
		(fill yes)
		(layer "In13.Cu")
		(net "M_B_CPU0_SB_CB<6>")
	)
	(gr_poly
		(pts
			(xy 331.451204 -266.594082) (xy 331.451204 -266.549632) (xy 331.251052 -266.549632) (xy 331.251052 -266.594082)
			(xy 331.351128 -266.694158)
		)
		(stroke
			(width 0)
			(type solid)
		)
		(fill yes)
		(layer "In13.Cu")
		(net "M_B_CPU0_SB_CS_N<1>")
	)
	(gr_poly
		(pts
			(xy 331.451204 -264.97407) (xy 331.451204 -264.92962) (xy 331.251052 -264.92962) (xy 331.251052 -264.97407)
			(xy 331.351128 -265.074146)
		)
		(stroke
			(width 0)
			(type solid)
		)
		(fill yes)
		(layer "In13.Cu")
		(net "M_B_CPU0_SB_PAR")
	)
	(gr_poly
		(pts
			(xy 331.451204 -263.757918) (xy 331.351128 -263.657842) (xy 331.251052 -263.757918) (xy 331.251052 -263.802368)
			(xy 331.451204 -263.802368)
		)
		(stroke
			(width 0)
			(type solid)
		)
		(fill yes)
		(layer "In13.Cu")
		(net "M_B_CPU0_SB_CA<4>")
	)
	(gr_poly
		(pts
			(xy 331.451204 -263.354058) (xy 331.451204 -263.309608) (xy 331.251052 -263.309608) (xy 331.251052 -263.354058)
			(xy 331.351128 -263.454134)
		)
		(stroke
			(width 0)
			(type solid)
		)
		(fill yes)
		(layer "In13.Cu")
		(net "M_B_CPU0_SB_CA<3>")
	)
	(gr_poly
		(pts
			(xy 331.451204 -262.137906) (xy 331.351128 -262.03783) (xy 331.251052 -262.137906) (xy 331.251052 -262.182356)
			(xy 331.451204 -262.182356)
		)
		(stroke
			(width 0)
			(type solid)
		)
		(fill yes)
		(layer "In13.Cu")
		(net "M_B_CPU0_SB_CA<0>")
	)
	(gr_poly
		(pts
			(xy 331.62113 -256.432558) (xy 331.62113 -256.384806) (xy 331.420978 -256.384806) (xy 331.420978 -256.432558)
			(xy 331.521054 -256.53238)
		)
		(stroke
			(width 0)
			(type solid)
		)
		(fill yes)
		(layer "In13.Cu")
		(net "M_B_CPU0_CLK_DN<0>")
	)
	(gr_poly
		(pts
			(xy 331.62113 -255.216152) (xy 331.521054 -255.116076) (xy 331.420978 -255.216152) (xy 331.420978 -255.260602)
			(xy 331.62113 -255.260602)
		)
		(stroke
			(width 0)
			(type solid)
		)
		(fill yes)
		(layer "In13.Cu")
		(net "M_B_CPU0_SA_CA<6>")
	)
	(gr_poly
		(pts
			(xy 331.62113 -254.812292) (xy 331.62113 -254.767842) (xy 331.420978 -254.767842) (xy 331.420978 -254.812292)
			(xy 331.521054 -254.912368)
		)
		(stroke
			(width 0)
			(type solid)
		)
		(fill yes)
		(layer "In13.Cu")
		(net "M_B_CPU0_SA_CA<5>")
	)
	(gr_poly
		(pts
			(xy 331.62113 -253.59614) (xy 331.521054 -253.496064) (xy 331.420978 -253.59614) (xy 331.420978 -253.64059)
			(xy 331.62113 -253.64059)
		)
		(stroke
			(width 0)
			(type solid)
		)
		(fill yes)
		(layer "In13.Cu")
		(net "M_B_CPU0_SA_CA<2>")
	)
	(gr_poly
		(pts
			(xy 331.62113 -253.19228) (xy 331.62113 -253.14783) (xy 331.420978 -253.14783) (xy 331.420978 -253.19228)
			(xy 331.521054 -253.292356)
		)
		(stroke
			(width 0)
			(type solid)
		)
		(fill yes)
		(layer "In13.Cu")
		(net "M_B_CPU0_SA_CA<1>")
	)
	(gr_poly
		(pts
			(xy 331.62113 -251.572268) (xy 331.62113 -251.527818) (xy 331.420978 -251.527818) (xy 331.420978 -251.572268)
			(xy 331.521054 -251.672344)
		)
		(stroke
			(width 0)
			(type solid)
		)
		(fill yes)
		(layer "In13.Cu")
		(net "M_B_CPU0_SA_CS_N<0>")
	)
	(gr_poly
		(pts
			(xy 331.62113 -250.356116) (xy 331.521054 -250.25604) (xy 331.420978 -250.356116) (xy 331.420978 -250.400566)
			(xy 331.62113 -250.400566)
		)
		(stroke
			(width 0)
			(type solid)
		)
		(fill yes)
		(layer "In13.Cu")
		(net "M_B_CPU0_ALERT_R_N")
	)
	(gr_poly
		(pts
			(xy 331.62113 -248.736104) (xy 331.521054 -248.636028) (xy 331.420978 -248.736104) (xy 331.420978 -248.780554)
			(xy 331.62113 -248.780554)
		)
		(stroke
			(width 0)
			(type solid)
		)
		(fill yes)
		(layer "In13.Cu")
		(net "M_B_CPU0_SA_CB<5>")
	)
	(gr_poly
		(pts
			(xy 331.62113 -248.332244) (xy 331.62113 -248.287794) (xy 331.420978 -248.287794) (xy 331.420978 -248.332244)
			(xy 331.521054 -248.43232)
		)
		(stroke
			(width 0)
			(type solid)
		)
		(fill yes)
		(layer "In13.Cu")
		(net "M_B_CPU0_SA_CB<6>")
	)
	(gr_poly
		(pts
			(xy 331.62113 -247.115838) (xy 331.521054 -247.016016) (xy 331.420978 -247.115838) (xy 331.420978 -247.16359)
			(xy 331.62113 -247.16359)
		)
		(stroke
			(width 0)
			(type solid)
		)
		(fill yes)
		(layer "In13.Cu")
		(net "M_B_CPU0_SA_DQS_DN<9>")
	)
	(gr_poly
		(pts
			(xy 331.62113 -246.712486) (xy 331.62113 -246.664734) (xy 331.420978 -246.664734) (xy 331.420978 -246.712486)
			(xy 331.521054 -246.812308)
		)
		(stroke
			(width 0)
			(type solid)
		)
		(fill yes)
		(layer "In13.Cu")
		(net "M_B_CPU0_SA_DQS_DN<4>")
	)
	(gr_poly
		(pts
			(xy 331.62113 -245.49608) (xy 331.521054 -245.396004) (xy 331.420978 -245.49608) (xy 331.420978 -245.54053)
			(xy 331.62113 -245.54053)
		)
		(stroke
			(width 0)
			(type solid)
		)
		(fill yes)
		(layer "In13.Cu")
		(net "M_B_CPU0_SA_CB<1>")
	)
	(gr_poly
		(pts
			(xy 331.62113 -245.09222) (xy 331.62113 -245.04777) (xy 331.420978 -245.04777) (xy 331.420978 -245.09222)
			(xy 331.521054 -245.192296)
		)
		(stroke
			(width 0)
			(type solid)
		)
		(fill yes)
		(layer "In13.Cu")
		(net "M_B_CPU0_SA_CB<2>")
	)
	(gr_poly
		(pts
			(xy 331.62113 -243.876068) (xy 331.521054 -243.775992) (xy 331.420978 -243.876068) (xy 331.420978 -243.920518)
			(xy 331.62113 -243.920518)
		)
		(stroke
			(width 0)
			(type solid)
		)
		(fill yes)
		(layer "In13.Cu")
		(net "M_B_CPU0_SA_DQ<29>")
	)
	(gr_poly
		(pts
			(xy 331.62113 -243.472208) (xy 331.62113 -243.427758) (xy 331.420978 -243.427758) (xy 331.420978 -243.472208)
			(xy 331.521054 -243.572284)
		)
		(stroke
			(width 0)
			(type solid)
		)
		(fill yes)
		(layer "In13.Cu")
		(net "M_B_CPU0_SA_DQ<30>")
	)
	(gr_poly
		(pts
			(xy 331.62113 -242.255802) (xy 331.521054 -242.15598) (xy 331.420978 -242.255802) (xy 331.420978 -242.303554)
			(xy 331.62113 -242.303554)
		)
		(stroke
			(width 0)
			(type solid)
		)
		(fill yes)
		(layer "In13.Cu")
		(net "M_B_CPU0_SA_DQS_DN<8>")
	)
	(gr_poly
		(pts
			(xy 331.62113 -241.85245) (xy 331.62113 -241.804698) (xy 331.420978 -241.804698) (xy 331.420978 -241.85245)
			(xy 331.521054 -241.952272)
		)
		(stroke
			(width 0)
			(type solid)
		)
		(fill yes)
		(layer "In13.Cu")
		(net "M_B_CPU0_SA_DQS_DN<3>")
	)
	(gr_poly
		(pts
			(xy 331.62113 -240.636044) (xy 331.521054 -240.535968) (xy 331.420978 -240.636044) (xy 331.420978 -240.680494)
			(xy 331.62113 -240.680494)
		)
		(stroke
			(width 0)
			(type solid)
		)
		(fill yes)
		(layer "In13.Cu")
		(net "M_B_CPU0_SA_DQ<25>")
	)
	(gr_poly
		(pts
			(xy 331.62113 -240.232184) (xy 331.62113 -240.187734) (xy 331.420978 -240.187734) (xy 331.420978 -240.232184)
			(xy 331.521054 -240.33226)
		)
		(stroke
			(width 0)
			(type solid)
		)
		(fill yes)
		(layer "In13.Cu")
		(net "M_B_CPU0_SA_DQ<26>")
	)
	(gr_poly
		(pts
			(xy 331.62113 -239.016032) (xy 331.521054 -238.915956) (xy 331.420978 -239.016032) (xy 331.420978 -239.060482)
			(xy 331.62113 -239.060482)
		)
		(stroke
			(width 0)
			(type solid)
		)
		(fill yes)
		(layer "In13.Cu")
		(net "M_B_CPU0_SA_DQ<21>")
	)
	(gr_poly
		(pts
			(xy 331.62113 -238.612172) (xy 331.62113 -238.567722) (xy 331.420978 -238.567722) (xy 331.420978 -238.612172)
			(xy 331.521054 -238.712248)
		)
		(stroke
			(width 0)
			(type solid)
		)
		(fill yes)
		(layer "In13.Cu")
		(net "M_B_CPU0_SA_DQ<22>")
	)
	(gr_poly
		(pts
			(xy 331.62113 -237.395766) (xy 331.521054 -237.295944) (xy 331.420978 -237.395766) (xy 331.420978 -237.443518)
			(xy 331.62113 -237.443518)
		)
		(stroke
			(width 0)
			(type solid)
		)
		(fill yes)
		(layer "In13.Cu")
		(net "M_B_CPU0_SA_DQS_DN<7>")
	)
	(gr_poly
		(pts
			(xy 331.62113 -236.992414) (xy 331.62113 -236.944662) (xy 331.420978 -236.944662) (xy 331.420978 -236.992414)
			(xy 331.521054 -237.092236)
		)
		(stroke
			(width 0)
			(type solid)
		)
		(fill yes)
		(layer "In13.Cu")
		(net "M_B_CPU0_SA_DQS_DN<2>")
	)
	(gr_poly
		(pts
			(xy 331.62113 -235.776008) (xy 331.521054 -235.675932) (xy 331.420978 -235.776008) (xy 331.420978 -235.820458)
			(xy 331.62113 -235.820458)
		)
		(stroke
			(width 0)
			(type solid)
		)
		(fill yes)
		(layer "In13.Cu")
		(net "M_B_CPU0_SA_DQ<17>")
	)
	(gr_poly
		(pts
			(xy 331.62113 -235.372148) (xy 331.62113 -235.327698) (xy 331.420978 -235.327698) (xy 331.420978 -235.372148)
			(xy 331.521054 -235.472224)
		)
		(stroke
			(width 0)
			(type solid)
		)
		(fill yes)
		(layer "In13.Cu")
		(net "M_B_CPU0_SA_DQ<18>")
	)
	(gr_poly
		(pts
			(xy 331.62113 -234.155996) (xy 331.521054 -234.05592) (xy 331.420978 -234.155996) (xy 331.420978 -234.200446)
			(xy 331.62113 -234.200446)
		)
		(stroke
			(width 0)
			(type solid)
		)
		(fill yes)
		(layer "In13.Cu")
		(net "M_B_CPU0_SA_DQ<13>")
	)
	(gr_poly
		(pts
			(xy 331.62113 -233.752136) (xy 331.62113 -233.707686) (xy 331.420978 -233.707686) (xy 331.420978 -233.752136)
			(xy 331.521054 -233.852212)
		)
		(stroke
			(width 0)
			(type solid)
		)
		(fill yes)
		(layer "In13.Cu")
		(net "M_B_CPU0_SA_DQ<14>")
	)
	(gr_poly
		(pts
			(xy 331.62113 -232.53573) (xy 331.521054 -232.435908) (xy 331.420978 -232.53573) (xy 331.420978 -232.583482)
			(xy 331.62113 -232.583482)
		)
		(stroke
			(width 0)
			(type solid)
		)
		(fill yes)
		(layer "In13.Cu")
		(net "M_B_CPU0_SA_DQS_DN<6>")
	)
	(gr_poly
		(pts
			(xy 331.62113 -232.132378) (xy 331.62113 -232.084626) (xy 331.420978 -232.084626) (xy 331.420978 -232.132378)
			(xy 331.521054 -232.2322)
		)
		(stroke
			(width 0)
			(type solid)
		)
		(fill yes)
		(layer "In13.Cu")
		(net "M_B_CPU0_SA_DQS_DN<1>")
	)
	(gr_poly
		(pts
			(xy 331.62113 -230.915972) (xy 331.521054 -230.815896) (xy 331.420978 -230.915972) (xy 331.420978 -230.960422)
			(xy 331.62113 -230.960422)
		)
		(stroke
			(width 0)
			(type solid)
		)
		(fill yes)
		(layer "In13.Cu")
		(net "M_B_CPU0_SA_DQ<9>")
	)
	(gr_poly
		(pts
			(xy 331.62113 -230.512366) (xy 331.62113 -230.467916) (xy 331.420978 -230.467916) (xy 331.420978 -230.512366)
			(xy 331.521054 -230.612188)
		)
		(stroke
			(width 0)
			(type solid)
		)
		(fill yes)
		(layer "In13.Cu")
		(net "M_B_CPU0_SA_DQ<10>")
	)
	(gr_poly
		(pts
			(xy 331.62113 -229.29596) (xy 331.521054 -229.195884) (xy 331.420978 -229.29596) (xy 331.420978 -229.34041)
			(xy 331.62113 -229.34041)
		)
		(stroke
			(width 0)
			(type solid)
		)
		(fill yes)
		(layer "In13.Cu")
		(net "M_B_CPU0_SA_DQ<5>")
	)
	(gr_poly
		(pts
			(xy 331.62113 -228.892354) (xy 331.62113 -228.847904) (xy 331.420978 -228.847904) (xy 331.420978 -228.892354)
			(xy 331.521054 -228.99243)
		)
		(stroke
			(width 0)
			(type solid)
		)
		(fill yes)
		(layer "In13.Cu")
		(net "M_B_CPU0_SA_DQ<6>")
	)
	(gr_poly
		(pts
			(xy 331.62113 -227.272596) (xy 331.62113 -227.224844) (xy 331.420978 -227.224844) (xy 331.420978 -227.272596)
			(xy 331.521054 -227.372418)
		)
		(stroke
			(width 0)
			(type solid)
		)
		(fill yes)
		(layer "In13.Cu")
		(net "M_B_CPU0_SA_DQS_DN<0>")
	)
	(gr_poly
		(pts
			(xy 331.62113 -226.05619) (xy 331.521054 -225.956114) (xy 331.420978 -226.05619) (xy 331.420978 -226.10064)
			(xy 331.62113 -226.10064)
		)
		(stroke
			(width 0)
			(type solid)
		)
		(fill yes)
		(layer "In13.Cu")
		(net "M_B_CPU0_SA_DQ<1>")
	)
	(gr_poly
		(pts
			(xy 331.62113 -225.65233) (xy 331.62113 -225.60788) (xy 331.420978 -225.60788) (xy 331.420978 -225.65233)
			(xy 331.521054 -225.752406)
		)
		(stroke
			(width 0)
			(type solid)
		)
		(fill yes)
		(layer "In13.Cu")
		(net "M_B_CPU0_SA_DQ<2>")
	)
	(gr_poly
		(pts
			(xy 331.627226 -227.676456) (xy 331.52715 -227.57638) (xy 331.427074 -227.676456) (xy 331.427074 -227.723954)
			(xy 331.627226 -227.723954)
		)
		(stroke
			(width 0)
			(type solid)
		)
		(fill yes)
		(layer "In13.Cu")
		(net "M_B_CPU0_SA_DQS_DN<5>")
	)
	(gr_poly
		(pts
			(xy 331.921104 -293.324026) (xy 331.921104 -293.279576) (xy 331.720952 -293.279576) (xy 331.720952 -293.324026)
			(xy 331.821028 -293.424102)
		)
		(stroke
			(width 0)
			(type solid)
		)
		(fill yes)
		(layer "In13.Cu")
		(net "M_B_CPU0_SB_DQ<31>")
	)
	(gr_poly
		(pts
			(xy 331.921104 -292.107874) (xy 331.821028 -292.007798) (xy 331.720952 -292.107874) (xy 331.720952 -292.152324)
			(xy 331.921104 -292.152324)
		)
		(stroke
			(width 0)
			(type solid)
		)
		(fill yes)
		(layer "In13.Cu")
		(net "M_B_CPU0_SB_DQ<28>")
	)
	(gr_poly
		(pts
			(xy 331.921104 -291.704268) (xy 331.921104 -291.656516) (xy 331.720952 -291.656516) (xy 331.720952 -291.704268)
			(xy 331.821028 -291.80409)
		)
		(stroke
			(width 0)
			(type solid)
		)
		(fill yes)
		(layer "In13.Cu")
		(net "M_B_CPU0_SB_DQS_DP<8>")
	)
	(gr_poly
		(pts
			(xy 331.921104 -290.487608) (xy 331.821028 -290.387786) (xy 331.720952 -290.487608) (xy 331.720952 -290.53536)
			(xy 331.921104 -290.53536)
		)
		(stroke
			(width 0)
			(type solid)
		)
		(fill yes)
		(layer "In13.Cu")
		(net "M_B_CPU0_SB_DQS_DP<3>")
	)
	(gr_poly
		(pts
			(xy 331.921104 -290.084002) (xy 331.921104 -290.039552) (xy 331.720952 -290.039552) (xy 331.720952 -290.084002)
			(xy 331.821028 -290.184078)
		)
		(stroke
			(width 0)
			(type solid)
		)
		(fill yes)
		(layer "In13.Cu")
		(net "M_B_CPU0_SB_DQ<27>")
	)
	(gr_poly
		(pts
			(xy 331.921104 -288.86785) (xy 331.821028 -288.767774) (xy 331.720952 -288.86785) (xy 331.720952 -288.9123)
			(xy 331.921104 -288.9123)
		)
		(stroke
			(width 0)
			(type solid)
		)
		(fill yes)
		(layer "In13.Cu")
		(net "M_B_CPU0_SB_DQ<24>")
	)
	(gr_poly
		(pts
			(xy 331.921104 -288.464244) (xy 331.921104 -288.419794) (xy 331.720952 -288.419794) (xy 331.720952 -288.464244)
			(xy 331.821028 -288.56432)
		)
		(stroke
			(width 0)
			(type solid)
		)
		(fill yes)
		(layer "In13.Cu")
		(net "M_B_CPU0_SB_DQ<23>")
	)
	(gr_poly
		(pts
			(xy 331.921104 -287.247838) (xy 331.821028 -287.148016) (xy 331.720952 -287.247838) (xy 331.720952 -287.292288)
			(xy 331.921104 -287.292288)
		)
		(stroke
			(width 0)
			(type solid)
		)
		(fill yes)
		(layer "In13.Cu")
		(net "M_B_CPU0_SB_DQ<20>")
	)
	(gr_poly
		(pts
			(xy 331.921104 -286.844232) (xy 331.921104 -286.79648) (xy 331.720952 -286.79648) (xy 331.720952 -286.844232)
			(xy 331.821028 -286.944308)
		)
		(stroke
			(width 0)
			(type solid)
		)
		(fill yes)
		(layer "In13.Cu")
		(net "M_B_CPU0_SB_DQS_DP<7>")
	)
	(gr_poly
		(pts
			(xy 331.921104 -285.627826) (xy 331.821028 -285.528004) (xy 331.720952 -285.627826) (xy 331.720952 -285.675578)
			(xy 331.921104 -285.675578)
		)
		(stroke
			(width 0)
			(type solid)
		)
		(fill yes)
		(layer "In13.Cu")
		(net "M_B_CPU0_SB_DQS_DP<2>")
	)
	(gr_poly
		(pts
			(xy 331.921104 -285.22422) (xy 331.921104 -285.17977) (xy 331.720952 -285.17977) (xy 331.720952 -285.22422)
			(xy 331.821028 -285.324296)
		)
		(stroke
			(width 0)
			(type solid)
		)
		(fill yes)
		(layer "In13.Cu")
		(net "M_B_CPU0_SB_DQ<19>")
	)
	(gr_poly
		(pts
			(xy 331.921104 -284.008068) (xy 331.821028 -283.907992) (xy 331.720952 -284.008068) (xy 331.720952 -284.052518)
			(xy 331.921104 -284.052518)
		)
		(stroke
			(width 0)
			(type solid)
		)
		(fill yes)
		(layer "In13.Cu")
		(net "M_B_CPU0_SB_DQ<16>")
	)
	(gr_poly
		(pts
			(xy 331.921104 -283.604208) (xy 331.921104 -283.559758) (xy 331.720952 -283.559758) (xy 331.720952 -283.604208)
			(xy 331.821028 -283.704284)
		)
		(stroke
			(width 0)
			(type solid)
		)
		(fill yes)
		(layer "In13.Cu")
		(net "M_B_CPU0_SB_DQ<15>")
	)
	(gr_poly
		(pts
			(xy 331.921104 -282.388056) (xy 331.821028 -282.28798) (xy 331.720952 -282.388056) (xy 331.720952 -282.432506)
			(xy 331.921104 -282.432506)
		)
		(stroke
			(width 0)
			(type solid)
		)
		(fill yes)
		(layer "In13.Cu")
		(net "M_B_CPU0_SB_DQ<12>")
	)
	(gr_poly
		(pts
			(xy 331.921104 -281.98445) (xy 331.921104 -281.936698) (xy 331.720952 -281.936698) (xy 331.720952 -281.98445)
			(xy 331.821028 -282.084272)
		)
		(stroke
			(width 0)
			(type solid)
		)
		(fill yes)
		(layer "In13.Cu")
		(net "M_B_CPU0_SB_DQS_DP<6>")
	)
	(gr_poly
		(pts
			(xy 331.921104 -280.76779) (xy 331.821028 -280.667968) (xy 331.720952 -280.76779) (xy 331.720952 -280.815542)
			(xy 331.921104 -280.815542)
		)
		(stroke
			(width 0)
			(type solid)
		)
		(fill yes)
		(layer "In13.Cu")
		(net "M_B_CPU0_SB_DQS_DP<1>")
	)
	(gr_poly
		(pts
			(xy 331.921104 -280.364184) (xy 331.921104 -280.319734) (xy 331.720952 -280.319734) (xy 331.720952 -280.364184)
			(xy 331.821028 -280.46426)
		)
		(stroke
			(width 0)
			(type solid)
		)
		(fill yes)
		(layer "In13.Cu")
		(net "M_B_CPU0_SB_DQ<11>")
	)
	(gr_poly
		(pts
			(xy 331.921104 -279.148032) (xy 331.821028 -279.047956) (xy 331.720952 -279.148032) (xy 331.720952 -279.192482)
			(xy 331.921104 -279.192482)
		)
		(stroke
			(width 0)
			(type solid)
		)
		(fill yes)
		(layer "In13.Cu")
		(net "M_B_CPU0_SB_DQ<8>")
	)
	(gr_poly
		(pts
			(xy 331.921104 -278.744172) (xy 331.921104 -278.699722) (xy 331.720952 -278.699722) (xy 331.720952 -278.744172)
			(xy 331.821028 -278.844248)
		)
		(stroke
			(width 0)
			(type solid)
		)
		(fill yes)
		(layer "In13.Cu")
		(net "M_B_CPU0_SB_DQ<7>")
	)
	(gr_poly
		(pts
			(xy 331.921104 -277.52802) (xy 331.821028 -277.427944) (xy 331.720952 -277.52802) (xy 331.720952 -277.57247)
			(xy 331.921104 -277.57247)
		)
		(stroke
			(width 0)
			(type solid)
		)
		(fill yes)
		(layer "In13.Cu")
		(net "M_B_CPU0_SB_DQ<4>")
	)
	(gr_poly
		(pts
			(xy 331.921104 -275.504148) (xy 331.921104 -275.459698) (xy 331.720952 -275.459698) (xy 331.720952 -275.504148)
			(xy 331.821028 -275.604224)
		)
		(stroke
			(width 0)
			(type solid)
		)
		(fill yes)
		(layer "In13.Cu")
		(net "M_B_CPU0_SB_DQ<3>")
	)
	(gr_poly
		(pts
			(xy 331.921104 -274.287996) (xy 331.821028 -274.18792) (xy 331.720952 -274.287996) (xy 331.720952 -274.332446)
			(xy 331.921104 -274.332446)
		)
		(stroke
			(width 0)
			(type solid)
		)
		(fill yes)
		(layer "In13.Cu")
		(net "M_B_CPU0_SB_DQ<0>")
	)
	(gr_poly
		(pts
			(xy 331.921104 -273.884136) (xy 331.921104 -273.839686) (xy 331.720952 -273.839686) (xy 331.720952 -273.884136)
			(xy 331.821028 -273.984212)
		)
		(stroke
			(width 0)
			(type solid)
		)
		(fill yes)
		(layer "In13.Cu")
		(net "M_B_CPU0_SB_CB<3>")
	)
	(gr_poly
		(pts
			(xy 331.921104 -272.667984) (xy 331.821028 -272.567908) (xy 331.720952 -272.667984) (xy 331.720952 -272.712434)
			(xy 331.921104 -272.712434)
		)
		(stroke
			(width 0)
			(type solid)
		)
		(fill yes)
		(layer "In13.Cu")
		(net "M_B_CPU0_SB_CB<0>")
	)
	(gr_poly
		(pts
			(xy 331.921104 -272.264378) (xy 331.921104 -272.216626) (xy 331.720952 -272.216626) (xy 331.720952 -272.264378)
			(xy 331.821028 -272.3642)
		)
		(stroke
			(width 0)
			(type solid)
		)
		(fill yes)
		(layer "In13.Cu")
		(net "M_B_CPU0_SB_DQS_DP<4>")
	)
	(gr_poly
		(pts
			(xy 331.921104 -271.047718) (xy 331.821028 -270.947896) (xy 331.720952 -271.047718) (xy 331.720952 -271.09547)
			(xy 331.921104 -271.09547)
		)
		(stroke
			(width 0)
			(type solid)
		)
		(fill yes)
		(layer "In13.Cu")
		(net "M_B_CPU0_SB_DQS_DP<9>")
	)
	(gr_poly
		(pts
			(xy 331.921104 -270.644112) (xy 331.921104 -270.599662) (xy 331.720952 -270.599662) (xy 331.720952 -270.644112)
			(xy 331.821028 -270.744188)
		)
		(stroke
			(width 0)
			(type solid)
		)
		(fill yes)
		(layer "In13.Cu")
		(net "M_B_CPU0_SB_CB<7>")
	)
	(gr_poly
		(pts
			(xy 331.921104 -269.42796) (xy 331.821028 -269.327884) (xy 331.720952 -269.42796) (xy 331.720952 -269.47241)
			(xy 331.921104 -269.47241)
		)
		(stroke
			(width 0)
			(type solid)
		)
		(fill yes)
		(layer "In13.Cu")
		(net "M_B_CPU0_SB_CB<4>")
	)
	(gr_poly
		(pts
			(xy 331.921104 -265.784076) (xy 331.921104 -265.739626) (xy 331.720952 -265.739626) (xy 331.720952 -265.784076)
			(xy 331.821028 -265.884152)
		)
		(stroke
			(width 0)
			(type solid)
		)
		(fill yes)
		(layer "In13.Cu")
		(net "M_B_CPU0_SB_CS_N<0>")
	)
	(gr_poly
		(pts
			(xy 331.921104 -264.567924) (xy 331.821028 -264.467848) (xy 331.720952 -264.567924) (xy 331.720952 -264.612374)
			(xy 331.921104 -264.612374)
		)
		(stroke
			(width 0)
			(type solid)
		)
		(fill yes)
		(layer "In13.Cu")
		(net "M_B_CPU0_SB_CA<6>")
	)
	(gr_poly
		(pts
			(xy 331.921104 -264.164064) (xy 331.921104 -264.119614) (xy 331.720952 -264.119614) (xy 331.720952 -264.164064)
			(xy 331.821028 -264.26414)
		)
		(stroke
			(width 0)
			(type solid)
		)
		(fill yes)
		(layer "In13.Cu")
		(net "M_B_CPU0_SB_CA<5>")
	)
	(gr_poly
		(pts
			(xy 331.921104 -262.947912) (xy 331.821028 -262.847836) (xy 331.720952 -262.947912) (xy 331.720952 -262.992362)
			(xy 331.921104 -262.992362)
		)
		(stroke
			(width 0)
			(type solid)
		)
		(fill yes)
		(layer "In13.Cu")
		(net "M_B_CPU0_SB_CA<2>")
	)
	(gr_poly
		(pts
			(xy 331.921104 -262.544052) (xy 331.921104 -262.499602) (xy 331.720952 -262.499602) (xy 331.720952 -262.544052)
			(xy 331.821028 -262.644128)
		)
		(stroke
			(width 0)
			(type solid)
		)
		(fill yes)
		(layer "In13.Cu")
		(net "M_B_CPU0_SB_CA<1>")
	)
	(gr_poly
		(pts
			(xy 331.9272 -267.801598) (xy 331.827378 -267.701522) (xy 331.727302 -267.801598) (xy 331.727302 -267.846048)
			(xy 331.9272 -267.846048)
		)
		(stroke
			(width 0)
			(type solid)
		)
		(fill yes)
		(layer "In13.Cu")
		(net "M_B_CPU0_SB_RSP<0>")
	)
	(gr_poly
		(pts
			(xy 331.92847 -277.12416) (xy 331.92847 -277.076662) (xy 331.728318 -277.076662) (xy 331.728318 -277.12416)
			(xy 331.828394 -277.224236)
		)
		(stroke
			(width 0)
			(type solid)
		)
		(fill yes)
		(layer "In13.Cu")
		(net "M_B_CPU0_SB_DQS_DP<5>")
	)
	(gr_poly
		(pts
			(xy 331.92847 -275.908008) (xy 331.828394 -275.807932) (xy 331.728318 -275.908008) (xy 331.728318 -275.955506)
			(xy 331.92847 -275.955506)
		)
		(stroke
			(width 0)
			(type solid)
		)
		(fill yes)
		(layer "In13.Cu")
		(net "M_B_CPU0_SB_DQS_DP<0>")
	)
	(gr_poly
		(pts
			(xy 332.091284 -256.025904) (xy 331.991208 -255.926082) (xy 331.891132 -256.025904) (xy 331.891132 -256.073656)
			(xy 332.091284 -256.073656)
		)
		(stroke
			(width 0)
			(type solid)
		)
		(fill yes)
		(layer "In13.Cu")
		(net "M_B_CPU0_CLK_DP<0>")
	)
	(gr_poly
		(pts
			(xy 332.091284 -255.622298) (xy 332.091284 -255.577848) (xy 331.891132 -255.577848) (xy 331.891132 -255.622298)
			(xy 331.991208 -255.722374)
		)
		(stroke
			(width 0)
			(type solid)
		)
		(fill yes)
		(layer "In13.Cu")
		(net "M_B_CPU0_SA_PAR")
	)
	(gr_poly
		(pts
			(xy 332.091284 -254.406146) (xy 331.991208 -254.30607) (xy 331.891132 -254.406146) (xy 331.891132 -254.450596)
			(xy 332.091284 -254.450596)
		)
		(stroke
			(width 0)
			(type solid)
		)
		(fill yes)
		(layer "In13.Cu")
		(net "M_B_CPU0_SA_CA<4>")
	)
	(gr_poly
		(pts
			(xy 332.091284 -254.002286) (xy 332.091284 -253.957836) (xy 331.891132 -253.957836) (xy 331.891132 -254.002286)
			(xy 331.991208 -254.102362)
		)
		(stroke
			(width 0)
			(type solid)
		)
		(fill yes)
		(layer "In13.Cu")
		(net "M_B_CPU0_SA_CA<3>")
	)
	(gr_poly
		(pts
			(xy 332.091284 -252.786134) (xy 331.991208 -252.686058) (xy 331.891132 -252.786134) (xy 331.891132 -252.830584)
			(xy 332.091284 -252.830584)
		)
		(stroke
			(width 0)
			(type solid)
		)
		(fill yes)
		(layer "In13.Cu")
		(net "M_B_CPU0_SA_CA<0>")
	)
	(gr_poly
		(pts
			(xy 332.091284 -252.382274) (xy 332.091284 -252.337824) (xy 331.891132 -252.337824) (xy 331.891132 -252.382274)
			(xy 331.991208 -252.48235)
		)
		(stroke
			(width 0)
			(type solid)
		)
		(fill yes)
		(layer "In13.Cu")
		(net "M_B_CPU0_SA_CS_N<1>")
	)
	(gr_poly
		(pts
			(xy 332.091284 -250.762262) (xy 332.091284 -250.717812) (xy 331.891132 -250.717812) (xy 331.891132 -250.762262)
			(xy 331.991208 -250.862338)
		)
		(stroke
			(width 0)
			(type solid)
		)
		(fill yes)
		(layer "In13.Cu")
		(net "M_B_CPU0_RESET_N")
	)
	(gr_poly
		(pts
			(xy 332.091284 -249.14225) (xy 332.091284 -249.0978) (xy 331.891132 -249.0978) (xy 331.891132 -249.14225)
			(xy 331.991208 -249.242326)
		)
		(stroke
			(width 0)
			(type solid)
		)
		(fill yes)
		(layer "In13.Cu")
		(net "M_B_CPU0_SA_CB<7>")
	)
	(gr_poly
		(pts
			(xy 332.091284 -247.926098) (xy 331.991208 -247.826022) (xy 331.891132 -247.926098) (xy 331.891132 -247.970548)
			(xy 332.091284 -247.970548)
		)
		(stroke
			(width 0)
			(type solid)
		)
		(fill yes)
		(layer "In13.Cu")
		(net "M_B_CPU0_SA_CB<4>")
	)
	(gr_poly
		(pts
			(xy 332.091284 -247.522492) (xy 332.091284 -247.47474) (xy 331.891132 -247.47474) (xy 331.891132 -247.522492)
			(xy 331.991208 -247.622314)
		)
		(stroke
			(width 0)
			(type solid)
		)
		(fill yes)
		(layer "In13.Cu")
		(net "M_B_CPU0_SA_DQS_DP<9>")
	)
	(gr_poly
		(pts
			(xy 332.091284 -246.305832) (xy 331.991208 -246.20601) (xy 331.891132 -246.305832) (xy 331.891132 -246.353584)
			(xy 332.091284 -246.353584)
		)
		(stroke
			(width 0)
			(type solid)
		)
		(fill yes)
		(layer "In13.Cu")
		(net "M_B_CPU0_SA_DQS_DP<4>")
	)
	(gr_poly
		(pts
			(xy 332.091284 -245.902226) (xy 332.091284 -245.857776) (xy 331.891132 -245.857776) (xy 331.891132 -245.902226)
			(xy 331.991208 -246.002302)
		)
		(stroke
			(width 0)
			(type solid)
		)
		(fill yes)
		(layer "In13.Cu")
		(net "M_B_CPU0_SA_CB<3>")
	)
	(gr_poly
		(pts
			(xy 332.091284 -244.686074) (xy 331.991208 -244.585998) (xy 331.891132 -244.686074) (xy 331.891132 -244.730524)
			(xy 332.091284 -244.730524)
		)
		(stroke
			(width 0)
			(type solid)
		)
		(fill yes)
		(layer "In13.Cu")
		(net "M_B_CPU0_SA_CB<0>")
	)
	(gr_poly
		(pts
			(xy 332.091284 -244.282214) (xy 332.091284 -244.237764) (xy 331.891132 -244.237764) (xy 331.891132 -244.282214)
			(xy 331.991208 -244.38229)
		)
		(stroke
			(width 0)
			(type solid)
		)
		(fill yes)
		(layer "In13.Cu")
		(net "M_B_CPU0_SA_DQ<31>")
	)
	(gr_poly
		(pts
			(xy 332.091284 -243.066062) (xy 331.991208 -242.965986) (xy 331.891132 -243.066062) (xy 331.891132 -243.110512)
			(xy 332.091284 -243.110512)
		)
		(stroke
			(width 0)
			(type solid)
		)
		(fill yes)
		(layer "In13.Cu")
		(net "M_B_CPU0_SA_DQ<28>")
	)
	(gr_poly
		(pts
			(xy 332.091284 -242.662456) (xy 332.091284 -242.614704) (xy 331.891132 -242.614704) (xy 331.891132 -242.662456)
			(xy 331.991208 -242.762278)
		)
		(stroke
			(width 0)
			(type solid)
		)
		(fill yes)
		(layer "In13.Cu")
		(net "M_B_CPU0_SA_DQS_DP<8>")
	)
	(gr_poly
		(pts
			(xy 332.091284 -241.445796) (xy 331.991208 -241.345974) (xy 331.891132 -241.445796) (xy 331.891132 -241.493548)
			(xy 332.091284 -241.493548)
		)
		(stroke
			(width 0)
			(type solid)
		)
		(fill yes)
		(layer "In13.Cu")
		(net "M_B_CPU0_SA_DQS_DP<3>")
	)
	(gr_poly
		(pts
			(xy 332.091284 -241.04219) (xy 332.091284 -240.99774) (xy 331.891132 -240.99774) (xy 331.891132 -241.04219)
			(xy 331.991208 -241.142266)
		)
		(stroke
			(width 0)
			(type solid)
		)
		(fill yes)
		(layer "In13.Cu")
		(net "M_B_CPU0_SA_DQ<27>")
	)
	(gr_poly
		(pts
			(xy 332.091284 -239.826038) (xy 331.991208 -239.725962) (xy 331.891132 -239.826038) (xy 331.891132 -239.870488)
			(xy 332.091284 -239.870488)
		)
		(stroke
			(width 0)
			(type solid)
		)
		(fill yes)
		(layer "In13.Cu")
		(net "M_B_CPU0_SA_DQ<24>")
	)
	(gr_poly
		(pts
			(xy 332.091284 -239.422178) (xy 332.091284 -239.377728) (xy 331.891132 -239.377728) (xy 331.891132 -239.422178)
			(xy 331.991208 -239.522254)
		)
		(stroke
			(width 0)
			(type solid)
		)
		(fill yes)
		(layer "In13.Cu")
		(net "M_B_CPU0_SA_DQ<23>")
	)
	(gr_poly
		(pts
			(xy 332.091284 -238.206026) (xy 331.991208 -238.10595) (xy 331.891132 -238.206026) (xy 331.891132 -238.250476)
			(xy 332.091284 -238.250476)
		)
		(stroke
			(width 0)
			(type solid)
		)
		(fill yes)
		(layer "In13.Cu")
		(net "M_B_CPU0_SA_DQ<20>")
	)
	(gr_poly
		(pts
			(xy 332.091284 -237.80242) (xy 332.091284 -237.754668) (xy 331.891132 -237.754668) (xy 331.891132 -237.80242)
			(xy 331.991208 -237.902242)
		)
		(stroke
			(width 0)
			(type solid)
		)
		(fill yes)
		(layer "In13.Cu")
		(net "M_B_CPU0_SA_DQS_DP<7>")
	)
	(gr_poly
		(pts
			(xy 332.091284 -236.58576) (xy 331.991208 -236.485938) (xy 331.891132 -236.58576) (xy 331.891132 -236.633512)
			(xy 332.091284 -236.633512)
		)
		(stroke
			(width 0)
			(type solid)
		)
		(fill yes)
		(layer "In13.Cu")
		(net "M_B_CPU0_SA_DQS_DP<2>")
	)
	(gr_poly
		(pts
			(xy 332.091284 -236.182154) (xy 332.091284 -236.137704) (xy 331.891132 -236.137704) (xy 331.891132 -236.182154)
			(xy 331.991208 -236.28223)
		)
		(stroke
			(width 0)
			(type solid)
		)
		(fill yes)
		(layer "In13.Cu")
		(net "M_B_CPU0_SA_DQ<19>")
	)
	(gr_poly
		(pts
			(xy 332.091284 -234.966002) (xy 331.991208 -234.865926) (xy 331.891132 -234.966002) (xy 331.891132 -235.010452)
			(xy 332.091284 -235.010452)
		)
		(stroke
			(width 0)
			(type solid)
		)
		(fill yes)
		(layer "In13.Cu")
		(net "M_B_CPU0_SA_DQ<16>")
	)
	(gr_poly
		(pts
			(xy 332.091284 -234.562142) (xy 332.091284 -234.517692) (xy 331.891132 -234.517692) (xy 331.891132 -234.562142)
			(xy 331.991208 -234.662218)
		)
		(stroke
			(width 0)
			(type solid)
		)
		(fill yes)
		(layer "In13.Cu")
		(net "M_B_CPU0_SA_DQ<15>")
	)
	(gr_poly
		(pts
			(xy 332.091284 -233.34599) (xy 331.991208 -233.245914) (xy 331.891132 -233.34599) (xy 331.891132 -233.39044)
			(xy 332.091284 -233.39044)
		)
		(stroke
			(width 0)
			(type solid)
		)
		(fill yes)
		(layer "In13.Cu")
		(net "M_B_CPU0_SA_DQ<12>")
	)
	(gr_poly
		(pts
			(xy 332.091284 -232.942384) (xy 332.091284 -232.894632) (xy 331.891132 -232.894632) (xy 331.891132 -232.942384)
			(xy 331.991208 -233.042206)
		)
		(stroke
			(width 0)
			(type solid)
		)
		(fill yes)
		(layer "In13.Cu")
		(net "M_B_CPU0_SA_DQS_DP<6>")
	)
	(gr_poly
		(pts
			(xy 332.091284 -231.725724) (xy 331.991208 -231.625902) (xy 331.891132 -231.725724) (xy 331.891132 -231.773476)
			(xy 332.091284 -231.773476)
		)
		(stroke
			(width 0)
			(type solid)
		)
		(fill yes)
		(layer "In13.Cu")
		(net "M_B_CPU0_SA_DQS_DP<1>")
	)
	(gr_poly
		(pts
			(xy 332.091284 -231.322372) (xy 332.091284 -231.277922) (xy 331.891132 -231.277922) (xy 331.891132 -231.322372)
			(xy 331.991208 -231.422448)
		)
		(stroke
			(width 0)
			(type solid)
		)
		(fill yes)
		(layer "In13.Cu")
		(net "M_B_CPU0_SA_DQ<11>")
	)
	(gr_poly
		(pts
			(xy 332.091284 -230.105966) (xy 331.991208 -230.006144) (xy 331.891132 -230.105966) (xy 331.891132 -230.150416)
			(xy 332.091284 -230.150416)
		)
		(stroke
			(width 0)
			(type solid)
		)
		(fill yes)
		(layer "In13.Cu")
		(net "M_B_CPU0_SA_DQ<8>")
	)
	(gr_poly
		(pts
			(xy 332.091284 -229.70236) (xy 332.091284 -229.65791) (xy 331.891132 -229.65791) (xy 331.891132 -229.70236)
			(xy 331.991208 -229.802436)
		)
		(stroke
			(width 0)
			(type solid)
		)
		(fill yes)
		(layer "In13.Cu")
		(net "M_B_CPU0_SA_DQ<7>")
	)
	(gr_poly
		(pts
			(xy 332.091284 -228.486208) (xy 331.991208 -228.386132) (xy 331.891132 -228.486208) (xy 331.891132 -228.530658)
			(xy 332.091284 -228.530658)
		)
		(stroke
			(width 0)
			(type solid)
		)
		(fill yes)
		(layer "In13.Cu")
		(net "M_B_CPU0_SA_DQ<4>")
	)
	(gr_poly
		(pts
			(xy 332.091284 -228.082602) (xy 332.091284 -228.03485) (xy 331.891132 -228.03485) (xy 331.891132 -228.082602)
			(xy 331.991208 -228.182424)
		)
		(stroke
			(width 0)
			(type solid)
		)
		(fill yes)
		(layer "In13.Cu")
		(net "M_B_CPU0_SA_DQS_DP<5>")
	)
	(gr_poly
		(pts
			(xy 332.091284 -226.865942) (xy 331.991208 -226.76612) (xy 331.891132 -226.865942) (xy 331.891132 -226.913694)
			(xy 332.091284 -226.913694)
		)
		(stroke
			(width 0)
			(type solid)
		)
		(fill yes)
		(layer "In13.Cu")
		(net "M_B_CPU0_SA_DQS_DP<0>")
	)
	(gr_poly
		(pts
			(xy 332.091284 -226.462336) (xy 332.091284 -226.417886) (xy 331.891132 -226.417886) (xy 331.891132 -226.462336)
			(xy 331.991208 -226.562412)
		)
		(stroke
			(width 0)
			(type solid)
		)
		(fill yes)
		(layer "In13.Cu")
		(net "M_B_CPU0_SA_DQ<3>")
	)
	(gr_poly
		(pts
			(xy 332.091284 -225.246184) (xy 331.991208 -225.146108) (xy 331.891132 -225.246184) (xy 331.891132 -225.290634)
			(xy 332.091284 -225.290634)
		)
		(stroke
			(width 0)
			(type solid)
		)
		(fill yes)
		(layer "In13.Cu")
		(net "M_B_CPU0_SA_DQ<0>")
	)
	(gr_poly
		(pts
			(xy 332.384908 -266.991592) (xy 332.284832 -266.891516) (xy 332.18501 -266.991592) (xy 332.18501 -267.036042)
			(xy 332.384908 -267.036042)
		)
		(stroke
			(width 0)
			(type solid)
		)
		(fill yes)
		(layer "In13.Cu")
		(net "M_B_CPU0_SA_RSP<0>")
	)
	(gr_poly
		(pts
			(xy 332.391258 -292.91788) (xy 332.291182 -292.817804) (xy 332.191106 -292.91788) (xy 332.191106 -292.96233)
			(xy 332.391258 -292.96233)
		)
		(stroke
			(width 0)
			(type solid)
		)
		(fill yes)
		(layer "In13.Cu")
		(net "M_B_CPU0_SB_DQ<29>")
	)
	(gr_poly
		(pts
			(xy 332.391258 -292.51402) (xy 332.391258 -292.46957) (xy 332.191106 -292.46957) (xy 332.191106 -292.51402)
			(xy 332.291182 -292.614096)
		)
		(stroke
			(width 0)
			(type solid)
		)
		(fill yes)
		(layer "In13.Cu")
		(net "M_B_CPU0_SB_DQ<30>")
	)
	(gr_poly
		(pts
			(xy 332.391258 -291.297614) (xy 332.291182 -291.197792) (xy 332.191106 -291.297614) (xy 332.191106 -291.345366)
			(xy 332.391258 -291.345366)
		)
		(stroke
			(width 0)
			(type solid)
		)
		(fill yes)
		(layer "In13.Cu")
		(net "M_B_CPU0_SB_DQS_DN<8>")
	)
	(gr_poly
		(pts
			(xy 332.391258 -290.894262) (xy 332.391258 -290.84651) (xy 332.191106 -290.84651) (xy 332.191106 -290.894262)
			(xy 332.291182 -290.994084)
		)
		(stroke
			(width 0)
			(type solid)
		)
		(fill yes)
		(layer "In13.Cu")
		(net "M_B_CPU0_SB_DQS_DN<3>")
	)
	(gr_poly
		(pts
			(xy 332.391258 -289.677856) (xy 332.291182 -289.57778) (xy 332.191106 -289.677856) (xy 332.191106 -289.722306)
			(xy 332.391258 -289.722306)
		)
		(stroke
			(width 0)
			(type solid)
		)
		(fill yes)
		(layer "In13.Cu")
		(net "M_B_CPU0_SB_DQ<25>")
	)
	(gr_poly
		(pts
			(xy 332.391258 -289.273996) (xy 332.391258 -289.229546) (xy 332.191106 -289.229546) (xy 332.191106 -289.273996)
			(xy 332.291182 -289.374072)
		)
		(stroke
			(width 0)
			(type solid)
		)
		(fill yes)
		(layer "In13.Cu")
		(net "M_B_CPU0_SB_DQ<26>")
	)
	(gr_poly
		(pts
			(xy 332.391258 -288.057844) (xy 332.291182 -287.957768) (xy 332.191106 -288.057844) (xy 332.191106 -288.102294)
			(xy 332.391258 -288.102294)
		)
		(stroke
			(width 0)
			(type solid)
		)
		(fill yes)
		(layer "In13.Cu")
		(net "M_B_CPU0_SB_DQ<21>")
	)
	(gr_poly
		(pts
			(xy 332.391258 -287.654238) (xy 332.391258 -287.609788) (xy 332.191106 -287.609788) (xy 332.191106 -287.654238)
			(xy 332.291182 -287.75406)
		)
		(stroke
			(width 0)
			(type solid)
		)
		(fill yes)
		(layer "In13.Cu")
		(net "M_B_CPU0_SB_DQ<22>")
	)
	(gr_poly
		(pts
			(xy 332.391258 -286.437832) (xy 332.291182 -286.337756) (xy 332.191106 -286.437832) (xy 332.191106 -286.485584)
			(xy 332.391258 -286.485584)
		)
		(stroke
			(width 0)
			(type solid)
		)
		(fill yes)
		(layer "In13.Cu")
		(net "M_B_CPU0_SB_DQS_DN<7>")
	)
	(gr_poly
		(pts
			(xy 332.391258 -286.03448) (xy 332.391258 -285.986728) (xy 332.191106 -285.986728) (xy 332.191106 -286.03448)
			(xy 332.291182 -286.134302)
		)
		(stroke
			(width 0)
			(type solid)
		)
		(fill yes)
		(layer "In13.Cu")
		(net "M_B_CPU0_SB_DQS_DN<2>")
	)
	(gr_poly
		(pts
			(xy 332.391258 -284.818074) (xy 332.291182 -284.717998) (xy 332.191106 -284.818074) (xy 332.191106 -284.862524)
			(xy 332.391258 -284.862524)
		)
		(stroke
			(width 0)
			(type solid)
		)
		(fill yes)
		(layer "In13.Cu")
		(net "M_B_CPU0_SB_DQ<17>")
	)
	(gr_poly
		(pts
			(xy 332.391258 -284.414214) (xy 332.391258 -284.369764) (xy 332.191106 -284.369764) (xy 332.191106 -284.414214)
			(xy 332.291182 -284.51429)
		)
		(stroke
			(width 0)
			(type solid)
		)
		(fill yes)
		(layer "In13.Cu")
		(net "M_B_CPU0_SB_DQ<18>")
	)
	(gr_poly
		(pts
			(xy 332.391258 -283.198062) (xy 332.291182 -283.097986) (xy 332.191106 -283.198062) (xy 332.191106 -283.242512)
			(xy 332.391258 -283.242512)
		)
		(stroke
			(width 0)
			(type solid)
		)
		(fill yes)
		(layer "In13.Cu")
		(net "M_B_CPU0_SB_DQ<13>")
	)
	(gr_poly
		(pts
			(xy 332.391258 -282.794202) (xy 332.391258 -282.749752) (xy 332.191106 -282.749752) (xy 332.191106 -282.794202)
			(xy 332.291182 -282.894278)
		)
		(stroke
			(width 0)
			(type solid)
		)
		(fill yes)
		(layer "In13.Cu")
		(net "M_B_CPU0_SB_DQ<14>")
	)
	(gr_poly
		(pts
			(xy 332.391258 -281.577796) (xy 332.291182 -281.477974) (xy 332.191106 -281.577796) (xy 332.191106 -281.625548)
			(xy 332.391258 -281.625548)
		)
		(stroke
			(width 0)
			(type solid)
		)
		(fill yes)
		(layer "In13.Cu")
		(net "M_B_CPU0_SB_DQS_DN<6>")
	)
	(gr_poly
		(pts
			(xy 332.391258 -281.174444) (xy 332.391258 -281.126692) (xy 332.191106 -281.126692) (xy 332.191106 -281.174444)
			(xy 332.291182 -281.274266)
		)
		(stroke
			(width 0)
			(type solid)
		)
		(fill yes)
		(layer "In13.Cu")
		(net "M_B_CPU0_SB_DQS_DN<1>")
	)
	(gr_poly
		(pts
			(xy 332.391258 -279.958038) (xy 332.291182 -279.857962) (xy 332.191106 -279.958038) (xy 332.191106 -280.002488)
			(xy 332.391258 -280.002488)
		)
		(stroke
			(width 0)
			(type solid)
		)
		(fill yes)
		(layer "In13.Cu")
		(net "M_B_CPU0_SB_DQ<9>")
	)
	(gr_poly
		(pts
			(xy 332.391258 -279.554178) (xy 332.391258 -279.509728) (xy 332.191106 -279.509728) (xy 332.191106 -279.554178)
			(xy 332.291182 -279.654254)
		)
		(stroke
			(width 0)
			(type solid)
		)
		(fill yes)
		(layer "In13.Cu")
		(net "M_B_CPU0_SB_DQ<10>")
	)
	(gr_poly
		(pts
			(xy 332.391258 -278.338026) (xy 332.291182 -278.23795) (xy 332.191106 -278.338026) (xy 332.191106 -278.382476)
			(xy 332.391258 -278.382476)
		)
		(stroke
			(width 0)
			(type solid)
		)
		(fill yes)
		(layer "In13.Cu")
		(net "M_B_CPU0_SB_DQ<5>")
	)
	(gr_poly
		(pts
			(xy 332.391258 -277.934166) (xy 332.391258 -277.889716) (xy 332.191106 -277.889716) (xy 332.191106 -277.934166)
			(xy 332.291182 -278.034242)
		)
		(stroke
			(width 0)
			(type solid)
		)
		(fill yes)
		(layer "In13.Cu")
		(net "M_B_CPU0_SB_DQ<6>")
	)
	(gr_poly
		(pts
			(xy 332.391258 -276.71776) (xy 332.291182 -276.617938) (xy 332.191106 -276.71776) (xy 332.191106 -276.765512)
			(xy 332.391258 -276.765512)
		)
		(stroke
			(width 0)
			(type solid)
		)
		(fill yes)
		(layer "In13.Cu")
		(net "M_B_CPU0_SB_DQS_DN<5>")
	)
	(gr_poly
		(pts
			(xy 332.391258 -276.314408) (xy 332.391258 -276.266656) (xy 332.191106 -276.266656) (xy 332.191106 -276.314408)
			(xy 332.291182 -276.41423)
		)
		(stroke
			(width 0)
			(type solid)
		)
		(fill yes)
		(layer "In13.Cu")
		(net "M_B_CPU0_SB_DQS_DN<0>")
	)
	(gr_poly
		(pts
			(xy 332.391258 -275.098002) (xy 332.291182 -274.997926) (xy 332.191106 -275.098002) (xy 332.191106 -275.142452)
			(xy 332.391258 -275.142452)
		)
		(stroke
			(width 0)
			(type solid)
		)
		(fill yes)
		(layer "In13.Cu")
		(net "M_B_CPU0_SB_DQ<1>")
	)
	(gr_poly
		(pts
			(xy 332.391258 -274.694142) (xy 332.391258 -274.649692) (xy 332.191106 -274.649692) (xy 332.191106 -274.694142)
			(xy 332.291182 -274.794218)
		)
		(stroke
			(width 0)
			(type solid)
		)
		(fill yes)
		(layer "In13.Cu")
		(net "M_B_CPU0_SB_DQ<2>")
	)
	(gr_poly
		(pts
			(xy 332.391258 -273.47799) (xy 332.291182 -273.377914) (xy 332.191106 -273.47799) (xy 332.191106 -273.52244)
			(xy 332.391258 -273.52244)
		)
		(stroke
			(width 0)
			(type solid)
		)
		(fill yes)
		(layer "In13.Cu")
		(net "M_B_CPU0_SB_CB<1>")
	)
	(gr_poly
		(pts
			(xy 332.391258 -273.07413) (xy 332.391258 -273.02968) (xy 332.191106 -273.02968) (xy 332.191106 -273.07413)
			(xy 332.291182 -273.174206)
		)
		(stroke
			(width 0)
			(type solid)
		)
		(fill yes)
		(layer "In13.Cu")
		(net "M_B_CPU0_SB_CB<2>")
	)
	(gr_poly
		(pts
			(xy 332.391258 -271.857724) (xy 332.291182 -271.757902) (xy 332.191106 -271.857724) (xy 332.191106 -271.905476)
			(xy 332.391258 -271.905476)
		)
		(stroke
			(width 0)
			(type solid)
		)
		(fill yes)
		(layer "In13.Cu")
		(net "M_B_CPU0_SB_DQS_DN<4>")
	)
	(gr_poly
		(pts
			(xy 332.391258 -271.454372) (xy 332.391258 -271.40662) (xy 332.191106 -271.40662) (xy 332.191106 -271.454372)
			(xy 332.291182 -271.554194)
		)
		(stroke
			(width 0)
			(type solid)
		)
		(fill yes)
		(layer "In13.Cu")
		(net "M_B_CPU0_SB_DQS_DN<9>")
	)
	(gr_poly
		(pts
			(xy 332.391258 -270.237966) (xy 332.291182 -270.13789) (xy 332.191106 -270.237966) (xy 332.191106 -270.282416)
			(xy 332.391258 -270.282416)
		)
		(stroke
			(width 0)
			(type solid)
		)
		(fill yes)
		(layer "In13.Cu")
		(net "M_B_CPU0_SB_CB<5>")
	)
	(gr_poly
		(pts
			(xy 332.391258 -269.834106) (xy 332.391258 -269.789656) (xy 332.191106 -269.789656) (xy 332.191106 -269.834106)
			(xy 332.291182 -269.934182)
		)
		(stroke
			(width 0)
			(type solid)
		)
		(fill yes)
		(layer "In13.Cu")
		(net "M_B_CPU0_SB_CB<6>")
	)
	(gr_poly
		(pts
			(xy 332.391258 -266.594082) (xy 332.391258 -266.549632) (xy 332.191106 -266.549632) (xy 332.191106 -266.594082)
			(xy 332.291182 -266.694158)
		)
		(stroke
			(width 0)
			(type solid)
		)
		(fill yes)
		(layer "In13.Cu")
		(net "M_B_CPU0_SB_CS_N<1>")
	)
	(gr_poly
		(pts
			(xy 332.391258 -264.97407) (xy 332.391258 -264.92962) (xy 332.191106 -264.92962) (xy 332.191106 -264.97407)
			(xy 332.291182 -265.074146)
		)
		(stroke
			(width 0)
			(type solid)
		)
		(fill yes)
		(layer "In13.Cu")
		(net "M_B_CPU0_SB_PAR")
	)
	(gr_poly
		(pts
			(xy 332.391258 -263.757918) (xy 332.291182 -263.657842) (xy 332.191106 -263.757918) (xy 332.191106 -263.802368)
			(xy 332.391258 -263.802368)
		)
		(stroke
			(width 0)
			(type solid)
		)
		(fill yes)
		(layer "In13.Cu")
		(net "M_B_CPU0_SB_CA<4>")
	)
	(gr_poly
		(pts
			(xy 332.391258 -263.354058) (xy 332.391258 -263.309608) (xy 332.191106 -263.309608) (xy 332.191106 -263.354058)
			(xy 332.291182 -263.454134)
		)
		(stroke
			(width 0)
			(type solid)
		)
		(fill yes)
		(layer "In13.Cu")
		(net "M_B_CPU0_SB_CA<3>")
	)
	(gr_poly
		(pts
			(xy 332.391258 -262.137906) (xy 332.291182 -262.03783) (xy 332.191106 -262.137906) (xy 332.191106 -262.182356)
			(xy 332.391258 -262.182356)
		)
		(stroke
			(width 0)
			(type solid)
		)
		(fill yes)
		(layer "In13.Cu")
		(net "M_B_CPU0_SB_CA<0>")
	)
	(gr_poly
		(pts
			(xy 332.561184 -256.432558) (xy 332.561184 -256.384806) (xy 332.361032 -256.384806) (xy 332.361032 -256.432558)
			(xy 332.461108 -256.53238)
		)
		(stroke
			(width 0)
			(type solid)
		)
		(fill yes)
		(layer "In13.Cu")
		(net "M_B_CPU0_CLK_DN<0>")
	)
	(gr_poly
		(pts
			(xy 332.561184 -255.216152) (xy 332.461108 -255.116076) (xy 332.361032 -255.216152) (xy 332.361032 -255.260602)
			(xy 332.561184 -255.260602)
		)
		(stroke
			(width 0)
			(type solid)
		)
		(fill yes)
		(layer "In13.Cu")
		(net "M_B_CPU0_SA_CA<6>")
	)
	(gr_poly
		(pts
			(xy 332.561184 -254.812292) (xy 332.561184 -254.767842) (xy 332.361032 -254.767842) (xy 332.361032 -254.812292)
			(xy 332.461108 -254.912368)
		)
		(stroke
			(width 0)
			(type solid)
		)
		(fill yes)
		(layer "In13.Cu")
		(net "M_B_CPU0_SA_CA<5>")
	)
	(gr_poly
		(pts
			(xy 332.561184 -253.59614) (xy 332.461108 -253.496064) (xy 332.361032 -253.59614) (xy 332.361032 -253.64059)
			(xy 332.561184 -253.64059)
		)
		(stroke
			(width 0)
			(type solid)
		)
		(fill yes)
		(layer "In13.Cu")
		(net "M_B_CPU0_SA_CA<2>")
	)
	(gr_poly
		(pts
			(xy 332.561184 -253.19228) (xy 332.561184 -253.14783) (xy 332.361032 -253.14783) (xy 332.361032 -253.19228)
			(xy 332.461108 -253.292356)
		)
		(stroke
			(width 0)
			(type solid)
		)
		(fill yes)
		(layer "In13.Cu")
		(net "M_B_CPU0_SA_CA<1>")
	)
	(gr_poly
		(pts
			(xy 332.561184 -251.572268) (xy 332.561184 -251.527818) (xy 332.361032 -251.527818) (xy 332.361032 -251.572268)
			(xy 332.461108 -251.672344)
		)
		(stroke
			(width 0)
			(type solid)
		)
		(fill yes)
		(layer "In13.Cu")
		(net "M_B_CPU0_SA_CS_N<0>")
	)
	(gr_poly
		(pts
			(xy 332.561184 -250.356116) (xy 332.461108 -250.25604) (xy 332.361032 -250.356116) (xy 332.361032 -250.400566)
			(xy 332.561184 -250.400566)
		)
		(stroke
			(width 0)
			(type solid)
		)
		(fill yes)
		(layer "In13.Cu")
		(net "M_B_CPU0_ALERT_R_N")
	)
	(gr_poly
		(pts
			(xy 332.561184 -248.736104) (xy 332.461108 -248.636028) (xy 332.361032 -248.736104) (xy 332.361032 -248.780554)
			(xy 332.561184 -248.780554)
		)
		(stroke
			(width 0)
			(type solid)
		)
		(fill yes)
		(layer "In13.Cu")
		(net "M_B_CPU0_SA_CB<5>")
	)
	(gr_poly
		(pts
			(xy 332.561184 -248.332244) (xy 332.561184 -248.287794) (xy 332.361032 -248.287794) (xy 332.361032 -248.332244)
			(xy 332.461108 -248.43232)
		)
		(stroke
			(width 0)
			(type solid)
		)
		(fill yes)
		(layer "In13.Cu")
		(net "M_B_CPU0_SA_CB<6>")
	)
	(gr_poly
		(pts
			(xy 332.561184 -247.115838) (xy 332.461108 -247.016016) (xy 332.361032 -247.115838) (xy 332.361032 -247.16359)
			(xy 332.561184 -247.16359)
		)
		(stroke
			(width 0)
			(type solid)
		)
		(fill yes)
		(layer "In13.Cu")
		(net "M_B_CPU0_SA_DQS_DN<9>")
	)
	(gr_poly
		(pts
			(xy 332.561184 -246.712486) (xy 332.561184 -246.664734) (xy 332.361032 -246.664734) (xy 332.361032 -246.712486)
			(xy 332.461108 -246.812308)
		)
		(stroke
			(width 0)
			(type solid)
		)
		(fill yes)
		(layer "In13.Cu")
		(net "M_B_CPU0_SA_DQS_DN<4>")
	)
	(gr_poly
		(pts
			(xy 332.561184 -245.49608) (xy 332.461108 -245.396004) (xy 332.361032 -245.49608) (xy 332.361032 -245.54053)
			(xy 332.561184 -245.54053)
		)
		(stroke
			(width 0)
			(type solid)
		)
		(fill yes)
		(layer "In13.Cu")
		(net "M_B_CPU0_SA_CB<1>")
	)
	(gr_poly
		(pts
			(xy 332.561184 -245.09222) (xy 332.561184 -245.04777) (xy 332.361032 -245.04777) (xy 332.361032 -245.09222)
			(xy 332.461108 -245.192296)
		)
		(stroke
			(width 0)
			(type solid)
		)
		(fill yes)
		(layer "In13.Cu")
		(net "M_B_CPU0_SA_CB<2>")
	)
	(gr_poly
		(pts
			(xy 332.561184 -243.876068) (xy 332.461108 -243.775992) (xy 332.361032 -243.876068) (xy 332.361032 -243.920518)
			(xy 332.561184 -243.920518)
		)
		(stroke
			(width 0)
			(type solid)
		)
		(fill yes)
		(layer "In13.Cu")
		(net "M_B_CPU0_SA_DQ<29>")
	)
	(gr_poly
		(pts
			(xy 332.561184 -243.472208) (xy 332.561184 -243.427758) (xy 332.361032 -243.427758) (xy 332.361032 -243.472208)
			(xy 332.461108 -243.572284)
		)
		(stroke
			(width 0)
			(type solid)
		)
		(fill yes)
		(layer "In13.Cu")
		(net "M_B_CPU0_SA_DQ<30>")
	)
	(gr_poly
		(pts
			(xy 332.561184 -242.255802) (xy 332.461108 -242.15598) (xy 332.361032 -242.255802) (xy 332.361032 -242.303554)
			(xy 332.561184 -242.303554)
		)
		(stroke
			(width 0)
			(type solid)
		)
		(fill yes)
		(layer "In13.Cu")
		(net "M_B_CPU0_SA_DQS_DN<8>")
	)
	(gr_poly
		(pts
			(xy 332.561184 -241.85245) (xy 332.561184 -241.804698) (xy 332.361032 -241.804698) (xy 332.361032 -241.85245)
			(xy 332.461108 -241.952272)
		)
		(stroke
			(width 0)
			(type solid)
		)
		(fill yes)
		(layer "In13.Cu")
		(net "M_B_CPU0_SA_DQS_DN<3>")
	)
	(gr_poly
		(pts
			(xy 332.561184 -240.636044) (xy 332.461108 -240.535968) (xy 332.361032 -240.636044) (xy 332.361032 -240.680494)
			(xy 332.561184 -240.680494)
		)
		(stroke
			(width 0)
			(type solid)
		)
		(fill yes)
		(layer "In13.Cu")
		(net "M_B_CPU0_SA_DQ<25>")
	)
	(gr_poly
		(pts
			(xy 332.561184 -240.232184) (xy 332.561184 -240.187734) (xy 332.361032 -240.187734) (xy 332.361032 -240.232184)
			(xy 332.461108 -240.33226)
		)
		(stroke
			(width 0)
			(type solid)
		)
		(fill yes)
		(layer "In13.Cu")
		(net "M_B_CPU0_SA_DQ<26>")
	)
	(gr_poly
		(pts
			(xy 332.561184 -239.016032) (xy 332.461108 -238.915956) (xy 332.361032 -239.016032) (xy 332.361032 -239.060482)
			(xy 332.561184 -239.060482)
		)
		(stroke
			(width 0)
			(type solid)
		)
		(fill yes)
		(layer "In13.Cu")
		(net "M_B_CPU0_SA_DQ<21>")
	)
	(gr_poly
		(pts
			(xy 332.561184 -238.612172) (xy 332.561184 -238.567722) (xy 332.361032 -238.567722) (xy 332.361032 -238.612172)
			(xy 332.461108 -238.712248)
		)
		(stroke
			(width 0)
			(type solid)
		)
		(fill yes)
		(layer "In13.Cu")
		(net "M_B_CPU0_SA_DQ<22>")
	)
	(gr_poly
		(pts
			(xy 332.561184 -237.395766) (xy 332.461108 -237.295944) (xy 332.361032 -237.395766) (xy 332.361032 -237.443518)
			(xy 332.561184 -237.443518)
		)
		(stroke
			(width 0)
			(type solid)
		)
		(fill yes)
		(layer "In13.Cu")
		(net "M_B_CPU0_SA_DQS_DN<7>")
	)
	(gr_poly
		(pts
			(xy 332.561184 -236.992414) (xy 332.561184 -236.944662) (xy 332.361032 -236.944662) (xy 332.361032 -236.992414)
			(xy 332.461108 -237.092236)
		)
		(stroke
			(width 0)
			(type solid)
		)
		(fill yes)
		(layer "In13.Cu")
		(net "M_B_CPU0_SA_DQS_DN<2>")
	)
	(gr_poly
		(pts
			(xy 332.561184 -235.776008) (xy 332.461108 -235.675932) (xy 332.361032 -235.776008) (xy 332.361032 -235.820458)
			(xy 332.561184 -235.820458)
		)
		(stroke
			(width 0)
			(type solid)
		)
		(fill yes)
		(layer "In13.Cu")
		(net "M_B_CPU0_SA_DQ<17>")
	)
	(gr_poly
		(pts
			(xy 332.561184 -235.372148) (xy 332.561184 -235.327698) (xy 332.361032 -235.327698) (xy 332.361032 -235.372148)
			(xy 332.461108 -235.472224)
		)
		(stroke
			(width 0)
			(type solid)
		)
		(fill yes)
		(layer "In13.Cu")
		(net "M_B_CPU0_SA_DQ<18>")
	)
	(gr_poly
		(pts
			(xy 332.561184 -234.155996) (xy 332.461108 -234.05592) (xy 332.361032 -234.155996) (xy 332.361032 -234.200446)
			(xy 332.561184 -234.200446)
		)
		(stroke
			(width 0)
			(type solid)
		)
		(fill yes)
		(layer "In13.Cu")
		(net "M_B_CPU0_SA_DQ<13>")
	)
	(gr_poly
		(pts
			(xy 332.561184 -233.752136) (xy 332.561184 -233.707686) (xy 332.361032 -233.707686) (xy 332.361032 -233.752136)
			(xy 332.461108 -233.852212)
		)
		(stroke
			(width 0)
			(type solid)
		)
		(fill yes)
		(layer "In13.Cu")
		(net "M_B_CPU0_SA_DQ<14>")
	)
	(gr_poly
		(pts
			(xy 332.561184 -232.53573) (xy 332.461108 -232.435908) (xy 332.361032 -232.53573) (xy 332.361032 -232.583482)
			(xy 332.561184 -232.583482)
		)
		(stroke
			(width 0)
			(type solid)
		)
		(fill yes)
		(layer "In13.Cu")
		(net "M_B_CPU0_SA_DQS_DN<6>")
	)
	(gr_poly
		(pts
			(xy 332.561184 -232.132378) (xy 332.561184 -232.084626) (xy 332.361032 -232.084626) (xy 332.361032 -232.132378)
			(xy 332.461108 -232.2322)
		)
		(stroke
			(width 0)
			(type solid)
		)
		(fill yes)
		(layer "In13.Cu")
		(net "M_B_CPU0_SA_DQS_DN<1>")
	)
	(gr_poly
		(pts
			(xy 332.561184 -230.915972) (xy 332.461108 -230.815896) (xy 332.361032 -230.915972) (xy 332.361032 -230.960422)
			(xy 332.561184 -230.960422)
		)
		(stroke
			(width 0)
			(type solid)
		)
		(fill yes)
		(layer "In13.Cu")
		(net "M_B_CPU0_SA_DQ<9>")
	)
	(gr_poly
		(pts
			(xy 332.561184 -230.512366) (xy 332.561184 -230.467916) (xy 332.361032 -230.467916) (xy 332.361032 -230.512366)
			(xy 332.461108 -230.612188)
		)
		(stroke
			(width 0)
			(type solid)
		)
		(fill yes)
		(layer "In13.Cu")
		(net "M_B_CPU0_SA_DQ<10>")
	)
	(gr_poly
		(pts
			(xy 332.561184 -229.29596) (xy 332.461108 -229.195884) (xy 332.361032 -229.29596) (xy 332.361032 -229.34041)
			(xy 332.561184 -229.34041)
		)
		(stroke
			(width 0)
			(type solid)
		)
		(fill yes)
		(layer "In13.Cu")
		(net "M_B_CPU0_SA_DQ<5>")
	)
	(gr_poly
		(pts
			(xy 332.561184 -228.892354) (xy 332.561184 -228.847904) (xy 332.361032 -228.847904) (xy 332.361032 -228.892354)
			(xy 332.461108 -228.99243)
		)
		(stroke
			(width 0)
			(type solid)
		)
		(fill yes)
		(layer "In13.Cu")
		(net "M_B_CPU0_SA_DQ<6>")
	)
	(gr_poly
		(pts
			(xy 332.561184 -227.676456) (xy 332.461108 -227.57638) (xy 332.361032 -227.676456) (xy 332.361032 -227.724208)
			(xy 332.561184 -227.724208)
		)
		(stroke
			(width 0)
			(type solid)
		)
		(fill yes)
		(layer "In13.Cu")
		(net "M_B_CPU0_SA_DQS_DN<5>")
	)
	(gr_poly
		(pts
			(xy 332.561184 -227.272596) (xy 332.561184 -227.224844) (xy 332.361032 -227.224844) (xy 332.361032 -227.272596)
			(xy 332.461108 -227.372418)
		)
		(stroke
			(width 0)
			(type solid)
		)
		(fill yes)
		(layer "In13.Cu")
		(net "M_B_CPU0_SA_DQS_DN<0>")
	)
	(gr_poly
		(pts
			(xy 332.561184 -226.05619) (xy 332.461108 -225.956114) (xy 332.361032 -226.05619) (xy 332.361032 -226.10064)
			(xy 332.561184 -226.10064)
		)
		(stroke
			(width 0)
			(type solid)
		)
		(fill yes)
		(layer "In13.Cu")
		(net "M_B_CPU0_SA_DQ<1>")
	)
	(gr_poly
		(pts
			(xy 332.561184 -225.65233) (xy 332.561184 -225.60788) (xy 332.361032 -225.60788) (xy 332.361032 -225.65233)
			(xy 332.461108 -225.752406)
		)
		(stroke
			(width 0)
			(type solid)
		)
		(fill yes)
		(layer "In13.Cu")
		(net "M_B_CPU0_SA_DQ<2>")
	)
	(gr_poly
		(pts
			(xy 332.861158 -293.324026) (xy 332.861158 -293.279576) (xy 332.661006 -293.279576) (xy 332.661006 -293.324026)
			(xy 332.761082 -293.424102)
		)
		(stroke
			(width 0)
			(type solid)
		)
		(fill yes)
		(layer "In13.Cu")
		(net "M_B_CPU0_SB_DQ<31>")
	)
	(gr_poly
		(pts
			(xy 332.861158 -292.107874) (xy 332.761082 -292.007798) (xy 332.661006 -292.107874) (xy 332.661006 -292.152324)
			(xy 332.861158 -292.152324)
		)
		(stroke
			(width 0)
			(type solid)
		)
		(fill yes)
		(layer "In13.Cu")
		(net "M_B_CPU0_SB_DQ<28>")
	)
	(gr_poly
		(pts
			(xy 332.861158 -291.704268) (xy 332.861158 -291.656516) (xy 332.661006 -291.656516) (xy 332.661006 -291.704268)
			(xy 332.761082 -291.80409)
		)
		(stroke
			(width 0)
			(type solid)
		)
		(fill yes)
		(layer "In13.Cu")
		(net "M_B_CPU0_SB_DQS_DP<8>")
	)
	(gr_poly
		(pts
			(xy 332.861158 -290.487608) (xy 332.761082 -290.387786) (xy 332.661006 -290.487608) (xy 332.661006 -290.53536)
			(xy 332.861158 -290.53536)
		)
		(stroke
			(width 0)
			(type solid)
		)
		(fill yes)
		(layer "In13.Cu")
		(net "M_B_CPU0_SB_DQS_DP<3>")
	)
	(gr_poly
		(pts
			(xy 332.861158 -290.084002) (xy 332.861158 -290.039552) (xy 332.661006 -290.039552) (xy 332.661006 -290.084002)
			(xy 332.761082 -290.184078)
		)
		(stroke
			(width 0)
			(type solid)
		)
		(fill yes)
		(layer "In13.Cu")
		(net "M_B_CPU0_SB_DQ<27>")
	)
	(gr_poly
		(pts
			(xy 332.861158 -288.86785) (xy 332.761082 -288.767774) (xy 332.661006 -288.86785) (xy 332.661006 -288.9123)
			(xy 332.861158 -288.9123)
		)
		(stroke
			(width 0)
			(type solid)
		)
		(fill yes)
		(layer "In13.Cu")
		(net "M_B_CPU0_SB_DQ<24>")
	)
	(gr_poly
		(pts
			(xy 332.861158 -288.464244) (xy 332.861158 -288.419794) (xy 332.661006 -288.419794) (xy 332.661006 -288.464244)
			(xy 332.761082 -288.56432)
		)
		(stroke
			(width 0)
			(type solid)
		)
		(fill yes)
		(layer "In13.Cu")
		(net "M_B_CPU0_SB_DQ<23>")
	)
	(gr_poly
		(pts
			(xy 332.861158 -287.247838) (xy 332.761082 -287.148016) (xy 332.661006 -287.247838) (xy 332.661006 -287.292288)
			(xy 332.861158 -287.292288)
		)
		(stroke
			(width 0)
			(type solid)
		)
		(fill yes)
		(layer "In13.Cu")
		(net "M_B_CPU0_SB_DQ<20>")
	)
	(gr_poly
		(pts
			(xy 332.861158 -286.844232) (xy 332.861158 -286.79648) (xy 332.661006 -286.79648) (xy 332.661006 -286.844232)
			(xy 332.761082 -286.944308)
		)
		(stroke
			(width 0)
			(type solid)
		)
		(fill yes)
		(layer "In13.Cu")
		(net "M_B_CPU0_SB_DQS_DP<7>")
	)
	(gr_poly
		(pts
			(xy 332.861158 -285.627826) (xy 332.761082 -285.528004) (xy 332.661006 -285.627826) (xy 332.661006 -285.675578)
			(xy 332.861158 -285.675578)
		)
		(stroke
			(width 0)
			(type solid)
		)
		(fill yes)
		(layer "In13.Cu")
		(net "M_B_CPU0_SB_DQS_DP<2>")
	)
	(gr_poly
		(pts
			(xy 332.861158 -285.22422) (xy 332.861158 -285.17977) (xy 332.661006 -285.17977) (xy 332.661006 -285.22422)
			(xy 332.761082 -285.324296)
		)
		(stroke
			(width 0)
			(type solid)
		)
		(fill yes)
		(layer "In13.Cu")
		(net "M_B_CPU0_SB_DQ<19>")
	)
	(gr_poly
		(pts
			(xy 332.861158 -284.008068) (xy 332.761082 -283.907992) (xy 332.661006 -284.008068) (xy 332.661006 -284.052518)
			(xy 332.861158 -284.052518)
		)
		(stroke
			(width 0)
			(type solid)
		)
		(fill yes)
		(layer "In13.Cu")
		(net "M_B_CPU0_SB_DQ<16>")
	)
	(gr_poly
		(pts
			(xy 332.861158 -283.604208) (xy 332.861158 -283.559758) (xy 332.661006 -283.559758) (xy 332.661006 -283.604208)
			(xy 332.761082 -283.704284)
		)
		(stroke
			(width 0)
			(type solid)
		)
		(fill yes)
		(layer "In13.Cu")
		(net "M_B_CPU0_SB_DQ<15>")
	)
	(gr_poly
		(pts
			(xy 332.861158 -282.388056) (xy 332.761082 -282.28798) (xy 332.661006 -282.388056) (xy 332.661006 -282.432506)
			(xy 332.861158 -282.432506)
		)
		(stroke
			(width 0)
			(type solid)
		)
		(fill yes)
		(layer "In13.Cu")
		(net "M_B_CPU0_SB_DQ<12>")
	)
	(gr_poly
		(pts
			(xy 332.861158 -281.98445) (xy 332.861158 -281.936698) (xy 332.661006 -281.936698) (xy 332.661006 -281.98445)
			(xy 332.761082 -282.084272)
		)
		(stroke
			(width 0)
			(type solid)
		)
		(fill yes)
		(layer "In13.Cu")
		(net "M_B_CPU0_SB_DQS_DP<6>")
	)
	(gr_poly
		(pts
			(xy 332.861158 -280.76779) (xy 332.761082 -280.667968) (xy 332.661006 -280.76779) (xy 332.661006 -280.815542)
			(xy 332.861158 -280.815542)
		)
		(stroke
			(width 0)
			(type solid)
		)
		(fill yes)
		(layer "In13.Cu")
		(net "M_B_CPU0_SB_DQS_DP<1>")
	)
	(gr_poly
		(pts
			(xy 332.861158 -280.364184) (xy 332.861158 -280.319734) (xy 332.661006 -280.319734) (xy 332.661006 -280.364184)
			(xy 332.761082 -280.46426)
		)
		(stroke
			(width 0)
			(type solid)
		)
		(fill yes)
		(layer "In13.Cu")
		(net "M_B_CPU0_SB_DQ<11>")
	)
	(gr_poly
		(pts
			(xy 332.861158 -279.148032) (xy 332.761082 -279.047956) (xy 332.661006 -279.148032) (xy 332.661006 -279.192482)
			(xy 332.861158 -279.192482)
		)
		(stroke
			(width 0)
			(type solid)
		)
		(fill yes)
		(layer "In13.Cu")
		(net "M_B_CPU0_SB_DQ<8>")
	)
	(gr_poly
		(pts
			(xy 332.861158 -278.744172) (xy 332.861158 -278.699722) (xy 332.661006 -278.699722) (xy 332.661006 -278.744172)
			(xy 332.761082 -278.844248)
		)
		(stroke
			(width 0)
			(type solid)
		)
		(fill yes)
		(layer "In13.Cu")
		(net "M_B_CPU0_SB_DQ<7>")
	)
	(gr_poly
		(pts
			(xy 332.861158 -277.52802) (xy 332.761082 -277.427944) (xy 332.661006 -277.52802) (xy 332.661006 -277.57247)
			(xy 332.861158 -277.57247)
		)
		(stroke
			(width 0)
			(type solid)
		)
		(fill yes)
		(layer "In13.Cu")
		(net "M_B_CPU0_SB_DQ<4>")
	)
	(gr_poly
		(pts
			(xy 332.861158 -277.124414) (xy 332.861158 -277.076662) (xy 332.661006 -277.076662) (xy 332.661006 -277.124414)
			(xy 332.761082 -277.224236)
		)
		(stroke
			(width 0)
			(type solid)
		)
		(fill yes)
		(layer "In13.Cu")
		(net "M_B_CPU0_SB_DQS_DP<5>")
	)
	(gr_poly
		(pts
			(xy 332.861158 -275.907754) (xy 332.761082 -275.807932) (xy 332.661006 -275.907754) (xy 332.661006 -275.955506)
			(xy 332.861158 -275.955506)
		)
		(stroke
			(width 0)
			(type solid)
		)
		(fill yes)
		(layer "In13.Cu")
		(net "M_B_CPU0_SB_DQS_DP<0>")
	)
	(gr_poly
		(pts
			(xy 332.861158 -275.504148) (xy 332.861158 -275.459698) (xy 332.661006 -275.459698) (xy 332.661006 -275.504148)
			(xy 332.761082 -275.604224)
		)
		(stroke
			(width 0)
			(type solid)
		)
		(fill yes)
		(layer "In13.Cu")
		(net "M_B_CPU0_SB_DQ<3>")
	)
	(gr_poly
		(pts
			(xy 332.861158 -274.287996) (xy 332.761082 -274.18792) (xy 332.661006 -274.287996) (xy 332.661006 -274.332446)
			(xy 332.861158 -274.332446)
		)
		(stroke
			(width 0)
			(type solid)
		)
		(fill yes)
		(layer "In13.Cu")
		(net "M_B_CPU0_SB_DQ<0>")
	)
	(gr_poly
		(pts
			(xy 332.861158 -273.884136) (xy 332.861158 -273.839686) (xy 332.661006 -273.839686) (xy 332.661006 -273.884136)
			(xy 332.761082 -273.984212)
		)
		(stroke
			(width 0)
			(type solid)
		)
		(fill yes)
		(layer "In13.Cu")
		(net "M_B_CPU0_SB_CB<3>")
	)
	(gr_poly
		(pts
			(xy 332.861158 -272.667984) (xy 332.761082 -272.567908) (xy 332.661006 -272.667984) (xy 332.661006 -272.712434)
			(xy 332.861158 -272.712434)
		)
		(stroke
			(width 0)
			(type solid)
		)
		(fill yes)
		(layer "In13.Cu")
		(net "M_B_CPU0_SB_CB<0>")
	)
	(gr_poly
		(pts
			(xy 332.861158 -272.264378) (xy 332.861158 -272.216626) (xy 332.661006 -272.216626) (xy 332.661006 -272.264378)
			(xy 332.761082 -272.3642)
		)
		(stroke
			(width 0)
			(type solid)
		)
		(fill yes)
		(layer "In13.Cu")
		(net "M_B_CPU0_SB_DQS_DP<4>")
	)
	(gr_poly
		(pts
			(xy 332.861158 -271.047718) (xy 332.761082 -270.947896) (xy 332.661006 -271.047718) (xy 332.661006 -271.09547)
			(xy 332.861158 -271.09547)
		)
		(stroke
			(width 0)
			(type solid)
		)
		(fill yes)
		(layer "In13.Cu")
		(net "M_B_CPU0_SB_DQS_DP<9>")
	)
	(gr_poly
		(pts
			(xy 332.861158 -270.644112) (xy 332.861158 -270.599662) (xy 332.661006 -270.599662) (xy 332.661006 -270.644112)
			(xy 332.761082 -270.744188)
		)
		(stroke
			(width 0)
			(type solid)
		)
		(fill yes)
		(layer "In13.Cu")
		(net "M_B_CPU0_SB_CB<7>")
	)
	(gr_poly
		(pts
			(xy 332.861158 -269.42796) (xy 332.761082 -269.327884) (xy 332.661006 -269.42796) (xy 332.661006 -269.47241)
			(xy 332.861158 -269.47241)
		)
		(stroke
			(width 0)
			(type solid)
		)
		(fill yes)
		(layer "In13.Cu")
		(net "M_B_CPU0_SB_CB<4>")
	)
	(gr_poly
		(pts
			(xy 332.861158 -267.801598) (xy 332.761082 -267.701522) (xy 332.661006 -267.801598) (xy 332.661006 -267.846048)
			(xy 332.861158 -267.846048)
		)
		(stroke
			(width 0)
			(type solid)
		)
		(fill yes)
		(layer "In13.Cu")
		(net "M_B_CPU0_SB_RSP<0>")
	)
	(gr_poly
		(pts
			(xy 332.861158 -265.784076) (xy 332.861158 -265.739626) (xy 332.661006 -265.739626) (xy 332.661006 -265.784076)
			(xy 332.761082 -265.884152)
		)
		(stroke
			(width 0)
			(type solid)
		)
		(fill yes)
		(layer "In13.Cu")
		(net "M_B_CPU0_SB_CS_N<0>")
	)
	(gr_poly
		(pts
			(xy 332.861158 -264.567924) (xy 332.761082 -264.467848) (xy 332.661006 -264.567924) (xy 332.661006 -264.612374)
			(xy 332.861158 -264.612374)
		)
		(stroke
			(width 0)
			(type solid)
		)
		(fill yes)
		(layer "In13.Cu")
		(net "M_B_CPU0_SB_CA<6>")
	)
	(gr_poly
		(pts
			(xy 332.861158 -264.164064) (xy 332.861158 -264.119614) (xy 332.661006 -264.119614) (xy 332.661006 -264.164064)
			(xy 332.761082 -264.26414)
		)
		(stroke
			(width 0)
			(type solid)
		)
		(fill yes)
		(layer "In13.Cu")
		(net "M_B_CPU0_SB_CA<5>")
	)
	(gr_poly
		(pts
			(xy 332.861158 -262.947912) (xy 332.761082 -262.847836) (xy 332.661006 -262.947912) (xy 332.661006 -262.992362)
			(xy 332.861158 -262.992362)
		)
		(stroke
			(width 0)
			(type solid)
		)
		(fill yes)
		(layer "In13.Cu")
		(net "M_B_CPU0_SB_CA<2>")
	)
	(gr_poly
		(pts
			(xy 332.861158 -262.544052) (xy 332.861158 -262.499602) (xy 332.661006 -262.499602) (xy 332.661006 -262.544052)
			(xy 332.761082 -262.644128)
		)
		(stroke
			(width 0)
			(type solid)
		)
		(fill yes)
		(layer "In13.Cu")
		(net "M_B_CPU0_SB_CA<1>")
	)
	(gr_poly
		(pts
			(xy 333.031084 -256.025904) (xy 332.931008 -255.926082) (xy 332.830932 -256.025904) (xy 332.830932 -256.073656)
			(xy 333.031084 -256.073656)
		)
		(stroke
			(width 0)
			(type solid)
		)
		(fill yes)
		(layer "In13.Cu")
		(net "M_B_CPU0_CLK_DP<0>")
	)
	(gr_poly
		(pts
			(xy 333.031084 -255.622298) (xy 333.031084 -255.577848) (xy 332.830932 -255.577848) (xy 332.830932 -255.622298)
			(xy 332.931008 -255.722374)
		)
		(stroke
			(width 0)
			(type solid)
		)
		(fill yes)
		(layer "In13.Cu")
		(net "M_B_CPU0_SA_PAR")
	)
	(gr_poly
		(pts
			(xy 333.031084 -254.406146) (xy 332.931008 -254.30607) (xy 332.830932 -254.406146) (xy 332.830932 -254.450596)
			(xy 333.031084 -254.450596)
		)
		(stroke
			(width 0)
			(type solid)
		)
		(fill yes)
		(layer "In13.Cu")
		(net "M_B_CPU0_SA_CA<4>")
	)
	(gr_poly
		(pts
			(xy 333.031084 -254.002286) (xy 333.031084 -253.957836) (xy 332.830932 -253.957836) (xy 332.830932 -254.002286)
			(xy 332.931008 -254.102362)
		)
		(stroke
			(width 0)
			(type solid)
		)
		(fill yes)
		(layer "In13.Cu")
		(net "M_B_CPU0_SA_CA<3>")
	)
	(gr_poly
		(pts
			(xy 333.031084 -252.786134) (xy 332.931008 -252.686058) (xy 332.830932 -252.786134) (xy 332.830932 -252.830584)
			(xy 333.031084 -252.830584)
		)
		(stroke
			(width 0)
			(type solid)
		)
		(fill yes)
		(layer "In13.Cu")
		(net "M_B_CPU0_SA_CA<0>")
	)
	(gr_poly
		(pts
			(xy 333.031084 -252.382274) (xy 333.031084 -252.337824) (xy 332.830932 -252.337824) (xy 332.830932 -252.382274)
			(xy 332.931008 -252.48235)
		)
		(stroke
			(width 0)
			(type solid)
		)
		(fill yes)
		(layer "In13.Cu")
		(net "M_B_CPU0_SA_CS_N<1>")
	)
	(gr_poly
		(pts
			(xy 333.031084 -250.762262) (xy 333.031084 -250.717812) (xy 332.830932 -250.717812) (xy 332.830932 -250.762262)
			(xy 332.931008 -250.862338)
		)
		(stroke
			(width 0)
			(type solid)
		)
		(fill yes)
		(layer "In13.Cu")
		(net "M_B_CPU0_RESET_N")
	)
	(gr_poly
		(pts
			(xy 333.031084 -249.14225) (xy 333.031084 -249.0978) (xy 332.830932 -249.0978) (xy 332.830932 -249.14225)
			(xy 332.931008 -249.242326)
		)
		(stroke
			(width 0)
			(type solid)
		)
		(fill yes)
		(layer "In13.Cu")
		(net "M_B_CPU0_SA_CB<7>")
	)
	(gr_poly
		(pts
			(xy 333.031084 -247.926098) (xy 332.931008 -247.826022) (xy 332.830932 -247.926098) (xy 332.830932 -247.970548)
			(xy 333.031084 -247.970548)
		)
		(stroke
			(width 0)
			(type solid)
		)
		(fill yes)
		(layer "In13.Cu")
		(net "M_B_CPU0_SA_CB<4>")
	)
	(gr_poly
		(pts
			(xy 333.031084 -247.522492) (xy 333.031084 -247.47474) (xy 332.830932 -247.47474) (xy 332.830932 -247.522492)
			(xy 332.931008 -247.622314)
		)
		(stroke
			(width 0)
			(type solid)
		)
		(fill yes)
		(layer "In13.Cu")
		(net "M_B_CPU0_SA_DQS_DP<9>")
	)
	(gr_poly
		(pts
			(xy 333.031084 -246.305832) (xy 332.931008 -246.20601) (xy 332.830932 -246.305832) (xy 332.830932 -246.353584)
			(xy 333.031084 -246.353584)
		)
		(stroke
			(width 0)
			(type solid)
		)
		(fill yes)
		(layer "In13.Cu")
		(net "M_B_CPU0_SA_DQS_DP<4>")
	)
	(gr_poly
		(pts
			(xy 333.031084 -245.902226) (xy 333.031084 -245.857776) (xy 332.830932 -245.857776) (xy 332.830932 -245.902226)
			(xy 332.931008 -246.002302)
		)
		(stroke
			(width 0)
			(type solid)
		)
		(fill yes)
		(layer "In13.Cu")
		(net "M_B_CPU0_SA_CB<3>")
	)
	(gr_poly
		(pts
			(xy 333.031084 -244.686074) (xy 332.931008 -244.585998) (xy 332.830932 -244.686074) (xy 332.830932 -244.730524)
			(xy 333.031084 -244.730524)
		)
		(stroke
			(width 0)
			(type solid)
		)
		(fill yes)
		(layer "In13.Cu")
		(net "M_B_CPU0_SA_CB<0>")
	)
	(gr_poly
		(pts
			(xy 333.031084 -244.282214) (xy 333.031084 -244.237764) (xy 332.830932 -244.237764) (xy 332.830932 -244.282214)
			(xy 332.931008 -244.38229)
		)
		(stroke
			(width 0)
			(type solid)
		)
		(fill yes)
		(layer "In13.Cu")
		(net "M_B_CPU0_SA_DQ<31>")
	)
	(gr_poly
		(pts
			(xy 333.031084 -243.066062) (xy 332.931008 -242.965986) (xy 332.830932 -243.066062) (xy 332.830932 -243.110512)
			(xy 333.031084 -243.110512)
		)
		(stroke
			(width 0)
			(type solid)
		)
		(fill yes)
		(layer "In13.Cu")
		(net "M_B_CPU0_SA_DQ<28>")
	)
	(gr_poly
		(pts
			(xy 333.031084 -242.662456) (xy 333.031084 -242.614704) (xy 332.830932 -242.614704) (xy 332.830932 -242.662456)
			(xy 332.931008 -242.762278)
		)
		(stroke
			(width 0)
			(type solid)
		)
		(fill yes)
		(layer "In13.Cu")
		(net "M_B_CPU0_SA_DQS_DP<8>")
	)
	(gr_poly
		(pts
			(xy 333.031084 -241.445796) (xy 332.931008 -241.345974) (xy 332.830932 -241.445796) (xy 332.830932 -241.493548)
			(xy 333.031084 -241.493548)
		)
		(stroke
			(width 0)
			(type solid)
		)
		(fill yes)
		(layer "In13.Cu")
		(net "M_B_CPU0_SA_DQS_DP<3>")
	)
	(gr_poly
		(pts
			(xy 333.031084 -241.04219) (xy 333.031084 -240.99774) (xy 332.830932 -240.99774) (xy 332.830932 -241.04219)
			(xy 332.931008 -241.142266)
		)
		(stroke
			(width 0)
			(type solid)
		)
		(fill yes)
		(layer "In13.Cu")
		(net "M_B_CPU0_SA_DQ<27>")
	)
	(gr_poly
		(pts
			(xy 333.031084 -239.826038) (xy 332.931008 -239.725962) (xy 332.830932 -239.826038) (xy 332.830932 -239.870488)
			(xy 333.031084 -239.870488)
		)
		(stroke
			(width 0)
			(type solid)
		)
		(fill yes)
		(layer "In13.Cu")
		(net "M_B_CPU0_SA_DQ<24>")
	)
	(gr_poly
		(pts
			(xy 333.031084 -239.422178) (xy 333.031084 -239.377728) (xy 332.830932 -239.377728) (xy 332.830932 -239.422178)
			(xy 332.931008 -239.522254)
		)
		(stroke
			(width 0)
			(type solid)
		)
		(fill yes)
		(layer "In13.Cu")
		(net "M_B_CPU0_SA_DQ<23>")
	)
	(gr_poly
		(pts
			(xy 333.031084 -238.206026) (xy 332.931008 -238.10595) (xy 332.830932 -238.206026) (xy 332.830932 -238.250476)
			(xy 333.031084 -238.250476)
		)
		(stroke
			(width 0)
			(type solid)
		)
		(fill yes)
		(layer "In13.Cu")
		(net "M_B_CPU0_SA_DQ<20>")
	)
	(gr_poly
		(pts
			(xy 333.031084 -237.80242) (xy 333.031084 -237.754668) (xy 332.830932 -237.754668) (xy 332.830932 -237.80242)
			(xy 332.931008 -237.902242)
		)
		(stroke
			(width 0)
			(type solid)
		)
		(fill yes)
		(layer "In13.Cu")
		(net "M_B_CPU0_SA_DQS_DP<7>")
	)
	(gr_poly
		(pts
			(xy 333.031084 -236.58576) (xy 332.931008 -236.485938) (xy 332.830932 -236.58576) (xy 332.830932 -236.633512)
			(xy 333.031084 -236.633512)
		)
		(stroke
			(width 0)
			(type solid)
		)
		(fill yes)
		(layer "In13.Cu")
		(net "M_B_CPU0_SA_DQS_DP<2>")
	)
	(gr_poly
		(pts
			(xy 333.031084 -236.182154) (xy 333.031084 -236.137704) (xy 332.830932 -236.137704) (xy 332.830932 -236.182154)
			(xy 332.931008 -236.28223)
		)
		(stroke
			(width 0)
			(type solid)
		)
		(fill yes)
		(layer "In13.Cu")
		(net "M_B_CPU0_SA_DQ<19>")
	)
	(gr_poly
		(pts
			(xy 333.031084 -234.966002) (xy 332.931008 -234.865926) (xy 332.830932 -234.966002) (xy 332.830932 -235.010452)
			(xy 333.031084 -235.010452)
		)
		(stroke
			(width 0)
			(type solid)
		)
		(fill yes)
		(layer "In13.Cu")
		(net "M_B_CPU0_SA_DQ<16>")
	)
	(gr_poly
		(pts
			(xy 333.031084 -234.562142) (xy 333.031084 -234.517692) (xy 332.830932 -234.517692) (xy 332.830932 -234.562142)
			(xy 332.931008 -234.662218)
		)
		(stroke
			(width 0)
			(type solid)
		)
		(fill yes)
		(layer "In13.Cu")
		(net "M_B_CPU0_SA_DQ<15>")
	)
	(gr_poly
		(pts
			(xy 333.031084 -233.34599) (xy 332.931008 -233.245914) (xy 332.830932 -233.34599) (xy 332.830932 -233.39044)
			(xy 333.031084 -233.39044)
		)
		(stroke
			(width 0)
			(type solid)
		)
		(fill yes)
		(layer "In13.Cu")
		(net "M_B_CPU0_SA_DQ<12>")
	)
	(gr_poly
		(pts
			(xy 333.031084 -232.942384) (xy 333.031084 -232.894632) (xy 332.830932 -232.894632) (xy 332.830932 -232.942384)
			(xy 332.931008 -233.042206)
		)
		(stroke
			(width 0)
			(type solid)
		)
		(fill yes)
		(layer "In13.Cu")
		(net "M_B_CPU0_SA_DQS_DP<6>")
	)
	(gr_poly
		(pts
			(xy 333.031084 -231.725724) (xy 332.931008 -231.625902) (xy 332.830932 -231.725724) (xy 332.830932 -231.773476)
			(xy 333.031084 -231.773476)
		)
		(stroke
			(width 0)
			(type solid)
		)
		(fill yes)
		(layer "In13.Cu")
		(net "M_B_CPU0_SA_DQS_DP<1>")
	)
	(gr_poly
		(pts
			(xy 333.031084 -231.322372) (xy 333.031084 -231.277922) (xy 332.830932 -231.277922) (xy 332.830932 -231.322372)
			(xy 332.931008 -231.422448)
		)
		(stroke
			(width 0)
			(type solid)
		)
		(fill yes)
		(layer "In13.Cu")
		(net "M_B_CPU0_SA_DQ<11>")
	)
	(gr_poly
		(pts
			(xy 333.031084 -230.105966) (xy 332.931008 -230.006144) (xy 332.830932 -230.105966) (xy 332.830932 -230.150416)
			(xy 333.031084 -230.150416)
		)
		(stroke
			(width 0)
			(type solid)
		)
		(fill yes)
		(layer "In13.Cu")
		(net "M_B_CPU0_SA_DQ<8>")
	)
	(gr_poly
		(pts
			(xy 333.031084 -229.70236) (xy 333.031084 -229.65791) (xy 332.830932 -229.65791) (xy 332.830932 -229.70236)
			(xy 332.931008 -229.802436)
		)
		(stroke
			(width 0)
			(type solid)
		)
		(fill yes)
		(layer "In13.Cu")
		(net "M_B_CPU0_SA_DQ<7>")
	)
	(gr_poly
		(pts
			(xy 333.031084 -228.486208) (xy 332.931008 -228.386132) (xy 332.830932 -228.486208) (xy 332.830932 -228.530658)
			(xy 333.031084 -228.530658)
		)
		(stroke
			(width 0)
			(type solid)
		)
		(fill yes)
		(layer "In13.Cu")
		(net "M_B_CPU0_SA_DQ<4>")
	)
	(gr_poly
		(pts
			(xy 333.031084 -228.082602) (xy 333.031084 -228.03485) (xy 332.830932 -228.03485) (xy 332.830932 -228.082602)
			(xy 332.931008 -228.182424)
		)
		(stroke
			(width 0)
			(type solid)
		)
		(fill yes)
		(layer "In13.Cu")
		(net "M_B_CPU0_SA_DQS_DP<5>")
	)
	(gr_poly
		(pts
			(xy 333.031084 -226.865942) (xy 332.931008 -226.76612) (xy 332.830932 -226.865942) (xy 332.830932 -226.913694)
			(xy 333.031084 -226.913694)
		)
		(stroke
			(width 0)
			(type solid)
		)
		(fill yes)
		(layer "In13.Cu")
		(net "M_B_CPU0_SA_DQS_DP<0>")
	)
	(gr_poly
		(pts
			(xy 333.031084 -226.462336) (xy 333.031084 -226.417886) (xy 332.830932 -226.417886) (xy 332.830932 -226.462336)
			(xy 332.931008 -226.562412)
		)
		(stroke
			(width 0)
			(type solid)
		)
		(fill yes)
		(layer "In13.Cu")
		(net "M_B_CPU0_SA_DQ<3>")
	)
	(gr_poly
		(pts
			(xy 333.031084 -225.246184) (xy 332.931008 -225.146108) (xy 332.830932 -225.246184) (xy 332.830932 -225.290634)
			(xy 333.031084 -225.290634)
		)
		(stroke
			(width 0)
			(type solid)
		)
		(fill yes)
		(layer "In13.Cu")
		(net "M_B_CPU0_SA_DQ<0>")
	)
	(gr_poly
		(pts
			(xy 333.331058 -292.91788) (xy 333.230982 -292.817804) (xy 333.130906 -292.91788) (xy 333.130906 -292.96233)
			(xy 333.331058 -292.96233)
		)
		(stroke
			(width 0)
			(type solid)
		)
		(fill yes)
		(layer "In13.Cu")
		(net "M_B_CPU0_SB_DQ<29>")
	)
	(gr_poly
		(pts
			(xy 333.331058 -292.51402) (xy 333.331058 -292.46957) (xy 333.130906 -292.46957) (xy 333.130906 -292.51402)
			(xy 333.230982 -292.614096)
		)
		(stroke
			(width 0)
			(type solid)
		)
		(fill yes)
		(layer "In13.Cu")
		(net "M_B_CPU0_SB_DQ<30>")
	)
	(gr_poly
		(pts
			(xy 333.331058 -291.297614) (xy 333.230982 -291.197792) (xy 333.130906 -291.297614) (xy 333.130906 -291.345366)
			(xy 333.331058 -291.345366)
		)
		(stroke
			(width 0)
			(type solid)
		)
		(fill yes)
		(layer "In13.Cu")
		(net "M_B_CPU0_SB_DQS_DN<8>")
	)
	(gr_poly
		(pts
			(xy 333.331058 -290.894262) (xy 333.331058 -290.84651) (xy 333.130906 -290.84651) (xy 333.130906 -290.894262)
			(xy 333.230982 -290.994084)
		)
		(stroke
			(width 0)
			(type solid)
		)
		(fill yes)
		(layer "In13.Cu")
		(net "M_B_CPU0_SB_DQS_DN<3>")
	)
	(gr_poly
		(pts
			(xy 333.331058 -289.677856) (xy 333.230982 -289.57778) (xy 333.130906 -289.677856) (xy 333.130906 -289.722306)
			(xy 333.331058 -289.722306)
		)
		(stroke
			(width 0)
			(type solid)
		)
		(fill yes)
		(layer "In13.Cu")
		(net "M_B_CPU0_SB_DQ<25>")
	)
	(gr_poly
		(pts
			(xy 333.331058 -289.273996) (xy 333.331058 -289.229546) (xy 333.130906 -289.229546) (xy 333.130906 -289.273996)
			(xy 333.230982 -289.374072)
		)
		(stroke
			(width 0)
			(type solid)
		)
		(fill yes)
		(layer "In13.Cu")
		(net "M_B_CPU0_SB_DQ<26>")
	)
	(gr_poly
		(pts
			(xy 333.331058 -288.057844) (xy 333.230982 -287.957768) (xy 333.130906 -288.057844) (xy 333.130906 -288.102294)
			(xy 333.331058 -288.102294)
		)
		(stroke
			(width 0)
			(type solid)
		)
		(fill yes)
		(layer "In13.Cu")
		(net "M_B_CPU0_SB_DQ<21>")
	)
	(gr_poly
		(pts
			(xy 333.331058 -287.654238) (xy 333.331058 -287.609788) (xy 333.130906 -287.609788) (xy 333.130906 -287.654238)
			(xy 333.230982 -287.75406)
		)
		(stroke
			(width 0)
			(type solid)
		)
		(fill yes)
		(layer "In13.Cu")
		(net "M_B_CPU0_SB_DQ<22>")
	)
	(gr_poly
		(pts
			(xy 333.331058 -286.437832) (xy 333.230982 -286.337756) (xy 333.130906 -286.437832) (xy 333.130906 -286.485584)
			(xy 333.331058 -286.485584)
		)
		(stroke
			(width 0)
			(type solid)
		)
		(fill yes)
		(layer "In13.Cu")
		(net "M_B_CPU0_SB_DQS_DN<7>")
	)
	(gr_poly
		(pts
			(xy 333.331058 -286.03448) (xy 333.331058 -285.986728) (xy 333.130906 -285.986728) (xy 333.130906 -286.03448)
			(xy 333.230982 -286.134302)
		)
		(stroke
			(width 0)
			(type solid)
		)
		(fill yes)
		(layer "In13.Cu")
		(net "M_B_CPU0_SB_DQS_DN<2>")
	)
	(gr_poly
		(pts
			(xy 333.331058 -284.818074) (xy 333.230982 -284.717998) (xy 333.130906 -284.818074) (xy 333.130906 -284.862524)
			(xy 333.331058 -284.862524)
		)
		(stroke
			(width 0)
			(type solid)
		)
		(fill yes)
		(layer "In13.Cu")
		(net "M_B_CPU0_SB_DQ<17>")
	)
	(gr_poly
		(pts
			(xy 333.331058 -284.414214) (xy 333.331058 -284.369764) (xy 333.130906 -284.369764) (xy 333.130906 -284.414214)
			(xy 333.230982 -284.51429)
		)
		(stroke
			(width 0)
			(type solid)
		)
		(fill yes)
		(layer "In13.Cu")
		(net "M_B_CPU0_SB_DQ<18>")
	)
	(gr_poly
		(pts
			(xy 333.331058 -283.198062) (xy 333.230982 -283.097986) (xy 333.130906 -283.198062) (xy 333.130906 -283.242512)
			(xy 333.331058 -283.242512)
		)
		(stroke
			(width 0)
			(type solid)
		)
		(fill yes)
		(layer "In13.Cu")
		(net "M_B_CPU0_SB_DQ<13>")
	)
	(gr_poly
		(pts
			(xy 333.331058 -282.794202) (xy 333.331058 -282.749752) (xy 333.130906 -282.749752) (xy 333.130906 -282.794202)
			(xy 333.230982 -282.894278)
		)
		(stroke
			(width 0)
			(type solid)
		)
		(fill yes)
		(layer "In13.Cu")
		(net "M_B_CPU0_SB_DQ<14>")
	)
	(gr_poly
		(pts
			(xy 333.331058 -281.577796) (xy 333.230982 -281.477974) (xy 333.130906 -281.577796) (xy 333.130906 -281.625548)
			(xy 333.331058 -281.625548)
		)
		(stroke
			(width 0)
			(type solid)
		)
		(fill yes)
		(layer "In13.Cu")
		(net "M_B_CPU0_SB_DQS_DN<6>")
	)
	(gr_poly
		(pts
			(xy 333.331058 -281.174444) (xy 333.331058 -281.126692) (xy 333.130906 -281.126692) (xy 333.130906 -281.174444)
			(xy 333.230982 -281.274266)
		)
		(stroke
			(width 0)
			(type solid)
		)
		(fill yes)
		(layer "In13.Cu")
		(net "M_B_CPU0_SB_DQS_DN<1>")
	)
	(gr_poly
		(pts
			(xy 333.331058 -279.958038) (xy 333.230982 -279.857962) (xy 333.130906 -279.958038) (xy 333.130906 -280.002488)
			(xy 333.331058 -280.002488)
		)
		(stroke
			(width 0)
			(type solid)
		)
		(fill yes)
		(layer "In13.Cu")
		(net "M_B_CPU0_SB_DQ<9>")
	)
	(gr_poly
		(pts
			(xy 333.331058 -279.554178) (xy 333.331058 -279.509728) (xy 333.130906 -279.509728) (xy 333.130906 -279.554178)
			(xy 333.230982 -279.654254)
		)
		(stroke
			(width 0)
			(type solid)
		)
		(fill yes)
		(layer "In13.Cu")
		(net "M_B_CPU0_SB_DQ<10>")
	)
	(gr_poly
		(pts
			(xy 333.331058 -278.338026) (xy 333.230982 -278.23795) (xy 333.130906 -278.338026) (xy 333.130906 -278.382476)
			(xy 333.331058 -278.382476)
		)
		(stroke
			(width 0)
			(type solid)
		)
		(fill yes)
		(layer "In13.Cu")
		(net "M_B_CPU0_SB_DQ<5>")
	)
	(gr_poly
		(pts
			(xy 333.331058 -277.934166) (xy 333.331058 -277.889716) (xy 333.130906 -277.889716) (xy 333.130906 -277.934166)
			(xy 333.230982 -278.034242)
		)
		(stroke
			(width 0)
			(type solid)
		)
		(fill yes)
		(layer "In13.Cu")
		(net "M_B_CPU0_SB_DQ<6>")
	)
	(gr_poly
		(pts
			(xy 333.331058 -276.71776) (xy 333.230982 -276.617938) (xy 333.130906 -276.71776) (xy 333.130906 -276.765512)
			(xy 333.331058 -276.765512)
		)
		(stroke
			(width 0)
			(type solid)
		)
		(fill yes)
		(layer "In13.Cu")
		(net "M_B_CPU0_SB_DQS_DN<5>")
	)
	(gr_poly
		(pts
			(xy 333.331058 -276.314408) (xy 333.331058 -276.266656) (xy 333.130906 -276.266656) (xy 333.130906 -276.314408)
			(xy 333.230982 -276.41423)
		)
		(stroke
			(width 0)
			(type solid)
		)
		(fill yes)
		(layer "In13.Cu")
		(net "M_B_CPU0_SB_DQS_DN<0>")
	)
	(gr_poly
		(pts
			(xy 333.331058 -275.098002) (xy 333.230982 -274.997926) (xy 333.130906 -275.098002) (xy 333.130906 -275.142452)
			(xy 333.331058 -275.142452)
		)
		(stroke
			(width 0)
			(type solid)
		)
		(fill yes)
		(layer "In13.Cu")
		(net "M_B_CPU0_SB_DQ<1>")
	)
	(gr_poly
		(pts
			(xy 333.331058 -274.694142) (xy 333.331058 -274.649692) (xy 333.130906 -274.649692) (xy 333.130906 -274.694142)
			(xy 333.230982 -274.794218)
		)
		(stroke
			(width 0)
			(type solid)
		)
		(fill yes)
		(layer "In13.Cu")
		(net "M_B_CPU0_SB_DQ<2>")
	)
	(gr_poly
		(pts
			(xy 333.331058 -273.47799) (xy 333.230982 -273.377914) (xy 333.130906 -273.47799) (xy 333.130906 -273.52244)
			(xy 333.331058 -273.52244)
		)
		(stroke
			(width 0)
			(type solid)
		)
		(fill yes)
		(layer "In13.Cu")
		(net "M_B_CPU0_SB_CB<1>")
	)
	(gr_poly
		(pts
			(xy 333.331058 -273.07413) (xy 333.331058 -273.02968) (xy 333.130906 -273.02968) (xy 333.130906 -273.07413)
			(xy 333.230982 -273.174206)
		)
		(stroke
			(width 0)
			(type solid)
		)
		(fill yes)
		(layer "In13.Cu")
		(net "M_B_CPU0_SB_CB<2>")
	)
	(gr_poly
		(pts
			(xy 333.331058 -271.857724) (xy 333.230982 -271.757902) (xy 333.130906 -271.857724) (xy 333.130906 -271.905476)
			(xy 333.331058 -271.905476)
		)
		(stroke
			(width 0)
			(type solid)
		)
		(fill yes)
		(layer "In13.Cu")
		(net "M_B_CPU0_SB_DQS_DN<4>")
	)
	(gr_poly
		(pts
			(xy 333.331058 -271.454372) (xy 333.331058 -271.40662) (xy 333.130906 -271.40662) (xy 333.130906 -271.454372)
			(xy 333.230982 -271.554194)
		)
		(stroke
			(width 0)
			(type solid)
		)
		(fill yes)
		(layer "In13.Cu")
		(net "M_B_CPU0_SB_DQS_DN<9>")
	)
	(gr_poly
		(pts
			(xy 333.331058 -270.237966) (xy 333.230982 -270.13789) (xy 333.130906 -270.237966) (xy 333.130906 -270.282416)
			(xy 333.331058 -270.282416)
		)
		(stroke
			(width 0)
			(type solid)
		)
		(fill yes)
		(layer "In13.Cu")
		(net "M_B_CPU0_SB_CB<5>")
	)
	(gr_poly
		(pts
			(xy 333.331058 -269.834106) (xy 333.331058 -269.789656) (xy 333.130906 -269.789656) (xy 333.130906 -269.834106)
			(xy 333.230982 -269.934182)
		)
		(stroke
			(width 0)
			(type solid)
		)
		(fill yes)
		(layer "In13.Cu")
		(net "M_B_CPU0_SB_CB<6>")
	)
	(gr_poly
		(pts
			(xy 333.331058 -266.594082) (xy 333.331058 -266.549632) (xy 333.130906 -266.549632) (xy 333.130906 -266.594082)
			(xy 333.230982 -266.694158)
		)
		(stroke
			(width 0)
			(type solid)
		)
		(fill yes)
		(layer "In13.Cu")
		(net "M_B_CPU0_SB_CS_N<1>")
	)
	(gr_poly
		(pts
			(xy 333.331058 -264.97407) (xy 333.331058 -264.92962) (xy 333.130906 -264.92962) (xy 333.130906 -264.97407)
			(xy 333.230982 -265.074146)
		)
		(stroke
			(width 0)
			(type solid)
		)
		(fill yes)
		(layer "In13.Cu")
		(net "M_B_CPU0_SB_PAR")
	)
	(gr_poly
		(pts
			(xy 333.331058 -263.757918) (xy 333.230982 -263.657842) (xy 333.130906 -263.757918) (xy 333.130906 -263.802368)
			(xy 333.331058 -263.802368)
		)
		(stroke
			(width 0)
			(type solid)
		)
		(fill yes)
		(layer "In13.Cu")
		(net "M_B_CPU0_SB_CA<4>")
	)
	(gr_poly
		(pts
			(xy 333.331058 -263.354058) (xy 333.331058 -263.309608) (xy 333.130906 -263.309608) (xy 333.130906 -263.354058)
			(xy 333.230982 -263.454134)
		)
		(stroke
			(width 0)
			(type solid)
		)
		(fill yes)
		(layer "In13.Cu")
		(net "M_B_CPU0_SB_CA<3>")
	)
	(gr_poly
		(pts
			(xy 333.331058 -262.137906) (xy 333.230982 -262.03783) (xy 333.130906 -262.137906) (xy 333.130906 -262.182356)
			(xy 333.331058 -262.182356)
		)
		(stroke
			(width 0)
			(type solid)
		)
		(fill yes)
		(layer "In13.Cu")
		(net "M_B_CPU0_SB_CA<0>")
	)
	(gr_poly
		(pts
			(xy 333.337154 -266.991592) (xy 333.237332 -266.891516) (xy 333.137256 -266.991592) (xy 333.137256 -267.036042)
			(xy 333.337154 -267.036042)
		)
		(stroke
			(width 0)
			(type solid)
		)
		(fill yes)
		(layer "In13.Cu")
		(net "M_B_CPU0_SA_RSP<0>")
	)
	(gr_poly
		(pts
			(xy 333.495142 -227.676456) (xy 333.395066 -227.57638) (xy 333.29499 -227.676456) (xy 333.29499 -227.723954)
			(xy 333.495142 -227.723954)
		)
		(stroke
			(width 0)
			(type solid)
		)
		(fill yes)
		(layer "In13.Cu")
		(net "M_B_CPU0_SA_DQS_DN<5>")
	)
	(gr_poly
		(pts
			(xy 333.501238 -256.432558) (xy 333.501238 -256.384806) (xy 333.301086 -256.384806) (xy 333.301086 -256.432558)
			(xy 333.401162 -256.53238)
		)
		(stroke
			(width 0)
			(type solid)
		)
		(fill yes)
		(layer "In13.Cu")
		(net "M_B_CPU0_CLK_DN<0>")
	)
	(gr_poly
		(pts
			(xy 333.501238 -255.216152) (xy 333.401162 -255.116076) (xy 333.301086 -255.216152) (xy 333.301086 -255.260602)
			(xy 333.501238 -255.260602)
		)
		(stroke
			(width 0)
			(type solid)
		)
		(fill yes)
		(layer "In13.Cu")
		(net "M_B_CPU0_SA_CA<6>")
	)
	(gr_poly
		(pts
			(xy 333.501238 -254.812292) (xy 333.501238 -254.767842) (xy 333.301086 -254.767842) (xy 333.301086 -254.812292)
			(xy 333.401162 -254.912368)
		)
		(stroke
			(width 0)
			(type solid)
		)
		(fill yes)
		(layer "In13.Cu")
		(net "M_B_CPU0_SA_CA<5>")
	)
	(gr_poly
		(pts
			(xy 333.501238 -253.59614) (xy 333.401162 -253.496064) (xy 333.301086 -253.59614) (xy 333.301086 -253.64059)
			(xy 333.501238 -253.64059)
		)
		(stroke
			(width 0)
			(type solid)
		)
		(fill yes)
		(layer "In13.Cu")
		(net "M_B_CPU0_SA_CA<2>")
	)
	(gr_poly
		(pts
			(xy 333.501238 -253.19228) (xy 333.501238 -253.14783) (xy 333.301086 -253.14783) (xy 333.301086 -253.19228)
			(xy 333.401162 -253.292356)
		)
		(stroke
			(width 0)
			(type solid)
		)
		(fill yes)
		(layer "In13.Cu")
		(net "M_B_CPU0_SA_CA<1>")
	)
	(gr_poly
		(pts
			(xy 333.501238 -251.572268) (xy 333.501238 -251.527818) (xy 333.301086 -251.527818) (xy 333.301086 -251.572268)
			(xy 333.401162 -251.672344)
		)
		(stroke
			(width 0)
			(type solid)
		)
		(fill yes)
		(layer "In13.Cu")
		(net "M_B_CPU0_SA_CS_N<0>")
	)
	(gr_poly
		(pts
			(xy 333.501238 -250.356116) (xy 333.401162 -250.25604) (xy 333.301086 -250.356116) (xy 333.301086 -250.400566)
			(xy 333.501238 -250.400566)
		)
		(stroke
			(width 0)
			(type solid)
		)
		(fill yes)
		(layer "In13.Cu")
		(net "M_B_CPU0_ALERT_R_N")
	)
	(gr_poly
		(pts
			(xy 333.501238 -248.736104) (xy 333.401162 -248.636028) (xy 333.301086 -248.736104) (xy 333.301086 -248.780554)
			(xy 333.501238 -248.780554)
		)
		(stroke
			(width 0)
			(type solid)
		)
		(fill yes)
		(layer "In13.Cu")
		(net "M_B_CPU0_SA_CB<5>")
	)
	(gr_poly
		(pts
			(xy 333.501238 -248.332244) (xy 333.501238 -248.287794) (xy 333.301086 -248.287794) (xy 333.301086 -248.332244)
			(xy 333.401162 -248.43232)
		)
		(stroke
			(width 0)
			(type solid)
		)
		(fill yes)
		(layer "In13.Cu")
		(net "M_B_CPU0_SA_CB<6>")
	)
	(gr_poly
		(pts
			(xy 333.501238 -247.115838) (xy 333.401162 -247.016016) (xy 333.301086 -247.115838) (xy 333.301086 -247.16359)
			(xy 333.501238 -247.16359)
		)
		(stroke
			(width 0)
			(type solid)
		)
		(fill yes)
		(layer "In13.Cu")
		(net "M_B_CPU0_SA_DQS_DN<9>")
	)
	(gr_poly
		(pts
			(xy 333.501238 -246.712486) (xy 333.501238 -246.664734) (xy 333.301086 -246.664734) (xy 333.301086 -246.712486)
			(xy 333.401162 -246.812308)
		)
		(stroke
			(width 0)
			(type solid)
		)
		(fill yes)
		(layer "In13.Cu")
		(net "M_B_CPU0_SA_DQS_DN<4>")
	)
	(gr_poly
		(pts
			(xy 333.501238 -245.49608) (xy 333.401162 -245.396004) (xy 333.301086 -245.49608) (xy 333.301086 -245.54053)
			(xy 333.501238 -245.54053)
		)
		(stroke
			(width 0)
			(type solid)
		)
		(fill yes)
		(layer "In13.Cu")
		(net "M_B_CPU0_SA_CB<1>")
	)
	(gr_poly
		(pts
			(xy 333.501238 -245.09222) (xy 333.501238 -245.04777) (xy 333.301086 -245.04777) (xy 333.301086 -245.09222)
			(xy 333.401162 -245.192296)
		)
		(stroke
			(width 0)
			(type solid)
		)
		(fill yes)
		(layer "In13.Cu")
		(net "M_B_CPU0_SA_CB<2>")
	)
	(gr_poly
		(pts
			(xy 333.501238 -243.876068) (xy 333.401162 -243.775992) (xy 333.301086 -243.876068) (xy 333.301086 -243.920518)
			(xy 333.501238 -243.920518)
		)
		(stroke
			(width 0)
			(type solid)
		)
		(fill yes)
		(layer "In13.Cu")
		(net "M_B_CPU0_SA_DQ<29>")
	)
	(gr_poly
		(pts
			(xy 333.501238 -243.472208) (xy 333.501238 -243.427758) (xy 333.301086 -243.427758) (xy 333.301086 -243.472208)
			(xy 333.401162 -243.572284)
		)
		(stroke
			(width 0)
			(type solid)
		)
		(fill yes)
		(layer "In13.Cu")
		(net "M_B_CPU0_SA_DQ<30>")
	)
	(gr_poly
		(pts
			(xy 333.501238 -242.255802) (xy 333.401162 -242.15598) (xy 333.301086 -242.255802) (xy 333.301086 -242.303554)
			(xy 333.501238 -242.303554)
		)
		(stroke
			(width 0)
			(type solid)
		)
		(fill yes)
		(layer "In13.Cu")
		(net "M_B_CPU0_SA_DQS_DN<8>")
	)
	(gr_poly
		(pts
			(xy 333.501238 -241.85245) (xy 333.501238 -241.804698) (xy 333.301086 -241.804698) (xy 333.301086 -241.85245)
			(xy 333.401162 -241.952272)
		)
		(stroke
			(width 0)
			(type solid)
		)
		(fill yes)
		(layer "In13.Cu")
		(net "M_B_CPU0_SA_DQS_DN<3>")
	)
	(gr_poly
		(pts
			(xy 333.501238 -240.636044) (xy 333.401162 -240.535968) (xy 333.301086 -240.636044) (xy 333.301086 -240.680494)
			(xy 333.501238 -240.680494)
		)
		(stroke
			(width 0)
			(type solid)
		)
		(fill yes)
		(layer "In13.Cu")
		(net "M_B_CPU0_SA_DQ<25>")
	)
	(gr_poly
		(pts
			(xy 333.501238 -240.232184) (xy 333.501238 -240.187734) (xy 333.301086 -240.187734) (xy 333.301086 -240.232184)
			(xy 333.401162 -240.33226)
		)
		(stroke
			(width 0)
			(type solid)
		)
		(fill yes)
		(layer "In13.Cu")
		(net "M_B_CPU0_SA_DQ<26>")
	)
	(gr_poly
		(pts
			(xy 333.501238 -239.016032) (xy 333.401162 -238.915956) (xy 333.301086 -239.016032) (xy 333.301086 -239.060482)
			(xy 333.501238 -239.060482)
		)
		(stroke
			(width 0)
			(type solid)
		)
		(fill yes)
		(layer "In13.Cu")
		(net "M_B_CPU0_SA_DQ<21>")
	)
	(gr_poly
		(pts
			(xy 333.501238 -238.612172) (xy 333.501238 -238.567722) (xy 333.301086 -238.567722) (xy 333.301086 -238.612172)
			(xy 333.401162 -238.712248)
		)
		(stroke
			(width 0)
			(type solid)
		)
		(fill yes)
		(layer "In13.Cu")
		(net "M_B_CPU0_SA_DQ<22>")
	)
	(gr_poly
		(pts
			(xy 333.501238 -237.395766) (xy 333.401162 -237.295944) (xy 333.301086 -237.395766) (xy 333.301086 -237.443518)
			(xy 333.501238 -237.443518)
		)
		(stroke
			(width 0)
			(type solid)
		)
		(fill yes)
		(layer "In13.Cu")
		(net "M_B_CPU0_SA_DQS_DN<7>")
	)
	(gr_poly
		(pts
			(xy 333.501238 -236.992414) (xy 333.501238 -236.944662) (xy 333.301086 -236.944662) (xy 333.301086 -236.992414)
			(xy 333.401162 -237.092236)
		)
		(stroke
			(width 0)
			(type solid)
		)
		(fill yes)
		(layer "In13.Cu")
		(net "M_B_CPU0_SA_DQS_DN<2>")
	)
	(gr_poly
		(pts
			(xy 333.501238 -235.776008) (xy 333.401162 -235.675932) (xy 333.301086 -235.776008) (xy 333.301086 -235.820458)
			(xy 333.501238 -235.820458)
		)
		(stroke
			(width 0)
			(type solid)
		)
		(fill yes)
		(layer "In13.Cu")
		(net "M_B_CPU0_SA_DQ<17>")
	)
	(gr_poly
		(pts
			(xy 333.501238 -235.372148) (xy 333.501238 -235.327698) (xy 333.301086 -235.327698) (xy 333.301086 -235.372148)
			(xy 333.401162 -235.472224)
		)
		(stroke
			(width 0)
			(type solid)
		)
		(fill yes)
		(layer "In13.Cu")
		(net "M_B_CPU0_SA_DQ<18>")
	)
	(gr_poly
		(pts
			(xy 333.501238 -234.155996) (xy 333.401162 -234.05592) (xy 333.301086 -234.155996) (xy 333.301086 -234.200446)
			(xy 333.501238 -234.200446)
		)
		(stroke
			(width 0)
			(type solid)
		)
		(fill yes)
		(layer "In13.Cu")
		(net "M_B_CPU0_SA_DQ<13>")
	)
	(gr_poly
		(pts
			(xy 333.501238 -233.752136) (xy 333.501238 -233.707686) (xy 333.301086 -233.707686) (xy 333.301086 -233.752136)
			(xy 333.401162 -233.852212)
		)
		(stroke
			(width 0)
			(type solid)
		)
		(fill yes)
		(layer "In13.Cu")
		(net "M_B_CPU0_SA_DQ<14>")
	)
	(gr_poly
		(pts
			(xy 333.501238 -232.53573) (xy 333.401162 -232.435908) (xy 333.301086 -232.53573) (xy 333.301086 -232.583482)
			(xy 333.501238 -232.583482)
		)
		(stroke
			(width 0)
			(type solid)
		)
		(fill yes)
		(layer "In13.Cu")
		(net "M_B_CPU0_SA_DQS_DN<6>")
	)
	(gr_poly
		(pts
			(xy 333.501238 -232.132378) (xy 333.501238 -232.084626) (xy 333.301086 -232.084626) (xy 333.301086 -232.132378)
			(xy 333.401162 -232.2322)
		)
		(stroke
			(width 0)
			(type solid)
		)
		(fill yes)
		(layer "In13.Cu")
		(net "M_B_CPU0_SA_DQS_DN<1>")
	)
	(gr_poly
		(pts
			(xy 333.501238 -230.915972) (xy 333.401162 -230.815896) (xy 333.301086 -230.915972) (xy 333.301086 -230.960422)
			(xy 333.501238 -230.960422)
		)
		(stroke
			(width 0)
			(type solid)
		)
		(fill yes)
		(layer "In13.Cu")
		(net "M_B_CPU0_SA_DQ<9>")
	)
	(gr_poly
		(pts
			(xy 333.501238 -230.512366) (xy 333.501238 -230.467916) (xy 333.301086 -230.467916) (xy 333.301086 -230.512366)
			(xy 333.401162 -230.612188)
		)
		(stroke
			(width 0)
			(type solid)
		)
		(fill yes)
		(layer "In13.Cu")
		(net "M_B_CPU0_SA_DQ<10>")
	)
	(gr_poly
		(pts
			(xy 333.501238 -229.29596) (xy 333.401162 -229.195884) (xy 333.301086 -229.29596) (xy 333.301086 -229.34041)
			(xy 333.501238 -229.34041)
		)
		(stroke
			(width 0)
			(type solid)
		)
		(fill yes)
		(layer "In13.Cu")
		(net "M_B_CPU0_SA_DQ<5>")
	)
	(gr_poly
		(pts
			(xy 333.501238 -228.892354) (xy 333.501238 -228.847904) (xy 333.301086 -228.847904) (xy 333.301086 -228.892354)
			(xy 333.401162 -228.99243)
		)
		(stroke
			(width 0)
			(type solid)
		)
		(fill yes)
		(layer "In13.Cu")
		(net "M_B_CPU0_SA_DQ<6>")
	)
	(gr_poly
		(pts
			(xy 333.501238 -227.272596) (xy 333.501238 -227.224844) (xy 333.301086 -227.224844) (xy 333.301086 -227.272596)
			(xy 333.401162 -227.372418)
		)
		(stroke
			(width 0)
			(type solid)
		)
		(fill yes)
		(layer "In13.Cu")
		(net "M_B_CPU0_SA_DQS_DN<0>")
	)
	(gr_poly
		(pts
			(xy 333.501238 -226.05619) (xy 333.401162 -225.956114) (xy 333.301086 -226.05619) (xy 333.301086 -226.10064)
			(xy 333.501238 -226.10064)
		)
		(stroke
			(width 0)
			(type solid)
		)
		(fill yes)
		(layer "In13.Cu")
		(net "M_B_CPU0_SA_DQ<1>")
	)
	(gr_poly
		(pts
			(xy 333.501238 -225.65233) (xy 333.501238 -225.60788) (xy 333.301086 -225.60788) (xy 333.301086 -225.65233)
			(xy 333.401162 -225.752406)
		)
		(stroke
			(width 0)
			(type solid)
		)
		(fill yes)
		(layer "In13.Cu")
		(net "M_B_CPU0_SA_DQ<2>")
	)
	(gr_poly
		(pts
			(xy 333.794862 -267.801598) (xy 333.694786 -267.701522) (xy 333.594964 -267.801598) (xy 333.594964 -267.846048)
			(xy 333.794862 -267.846048)
		)
		(stroke
			(width 0)
			(type solid)
		)
		(fill yes)
		(layer "In13.Cu")
		(net "M_B_CPU0_SB_RSP<0>")
	)
	(gr_poly
		(pts
			(xy 333.801212 -293.324026) (xy 333.801212 -293.279576) (xy 333.60106 -293.279576) (xy 333.60106 -293.324026)
			(xy 333.701136 -293.424102)
		)
		(stroke
			(width 0)
			(type solid)
		)
		(fill yes)
		(layer "In13.Cu")
		(net "M_B_CPU0_SB_DQ<31>")
	)
	(gr_poly
		(pts
			(xy 333.801212 -292.107874) (xy 333.701136 -292.007798) (xy 333.60106 -292.107874) (xy 333.60106 -292.152324)
			(xy 333.801212 -292.152324)
		)
		(stroke
			(width 0)
			(type solid)
		)
		(fill yes)
		(layer "In13.Cu")
		(net "M_B_CPU0_SB_DQ<28>")
	)
	(gr_poly
		(pts
			(xy 333.801212 -291.704268) (xy 333.801212 -291.656516) (xy 333.60106 -291.656516) (xy 333.60106 -291.704268)
			(xy 333.701136 -291.80409)
		)
		(stroke
			(width 0)
			(type solid)
		)
		(fill yes)
		(layer "In13.Cu")
		(net "M_B_CPU0_SB_DQS_DP<8>")
	)
	(gr_poly
		(pts
			(xy 333.801212 -290.487608) (xy 333.701136 -290.387786) (xy 333.60106 -290.487608) (xy 333.60106 -290.53536)
			(xy 333.801212 -290.53536)
		)
		(stroke
			(width 0)
			(type solid)
		)
		(fill yes)
		(layer "In13.Cu")
		(net "M_B_CPU0_SB_DQS_DP<3>")
	)
	(gr_poly
		(pts
			(xy 333.801212 -290.084002) (xy 333.801212 -290.039552) (xy 333.60106 -290.039552) (xy 333.60106 -290.084002)
			(xy 333.701136 -290.184078)
		)
		(stroke
			(width 0)
			(type solid)
		)
		(fill yes)
		(layer "In13.Cu")
		(net "M_B_CPU0_SB_DQ<27>")
	)
	(gr_poly
		(pts
			(xy 333.801212 -288.86785) (xy 333.701136 -288.767774) (xy 333.60106 -288.86785) (xy 333.60106 -288.9123)
			(xy 333.801212 -288.9123)
		)
		(stroke
			(width 0)
			(type solid)
		)
		(fill yes)
		(layer "In13.Cu")
		(net "M_B_CPU0_SB_DQ<24>")
	)
	(gr_poly
		(pts
			(xy 333.801212 -288.464244) (xy 333.801212 -288.419794) (xy 333.60106 -288.419794) (xy 333.60106 -288.464244)
			(xy 333.701136 -288.56432)
		)
		(stroke
			(width 0)
			(type solid)
		)
		(fill yes)
		(layer "In13.Cu")
		(net "M_B_CPU0_SB_DQ<23>")
	)
	(gr_poly
		(pts
			(xy 333.801212 -287.247838) (xy 333.701136 -287.148016) (xy 333.60106 -287.247838) (xy 333.60106 -287.292288)
			(xy 333.801212 -287.292288)
		)
		(stroke
			(width 0)
			(type solid)
		)
		(fill yes)
		(layer "In13.Cu")
		(net "M_B_CPU0_SB_DQ<20>")
	)
	(gr_poly
		(pts
			(xy 333.801212 -286.844232) (xy 333.801212 -286.79648) (xy 333.60106 -286.79648) (xy 333.60106 -286.844232)
			(xy 333.701136 -286.944308)
		)
		(stroke
			(width 0)
			(type solid)
		)
		(fill yes)
		(layer "In13.Cu")
		(net "M_B_CPU0_SB_DQS_DP<7>")
	)
	(gr_poly
		(pts
			(xy 333.801212 -285.627826) (xy 333.701136 -285.528004) (xy 333.60106 -285.627826) (xy 333.60106 -285.675578)
			(xy 333.801212 -285.675578)
		)
		(stroke
			(width 0)
			(type solid)
		)
		(fill yes)
		(layer "In13.Cu")
		(net "M_B_CPU0_SB_DQS_DP<2>")
	)
	(gr_poly
		(pts
			(xy 333.801212 -285.22422) (xy 333.801212 -285.17977) (xy 333.60106 -285.17977) (xy 333.60106 -285.22422)
			(xy 333.701136 -285.324296)
		)
		(stroke
			(width 0)
			(type solid)
		)
		(fill yes)
		(layer "In13.Cu")
		(net "M_B_CPU0_SB_DQ<19>")
	)
	(gr_poly
		(pts
			(xy 333.801212 -284.008068) (xy 333.701136 -283.907992) (xy 333.60106 -284.008068) (xy 333.60106 -284.052518)
			(xy 333.801212 -284.052518)
		)
		(stroke
			(width 0)
			(type solid)
		)
		(fill yes)
		(layer "In13.Cu")
		(net "M_B_CPU0_SB_DQ<16>")
	)
	(gr_poly
		(pts
			(xy 333.801212 -283.604208) (xy 333.801212 -283.559758) (xy 333.60106 -283.559758) (xy 333.60106 -283.604208)
			(xy 333.701136 -283.704284)
		)
		(stroke
			(width 0)
			(type solid)
		)
		(fill yes)
		(layer "In13.Cu")
		(net "M_B_CPU0_SB_DQ<15>")
	)
	(gr_poly
		(pts
			(xy 333.801212 -282.388056) (xy 333.701136 -282.28798) (xy 333.60106 -282.388056) (xy 333.60106 -282.432506)
			(xy 333.801212 -282.432506)
		)
		(stroke
			(width 0)
			(type solid)
		)
		(fill yes)
		(layer "In13.Cu")
		(net "M_B_CPU0_SB_DQ<12>")
	)
	(gr_poly
		(pts
			(xy 333.801212 -281.98445) (xy 333.801212 -281.936698) (xy 333.60106 -281.936698) (xy 333.60106 -281.98445)
			(xy 333.701136 -282.084272)
		)
		(stroke
			(width 0)
			(type solid)
		)
		(fill yes)
		(layer "In13.Cu")
		(net "M_B_CPU0_SB_DQS_DP<6>")
	)
	(gr_poly
		(pts
			(xy 333.801212 -280.76779) (xy 333.701136 -280.667968) (xy 333.60106 -280.76779) (xy 333.60106 -280.815542)
			(xy 333.801212 -280.815542)
		)
		(stroke
			(width 0)
			(type solid)
		)
		(fill yes)
		(layer "In13.Cu")
		(net "M_B_CPU0_SB_DQS_DP<1>")
	)
	(gr_poly
		(pts
			(xy 333.801212 -280.364184) (xy 333.801212 -280.319734) (xy 333.60106 -280.319734) (xy 333.60106 -280.364184)
			(xy 333.701136 -280.46426)
		)
		(stroke
			(width 0)
			(type solid)
		)
		(fill yes)
		(layer "In13.Cu")
		(net "M_B_CPU0_SB_DQ<11>")
	)
	(gr_poly
		(pts
			(xy 333.801212 -279.148032) (xy 333.701136 -279.047956) (xy 333.60106 -279.148032) (xy 333.60106 -279.192482)
			(xy 333.801212 -279.192482)
		)
		(stroke
			(width 0)
			(type solid)
		)
		(fill yes)
		(layer "In13.Cu")
		(net "M_B_CPU0_SB_DQ<8>")
	)
	(gr_poly
		(pts
			(xy 333.801212 -278.744172) (xy 333.801212 -278.699722) (xy 333.60106 -278.699722) (xy 333.60106 -278.744172)
			(xy 333.701136 -278.844248)
		)
		(stroke
			(width 0)
			(type solid)
		)
		(fill yes)
		(layer "In13.Cu")
		(net "M_B_CPU0_SB_DQ<7>")
	)
	(gr_poly
		(pts
			(xy 333.801212 -277.52802) (xy 333.701136 -277.427944) (xy 333.60106 -277.52802) (xy 333.60106 -277.57247)
			(xy 333.801212 -277.57247)
		)
		(stroke
			(width 0)
			(type solid)
		)
		(fill yes)
		(layer "In13.Cu")
		(net "M_B_CPU0_SB_DQ<4>")
	)
	(gr_poly
		(pts
			(xy 333.801212 -277.12416) (xy 333.801212 -277.076662) (xy 333.60106 -277.076662) (xy 333.60106 -277.12416)
			(xy 333.701136 -277.224236)
		)
		(stroke
			(width 0)
			(type solid)
		)
		(fill yes)
		(layer "In13.Cu")
		(net "M_B_CPU0_SB_DQS_DP<5>")
	)
	(gr_poly
		(pts
			(xy 333.801212 -275.908008) (xy 333.701136 -275.807932) (xy 333.60106 -275.908008) (xy 333.60106 -275.955506)
			(xy 333.801212 -275.955506)
		)
		(stroke
			(width 0)
			(type solid)
		)
		(fill yes)
		(layer "In13.Cu")
		(net "M_B_CPU0_SB_DQS_DP<0>")
	)
	(gr_poly
		(pts
			(xy 333.801212 -275.504148) (xy 333.801212 -275.459698) (xy 333.60106 -275.459698) (xy 333.60106 -275.504148)
			(xy 333.701136 -275.604224)
		)
		(stroke
			(width 0)
			(type solid)
		)
		(fill yes)
		(layer "In13.Cu")
		(net "M_B_CPU0_SB_DQ<3>")
	)
	(gr_poly
		(pts
			(xy 333.801212 -274.287996) (xy 333.701136 -274.18792) (xy 333.60106 -274.287996) (xy 333.60106 -274.332446)
			(xy 333.801212 -274.332446)
		)
		(stroke
			(width 0)
			(type solid)
		)
		(fill yes)
		(layer "In13.Cu")
		(net "M_B_CPU0_SB_DQ<0>")
	)
	(gr_poly
		(pts
			(xy 333.801212 -273.884136) (xy 333.801212 -273.839686) (xy 333.60106 -273.839686) (xy 333.60106 -273.884136)
			(xy 333.701136 -273.984212)
		)
		(stroke
			(width 0)
			(type solid)
		)
		(fill yes)
		(layer "In13.Cu")
		(net "M_B_CPU0_SB_CB<3>")
	)
	(gr_poly
		(pts
			(xy 333.801212 -272.667984) (xy 333.701136 -272.567908) (xy 333.60106 -272.667984) (xy 333.60106 -272.712434)
			(xy 333.801212 -272.712434)
		)
		(stroke
			(width 0)
			(type solid)
		)
		(fill yes)
		(layer "In13.Cu")
		(net "M_B_CPU0_SB_CB<0>")
	)
	(gr_poly
		(pts
			(xy 333.801212 -272.264378) (xy 333.801212 -272.216626) (xy 333.60106 -272.216626) (xy 333.60106 -272.264378)
			(xy 333.701136 -272.3642)
		)
		(stroke
			(width 0)
			(type solid)
		)
		(fill yes)
		(layer "In13.Cu")
		(net "M_B_CPU0_SB_DQS_DP<4>")
	)
	(gr_poly
		(pts
			(xy 333.801212 -271.047718) (xy 333.701136 -270.947896) (xy 333.60106 -271.047718) (xy 333.60106 -271.09547)
			(xy 333.801212 -271.09547)
		)
		(stroke
			(width 0)
			(type solid)
		)
		(fill yes)
		(layer "In13.Cu")
		(net "M_B_CPU0_SB_DQS_DP<9>")
	)
	(gr_poly
		(pts
			(xy 333.801212 -270.644112) (xy 333.801212 -270.599662) (xy 333.60106 -270.599662) (xy 333.60106 -270.644112)
			(xy 333.701136 -270.744188)
		)
		(stroke
			(width 0)
			(type solid)
		)
		(fill yes)
		(layer "In13.Cu")
		(net "M_B_CPU0_SB_CB<7>")
	)
	(gr_poly
		(pts
			(xy 333.801212 -269.42796) (xy 333.701136 -269.327884) (xy 333.60106 -269.42796) (xy 333.60106 -269.47241)
			(xy 333.801212 -269.47241)
		)
		(stroke
			(width 0)
			(type solid)
		)
		(fill yes)
		(layer "In13.Cu")
		(net "M_B_CPU0_SB_CB<4>")
	)
	(gr_poly
		(pts
			(xy 333.801212 -265.784076) (xy 333.801212 -265.739626) (xy 333.60106 -265.739626) (xy 333.60106 -265.784076)
			(xy 333.701136 -265.884152)
		)
		(stroke
			(width 0)
			(type solid)
		)
		(fill yes)
		(layer "In13.Cu")
		(net "M_B_CPU0_SB_CS_N<0>")
	)
	(gr_poly
		(pts
			(xy 333.801212 -264.567924) (xy 333.701136 -264.467848) (xy 333.60106 -264.567924) (xy 333.60106 -264.612374)
			(xy 333.801212 -264.612374)
		)
		(stroke
			(width 0)
			(type solid)
		)
		(fill yes)
		(layer "In13.Cu")
		(net "M_B_CPU0_SB_CA<6>")
	)
	(gr_poly
		(pts
			(xy 333.801212 -264.164064) (xy 333.801212 -264.119614) (xy 333.60106 -264.119614) (xy 333.60106 -264.164064)
			(xy 333.701136 -264.26414)
		)
		(stroke
			(width 0)
			(type solid)
		)
		(fill yes)
		(layer "In13.Cu")
		(net "M_B_CPU0_SB_CA<5>")
	)
	(gr_poly
		(pts
			(xy 333.801212 -262.947912) (xy 333.701136 -262.847836) (xy 333.60106 -262.947912) (xy 333.60106 -262.992362)
			(xy 333.801212 -262.992362)
		)
		(stroke
			(width 0)
			(type solid)
		)
		(fill yes)
		(layer "In13.Cu")
		(net "M_B_CPU0_SB_CA<2>")
	)
	(gr_poly
		(pts
			(xy 333.801212 -262.544052) (xy 333.801212 -262.499602) (xy 333.60106 -262.499602) (xy 333.60106 -262.544052)
			(xy 333.701136 -262.644128)
		)
		(stroke
			(width 0)
			(type solid)
		)
		(fill yes)
		(layer "In13.Cu")
		(net "M_B_CPU0_SB_CA<1>")
	)
	(gr_poly
		(pts
			(xy 333.971138 -256.025904) (xy 333.871062 -255.926082) (xy 333.770986 -256.025904) (xy 333.770986 -256.073656)
			(xy 333.971138 -256.073656)
		)
		(stroke
			(width 0)
			(type solid)
		)
		(fill yes)
		(layer "In13.Cu")
		(net "M_B_CPU0_CLK_DP<0>")
	)
	(gr_poly
		(pts
			(xy 333.971138 -255.622298) (xy 333.971138 -255.577848) (xy 333.770986 -255.577848) (xy 333.770986 -255.622298)
			(xy 333.871062 -255.722374)
		)
		(stroke
			(width 0)
			(type solid)
		)
		(fill yes)
		(layer "In13.Cu")
		(net "M_B_CPU0_SA_PAR")
	)
	(gr_poly
		(pts
			(xy 333.971138 -254.406146) (xy 333.871062 -254.30607) (xy 333.770986 -254.406146) (xy 333.770986 -254.450596)
			(xy 333.971138 -254.450596)
		)
		(stroke
			(width 0)
			(type solid)
		)
		(fill yes)
		(layer "In13.Cu")
		(net "M_B_CPU0_SA_CA<4>")
	)
	(gr_poly
		(pts
			(xy 333.971138 -254.002286) (xy 333.971138 -253.957836) (xy 333.770986 -253.957836) (xy 333.770986 -254.002286)
			(xy 333.871062 -254.102362)
		)
		(stroke
			(width 0)
			(type solid)
		)
		(fill yes)
		(layer "In13.Cu")
		(net "M_B_CPU0_SA_CA<3>")
	)
	(gr_poly
		(pts
			(xy 333.971138 -252.786134) (xy 333.871062 -252.686058) (xy 333.770986 -252.786134) (xy 333.770986 -252.830584)
			(xy 333.971138 -252.830584)
		)
		(stroke
			(width 0)
			(type solid)
		)
		(fill yes)
		(layer "In13.Cu")
		(net "M_B_CPU0_SA_CA<0>")
	)
	(gr_poly
		(pts
			(xy 333.971138 -252.382274) (xy 333.971138 -252.337824) (xy 333.770986 -252.337824) (xy 333.770986 -252.382274)
			(xy 333.871062 -252.48235)
		)
		(stroke
			(width 0)
			(type solid)
		)
		(fill yes)
		(layer "In13.Cu")
		(net "M_B_CPU0_SA_CS_N<1>")
	)
	(gr_poly
		(pts
			(xy 333.971138 -250.762262) (xy 333.971138 -250.717812) (xy 333.770986 -250.717812) (xy 333.770986 -250.762262)
			(xy 333.871062 -250.862338)
		)
		(stroke
			(width 0)
			(type solid)
		)
		(fill yes)
		(layer "In13.Cu")
		(net "M_B_CPU0_RESET_N")
	)
	(gr_poly
		(pts
			(xy 333.971138 -249.14225) (xy 333.971138 -249.0978) (xy 333.770986 -249.0978) (xy 333.770986 -249.14225)
			(xy 333.871062 -249.242326)
		)
		(stroke
			(width 0)
			(type solid)
		)
		(fill yes)
		(layer "In13.Cu")
		(net "M_B_CPU0_SA_CB<7>")
	)
	(gr_poly
		(pts
			(xy 333.971138 -247.926098) (xy 333.871062 -247.826022) (xy 333.770986 -247.926098) (xy 333.770986 -247.970548)
			(xy 333.971138 -247.970548)
		)
		(stroke
			(width 0)
			(type solid)
		)
		(fill yes)
		(layer "In13.Cu")
		(net "M_B_CPU0_SA_CB<4>")
	)
	(gr_poly
		(pts
			(xy 333.971138 -247.522492) (xy 333.971138 -247.47474) (xy 333.770986 -247.47474) (xy 333.770986 -247.522492)
			(xy 333.871062 -247.622314)
		)
		(stroke
			(width 0)
			(type solid)
		)
		(fill yes)
		(layer "In13.Cu")
		(net "M_B_CPU0_SA_DQS_DP<9>")
	)
	(gr_poly
		(pts
			(xy 333.971138 -246.305832) (xy 333.871062 -246.20601) (xy 333.770986 -246.305832) (xy 333.770986 -246.353584)
			(xy 333.971138 -246.353584)
		)
		(stroke
			(width 0)
			(type solid)
		)
		(fill yes)
		(layer "In13.Cu")
		(net "M_B_CPU0_SA_DQS_DP<4>")
	)
	(gr_poly
		(pts
			(xy 333.971138 -245.902226) (xy 333.971138 -245.857776) (xy 333.770986 -245.857776) (xy 333.770986 -245.902226)
			(xy 333.871062 -246.002302)
		)
		(stroke
			(width 0)
			(type solid)
		)
		(fill yes)
		(layer "In13.Cu")
		(net "M_B_CPU0_SA_CB<3>")
	)
	(gr_poly
		(pts
			(xy 333.971138 -244.686074) (xy 333.871062 -244.585998) (xy 333.770986 -244.686074) (xy 333.770986 -244.730524)
			(xy 333.971138 -244.730524)
		)
		(stroke
			(width 0)
			(type solid)
		)
		(fill yes)
		(layer "In13.Cu")
		(net "M_B_CPU0_SA_CB<0>")
	)
	(gr_poly
		(pts
			(xy 333.971138 -244.282214) (xy 333.971138 -244.237764) (xy 333.770986 -244.237764) (xy 333.770986 -244.282214)
			(xy 333.871062 -244.38229)
		)
		(stroke
			(width 0)
			(type solid)
		)
		(fill yes)
		(layer "In13.Cu")
		(net "M_B_CPU0_SA_DQ<31>")
	)
	(gr_poly
		(pts
			(xy 333.971138 -243.066062) (xy 333.871062 -242.965986) (xy 333.770986 -243.066062) (xy 333.770986 -243.110512)
			(xy 333.971138 -243.110512)
		)
		(stroke
			(width 0)
			(type solid)
		)
		(fill yes)
		(layer "In13.Cu")
		(net "M_B_CPU0_SA_DQ<28>")
	)
	(gr_poly
		(pts
			(xy 333.971138 -242.662456) (xy 333.971138 -242.614704) (xy 333.770986 -242.614704) (xy 333.770986 -242.662456)
			(xy 333.871062 -242.762278)
		)
		(stroke
			(width 0)
			(type solid)
		)
		(fill yes)
		(layer "In13.Cu")
		(net "M_B_CPU0_SA_DQS_DP<8>")
	)
	(gr_poly
		(pts
			(xy 333.971138 -241.445796) (xy 333.871062 -241.345974) (xy 333.770986 -241.445796) (xy 333.770986 -241.493548)
			(xy 333.971138 -241.493548)
		)
		(stroke
			(width 0)
			(type solid)
		)
		(fill yes)
		(layer "In13.Cu")
		(net "M_B_CPU0_SA_DQS_DP<3>")
	)
	(gr_poly
		(pts
			(xy 333.971138 -241.04219) (xy 333.971138 -240.99774) (xy 333.770986 -240.99774) (xy 333.770986 -241.04219)
			(xy 333.871062 -241.142266)
		)
		(stroke
			(width 0)
			(type solid)
		)
		(fill yes)
		(layer "In13.Cu")
		(net "M_B_CPU0_SA_DQ<27>")
	)
	(gr_poly
		(pts
			(xy 333.971138 -239.826038) (xy 333.871062 -239.725962) (xy 333.770986 -239.826038) (xy 333.770986 -239.870488)
			(xy 333.971138 -239.870488)
		)
		(stroke
			(width 0)
			(type solid)
		)
		(fill yes)
		(layer "In13.Cu")
		(net "M_B_CPU0_SA_DQ<24>")
	)
	(gr_poly
		(pts
			(xy 333.971138 -239.422178) (xy 333.971138 -239.377728) (xy 333.770986 -239.377728) (xy 333.770986 -239.422178)
			(xy 333.871062 -239.522254)
		)
		(stroke
			(width 0)
			(type solid)
		)
		(fill yes)
		(layer "In13.Cu")
		(net "M_B_CPU0_SA_DQ<23>")
	)
	(gr_poly
		(pts
			(xy 333.971138 -238.206026) (xy 333.871062 -238.10595) (xy 333.770986 -238.206026) (xy 333.770986 -238.250476)
			(xy 333.971138 -238.250476)
		)
		(stroke
			(width 0)
			(type solid)
		)
		(fill yes)
		(layer "In13.Cu")
		(net "M_B_CPU0_SA_DQ<20>")
	)
	(gr_poly
		(pts
			(xy 333.971138 -237.80242) (xy 333.971138 -237.754668) (xy 333.770986 -237.754668) (xy 333.770986 -237.80242)
			(xy 333.871062 -237.902242)
		)
		(stroke
			(width 0)
			(type solid)
		)
		(fill yes)
		(layer "In13.Cu")
		(net "M_B_CPU0_SA_DQS_DP<7>")
	)
	(gr_poly
		(pts
			(xy 333.971138 -236.58576) (xy 333.871062 -236.485938) (xy 333.770986 -236.58576) (xy 333.770986 -236.633512)
			(xy 333.971138 -236.633512)
		)
		(stroke
			(width 0)
			(type solid)
		)
		(fill yes)
		(layer "In13.Cu")
		(net "M_B_CPU0_SA_DQS_DP<2>")
	)
	(gr_poly
		(pts
			(xy 333.971138 -236.182154) (xy 333.971138 -236.137704) (xy 333.770986 -236.137704) (xy 333.770986 -236.182154)
			(xy 333.871062 -236.28223)
		)
		(stroke
			(width 0)
			(type solid)
		)
		(fill yes)
		(layer "In13.Cu")
		(net "M_B_CPU0_SA_DQ<19>")
	)
	(gr_poly
		(pts
			(xy 333.971138 -234.966002) (xy 333.871062 -234.865926) (xy 333.770986 -234.966002) (xy 333.770986 -235.010452)
			(xy 333.971138 -235.010452)
		)
		(stroke
			(width 0)
			(type solid)
		)
		(fill yes)
		(layer "In13.Cu")
		(net "M_B_CPU0_SA_DQ<16>")
	)
	(gr_poly
		(pts
			(xy 333.971138 -234.562142) (xy 333.971138 -234.517692) (xy 333.770986 -234.517692) (xy 333.770986 -234.562142)
			(xy 333.871062 -234.662218)
		)
		(stroke
			(width 0)
			(type solid)
		)
		(fill yes)
		(layer "In13.Cu")
		(net "M_B_CPU0_SA_DQ<15>")
	)
	(gr_poly
		(pts
			(xy 333.971138 -233.34599) (xy 333.871062 -233.245914) (xy 333.770986 -233.34599) (xy 333.770986 -233.39044)
			(xy 333.971138 -233.39044)
		)
		(stroke
			(width 0)
			(type solid)
		)
		(fill yes)
		(layer "In13.Cu")
		(net "M_B_CPU0_SA_DQ<12>")
	)
	(gr_poly
		(pts
			(xy 333.971138 -232.942384) (xy 333.971138 -232.894632) (xy 333.770986 -232.894632) (xy 333.770986 -232.942384)
			(xy 333.871062 -233.042206)
		)
		(stroke
			(width 0)
			(type solid)
		)
		(fill yes)
		(layer "In13.Cu")
		(net "M_B_CPU0_SA_DQS_DP<6>")
	)
	(gr_poly
		(pts
			(xy 333.971138 -231.725724) (xy 333.871062 -231.625902) (xy 333.770986 -231.725724) (xy 333.770986 -231.773476)
			(xy 333.971138 -231.773476)
		)
		(stroke
			(width 0)
			(type solid)
		)
		(fill yes)
		(layer "In13.Cu")
		(net "M_B_CPU0_SA_DQS_DP<1>")
	)
	(gr_poly
		(pts
			(xy 333.971138 -231.322372) (xy 333.971138 -231.277922) (xy 333.770986 -231.277922) (xy 333.770986 -231.322372)
			(xy 333.871062 -231.422448)
		)
		(stroke
			(width 0)
			(type solid)
		)
		(fill yes)
		(layer "In13.Cu")
		(net "M_B_CPU0_SA_DQ<11>")
	)
	(gr_poly
		(pts
			(xy 333.971138 -230.105966) (xy 333.871062 -230.006144) (xy 333.770986 -230.105966) (xy 333.770986 -230.150416)
			(xy 333.971138 -230.150416)
		)
		(stroke
			(width 0)
			(type solid)
		)
		(fill yes)
		(layer "In13.Cu")
		(net "M_B_CPU0_SA_DQ<8>")
	)
	(gr_poly
		(pts
			(xy 333.971138 -229.70236) (xy 333.971138 -229.65791) (xy 333.770986 -229.65791) (xy 333.770986 -229.70236)
			(xy 333.871062 -229.802436)
		)
		(stroke
			(width 0)
			(type solid)
		)
		(fill yes)
		(layer "In13.Cu")
		(net "M_B_CPU0_SA_DQ<7>")
	)
	(gr_poly
		(pts
			(xy 333.971138 -228.486208) (xy 333.871062 -228.386132) (xy 333.770986 -228.486208) (xy 333.770986 -228.530658)
			(xy 333.971138 -228.530658)
		)
		(stroke
			(width 0)
			(type solid)
		)
		(fill yes)
		(layer "In13.Cu")
		(net "M_B_CPU0_SA_DQ<4>")
	)
	(gr_poly
		(pts
			(xy 333.971138 -228.082602) (xy 333.971138 -228.03485) (xy 333.770986 -228.03485) (xy 333.770986 -228.082602)
			(xy 333.871062 -228.182424)
		)
		(stroke
			(width 0)
			(type solid)
		)
		(fill yes)
		(layer "In13.Cu")
		(net "M_B_CPU0_SA_DQS_DP<5>")
	)
	(gr_poly
		(pts
			(xy 333.971138 -226.865942) (xy 333.871062 -226.76612) (xy 333.770986 -226.865942) (xy 333.770986 -226.913694)
			(xy 333.971138 -226.913694)
		)
		(stroke
			(width 0)
			(type solid)
		)
		(fill yes)
		(layer "In13.Cu")
		(net "M_B_CPU0_SA_DQS_DP<0>")
	)
	(gr_poly
		(pts
			(xy 333.971138 -226.462336) (xy 333.971138 -226.417886) (xy 333.770986 -226.417886) (xy 333.770986 -226.462336)
			(xy 333.871062 -226.562412)
		)
		(stroke
			(width 0)
			(type solid)
		)
		(fill yes)
		(layer "In13.Cu")
		(net "M_B_CPU0_SA_DQ<3>")
	)
	(gr_poly
		(pts
			(xy 333.971138 -225.246184) (xy 333.871062 -225.146108) (xy 333.770986 -225.246184) (xy 333.770986 -225.290634)
			(xy 333.971138 -225.290634)
		)
		(stroke
			(width 0)
			(type solid)
		)
		(fill yes)
		(layer "In13.Cu")
		(net "M_B_CPU0_SA_DQ<0>")
	)
	(gr_poly
		(pts
			(xy 334.271112 -292.91788) (xy 334.171036 -292.817804) (xy 334.07096 -292.91788) (xy 334.07096 -292.96233)
			(xy 334.271112 -292.96233)
		)
		(stroke
			(width 0)
			(type solid)
		)
		(fill yes)
		(layer "In13.Cu")
		(net "M_B_CPU0_SB_DQ<29>")
	)
	(gr_poly
		(pts
			(xy 334.271112 -292.51402) (xy 334.271112 -292.46957) (xy 334.07096 -292.46957) (xy 334.07096 -292.51402)
			(xy 334.171036 -292.614096)
		)
		(stroke
			(width 0)
			(type solid)
		)
		(fill yes)
		(layer "In13.Cu")
		(net "M_B_CPU0_SB_DQ<30>")
	)
	(gr_poly
		(pts
			(xy 334.271112 -291.297614) (xy 334.171036 -291.197792) (xy 334.07096 -291.297614) (xy 334.07096 -291.345366)
			(xy 334.271112 -291.345366)
		)
		(stroke
			(width 0)
			(type solid)
		)
		(fill yes)
		(layer "In13.Cu")
		(net "M_B_CPU0_SB_DQS_DN<8>")
	)
	(gr_poly
		(pts
			(xy 334.271112 -290.894262) (xy 334.271112 -290.84651) (xy 334.07096 -290.84651) (xy 334.07096 -290.894262)
			(xy 334.171036 -290.994084)
		)
		(stroke
			(width 0)
			(type solid)
		)
		(fill yes)
		(layer "In13.Cu")
		(net "M_B_CPU0_SB_DQS_DN<3>")
	)
	(gr_poly
		(pts
			(xy 334.271112 -289.677856) (xy 334.171036 -289.57778) (xy 334.07096 -289.677856) (xy 334.07096 -289.722306)
			(xy 334.271112 -289.722306)
		)
		(stroke
			(width 0)
			(type solid)
		)
		(fill yes)
		(layer "In13.Cu")
		(net "M_B_CPU0_SB_DQ<25>")
	)
	(gr_poly
		(pts
			(xy 334.271112 -289.273996) (xy 334.271112 -289.229546) (xy 334.07096 -289.229546) (xy 334.07096 -289.273996)
			(xy 334.171036 -289.374072)
		)
		(stroke
			(width 0)
			(type solid)
		)
		(fill yes)
		(layer "In13.Cu")
		(net "M_B_CPU0_SB_DQ<26>")
	)
	(gr_poly
		(pts
			(xy 334.271112 -288.057844) (xy 334.171036 -287.957768) (xy 334.07096 -288.057844) (xy 334.07096 -288.102294)
			(xy 334.271112 -288.102294)
		)
		(stroke
			(width 0)
			(type solid)
		)
		(fill yes)
		(layer "In13.Cu")
		(net "M_B_CPU0_SB_DQ<21>")
	)
	(gr_poly
		(pts
			(xy 334.271112 -287.654238) (xy 334.271112 -287.609788) (xy 334.07096 -287.609788) (xy 334.07096 -287.654238)
			(xy 334.171036 -287.75406)
		)
		(stroke
			(width 0)
			(type solid)
		)
		(fill yes)
		(layer "In13.Cu")
		(net "M_B_CPU0_SB_DQ<22>")
	)
	(gr_poly
		(pts
			(xy 334.271112 -286.437832) (xy 334.171036 -286.337756) (xy 334.07096 -286.437832) (xy 334.07096 -286.485584)
			(xy 334.271112 -286.485584)
		)
		(stroke
			(width 0)
			(type solid)
		)
		(fill yes)
		(layer "In13.Cu")
		(net "M_B_CPU0_SB_DQS_DN<7>")
	)
	(gr_poly
		(pts
			(xy 334.271112 -286.03448) (xy 334.271112 -285.986728) (xy 334.07096 -285.986728) (xy 334.07096 -286.03448)
			(xy 334.171036 -286.134302)
		)
		(stroke
			(width 0)
			(type solid)
		)
		(fill yes)
		(layer "In13.Cu")
		(net "M_B_CPU0_SB_DQS_DN<2>")
	)
	(gr_poly
		(pts
			(xy 334.271112 -284.818074) (xy 334.171036 -284.717998) (xy 334.07096 -284.818074) (xy 334.07096 -284.862524)
			(xy 334.271112 -284.862524)
		)
		(stroke
			(width 0)
			(type solid)
		)
		(fill yes)
		(layer "In13.Cu")
		(net "M_B_CPU0_SB_DQ<17>")
	)
	(gr_poly
		(pts
			(xy 334.271112 -284.414214) (xy 334.271112 -284.369764) (xy 334.07096 -284.369764) (xy 334.07096 -284.414214)
			(xy 334.171036 -284.51429)
		)
		(stroke
			(width 0)
			(type solid)
		)
		(fill yes)
		(layer "In13.Cu")
		(net "M_B_CPU0_SB_DQ<18>")
	)
	(gr_poly
		(pts
			(xy 334.271112 -283.198062) (xy 334.171036 -283.097986) (xy 334.07096 -283.198062) (xy 334.07096 -283.242512)
			(xy 334.271112 -283.242512)
		)
		(stroke
			(width 0)
			(type solid)
		)
		(fill yes)
		(layer "In13.Cu")
		(net "M_B_CPU0_SB_DQ<13>")
	)
	(gr_poly
		(pts
			(xy 334.271112 -282.794202) (xy 334.271112 -282.749752) (xy 334.07096 -282.749752) (xy 334.07096 -282.794202)
			(xy 334.171036 -282.894278)
		)
		(stroke
			(width 0)
			(type solid)
		)
		(fill yes)
		(layer "In13.Cu")
		(net "M_B_CPU0_SB_DQ<14>")
	)
	(gr_poly
		(pts
			(xy 334.271112 -281.577796) (xy 334.171036 -281.477974) (xy 334.07096 -281.577796) (xy 334.07096 -281.625548)
			(xy 334.271112 -281.625548)
		)
		(stroke
			(width 0)
			(type solid)
		)
		(fill yes)
		(layer "In13.Cu")
		(net "M_B_CPU0_SB_DQS_DN<6>")
	)
	(gr_poly
		(pts
			(xy 334.271112 -281.174444) (xy 334.271112 -281.126692) (xy 334.07096 -281.126692) (xy 334.07096 -281.174444)
			(xy 334.171036 -281.274266)
		)
		(stroke
			(width 0)
			(type solid)
		)
		(fill yes)
		(layer "In13.Cu")
		(net "M_B_CPU0_SB_DQS_DN<1>")
	)
	(gr_poly
		(pts
			(xy 334.271112 -279.958038) (xy 334.171036 -279.857962) (xy 334.07096 -279.958038) (xy 334.07096 -280.002488)
			(xy 334.271112 -280.002488)
		)
		(stroke
			(width 0)
			(type solid)
		)
		(fill yes)
		(layer "In13.Cu")
		(net "M_B_CPU0_SB_DQ<9>")
	)
	(gr_poly
		(pts
			(xy 334.271112 -279.554178) (xy 334.271112 -279.509728) (xy 334.07096 -279.509728) (xy 334.07096 -279.554178)
			(xy 334.171036 -279.654254)
		)
		(stroke
			(width 0)
			(type solid)
		)
		(fill yes)
		(layer "In13.Cu")
		(net "M_B_CPU0_SB_DQ<10>")
	)
	(gr_poly
		(pts
			(xy 334.271112 -278.338026) (xy 334.171036 -278.23795) (xy 334.07096 -278.338026) (xy 334.07096 -278.382476)
			(xy 334.271112 -278.382476)
		)
		(stroke
			(width 0)
			(type solid)
		)
		(fill yes)
		(layer "In13.Cu")
		(net "M_B_CPU0_SB_DQ<5>")
	)
	(gr_poly
		(pts
			(xy 334.271112 -277.934166) (xy 334.271112 -277.889716) (xy 334.07096 -277.889716) (xy 334.07096 -277.934166)
			(xy 334.171036 -278.034242)
		)
		(stroke
			(width 0)
			(type solid)
		)
		(fill yes)
		(layer "In13.Cu")
		(net "M_B_CPU0_SB_DQ<6>")
	)
	(gr_poly
		(pts
			(xy 334.271112 -275.098002) (xy 334.171036 -274.997926) (xy 334.07096 -275.098002) (xy 334.07096 -275.142452)
			(xy 334.271112 -275.142452)
		)
		(stroke
			(width 0)
			(type solid)
		)
		(fill yes)
		(layer "In13.Cu")
		(net "M_B_CPU0_SB_DQ<1>")
	)
	(gr_poly
		(pts
			(xy 334.271112 -274.694142) (xy 334.271112 -274.649692) (xy 334.07096 -274.649692) (xy 334.07096 -274.694142)
			(xy 334.171036 -274.794218)
		)
		(stroke
			(width 0)
			(type solid)
		)
		(fill yes)
		(layer "In13.Cu")
		(net "M_B_CPU0_SB_DQ<2>")
	)
	(gr_poly
		(pts
			(xy 334.271112 -273.47799) (xy 334.171036 -273.377914) (xy 334.07096 -273.47799) (xy 334.07096 -273.52244)
			(xy 334.271112 -273.52244)
		)
		(stroke
			(width 0)
			(type solid)
		)
		(fill yes)
		(layer "In13.Cu")
		(net "M_B_CPU0_SB_CB<1>")
	)
	(gr_poly
		(pts
			(xy 334.271112 -273.07413) (xy 334.271112 -273.02968) (xy 334.07096 -273.02968) (xy 334.07096 -273.07413)
			(xy 334.171036 -273.174206)
		)
		(stroke
			(width 0)
			(type solid)
		)
		(fill yes)
		(layer "In13.Cu")
		(net "M_B_CPU0_SB_CB<2>")
	)
	(gr_poly
		(pts
			(xy 334.271112 -271.857724) (xy 334.171036 -271.757902) (xy 334.07096 -271.857724) (xy 334.07096 -271.905476)
			(xy 334.271112 -271.905476)
		)
		(stroke
			(width 0)
			(type solid)
		)
		(fill yes)
		(layer "In13.Cu")
		(net "M_B_CPU0_SB_DQS_DN<4>")
	)
	(gr_poly
		(pts
			(xy 334.271112 -271.454372) (xy 334.271112 -271.40662) (xy 334.07096 -271.40662) (xy 334.07096 -271.454372)
			(xy 334.171036 -271.554194)
		)
		(stroke
			(width 0)
			(type solid)
		)
		(fill yes)
		(layer "In13.Cu")
		(net "M_B_CPU0_SB_DQS_DN<9>")
	)
	(gr_poly
		(pts
			(xy 334.271112 -270.237966) (xy 334.171036 -270.13789) (xy 334.07096 -270.237966) (xy 334.07096 -270.282416)
			(xy 334.271112 -270.282416)
		)
		(stroke
			(width 0)
			(type solid)
		)
		(fill yes)
		(layer "In13.Cu")
		(net "M_B_CPU0_SB_CB<5>")
	)
	(gr_poly
		(pts
			(xy 334.271112 -269.834106) (xy 334.271112 -269.789656) (xy 334.07096 -269.789656) (xy 334.07096 -269.834106)
			(xy 334.171036 -269.934182)
		)
		(stroke
			(width 0)
			(type solid)
		)
		(fill yes)
		(layer "In13.Cu")
		(net "M_B_CPU0_SB_CB<6>")
	)
	(gr_poly
		(pts
			(xy 334.271112 -266.594082) (xy 334.271112 -266.549632) (xy 334.07096 -266.549632) (xy 334.07096 -266.594082)
			(xy 334.171036 -266.694158)
		)
		(stroke
			(width 0)
			(type solid)
		)
		(fill yes)
		(layer "In13.Cu")
		(net "M_B_CPU0_SB_CS_N<1>")
	)
	(gr_poly
		(pts
			(xy 334.271112 -264.97407) (xy 334.271112 -264.92962) (xy 334.07096 -264.92962) (xy 334.07096 -264.97407)
			(xy 334.171036 -265.074146)
		)
		(stroke
			(width 0)
			(type solid)
		)
		(fill yes)
		(layer "In13.Cu")
		(net "M_B_CPU0_SB_PAR")
	)
	(gr_poly
		(pts
			(xy 334.271112 -263.757918) (xy 334.171036 -263.657842) (xy 334.07096 -263.757918) (xy 334.07096 -263.802368)
			(xy 334.271112 -263.802368)
		)
		(stroke
			(width 0)
			(type solid)
		)
		(fill yes)
		(layer "In13.Cu")
		(net "M_B_CPU0_SB_CA<4>")
	)
	(gr_poly
		(pts
			(xy 334.271112 -263.354058) (xy 334.271112 -263.309608) (xy 334.07096 -263.309608) (xy 334.07096 -263.354058)
			(xy 334.171036 -263.454134)
		)
		(stroke
			(width 0)
			(type solid)
		)
		(fill yes)
		(layer "In13.Cu")
		(net "M_B_CPU0_SB_CA<3>")
	)
	(gr_poly
		(pts
			(xy 334.271112 -262.137906) (xy 334.171036 -262.03783) (xy 334.07096 -262.137906) (xy 334.07096 -262.182356)
			(xy 334.271112 -262.182356)
		)
		(stroke
			(width 0)
			(type solid)
		)
		(fill yes)
		(layer "In13.Cu")
		(net "M_B_CPU0_SB_CA<0>")
	)
	(gr_poly
		(pts
			(xy 334.277208 -266.991592) (xy 334.177386 -266.891516) (xy 334.07731 -266.991592) (xy 334.07731 -267.036042)
			(xy 334.277208 -267.036042)
		)
		(stroke
			(width 0)
			(type solid)
		)
		(fill yes)
		(layer "In13.Cu")
		(net "M_B_CPU0_SA_RSP<0>")
	)
	(gr_poly
		(pts
			(xy 334.278478 -276.71776) (xy 334.178402 -276.617938) (xy 334.078326 -276.71776) (xy 334.078326 -276.765512)
			(xy 334.278478 -276.765512)
		)
		(stroke
			(width 0)
			(type solid)
		)
		(fill yes)
		(layer "In13.Cu")
		(net "M_B_CPU0_SB_DQS_DN<5>")
	)
	(gr_poly
		(pts
			(xy 334.278478 -276.314408) (xy 334.278478 -276.266656) (xy 334.078326 -276.266656) (xy 334.078326 -276.314408)
			(xy 334.178402 -276.41423)
		)
		(stroke
			(width 0)
			(type solid)
		)
		(fill yes)
		(layer "In13.Cu")
		(net "M_B_CPU0_SB_DQS_DN<0>")
	)
	(gr_poly
		(pts
			(xy 334.434942 -227.676456) (xy 334.33512 -227.57638) (xy 334.235044 -227.676456) (xy 334.235044 -227.723954)
			(xy 334.434942 -227.723954)
		)
		(stroke
			(width 0)
			(type solid)
		)
		(fill yes)
		(layer "In13.Cu")
		(net "M_B_CPU0_SA_DQS_DN<5>")
	)
	(gr_poly
		(pts
			(xy 334.441292 -256.432558) (xy 334.441292 -256.384806) (xy 334.24114 -256.384806) (xy 334.24114 -256.432558)
			(xy 334.341216 -256.53238)
		)
		(stroke
			(width 0)
			(type solid)
		)
		(fill yes)
		(layer "In13.Cu")
		(net "M_B_CPU0_CLK_DN<0>")
	)
	(gr_poly
		(pts
			(xy 334.441292 -255.216152) (xy 334.341216 -255.116076) (xy 334.24114 -255.216152) (xy 334.24114 -255.260602)
			(xy 334.441292 -255.260602)
		)
		(stroke
			(width 0)
			(type solid)
		)
		(fill yes)
		(layer "In13.Cu")
		(net "M_B_CPU0_SA_CA<6>")
	)
	(gr_poly
		(pts
			(xy 334.441292 -254.812292) (xy 334.441292 -254.767842) (xy 334.24114 -254.767842) (xy 334.24114 -254.812292)
			(xy 334.341216 -254.912368)
		)
		(stroke
			(width 0)
			(type solid)
		)
		(fill yes)
		(layer "In13.Cu")
		(net "M_B_CPU0_SA_CA<5>")
	)
	(gr_poly
		(pts
			(xy 334.441292 -253.59614) (xy 334.341216 -253.496064) (xy 334.24114 -253.59614) (xy 334.24114 -253.64059)
			(xy 334.441292 -253.64059)
		)
		(stroke
			(width 0)
			(type solid)
		)
		(fill yes)
		(layer "In13.Cu")
		(net "M_B_CPU0_SA_CA<2>")
	)
	(gr_poly
		(pts
			(xy 334.441292 -253.19228) (xy 334.441292 -253.14783) (xy 334.24114 -253.14783) (xy 334.24114 -253.19228)
			(xy 334.341216 -253.292356)
		)
		(stroke
			(width 0)
			(type solid)
		)
		(fill yes)
		(layer "In13.Cu")
		(net "M_B_CPU0_SA_CA<1>")
	)
	(gr_poly
		(pts
			(xy 334.441292 -251.572268) (xy 334.441292 -251.527818) (xy 334.24114 -251.527818) (xy 334.24114 -251.572268)
			(xy 334.341216 -251.672344)
		)
		(stroke
			(width 0)
			(type solid)
		)
		(fill yes)
		(layer "In13.Cu")
		(net "M_B_CPU0_SA_CS_N<0>")
	)
	(gr_poly
		(pts
			(xy 334.441292 -250.356116) (xy 334.341216 -250.25604) (xy 334.24114 -250.356116) (xy 334.24114 -250.400566)
			(xy 334.441292 -250.400566)
		)
		(stroke
			(width 0)
			(type solid)
		)
		(fill yes)
		(layer "In13.Cu")
		(net "M_B_CPU0_ALERT_R_N")
	)
	(gr_poly
		(pts
			(xy 334.441292 -248.736104) (xy 334.341216 -248.636028) (xy 334.24114 -248.736104) (xy 334.24114 -248.780554)
			(xy 334.441292 -248.780554)
		)
		(stroke
			(width 0)
			(type solid)
		)
		(fill yes)
		(layer "In13.Cu")
		(net "M_B_CPU0_SA_CB<5>")
	)
	(gr_poly
		(pts
			(xy 334.441292 -248.332244) (xy 334.441292 -248.287794) (xy 334.24114 -248.287794) (xy 334.24114 -248.332244)
			(xy 334.341216 -248.43232)
		)
		(stroke
			(width 0)
			(type solid)
		)
		(fill yes)
		(layer "In13.Cu")
		(net "M_B_CPU0_SA_CB<6>")
	)
	(gr_poly
		(pts
			(xy 334.441292 -247.115838) (xy 334.341216 -247.016016) (xy 334.24114 -247.115838) (xy 334.24114 -247.16359)
			(xy 334.441292 -247.16359)
		)
		(stroke
			(width 0)
			(type solid)
		)
		(fill yes)
		(layer "In13.Cu")
		(net "M_B_CPU0_SA_DQS_DN<9>")
	)
	(gr_poly
		(pts
			(xy 334.441292 -246.712486) (xy 334.441292 -246.664734) (xy 334.24114 -246.664734) (xy 334.24114 -246.712486)
			(xy 334.341216 -246.812308)
		)
		(stroke
			(width 0)
			(type solid)
		)
		(fill yes)
		(layer "In13.Cu")
		(net "M_B_CPU0_SA_DQS_DN<4>")
	)
	(gr_poly
		(pts
			(xy 334.441292 -245.49608) (xy 334.341216 -245.396004) (xy 334.24114 -245.49608) (xy 334.24114 -245.54053)
			(xy 334.441292 -245.54053)
		)
		(stroke
			(width 0)
			(type solid)
		)
		(fill yes)
		(layer "In13.Cu")
		(net "M_B_CPU0_SA_CB<1>")
	)
	(gr_poly
		(pts
			(xy 334.441292 -245.09222) (xy 334.441292 -245.04777) (xy 334.24114 -245.04777) (xy 334.24114 -245.09222)
			(xy 334.341216 -245.192296)
		)
		(stroke
			(width 0)
			(type solid)
		)
		(fill yes)
		(layer "In13.Cu")
		(net "M_B_CPU0_SA_CB<2>")
	)
	(gr_poly
		(pts
			(xy 334.441292 -243.876068) (xy 334.341216 -243.775992) (xy 334.24114 -243.876068) (xy 334.24114 -243.920518)
			(xy 334.441292 -243.920518)
		)
		(stroke
			(width 0)
			(type solid)
		)
		(fill yes)
		(layer "In13.Cu")
		(net "M_B_CPU0_SA_DQ<29>")
	)
	(gr_poly
		(pts
			(xy 334.441292 -243.472208) (xy 334.441292 -243.427758) (xy 334.24114 -243.427758) (xy 334.24114 -243.472208)
			(xy 334.341216 -243.572284)
		)
		(stroke
			(width 0)
			(type solid)
		)
		(fill yes)
		(layer "In13.Cu")
		(net "M_B_CPU0_SA_DQ<30>")
	)
	(gr_poly
		(pts
			(xy 334.441292 -242.255802) (xy 334.341216 -242.15598) (xy 334.24114 -242.255802) (xy 334.24114 -242.303554)
			(xy 334.441292 -242.303554)
		)
		(stroke
			(width 0)
			(type solid)
		)
		(fill yes)
		(layer "In13.Cu")
		(net "M_B_CPU0_SA_DQS_DN<8>")
	)
	(gr_poly
		(pts
			(xy 334.441292 -241.85245) (xy 334.441292 -241.804698) (xy 334.24114 -241.804698) (xy 334.24114 -241.85245)
			(xy 334.341216 -241.952272)
		)
		(stroke
			(width 0)
			(type solid)
		)
		(fill yes)
		(layer "In13.Cu")
		(net "M_B_CPU0_SA_DQS_DN<3>")
	)
	(gr_poly
		(pts
			(xy 334.441292 -240.636044) (xy 334.341216 -240.535968) (xy 334.24114 -240.636044) (xy 334.24114 -240.680494)
			(xy 334.441292 -240.680494)
		)
		(stroke
			(width 0)
			(type solid)
		)
		(fill yes)
		(layer "In13.Cu")
		(net "M_B_CPU0_SA_DQ<25>")
	)
	(gr_poly
		(pts
			(xy 334.441292 -240.232184) (xy 334.441292 -240.187734) (xy 334.24114 -240.187734) (xy 334.24114 -240.232184)
			(xy 334.341216 -240.33226)
		)
		(stroke
			(width 0)
			(type solid)
		)
		(fill yes)
		(layer "In13.Cu")
		(net "M_B_CPU0_SA_DQ<26>")
	)
	(gr_poly
		(pts
			(xy 334.441292 -239.016032) (xy 334.341216 -238.915956) (xy 334.24114 -239.016032) (xy 334.24114 -239.060482)
			(xy 334.441292 -239.060482)
		)
		(stroke
			(width 0)
			(type solid)
		)
		(fill yes)
		(layer "In13.Cu")
		(net "M_B_CPU0_SA_DQ<21>")
	)
	(gr_poly
		(pts
			(xy 334.441292 -238.612172) (xy 334.441292 -238.567722) (xy 334.24114 -238.567722) (xy 334.24114 -238.612172)
			(xy 334.341216 -238.712248)
		)
		(stroke
			(width 0)
			(type solid)
		)
		(fill yes)
		(layer "In13.Cu")
		(net "M_B_CPU0_SA_DQ<22>")
	)
	(gr_poly
		(pts
			(xy 334.441292 -237.395766) (xy 334.341216 -237.295944) (xy 334.24114 -237.395766) (xy 334.24114 -237.443518)
			(xy 334.441292 -237.443518)
		)
		(stroke
			(width 0)
			(type solid)
		)
		(fill yes)
		(layer "In13.Cu")
		(net "M_B_CPU0_SA_DQS_DN<7>")
	)
	(gr_poly
		(pts
			(xy 334.441292 -236.992414) (xy 334.441292 -236.944662) (xy 334.24114 -236.944662) (xy 334.24114 -236.992414)
			(xy 334.341216 -237.092236)
		)
		(stroke
			(width 0)
			(type solid)
		)
		(fill yes)
		(layer "In13.Cu")
		(net "M_B_CPU0_SA_DQS_DN<2>")
	)
	(gr_poly
		(pts
			(xy 334.441292 -235.776008) (xy 334.341216 -235.675932) (xy 334.24114 -235.776008) (xy 334.24114 -235.820458)
			(xy 334.441292 -235.820458)
		)
		(stroke
			(width 0)
			(type solid)
		)
		(fill yes)
		(layer "In13.Cu")
		(net "M_B_CPU0_SA_DQ<17>")
	)
	(gr_poly
		(pts
			(xy 334.441292 -235.372148) (xy 334.441292 -235.327698) (xy 334.24114 -235.327698) (xy 334.24114 -235.372148)
			(xy 334.341216 -235.472224)
		)
		(stroke
			(width 0)
			(type solid)
		)
		(fill yes)
		(layer "In13.Cu")
		(net "M_B_CPU0_SA_DQ<18>")
	)
	(gr_poly
		(pts
			(xy 334.441292 -234.155996) (xy 334.341216 -234.05592) (xy 334.24114 -234.155996) (xy 334.24114 -234.200446)
			(xy 334.441292 -234.200446)
		)
		(stroke
			(width 0)
			(type solid)
		)
		(fill yes)
		(layer "In13.Cu")
		(net "M_B_CPU0_SA_DQ<13>")
	)
	(gr_poly
		(pts
			(xy 334.441292 -233.752136) (xy 334.441292 -233.707686) (xy 334.24114 -233.707686) (xy 334.24114 -233.752136)
			(xy 334.341216 -233.852212)
		)
		(stroke
			(width 0)
			(type solid)
		)
		(fill yes)
		(layer "In13.Cu")
		(net "M_B_CPU0_SA_DQ<14>")
	)
	(gr_poly
		(pts
			(xy 334.441292 -232.53573) (xy 334.341216 -232.435908) (xy 334.24114 -232.53573) (xy 334.24114 -232.583482)
			(xy 334.441292 -232.583482)
		)
		(stroke
			(width 0)
			(type solid)
		)
		(fill yes)
		(layer "In13.Cu")
		(net "M_B_CPU0_SA_DQS_DN<6>")
	)
	(gr_poly
		(pts
			(xy 334.441292 -232.132378) (xy 334.441292 -232.084626) (xy 334.24114 -232.084626) (xy 334.24114 -232.132378)
			(xy 334.341216 -232.2322)
		)
		(stroke
			(width 0)
			(type solid)
		)
		(fill yes)
		(layer "In13.Cu")
		(net "M_B_CPU0_SA_DQS_DN<1>")
	)
	(gr_poly
		(pts
			(xy 334.441292 -230.915972) (xy 334.341216 -230.815896) (xy 334.24114 -230.915972) (xy 334.24114 -230.960422)
			(xy 334.441292 -230.960422)
		)
		(stroke
			(width 0)
			(type solid)
		)
		(fill yes)
		(layer "In13.Cu")
		(net "M_B_CPU0_SA_DQ<9>")
	)
	(gr_poly
		(pts
			(xy 334.441292 -230.512366) (xy 334.441292 -230.467916) (xy 334.24114 -230.467916) (xy 334.24114 -230.512366)
			(xy 334.341216 -230.612188)
		)
		(stroke
			(width 0)
			(type solid)
		)
		(fill yes)
		(layer "In13.Cu")
		(net "M_B_CPU0_SA_DQ<10>")
	)
	(gr_poly
		(pts
			(xy 334.441292 -229.29596) (xy 334.341216 -229.195884) (xy 334.24114 -229.29596) (xy 334.24114 -229.34041)
			(xy 334.441292 -229.34041)
		)
		(stroke
			(width 0)
			(type solid)
		)
		(fill yes)
		(layer "In13.Cu")
		(net "M_B_CPU0_SA_DQ<5>")
	)
	(gr_poly
		(pts
			(xy 334.441292 -228.892354) (xy 334.441292 -228.847904) (xy 334.24114 -228.847904) (xy 334.24114 -228.892354)
			(xy 334.341216 -228.99243)
		)
		(stroke
			(width 0)
			(type solid)
		)
		(fill yes)
		(layer "In13.Cu")
		(net "M_B_CPU0_SA_DQ<6>")
	)
	(gr_poly
		(pts
			(xy 334.441292 -227.272596) (xy 334.441292 -227.224844) (xy 334.24114 -227.224844) (xy 334.24114 -227.272596)
			(xy 334.341216 -227.372418)
		)
		(stroke
			(width 0)
			(type solid)
		)
		(fill yes)
		(layer "In13.Cu")
		(net "M_B_CPU0_SA_DQS_DN<0>")
	)
	(gr_poly
		(pts
			(xy 334.441292 -226.05619) (xy 334.341216 -225.956114) (xy 334.24114 -226.05619) (xy 334.24114 -226.10064)
			(xy 334.441292 -226.10064)
		)
		(stroke
			(width 0)
			(type solid)
		)
		(fill yes)
		(layer "In13.Cu")
		(net "M_B_CPU0_SA_DQ<1>")
	)
	(gr_poly
		(pts
			(xy 334.441292 -225.65233) (xy 334.441292 -225.60788) (xy 334.24114 -225.60788) (xy 334.24114 -225.65233)
			(xy 334.341216 -225.752406)
		)
		(stroke
			(width 0)
			(type solid)
		)
		(fill yes)
		(layer "In13.Cu")
		(net "M_B_CPU0_SA_DQ<2>")
	)
	(gr_poly
		(pts
			(xy 334.734916 -267.801598) (xy 334.63484 -267.701522) (xy 334.535018 -267.801598) (xy 334.535018 -267.846048)
			(xy 334.734916 -267.846048)
		)
		(stroke
			(width 0)
			(type solid)
		)
		(fill yes)
		(layer "In13.Cu")
		(net "M_B_CPU0_SB_RSP<0>")
	)
	(gr_poly
		(pts
			(xy 334.741266 -293.324026) (xy 334.741266 -293.279576) (xy 334.541114 -293.279576) (xy 334.541114 -293.324026)
			(xy 334.64119 -293.424102)
		)
		(stroke
			(width 0)
			(type solid)
		)
		(fill yes)
		(layer "In13.Cu")
		(net "M_B_CPU0_SB_DQ<31>")
	)
	(gr_poly
		(pts
			(xy 334.741266 -292.107874) (xy 334.64119 -292.007798) (xy 334.541114 -292.107874) (xy 334.541114 -292.152324)
			(xy 334.741266 -292.152324)
		)
		(stroke
			(width 0)
			(type solid)
		)
		(fill yes)
		(layer "In13.Cu")
		(net "M_B_CPU0_SB_DQ<28>")
	)
	(gr_poly
		(pts
			(xy 334.741266 -291.704268) (xy 334.741266 -291.656516) (xy 334.541114 -291.656516) (xy 334.541114 -291.704268)
			(xy 334.64119 -291.80409)
		)
		(stroke
			(width 0)
			(type solid)
		)
		(fill yes)
		(layer "In13.Cu")
		(net "M_B_CPU0_SB_DQS_DP<8>")
	)
	(gr_poly
		(pts
			(xy 334.741266 -290.487608) (xy 334.64119 -290.387786) (xy 334.541114 -290.487608) (xy 334.541114 -290.53536)
			(xy 334.741266 -290.53536)
		)
		(stroke
			(width 0)
			(type solid)
		)
		(fill yes)
		(layer "In13.Cu")
		(net "M_B_CPU0_SB_DQS_DP<3>")
	)
	(gr_poly
		(pts
			(xy 334.741266 -290.084002) (xy 334.741266 -290.039552) (xy 334.541114 -290.039552) (xy 334.541114 -290.084002)
			(xy 334.64119 -290.184078)
		)
		(stroke
			(width 0)
			(type solid)
		)
		(fill yes)
		(layer "In13.Cu")
		(net "M_B_CPU0_SB_DQ<27>")
	)
	(gr_poly
		(pts
			(xy 334.741266 -288.86785) (xy 334.64119 -288.767774) (xy 334.541114 -288.86785) (xy 334.541114 -288.9123)
			(xy 334.741266 -288.9123)
		)
		(stroke
			(width 0)
			(type solid)
		)
		(fill yes)
		(layer "In13.Cu")
		(net "M_B_CPU0_SB_DQ<24>")
	)
	(gr_poly
		(pts
			(xy 334.741266 -288.464244) (xy 334.741266 -288.419794) (xy 334.541114 -288.419794) (xy 334.541114 -288.464244)
			(xy 334.64119 -288.56432)
		)
		(stroke
			(width 0)
			(type solid)
		)
		(fill yes)
		(layer "In13.Cu")
		(net "M_B_CPU0_SB_DQ<23>")
	)
	(gr_poly
		(pts
			(xy 334.741266 -287.247838) (xy 334.64119 -287.148016) (xy 334.541114 -287.247838) (xy 334.541114 -287.292288)
			(xy 334.741266 -287.292288)
		)
		(stroke
			(width 0)
			(type solid)
		)
		(fill yes)
		(layer "In13.Cu")
		(net "M_B_CPU0_SB_DQ<20>")
	)
	(gr_poly
		(pts
			(xy 334.741266 -286.844232) (xy 334.741266 -286.79648) (xy 334.541114 -286.79648) (xy 334.541114 -286.844232)
			(xy 334.64119 -286.944308)
		)
		(stroke
			(width 0)
			(type solid)
		)
		(fill yes)
		(layer "In13.Cu")
		(net "M_B_CPU0_SB_DQS_DP<7>")
	)
	(gr_poly
		(pts
			(xy 334.741266 -285.627826) (xy 334.64119 -285.528004) (xy 334.541114 -285.627826) (xy 334.541114 -285.675578)
			(xy 334.741266 -285.675578)
		)
		(stroke
			(width 0)
			(type solid)
		)
		(fill yes)
		(layer "In13.Cu")
		(net "M_B_CPU0_SB_DQS_DP<2>")
	)
	(gr_poly
		(pts
			(xy 334.741266 -285.22422) (xy 334.741266 -285.17977) (xy 334.541114 -285.17977) (xy 334.541114 -285.22422)
			(xy 334.64119 -285.324296)
		)
		(stroke
			(width 0)
			(type solid)
		)
		(fill yes)
		(layer "In13.Cu")
		(net "M_B_CPU0_SB_DQ<19>")
	)
	(gr_poly
		(pts
			(xy 334.741266 -284.008068) (xy 334.64119 -283.907992) (xy 334.541114 -284.008068) (xy 334.541114 -284.052518)
			(xy 334.741266 -284.052518)
		)
		(stroke
			(width 0)
			(type solid)
		)
		(fill yes)
		(layer "In13.Cu")
		(net "M_B_CPU0_SB_DQ<16>")
	)
	(gr_poly
		(pts
			(xy 334.741266 -283.604208) (xy 334.741266 -283.559758) (xy 334.541114 -283.559758) (xy 334.541114 -283.604208)
			(xy 334.64119 -283.704284)
		)
		(stroke
			(width 0)
			(type solid)
		)
		(fill yes)
		(layer "In13.Cu")
		(net "M_B_CPU0_SB_DQ<15>")
	)
	(gr_poly
		(pts
			(xy 334.741266 -282.388056) (xy 334.64119 -282.28798) (xy 334.541114 -282.388056) (xy 334.541114 -282.432506)
			(xy 334.741266 -282.432506)
		)
		(stroke
			(width 0)
			(type solid)
		)
		(fill yes)
		(layer "In13.Cu")
		(net "M_B_CPU0_SB_DQ<12>")
	)
	(gr_poly
		(pts
			(xy 334.741266 -281.98445) (xy 334.741266 -281.936698) (xy 334.541114 -281.936698) (xy 334.541114 -281.98445)
			(xy 334.64119 -282.084272)
		)
		(stroke
			(width 0)
			(type solid)
		)
		(fill yes)
		(layer "In13.Cu")
		(net "M_B_CPU0_SB_DQS_DP<6>")
	)
	(gr_poly
		(pts
			(xy 334.741266 -280.76779) (xy 334.64119 -280.667968) (xy 334.541114 -280.76779) (xy 334.541114 -280.815542)
			(xy 334.741266 -280.815542)
		)
		(stroke
			(width 0)
			(type solid)
		)
		(fill yes)
		(layer "In13.Cu")
		(net "M_B_CPU0_SB_DQS_DP<1>")
	)
	(gr_poly
		(pts
			(xy 334.741266 -280.364184) (xy 334.741266 -280.319734) (xy 334.541114 -280.319734) (xy 334.541114 -280.364184)
			(xy 334.64119 -280.46426)
		)
		(stroke
			(width 0)
			(type solid)
		)
		(fill yes)
		(layer "In13.Cu")
		(net "M_B_CPU0_SB_DQ<11>")
	)
	(gr_poly
		(pts
			(xy 334.741266 -279.148032) (xy 334.64119 -279.047956) (xy 334.541114 -279.148032) (xy 334.541114 -279.192482)
			(xy 334.741266 -279.192482)
		)
		(stroke
			(width 0)
			(type solid)
		)
		(fill yes)
		(layer "In13.Cu")
		(net "M_B_CPU0_SB_DQ<8>")
	)
	(gr_poly
		(pts
			(xy 334.741266 -278.744172) (xy 334.741266 -278.699722) (xy 334.541114 -278.699722) (xy 334.541114 -278.744172)
			(xy 334.64119 -278.844248)
		)
		(stroke
			(width 0)
			(type solid)
		)
		(fill yes)
		(layer "In13.Cu")
		(net "M_B_CPU0_SB_DQ<7>")
	)
	(gr_poly
		(pts
			(xy 334.741266 -277.52802) (xy 334.64119 -277.427944) (xy 334.541114 -277.52802) (xy 334.541114 -277.57247)
			(xy 334.741266 -277.57247)
		)
		(stroke
			(width 0)
			(type solid)
		)
		(fill yes)
		(layer "In13.Cu")
		(net "M_B_CPU0_SB_DQ<4>")
	)
	(gr_poly
		(pts
			(xy 334.741266 -277.12416) (xy 334.741266 -277.076662) (xy 334.541114 -277.076662) (xy 334.541114 -277.12416)
			(xy 334.64119 -277.224236)
		)
		(stroke
			(width 0)
			(type solid)
		)
		(fill yes)
		(layer "In13.Cu")
		(net "M_B_CPU0_SB_DQS_DP<5>")
	)
	(gr_poly
		(pts
			(xy 334.741266 -275.908008) (xy 334.64119 -275.807932) (xy 334.541114 -275.908008) (xy 334.541114 -275.955506)
			(xy 334.741266 -275.955506)
		)
		(stroke
			(width 0)
			(type solid)
		)
		(fill yes)
		(layer "In13.Cu")
		(net "M_B_CPU0_SB_DQS_DP<0>")
	)
	(gr_poly
		(pts
			(xy 334.741266 -275.504148) (xy 334.741266 -275.459698) (xy 334.541114 -275.459698) (xy 334.541114 -275.504148)
			(xy 334.64119 -275.604224)
		)
		(stroke
			(width 0)
			(type solid)
		)
		(fill yes)
		(layer "In13.Cu")
		(net "M_B_CPU0_SB_DQ<3>")
	)
	(gr_poly
		(pts
			(xy 334.741266 -274.287996) (xy 334.64119 -274.18792) (xy 334.541114 -274.287996) (xy 334.541114 -274.332446)
			(xy 334.741266 -274.332446)
		)
		(stroke
			(width 0)
			(type solid)
		)
		(fill yes)
		(layer "In13.Cu")
		(net "M_B_CPU0_SB_DQ<0>")
	)
	(gr_poly
		(pts
			(xy 334.741266 -273.884136) (xy 334.741266 -273.839686) (xy 334.541114 -273.839686) (xy 334.541114 -273.884136)
			(xy 334.64119 -273.984212)
		)
		(stroke
			(width 0)
			(type solid)
		)
		(fill yes)
		(layer "In13.Cu")
		(net "M_B_CPU0_SB_CB<3>")
	)
	(gr_poly
		(pts
			(xy 334.741266 -272.667984) (xy 334.64119 -272.567908) (xy 334.541114 -272.667984) (xy 334.541114 -272.712434)
			(xy 334.741266 -272.712434)
		)
		(stroke
			(width 0)
			(type solid)
		)
		(fill yes)
		(layer "In13.Cu")
		(net "M_B_CPU0_SB_CB<0>")
	)
	(gr_poly
		(pts
			(xy 334.741266 -272.264378) (xy 334.741266 -272.216626) (xy 334.541114 -272.216626) (xy 334.541114 -272.264378)
			(xy 334.64119 -272.3642)
		)
		(stroke
			(width 0)
			(type solid)
		)
		(fill yes)
		(layer "In13.Cu")
		(net "M_B_CPU0_SB_DQS_DP<4>")
	)
	(gr_poly
		(pts
			(xy 334.741266 -271.047718) (xy 334.64119 -270.947896) (xy 334.541114 -271.047718) (xy 334.541114 -271.09547)
			(xy 334.741266 -271.09547)
		)
		(stroke
			(width 0)
			(type solid)
		)
		(fill yes)
		(layer "In13.Cu")
		(net "M_B_CPU0_SB_DQS_DP<9>")
	)
	(gr_poly
		(pts
			(xy 334.741266 -270.644112) (xy 334.741266 -270.599662) (xy 334.541114 -270.599662) (xy 334.541114 -270.644112)
			(xy 334.64119 -270.744188)
		)
		(stroke
			(width 0)
			(type solid)
		)
		(fill yes)
		(layer "In13.Cu")
		(net "M_B_CPU0_SB_CB<7>")
	)
	(gr_poly
		(pts
			(xy 334.741266 -269.42796) (xy 334.64119 -269.327884) (xy 334.541114 -269.42796) (xy 334.541114 -269.47241)
			(xy 334.741266 -269.47241)
		)
		(stroke
			(width 0)
			(type solid)
		)
		(fill yes)
		(layer "In13.Cu")
		(net "M_B_CPU0_SB_CB<4>")
	)
	(gr_poly
		(pts
			(xy 334.741266 -265.784076) (xy 334.741266 -265.739626) (xy 334.541114 -265.739626) (xy 334.541114 -265.784076)
			(xy 334.64119 -265.884152)
		)
		(stroke
			(width 0)
			(type solid)
		)
		(fill yes)
		(layer "In13.Cu")
		(net "M_B_CPU0_SB_CS_N<0>")
	)
	(gr_poly
		(pts
			(xy 334.741266 -264.567924) (xy 334.64119 -264.467848) (xy 334.541114 -264.567924) (xy 334.541114 -264.612374)
			(xy 334.741266 -264.612374)
		)
		(stroke
			(width 0)
			(type solid)
		)
		(fill yes)
		(layer "In13.Cu")
		(net "M_B_CPU0_SB_CA<6>")
	)
	(gr_poly
		(pts
			(xy 334.741266 -264.164064) (xy 334.741266 -264.119614) (xy 334.541114 -264.119614) (xy 334.541114 -264.164064)
			(xy 334.64119 -264.26414)
		)
		(stroke
			(width 0)
			(type solid)
		)
		(fill yes)
		(layer "In13.Cu")
		(net "M_B_CPU0_SB_CA<5>")
	)
	(gr_poly
		(pts
			(xy 334.741266 -262.947912) (xy 334.64119 -262.847836) (xy 334.541114 -262.947912) (xy 334.541114 -262.992362)
			(xy 334.741266 -262.992362)
		)
		(stroke
			(width 0)
			(type solid)
		)
		(fill yes)
		(layer "In13.Cu")
		(net "M_B_CPU0_SB_CA<2>")
	)
	(gr_poly
		(pts
			(xy 334.741266 -262.544052) (xy 334.741266 -262.499602) (xy 334.541114 -262.499602) (xy 334.541114 -262.544052)
			(xy 334.64119 -262.644128)
		)
		(stroke
			(width 0)
			(type solid)
		)
		(fill yes)
		(layer "In13.Cu")
		(net "M_B_CPU0_SB_CA<1>")
	)
	(gr_poly
		(pts
			(xy 334.911192 -256.025904) (xy 334.811116 -255.926082) (xy 334.71104 -256.025904) (xy 334.71104 -256.073656)
			(xy 334.911192 -256.073656)
		)
		(stroke
			(width 0)
			(type solid)
		)
		(fill yes)
		(layer "In13.Cu")
		(net "M_B_CPU0_CLK_DP<0>")
	)
	(gr_poly
		(pts
			(xy 334.911192 -255.622298) (xy 334.911192 -255.577848) (xy 334.71104 -255.577848) (xy 334.71104 -255.622298)
			(xy 334.811116 -255.722374)
		)
		(stroke
			(width 0)
			(type solid)
		)
		(fill yes)
		(layer "In13.Cu")
		(net "M_B_CPU0_SA_PAR")
	)
	(gr_poly
		(pts
			(xy 334.911192 -254.406146) (xy 334.811116 -254.30607) (xy 334.71104 -254.406146) (xy 334.71104 -254.450596)
			(xy 334.911192 -254.450596)
		)
		(stroke
			(width 0)
			(type solid)
		)
		(fill yes)
		(layer "In13.Cu")
		(net "M_B_CPU0_SA_CA<4>")
	)
	(gr_poly
		(pts
			(xy 334.911192 -254.002286) (xy 334.911192 -253.957836) (xy 334.71104 -253.957836) (xy 334.71104 -254.002286)
			(xy 334.811116 -254.102362)
		)
		(stroke
			(width 0)
			(type solid)
		)
		(fill yes)
		(layer "In13.Cu")
		(net "M_B_CPU0_SA_CA<3>")
	)
	(gr_poly
		(pts
			(xy 334.911192 -252.786134) (xy 334.811116 -252.686058) (xy 334.71104 -252.786134) (xy 334.71104 -252.830584)
			(xy 334.911192 -252.830584)
		)
		(stroke
			(width 0)
			(type solid)
		)
		(fill yes)
		(layer "In13.Cu")
		(net "M_B_CPU0_SA_CA<0>")
	)
	(gr_poly
		(pts
			(xy 334.911192 -252.382274) (xy 334.911192 -252.337824) (xy 334.71104 -252.337824) (xy 334.71104 -252.382274)
			(xy 334.811116 -252.48235)
		)
		(stroke
			(width 0)
			(type solid)
		)
		(fill yes)
		(layer "In13.Cu")
		(net "M_B_CPU0_SA_CS_N<1>")
	)
	(gr_poly
		(pts
			(xy 334.911192 -250.762262) (xy 334.911192 -250.717812) (xy 334.71104 -250.717812) (xy 334.71104 -250.762262)
			(xy 334.811116 -250.862338)
		)
		(stroke
			(width 0)
			(type solid)
		)
		(fill yes)
		(layer "In13.Cu")
		(net "M_B_CPU0_RESET_N")
	)
	(gr_poly
		(pts
			(xy 334.911192 -249.14225) (xy 334.911192 -249.0978) (xy 334.71104 -249.0978) (xy 334.71104 -249.14225)
			(xy 334.811116 -249.242326)
		)
		(stroke
			(width 0)
			(type solid)
		)
		(fill yes)
		(layer "In13.Cu")
		(net "M_B_CPU0_SA_CB<7>")
	)
	(gr_poly
		(pts
			(xy 334.911192 -247.926098) (xy 334.811116 -247.826022) (xy 334.71104 -247.926098) (xy 334.71104 -247.970548)
			(xy 334.911192 -247.970548)
		)
		(stroke
			(width 0)
			(type solid)
		)
		(fill yes)
		(layer "In13.Cu")
		(net "M_B_CPU0_SA_CB<4>")
	)
	(gr_poly
		(pts
			(xy 334.911192 -247.522492) (xy 334.911192 -247.47474) (xy 334.71104 -247.47474) (xy 334.71104 -247.522492)
			(xy 334.811116 -247.622314)
		)
		(stroke
			(width 0)
			(type solid)
		)
		(fill yes)
		(layer "In13.Cu")
		(net "M_B_CPU0_SA_DQS_DP<9>")
	)
	(gr_poly
		(pts
			(xy 334.911192 -246.305832) (xy 334.811116 -246.20601) (xy 334.71104 -246.305832) (xy 334.71104 -246.353584)
			(xy 334.911192 -246.353584)
		)
		(stroke
			(width 0)
			(type solid)
		)
		(fill yes)
		(layer "In13.Cu")
		(net "M_B_CPU0_SA_DQS_DP<4>")
	)
	(gr_poly
		(pts
			(xy 334.911192 -245.902226) (xy 334.911192 -245.857776) (xy 334.71104 -245.857776) (xy 334.71104 -245.902226)
			(xy 334.811116 -246.002302)
		)
		(stroke
			(width 0)
			(type solid)
		)
		(fill yes)
		(layer "In13.Cu")
		(net "M_B_CPU0_SA_CB<3>")
	)
	(gr_poly
		(pts
			(xy 334.911192 -244.686074) (xy 334.811116 -244.585998) (xy 334.71104 -244.686074) (xy 334.71104 -244.730524)
			(xy 334.911192 -244.730524)
		)
		(stroke
			(width 0)
			(type solid)
		)
		(fill yes)
		(layer "In13.Cu")
		(net "M_B_CPU0_SA_CB<0>")
	)
	(gr_poly
		(pts
			(xy 334.911192 -244.282214) (xy 334.911192 -244.237764) (xy 334.71104 -244.237764) (xy 334.71104 -244.282214)
			(xy 334.811116 -244.38229)
		)
		(stroke
			(width 0)
			(type solid)
		)
		(fill yes)
		(layer "In13.Cu")
		(net "M_B_CPU0_SA_DQ<31>")
	)
	(gr_poly
		(pts
			(xy 334.911192 -243.066062) (xy 334.811116 -242.965986) (xy 334.71104 -243.066062) (xy 334.71104 -243.110512)
			(xy 334.911192 -243.110512)
		)
		(stroke
			(width 0)
			(type solid)
		)
		(fill yes)
		(layer "In13.Cu")
		(net "M_B_CPU0_SA_DQ<28>")
	)
	(gr_poly
		(pts
			(xy 334.911192 -242.662456) (xy 334.911192 -242.614704) (xy 334.71104 -242.614704) (xy 334.71104 -242.662456)
			(xy 334.811116 -242.762278)
		)
		(stroke
			(width 0)
			(type solid)
		)
		(fill yes)
		(layer "In13.Cu")
		(net "M_B_CPU0_SA_DQS_DP<8>")
	)
	(gr_poly
		(pts
			(xy 334.911192 -241.445796) (xy 334.811116 -241.345974) (xy 334.71104 -241.445796) (xy 334.71104 -241.493548)
			(xy 334.911192 -241.493548)
		)
		(stroke
			(width 0)
			(type solid)
		)
		(fill yes)
		(layer "In13.Cu")
		(net "M_B_CPU0_SA_DQS_DP<3>")
	)
	(gr_poly
		(pts
			(xy 334.911192 -241.04219) (xy 334.911192 -240.99774) (xy 334.71104 -240.99774) (xy 334.71104 -241.04219)
			(xy 334.811116 -241.142266)
		)
		(stroke
			(width 0)
			(type solid)
		)
		(fill yes)
		(layer "In13.Cu")
		(net "M_B_CPU0_SA_DQ<27>")
	)
	(gr_poly
		(pts
			(xy 334.911192 -239.826038) (xy 334.811116 -239.725962) (xy 334.71104 -239.826038) (xy 334.71104 -239.870488)
			(xy 334.911192 -239.870488)
		)
		(stroke
			(width 0)
			(type solid)
		)
		(fill yes)
		(layer "In13.Cu")
		(net "M_B_CPU0_SA_DQ<24>")
	)
	(gr_poly
		(pts
			(xy 334.911192 -239.422178) (xy 334.911192 -239.377728) (xy 334.71104 -239.377728) (xy 334.71104 -239.422178)
			(xy 334.811116 -239.522254)
		)
		(stroke
			(width 0)
			(type solid)
		)
		(fill yes)
		(layer "In13.Cu")
		(net "M_B_CPU0_SA_DQ<23>")
	)
	(gr_poly
		(pts
			(xy 334.911192 -238.206026) (xy 334.811116 -238.10595) (xy 334.71104 -238.206026) (xy 334.71104 -238.250476)
			(xy 334.911192 -238.250476)
		)
		(stroke
			(width 0)
			(type solid)
		)
		(fill yes)
		(layer "In13.Cu")
		(net "M_B_CPU0_SA_DQ<20>")
	)
	(gr_poly
		(pts
			(xy 334.911192 -237.80242) (xy 334.911192 -237.754668) (xy 334.71104 -237.754668) (xy 334.71104 -237.80242)
			(xy 334.811116 -237.902242)
		)
		(stroke
			(width 0)
			(type solid)
		)
		(fill yes)
		(layer "In13.Cu")
		(net "M_B_CPU0_SA_DQS_DP<7>")
	)
	(gr_poly
		(pts
			(xy 334.911192 -236.58576) (xy 334.811116 -236.485938) (xy 334.71104 -236.58576) (xy 334.71104 -236.633512)
			(xy 334.911192 -236.633512)
		)
		(stroke
			(width 0)
			(type solid)
		)
		(fill yes)
		(layer "In13.Cu")
		(net "M_B_CPU0_SA_DQS_DP<2>")
	)
	(gr_poly
		(pts
			(xy 334.911192 -236.182154) (xy 334.911192 -236.137704) (xy 334.71104 -236.137704) (xy 334.71104 -236.182154)
			(xy 334.811116 -236.28223)
		)
		(stroke
			(width 0)
			(type solid)
		)
		(fill yes)
		(layer "In13.Cu")
		(net "M_B_CPU0_SA_DQ<19>")
	)
	(gr_poly
		(pts
			(xy 334.911192 -234.966002) (xy 334.811116 -234.865926) (xy 334.71104 -234.966002) (xy 334.71104 -235.010452)
			(xy 334.911192 -235.010452)
		)
		(stroke
			(width 0)
			(type solid)
		)
		(fill yes)
		(layer "In13.Cu")
		(net "M_B_CPU0_SA_DQ<16>")
	)
	(gr_poly
		(pts
			(xy 334.911192 -234.562142) (xy 334.911192 -234.517692) (xy 334.71104 -234.517692) (xy 334.71104 -234.562142)
			(xy 334.811116 -234.662218)
		)
		(stroke
			(width 0)
			(type solid)
		)
		(fill yes)
		(layer "In13.Cu")
		(net "M_B_CPU0_SA_DQ<15>")
	)
	(gr_poly
		(pts
			(xy 334.911192 -233.34599) (xy 334.811116 -233.245914) (xy 334.71104 -233.34599) (xy 334.71104 -233.39044)
			(xy 334.911192 -233.39044)
		)
		(stroke
			(width 0)
			(type solid)
		)
		(fill yes)
		(layer "In13.Cu")
		(net "M_B_CPU0_SA_DQ<12>")
	)
	(gr_poly
		(pts
			(xy 334.911192 -232.942384) (xy 334.911192 -232.894632) (xy 334.71104 -232.894632) (xy 334.71104 -232.942384)
			(xy 334.811116 -233.042206)
		)
		(stroke
			(width 0)
			(type solid)
		)
		(fill yes)
		(layer "In13.Cu")
		(net "M_B_CPU0_SA_DQS_DP<6>")
	)
	(gr_poly
		(pts
			(xy 334.911192 -231.725724) (xy 334.811116 -231.625902) (xy 334.71104 -231.725724) (xy 334.71104 -231.773476)
			(xy 334.911192 -231.773476)
		)
		(stroke
			(width 0)
			(type solid)
		)
		(fill yes)
		(layer "In13.Cu")
		(net "M_B_CPU0_SA_DQS_DP<1>")
	)
	(gr_poly
		(pts
			(xy 334.911192 -231.322372) (xy 334.911192 -231.277922) (xy 334.71104 -231.277922) (xy 334.71104 -231.322372)
			(xy 334.811116 -231.422448)
		)
		(stroke
			(width 0)
			(type solid)
		)
		(fill yes)
		(layer "In13.Cu")
		(net "M_B_CPU0_SA_DQ<11>")
	)
	(gr_poly
		(pts
			(xy 334.911192 -230.105966) (xy 334.811116 -230.006144) (xy 334.71104 -230.105966) (xy 334.71104 -230.150416)
			(xy 334.911192 -230.150416)
		)
		(stroke
			(width 0)
			(type solid)
		)
		(fill yes)
		(layer "In13.Cu")
		(net "M_B_CPU0_SA_DQ<8>")
	)
	(gr_poly
		(pts
			(xy 334.911192 -229.70236) (xy 334.911192 -229.65791) (xy 334.71104 -229.65791) (xy 334.71104 -229.70236)
			(xy 334.811116 -229.802436)
		)
		(stroke
			(width 0)
			(type solid)
		)
		(fill yes)
		(layer "In13.Cu")
		(net "M_B_CPU0_SA_DQ<7>")
	)
	(gr_poly
		(pts
			(xy 334.911192 -228.486208) (xy 334.811116 -228.386132) (xy 334.71104 -228.486208) (xy 334.71104 -228.530658)
			(xy 334.911192 -228.530658)
		)
		(stroke
			(width 0)
			(type solid)
		)
		(fill yes)
		(layer "In13.Cu")
		(net "M_B_CPU0_SA_DQ<4>")
	)
	(gr_poly
		(pts
			(xy 334.911192 -228.082602) (xy 334.911192 -228.03485) (xy 334.71104 -228.03485) (xy 334.71104 -228.082602)
			(xy 334.811116 -228.182424)
		)
		(stroke
			(width 0)
			(type solid)
		)
		(fill yes)
		(layer "In13.Cu")
		(net "M_B_CPU0_SA_DQS_DP<5>")
	)
	(gr_poly
		(pts
			(xy 334.911192 -226.865942) (xy 334.811116 -226.76612) (xy 334.71104 -226.865942) (xy 334.71104 -226.913694)
			(xy 334.911192 -226.913694)
		)
		(stroke
			(width 0)
			(type solid)
		)
		(fill yes)
		(layer "In13.Cu")
		(net "M_B_CPU0_SA_DQS_DP<0>")
	)
	(gr_poly
		(pts
			(xy 334.911192 -226.462336) (xy 334.911192 -226.417886) (xy 334.71104 -226.417886) (xy 334.71104 -226.462336)
			(xy 334.811116 -226.562412)
		)
		(stroke
			(width 0)
			(type solid)
		)
		(fill yes)
		(layer "In13.Cu")
		(net "M_B_CPU0_SA_DQ<3>")
	)
	(gr_poly
		(pts
			(xy 334.911192 -225.246184) (xy 334.811116 -225.146108) (xy 334.71104 -225.246184) (xy 334.71104 -225.290634)
			(xy 334.911192 -225.290634)
		)
		(stroke
			(width 0)
			(type solid)
		)
		(fill yes)
		(layer "In13.Cu")
		(net "M_B_CPU0_SA_DQ<0>")
	)
	(gr_poly
		(pts
			(xy 335.211166 -292.91788) (xy 335.11109 -292.817804) (xy 335.011014 -292.91788) (xy 335.011014 -292.96233)
			(xy 335.211166 -292.96233)
		)
		(stroke
			(width 0)
			(type solid)
		)
		(fill yes)
		(layer "In13.Cu")
		(net "M_B_CPU0_SB_DQ<29>")
	)
	(gr_poly
		(pts
			(xy 335.211166 -292.51402) (xy 335.211166 -292.46957) (xy 335.011014 -292.46957) (xy 335.011014 -292.51402)
			(xy 335.11109 -292.614096)
		)
		(stroke
			(width 0)
			(type solid)
		)
		(fill yes)
		(layer "In13.Cu")
		(net "M_B_CPU0_SB_DQ<30>")
	)
	(gr_poly
		(pts
			(xy 335.211166 -291.297614) (xy 335.11109 -291.197792) (xy 335.011014 -291.297614) (xy 335.011014 -291.345366)
			(xy 335.211166 -291.345366)
		)
		(stroke
			(width 0)
			(type solid)
		)
		(fill yes)
		(layer "In13.Cu")
		(net "M_B_CPU0_SB_DQS_DN<8>")
	)
	(gr_poly
		(pts
			(xy 335.211166 -290.894262) (xy 335.211166 -290.84651) (xy 335.011014 -290.84651) (xy 335.011014 -290.894262)
			(xy 335.11109 -290.994084)
		)
		(stroke
			(width 0)
			(type solid)
		)
		(fill yes)
		(layer "In13.Cu")
		(net "M_B_CPU0_SB_DQS_DN<3>")
	)
	(gr_poly
		(pts
			(xy 335.211166 -289.677856) (xy 335.11109 -289.57778) (xy 335.011014 -289.677856) (xy 335.011014 -289.722306)
			(xy 335.211166 -289.722306)
		)
		(stroke
			(width 0)
			(type solid)
		)
		(fill yes)
		(layer "In13.Cu")
		(net "M_B_CPU0_SB_DQ<25>")
	)
	(gr_poly
		(pts
			(xy 335.211166 -289.273996) (xy 335.211166 -289.229546) (xy 335.011014 -289.229546) (xy 335.011014 -289.273996)
			(xy 335.11109 -289.374072)
		)
		(stroke
			(width 0)
			(type solid)
		)
		(fill yes)
		(layer "In13.Cu")
		(net "M_B_CPU0_SB_DQ<26>")
	)
	(gr_poly
		(pts
			(xy 335.211166 -288.057844) (xy 335.11109 -287.957768) (xy 335.011014 -288.057844) (xy 335.011014 -288.102294)
			(xy 335.211166 -288.102294)
		)
		(stroke
			(width 0)
			(type solid)
		)
		(fill yes)
		(layer "In13.Cu")
		(net "M_B_CPU0_SB_DQ<21>")
	)
	(gr_poly
		(pts
			(xy 335.211166 -287.654238) (xy 335.211166 -287.609788) (xy 335.011014 -287.609788) (xy 335.011014 -287.654238)
			(xy 335.11109 -287.75406)
		)
		(stroke
			(width 0)
			(type solid)
		)
		(fill yes)
		(layer "In13.Cu")
		(net "M_B_CPU0_SB_DQ<22>")
	)
	(gr_poly
		(pts
			(xy 335.211166 -286.437832) (xy 335.11109 -286.337756) (xy 335.011014 -286.437832) (xy 335.011014 -286.485584)
			(xy 335.211166 -286.485584)
		)
		(stroke
			(width 0)
			(type solid)
		)
		(fill yes)
		(layer "In13.Cu")
		(net "M_B_CPU0_SB_DQS_DN<7>")
	)
	(gr_poly
		(pts
			(xy 335.211166 -286.03448) (xy 335.211166 -285.986728) (xy 335.011014 -285.986728) (xy 335.011014 -286.03448)
			(xy 335.11109 -286.134302)
		)
		(stroke
			(width 0)
			(type solid)
		)
		(fill yes)
		(layer "In13.Cu")
		(net "M_B_CPU0_SB_DQS_DN<2>")
	)
	(gr_poly
		(pts
			(xy 335.211166 -284.818074) (xy 335.11109 -284.717998) (xy 335.011014 -284.818074) (xy 335.011014 -284.862524)
			(xy 335.211166 -284.862524)
		)
		(stroke
			(width 0)
			(type solid)
		)
		(fill yes)
		(layer "In13.Cu")
		(net "M_B_CPU0_SB_DQ<17>")
	)
	(gr_poly
		(pts
			(xy 335.211166 -284.414214) (xy 335.211166 -284.369764) (xy 335.011014 -284.369764) (xy 335.011014 -284.414214)
			(xy 335.11109 -284.51429)
		)
		(stroke
			(width 0)
			(type solid)
		)
		(fill yes)
		(layer "In13.Cu")
		(net "M_B_CPU0_SB_DQ<18>")
	)
	(gr_poly
		(pts
			(xy 335.211166 -283.198062) (xy 335.11109 -283.097986) (xy 335.011014 -283.198062) (xy 335.011014 -283.242512)
			(xy 335.211166 -283.242512)
		)
		(stroke
			(width 0)
			(type solid)
		)
		(fill yes)
		(layer "In13.Cu")
		(net "M_B_CPU0_SB_DQ<13>")
	)
	(gr_poly
		(pts
			(xy 335.211166 -282.794202) (xy 335.211166 -282.749752) (xy 335.011014 -282.749752) (xy 335.011014 -282.794202)
			(xy 335.11109 -282.894278)
		)
		(stroke
			(width 0)
			(type solid)
		)
		(fill yes)
		(layer "In13.Cu")
		(net "M_B_CPU0_SB_DQ<14>")
	)
	(gr_poly
		(pts
			(xy 335.211166 -281.577796) (xy 335.11109 -281.477974) (xy 335.011014 -281.577796) (xy 335.011014 -281.625548)
			(xy 335.211166 -281.625548)
		)
		(stroke
			(width 0)
			(type solid)
		)
		(fill yes)
		(layer "In13.Cu")
		(net "M_B_CPU0_SB_DQS_DN<6>")
	)
	(gr_poly
		(pts
			(xy 335.211166 -281.174444) (xy 335.211166 -281.126692) (xy 335.011014 -281.126692) (xy 335.011014 -281.174444)
			(xy 335.11109 -281.274266)
		)
		(stroke
			(width 0)
			(type solid)
		)
		(fill yes)
		(layer "In13.Cu")
		(net "M_B_CPU0_SB_DQS_DN<1>")
	)
	(gr_poly
		(pts
			(xy 335.211166 -279.958038) (xy 335.11109 -279.857962) (xy 335.011014 -279.958038) (xy 335.011014 -280.002488)
			(xy 335.211166 -280.002488)
		)
		(stroke
			(width 0)
			(type solid)
		)
		(fill yes)
		(layer "In13.Cu")
		(net "M_B_CPU0_SB_DQ<9>")
	)
	(gr_poly
		(pts
			(xy 335.211166 -279.554178) (xy 335.211166 -279.509728) (xy 335.011014 -279.509728) (xy 335.011014 -279.554178)
			(xy 335.11109 -279.654254)
		)
		(stroke
			(width 0)
			(type solid)
		)
		(fill yes)
		(layer "In13.Cu")
		(net "M_B_CPU0_SB_DQ<10>")
	)
	(gr_poly
		(pts
			(xy 335.211166 -278.338026) (xy 335.11109 -278.23795) (xy 335.011014 -278.338026) (xy 335.011014 -278.382476)
			(xy 335.211166 -278.382476)
		)
		(stroke
			(width 0)
			(type solid)
		)
		(fill yes)
		(layer "In13.Cu")
		(net "M_B_CPU0_SB_DQ<5>")
	)
	(gr_poly
		(pts
			(xy 335.211166 -277.934166) (xy 335.211166 -277.889716) (xy 335.011014 -277.889716) (xy 335.011014 -277.934166)
			(xy 335.11109 -278.034242)
		)
		(stroke
			(width 0)
			(type solid)
		)
		(fill yes)
		(layer "In13.Cu")
		(net "M_B_CPU0_SB_DQ<6>")
	)
	(gr_poly
		(pts
			(xy 335.211166 -276.71776) (xy 335.11109 -276.617938) (xy 335.011014 -276.71776) (xy 335.011014 -276.765512)
			(xy 335.211166 -276.765512)
		)
		(stroke
			(width 0)
			(type solid)
		)
		(fill yes)
		(layer "In13.Cu")
		(net "M_B_CPU0_SB_DQS_DN<5>")
	)
	(gr_poly
		(pts
			(xy 335.211166 -276.314408) (xy 335.211166 -276.266656) (xy 335.011014 -276.266656) (xy 335.011014 -276.314408)
			(xy 335.11109 -276.41423)
		)
		(stroke
			(width 0)
			(type solid)
		)
		(fill yes)
		(layer "In13.Cu")
		(net "M_B_CPU0_SB_DQS_DN<0>")
	)
	(gr_poly
		(pts
			(xy 335.211166 -275.098002) (xy 335.11109 -274.997926) (xy 335.011014 -275.098002) (xy 335.011014 -275.142452)
			(xy 335.211166 -275.142452)
		)
		(stroke
			(width 0)
			(type solid)
		)
		(fill yes)
		(layer "In13.Cu")
		(net "M_B_CPU0_SB_DQ<1>")
	)
	(gr_poly
		(pts
			(xy 335.211166 -274.694142) (xy 335.211166 -274.649692) (xy 335.011014 -274.649692) (xy 335.011014 -274.694142)
			(xy 335.11109 -274.794218)
		)
		(stroke
			(width 0)
			(type solid)
		)
		(fill yes)
		(layer "In13.Cu")
		(net "M_B_CPU0_SB_DQ<2>")
	)
	(gr_poly
		(pts
			(xy 335.211166 -273.47799) (xy 335.11109 -273.377914) (xy 335.011014 -273.47799) (xy 335.011014 -273.52244)
			(xy 335.211166 -273.52244)
		)
		(stroke
			(width 0)
			(type solid)
		)
		(fill yes)
		(layer "In13.Cu")
		(net "M_B_CPU0_SB_CB<1>")
	)
	(gr_poly
		(pts
			(xy 335.211166 -273.07413) (xy 335.211166 -273.02968) (xy 335.011014 -273.02968) (xy 335.011014 -273.07413)
			(xy 335.11109 -273.174206)
		)
		(stroke
			(width 0)
			(type solid)
		)
		(fill yes)
		(layer "In13.Cu")
		(net "M_B_CPU0_SB_CB<2>")
	)
	(gr_poly
		(pts
			(xy 335.211166 -271.857724) (xy 335.11109 -271.757902) (xy 335.011014 -271.857724) (xy 335.011014 -271.905476)
			(xy 335.211166 -271.905476)
		)
		(stroke
			(width 0)
			(type solid)
		)
		(fill yes)
		(layer "In13.Cu")
		(net "M_B_CPU0_SB_DQS_DN<4>")
	)
	(gr_poly
		(pts
			(xy 335.211166 -271.454372) (xy 335.211166 -271.40662) (xy 335.011014 -271.40662) (xy 335.011014 -271.454372)
			(xy 335.11109 -271.554194)
		)
		(stroke
			(width 0)
			(type solid)
		)
		(fill yes)
		(layer "In13.Cu")
		(net "M_B_CPU0_SB_DQS_DN<9>")
	)
	(gr_poly
		(pts
			(xy 335.211166 -270.237966) (xy 335.11109 -270.13789) (xy 335.011014 -270.237966) (xy 335.011014 -270.282416)
			(xy 335.211166 -270.282416)
		)
		(stroke
			(width 0)
			(type solid)
		)
		(fill yes)
		(layer "In13.Cu")
		(net "M_B_CPU0_SB_CB<5>")
	)
	(gr_poly
		(pts
			(xy 335.211166 -269.834106) (xy 335.211166 -269.789656) (xy 335.011014 -269.789656) (xy 335.011014 -269.834106)
			(xy 335.11109 -269.934182)
		)
		(stroke
			(width 0)
			(type solid)
		)
		(fill yes)
		(layer "In13.Cu")
		(net "M_B_CPU0_SB_CB<6>")
	)
	(gr_poly
		(pts
			(xy 335.211166 -266.991592) (xy 335.11109 -266.891516) (xy 335.011014 -266.991592) (xy 335.011014 -267.036042)
			(xy 335.211166 -267.036042)
		)
		(stroke
			(width 0)
			(type solid)
		)
		(fill yes)
		(layer "In13.Cu")
		(net "M_B_CPU0_SA_RSP<0>")
	)
	(gr_poly
		(pts
			(xy 335.211166 -266.594082) (xy 335.211166 -266.549632) (xy 335.011014 -266.549632) (xy 335.011014 -266.594082)
			(xy 335.11109 -266.694158)
		)
		(stroke
			(width 0)
			(type solid)
		)
		(fill yes)
		(layer "In13.Cu")
		(net "M_B_CPU0_SB_CS_N<1>")
	)
	(gr_poly
		(pts
			(xy 335.211166 -264.97407) (xy 335.211166 -264.92962) (xy 335.011014 -264.92962) (xy 335.011014 -264.97407)
			(xy 335.11109 -265.074146)
		)
		(stroke
			(width 0)
			(type solid)
		)
		(fill yes)
		(layer "In13.Cu")
		(net "M_B_CPU0_SB_PAR")
	)
	(gr_poly
		(pts
			(xy 335.211166 -263.757918) (xy 335.11109 -263.657842) (xy 335.011014 -263.757918) (xy 335.011014 -263.802368)
			(xy 335.211166 -263.802368)
		)
		(stroke
			(width 0)
			(type solid)
		)
		(fill yes)
		(layer "In13.Cu")
		(net "M_B_CPU0_SB_CA<4>")
	)
	(gr_poly
		(pts
			(xy 335.211166 -263.354058) (xy 335.211166 -263.309608) (xy 335.011014 -263.309608) (xy 335.011014 -263.354058)
			(xy 335.11109 -263.454134)
		)
		(stroke
			(width 0)
			(type solid)
		)
		(fill yes)
		(layer "In13.Cu")
		(net "M_B_CPU0_SB_CA<3>")
	)
	(gr_poly
		(pts
			(xy 335.211166 -262.137906) (xy 335.11109 -262.03783) (xy 335.011014 -262.137906) (xy 335.011014 -262.182356)
			(xy 335.211166 -262.182356)
		)
		(stroke
			(width 0)
			(type solid)
		)
		(fill yes)
		(layer "In13.Cu")
		(net "M_B_CPU0_SB_CA<0>")
	)
	(gr_poly
		(pts
			(xy 335.381092 -256.432558) (xy 335.381092 -256.384806) (xy 335.18094 -256.384806) (xy 335.18094 -256.432558)
			(xy 335.281016 -256.53238)
		)
		(stroke
			(width 0)
			(type solid)
		)
		(fill yes)
		(layer "In13.Cu")
		(net "M_B_CPU0_CLK_DN<0>")
	)
	(gr_poly
		(pts
			(xy 335.381092 -255.216152) (xy 335.281016 -255.116076) (xy 335.18094 -255.216152) (xy 335.18094 -255.260602)
			(xy 335.381092 -255.260602)
		)
		(stroke
			(width 0)
			(type solid)
		)
		(fill yes)
		(layer "In13.Cu")
		(net "M_B_CPU0_SA_CA<6>")
	)
	(gr_poly
		(pts
			(xy 335.381092 -254.812292) (xy 335.381092 -254.767842) (xy 335.18094 -254.767842) (xy 335.18094 -254.812292)
			(xy 335.281016 -254.912368)
		)
		(stroke
			(width 0)
			(type solid)
		)
		(fill yes)
		(layer "In13.Cu")
		(net "M_B_CPU0_SA_CA<5>")
	)
	(gr_poly
		(pts
			(xy 335.381092 -253.59614) (xy 335.281016 -253.496064) (xy 335.18094 -253.59614) (xy 335.18094 -253.64059)
			(xy 335.381092 -253.64059)
		)
		(stroke
			(width 0)
			(type solid)
		)
		(fill yes)
		(layer "In13.Cu")
		(net "M_B_CPU0_SA_CA<2>")
	)
	(gr_poly
		(pts
			(xy 335.381092 -253.19228) (xy 335.381092 -253.14783) (xy 335.18094 -253.14783) (xy 335.18094 -253.19228)
			(xy 335.281016 -253.292356)
		)
		(stroke
			(width 0)
			(type solid)
		)
		(fill yes)
		(layer "In13.Cu")
		(net "M_B_CPU0_SA_CA<1>")
	)
	(gr_poly
		(pts
			(xy 335.381092 -251.572268) (xy 335.381092 -251.527818) (xy 335.18094 -251.527818) (xy 335.18094 -251.572268)
			(xy 335.281016 -251.672344)
		)
		(stroke
			(width 0)
			(type solid)
		)
		(fill yes)
		(layer "In13.Cu")
		(net "M_B_CPU0_SA_CS_N<0>")
	)
	(gr_poly
		(pts
			(xy 335.381092 -250.356116) (xy 335.281016 -250.25604) (xy 335.18094 -250.356116) (xy 335.18094 -250.400566)
			(xy 335.381092 -250.400566)
		)
		(stroke
			(width 0)
			(type solid)
		)
		(fill yes)
		(layer "In13.Cu")
		(net "M_B_CPU0_ALERT_R_N")
	)
	(gr_poly
		(pts
			(xy 335.381092 -248.736104) (xy 335.281016 -248.636028) (xy 335.18094 -248.736104) (xy 335.18094 -248.780554)
			(xy 335.381092 -248.780554)
		)
		(stroke
			(width 0)
			(type solid)
		)
		(fill yes)
		(layer "In13.Cu")
		(net "M_B_CPU0_SA_CB<5>")
	)
	(gr_poly
		(pts
			(xy 335.381092 -248.332244) (xy 335.381092 -248.287794) (xy 335.18094 -248.287794) (xy 335.18094 -248.332244)
			(xy 335.281016 -248.43232)
		)
		(stroke
			(width 0)
			(type solid)
		)
		(fill yes)
		(layer "In13.Cu")
		(net "M_B_CPU0_SA_CB<6>")
	)
	(gr_poly
		(pts
			(xy 335.381092 -247.115838) (xy 335.281016 -247.016016) (xy 335.18094 -247.115838) (xy 335.18094 -247.16359)
			(xy 335.381092 -247.16359)
		)
		(stroke
			(width 0)
			(type solid)
		)
		(fill yes)
		(layer "In13.Cu")
		(net "M_B_CPU0_SA_DQS_DN<9>")
	)
	(gr_poly
		(pts
			(xy 335.381092 -246.712486) (xy 335.381092 -246.664734) (xy 335.18094 -246.664734) (xy 335.18094 -246.712486)
			(xy 335.281016 -246.812308)
		)
		(stroke
			(width 0)
			(type solid)
		)
		(fill yes)
		(layer "In13.Cu")
		(net "M_B_CPU0_SA_DQS_DN<4>")
	)
	(gr_poly
		(pts
			(xy 335.381092 -245.49608) (xy 335.281016 -245.396004) (xy 335.18094 -245.49608) (xy 335.18094 -245.54053)
			(xy 335.381092 -245.54053)
		)
		(stroke
			(width 0)
			(type solid)
		)
		(fill yes)
		(layer "In13.Cu")
		(net "M_B_CPU0_SA_CB<1>")
	)
	(gr_poly
		(pts
			(xy 335.381092 -245.09222) (xy 335.381092 -245.04777) (xy 335.18094 -245.04777) (xy 335.18094 -245.09222)
			(xy 335.281016 -245.192296)
		)
		(stroke
			(width 0)
			(type solid)
		)
		(fill yes)
		(layer "In13.Cu")
		(net "M_B_CPU0_SA_CB<2>")
	)
	(gr_poly
		(pts
			(xy 335.381092 -243.876068) (xy 335.281016 -243.775992) (xy 335.18094 -243.876068) (xy 335.18094 -243.920518)
			(xy 335.381092 -243.920518)
		)
		(stroke
			(width 0)
			(type solid)
		)
		(fill yes)
		(layer "In13.Cu")
		(net "M_B_CPU0_SA_DQ<29>")
	)
	(gr_poly
		(pts
			(xy 335.381092 -243.472208) (xy 335.381092 -243.427758) (xy 335.18094 -243.427758) (xy 335.18094 -243.472208)
			(xy 335.281016 -243.572284)
		)
		(stroke
			(width 0)
			(type solid)
		)
		(fill yes)
		(layer "In13.Cu")
		(net "M_B_CPU0_SA_DQ<30>")
	)
	(gr_poly
		(pts
			(xy 335.381092 -242.255802) (xy 335.281016 -242.15598) (xy 335.18094 -242.255802) (xy 335.18094 -242.303554)
			(xy 335.381092 -242.303554)
		)
		(stroke
			(width 0)
			(type solid)
		)
		(fill yes)
		(layer "In13.Cu")
		(net "M_B_CPU0_SA_DQS_DN<8>")
	)
	(gr_poly
		(pts
			(xy 335.381092 -241.85245) (xy 335.381092 -241.804698) (xy 335.18094 -241.804698) (xy 335.18094 -241.85245)
			(xy 335.281016 -241.952272)
		)
		(stroke
			(width 0)
			(type solid)
		)
		(fill yes)
		(layer "In13.Cu")
		(net "M_B_CPU0_SA_DQS_DN<3>")
	)
	(gr_poly
		(pts
			(xy 335.381092 -240.636044) (xy 335.281016 -240.535968) (xy 335.18094 -240.636044) (xy 335.18094 -240.680494)
			(xy 335.381092 -240.680494)
		)
		(stroke
			(width 0)
			(type solid)
		)
		(fill yes)
		(layer "In13.Cu")
		(net "M_B_CPU0_SA_DQ<25>")
	)
	(gr_poly
		(pts
			(xy 335.381092 -240.232184) (xy 335.381092 -240.187734) (xy 335.18094 -240.187734) (xy 335.18094 -240.232184)
			(xy 335.281016 -240.33226)
		)
		(stroke
			(width 0)
			(type solid)
		)
		(fill yes)
		(layer "In13.Cu")
		(net "M_B_CPU0_SA_DQ<26>")
	)
	(gr_poly
		(pts
			(xy 335.381092 -239.016032) (xy 335.281016 -238.915956) (xy 335.18094 -239.016032) (xy 335.18094 -239.060482)
			(xy 335.381092 -239.060482)
		)
		(stroke
			(width 0)
			(type solid)
		)
		(fill yes)
		(layer "In13.Cu")
		(net "M_B_CPU0_SA_DQ<21>")
	)
	(gr_poly
		(pts
			(xy 335.381092 -238.612172) (xy 335.381092 -238.567722) (xy 335.18094 -238.567722) (xy 335.18094 -238.612172)
			(xy 335.281016 -238.712248)
		)
		(stroke
			(width 0)
			(type solid)
		)
		(fill yes)
		(layer "In13.Cu")
		(net "M_B_CPU0_SA_DQ<22>")
	)
	(gr_poly
		(pts
			(xy 335.381092 -237.395766) (xy 335.281016 -237.295944) (xy 335.18094 -237.395766) (xy 335.18094 -237.443518)
			(xy 335.381092 -237.443518)
		)
		(stroke
			(width 0)
			(type solid)
		)
		(fill yes)
		(layer "In13.Cu")
		(net "M_B_CPU0_SA_DQS_DN<7>")
	)
	(gr_poly
		(pts
			(xy 335.381092 -236.992414) (xy 335.381092 -236.944662) (xy 335.18094 -236.944662) (xy 335.18094 -236.992414)
			(xy 335.281016 -237.092236)
		)
		(stroke
			(width 0)
			(type solid)
		)
		(fill yes)
		(layer "In13.Cu")
		(net "M_B_CPU0_SA_DQS_DN<2>")
	)
	(gr_poly
		(pts
			(xy 335.381092 -235.776008) (xy 335.281016 -235.675932) (xy 335.18094 -235.776008) (xy 335.18094 -235.820458)
			(xy 335.381092 -235.820458)
		)
		(stroke
			(width 0)
			(type solid)
		)
		(fill yes)
		(layer "In13.Cu")
		(net "M_B_CPU0_SA_DQ<17>")
	)
	(gr_poly
		(pts
			(xy 335.381092 -235.372148) (xy 335.381092 -235.327698) (xy 335.18094 -235.327698) (xy 335.18094 -235.372148)
			(xy 335.281016 -235.472224)
		)
		(stroke
			(width 0)
			(type solid)
		)
		(fill yes)
		(layer "In13.Cu")
		(net "M_B_CPU0_SA_DQ<18>")
	)
	(gr_poly
		(pts
			(xy 335.381092 -234.155996) (xy 335.281016 -234.05592) (xy 335.18094 -234.155996) (xy 335.18094 -234.200446)
			(xy 335.381092 -234.200446)
		)
		(stroke
			(width 0)
			(type solid)
		)
		(fill yes)
		(layer "In13.Cu")
		(net "M_B_CPU0_SA_DQ<13>")
	)
	(gr_poly
		(pts
			(xy 335.381092 -233.752136) (xy 335.381092 -233.707686) (xy 335.18094 -233.707686) (xy 335.18094 -233.752136)
			(xy 335.281016 -233.852212)
		)
		(stroke
			(width 0)
			(type solid)
		)
		(fill yes)
		(layer "In13.Cu")
		(net "M_B_CPU0_SA_DQ<14>")
	)
	(gr_poly
		(pts
			(xy 335.381092 -232.53573) (xy 335.281016 -232.435908) (xy 335.18094 -232.53573) (xy 335.18094 -232.583482)
			(xy 335.381092 -232.583482)
		)
		(stroke
			(width 0)
			(type solid)
		)
		(fill yes)
		(layer "In13.Cu")
		(net "M_B_CPU0_SA_DQS_DN<6>")
	)
	(gr_poly
		(pts
			(xy 335.381092 -232.132378) (xy 335.381092 -232.084626) (xy 335.18094 -232.084626) (xy 335.18094 -232.132378)
			(xy 335.281016 -232.2322)
		)
		(stroke
			(width 0)
			(type solid)
		)
		(fill yes)
		(layer "In13.Cu")
		(net "M_B_CPU0_SA_DQS_DN<1>")
	)
	(gr_poly
		(pts
			(xy 335.381092 -230.915972) (xy 335.281016 -230.815896) (xy 335.18094 -230.915972) (xy 335.18094 -230.960422)
			(xy 335.381092 -230.960422)
		)
		(stroke
			(width 0)
			(type solid)
		)
		(fill yes)
		(layer "In13.Cu")
		(net "M_B_CPU0_SA_DQ<9>")
	)
	(gr_poly
		(pts
			(xy 335.381092 -230.512366) (xy 335.381092 -230.467916) (xy 335.18094 -230.467916) (xy 335.18094 -230.512366)
			(xy 335.281016 -230.612188)
		)
		(stroke
			(width 0)
			(type solid)
		)
		(fill yes)
		(layer "In13.Cu")
		(net "M_B_CPU0_SA_DQ<10>")
	)
	(gr_poly
		(pts
			(xy 335.381092 -229.29596) (xy 335.281016 -229.195884) (xy 335.18094 -229.29596) (xy 335.18094 -229.34041)
			(xy 335.381092 -229.34041)
		)
		(stroke
			(width 0)
			(type solid)
		)
		(fill yes)
		(layer "In13.Cu")
		(net "M_B_CPU0_SA_DQ<5>")
	)
	(gr_poly
		(pts
			(xy 335.381092 -228.892354) (xy 335.381092 -228.847904) (xy 335.18094 -228.847904) (xy 335.18094 -228.892354)
			(xy 335.281016 -228.99243)
		)
		(stroke
			(width 0)
			(type solid)
		)
		(fill yes)
		(layer "In13.Cu")
		(net "M_B_CPU0_SA_DQ<6>")
	)
	(gr_poly
		(pts
			(xy 335.381092 -227.272596) (xy 335.381092 -227.224844) (xy 335.18094 -227.224844) (xy 335.18094 -227.272596)
			(xy 335.281016 -227.372418)
		)
		(stroke
			(width 0)
			(type solid)
		)
		(fill yes)
		(layer "In13.Cu")
		(net "M_B_CPU0_SA_DQS_DN<0>")
	)
	(gr_poly
		(pts
			(xy 335.381092 -226.05619) (xy 335.281016 -225.956114) (xy 335.18094 -226.05619) (xy 335.18094 -226.10064)
			(xy 335.381092 -226.10064)
		)
		(stroke
			(width 0)
			(type solid)
		)
		(fill yes)
		(layer "In13.Cu")
		(net "M_B_CPU0_SA_DQ<1>")
	)
	(gr_poly
		(pts
			(xy 335.381092 -225.65233) (xy 335.381092 -225.60788) (xy 335.18094 -225.60788) (xy 335.18094 -225.65233)
			(xy 335.281016 -225.752406)
		)
		(stroke
			(width 0)
			(type solid)
		)
		(fill yes)
		(layer "In13.Cu")
		(net "M_B_CPU0_SA_DQ<2>")
	)
	(gr_poly
		(pts
			(xy 335.387188 -227.676456) (xy 335.287112 -227.57638) (xy 335.18729 -227.676456) (xy 335.18729 -227.723954)
			(xy 335.387188 -227.723954)
		)
		(stroke
			(width 0)
			(type solid)
		)
		(fill yes)
		(layer "In13.Cu")
		(net "M_B_CPU0_SA_DQS_DN<5>")
	)
	(gr_poly
		(pts
			(xy 335.681066 -293.324026) (xy 335.681066 -293.279576) (xy 335.480914 -293.279576) (xy 335.480914 -293.324026)
			(xy 335.58099 -293.424102)
		)
		(stroke
			(width 0)
			(type solid)
		)
		(fill yes)
		(layer "In13.Cu")
		(net "M_B_CPU0_SB_DQ<31>")
	)
	(gr_poly
		(pts
			(xy 335.681066 -292.107874) (xy 335.58099 -292.007798) (xy 335.480914 -292.107874) (xy 335.480914 -292.152324)
			(xy 335.681066 -292.152324)
		)
		(stroke
			(width 0)
			(type solid)
		)
		(fill yes)
		(layer "In13.Cu")
		(net "M_B_CPU0_SB_DQ<28>")
	)
	(gr_poly
		(pts
			(xy 335.681066 -291.704268) (xy 335.681066 -291.656516) (xy 335.480914 -291.656516) (xy 335.480914 -291.704268)
			(xy 335.58099 -291.80409)
		)
		(stroke
			(width 0)
			(type solid)
		)
		(fill yes)
		(layer "In13.Cu")
		(net "M_B_CPU0_SB_DQS_DP<8>")
	)
	(gr_poly
		(pts
			(xy 335.681066 -290.487608) (xy 335.58099 -290.387786) (xy 335.480914 -290.487608) (xy 335.480914 -290.53536)
			(xy 335.681066 -290.53536)
		)
		(stroke
			(width 0)
			(type solid)
		)
		(fill yes)
		(layer "In13.Cu")
		(net "M_B_CPU0_SB_DQS_DP<3>")
	)
	(gr_poly
		(pts
			(xy 335.681066 -290.084002) (xy 335.681066 -290.039552) (xy 335.480914 -290.039552) (xy 335.480914 -290.084002)
			(xy 335.58099 -290.184078)
		)
		(stroke
			(width 0)
			(type solid)
		)
		(fill yes)
		(layer "In13.Cu")
		(net "M_B_CPU0_SB_DQ<27>")
	)
	(gr_poly
		(pts
			(xy 335.681066 -288.86785) (xy 335.58099 -288.767774) (xy 335.480914 -288.86785) (xy 335.480914 -288.9123)
			(xy 335.681066 -288.9123)
		)
		(stroke
			(width 0)
			(type solid)
		)
		(fill yes)
		(layer "In13.Cu")
		(net "M_B_CPU0_SB_DQ<24>")
	)
	(gr_poly
		(pts
			(xy 335.681066 -288.464244) (xy 335.681066 -288.419794) (xy 335.480914 -288.419794) (xy 335.480914 -288.464244)
			(xy 335.58099 -288.56432)
		)
		(stroke
			(width 0)
			(type solid)
		)
		(fill yes)
		(layer "In13.Cu")
		(net "M_B_CPU0_SB_DQ<23>")
	)
	(gr_poly
		(pts
			(xy 335.681066 -287.247838) (xy 335.58099 -287.148016) (xy 335.480914 -287.247838) (xy 335.480914 -287.292288)
			(xy 335.681066 -287.292288)
		)
		(stroke
			(width 0)
			(type solid)
		)
		(fill yes)
		(layer "In13.Cu")
		(net "M_B_CPU0_SB_DQ<20>")
	)
	(gr_poly
		(pts
			(xy 335.681066 -286.844232) (xy 335.681066 -286.79648) (xy 335.480914 -286.79648) (xy 335.480914 -286.844232)
			(xy 335.58099 -286.944308)
		)
		(stroke
			(width 0)
			(type solid)
		)
		(fill yes)
		(layer "In13.Cu")
		(net "M_B_CPU0_SB_DQS_DP<7>")
	)
	(gr_poly
		(pts
			(xy 335.681066 -285.627826) (xy 335.58099 -285.528004) (xy 335.480914 -285.627826) (xy 335.480914 -285.675578)
			(xy 335.681066 -285.675578)
		)
		(stroke
			(width 0)
			(type solid)
		)
		(fill yes)
		(layer "In13.Cu")
		(net "M_B_CPU0_SB_DQS_DP<2>")
	)
	(gr_poly
		(pts
			(xy 335.681066 -285.22422) (xy 335.681066 -285.17977) (xy 335.480914 -285.17977) (xy 335.480914 -285.22422)
			(xy 335.58099 -285.324296)
		)
		(stroke
			(width 0)
			(type solid)
		)
		(fill yes)
		(layer "In13.Cu")
		(net "M_B_CPU0_SB_DQ<19>")
	)
	(gr_poly
		(pts
			(xy 335.681066 -284.008068) (xy 335.58099 -283.907992) (xy 335.480914 -284.008068) (xy 335.480914 -284.052518)
			(xy 335.681066 -284.052518)
		)
		(stroke
			(width 0)
			(type solid)
		)
		(fill yes)
		(layer "In13.Cu")
		(net "M_B_CPU0_SB_DQ<16>")
	)
	(gr_poly
		(pts
			(xy 335.681066 -283.604208) (xy 335.681066 -283.559758) (xy 335.480914 -283.559758) (xy 335.480914 -283.604208)
			(xy 335.58099 -283.704284)
		)
		(stroke
			(width 0)
			(type solid)
		)
		(fill yes)
		(layer "In13.Cu")
		(net "M_B_CPU0_SB_DQ<15>")
	)
	(gr_poly
		(pts
			(xy 335.681066 -282.388056) (xy 335.58099 -282.28798) (xy 335.480914 -282.388056) (xy 335.480914 -282.432506)
			(xy 335.681066 -282.432506)
		)
		(stroke
			(width 0)
			(type solid)
		)
		(fill yes)
		(layer "In13.Cu")
		(net "M_B_CPU0_SB_DQ<12>")
	)
	(gr_poly
		(pts
			(xy 335.681066 -281.98445) (xy 335.681066 -281.936698) (xy 335.480914 -281.936698) (xy 335.480914 -281.98445)
			(xy 335.58099 -282.084272)
		)
		(stroke
			(width 0)
			(type solid)
		)
		(fill yes)
		(layer "In13.Cu")
		(net "M_B_CPU0_SB_DQS_DP<6>")
	)
	(gr_poly
		(pts
			(xy 335.681066 -280.76779) (xy 335.58099 -280.667968) (xy 335.480914 -280.76779) (xy 335.480914 -280.815542)
			(xy 335.681066 -280.815542)
		)
		(stroke
			(width 0)
			(type solid)
		)
		(fill yes)
		(layer "In13.Cu")
		(net "M_B_CPU0_SB_DQS_DP<1>")
	)
	(gr_poly
		(pts
			(xy 335.681066 -280.364184) (xy 335.681066 -280.319734) (xy 335.480914 -280.319734) (xy 335.480914 -280.364184)
			(xy 335.58099 -280.46426)
		)
		(stroke
			(width 0)
			(type solid)
		)
		(fill yes)
		(layer "In13.Cu")
		(net "M_B_CPU0_SB_DQ<11>")
	)
	(gr_poly
		(pts
			(xy 335.681066 -279.148032) (xy 335.58099 -279.047956) (xy 335.480914 -279.148032) (xy 335.480914 -279.192482)
			(xy 335.681066 -279.192482)
		)
		(stroke
			(width 0)
			(type solid)
		)
		(fill yes)
		(layer "In13.Cu")
		(net "M_B_CPU0_SB_DQ<8>")
	)
	(gr_poly
		(pts
			(xy 335.681066 -278.744172) (xy 335.681066 -278.699722) (xy 335.480914 -278.699722) (xy 335.480914 -278.744172)
			(xy 335.58099 -278.844248)
		)
		(stroke
			(width 0)
			(type solid)
		)
		(fill yes)
		(layer "In13.Cu")
		(net "M_B_CPU0_SB_DQ<7>")
	)
	(gr_poly
		(pts
			(xy 335.681066 -277.52802) (xy 335.58099 -277.427944) (xy 335.480914 -277.52802) (xy 335.480914 -277.57247)
			(xy 335.681066 -277.57247)
		)
		(stroke
			(width 0)
			(type solid)
		)
		(fill yes)
		(layer "In13.Cu")
		(net "M_B_CPU0_SB_DQ<4>")
	)
	(gr_poly
		(pts
			(xy 335.681066 -275.504148) (xy 335.681066 -275.459698) (xy 335.480914 -275.459698) (xy 335.480914 -275.504148)
			(xy 335.58099 -275.604224)
		)
		(stroke
			(width 0)
			(type solid)
		)
		(fill yes)
		(layer "In13.Cu")
		(net "M_B_CPU0_SB_DQ<3>")
	)
	(gr_poly
		(pts
			(xy 335.681066 -274.287996) (xy 335.58099 -274.18792) (xy 335.480914 -274.287996) (xy 335.480914 -274.332446)
			(xy 335.681066 -274.332446)
		)
		(stroke
			(width 0)
			(type solid)
		)
		(fill yes)
		(layer "In13.Cu")
		(net "M_B_CPU0_SB_DQ<0>")
	)
	(gr_poly
		(pts
			(xy 335.681066 -273.884136) (xy 335.681066 -273.839686) (xy 335.480914 -273.839686) (xy 335.480914 -273.884136)
			(xy 335.58099 -273.984212)
		)
		(stroke
			(width 0)
			(type solid)
		)
		(fill yes)
		(layer "In13.Cu")
		(net "M_B_CPU0_SB_CB<3>")
	)
	(gr_poly
		(pts
			(xy 335.681066 -272.667984) (xy 335.58099 -272.567908) (xy 335.480914 -272.667984) (xy 335.480914 -272.712434)
			(xy 335.681066 -272.712434)
		)
		(stroke
			(width 0)
			(type solid)
		)
		(fill yes)
		(layer "In13.Cu")
		(net "M_B_CPU0_SB_CB<0>")
	)
	(gr_poly
		(pts
			(xy 335.681066 -272.264378) (xy 335.681066 -272.216626) (xy 335.480914 -272.216626) (xy 335.480914 -272.264378)
			(xy 335.58099 -272.3642)
		)
		(stroke
			(width 0)
			(type solid)
		)
		(fill yes)
		(layer "In13.Cu")
		(net "M_B_CPU0_SB_DQS_DP<4>")
	)
	(gr_poly
		(pts
			(xy 335.681066 -271.047718) (xy 335.58099 -270.947896) (xy 335.480914 -271.047718) (xy 335.480914 -271.09547)
			(xy 335.681066 -271.09547)
		)
		(stroke
			(width 0)
			(type solid)
		)
		(fill yes)
		(layer "In13.Cu")
		(net "M_B_CPU0_SB_DQS_DP<9>")
	)
	(gr_poly
		(pts
			(xy 335.681066 -270.644112) (xy 335.681066 -270.599662) (xy 335.480914 -270.599662) (xy 335.480914 -270.644112)
			(xy 335.58099 -270.744188)
		)
		(stroke
			(width 0)
			(type solid)
		)
		(fill yes)
		(layer "In13.Cu")
		(net "M_B_CPU0_SB_CB<7>")
	)
	(gr_poly
		(pts
			(xy 335.681066 -269.42796) (xy 335.58099 -269.327884) (xy 335.480914 -269.42796) (xy 335.480914 -269.47241)
			(xy 335.681066 -269.47241)
		)
		(stroke
			(width 0)
			(type solid)
		)
		(fill yes)
		(layer "In13.Cu")
		(net "M_B_CPU0_SB_CB<4>")
	)
	(gr_poly
		(pts
			(xy 335.681066 -265.784076) (xy 335.681066 -265.739626) (xy 335.480914 -265.739626) (xy 335.480914 -265.784076)
			(xy 335.58099 -265.884152)
		)
		(stroke
			(width 0)
			(type solid)
		)
		(fill yes)
		(layer "In13.Cu")
		(net "M_B_CPU0_SB_CS_N<0>")
	)
	(gr_poly
		(pts
			(xy 335.681066 -264.567924) (xy 335.58099 -264.467848) (xy 335.480914 -264.567924) (xy 335.480914 -264.612374)
			(xy 335.681066 -264.612374)
		)
		(stroke
			(width 0)
			(type solid)
		)
		(fill yes)
		(layer "In13.Cu")
		(net "M_B_CPU0_SB_CA<6>")
	)
	(gr_poly
		(pts
			(xy 335.681066 -264.164064) (xy 335.681066 -264.119614) (xy 335.480914 -264.119614) (xy 335.480914 -264.164064)
			(xy 335.58099 -264.26414)
		)
		(stroke
			(width 0)
			(type solid)
		)
		(fill yes)
		(layer "In13.Cu")
		(net "M_B_CPU0_SB_CA<5>")
	)
	(gr_poly
		(pts
			(xy 335.681066 -262.947912) (xy 335.58099 -262.847836) (xy 335.480914 -262.947912) (xy 335.480914 -262.992362)
			(xy 335.681066 -262.992362)
		)
		(stroke
			(width 0)
			(type solid)
		)
		(fill yes)
		(layer "In13.Cu")
		(net "M_B_CPU0_SB_CA<2>")
	)
	(gr_poly
		(pts
			(xy 335.681066 -262.544052) (xy 335.681066 -262.499602) (xy 335.480914 -262.499602) (xy 335.480914 -262.544052)
			(xy 335.58099 -262.644128)
		)
		(stroke
			(width 0)
			(type solid)
		)
		(fill yes)
		(layer "In13.Cu")
		(net "M_B_CPU0_SB_CA<1>")
	)
	(gr_poly
		(pts
			(xy 335.687162 -267.801598) (xy 335.58734 -267.701522) (xy 335.487264 -267.801598) (xy 335.487264 -267.846048)
			(xy 335.687162 -267.846048)
		)
		(stroke
			(width 0)
			(type solid)
		)
		(fill yes)
		(layer "In13.Cu")
		(net "M_B_CPU0_SB_RSP<0>")
	)
	(gr_poly
		(pts
			(xy 335.688432 -277.12416) (xy 335.688432 -277.076662) (xy 335.48828 -277.076662) (xy 335.48828 -277.12416)
			(xy 335.588356 -277.224236)
		)
		(stroke
			(width 0)
			(type solid)
		)
		(fill yes)
		(layer "In13.Cu")
		(net "M_B_CPU0_SB_DQS_DP<5>")
	)
	(gr_poly
		(pts
			(xy 335.688432 -275.908008) (xy 335.588356 -275.807932) (xy 335.48828 -275.908008) (xy 335.48828 -275.955506)
			(xy 335.688432 -275.955506)
		)
		(stroke
			(width 0)
			(type solid)
		)
		(fill yes)
		(layer "In13.Cu")
		(net "M_B_CPU0_SB_DQS_DP<0>")
	)
	(gr_poly
		(pts
			(xy 335.851246 -255.622298) (xy 335.851246 -255.577848) (xy 335.651094 -255.577848) (xy 335.651094 -255.622298)
			(xy 335.75117 -255.722374)
		)
		(stroke
			(width 0)
			(type solid)
		)
		(fill yes)
		(layer "In13.Cu")
		(net "M_B_CPU0_SA_PAR")
	)
	(gr_poly
		(pts
			(xy 335.851246 -254.002286) (xy 335.851246 -253.957836) (xy 335.651094 -253.957836) (xy 335.651094 -254.002286)
			(xy 335.75117 -254.102362)
		)
		(stroke
			(width 0)
			(type solid)
		)
		(fill yes)
		(layer "In13.Cu")
		(net "M_B_CPU0_SA_CA<3>")
	)
	(gr_poly
		(pts
			(xy 335.851246 -252.382274) (xy 335.851246 -252.337824) (xy 335.651094 -252.337824) (xy 335.651094 -252.382274)
			(xy 335.75117 -252.48235)
		)
		(stroke
			(width 0)
			(type solid)
		)
		(fill yes)
		(layer "In13.Cu")
		(net "M_B_CPU0_SA_CS_N<1>")
	)
	(gr_poly
		(pts
			(xy 335.851246 -250.762262) (xy 335.851246 -250.717812) (xy 335.651094 -250.717812) (xy 335.651094 -250.762262)
			(xy 335.75117 -250.862338)
		)
		(stroke
			(width 0)
			(type solid)
		)
		(fill yes)
		(layer "In13.Cu")
		(net "M_B_CPU0_RESET_N")
	)
	(gr_poly
		(pts
			(xy 335.851246 -249.14225) (xy 335.851246 -249.0978) (xy 335.651094 -249.0978) (xy 335.651094 -249.14225)
			(xy 335.75117 -249.242326)
		)
		(stroke
			(width 0)
			(type solid)
		)
		(fill yes)
		(layer "In13.Cu")
		(net "M_B_CPU0_SA_CB<7>")
	)
	(gr_poly
		(pts
			(xy 335.851246 -247.522492) (xy 335.851246 -247.47474) (xy 335.651094 -247.47474) (xy 335.651094 -247.522492)
			(xy 335.75117 -247.622314)
		)
		(stroke
			(width 0)
			(type solid)
		)
		(fill yes)
		(layer "In13.Cu")
		(net "M_B_CPU0_SA_DQS_DP<9>")
	)
	(gr_poly
		(pts
			(xy 335.851246 -245.902226) (xy 335.851246 -245.857776) (xy 335.651094 -245.857776) (xy 335.651094 -245.902226)
			(xy 335.75117 -246.002302)
		)
		(stroke
			(width 0)
			(type solid)
		)
		(fill yes)
		(layer "In13.Cu")
		(net "M_B_CPU0_SA_CB<3>")
	)
	(gr_poly
		(pts
			(xy 335.851246 -244.282214) (xy 335.851246 -244.237764) (xy 335.651094 -244.237764) (xy 335.651094 -244.282214)
			(xy 335.75117 -244.38229)
		)
		(stroke
			(width 0)
			(type solid)
		)
		(fill yes)
		(layer "In13.Cu")
		(net "M_B_CPU0_SA_DQ<31>")
	)
	(gr_poly
		(pts
			(xy 335.851246 -242.662456) (xy 335.851246 -242.614704) (xy 335.651094 -242.614704) (xy 335.651094 -242.662456)
			(xy 335.75117 -242.762278)
		)
		(stroke
			(width 0)
			(type solid)
		)
		(fill yes)
		(layer "In13.Cu")
		(net "M_B_CPU0_SA_DQS_DP<8>")
	)
	(gr_poly
		(pts
			(xy 335.851246 -241.04219) (xy 335.851246 -240.99774) (xy 335.651094 -240.99774) (xy 335.651094 -241.04219)
			(xy 335.75117 -241.142266)
		)
		(stroke
			(width 0)
			(type solid)
		)
		(fill yes)
		(layer "In13.Cu")
		(net "M_B_CPU0_SA_DQ<27>")
	)
	(gr_poly
		(pts
			(xy 335.851246 -239.422178) (xy 335.851246 -239.377728) (xy 335.651094 -239.377728) (xy 335.651094 -239.422178)
			(xy 335.75117 -239.522254)
		)
		(stroke
			(width 0)
			(type solid)
		)
		(fill yes)
		(layer "In13.Cu")
		(net "M_B_CPU0_SA_DQ<23>")
	)
	(gr_poly
		(pts
			(xy 335.851246 -237.80242) (xy 335.851246 -237.754668) (xy 335.651094 -237.754668) (xy 335.651094 -237.80242)
			(xy 335.75117 -237.902242)
		)
		(stroke
			(width 0)
			(type solid)
		)
		(fill yes)
		(layer "In13.Cu")
		(net "M_B_CPU0_SA_DQS_DP<7>")
	)
	(gr_poly
		(pts
			(xy 335.851246 -236.182154) (xy 335.851246 -236.137704) (xy 335.651094 -236.137704) (xy 335.651094 -236.182154)
			(xy 335.75117 -236.28223)
		)
		(stroke
			(width 0)
			(type solid)
		)
		(fill yes)
		(layer "In13.Cu")
		(net "M_B_CPU0_SA_DQ<19>")
	)
	(gr_poly
		(pts
			(xy 335.851246 -234.562142) (xy 335.851246 -234.517692) (xy 335.651094 -234.517692) (xy 335.651094 -234.562142)
			(xy 335.75117 -234.662218)
		)
		(stroke
			(width 0)
			(type solid)
		)
		(fill yes)
		(layer "In13.Cu")
		(net "M_B_CPU0_SA_DQ<15>")
	)
	(gr_poly
		(pts
			(xy 335.851246 -232.942384) (xy 335.851246 -232.894632) (xy 335.651094 -232.894632) (xy 335.651094 -232.942384)
			(xy 335.75117 -233.042206)
		)
		(stroke
			(width 0)
			(type solid)
		)
		(fill yes)
		(layer "In13.Cu")
		(net "M_B_CPU0_SA_DQS_DP<6>")
	)
	(gr_poly
		(pts
			(xy 335.851246 -231.322372) (xy 335.851246 -231.277922) (xy 335.651094 -231.277922) (xy 335.651094 -231.322372)
			(xy 335.75117 -231.422448)
		)
		(stroke
			(width 0)
			(type solid)
		)
		(fill yes)
		(layer "In13.Cu")
		(net "M_B_CPU0_SA_DQ<11>")
	)
	(gr_poly
		(pts
			(xy 335.851246 -229.70236) (xy 335.851246 -229.65791) (xy 335.651094 -229.65791) (xy 335.651094 -229.70236)
			(xy 335.75117 -229.802436)
		)
		(stroke
			(width 0)
			(type solid)
		)
		(fill yes)
		(layer "In13.Cu")
		(net "M_B_CPU0_SA_DQ<7>")
	)
	(gr_poly
		(pts
			(xy 335.851246 -228.082602) (xy 335.851246 -228.03485) (xy 335.651094 -228.03485) (xy 335.651094 -228.082602)
			(xy 335.75117 -228.182424)
		)
		(stroke
			(width 0)
			(type solid)
		)
		(fill yes)
		(layer "In13.Cu")
		(net "M_B_CPU0_SA_DQS_DP<5>")
	)
	(gr_poly
		(pts
			(xy 335.851246 -226.462336) (xy 335.851246 -226.417886) (xy 335.651094 -226.417886) (xy 335.651094 -226.462336)
			(xy 335.75117 -226.562412)
		)
		(stroke
			(width 0)
			(type solid)
		)
		(fill yes)
		(layer "In13.Cu")
		(net "M_B_CPU0_SA_DQ<3>")
	)
	(gr_poly
		(pts
			(xy 336.14487 -266.991592) (xy 336.044794 -266.891516) (xy 335.944972 -266.991592) (xy 335.944972 -267.036042)
			(xy 336.14487 -267.036042)
		)
		(stroke
			(width 0)
			(type solid)
		)
		(fill yes)
		(layer "In13.Cu")
		(net "M_B_CPU0_SA_RSP<0>")
	)
	(gr_poly
		(pts
			(xy 336.15122 -292.91788) (xy 336.051144 -292.817804) (xy 335.951068 -292.91788) (xy 335.951068 -292.96233)
			(xy 336.15122 -292.96233)
		)
		(stroke
			(width 0)
			(type solid)
		)
		(fill yes)
		(layer "In13.Cu")
		(net "M_B_CPU0_SB_DQ<29>")
	)
	(gr_poly
		(pts
			(xy 336.15122 -291.297614) (xy 336.051144 -291.197792) (xy 335.951068 -291.297614) (xy 335.951068 -291.345366)
			(xy 336.15122 -291.345366)
		)
		(stroke
			(width 0)
			(type solid)
		)
		(fill yes)
		(layer "In13.Cu")
		(net "M_B_CPU0_SB_DQS_DN<8>")
	)
	(gr_poly
		(pts
			(xy 336.15122 -289.677856) (xy 336.051144 -289.57778) (xy 335.951068 -289.677856) (xy 335.951068 -289.722306)
			(xy 336.15122 -289.722306)
		)
		(stroke
			(width 0)
			(type solid)
		)
		(fill yes)
		(layer "In13.Cu")
		(net "M_B_CPU0_SB_DQ<25>")
	)
	(gr_poly
		(pts
			(xy 336.15122 -288.057844) (xy 336.051144 -287.957768) (xy 335.951068 -288.057844) (xy 335.951068 -288.102294)
			(xy 336.15122 -288.102294)
		)
		(stroke
			(width 0)
			(type solid)
		)
		(fill yes)
		(layer "In13.Cu")
		(net "M_B_CPU0_SB_DQ<21>")
	)
	(gr_poly
		(pts
			(xy 336.15122 -286.437832) (xy 336.051144 -286.337756) (xy 335.951068 -286.437832) (xy 335.951068 -286.485584)
			(xy 336.15122 -286.485584)
		)
		(stroke
			(width 0)
			(type solid)
		)
		(fill yes)
		(layer "In13.Cu")
		(net "M_B_CPU0_SB_DQS_DN<7>")
	)
	(gr_poly
		(pts
			(xy 336.15122 -284.818074) (xy 336.051144 -284.717998) (xy 335.951068 -284.818074) (xy 335.951068 -284.862524)
			(xy 336.15122 -284.862524)
		)
		(stroke
			(width 0)
			(type solid)
		)
		(fill yes)
		(layer "In13.Cu")
		(net "M_B_CPU0_SB_DQ<17>")
	)
	(gr_poly
		(pts
			(xy 336.15122 -283.198062) (xy 336.051144 -283.097986) (xy 335.951068 -283.198062) (xy 335.951068 -283.242512)
			(xy 336.15122 -283.242512)
		)
		(stroke
			(width 0)
			(type solid)
		)
		(fill yes)
		(layer "In13.Cu")
		(net "M_B_CPU0_SB_DQ<13>")
	)
	(gr_poly
		(pts
			(xy 336.15122 -281.577796) (xy 336.051144 -281.477974) (xy 335.951068 -281.577796) (xy 335.951068 -281.625548)
			(xy 336.15122 -281.625548)
		)
		(stroke
			(width 0)
			(type solid)
		)
		(fill yes)
		(layer "In13.Cu")
		(net "M_B_CPU0_SB_DQS_DN<6>")
	)
	(gr_poly
		(pts
			(xy 336.15122 -279.958038) (xy 336.051144 -279.857962) (xy 335.951068 -279.958038) (xy 335.951068 -280.002488)
			(xy 336.15122 -280.002488)
		)
		(stroke
			(width 0)
			(type solid)
		)
		(fill yes)
		(layer "In13.Cu")
		(net "M_B_CPU0_SB_DQ<9>")
	)
	(gr_poly
		(pts
			(xy 336.15122 -278.338026) (xy 336.051144 -278.23795) (xy 335.951068 -278.338026) (xy 335.951068 -278.382476)
			(xy 336.15122 -278.382476)
		)
		(stroke
			(width 0)
			(type solid)
		)
		(fill yes)
		(layer "In13.Cu")
		(net "M_B_CPU0_SB_DQ<5>")
	)
	(gr_poly
		(pts
			(xy 336.15122 -276.71776) (xy 336.051144 -276.617938) (xy 335.951068 -276.71776) (xy 335.951068 -276.765512)
			(xy 336.15122 -276.765512)
		)
		(stroke
			(width 0)
			(type solid)
		)
		(fill yes)
		(layer "In13.Cu")
		(net "M_B_CPU0_SB_DQS_DN<5>")
	)
	(gr_poly
		(pts
			(xy 336.15122 -275.098002) (xy 336.051144 -274.997926) (xy 335.951068 -275.098002) (xy 335.951068 -275.142452)
			(xy 336.15122 -275.142452)
		)
		(stroke
			(width 0)
			(type solid)
		)
		(fill yes)
		(layer "In13.Cu")
		(net "M_B_CPU0_SB_DQ<1>")
	)
	(gr_poly
		(pts
			(xy 336.15122 -273.47799) (xy 336.051144 -273.377914) (xy 335.951068 -273.47799) (xy 335.951068 -273.52244)
			(xy 336.15122 -273.52244)
		)
		(stroke
			(width 0)
			(type solid)
		)
		(fill yes)
		(layer "In13.Cu")
		(net "M_B_CPU0_SB_CB<1>")
	)
	(gr_poly
		(pts
			(xy 336.15122 -271.857724) (xy 336.051144 -271.757902) (xy 335.951068 -271.857724) (xy 335.951068 -271.905476)
			(xy 336.15122 -271.905476)
		)
		(stroke
			(width 0)
			(type solid)
		)
		(fill yes)
		(layer "In13.Cu")
		(net "M_B_CPU0_SB_DQS_DN<4>")
	)
	(gr_poly
		(pts
			(xy 336.15122 -270.237966) (xy 336.051144 -270.13789) (xy 335.951068 -270.237966) (xy 335.951068 -270.282416)
			(xy 336.15122 -270.282416)
		)
		(stroke
			(width 0)
			(type solid)
		)
		(fill yes)
		(layer "In13.Cu")
		(net "M_B_CPU0_SB_CB<5>")
	)
	(gr_poly
		(pts
			(xy 336.15122 -263.757918) (xy 336.051144 -263.657842) (xy 335.951068 -263.757918) (xy 335.951068 -263.802368)
			(xy 336.15122 -263.802368)
		)
		(stroke
			(width 0)
			(type solid)
		)
		(fill yes)
		(layer "In13.Cu")
		(net "M_B_CPU0_SB_CA<4>")
	)
	(gr_poly
		(pts
			(xy 336.15122 -262.137906) (xy 336.051144 -262.03783) (xy 335.951068 -262.137906) (xy 335.951068 -262.182356)
			(xy 336.15122 -262.182356)
		)
		(stroke
			(width 0)
			(type solid)
		)
		(fill yes)
		(layer "In13.Cu")
		(net "M_B_CPU0_SB_CA<0>")
	)
	(gr_poly
		(pts
			(xy 336.321146 -255.216152) (xy 336.22107 -255.116076) (xy 336.120994 -255.216152) (xy 336.120994 -255.260602)
			(xy 336.321146 -255.260602)
		)
		(stroke
			(width 0)
			(type solid)
		)
		(fill yes)
		(layer "In13.Cu")
		(net "M_B_CPU0_SA_CA<6>")
	)
	(gr_poly
		(pts
			(xy 336.321146 -253.59614) (xy 336.22107 -253.496064) (xy 336.120994 -253.59614) (xy 336.120994 -253.64059)
			(xy 336.321146 -253.64059)
		)
		(stroke
			(width 0)
			(type solid)
		)
		(fill yes)
		(layer "In13.Cu")
		(net "M_B_CPU0_SA_CA<2>")
	)
	(gr_poly
		(pts
			(xy 336.321146 -250.356116) (xy 336.22107 -250.25604) (xy 336.120994 -250.356116) (xy 336.120994 -250.400566)
			(xy 336.321146 -250.400566)
		)
		(stroke
			(width 0)
			(type solid)
		)
		(fill yes)
		(layer "In13.Cu")
		(net "M_B_CPU0_ALERT_R_N")
	)
	(gr_poly
		(pts
			(xy 336.321146 -248.736104) (xy 336.22107 -248.636028) (xy 336.120994 -248.736104) (xy 336.120994 -248.780554)
			(xy 336.321146 -248.780554)
		)
		(stroke
			(width 0)
			(type solid)
		)
		(fill yes)
		(layer "In13.Cu")
		(net "M_B_CPU0_SA_CB<5>")
	)
	(gr_poly
		(pts
			(xy 336.321146 -247.115838) (xy 336.22107 -247.016016) (xy 336.120994 -247.115838) (xy 336.120994 -247.16359)
			(xy 336.321146 -247.16359)
		)
		(stroke
			(width 0)
			(type solid)
		)
		(fill yes)
		(layer "In13.Cu")
		(net "M_B_CPU0_SA_DQS_DN<9>")
	)
	(gr_poly
		(pts
			(xy 336.321146 -245.49608) (xy 336.22107 -245.396004) (xy 336.120994 -245.49608) (xy 336.120994 -245.54053)
			(xy 336.321146 -245.54053)
		)
		(stroke
			(width 0)
			(type solid)
		)
		(fill yes)
		(layer "In13.Cu")
		(net "M_B_CPU0_SA_CB<1>")
	)
	(gr_poly
		(pts
			(xy 336.321146 -243.876068) (xy 336.22107 -243.775992) (xy 336.120994 -243.876068) (xy 336.120994 -243.920518)
			(xy 336.321146 -243.920518)
		)
		(stroke
			(width 0)
			(type solid)
		)
		(fill yes)
		(layer "In13.Cu")
		(net "M_B_CPU0_SA_DQ<29>")
	)
	(gr_poly
		(pts
			(xy 336.321146 -242.255802) (xy 336.22107 -242.15598) (xy 336.120994 -242.255802) (xy 336.120994 -242.303554)
			(xy 336.321146 -242.303554)
		)
		(stroke
			(width 0)
			(type solid)
		)
		(fill yes)
		(layer "In13.Cu")
		(net "M_B_CPU0_SA_DQS_DN<8>")
	)
	(gr_poly
		(pts
			(xy 336.321146 -240.636044) (xy 336.22107 -240.535968) (xy 336.120994 -240.636044) (xy 336.120994 -240.680494)
			(xy 336.321146 -240.680494)
		)
		(stroke
			(width 0)
			(type solid)
		)
		(fill yes)
		(layer "In13.Cu")
		(net "M_B_CPU0_SA_DQ<25>")
	)
	(gr_poly
		(pts
			(xy 336.321146 -239.016032) (xy 336.22107 -238.915956) (xy 336.120994 -239.016032) (xy 336.120994 -239.060482)
			(xy 336.321146 -239.060482)
		)
		(stroke
			(width 0)
			(type solid)
		)
		(fill yes)
		(layer "In13.Cu")
		(net "M_B_CPU0_SA_DQ<21>")
	)
	(gr_poly
		(pts
			(xy 336.321146 -237.395766) (xy 336.22107 -237.295944) (xy 336.120994 -237.395766) (xy 336.120994 -237.443518)
			(xy 336.321146 -237.443518)
		)
		(stroke
			(width 0)
			(type solid)
		)
		(fill yes)
		(layer "In13.Cu")
		(net "M_B_CPU0_SA_DQS_DN<7>")
	)
	(gr_poly
		(pts
			(xy 336.321146 -235.776008) (xy 336.22107 -235.675932) (xy 336.120994 -235.776008) (xy 336.120994 -235.820458)
			(xy 336.321146 -235.820458)
		)
		(stroke
			(width 0)
			(type solid)
		)
		(fill yes)
		(layer "In13.Cu")
		(net "M_B_CPU0_SA_DQ<17>")
	)
	(gr_poly
		(pts
			(xy 336.321146 -234.155996) (xy 336.22107 -234.05592) (xy 336.120994 -234.155996) (xy 336.120994 -234.200446)
			(xy 336.321146 -234.200446)
		)
		(stroke
			(width 0)
			(type solid)
		)
		(fill yes)
		(layer "In13.Cu")
		(net "M_B_CPU0_SA_DQ<13>")
	)
	(gr_poly
		(pts
			(xy 336.321146 -232.53573) (xy 336.22107 -232.435908) (xy 336.120994 -232.53573) (xy 336.120994 -232.583482)
			(xy 336.321146 -232.583482)
		)
		(stroke
			(width 0)
			(type solid)
		)
		(fill yes)
		(layer "In13.Cu")
		(net "M_B_CPU0_SA_DQS_DN<6>")
	)
	(gr_poly
		(pts
			(xy 336.321146 -230.915972) (xy 336.22107 -230.815896) (xy 336.120994 -230.915972) (xy 336.120994 -230.960422)
			(xy 336.321146 -230.960422)
		)
		(stroke
			(width 0)
			(type solid)
		)
		(fill yes)
		(layer "In13.Cu")
		(net "M_B_CPU0_SA_DQ<9>")
	)
	(gr_poly
		(pts
			(xy 336.321146 -229.29596) (xy 336.22107 -229.195884) (xy 336.120994 -229.29596) (xy 336.120994 -229.34041)
			(xy 336.321146 -229.34041)
		)
		(stroke
			(width 0)
			(type solid)
		)
		(fill yes)
		(layer "In13.Cu")
		(net "M_B_CPU0_SA_DQ<5>")
	)
	(gr_poly
		(pts
			(xy 336.321146 -226.05619) (xy 336.22107 -225.956114) (xy 336.120994 -226.05619) (xy 336.120994 -226.10064)
			(xy 336.321146 -226.10064)
		)
		(stroke
			(width 0)
			(type solid)
		)
		(fill yes)
		(layer "In13.Cu")
		(net "M_B_CPU0_SA_DQ<1>")
	)
	(gr_poly
		(pts
			(xy 336.327242 -227.676456) (xy 336.227166 -227.57638) (xy 336.12709 -227.676456) (xy 336.12709 -227.723954)
			(xy 336.327242 -227.723954)
		)
		(stroke
			(width 0)
			(type solid)
		)
		(fill yes)
		(layer "In13.Cu")
		(net "M_B_CPU0_SA_DQS_DN<5>")
	)
	(gr_poly
		(pts
			(xy 336.62112 -293.324026) (xy 336.62112 -293.279576) (xy 336.420968 -293.279576) (xy 336.420968 -293.324026)
			(xy 336.521044 -293.424102)
		)
		(stroke
			(width 0)
			(type solid)
		)
		(fill yes)
		(layer "In13.Cu")
		(net "M_B_CPU0_SB_DQ<31>")
	)
	(gr_poly
		(pts
			(xy 336.62112 -291.704268) (xy 336.62112 -291.656516) (xy 336.420968 -291.656516) (xy 336.420968 -291.704268)
			(xy 336.521044 -291.80409)
		)
		(stroke
			(width 0)
			(type solid)
		)
		(fill yes)
		(layer "In13.Cu")
		(net "M_B_CPU0_SB_DQS_DP<8>")
	)
	(gr_poly
		(pts
			(xy 336.62112 -290.084002) (xy 336.62112 -290.039552) (xy 336.420968 -290.039552) (xy 336.420968 -290.084002)
			(xy 336.521044 -290.184078)
		)
		(stroke
			(width 0)
			(type solid)
		)
		(fill yes)
		(layer "In13.Cu")
		(net "M_B_CPU0_SB_DQ<27>")
	)
	(gr_poly
		(pts
			(xy 336.62112 -288.464244) (xy 336.62112 -288.419794) (xy 336.420968 -288.419794) (xy 336.420968 -288.464244)
			(xy 336.521044 -288.56432)
		)
		(stroke
			(width 0)
			(type solid)
		)
		(fill yes)
		(layer "In13.Cu")
		(net "M_B_CPU0_SB_DQ<23>")
	)
	(gr_poly
		(pts
			(xy 336.62112 -286.844232) (xy 336.62112 -286.79648) (xy 336.420968 -286.79648) (xy 336.420968 -286.844232)
			(xy 336.521044 -286.944308)
		)
		(stroke
			(width 0)
			(type solid)
		)
		(fill yes)
		(layer "In13.Cu")
		(net "M_B_CPU0_SB_DQS_DP<7>")
	)
	(gr_poly
		(pts
			(xy 336.62112 -285.22422) (xy 336.62112 -285.17977) (xy 336.420968 -285.17977) (xy 336.420968 -285.22422)
			(xy 336.521044 -285.324296)
		)
		(stroke
			(width 0)
			(type solid)
		)
		(fill yes)
		(layer "In13.Cu")
		(net "M_B_CPU0_SB_DQ<19>")
	)
	(gr_poly
		(pts
			(xy 336.62112 -283.604208) (xy 336.62112 -283.559758) (xy 336.420968 -283.559758) (xy 336.420968 -283.604208)
			(xy 336.521044 -283.704284)
		)
		(stroke
			(width 0)
			(type solid)
		)
		(fill yes)
		(layer "In13.Cu")
		(net "M_B_CPU0_SB_DQ<15>")
	)
	(gr_poly
		(pts
			(xy 336.62112 -281.98445) (xy 336.62112 -281.936698) (xy 336.420968 -281.936698) (xy 336.420968 -281.98445)
			(xy 336.521044 -282.084272)
		)
		(stroke
			(width 0)
			(type solid)
		)
		(fill yes)
		(layer "In13.Cu")
		(net "M_B_CPU0_SB_DQS_DP<6>")
	)
	(gr_poly
		(pts
			(xy 336.62112 -280.364184) (xy 336.62112 -280.319734) (xy 336.420968 -280.319734) (xy 336.420968 -280.364184)
			(xy 336.521044 -280.46426)
		)
		(stroke
			(width 0)
			(type solid)
		)
		(fill yes)
		(layer "In13.Cu")
		(net "M_B_CPU0_SB_DQ<11>")
	)
	(gr_poly
		(pts
			(xy 336.62112 -278.744172) (xy 336.62112 -278.699722) (xy 336.420968 -278.699722) (xy 336.420968 -278.744172)
			(xy 336.521044 -278.844248)
		)
		(stroke
			(width 0)
			(type solid)
		)
		(fill yes)
		(layer "In13.Cu")
		(net "M_B_CPU0_SB_DQ<7>")
	)
	(gr_poly
		(pts
			(xy 336.62112 -275.504148) (xy 336.62112 -275.459698) (xy 336.420968 -275.459698) (xy 336.420968 -275.504148)
			(xy 336.521044 -275.604224)
		)
		(stroke
			(width 0)
			(type solid)
		)
		(fill yes)
		(layer "In13.Cu")
		(net "M_B_CPU0_SB_DQ<3>")
	)
	(gr_poly
		(pts
			(xy 336.62112 -273.884136) (xy 336.62112 -273.839686) (xy 336.420968 -273.839686) (xy 336.420968 -273.884136)
			(xy 336.521044 -273.984212)
		)
		(stroke
			(width 0)
			(type solid)
		)
		(fill yes)
		(layer "In13.Cu")
		(net "M_B_CPU0_SB_CB<3>")
	)
	(gr_poly
		(pts
			(xy 336.62112 -272.264378) (xy 336.62112 -272.216626) (xy 336.420968 -272.216626) (xy 336.420968 -272.264378)
			(xy 336.521044 -272.3642)
		)
		(stroke
			(width 0)
			(type solid)
		)
		(fill yes)
		(layer "In13.Cu")
		(net "M_B_CPU0_SB_DQS_DP<4>")
	)
	(gr_poly
		(pts
			(xy 336.62112 -270.644112) (xy 336.62112 -270.599662) (xy 336.420968 -270.599662) (xy 336.420968 -270.644112)
			(xy 336.521044 -270.744188)
		)
		(stroke
			(width 0)
			(type solid)
		)
		(fill yes)
		(layer "In13.Cu")
		(net "M_B_CPU0_SB_CB<7>")
	)
	(gr_poly
		(pts
			(xy 336.62112 -265.784076) (xy 336.62112 -265.739626) (xy 336.420968 -265.739626) (xy 336.420968 -265.784076)
			(xy 336.521044 -265.884152)
		)
		(stroke
			(width 0)
			(type solid)
		)
		(fill yes)
		(layer "In13.Cu")
		(net "M_B_CPU0_SB_CS_N<0>")
	)
	(gr_poly
		(pts
			(xy 336.62112 -264.164064) (xy 336.62112 -264.119614) (xy 336.420968 -264.119614) (xy 336.420968 -264.164064)
			(xy 336.521044 -264.26414)
		)
		(stroke
			(width 0)
			(type solid)
		)
		(fill yes)
		(layer "In13.Cu")
		(net "M_B_CPU0_SB_CA<5>")
	)
	(gr_poly
		(pts
			(xy 336.62112 -262.544052) (xy 336.62112 -262.499602) (xy 336.420968 -262.499602) (xy 336.420968 -262.544052)
			(xy 336.521044 -262.644128)
		)
		(stroke
			(width 0)
			(type solid)
		)
		(fill yes)
		(layer "In13.Cu")
		(net "M_B_CPU0_SB_CA<1>")
	)
	(gr_poly
		(pts
			(xy 336.628486 -277.12416) (xy 336.628486 -277.076662) (xy 336.428334 -277.076662) (xy 336.428334 -277.12416)
			(xy 336.52841 -277.224236)
		)
		(stroke
			(width 0)
			(type solid)
		)
		(fill yes)
		(layer "In13.Cu")
		(net "M_B_CPU0_SB_DQS_DP<5>")
	)
	(gr_poly
		(pts
			(xy 336.7913 -255.622298) (xy 336.7913 -255.577848) (xy 336.591148 -255.577848) (xy 336.591148 -255.622298)
			(xy 336.691224 -255.722374)
		)
		(stroke
			(width 0)
			(type solid)
		)
		(fill yes)
		(layer "In13.Cu")
		(net "M_B_CPU0_SA_PAR")
	)
	(gr_poly
		(pts
			(xy 336.7913 -254.002286) (xy 336.7913 -253.957836) (xy 336.591148 -253.957836) (xy 336.591148 -254.002286)
			(xy 336.691224 -254.102362)
		)
		(stroke
			(width 0)
			(type solid)
		)
		(fill yes)
		(layer "In13.Cu")
		(net "M_B_CPU0_SA_CA<3>")
	)
	(gr_poly
		(pts
			(xy 336.7913 -252.382274) (xy 336.7913 -252.337824) (xy 336.591148 -252.337824) (xy 336.591148 -252.382274)
			(xy 336.691224 -252.48235)
		)
		(stroke
			(width 0)
			(type solid)
		)
		(fill yes)
		(layer "In13.Cu")
		(net "M_B_CPU0_SA_CS_N<1>")
	)
	(gr_poly
		(pts
			(xy 336.7913 -250.762262) (xy 336.7913 -250.717812) (xy 336.591148 -250.717812) (xy 336.591148 -250.762262)
			(xy 336.691224 -250.862338)
		)
		(stroke
			(width 0)
			(type solid)
		)
		(fill yes)
		(layer "In13.Cu")
		(net "M_B_CPU0_RESET_N")
	)
	(gr_poly
		(pts
			(xy 336.7913 -249.14225) (xy 336.7913 -249.0978) (xy 336.591148 -249.0978) (xy 336.591148 -249.14225)
			(xy 336.691224 -249.242326)
		)
		(stroke
			(width 0)
			(type solid)
		)
		(fill yes)
		(layer "In13.Cu")
		(net "M_B_CPU0_SA_CB<7>")
	)
	(gr_poly
		(pts
			(xy 336.7913 -247.522492) (xy 336.7913 -247.47474) (xy 336.591148 -247.47474) (xy 336.591148 -247.522492)
			(xy 336.691224 -247.622314)
		)
		(stroke
			(width 0)
			(type solid)
		)
		(fill yes)
		(layer "In13.Cu")
		(net "M_B_CPU0_SA_DQS_DP<9>")
	)
	(gr_poly
		(pts
			(xy 336.7913 -245.902226) (xy 336.7913 -245.857776) (xy 336.591148 -245.857776) (xy 336.591148 -245.902226)
			(xy 336.691224 -246.002302)
		)
		(stroke
			(width 0)
			(type solid)
		)
		(fill yes)
		(layer "In13.Cu")
		(net "M_B_CPU0_SA_CB<3>")
	)
	(gr_poly
		(pts
			(xy 336.7913 -244.282214) (xy 336.7913 -244.237764) (xy 336.591148 -244.237764) (xy 336.591148 -244.282214)
			(xy 336.691224 -244.38229)
		)
		(stroke
			(width 0)
			(type solid)
		)
		(fill yes)
		(layer "In13.Cu")
		(net "M_B_CPU0_SA_DQ<31>")
	)
	(gr_poly
		(pts
			(xy 336.7913 -242.662456) (xy 336.7913 -242.614704) (xy 336.591148 -242.614704) (xy 336.591148 -242.662456)
			(xy 336.691224 -242.762278)
		)
		(stroke
			(width 0)
			(type solid)
		)
		(fill yes)
		(layer "In13.Cu")
		(net "M_B_CPU0_SA_DQS_DP<8>")
	)
	(gr_poly
		(pts
			(xy 336.7913 -241.04219) (xy 336.7913 -240.99774) (xy 336.591148 -240.99774) (xy 336.591148 -241.04219)
			(xy 336.691224 -241.142266)
		)
		(stroke
			(width 0)
			(type solid)
		)
		(fill yes)
		(layer "In13.Cu")
		(net "M_B_CPU0_SA_DQ<27>")
	)
	(gr_poly
		(pts
			(xy 336.7913 -239.422178) (xy 336.7913 -239.377728) (xy 336.591148 -239.377728) (xy 336.591148 -239.422178)
			(xy 336.691224 -239.522254)
		)
		(stroke
			(width 0)
			(type solid)
		)
		(fill yes)
		(layer "In13.Cu")
		(net "M_B_CPU0_SA_DQ<23>")
	)
	(gr_poly
		(pts
			(xy 336.7913 -237.80242) (xy 336.7913 -237.754668) (xy 336.591148 -237.754668) (xy 336.591148 -237.80242)
			(xy 336.691224 -237.902242)
		)
		(stroke
			(width 0)
			(type solid)
		)
		(fill yes)
		(layer "In13.Cu")
		(net "M_B_CPU0_SA_DQS_DP<7>")
	)
	(gr_poly
		(pts
			(xy 336.7913 -236.182154) (xy 336.7913 -236.137704) (xy 336.591148 -236.137704) (xy 336.591148 -236.182154)
			(xy 336.691224 -236.28223)
		)
		(stroke
			(width 0)
			(type solid)
		)
		(fill yes)
		(layer "In13.Cu")
		(net "M_B_CPU0_SA_DQ<19>")
	)
	(gr_poly
		(pts
			(xy 336.7913 -234.562142) (xy 336.7913 -234.517692) (xy 336.591148 -234.517692) (xy 336.591148 -234.562142)
			(xy 336.691224 -234.662218)
		)
		(stroke
			(width 0)
			(type solid)
		)
		(fill yes)
		(layer "In13.Cu")
		(net "M_B_CPU0_SA_DQ<15>")
	)
	(gr_poly
		(pts
			(xy 336.7913 -232.942384) (xy 336.7913 -232.894632) (xy 336.591148 -232.894632) (xy 336.591148 -232.942384)
			(xy 336.691224 -233.042206)
		)
		(stroke
			(width 0)
			(type solid)
		)
		(fill yes)
		(layer "In13.Cu")
		(net "M_B_CPU0_SA_DQS_DP<6>")
	)
	(gr_poly
		(pts
			(xy 336.7913 -231.322372) (xy 336.7913 -231.277922) (xy 336.591148 -231.277922) (xy 336.591148 -231.322372)
			(xy 336.691224 -231.422448)
		)
		(stroke
			(width 0)
			(type solid)
		)
		(fill yes)
		(layer "In13.Cu")
		(net "M_B_CPU0_SA_DQ<11>")
	)
	(gr_poly
		(pts
			(xy 336.7913 -229.70236) (xy 336.7913 -229.65791) (xy 336.591148 -229.65791) (xy 336.591148 -229.70236)
			(xy 336.691224 -229.802436)
		)
		(stroke
			(width 0)
			(type solid)
		)
		(fill yes)
		(layer "In13.Cu")
		(net "M_B_CPU0_SA_DQ<7>")
	)
	(gr_poly
		(pts
			(xy 336.7913 -228.082602) (xy 336.7913 -228.03485) (xy 336.591148 -228.03485) (xy 336.591148 -228.082602)
			(xy 336.691224 -228.182424)
		)
		(stroke
			(width 0)
			(type solid)
		)
		(fill yes)
		(layer "In13.Cu")
		(net "M_B_CPU0_SA_DQS_DP<5>")
	)
	(gr_poly
		(pts
			(xy 336.7913 -226.462336) (xy 336.7913 -226.417886) (xy 336.591148 -226.417886) (xy 336.591148 -226.462336)
			(xy 336.691224 -226.562412)
		)
		(stroke
			(width 0)
			(type solid)
		)
		(fill yes)
		(layer "In13.Cu")
		(net "M_B_CPU0_SA_DQ<3>")
	)
	(gr_poly
		(pts
			(xy 337.084924 -266.991592) (xy 336.984848 -266.891516) (xy 336.885026 -266.991592) (xy 336.885026 -267.036042)
			(xy 337.084924 -267.036042)
		)
		(stroke
			(width 0)
			(type solid)
		)
		(fill yes)
		(layer "In13.Cu")
		(net "M_B_CPU0_SA_RSP<0>")
	)
	(gr_poly
		(pts
			(xy 337.091274 -292.91788) (xy 336.991198 -292.817804) (xy 336.891122 -292.91788) (xy 336.891122 -292.96233)
			(xy 337.091274 -292.96233)
		)
		(stroke
			(width 0)
			(type solid)
		)
		(fill yes)
		(layer "In13.Cu")
		(net "M_B_CPU0_SB_DQ<29>")
	)
	(gr_poly
		(pts
			(xy 337.091274 -291.297614) (xy 336.991198 -291.197792) (xy 336.891122 -291.297614) (xy 336.891122 -291.345366)
			(xy 337.091274 -291.345366)
		)
		(stroke
			(width 0)
			(type solid)
		)
		(fill yes)
		(layer "In13.Cu")
		(net "M_B_CPU0_SB_DQS_DN<8>")
	)
	(gr_poly
		(pts
			(xy 337.091274 -289.677856) (xy 336.991198 -289.57778) (xy 336.891122 -289.677856) (xy 336.891122 -289.722306)
			(xy 337.091274 -289.722306)
		)
		(stroke
			(width 0)
			(type solid)
		)
		(fill yes)
		(layer "In13.Cu")
		(net "M_B_CPU0_SB_DQ<25>")
	)
	(gr_poly
		(pts
			(xy 337.091274 -288.057844) (xy 336.991198 -287.957768) (xy 336.891122 -288.057844) (xy 336.891122 -288.102294)
			(xy 337.091274 -288.102294)
		)
		(stroke
			(width 0)
			(type solid)
		)
		(fill yes)
		(layer "In13.Cu")
		(net "M_B_CPU0_SB_DQ<21>")
	)
	(gr_poly
		(pts
			(xy 337.091274 -286.437832) (xy 336.991198 -286.337756) (xy 336.891122 -286.437832) (xy 336.891122 -286.485584)
			(xy 337.091274 -286.485584)
		)
		(stroke
			(width 0)
			(type solid)
		)
		(fill yes)
		(layer "In13.Cu")
		(net "M_B_CPU0_SB_DQS_DN<7>")
	)
	(gr_poly
		(pts
			(xy 337.091274 -284.818074) (xy 336.991198 -284.717998) (xy 336.891122 -284.818074) (xy 336.891122 -284.862524)
			(xy 337.091274 -284.862524)
		)
		(stroke
			(width 0)
			(type solid)
		)
		(fill yes)
		(layer "In13.Cu")
		(net "M_B_CPU0_SB_DQ<17>")
	)
	(gr_poly
		(pts
			(xy 337.091274 -283.198062) (xy 336.991198 -283.097986) (xy 336.891122 -283.198062) (xy 336.891122 -283.242512)
			(xy 337.091274 -283.242512)
		)
		(stroke
			(width 0)
			(type solid)
		)
		(fill yes)
		(layer "In13.Cu")
		(net "M_B_CPU0_SB_DQ<13>")
	)
	(gr_poly
		(pts
			(xy 337.091274 -281.577796) (xy 336.991198 -281.477974) (xy 336.891122 -281.577796) (xy 336.891122 -281.625548)
			(xy 337.091274 -281.625548)
		)
		(stroke
			(width 0)
			(type solid)
		)
		(fill yes)
		(layer "In13.Cu")
		(net "M_B_CPU0_SB_DQS_DN<6>")
	)
	(gr_poly
		(pts
			(xy 337.091274 -279.958038) (xy 336.991198 -279.857962) (xy 336.891122 -279.958038) (xy 336.891122 -280.002488)
			(xy 337.091274 -280.002488)
		)
		(stroke
			(width 0)
			(type solid)
		)
		(fill yes)
		(layer "In13.Cu")
		(net "M_B_CPU0_SB_DQ<9>")
	)
	(gr_poly
		(pts
			(xy 337.091274 -278.338026) (xy 336.991198 -278.23795) (xy 336.891122 -278.338026) (xy 336.891122 -278.382476)
			(xy 337.091274 -278.382476)
		)
		(stroke
			(width 0)
			(type solid)
		)
		(fill yes)
		(layer "In13.Cu")
		(net "M_B_CPU0_SB_DQ<5>")
	)
	(gr_poly
		(pts
			(xy 337.091274 -276.71776) (xy 336.991198 -276.617938) (xy 336.891122 -276.71776) (xy 336.891122 -276.765512)
			(xy 337.091274 -276.765512)
		)
		(stroke
			(width 0)
			(type solid)
		)
		(fill yes)
		(layer "In13.Cu")
		(net "M_B_CPU0_SB_DQS_DN<5>")
	)
	(gr_poly
		(pts
			(xy 337.091274 -275.098002) (xy 336.991198 -274.997926) (xy 336.891122 -275.098002) (xy 336.891122 -275.142452)
			(xy 337.091274 -275.142452)
		)
		(stroke
			(width 0)
			(type solid)
		)
		(fill yes)
		(layer "In13.Cu")
		(net "M_B_CPU0_SB_DQ<1>")
	)
	(gr_poly
		(pts
			(xy 337.091274 -273.47799) (xy 336.991198 -273.377914) (xy 336.891122 -273.47799) (xy 336.891122 -273.52244)
			(xy 337.091274 -273.52244)
		)
		(stroke
			(width 0)
			(type solid)
		)
		(fill yes)
		(layer "In13.Cu")
		(net "M_B_CPU0_SB_CB<1>")
	)
	(gr_poly
		(pts
			(xy 337.091274 -271.857724) (xy 336.991198 -271.757902) (xy 336.891122 -271.857724) (xy 336.891122 -271.905476)
			(xy 337.091274 -271.905476)
		)
		(stroke
			(width 0)
			(type solid)
		)
		(fill yes)
		(layer "In13.Cu")
		(net "M_B_CPU0_SB_DQS_DN<4>")
	)
	(gr_poly
		(pts
			(xy 337.091274 -270.237966) (xy 336.991198 -270.13789) (xy 336.891122 -270.237966) (xy 336.891122 -270.282416)
			(xy 337.091274 -270.282416)
		)
		(stroke
			(width 0)
			(type solid)
		)
		(fill yes)
		(layer "In13.Cu")
		(net "M_B_CPU0_SB_CB<5>")
	)
	(gr_poly
		(pts
			(xy 337.091274 -263.757918) (xy 336.991198 -263.657842) (xy 336.891122 -263.757918) (xy 336.891122 -263.802368)
			(xy 337.091274 -263.802368)
		)
		(stroke
			(width 0)
			(type solid)
		)
		(fill yes)
		(layer "In13.Cu")
		(net "M_B_CPU0_SB_CA<4>")
	)
	(gr_poly
		(pts
			(xy 337.091274 -262.137906) (xy 336.991198 -262.03783) (xy 336.891122 -262.137906) (xy 336.891122 -262.182356)
			(xy 337.091274 -262.182356)
		)
		(stroke
			(width 0)
			(type solid)
		)
		(fill yes)
		(layer "In13.Cu")
		(net "M_B_CPU0_SB_CA<0>")
	)
	(gr_poly
		(pts
			(xy 382.844802 -255.622298) (xy 382.844802 -255.577848) (xy 382.64465 -255.577848) (xy 382.64465 -255.622298)
			(xy 382.744726 -255.722374)
		)
		(stroke
			(width 0)
			(type solid)
		)
		(fill yes)
		(layer "In13.Cu")
		(net "M_H_CPU0_SA_PAR")
	)
	(gr_poly
		(pts
			(xy 382.844802 -254.002286) (xy 382.844802 -253.957836) (xy 382.64465 -253.957836) (xy 382.64465 -254.002286)
			(xy 382.744726 -254.102362)
		)
		(stroke
			(width 0)
			(type solid)
		)
		(fill yes)
		(layer "In13.Cu")
		(net "M_H_CPU0_SA_CA<3>")
	)
	(gr_poly
		(pts
			(xy 382.844802 -250.762262) (xy 382.844802 -250.717812) (xy 382.64465 -250.717812) (xy 382.64465 -250.762262)
			(xy 382.744726 -250.862338)
		)
		(stroke
			(width 0)
			(type solid)
		)
		(fill yes)
		(layer "In13.Cu")
		(net "M_H_CPU0_RESET_N")
	)
	(gr_poly
		(pts
			(xy 382.844802 -249.14225) (xy 382.844802 -249.0978) (xy 382.64465 -249.0978) (xy 382.64465 -249.14225)
			(xy 382.744726 -249.242326)
		)
		(stroke
			(width 0)
			(type solid)
		)
		(fill yes)
		(layer "In13.Cu")
		(net "M_H_CPU0_SA_CB<7>")
	)
	(gr_poly
		(pts
			(xy 382.844802 -247.522492) (xy 382.844802 -247.47474) (xy 382.64465 -247.47474) (xy 382.64465 -247.522492)
			(xy 382.744726 -247.622314)
		)
		(stroke
			(width 0)
			(type solid)
		)
		(fill yes)
		(layer "In13.Cu")
		(net "M_H_CPU0_SA_DQS_DP<9>")
	)
	(gr_poly
		(pts
			(xy 382.844802 -245.902226) (xy 382.844802 -245.857776) (xy 382.64465 -245.857776) (xy 382.64465 -245.902226)
			(xy 382.744726 -246.002302)
		)
		(stroke
			(width 0)
			(type solid)
		)
		(fill yes)
		(layer "In13.Cu")
		(net "M_H_CPU0_SA_CB<3>")
	)
	(gr_poly
		(pts
			(xy 382.844802 -244.282214) (xy 382.844802 -244.237764) (xy 382.64465 -244.237764) (xy 382.64465 -244.282214)
			(xy 382.744726 -244.38229)
		)
		(stroke
			(width 0)
			(type solid)
		)
		(fill yes)
		(layer "In13.Cu")
		(net "M_H_CPU0_SA_DQ<31>")
	)
	(gr_poly
		(pts
			(xy 382.844802 -242.662456) (xy 382.844802 -242.614704) (xy 382.64465 -242.614704) (xy 382.64465 -242.662456)
			(xy 382.744726 -242.762278)
		)
		(stroke
			(width 0)
			(type solid)
		)
		(fill yes)
		(layer "In13.Cu")
		(net "M_H_CPU0_SA_DQS_DP<8>")
	)
	(gr_poly
		(pts
			(xy 382.844802 -241.04219) (xy 382.844802 -240.99774) (xy 382.64465 -240.99774) (xy 382.64465 -241.04219)
			(xy 382.744726 -241.142266)
		)
		(stroke
			(width 0)
			(type solid)
		)
		(fill yes)
		(layer "In13.Cu")
		(net "M_H_CPU0_SA_DQ<27>")
	)
	(gr_poly
		(pts
			(xy 382.844802 -239.422178) (xy 382.844802 -239.377728) (xy 382.64465 -239.377728) (xy 382.64465 -239.422178)
			(xy 382.744726 -239.522254)
		)
		(stroke
			(width 0)
			(type solid)
		)
		(fill yes)
		(layer "In13.Cu")
		(net "M_H_CPU0_SA_DQ<23>")
	)
	(gr_poly
		(pts
			(xy 382.844802 -237.80242) (xy 382.844802 -237.754668) (xy 382.64465 -237.754668) (xy 382.64465 -237.80242)
			(xy 382.744726 -237.902242)
		)
		(stroke
			(width 0)
			(type solid)
		)
		(fill yes)
		(layer "In13.Cu")
		(net "M_H_CPU0_SA_DQS_DP<7>")
	)
	(gr_poly
		(pts
			(xy 382.844802 -236.182154) (xy 382.844802 -236.137704) (xy 382.64465 -236.137704) (xy 382.64465 -236.182154)
			(xy 382.744726 -236.28223)
		)
		(stroke
			(width 0)
			(type solid)
		)
		(fill yes)
		(layer "In13.Cu")
		(net "M_H_CPU0_SA_DQ<19>")
	)
	(gr_poly
		(pts
			(xy 382.844802 -234.562142) (xy 382.844802 -234.517692) (xy 382.64465 -234.517692) (xy 382.64465 -234.562142)
			(xy 382.744726 -234.662218)
		)
		(stroke
			(width 0)
			(type solid)
		)
		(fill yes)
		(layer "In13.Cu")
		(net "M_H_CPU0_SA_DQ<15>")
	)
	(gr_poly
		(pts
			(xy 382.844802 -232.942384) (xy 382.844802 -232.894632) (xy 382.64465 -232.894632) (xy 382.64465 -232.942384)
			(xy 382.744726 -233.042206)
		)
		(stroke
			(width 0)
			(type solid)
		)
		(fill yes)
		(layer "In13.Cu")
		(net "M_H_CPU0_SA_DQS_DP<6>")
	)
	(gr_poly
		(pts
			(xy 382.844802 -231.322372) (xy 382.844802 -231.277922) (xy 382.64465 -231.277922) (xy 382.64465 -231.322372)
			(xy 382.744726 -231.422448)
		)
		(stroke
			(width 0)
			(type solid)
		)
		(fill yes)
		(layer "In13.Cu")
		(net "M_H_CPU0_SA_DQ<11>")
	)
	(gr_poly
		(pts
			(xy 382.844802 -229.70236) (xy 382.844802 -229.65791) (xy 382.64465 -229.65791) (xy 382.64465 -229.70236)
			(xy 382.744726 -229.802436)
		)
		(stroke
			(width 0)
			(type solid)
		)
		(fill yes)
		(layer "In13.Cu")
		(net "M_H_CPU0_SA_DQ<7>")
	)
	(gr_poly
		(pts
			(xy 382.844802 -228.082602) (xy 382.844802 -228.03485) (xy 382.64465 -228.03485) (xy 382.64465 -228.082602)
			(xy 382.744726 -228.182424)
		)
		(stroke
			(width 0)
			(type solid)
		)
		(fill yes)
		(layer "In13.Cu")
		(net "M_H_CPU0_SA_DQS_DP<5>")
	)
	(gr_poly
		(pts
			(xy 382.844802 -226.462336) (xy 382.844802 -226.417886) (xy 382.64465 -226.417886) (xy 382.64465 -226.462336)
			(xy 382.744726 -226.562412)
		)
		(stroke
			(width 0)
			(type solid)
		)
		(fill yes)
		(layer "In13.Cu")
		(net "M_H_CPU0_SA_DQ<3>")
	)
	(gr_poly
		(pts
			(xy 383.144776 -292.91788) (xy 383.0447 -292.817804) (xy 382.944624 -292.91788) (xy 382.944624 -292.96233)
			(xy 383.144776 -292.96233)
		)
		(stroke
			(width 0)
			(type solid)
		)
		(fill yes)
		(layer "In13.Cu")
		(net "M_H_CPU0_SB_DQ<29>")
	)
	(gr_poly
		(pts
			(xy 383.144776 -291.297614) (xy 383.0447 -291.197792) (xy 382.944624 -291.297614) (xy 382.944624 -291.345366)
			(xy 383.144776 -291.345366)
		)
		(stroke
			(width 0)
			(type solid)
		)
		(fill yes)
		(layer "In13.Cu")
		(net "M_H_CPU0_SB_DQS_DN<8>")
	)
	(gr_poly
		(pts
			(xy 383.144776 -289.677856) (xy 383.0447 -289.57778) (xy 382.944624 -289.677856) (xy 382.944624 -289.722306)
			(xy 383.144776 -289.722306)
		)
		(stroke
			(width 0)
			(type solid)
		)
		(fill yes)
		(layer "In13.Cu")
		(net "M_H_CPU0_SB_DQ<25>")
	)
	(gr_poly
		(pts
			(xy 383.144776 -288.057844) (xy 383.0447 -287.957768) (xy 382.944624 -288.057844) (xy 382.944624 -288.102294)
			(xy 383.144776 -288.102294)
		)
		(stroke
			(width 0)
			(type solid)
		)
		(fill yes)
		(layer "In13.Cu")
		(net "M_H_CPU0_SB_DQ<21>")
	)
	(gr_poly
		(pts
			(xy 383.144776 -286.437832) (xy 383.0447 -286.337756) (xy 382.944624 -286.437832) (xy 382.944624 -286.485584)
			(xy 383.144776 -286.485584)
		)
		(stroke
			(width 0)
			(type solid)
		)
		(fill yes)
		(layer "In13.Cu")
		(net "M_H_CPU0_SB_DQS_DN<7>")
	)
	(gr_poly
		(pts
			(xy 383.144776 -284.818074) (xy 383.0447 -284.717998) (xy 382.944624 -284.818074) (xy 382.944624 -284.862524)
			(xy 383.144776 -284.862524)
		)
		(stroke
			(width 0)
			(type solid)
		)
		(fill yes)
		(layer "In13.Cu")
		(net "M_H_CPU0_SB_DQ<17>")
	)
	(gr_poly
		(pts
			(xy 383.144776 -283.198062) (xy 383.0447 -283.097986) (xy 382.944624 -283.198062) (xy 382.944624 -283.242512)
			(xy 383.144776 -283.242512)
		)
		(stroke
			(width 0)
			(type solid)
		)
		(fill yes)
		(layer "In13.Cu")
		(net "M_H_CPU0_SB_DQ<13>")
	)
	(gr_poly
		(pts
			(xy 383.144776 -281.577796) (xy 383.0447 -281.477974) (xy 382.944624 -281.577796) (xy 382.944624 -281.625548)
			(xy 383.144776 -281.625548)
		)
		(stroke
			(width 0)
			(type solid)
		)
		(fill yes)
		(layer "In13.Cu")
		(net "M_H_CPU0_SB_DQS_DN<6>")
	)
	(gr_poly
		(pts
			(xy 383.144776 -279.958038) (xy 383.0447 -279.857962) (xy 382.944624 -279.958038) (xy 382.944624 -280.002488)
			(xy 383.144776 -280.002488)
		)
		(stroke
			(width 0)
			(type solid)
		)
		(fill yes)
		(layer "In13.Cu")
		(net "M_H_CPU0_SB_DQ<9>")
	)
	(gr_poly
		(pts
			(xy 383.144776 -278.338026) (xy 383.0447 -278.23795) (xy 382.944624 -278.338026) (xy 382.944624 -278.382476)
			(xy 383.144776 -278.382476)
		)
		(stroke
			(width 0)
			(type solid)
		)
		(fill yes)
		(layer "In13.Cu")
		(net "M_H_CPU0_SB_DQ<5>")
	)
	(gr_poly
		(pts
			(xy 383.144776 -276.71776) (xy 383.0447 -276.617938) (xy 382.944624 -276.71776) (xy 382.944624 -276.765512)
			(xy 383.144776 -276.765512)
		)
		(stroke
			(width 0)
			(type solid)
		)
		(fill yes)
		(layer "In13.Cu")
		(net "M_H_CPU0_SB_DQS_DN<5>")
	)
	(gr_poly
		(pts
			(xy 383.144776 -275.098002) (xy 383.0447 -274.997926) (xy 382.944624 -275.098002) (xy 382.944624 -275.142452)
			(xy 383.144776 -275.142452)
		)
		(stroke
			(width 0)
			(type solid)
		)
		(fill yes)
		(layer "In13.Cu")
		(net "M_H_CPU0_SB_DQ<1>")
	)
	(gr_poly
		(pts
			(xy 383.144776 -273.47799) (xy 383.0447 -273.377914) (xy 382.944624 -273.47799) (xy 382.944624 -273.52244)
			(xy 383.144776 -273.52244)
		)
		(stroke
			(width 0)
			(type solid)
		)
		(fill yes)
		(layer "In13.Cu")
		(net "M_H_CPU0_SB_CB<1>")
	)
	(gr_poly
		(pts
			(xy 383.144776 -271.857724) (xy 383.0447 -271.757902) (xy 382.944624 -271.857724) (xy 382.944624 -271.905476)
			(xy 383.144776 -271.905476)
		)
		(stroke
			(width 0)
			(type solid)
		)
		(fill yes)
		(layer "In13.Cu")
		(net "M_H_CPU0_SB_DQS_DN<4>")
	)
	(gr_poly
		(pts
			(xy 383.144776 -270.237966) (xy 383.0447 -270.13789) (xy 382.944624 -270.237966) (xy 382.944624 -270.282416)
			(xy 383.144776 -270.282416)
		)
		(stroke
			(width 0)
			(type solid)
		)
		(fill yes)
		(layer "In13.Cu")
		(net "M_H_CPU0_SB_CB<5>")
	)
	(gr_poly
		(pts
			(xy 383.144776 -266.997942) (xy 383.0447 -266.897866) (xy 382.944624 -266.997942) (xy 382.944624 -267.042392)
			(xy 383.144776 -267.042392)
		)
		(stroke
			(width 0)
			(type solid)
		)
		(fill yes)
		(layer "In13.Cu")
		(net "M_H_CPU0_SA_RSP<0>")
	)
	(gr_poly
		(pts
			(xy 383.144776 -265.37793) (xy 383.0447 -265.277854) (xy 382.944624 -265.37793) (xy 382.944624 -265.42238)
			(xy 383.144776 -265.42238)
		)
		(stroke
			(width 0)
			(type solid)
		)
		(fill yes)
		(layer "In13.Cu")
		(net "M_H_CPU0_SB_PAR")
	)
	(gr_poly
		(pts
			(xy 383.144776 -263.757918) (xy 383.0447 -263.657842) (xy 382.944624 -263.757918) (xy 382.944624 -263.802368)
			(xy 383.144776 -263.802368)
		)
		(stroke
			(width 0)
			(type solid)
		)
		(fill yes)
		(layer "In13.Cu")
		(net "M_H_CPU0_SB_CA<4>")
	)
	(gr_poly
		(pts
			(xy 383.144776 -262.137906) (xy 383.0447 -262.03783) (xy 382.944624 -262.137906) (xy 382.944624 -262.182356)
			(xy 383.144776 -262.182356)
		)
		(stroke
			(width 0)
			(type solid)
		)
		(fill yes)
		(layer "In13.Cu")
		(net "M_H_CPU0_SB_CA<0>")
	)
	(gr_poly
		(pts
			(xy 383.314956 -255.216152) (xy 383.21488 -255.116076) (xy 383.114804 -255.216152) (xy 383.114804 -255.260602)
			(xy 383.314956 -255.260602)
		)
		(stroke
			(width 0)
			(type solid)
		)
		(fill yes)
		(layer "In13.Cu")
		(net "M_H_CPU0_SA_CA<6>")
	)
	(gr_poly
		(pts
			(xy 383.314956 -253.59614) (xy 383.21488 -253.496064) (xy 383.114804 -253.59614) (xy 383.114804 -253.64059)
			(xy 383.314956 -253.64059)
		)
		(stroke
			(width 0)
			(type solid)
		)
		(fill yes)
		(layer "In13.Cu")
		(net "M_H_CPU0_SA_CA<2>")
	)
	(gr_poly
		(pts
			(xy 383.314956 -251.976128) (xy 383.21488 -251.876052) (xy 383.114804 -251.976128) (xy 383.114804 -252.020578)
			(xy 383.314956 -252.020578)
		)
		(stroke
			(width 0)
			(type solid)
		)
		(fill yes)
		(layer "In13.Cu")
		(net "M_H_CPU0_SA_CS_N<1>")
	)
	(gr_poly
		(pts
			(xy 383.314956 -250.356116) (xy 383.21488 -250.25604) (xy 383.114804 -250.356116) (xy 383.114804 -250.400566)
			(xy 383.314956 -250.400566)
		)
		(stroke
			(width 0)
			(type solid)
		)
		(fill yes)
		(layer "In13.Cu")
		(net "M_H_CPU0_ALERT_R_N")
	)
	(gr_poly
		(pts
			(xy 383.314956 -248.736104) (xy 383.21488 -248.636028) (xy 383.114804 -248.736104) (xy 383.114804 -248.780554)
			(xy 383.314956 -248.780554)
		)
		(stroke
			(width 0)
			(type solid)
		)
		(fill yes)
		(layer "In13.Cu")
		(net "M_H_CPU0_SA_CB<5>")
	)
	(gr_poly
		(pts
			(xy 383.314956 -247.115838) (xy 383.21488 -247.016016) (xy 383.114804 -247.115838) (xy 383.114804 -247.16359)
			(xy 383.314956 -247.16359)
		)
		(stroke
			(width 0)
			(type solid)
		)
		(fill yes)
		(layer "In13.Cu")
		(net "M_H_CPU0_SA_DQS_DN<9>")
	)
	(gr_poly
		(pts
			(xy 383.314956 -245.49608) (xy 383.21488 -245.396004) (xy 383.114804 -245.49608) (xy 383.114804 -245.54053)
			(xy 383.314956 -245.54053)
		)
		(stroke
			(width 0)
			(type solid)
		)
		(fill yes)
		(layer "In13.Cu")
		(net "M_H_CPU0_SA_CB<1>")
	)
	(gr_poly
		(pts
			(xy 383.314956 -243.876068) (xy 383.21488 -243.775992) (xy 383.114804 -243.876068) (xy 383.114804 -243.920518)
			(xy 383.314956 -243.920518)
		)
		(stroke
			(width 0)
			(type solid)
		)
		(fill yes)
		(layer "In13.Cu")
		(net "M_H_CPU0_SA_DQ<29>")
	)
	(gr_poly
		(pts
			(xy 383.314956 -242.255802) (xy 383.21488 -242.15598) (xy 383.114804 -242.255802) (xy 383.114804 -242.303554)
			(xy 383.314956 -242.303554)
		)
		(stroke
			(width 0)
			(type solid)
		)
		(fill yes)
		(layer "In13.Cu")
		(net "M_H_CPU0_SA_DQS_DN<8>")
	)
	(gr_poly
		(pts
			(xy 383.314956 -240.636044) (xy 383.21488 -240.535968) (xy 383.114804 -240.636044) (xy 383.114804 -240.680494)
			(xy 383.314956 -240.680494)
		)
		(stroke
			(width 0)
			(type solid)
		)
		(fill yes)
		(layer "In13.Cu")
		(net "M_H_CPU0_SA_DQ<25>")
	)
	(gr_poly
		(pts
			(xy 383.314956 -239.016032) (xy 383.21488 -238.915956) (xy 383.114804 -239.016032) (xy 383.114804 -239.060482)
			(xy 383.314956 -239.060482)
		)
		(stroke
			(width 0)
			(type solid)
		)
		(fill yes)
		(layer "In13.Cu")
		(net "M_H_CPU0_SA_DQ<21>")
	)
	(gr_poly
		(pts
			(xy 383.314956 -237.395766) (xy 383.21488 -237.295944) (xy 383.114804 -237.395766) (xy 383.114804 -237.443518)
			(xy 383.314956 -237.443518)
		)
		(stroke
			(width 0)
			(type solid)
		)
		(fill yes)
		(layer "In13.Cu")
		(net "M_H_CPU0_SA_DQS_DN<7>")
	)
	(gr_poly
		(pts
			(xy 383.314956 -235.776008) (xy 383.21488 -235.675932) (xy 383.114804 -235.776008) (xy 383.114804 -235.820458)
			(xy 383.314956 -235.820458)
		)
		(stroke
			(width 0)
			(type solid)
		)
		(fill yes)
		(layer "In13.Cu")
		(net "M_H_CPU0_SA_DQ<17>")
	)
	(gr_poly
		(pts
			(xy 383.314956 -234.155996) (xy 383.21488 -234.05592) (xy 383.114804 -234.155996) (xy 383.114804 -234.200446)
			(xy 383.314956 -234.200446)
		)
		(stroke
			(width 0)
			(type solid)
		)
		(fill yes)
		(layer "In13.Cu")
		(net "M_H_CPU0_SA_DQ<13>")
	)
	(gr_poly
		(pts
			(xy 383.314956 -232.53573) (xy 383.21488 -232.435908) (xy 383.114804 -232.53573) (xy 383.114804 -232.583482)
			(xy 383.314956 -232.583482)
		)
		(stroke
			(width 0)
			(type solid)
		)
		(fill yes)
		(layer "In13.Cu")
		(net "M_H_CPU0_SA_DQS_DN<6>")
	)
	(gr_poly
		(pts
			(xy 383.314956 -230.915972) (xy 383.21488 -230.815896) (xy 383.114804 -230.915972) (xy 383.114804 -230.960422)
			(xy 383.314956 -230.960422)
		)
		(stroke
			(width 0)
			(type solid)
		)
		(fill yes)
		(layer "In13.Cu")
		(net "M_H_CPU0_SA_DQ<9>")
	)
	(gr_poly
		(pts
			(xy 383.314956 -229.29596) (xy 383.21488 -229.195884) (xy 383.114804 -229.29596) (xy 383.114804 -229.34041)
			(xy 383.314956 -229.34041)
		)
		(stroke
			(width 0)
			(type solid)
		)
		(fill yes)
		(layer "In13.Cu")
		(net "M_H_CPU0_SA_DQ<5>")
	)
	(gr_poly
		(pts
			(xy 383.314956 -227.675948) (xy 383.21488 -227.576126) (xy 383.114804 -227.675948) (xy 383.114804 -227.7237)
			(xy 383.314956 -227.7237)
		)
		(stroke
			(width 0)
			(type solid)
		)
		(fill yes)
		(layer "In13.Cu")
		(net "M_H_CPU0_SA_DQS_DN<5>")
	)
	(gr_poly
		(pts
			(xy 383.314956 -226.05619) (xy 383.21488 -225.956114) (xy 383.114804 -226.05619) (xy 383.114804 -226.10064)
			(xy 383.314956 -226.10064)
		)
		(stroke
			(width 0)
			(type solid)
		)
		(fill yes)
		(layer "In13.Cu")
		(net "M_H_CPU0_SA_DQ<1>")
	)
	(gr_poly
		(pts
			(xy 383.61493 -293.324026) (xy 383.61493 -293.279576) (xy 383.414778 -293.279576) (xy 383.414778 -293.324026)
			(xy 383.514854 -293.424102)
		)
		(stroke
			(width 0)
			(type solid)
		)
		(fill yes)
		(layer "In13.Cu")
		(net "M_H_CPU0_SB_DQ<31>")
	)
	(gr_poly
		(pts
			(xy 383.61493 -291.704268) (xy 383.61493 -291.656516) (xy 383.414778 -291.656516) (xy 383.414778 -291.704268)
			(xy 383.514854 -291.80409)
		)
		(stroke
			(width 0)
			(type solid)
		)
		(fill yes)
		(layer "In13.Cu")
		(net "M_H_CPU0_SB_DQS_DP<8>")
	)
	(gr_poly
		(pts
			(xy 383.61493 -290.084002) (xy 383.61493 -290.039552) (xy 383.414778 -290.039552) (xy 383.414778 -290.084002)
			(xy 383.514854 -290.184078)
		)
		(stroke
			(width 0)
			(type solid)
		)
		(fill yes)
		(layer "In13.Cu")
		(net "M_H_CPU0_SB_DQ<27>")
	)
	(gr_poly
		(pts
			(xy 383.61493 -288.464244) (xy 383.61493 -288.419794) (xy 383.414778 -288.419794) (xy 383.414778 -288.464244)
			(xy 383.514854 -288.56432)
		)
		(stroke
			(width 0)
			(type solid)
		)
		(fill yes)
		(layer "In13.Cu")
		(net "M_H_CPU0_SB_DQ<23>")
	)
	(gr_poly
		(pts
			(xy 383.61493 -286.844232) (xy 383.61493 -286.79648) (xy 383.414778 -286.79648) (xy 383.414778 -286.844232)
			(xy 383.514854 -286.944308)
		)
		(stroke
			(width 0)
			(type solid)
		)
		(fill yes)
		(layer "In13.Cu")
		(net "M_H_CPU0_SB_DQS_DP<7>")
	)
	(gr_poly
		(pts
			(xy 383.61493 -285.22422) (xy 383.61493 -285.17977) (xy 383.414778 -285.17977) (xy 383.414778 -285.22422)
			(xy 383.514854 -285.324296)
		)
		(stroke
			(width 0)
			(type solid)
		)
		(fill yes)
		(layer "In13.Cu")
		(net "M_H_CPU0_SB_DQ<19>")
	)
	(gr_poly
		(pts
			(xy 383.61493 -283.604208) (xy 383.61493 -283.559758) (xy 383.414778 -283.559758) (xy 383.414778 -283.604208)
			(xy 383.514854 -283.704284)
		)
		(stroke
			(width 0)
			(type solid)
		)
		(fill yes)
		(layer "In13.Cu")
		(net "M_H_CPU0_SB_DQ<15>")
	)
	(gr_poly
		(pts
			(xy 383.61493 -281.98445) (xy 383.61493 -281.936698) (xy 383.414778 -281.936698) (xy 383.414778 -281.98445)
			(xy 383.514854 -282.084272)
		)
		(stroke
			(width 0)
			(type solid)
		)
		(fill yes)
		(layer "In13.Cu")
		(net "M_H_CPU0_SB_DQS_DP<6>")
	)
	(gr_poly
		(pts
			(xy 383.61493 -280.364184) (xy 383.61493 -280.319734) (xy 383.414778 -280.319734) (xy 383.414778 -280.364184)
			(xy 383.514854 -280.46426)
		)
		(stroke
			(width 0)
			(type solid)
		)
		(fill yes)
		(layer "In13.Cu")
		(net "M_H_CPU0_SB_DQ<11>")
	)
	(gr_poly
		(pts
			(xy 383.61493 -278.744172) (xy 383.61493 -278.699722) (xy 383.414778 -278.699722) (xy 383.414778 -278.744172)
			(xy 383.514854 -278.844248)
		)
		(stroke
			(width 0)
			(type solid)
		)
		(fill yes)
		(layer "In13.Cu")
		(net "M_H_CPU0_SB_DQ<7>")
	)
	(gr_poly
		(pts
			(xy 383.61493 -277.124414) (xy 383.61493 -277.076662) (xy 383.414778 -277.076662) (xy 383.414778 -277.124414)
			(xy 383.514854 -277.224236)
		)
		(stroke
			(width 0)
			(type solid)
		)
		(fill yes)
		(layer "In13.Cu")
		(net "M_H_CPU0_SB_DQS_DP<5>")
	)
	(gr_poly
		(pts
			(xy 383.61493 -275.504148) (xy 383.61493 -275.459698) (xy 383.414778 -275.459698) (xy 383.414778 -275.504148)
			(xy 383.514854 -275.604224)
		)
		(stroke
			(width 0)
			(type solid)
		)
		(fill yes)
		(layer "In13.Cu")
		(net "M_H_CPU0_SB_DQ<3>")
	)
	(gr_poly
		(pts
			(xy 383.61493 -273.884136) (xy 383.61493 -273.839686) (xy 383.414778 -273.839686) (xy 383.414778 -273.884136)
			(xy 383.514854 -273.984212)
		)
		(stroke
			(width 0)
			(type solid)
		)
		(fill yes)
		(layer "In13.Cu")
		(net "M_H_CPU0_SB_CB<3>")
	)
	(gr_poly
		(pts
			(xy 383.61493 -272.264378) (xy 383.61493 -272.216626) (xy 383.414778 -272.216626) (xy 383.414778 -272.264378)
			(xy 383.514854 -272.3642)
		)
		(stroke
			(width 0)
			(type solid)
		)
		(fill yes)
		(layer "In13.Cu")
		(net "M_H_CPU0_SB_DQS_DP<4>")
	)
	(gr_poly
		(pts
			(xy 383.61493 -270.644112) (xy 383.61493 -270.599662) (xy 383.414778 -270.599662) (xy 383.414778 -270.644112)
			(xy 383.514854 -270.744188)
		)
		(stroke
			(width 0)
			(type solid)
		)
		(fill yes)
		(layer "In13.Cu")
		(net "M_H_CPU0_SB_CB<7>")
	)
	(gr_poly
		(pts
			(xy 383.61493 -265.784076) (xy 383.61493 -265.739626) (xy 383.414778 -265.739626) (xy 383.414778 -265.784076)
			(xy 383.514854 -265.884152)
		)
		(stroke
			(width 0)
			(type solid)
		)
		(fill yes)
		(layer "In13.Cu")
		(net "M_H_CPU0_SB_CS_N<0>")
	)
	(gr_poly
		(pts
			(xy 383.61493 -264.164064) (xy 383.61493 -264.119614) (xy 383.414778 -264.119614) (xy 383.414778 -264.164064)
			(xy 383.514854 -264.26414)
		)
		(stroke
			(width 0)
			(type solid)
		)
		(fill yes)
		(layer "In13.Cu")
		(net "M_H_CPU0_SB_CA<5>")
	)
	(gr_poly
		(pts
			(xy 383.61493 -262.544052) (xy 383.61493 -262.499602) (xy 383.414778 -262.499602) (xy 383.414778 -262.544052)
			(xy 383.514854 -262.644128)
		)
		(stroke
			(width 0)
			(type solid)
		)
		(fill yes)
		(layer "In13.Cu")
		(net "M_H_CPU0_SB_CA<1>")
	)
	(gr_poly
		(pts
			(xy 383.784856 -255.622298) (xy 383.784856 -255.577848) (xy 383.584704 -255.577848) (xy 383.584704 -255.622298)
			(xy 383.68478 -255.722374)
		)
		(stroke
			(width 0)
			(type solid)
		)
		(fill yes)
		(layer "In13.Cu")
		(net "M_H_CPU0_SA_PAR")
	)
	(gr_poly
		(pts
			(xy 383.784856 -254.002286) (xy 383.784856 -253.957836) (xy 383.584704 -253.957836) (xy 383.584704 -254.002286)
			(xy 383.68478 -254.102362)
		)
		(stroke
			(width 0)
			(type solid)
		)
		(fill yes)
		(layer "In13.Cu")
		(net "M_H_CPU0_SA_CA<3>")
	)
	(gr_poly
		(pts
			(xy 383.784856 -250.762262) (xy 383.784856 -250.717812) (xy 383.584704 -250.717812) (xy 383.584704 -250.762262)
			(xy 383.68478 -250.862338)
		)
		(stroke
			(width 0)
			(type solid)
		)
		(fill yes)
		(layer "In13.Cu")
		(net "M_H_CPU0_RESET_N")
	)
	(gr_poly
		(pts
			(xy 383.784856 -249.14225) (xy 383.784856 -249.0978) (xy 383.584704 -249.0978) (xy 383.584704 -249.14225)
			(xy 383.68478 -249.242326)
		)
		(stroke
			(width 0)
			(type solid)
		)
		(fill yes)
		(layer "In13.Cu")
		(net "M_H_CPU0_SA_CB<7>")
	)
	(gr_poly
		(pts
			(xy 383.784856 -247.522492) (xy 383.784856 -247.47474) (xy 383.584704 -247.47474) (xy 383.584704 -247.522492)
			(xy 383.68478 -247.622314)
		)
		(stroke
			(width 0)
			(type solid)
		)
		(fill yes)
		(layer "In13.Cu")
		(net "M_H_CPU0_SA_DQS_DP<9>")
	)
	(gr_poly
		(pts
			(xy 383.784856 -245.902226) (xy 383.784856 -245.857776) (xy 383.584704 -245.857776) (xy 383.584704 -245.902226)
			(xy 383.68478 -246.002302)
		)
		(stroke
			(width 0)
			(type solid)
		)
		(fill yes)
		(layer "In13.Cu")
		(net "M_H_CPU0_SA_CB<3>")
	)
	(gr_poly
		(pts
			(xy 383.784856 -244.282214) (xy 383.784856 -244.237764) (xy 383.584704 -244.237764) (xy 383.584704 -244.282214)
			(xy 383.68478 -244.38229)
		)
		(stroke
			(width 0)
			(type solid)
		)
		(fill yes)
		(layer "In13.Cu")
		(net "M_H_CPU0_SA_DQ<31>")
	)
	(gr_poly
		(pts
			(xy 383.784856 -242.662456) (xy 383.784856 -242.614704) (xy 383.584704 -242.614704) (xy 383.584704 -242.662456)
			(xy 383.68478 -242.762278)
		)
		(stroke
			(width 0)
			(type solid)
		)
		(fill yes)
		(layer "In13.Cu")
		(net "M_H_CPU0_SA_DQS_DP<8>")
	)
	(gr_poly
		(pts
			(xy 383.784856 -241.04219) (xy 383.784856 -240.99774) (xy 383.584704 -240.99774) (xy 383.584704 -241.04219)
			(xy 383.68478 -241.142266)
		)
		(stroke
			(width 0)
			(type solid)
		)
		(fill yes)
		(layer "In13.Cu")
		(net "M_H_CPU0_SA_DQ<27>")
	)
	(gr_poly
		(pts
			(xy 383.784856 -239.422178) (xy 383.784856 -239.377728) (xy 383.584704 -239.377728) (xy 383.584704 -239.422178)
			(xy 383.68478 -239.522254)
		)
		(stroke
			(width 0)
			(type solid)
		)
		(fill yes)
		(layer "In13.Cu")
		(net "M_H_CPU0_SA_DQ<23>")
	)
	(gr_poly
		(pts
			(xy 383.784856 -237.80242) (xy 383.784856 -237.754668) (xy 383.584704 -237.754668) (xy 383.584704 -237.80242)
			(xy 383.68478 -237.902242)
		)
		(stroke
			(width 0)
			(type solid)
		)
		(fill yes)
		(layer "In13.Cu")
		(net "M_H_CPU0_SA_DQS_DP<7>")
	)
	(gr_poly
		(pts
			(xy 383.784856 -236.182154) (xy 383.784856 -236.137704) (xy 383.584704 -236.137704) (xy 383.584704 -236.182154)
			(xy 383.68478 -236.28223)
		)
		(stroke
			(width 0)
			(type solid)
		)
		(fill yes)
		(layer "In13.Cu")
		(net "M_H_CPU0_SA_DQ<19>")
	)
	(gr_poly
		(pts
			(xy 383.784856 -234.562142) (xy 383.784856 -234.517692) (xy 383.584704 -234.517692) (xy 383.584704 -234.562142)
			(xy 383.68478 -234.662218)
		)
		(stroke
			(width 0)
			(type solid)
		)
		(fill yes)
		(layer "In13.Cu")
		(net "M_H_CPU0_SA_DQ<15>")
	)
	(gr_poly
		(pts
			(xy 383.784856 -232.942384) (xy 383.784856 -232.894632) (xy 383.584704 -232.894632) (xy 383.584704 -232.942384)
			(xy 383.68478 -233.042206)
		)
		(stroke
			(width 0)
			(type solid)
		)
		(fill yes)
		(layer "In13.Cu")
		(net "M_H_CPU0_SA_DQS_DP<6>")
	)
	(gr_poly
		(pts
			(xy 383.784856 -231.322372) (xy 383.784856 -231.277922) (xy 383.584704 -231.277922) (xy 383.584704 -231.322372)
			(xy 383.68478 -231.422448)
		)
		(stroke
			(width 0)
			(type solid)
		)
		(fill yes)
		(layer "In13.Cu")
		(net "M_H_CPU0_SA_DQ<11>")
	)
	(gr_poly
		(pts
			(xy 383.784856 -229.70236) (xy 383.784856 -229.65791) (xy 383.584704 -229.65791) (xy 383.584704 -229.70236)
			(xy 383.68478 -229.802436)
		)
		(stroke
			(width 0)
			(type solid)
		)
		(fill yes)
		(layer "In13.Cu")
		(net "M_H_CPU0_SA_DQ<7>")
	)
	(gr_poly
		(pts
			(xy 383.784856 -228.082602) (xy 383.784856 -228.03485) (xy 383.584704 -228.03485) (xy 383.584704 -228.082602)
			(xy 383.68478 -228.182424)
		)
		(stroke
			(width 0)
			(type solid)
		)
		(fill yes)
		(layer "In13.Cu")
		(net "M_H_CPU0_SA_DQS_DP<5>")
	)
	(gr_poly
		(pts
			(xy 383.784856 -226.462336) (xy 383.784856 -226.417886) (xy 383.584704 -226.417886) (xy 383.584704 -226.462336)
			(xy 383.68478 -226.562412)
		)
		(stroke
			(width 0)
			(type solid)
		)
		(fill yes)
		(layer "In13.Cu")
		(net "M_H_CPU0_SA_DQ<3>")
	)
	(gr_poly
		(pts
			(xy 384.08483 -292.91788) (xy 383.984754 -292.817804) (xy 383.884678 -292.91788) (xy 383.884678 -292.96233)
			(xy 384.08483 -292.96233)
		)
		(stroke
			(width 0)
			(type solid)
		)
		(fill yes)
		(layer "In13.Cu")
		(net "M_H_CPU0_SB_DQ<29>")
	)
	(gr_poly
		(pts
			(xy 384.08483 -291.297614) (xy 383.984754 -291.197792) (xy 383.884678 -291.297614) (xy 383.884678 -291.345366)
			(xy 384.08483 -291.345366)
		)
		(stroke
			(width 0)
			(type solid)
		)
		(fill yes)
		(layer "In13.Cu")
		(net "M_H_CPU0_SB_DQS_DN<8>")
	)
	(gr_poly
		(pts
			(xy 384.08483 -289.677856) (xy 383.984754 -289.57778) (xy 383.884678 -289.677856) (xy 383.884678 -289.722306)
			(xy 384.08483 -289.722306)
		)
		(stroke
			(width 0)
			(type solid)
		)
		(fill yes)
		(layer "In13.Cu")
		(net "M_H_CPU0_SB_DQ<25>")
	)
	(gr_poly
		(pts
			(xy 384.08483 -288.057844) (xy 383.984754 -287.957768) (xy 383.884678 -288.057844) (xy 383.884678 -288.102294)
			(xy 384.08483 -288.102294)
		)
		(stroke
			(width 0)
			(type solid)
		)
		(fill yes)
		(layer "In13.Cu")
		(net "M_H_CPU0_SB_DQ<21>")
	)
	(gr_poly
		(pts
			(xy 384.08483 -286.437832) (xy 383.984754 -286.337756) (xy 383.884678 -286.437832) (xy 383.884678 -286.485584)
			(xy 384.08483 -286.485584)
		)
		(stroke
			(width 0)
			(type solid)
		)
		(fill yes)
		(layer "In13.Cu")
		(net "M_H_CPU0_SB_DQS_DN<7>")
	)
	(gr_poly
		(pts
			(xy 384.08483 -284.818074) (xy 383.984754 -284.717998) (xy 383.884678 -284.818074) (xy 383.884678 -284.862524)
			(xy 384.08483 -284.862524)
		)
		(stroke
			(width 0)
			(type solid)
		)
		(fill yes)
		(layer "In13.Cu")
		(net "M_H_CPU0_SB_DQ<17>")
	)
	(gr_poly
		(pts
			(xy 384.08483 -283.198062) (xy 383.984754 -283.097986) (xy 383.884678 -283.198062) (xy 383.884678 -283.242512)
			(xy 384.08483 -283.242512)
		)
		(stroke
			(width 0)
			(type solid)
		)
		(fill yes)
		(layer "In13.Cu")
		(net "M_H_CPU0_SB_DQ<13>")
	)
	(gr_poly
		(pts
			(xy 384.08483 -281.577796) (xy 383.984754 -281.477974) (xy 383.884678 -281.577796) (xy 383.884678 -281.625548)
			(xy 384.08483 -281.625548)
		)
		(stroke
			(width 0)
			(type solid)
		)
		(fill yes)
		(layer "In13.Cu")
		(net "M_H_CPU0_SB_DQS_DN<6>")
	)
	(gr_poly
		(pts
			(xy 384.08483 -279.958038) (xy 383.984754 -279.857962) (xy 383.884678 -279.958038) (xy 383.884678 -280.002488)
			(xy 384.08483 -280.002488)
		)
		(stroke
			(width 0)
			(type solid)
		)
		(fill yes)
		(layer "In13.Cu")
		(net "M_H_CPU0_SB_DQ<9>")
	)
	(gr_poly
		(pts
			(xy 384.08483 -278.338026) (xy 383.984754 -278.23795) (xy 383.884678 -278.338026) (xy 383.884678 -278.382476)
			(xy 384.08483 -278.382476)
		)
		(stroke
			(width 0)
			(type solid)
		)
		(fill yes)
		(layer "In13.Cu")
		(net "M_H_CPU0_SB_DQ<5>")
	)
	(gr_poly
		(pts
			(xy 384.08483 -276.71776) (xy 383.984754 -276.617938) (xy 383.884678 -276.71776) (xy 383.884678 -276.765512)
			(xy 384.08483 -276.765512)
		)
		(stroke
			(width 0)
			(type solid)
		)
		(fill yes)
		(layer "In13.Cu")
		(net "M_H_CPU0_SB_DQS_DN<5>")
	)
	(gr_poly
		(pts
			(xy 384.08483 -275.098002) (xy 383.984754 -274.997926) (xy 383.884678 -275.098002) (xy 383.884678 -275.142452)
			(xy 384.08483 -275.142452)
		)
		(stroke
			(width 0)
			(type solid)
		)
		(fill yes)
		(layer "In13.Cu")
		(net "M_H_CPU0_SB_DQ<1>")
	)
	(gr_poly
		(pts
			(xy 384.08483 -273.47799) (xy 383.984754 -273.377914) (xy 383.884678 -273.47799) (xy 383.884678 -273.52244)
			(xy 384.08483 -273.52244)
		)
		(stroke
			(width 0)
			(type solid)
		)
		(fill yes)
		(layer "In13.Cu")
		(net "M_H_CPU0_SB_CB<1>")
	)
	(gr_poly
		(pts
			(xy 384.08483 -271.857724) (xy 383.984754 -271.757902) (xy 383.884678 -271.857724) (xy 383.884678 -271.905476)
			(xy 384.08483 -271.905476)
		)
		(stroke
			(width 0)
			(type solid)
		)
		(fill yes)
		(layer "In13.Cu")
		(net "M_H_CPU0_SB_DQS_DN<4>")
	)
	(gr_poly
		(pts
			(xy 384.08483 -270.237966) (xy 383.984754 -270.13789) (xy 383.884678 -270.237966) (xy 383.884678 -270.282416)
			(xy 384.08483 -270.282416)
		)
		(stroke
			(width 0)
			(type solid)
		)
		(fill yes)
		(layer "In13.Cu")
		(net "M_H_CPU0_SB_CB<5>")
	)
	(gr_poly
		(pts
			(xy 384.08483 -266.997942) (xy 383.984754 -266.897866) (xy 383.884678 -266.997942) (xy 383.884678 -267.042392)
			(xy 384.08483 -267.042392)
		)
		(stroke
			(width 0)
			(type solid)
		)
		(fill yes)
		(layer "In13.Cu")
		(net "M_H_CPU0_SA_RSP<0>")
	)
	(gr_poly
		(pts
			(xy 384.08483 -265.37793) (xy 383.984754 -265.277854) (xy 383.884678 -265.37793) (xy 383.884678 -265.42238)
			(xy 384.08483 -265.42238)
		)
		(stroke
			(width 0)
			(type solid)
		)
		(fill yes)
		(layer "In13.Cu")
		(net "M_H_CPU0_SB_PAR")
	)
	(gr_poly
		(pts
			(xy 384.08483 -263.757918) (xy 383.984754 -263.657842) (xy 383.884678 -263.757918) (xy 383.884678 -263.802368)
			(xy 384.08483 -263.802368)
		)
		(stroke
			(width 0)
			(type solid)
		)
		(fill yes)
		(layer "In13.Cu")
		(net "M_H_CPU0_SB_CA<4>")
	)
	(gr_poly
		(pts
			(xy 384.08483 -262.137906) (xy 383.984754 -262.03783) (xy 383.884678 -262.137906) (xy 383.884678 -262.182356)
			(xy 384.08483 -262.182356)
		)
		(stroke
			(width 0)
			(type solid)
		)
		(fill yes)
		(layer "In13.Cu")
		(net "M_H_CPU0_SB_CA<0>")
	)
	(gr_poly
		(pts
			(xy 384.25501 -256.432558) (xy 384.25501 -256.384806) (xy 384.054858 -256.384806) (xy 384.054858 -256.432558)
			(xy 384.154934 -256.53238)
		)
		(stroke
			(width 0)
			(type solid)
		)
		(fill yes)
		(layer "In13.Cu")
		(net "M_H_CPU0_CLK_DN<0>")
	)
	(gr_poly
		(pts
			(xy 384.25501 -255.216152) (xy 384.154934 -255.116076) (xy 384.054858 -255.216152) (xy 384.054858 -255.260602)
			(xy 384.25501 -255.260602)
		)
		(stroke
			(width 0)
			(type solid)
		)
		(fill yes)
		(layer "In13.Cu")
		(net "M_H_CPU0_SA_CA<6>")
	)
	(gr_poly
		(pts
			(xy 384.25501 -254.812292) (xy 384.25501 -254.767842) (xy 384.054858 -254.767842) (xy 384.054858 -254.812292)
			(xy 384.154934 -254.912368)
		)
		(stroke
			(width 0)
			(type solid)
		)
		(fill yes)
		(layer "In13.Cu")
		(net "M_H_CPU0_SA_CA<5>")
	)
	(gr_poly
		(pts
			(xy 384.25501 -253.59614) (xy 384.154934 -253.496064) (xy 384.054858 -253.59614) (xy 384.054858 -253.64059)
			(xy 384.25501 -253.64059)
		)
		(stroke
			(width 0)
			(type solid)
		)
		(fill yes)
		(layer "In13.Cu")
		(net "M_H_CPU0_SA_CA<2>")
	)
	(gr_poly
		(pts
			(xy 384.25501 -253.19228) (xy 384.25501 -253.14783) (xy 384.054858 -253.14783) (xy 384.054858 -253.19228)
			(xy 384.154934 -253.292356)
		)
		(stroke
			(width 0)
			(type solid)
		)
		(fill yes)
		(layer "In13.Cu")
		(net "M_H_CPU0_SA_CA<1>")
	)
	(gr_poly
		(pts
			(xy 384.25501 -251.976128) (xy 384.154934 -251.876052) (xy 384.054858 -251.976128) (xy 384.054858 -252.020578)
			(xy 384.25501 -252.020578)
		)
		(stroke
			(width 0)
			(type solid)
		)
		(fill yes)
		(layer "In13.Cu")
		(net "M_H_CPU0_SA_CS_N<1>")
	)
	(gr_poly
		(pts
			(xy 384.25501 -250.356116) (xy 384.154934 -250.25604) (xy 384.054858 -250.356116) (xy 384.054858 -250.400566)
			(xy 384.25501 -250.400566)
		)
		(stroke
			(width 0)
			(type solid)
		)
		(fill yes)
		(layer "In13.Cu")
		(net "M_H_CPU0_ALERT_R_N")
	)
	(gr_poly
		(pts
			(xy 384.25501 -248.736104) (xy 384.154934 -248.636028) (xy 384.054858 -248.736104) (xy 384.054858 -248.780554)
			(xy 384.25501 -248.780554)
		)
		(stroke
			(width 0)
			(type solid)
		)
		(fill yes)
		(layer "In13.Cu")
		(net "M_H_CPU0_SA_CB<5>")
	)
	(gr_poly
		(pts
			(xy 384.25501 -248.332244) (xy 384.25501 -248.287794) (xy 384.054858 -248.287794) (xy 384.054858 -248.332244)
			(xy 384.154934 -248.43232)
		)
		(stroke
			(width 0)
			(type solid)
		)
		(fill yes)
		(layer "In13.Cu")
		(net "M_H_CPU0_SA_CB<6>")
	)
	(gr_poly
		(pts
			(xy 384.25501 -247.115838) (xy 384.154934 -247.016016) (xy 384.054858 -247.115838) (xy 384.054858 -247.16359)
			(xy 384.25501 -247.16359)
		)
		(stroke
			(width 0)
			(type solid)
		)
		(fill yes)
		(layer "In13.Cu")
		(net "M_H_CPU0_SA_DQS_DN<9>")
	)
	(gr_poly
		(pts
			(xy 384.25501 -246.712486) (xy 384.25501 -246.664734) (xy 384.054858 -246.664734) (xy 384.054858 -246.712486)
			(xy 384.154934 -246.812308)
		)
		(stroke
			(width 0)
			(type solid)
		)
		(fill yes)
		(layer "In13.Cu")
		(net "M_H_CPU0_SA_DQS_DN<4>")
	)
	(gr_poly
		(pts
			(xy 384.25501 -245.49608) (xy 384.154934 -245.396004) (xy 384.054858 -245.49608) (xy 384.054858 -245.54053)
			(xy 384.25501 -245.54053)
		)
		(stroke
			(width 0)
			(type solid)
		)
		(fill yes)
		(layer "In13.Cu")
		(net "M_H_CPU0_SA_CB<1>")
	)
	(gr_poly
		(pts
			(xy 384.25501 -245.09222) (xy 384.25501 -245.04777) (xy 384.054858 -245.04777) (xy 384.054858 -245.09222)
			(xy 384.154934 -245.192296)
		)
		(stroke
			(width 0)
			(type solid)
		)
		(fill yes)
		(layer "In13.Cu")
		(net "M_H_CPU0_SA_CB<2>")
	)
	(gr_poly
		(pts
			(xy 384.25501 -243.876068) (xy 384.154934 -243.775992) (xy 384.054858 -243.876068) (xy 384.054858 -243.920518)
			(xy 384.25501 -243.920518)
		)
		(stroke
			(width 0)
			(type solid)
		)
		(fill yes)
		(layer "In13.Cu")
		(net "M_H_CPU0_SA_DQ<29>")
	)
	(gr_poly
		(pts
			(xy 384.25501 -243.472208) (xy 384.25501 -243.427758) (xy 384.054858 -243.427758) (xy 384.054858 -243.472208)
			(xy 384.154934 -243.572284)
		)
		(stroke
			(width 0)
			(type solid)
		)
		(fill yes)
		(layer "In13.Cu")
		(net "M_H_CPU0_SA_DQ<30>")
	)
	(gr_poly
		(pts
			(xy 384.25501 -242.255802) (xy 384.154934 -242.15598) (xy 384.054858 -242.255802) (xy 384.054858 -242.303554)
			(xy 384.25501 -242.303554)
		)
		(stroke
			(width 0)
			(type solid)
		)
		(fill yes)
		(layer "In13.Cu")
		(net "M_H_CPU0_SA_DQS_DN<8>")
	)
	(gr_poly
		(pts
			(xy 384.25501 -241.85245) (xy 384.25501 -241.804698) (xy 384.054858 -241.804698) (xy 384.054858 -241.85245)
			(xy 384.154934 -241.952272)
		)
		(stroke
			(width 0)
			(type solid)
		)
		(fill yes)
		(layer "In13.Cu")
		(net "M_H_CPU0_SA_DQS_DN<3>")
	)
	(gr_poly
		(pts
			(xy 384.25501 -240.636044) (xy 384.154934 -240.535968) (xy 384.054858 -240.636044) (xy 384.054858 -240.680494)
			(xy 384.25501 -240.680494)
		)
		(stroke
			(width 0)
			(type solid)
		)
		(fill yes)
		(layer "In13.Cu")
		(net "M_H_CPU0_SA_DQ<25>")
	)
	(gr_poly
		(pts
			(xy 384.25501 -240.232184) (xy 384.25501 -240.187734) (xy 384.054858 -240.187734) (xy 384.054858 -240.232184)
			(xy 384.154934 -240.33226)
		)
		(stroke
			(width 0)
			(type solid)
		)
		(fill yes)
		(layer "In13.Cu")
		(net "M_H_CPU0_SA_DQ<26>")
	)
	(gr_poly
		(pts
			(xy 384.25501 -239.016032) (xy 384.154934 -238.915956) (xy 384.054858 -239.016032) (xy 384.054858 -239.060482)
			(xy 384.25501 -239.060482)
		)
		(stroke
			(width 0)
			(type solid)
		)
		(fill yes)
		(layer "In13.Cu")
		(net "M_H_CPU0_SA_DQ<21>")
	)
	(gr_poly
		(pts
			(xy 384.25501 -238.612172) (xy 384.25501 -238.567722) (xy 384.054858 -238.567722) (xy 384.054858 -238.612172)
			(xy 384.154934 -238.712248)
		)
		(stroke
			(width 0)
			(type solid)
		)
		(fill yes)
		(layer "In13.Cu")
		(net "M_H_CPU0_SA_DQ<22>")
	)
	(gr_poly
		(pts
			(xy 384.25501 -237.395766) (xy 384.154934 -237.295944) (xy 384.054858 -237.395766) (xy 384.054858 -237.443518)
			(xy 384.25501 -237.443518)
		)
		(stroke
			(width 0)
			(type solid)
		)
		(fill yes)
		(layer "In13.Cu")
		(net "M_H_CPU0_SA_DQS_DN<7>")
	)
	(gr_poly
		(pts
			(xy 384.25501 -236.992414) (xy 384.25501 -236.944662) (xy 384.054858 -236.944662) (xy 384.054858 -236.992414)
			(xy 384.154934 -237.092236)
		)
		(stroke
			(width 0)
			(type solid)
		)
		(fill yes)
		(layer "In13.Cu")
		(net "M_H_CPU0_SA_DQS_DN<2>")
	)
	(gr_poly
		(pts
			(xy 384.25501 -235.776008) (xy 384.154934 -235.675932) (xy 384.054858 -235.776008) (xy 384.054858 -235.820458)
			(xy 384.25501 -235.820458)
		)
		(stroke
			(width 0)
			(type solid)
		)
		(fill yes)
		(layer "In13.Cu")
		(net "M_H_CPU0_SA_DQ<17>")
	)
	(gr_poly
		(pts
			(xy 384.25501 -235.372148) (xy 384.25501 -235.327698) (xy 384.054858 -235.327698) (xy 384.054858 -235.372148)
			(xy 384.154934 -235.472224)
		)
		(stroke
			(width 0)
			(type solid)
		)
		(fill yes)
		(layer "In13.Cu")
		(net "M_H_CPU0_SA_DQ<18>")
	)
	(gr_poly
		(pts
			(xy 384.25501 -234.155996) (xy 384.154934 -234.05592) (xy 384.054858 -234.155996) (xy 384.054858 -234.200446)
			(xy 384.25501 -234.200446)
		)
		(stroke
			(width 0)
			(type solid)
		)
		(fill yes)
		(layer "In13.Cu")
		(net "M_H_CPU0_SA_DQ<13>")
	)
	(gr_poly
		(pts
			(xy 384.25501 -233.752136) (xy 384.25501 -233.707686) (xy 384.054858 -233.707686) (xy 384.054858 -233.752136)
			(xy 384.154934 -233.852212)
		)
		(stroke
			(width 0)
			(type solid)
		)
		(fill yes)
		(layer "In13.Cu")
		(net "M_H_CPU0_SA_DQ<14>")
	)
	(gr_poly
		(pts
			(xy 384.25501 -232.53573) (xy 384.154934 -232.435908) (xy 384.054858 -232.53573) (xy 384.054858 -232.583482)
			(xy 384.25501 -232.583482)
		)
		(stroke
			(width 0)
			(type solid)
		)
		(fill yes)
		(layer "In13.Cu")
		(net "M_H_CPU0_SA_DQS_DN<6>")
	)
	(gr_poly
		(pts
			(xy 384.25501 -232.132378) (xy 384.25501 -232.084626) (xy 384.054858 -232.084626) (xy 384.054858 -232.132378)
			(xy 384.154934 -232.2322)
		)
		(stroke
			(width 0)
			(type solid)
		)
		(fill yes)
		(layer "In13.Cu")
		(net "M_H_CPU0_SA_DQS_DN<1>")
	)
	(gr_poly
		(pts
			(xy 384.25501 -230.915972) (xy 384.154934 -230.815896) (xy 384.054858 -230.915972) (xy 384.054858 -230.960422)
			(xy 384.25501 -230.960422)
		)
		(stroke
			(width 0)
			(type solid)
		)
		(fill yes)
		(layer "In13.Cu")
		(net "M_H_CPU0_SA_DQ<9>")
	)
	(gr_poly
		(pts
			(xy 384.25501 -230.512366) (xy 384.25501 -230.467916) (xy 384.054858 -230.467916) (xy 384.054858 -230.512366)
			(xy 384.154934 -230.612188)
		)
		(stroke
			(width 0)
			(type solid)
		)
		(fill yes)
		(layer "In13.Cu")
		(net "M_H_CPU0_SA_DQ<10>")
	)
	(gr_poly
		(pts
			(xy 384.25501 -229.29596) (xy 384.154934 -229.195884) (xy 384.054858 -229.29596) (xy 384.054858 -229.34041)
			(xy 384.25501 -229.34041)
		)
		(stroke
			(width 0)
			(type solid)
		)
		(fill yes)
		(layer "In13.Cu")
		(net "M_H_CPU0_SA_DQ<5>")
	)
	(gr_poly
		(pts
			(xy 384.25501 -228.892354) (xy 384.25501 -228.847904) (xy 384.054858 -228.847904) (xy 384.054858 -228.892354)
			(xy 384.154934 -228.99243)
		)
		(stroke
			(width 0)
			(type solid)
		)
		(fill yes)
		(layer "In13.Cu")
		(net "M_H_CPU0_SA_DQ<6>")
	)
	(gr_poly
		(pts
			(xy 384.25501 -227.675948) (xy 384.154934 -227.576126) (xy 384.054858 -227.675948) (xy 384.054858 -227.7237)
			(xy 384.25501 -227.7237)
		)
		(stroke
			(width 0)
			(type solid)
		)
		(fill yes)
		(layer "In13.Cu")
		(net "M_H_CPU0_SA_DQS_DN<5>")
	)
	(gr_poly
		(pts
			(xy 384.25501 -227.272596) (xy 384.25501 -227.224844) (xy 384.054858 -227.224844) (xy 384.054858 -227.272596)
			(xy 384.154934 -227.372418)
		)
		(stroke
			(width 0)
			(type solid)
		)
		(fill yes)
		(layer "In13.Cu")
		(net "M_H_CPU0_SA_DQS_DN<0>")
	)
	(gr_poly
		(pts
			(xy 384.25501 -226.05619) (xy 384.154934 -225.956114) (xy 384.054858 -226.05619) (xy 384.054858 -226.10064)
			(xy 384.25501 -226.10064)
		)
		(stroke
			(width 0)
			(type solid)
		)
		(fill yes)
		(layer "In13.Cu")
		(net "M_H_CPU0_SA_DQ<1>")
	)
	(gr_poly
		(pts
			(xy 384.25501 -225.65233) (xy 384.25501 -225.60788) (xy 384.054858 -225.60788) (xy 384.054858 -225.65233)
			(xy 384.154934 -225.752406)
		)
		(stroke
			(width 0)
			(type solid)
		)
		(fill yes)
		(layer "In13.Cu")
		(net "M_H_CPU0_SA_DQ<2>")
	)
	(gr_poly
		(pts
			(xy 384.554984 -293.324026) (xy 384.554984 -293.279576) (xy 384.354832 -293.279576) (xy 384.354832 -293.324026)
			(xy 384.454908 -293.424102)
		)
		(stroke
			(width 0)
			(type solid)
		)
		(fill yes)
		(layer "In13.Cu")
		(net "M_H_CPU0_SB_DQ<31>")
	)
	(gr_poly
		(pts
			(xy 384.554984 -292.107874) (xy 384.454908 -292.007798) (xy 384.354832 -292.107874) (xy 384.354832 -292.152324)
			(xy 384.554984 -292.152324)
		)
		(stroke
			(width 0)
			(type solid)
		)
		(fill yes)
		(layer "In13.Cu")
		(net "M_H_CPU0_SB_DQ<28>")
	)
	(gr_poly
		(pts
			(xy 384.554984 -291.704268) (xy 384.554984 -291.656516) (xy 384.354832 -291.656516) (xy 384.354832 -291.704268)
			(xy 384.454908 -291.80409)
		)
		(stroke
			(width 0)
			(type solid)
		)
		(fill yes)
		(layer "In13.Cu")
		(net "M_H_CPU0_SB_DQS_DP<8>")
	)
	(gr_poly
		(pts
			(xy 384.554984 -290.487608) (xy 384.454908 -290.387786) (xy 384.354832 -290.487608) (xy 384.354832 -290.53536)
			(xy 384.554984 -290.53536)
		)
		(stroke
			(width 0)
			(type solid)
		)
		(fill yes)
		(layer "In13.Cu")
		(net "M_H_CPU0_SB_DQS_DP<3>")
	)
	(gr_poly
		(pts
			(xy 384.554984 -290.084002) (xy 384.554984 -290.039552) (xy 384.354832 -290.039552) (xy 384.354832 -290.084002)
			(xy 384.454908 -290.184078)
		)
		(stroke
			(width 0)
			(type solid)
		)
		(fill yes)
		(layer "In13.Cu")
		(net "M_H_CPU0_SB_DQ<27>")
	)
	(gr_poly
		(pts
			(xy 384.554984 -288.86785) (xy 384.454908 -288.767774) (xy 384.354832 -288.86785) (xy 384.354832 -288.9123)
			(xy 384.554984 -288.9123)
		)
		(stroke
			(width 0)
			(type solid)
		)
		(fill yes)
		(layer "In13.Cu")
		(net "M_H_CPU0_SB_DQ<24>")
	)
	(gr_poly
		(pts
			(xy 384.554984 -288.464244) (xy 384.554984 -288.419794) (xy 384.354832 -288.419794) (xy 384.354832 -288.464244)
			(xy 384.454908 -288.56432)
		)
		(stroke
			(width 0)
			(type solid)
		)
		(fill yes)
		(layer "In13.Cu")
		(net "M_H_CPU0_SB_DQ<23>")
	)
	(gr_poly
		(pts
			(xy 384.554984 -287.247838) (xy 384.454908 -287.148016) (xy 384.354832 -287.247838) (xy 384.354832 -287.292288)
			(xy 384.554984 -287.292288)
		)
		(stroke
			(width 0)
			(type solid)
		)
		(fill yes)
		(layer "In13.Cu")
		(net "M_H_CPU0_SB_DQ<20>")
	)
	(gr_poly
		(pts
			(xy 384.554984 -286.844232) (xy 384.554984 -286.79648) (xy 384.354832 -286.79648) (xy 384.354832 -286.844232)
			(xy 384.454908 -286.944308)
		)
		(stroke
			(width 0)
			(type solid)
		)
		(fill yes)
		(layer "In13.Cu")
		(net "M_H_CPU0_SB_DQS_DP<7>")
	)
	(gr_poly
		(pts
			(xy 384.554984 -285.627826) (xy 384.454908 -285.528004) (xy 384.354832 -285.627826) (xy 384.354832 -285.675578)
			(xy 384.554984 -285.675578)
		)
		(stroke
			(width 0)
			(type solid)
		)
		(fill yes)
		(layer "In13.Cu")
		(net "M_H_CPU0_SB_DQS_DP<2>")
	)
	(gr_poly
		(pts
			(xy 384.554984 -285.22422) (xy 384.554984 -285.17977) (xy 384.354832 -285.17977) (xy 384.354832 -285.22422)
			(xy 384.454908 -285.324296)
		)
		(stroke
			(width 0)
			(type solid)
		)
		(fill yes)
		(layer "In13.Cu")
		(net "M_H_CPU0_SB_DQ<19>")
	)
	(gr_poly
		(pts
			(xy 384.554984 -284.008068) (xy 384.454908 -283.907992) (xy 384.354832 -284.008068) (xy 384.354832 -284.052518)
			(xy 384.554984 -284.052518)
		)
		(stroke
			(width 0)
			(type solid)
		)
		(fill yes)
		(layer "In13.Cu")
		(net "M_H_CPU0_SB_DQ<16>")
	)
	(gr_poly
		(pts
			(xy 384.554984 -283.604208) (xy 384.554984 -283.559758) (xy 384.354832 -283.559758) (xy 384.354832 -283.604208)
			(xy 384.454908 -283.704284)
		)
		(stroke
			(width 0)
			(type solid)
		)
		(fill yes)
		(layer "In13.Cu")
		(net "M_H_CPU0_SB_DQ<15>")
	)
	(gr_poly
		(pts
			(xy 384.554984 -282.388056) (xy 384.454908 -282.28798) (xy 384.354832 -282.388056) (xy 384.354832 -282.432506)
			(xy 384.554984 -282.432506)
		)
		(stroke
			(width 0)
			(type solid)
		)
		(fill yes)
		(layer "In13.Cu")
		(net "M_H_CPU0_SB_DQ<12>")
	)
	(gr_poly
		(pts
			(xy 384.554984 -281.98445) (xy 384.554984 -281.936698) (xy 384.354832 -281.936698) (xy 384.354832 -281.98445)
			(xy 384.454908 -282.084272)
		)
		(stroke
			(width 0)
			(type solid)
		)
		(fill yes)
		(layer "In13.Cu")
		(net "M_H_CPU0_SB_DQS_DP<6>")
	)
	(gr_poly
		(pts
			(xy 384.554984 -280.76779) (xy 384.454908 -280.667968) (xy 384.354832 -280.76779) (xy 384.354832 -280.815542)
			(xy 384.554984 -280.815542)
		)
		(stroke
			(width 0)
			(type solid)
		)
		(fill yes)
		(layer "In13.Cu")
		(net "M_H_CPU0_SB_DQS_DP<1>")
	)
	(gr_poly
		(pts
			(xy 384.554984 -280.364184) (xy 384.554984 -280.319734) (xy 384.354832 -280.319734) (xy 384.354832 -280.364184)
			(xy 384.454908 -280.46426)
		)
		(stroke
			(width 0)
			(type solid)
		)
		(fill yes)
		(layer "In13.Cu")
		(net "M_H_CPU0_SB_DQ<11>")
	)
	(gr_poly
		(pts
			(xy 384.554984 -279.148032) (xy 384.454908 -279.047956) (xy 384.354832 -279.148032) (xy 384.354832 -279.192482)
			(xy 384.554984 -279.192482)
		)
		(stroke
			(width 0)
			(type solid)
		)
		(fill yes)
		(layer "In13.Cu")
		(net "M_H_CPU0_SB_DQ<8>")
	)
	(gr_poly
		(pts
			(xy 384.554984 -278.744172) (xy 384.554984 -278.699722) (xy 384.354832 -278.699722) (xy 384.354832 -278.744172)
			(xy 384.454908 -278.844248)
		)
		(stroke
			(width 0)
			(type solid)
		)
		(fill yes)
		(layer "In13.Cu")
		(net "M_H_CPU0_SB_DQ<7>")
	)
	(gr_poly
		(pts
			(xy 384.554984 -277.52802) (xy 384.454908 -277.427944) (xy 384.354832 -277.52802) (xy 384.354832 -277.57247)
			(xy 384.554984 -277.57247)
		)
		(stroke
			(width 0)
			(type solid)
		)
		(fill yes)
		(layer "In13.Cu")
		(net "M_H_CPU0_SB_DQ<4>")
	)
	(gr_poly
		(pts
			(xy 384.554984 -277.124414) (xy 384.554984 -277.076662) (xy 384.354832 -277.076662) (xy 384.354832 -277.124414)
			(xy 384.454908 -277.224236)
		)
		(stroke
			(width 0)
			(type solid)
		)
		(fill yes)
		(layer "In13.Cu")
		(net "M_H_CPU0_SB_DQS_DP<5>")
	)
	(gr_poly
		(pts
			(xy 384.554984 -275.907754) (xy 384.454908 -275.807932) (xy 384.354832 -275.907754) (xy 384.354832 -275.955506)
			(xy 384.554984 -275.955506)
		)
		(stroke
			(width 0)
			(type solid)
		)
		(fill yes)
		(layer "In13.Cu")
		(net "M_H_CPU0_SB_DQS_DP<0>")
	)
	(gr_poly
		(pts
			(xy 384.554984 -275.504148) (xy 384.554984 -275.459698) (xy 384.354832 -275.459698) (xy 384.354832 -275.504148)
			(xy 384.454908 -275.604224)
		)
		(stroke
			(width 0)
			(type solid)
		)
		(fill yes)
		(layer "In13.Cu")
		(net "M_H_CPU0_SB_DQ<3>")
	)
	(gr_poly
		(pts
			(xy 384.554984 -274.287996) (xy 384.454908 -274.18792) (xy 384.354832 -274.287996) (xy 384.354832 -274.332446)
			(xy 384.554984 -274.332446)
		)
		(stroke
			(width 0)
			(type solid)
		)
		(fill yes)
		(layer "In13.Cu")
		(net "M_H_CPU0_SB_DQ<0>")
	)
	(gr_poly
		(pts
			(xy 384.554984 -273.884136) (xy 384.554984 -273.839686) (xy 384.354832 -273.839686) (xy 384.354832 -273.884136)
			(xy 384.454908 -273.984212)
		)
		(stroke
			(width 0)
			(type solid)
		)
		(fill yes)
		(layer "In13.Cu")
		(net "M_H_CPU0_SB_CB<3>")
	)
	(gr_poly
		(pts
			(xy 384.554984 -272.667984) (xy 384.454908 -272.567908) (xy 384.354832 -272.667984) (xy 384.354832 -272.712434)
			(xy 384.554984 -272.712434)
		)
		(stroke
			(width 0)
			(type solid)
		)
		(fill yes)
		(layer "In13.Cu")
		(net "M_H_CPU0_SB_CB<0>")
	)
	(gr_poly
		(pts
			(xy 384.554984 -272.264378) (xy 384.554984 -272.216626) (xy 384.354832 -272.216626) (xy 384.354832 -272.264378)
			(xy 384.454908 -272.3642)
		)
		(stroke
			(width 0)
			(type solid)
		)
		(fill yes)
		(layer "In13.Cu")
		(net "M_H_CPU0_SB_DQS_DP<4>")
	)
	(gr_poly
		(pts
			(xy 384.554984 -271.047718) (xy 384.454908 -270.947896) (xy 384.354832 -271.047718) (xy 384.354832 -271.09547)
			(xy 384.554984 -271.09547)
		)
		(stroke
			(width 0)
			(type solid)
		)
		(fill yes)
		(layer "In13.Cu")
		(net "M_H_CPU0_SB_DQS_DP<9>")
	)
	(gr_poly
		(pts
			(xy 384.554984 -270.644112) (xy 384.554984 -270.599662) (xy 384.354832 -270.599662) (xy 384.354832 -270.644112)
			(xy 384.454908 -270.744188)
		)
		(stroke
			(width 0)
			(type solid)
		)
		(fill yes)
		(layer "In13.Cu")
		(net "M_H_CPU0_SB_CB<7>")
	)
	(gr_poly
		(pts
			(xy 384.554984 -269.42796) (xy 384.454908 -269.327884) (xy 384.354832 -269.42796) (xy 384.354832 -269.47241)
			(xy 384.554984 -269.47241)
		)
		(stroke
			(width 0)
			(type solid)
		)
		(fill yes)
		(layer "In13.Cu")
		(net "M_H_CPU0_SB_CB<4>")
	)
	(gr_poly
		(pts
			(xy 384.554984 -267.807948) (xy 384.454908 -267.707872) (xy 384.354832 -267.807948) (xy 384.354832 -267.852398)
			(xy 384.554984 -267.852398)
		)
		(stroke
			(width 0)
			(type solid)
		)
		(fill yes)
		(layer "In13.Cu")
		(net "M_H_CPU0_SB_RSP<0>")
	)
	(gr_poly
		(pts
			(xy 384.554984 -265.784076) (xy 384.554984 -265.739626) (xy 384.354832 -265.739626) (xy 384.354832 -265.784076)
			(xy 384.454908 -265.884152)
		)
		(stroke
			(width 0)
			(type solid)
		)
		(fill yes)
		(layer "In13.Cu")
		(net "M_H_CPU0_SB_CS_N<0>")
	)
	(gr_poly
		(pts
			(xy 384.554984 -264.567924) (xy 384.454908 -264.467848) (xy 384.354832 -264.567924) (xy 384.354832 -264.612374)
			(xy 384.554984 -264.612374)
		)
		(stroke
			(width 0)
			(type solid)
		)
		(fill yes)
		(layer "In13.Cu")
		(net "M_H_CPU0_SB_CA<6>")
	)
	(gr_poly
		(pts
			(xy 384.554984 -264.164064) (xy 384.554984 -264.119614) (xy 384.354832 -264.119614) (xy 384.354832 -264.164064)
			(xy 384.454908 -264.26414)
		)
		(stroke
			(width 0)
			(type solid)
		)
		(fill yes)
		(layer "In13.Cu")
		(net "M_H_CPU0_SB_CA<5>")
	)
	(gr_poly
		(pts
			(xy 384.554984 -262.947912) (xy 384.454908 -262.847836) (xy 384.354832 -262.947912) (xy 384.354832 -262.992362)
			(xy 384.554984 -262.992362)
		)
		(stroke
			(width 0)
			(type solid)
		)
		(fill yes)
		(layer "In13.Cu")
		(net "M_H_CPU0_SB_CA<2>")
	)
	(gr_poly
		(pts
			(xy 384.554984 -262.544052) (xy 384.554984 -262.499602) (xy 384.354832 -262.499602) (xy 384.354832 -262.544052)
			(xy 384.454908 -262.644128)
		)
		(stroke
			(width 0)
			(type solid)
		)
		(fill yes)
		(layer "In13.Cu")
		(net "M_H_CPU0_SB_CA<1>")
	)
	(gr_poly
		(pts
			(xy 384.72491 -256.025904) (xy 384.624834 -255.926082) (xy 384.524758 -256.025904) (xy 384.524758 -256.073656)
			(xy 384.72491 -256.073656)
		)
		(stroke
			(width 0)
			(type solid)
		)
		(fill yes)
		(layer "In13.Cu")
		(net "M_H_CPU0_CLK_DP<0>")
	)
	(gr_poly
		(pts
			(xy 384.72491 -255.622298) (xy 384.72491 -255.577848) (xy 384.524758 -255.577848) (xy 384.524758 -255.622298)
			(xy 384.624834 -255.722374)
		)
		(stroke
			(width 0)
			(type solid)
		)
		(fill yes)
		(layer "In13.Cu")
		(net "M_H_CPU0_SA_PAR")
	)
	(gr_poly
		(pts
			(xy 384.72491 -254.406146) (xy 384.624834 -254.30607) (xy 384.524758 -254.406146) (xy 384.524758 -254.450596)
			(xy 384.72491 -254.450596)
		)
		(stroke
			(width 0)
			(type solid)
		)
		(fill yes)
		(layer "In13.Cu")
		(net "M_H_CPU0_SA_CA<4>")
	)
	(gr_poly
		(pts
			(xy 384.72491 -254.002286) (xy 384.72491 -253.957836) (xy 384.524758 -253.957836) (xy 384.524758 -254.002286)
			(xy 384.624834 -254.102362)
		)
		(stroke
			(width 0)
			(type solid)
		)
		(fill yes)
		(layer "In13.Cu")
		(net "M_H_CPU0_SA_CA<3>")
	)
	(gr_poly
		(pts
			(xy 384.72491 -252.786134) (xy 384.624834 -252.686058) (xy 384.524758 -252.786134) (xy 384.524758 -252.830584)
			(xy 384.72491 -252.830584)
		)
		(stroke
			(width 0)
			(type solid)
		)
		(fill yes)
		(layer "In13.Cu")
		(net "M_H_CPU0_SA_CA<0>")
	)
	(gr_poly
		(pts
			(xy 384.72491 -251.166122) (xy 384.624834 -251.066046) (xy 384.524758 -251.166122) (xy 384.524758 -251.210572)
			(xy 384.72491 -251.210572)
		)
		(stroke
			(width 0)
			(type solid)
		)
		(fill yes)
		(layer "In13.Cu")
		(net "M_H_CPU0_SA_CS_N<0>")
	)
	(gr_poly
		(pts
			(xy 384.72491 -250.762262) (xy 384.72491 -250.717812) (xy 384.524758 -250.717812) (xy 384.524758 -250.762262)
			(xy 384.624834 -250.862338)
		)
		(stroke
			(width 0)
			(type solid)
		)
		(fill yes)
		(layer "In13.Cu")
		(net "M_H_CPU0_RESET_N")
	)
	(gr_poly
		(pts
			(xy 384.72491 -249.14225) (xy 384.72491 -249.0978) (xy 384.524758 -249.0978) (xy 384.524758 -249.14225)
			(xy 384.624834 -249.242326)
		)
		(stroke
			(width 0)
			(type solid)
		)
		(fill yes)
		(layer "In13.Cu")
		(net "M_H_CPU0_SA_CB<7>")
	)
	(gr_poly
		(pts
			(xy 384.72491 -247.926098) (xy 384.624834 -247.826022) (xy 384.524758 -247.926098) (xy 384.524758 -247.970548)
			(xy 384.72491 -247.970548)
		)
		(stroke
			(width 0)
			(type solid)
		)
		(fill yes)
		(layer "In13.Cu")
		(net "M_H_CPU0_SA_CB<4>")
	)
	(gr_poly
		(pts
			(xy 384.72491 -247.522492) (xy 384.72491 -247.47474) (xy 384.524758 -247.47474) (xy 384.524758 -247.522492)
			(xy 384.624834 -247.622314)
		)
		(stroke
			(width 0)
			(type solid)
		)
		(fill yes)
		(layer "In13.Cu")
		(net "M_H_CPU0_SA_DQS_DP<9>")
	)
	(gr_poly
		(pts
			(xy 384.72491 -246.305832) (xy 384.624834 -246.20601) (xy 384.524758 -246.305832) (xy 384.524758 -246.353584)
			(xy 384.72491 -246.353584)
		)
		(stroke
			(width 0)
			(type solid)
		)
		(fill yes)
		(layer "In13.Cu")
		(net "M_H_CPU0_SA_DQS_DP<4>")
	)
	(gr_poly
		(pts
			(xy 384.72491 -245.902226) (xy 384.72491 -245.857776) (xy 384.524758 -245.857776) (xy 384.524758 -245.902226)
			(xy 384.624834 -246.002302)
		)
		(stroke
			(width 0)
			(type solid)
		)
		(fill yes)
		(layer "In13.Cu")
		(net "M_H_CPU0_SA_CB<3>")
	)
	(gr_poly
		(pts
			(xy 384.72491 -244.686074) (xy 384.624834 -244.585998) (xy 384.524758 -244.686074) (xy 384.524758 -244.730524)
			(xy 384.72491 -244.730524)
		)
		(stroke
			(width 0)
			(type solid)
		)
		(fill yes)
		(layer "In13.Cu")
		(net "M_H_CPU0_SA_CB<0>")
	)
	(gr_poly
		(pts
			(xy 384.72491 -244.282214) (xy 384.72491 -244.237764) (xy 384.524758 -244.237764) (xy 384.524758 -244.282214)
			(xy 384.624834 -244.38229)
		)
		(stroke
			(width 0)
			(type solid)
		)
		(fill yes)
		(layer "In13.Cu")
		(net "M_H_CPU0_SA_DQ<31>")
	)
	(gr_poly
		(pts
			(xy 384.72491 -243.066062) (xy 384.624834 -242.965986) (xy 384.524758 -243.066062) (xy 384.524758 -243.110512)
			(xy 384.72491 -243.110512)
		)
		(stroke
			(width 0)
			(type solid)
		)
		(fill yes)
		(layer "In13.Cu")
		(net "M_H_CPU0_SA_DQ<28>")
	)
	(gr_poly
		(pts
			(xy 384.72491 -242.662456) (xy 384.72491 -242.614704) (xy 384.524758 -242.614704) (xy 384.524758 -242.662456)
			(xy 384.624834 -242.762278)
		)
		(stroke
			(width 0)
			(type solid)
		)
		(fill yes)
		(layer "In13.Cu")
		(net "M_H_CPU0_SA_DQS_DP<8>")
	)
	(gr_poly
		(pts
			(xy 384.72491 -241.445796) (xy 384.624834 -241.345974) (xy 384.524758 -241.445796) (xy 384.524758 -241.493548)
			(xy 384.72491 -241.493548)
		)
		(stroke
			(width 0)
			(type solid)
		)
		(fill yes)
		(layer "In13.Cu")
		(net "M_H_CPU0_SA_DQS_DP<3>")
	)
	(gr_poly
		(pts
			(xy 384.72491 -241.04219) (xy 384.72491 -240.99774) (xy 384.524758 -240.99774) (xy 384.524758 -241.04219)
			(xy 384.624834 -241.142266)
		)
		(stroke
			(width 0)
			(type solid)
		)
		(fill yes)
		(layer "In13.Cu")
		(net "M_H_CPU0_SA_DQ<27>")
	)
	(gr_poly
		(pts
			(xy 384.72491 -239.826038) (xy 384.624834 -239.725962) (xy 384.524758 -239.826038) (xy 384.524758 -239.870488)
			(xy 384.72491 -239.870488)
		)
		(stroke
			(width 0)
			(type solid)
		)
		(fill yes)
		(layer "In13.Cu")
		(net "M_H_CPU0_SA_DQ<24>")
	)
	(gr_poly
		(pts
			(xy 384.72491 -239.422178) (xy 384.72491 -239.377728) (xy 384.524758 -239.377728) (xy 384.524758 -239.422178)
			(xy 384.624834 -239.522254)
		)
		(stroke
			(width 0)
			(type solid)
		)
		(fill yes)
		(layer "In13.Cu")
		(net "M_H_CPU0_SA_DQ<23>")
	)
	(gr_poly
		(pts
			(xy 384.72491 -238.206026) (xy 384.624834 -238.10595) (xy 384.524758 -238.206026) (xy 384.524758 -238.250476)
			(xy 384.72491 -238.250476)
		)
		(stroke
			(width 0)
			(type solid)
		)
		(fill yes)
		(layer "In13.Cu")
		(net "M_H_CPU0_SA_DQ<20>")
	)
	(gr_poly
		(pts
			(xy 384.72491 -237.80242) (xy 384.72491 -237.754668) (xy 384.524758 -237.754668) (xy 384.524758 -237.80242)
			(xy 384.624834 -237.902242)
		)
		(stroke
			(width 0)
			(type solid)
		)
		(fill yes)
		(layer "In13.Cu")
		(net "M_H_CPU0_SA_DQS_DP<7>")
	)
	(gr_poly
		(pts
			(xy 384.72491 -236.58576) (xy 384.624834 -236.485938) (xy 384.524758 -236.58576) (xy 384.524758 -236.633512)
			(xy 384.72491 -236.633512)
		)
		(stroke
			(width 0)
			(type solid)
		)
		(fill yes)
		(layer "In13.Cu")
		(net "M_H_CPU0_SA_DQS_DP<2>")
	)
	(gr_poly
		(pts
			(xy 384.72491 -236.182154) (xy 384.72491 -236.137704) (xy 384.524758 -236.137704) (xy 384.524758 -236.182154)
			(xy 384.624834 -236.28223)
		)
		(stroke
			(width 0)
			(type solid)
		)
		(fill yes)
		(layer "In13.Cu")
		(net "M_H_CPU0_SA_DQ<19>")
	)
	(gr_poly
		(pts
			(xy 384.72491 -234.966002) (xy 384.624834 -234.865926) (xy 384.524758 -234.966002) (xy 384.524758 -235.010452)
			(xy 384.72491 -235.010452)
		)
		(stroke
			(width 0)
			(type solid)
		)
		(fill yes)
		(layer "In13.Cu")
		(net "M_H_CPU0_SA_DQ<16>")
	)
	(gr_poly
		(pts
			(xy 384.72491 -234.562142) (xy 384.72491 -234.517692) (xy 384.524758 -234.517692) (xy 384.524758 -234.562142)
			(xy 384.624834 -234.662218)
		)
		(stroke
			(width 0)
			(type solid)
		)
		(fill yes)
		(layer "In13.Cu")
		(net "M_H_CPU0_SA_DQ<15>")
	)
	(gr_poly
		(pts
			(xy 384.72491 -233.34599) (xy 384.624834 -233.245914) (xy 384.524758 -233.34599) (xy 384.524758 -233.39044)
			(xy 384.72491 -233.39044)
		)
		(stroke
			(width 0)
			(type solid)
		)
		(fill yes)
		(layer "In13.Cu")
		(net "M_H_CPU0_SA_DQ<12>")
	)
	(gr_poly
		(pts
			(xy 384.72491 -232.942384) (xy 384.72491 -232.894632) (xy 384.524758 -232.894632) (xy 384.524758 -232.942384)
			(xy 384.624834 -233.042206)
		)
		(stroke
			(width 0)
			(type solid)
		)
		(fill yes)
		(layer "In13.Cu")
		(net "M_H_CPU0_SA_DQS_DP<6>")
	)
	(gr_poly
		(pts
			(xy 384.72491 -231.725724) (xy 384.624834 -231.625902) (xy 384.524758 -231.725724) (xy 384.524758 -231.773476)
			(xy 384.72491 -231.773476)
		)
		(stroke
			(width 0)
			(type solid)
		)
		(fill yes)
		(layer "In13.Cu")
		(net "M_H_CPU0_SA_DQS_DP<1>")
	)
	(gr_poly
		(pts
			(xy 384.72491 -231.322372) (xy 384.72491 -231.277922) (xy 384.524758 -231.277922) (xy 384.524758 -231.322372)
			(xy 384.624834 -231.422448)
		)
		(stroke
			(width 0)
			(type solid)
		)
		(fill yes)
		(layer "In13.Cu")
		(net "M_H_CPU0_SA_DQ<11>")
	)
	(gr_poly
		(pts
			(xy 384.72491 -230.105966) (xy 384.624834 -230.006144) (xy 384.524758 -230.105966) (xy 384.524758 -230.150416)
			(xy 384.72491 -230.150416)
		)
		(stroke
			(width 0)
			(type solid)
		)
		(fill yes)
		(layer "In13.Cu")
		(net "M_H_CPU0_SA_DQ<8>")
	)
	(gr_poly
		(pts
			(xy 384.72491 -229.70236) (xy 384.72491 -229.65791) (xy 384.524758 -229.65791) (xy 384.524758 -229.70236)
			(xy 384.624834 -229.802436)
		)
		(stroke
			(width 0)
			(type solid)
		)
		(fill yes)
		(layer "In13.Cu")
		(net "M_H_CPU0_SA_DQ<7>")
	)
	(gr_poly
		(pts
			(xy 384.72491 -228.486208) (xy 384.624834 -228.386132) (xy 384.524758 -228.486208) (xy 384.524758 -228.530658)
			(xy 384.72491 -228.530658)
		)
		(stroke
			(width 0)
			(type solid)
		)
		(fill yes)
		(layer "In13.Cu")
		(net "M_H_CPU0_SA_DQ<4>")
	)
	(gr_poly
		(pts
			(xy 384.72491 -228.082602) (xy 384.72491 -228.03485) (xy 384.524758 -228.03485) (xy 384.524758 -228.082602)
			(xy 384.624834 -228.182424)
		)
		(stroke
			(width 0)
			(type solid)
		)
		(fill yes)
		(layer "In13.Cu")
		(net "M_H_CPU0_SA_DQS_DP<5>")
	)
	(gr_poly
		(pts
			(xy 384.72491 -226.865942) (xy 384.624834 -226.76612) (xy 384.524758 -226.865942) (xy 384.524758 -226.913694)
			(xy 384.72491 -226.913694)
		)
		(stroke
			(width 0)
			(type solid)
		)
		(fill yes)
		(layer "In13.Cu")
		(net "M_H_CPU0_SA_DQS_DP<0>")
	)
	(gr_poly
		(pts
			(xy 384.72491 -226.462336) (xy 384.72491 -226.417886) (xy 384.524758 -226.417886) (xy 384.524758 -226.462336)
			(xy 384.624834 -226.562412)
		)
		(stroke
			(width 0)
			(type solid)
		)
		(fill yes)
		(layer "In13.Cu")
		(net "M_H_CPU0_SA_DQ<3>")
	)
	(gr_poly
		(pts
			(xy 384.72491 -225.246184) (xy 384.624834 -225.146108) (xy 384.524758 -225.246184) (xy 384.524758 -225.290634)
			(xy 384.72491 -225.290634)
		)
		(stroke
			(width 0)
			(type solid)
		)
		(fill yes)
		(layer "In13.Cu")
		(net "M_H_CPU0_SA_DQ<0>")
	)
	(gr_poly
		(pts
			(xy 385.024884 -292.91788) (xy 384.924808 -292.817804) (xy 384.824732 -292.91788) (xy 384.824732 -292.96233)
			(xy 385.024884 -292.96233)
		)
		(stroke
			(width 0)
			(type solid)
		)
		(fill yes)
		(layer "In13.Cu")
		(net "M_H_CPU0_SB_DQ<29>")
	)
	(gr_poly
		(pts
			(xy 385.024884 -292.51402) (xy 385.024884 -292.46957) (xy 384.824732 -292.46957) (xy 384.824732 -292.51402)
			(xy 384.924808 -292.614096)
		)
		(stroke
			(width 0)
			(type solid)
		)
		(fill yes)
		(layer "In13.Cu")
		(net "M_H_CPU0_SB_DQ<30>")
	)
	(gr_poly
		(pts
			(xy 385.024884 -291.297614) (xy 384.924808 -291.197792) (xy 384.824732 -291.297614) (xy 384.824732 -291.345366)
			(xy 385.024884 -291.345366)
		)
		(stroke
			(width 0)
			(type solid)
		)
		(fill yes)
		(layer "In13.Cu")
		(net "M_H_CPU0_SB_DQS_DN<8>")
	)
	(gr_poly
		(pts
			(xy 385.024884 -290.894262) (xy 385.024884 -290.84651) (xy 384.824732 -290.84651) (xy 384.824732 -290.894262)
			(xy 384.924808 -290.994084)
		)
		(stroke
			(width 0)
			(type solid)
		)
		(fill yes)
		(layer "In13.Cu")
		(net "M_H_CPU0_SB_DQS_DN<3>")
	)
	(gr_poly
		(pts
			(xy 385.024884 -289.677856) (xy 384.924808 -289.57778) (xy 384.824732 -289.677856) (xy 384.824732 -289.722306)
			(xy 385.024884 -289.722306)
		)
		(stroke
			(width 0)
			(type solid)
		)
		(fill yes)
		(layer "In13.Cu")
		(net "M_H_CPU0_SB_DQ<25>")
	)
	(gr_poly
		(pts
			(xy 385.024884 -289.273996) (xy 385.024884 -289.229546) (xy 384.824732 -289.229546) (xy 384.824732 -289.273996)
			(xy 384.924808 -289.374072)
		)
		(stroke
			(width 0)
			(type solid)
		)
		(fill yes)
		(layer "In13.Cu")
		(net "M_H_CPU0_SB_DQ<26>")
	)
	(gr_poly
		(pts
			(xy 385.024884 -288.057844) (xy 384.924808 -287.957768) (xy 384.824732 -288.057844) (xy 384.824732 -288.102294)
			(xy 385.024884 -288.102294)
		)
		(stroke
			(width 0)
			(type solid)
		)
		(fill yes)
		(layer "In13.Cu")
		(net "M_H_CPU0_SB_DQ<21>")
	)
	(gr_poly
		(pts
			(xy 385.024884 -287.654238) (xy 385.024884 -287.609788) (xy 384.824732 -287.609788) (xy 384.824732 -287.654238)
			(xy 384.924808 -287.75406)
		)
		(stroke
			(width 0)
			(type solid)
		)
		(fill yes)
		(layer "In13.Cu")
		(net "M_H_CPU0_SB_DQ<22>")
	)
	(gr_poly
		(pts
			(xy 385.024884 -286.437832) (xy 384.924808 -286.337756) (xy 384.824732 -286.437832) (xy 384.824732 -286.485584)
			(xy 385.024884 -286.485584)
		)
		(stroke
			(width 0)
			(type solid)
		)
		(fill yes)
		(layer "In13.Cu")
		(net "M_H_CPU0_SB_DQS_DN<7>")
	)
	(gr_poly
		(pts
			(xy 385.024884 -286.03448) (xy 385.024884 -285.986728) (xy 384.824732 -285.986728) (xy 384.824732 -286.03448)
			(xy 384.924808 -286.134302)
		)
		(stroke
			(width 0)
			(type solid)
		)
		(fill yes)
		(layer "In13.Cu")
		(net "M_H_CPU0_SB_DQS_DN<2>")
	)
	(gr_poly
		(pts
			(xy 385.024884 -284.818074) (xy 384.924808 -284.717998) (xy 384.824732 -284.818074) (xy 384.824732 -284.862524)
			(xy 385.024884 -284.862524)
		)
		(stroke
			(width 0)
			(type solid)
		)
		(fill yes)
		(layer "In13.Cu")
		(net "M_H_CPU0_SB_DQ<17>")
	)
	(gr_poly
		(pts
			(xy 385.024884 -284.414214) (xy 385.024884 -284.369764) (xy 384.824732 -284.369764) (xy 384.824732 -284.414214)
			(xy 384.924808 -284.51429)
		)
		(stroke
			(width 0)
			(type solid)
		)
		(fill yes)
		(layer "In13.Cu")
		(net "M_H_CPU0_SB_DQ<18>")
	)
	(gr_poly
		(pts
			(xy 385.024884 -283.198062) (xy 384.924808 -283.097986) (xy 384.824732 -283.198062) (xy 384.824732 -283.242512)
			(xy 385.024884 -283.242512)
		)
		(stroke
			(width 0)
			(type solid)
		)
		(fill yes)
		(layer "In13.Cu")
		(net "M_H_CPU0_SB_DQ<13>")
	)
	(gr_poly
		(pts
			(xy 385.024884 -282.794202) (xy 385.024884 -282.749752) (xy 384.824732 -282.749752) (xy 384.824732 -282.794202)
			(xy 384.924808 -282.894278)
		)
		(stroke
			(width 0)
			(type solid)
		)
		(fill yes)
		(layer "In13.Cu")
		(net "M_H_CPU0_SB_DQ<14>")
	)
	(gr_poly
		(pts
			(xy 385.024884 -281.577796) (xy 384.924808 -281.477974) (xy 384.824732 -281.577796) (xy 384.824732 -281.625548)
			(xy 385.024884 -281.625548)
		)
		(stroke
			(width 0)
			(type solid)
		)
		(fill yes)
		(layer "In13.Cu")
		(net "M_H_CPU0_SB_DQS_DN<6>")
	)
	(gr_poly
		(pts
			(xy 385.024884 -281.174444) (xy 385.024884 -281.126692) (xy 384.824732 -281.126692) (xy 384.824732 -281.174444)
			(xy 384.924808 -281.274266)
		)
		(stroke
			(width 0)
			(type solid)
		)
		(fill yes)
		(layer "In13.Cu")
		(net "M_H_CPU0_SB_DQS_DN<1>")
	)
	(gr_poly
		(pts
			(xy 385.024884 -279.958038) (xy 384.924808 -279.857962) (xy 384.824732 -279.958038) (xy 384.824732 -280.002488)
			(xy 385.024884 -280.002488)
		)
		(stroke
			(width 0)
			(type solid)
		)
		(fill yes)
		(layer "In13.Cu")
		(net "M_H_CPU0_SB_DQ<9>")
	)
	(gr_poly
		(pts
			(xy 385.024884 -279.554178) (xy 385.024884 -279.509728) (xy 384.824732 -279.509728) (xy 384.824732 -279.554178)
			(xy 384.924808 -279.654254)
		)
		(stroke
			(width 0)
			(type solid)
		)
		(fill yes)
		(layer "In13.Cu")
		(net "M_H_CPU0_SB_DQ<10>")
	)
	(gr_poly
		(pts
			(xy 385.024884 -278.338026) (xy 384.924808 -278.23795) (xy 384.824732 -278.338026) (xy 384.824732 -278.382476)
			(xy 385.024884 -278.382476)
		)
		(stroke
			(width 0)
			(type solid)
		)
		(fill yes)
		(layer "In13.Cu")
		(net "M_H_CPU0_SB_DQ<5>")
	)
	(gr_poly
		(pts
			(xy 385.024884 -277.934166) (xy 385.024884 -277.889716) (xy 384.824732 -277.889716) (xy 384.824732 -277.934166)
			(xy 384.924808 -278.034242)
		)
		(stroke
			(width 0)
			(type solid)
		)
		(fill yes)
		(layer "In13.Cu")
		(net "M_H_CPU0_SB_DQ<6>")
	)
	(gr_poly
		(pts
			(xy 385.024884 -276.71776) (xy 384.924808 -276.617938) (xy 384.824732 -276.71776) (xy 384.824732 -276.765512)
			(xy 385.024884 -276.765512)
		)
		(stroke
			(width 0)
			(type solid)
		)
		(fill yes)
		(layer "In13.Cu")
		(net "M_H_CPU0_SB_DQS_DN<5>")
	)
	(gr_poly
		(pts
			(xy 385.024884 -276.314408) (xy 385.024884 -276.266656) (xy 384.824732 -276.266656) (xy 384.824732 -276.314408)
			(xy 384.924808 -276.41423)
		)
		(stroke
			(width 0)
			(type solid)
		)
		(fill yes)
		(layer "In13.Cu")
		(net "M_H_CPU0_SB_DQS_DN<0>")
	)
	(gr_poly
		(pts
			(xy 385.024884 -275.098002) (xy 384.924808 -274.997926) (xy 384.824732 -275.098002) (xy 384.824732 -275.142452)
			(xy 385.024884 -275.142452)
		)
		(stroke
			(width 0)
			(type solid)
		)
		(fill yes)
		(layer "In13.Cu")
		(net "M_H_CPU0_SB_DQ<1>")
	)
	(gr_poly
		(pts
			(xy 385.024884 -274.694142) (xy 385.024884 -274.649692) (xy 384.824732 -274.649692) (xy 384.824732 -274.694142)
			(xy 384.924808 -274.794218)
		)
		(stroke
			(width 0)
			(type solid)
		)
		(fill yes)
		(layer "In13.Cu")
		(net "M_H_CPU0_SB_DQ<2>")
	)
	(gr_poly
		(pts
			(xy 385.024884 -273.47799) (xy 384.924808 -273.377914) (xy 384.824732 -273.47799) (xy 384.824732 -273.52244)
			(xy 385.024884 -273.52244)
		)
		(stroke
			(width 0)
			(type solid)
		)
		(fill yes)
		(layer "In13.Cu")
		(net "M_H_CPU0_SB_CB<1>")
	)
	(gr_poly
		(pts
			(xy 385.024884 -273.07413) (xy 385.024884 -273.02968) (xy 384.824732 -273.02968) (xy 384.824732 -273.07413)
			(xy 384.924808 -273.174206)
		)
		(stroke
			(width 0)
			(type solid)
		)
		(fill yes)
		(layer "In13.Cu")
		(net "M_H_CPU0_SB_CB<2>")
	)
	(gr_poly
		(pts
			(xy 385.024884 -271.857724) (xy 384.924808 -271.757902) (xy 384.824732 -271.857724) (xy 384.824732 -271.905476)
			(xy 385.024884 -271.905476)
		)
		(stroke
			(width 0)
			(type solid)
		)
		(fill yes)
		(layer "In13.Cu")
		(net "M_H_CPU0_SB_DQS_DN<4>")
	)
	(gr_poly
		(pts
			(xy 385.024884 -271.454372) (xy 385.024884 -271.40662) (xy 384.824732 -271.40662) (xy 384.824732 -271.454372)
			(xy 384.924808 -271.554194)
		)
		(stroke
			(width 0)
			(type solid)
		)
		(fill yes)
		(layer "In13.Cu")
		(net "M_H_CPU0_SB_DQS_DN<9>")
	)
	(gr_poly
		(pts
			(xy 385.024884 -270.237966) (xy 384.924808 -270.13789) (xy 384.824732 -270.237966) (xy 384.824732 -270.282416)
			(xy 385.024884 -270.282416)
		)
		(stroke
			(width 0)
			(type solid)
		)
		(fill yes)
		(layer "In13.Cu")
		(net "M_H_CPU0_SB_CB<5>")
	)
	(gr_poly
		(pts
			(xy 385.024884 -269.834106) (xy 385.024884 -269.789656) (xy 384.824732 -269.789656) (xy 384.824732 -269.834106)
			(xy 384.924808 -269.934182)
		)
		(stroke
			(width 0)
			(type solid)
		)
		(fill yes)
		(layer "In13.Cu")
		(net "M_H_CPU0_SB_CB<6>")
	)
	(gr_poly
		(pts
			(xy 385.024884 -266.997942) (xy 384.924808 -266.897866) (xy 384.824732 -266.997942) (xy 384.824732 -267.042392)
			(xy 385.024884 -267.042392)
		)
		(stroke
			(width 0)
			(type solid)
		)
		(fill yes)
		(layer "In13.Cu")
		(net "M_H_CPU0_SA_RSP<0>")
	)
	(gr_poly
		(pts
			(xy 385.024884 -266.594082) (xy 385.024884 -266.549632) (xy 384.824732 -266.549632) (xy 384.824732 -266.594082)
			(xy 384.924808 -266.694158)
		)
		(stroke
			(width 0)
			(type solid)
		)
		(fill yes)
		(layer "In13.Cu")
		(net "M_H_CPU0_SB_CS_N<1>")
	)
	(gr_poly
		(pts
			(xy 385.024884 -265.37793) (xy 384.924808 -265.277854) (xy 384.824732 -265.37793) (xy 384.824732 -265.42238)
			(xy 385.024884 -265.42238)
		)
		(stroke
			(width 0)
			(type solid)
		)
		(fill yes)
		(layer "In13.Cu")
		(net "M_H_CPU0_SB_PAR")
	)
	(gr_poly
		(pts
			(xy 385.024884 -263.757918) (xy 384.924808 -263.657842) (xy 384.824732 -263.757918) (xy 384.824732 -263.802368)
			(xy 385.024884 -263.802368)
		)
		(stroke
			(width 0)
			(type solid)
		)
		(fill yes)
		(layer "In13.Cu")
		(net "M_H_CPU0_SB_CA<4>")
	)
	(gr_poly
		(pts
			(xy 385.024884 -263.354058) (xy 385.024884 -263.309608) (xy 384.824732 -263.309608) (xy 384.824732 -263.354058)
			(xy 384.924808 -263.454134)
		)
		(stroke
			(width 0)
			(type solid)
		)
		(fill yes)
		(layer "In13.Cu")
		(net "M_H_CPU0_SB_CA<3>")
	)
	(gr_poly
		(pts
			(xy 385.024884 -262.137906) (xy 384.924808 -262.03783) (xy 384.824732 -262.137906) (xy 384.824732 -262.182356)
			(xy 385.024884 -262.182356)
		)
		(stroke
			(width 0)
			(type solid)
		)
		(fill yes)
		(layer "In13.Cu")
		(net "M_H_CPU0_SB_CA<0>")
	)
	(gr_poly
		(pts
			(xy 385.19481 -256.432558) (xy 385.19481 -256.384806) (xy 384.994658 -256.384806) (xy 384.994658 -256.432558)
			(xy 385.094734 -256.53238)
		)
		(stroke
			(width 0)
			(type solid)
		)
		(fill yes)
		(layer "In13.Cu")
		(net "M_H_CPU0_CLK_DN<0>")
	)
	(gr_poly
		(pts
			(xy 385.19481 -255.216152) (xy 385.094734 -255.116076) (xy 384.994658 -255.216152) (xy 384.994658 -255.260602)
			(xy 385.19481 -255.260602)
		)
		(stroke
			(width 0)
			(type solid)
		)
		(fill yes)
		(layer "In13.Cu")
		(net "M_H_CPU0_SA_CA<6>")
	)
	(gr_poly
		(pts
			(xy 385.19481 -254.812292) (xy 385.19481 -254.767842) (xy 384.994658 -254.767842) (xy 384.994658 -254.812292)
			(xy 385.094734 -254.912368)
		)
		(stroke
			(width 0)
			(type solid)
		)
		(fill yes)
		(layer "In13.Cu")
		(net "M_H_CPU0_SA_CA<5>")
	)
	(gr_poly
		(pts
			(xy 385.19481 -253.59614) (xy 385.094734 -253.496064) (xy 384.994658 -253.59614) (xy 384.994658 -253.64059)
			(xy 385.19481 -253.64059)
		)
		(stroke
			(width 0)
			(type solid)
		)
		(fill yes)
		(layer "In13.Cu")
		(net "M_H_CPU0_SA_CA<2>")
	)
	(gr_poly
		(pts
			(xy 385.19481 -253.19228) (xy 385.19481 -253.14783) (xy 384.994658 -253.14783) (xy 384.994658 -253.19228)
			(xy 385.094734 -253.292356)
		)
		(stroke
			(width 0)
			(type solid)
		)
		(fill yes)
		(layer "In13.Cu")
		(net "M_H_CPU0_SA_CA<1>")
	)
	(gr_poly
		(pts
			(xy 385.19481 -251.976128) (xy 385.094734 -251.876052) (xy 384.994658 -251.976128) (xy 384.994658 -252.020578)
			(xy 385.19481 -252.020578)
		)
		(stroke
			(width 0)
			(type solid)
		)
		(fill yes)
		(layer "In13.Cu")
		(net "M_H_CPU0_SA_CS_N<1>")
	)
	(gr_poly
		(pts
			(xy 385.19481 -250.356116) (xy 385.094734 -250.25604) (xy 384.994658 -250.356116) (xy 384.994658 -250.400566)
			(xy 385.19481 -250.400566)
		)
		(stroke
			(width 0)
			(type solid)
		)
		(fill yes)
		(layer "In13.Cu")
		(net "M_H_CPU0_ALERT_R_N")
	)
	(gr_poly
		(pts
			(xy 385.19481 -248.736104) (xy 385.094734 -248.636028) (xy 384.994658 -248.736104) (xy 384.994658 -248.780554)
			(xy 385.19481 -248.780554)
		)
		(stroke
			(width 0)
			(type solid)
		)
		(fill yes)
		(layer "In13.Cu")
		(net "M_H_CPU0_SA_CB<5>")
	)
	(gr_poly
		(pts
			(xy 385.19481 -248.332244) (xy 385.19481 -248.287794) (xy 384.994658 -248.287794) (xy 384.994658 -248.332244)
			(xy 385.094734 -248.43232)
		)
		(stroke
			(width 0)
			(type solid)
		)
		(fill yes)
		(layer "In13.Cu")
		(net "M_H_CPU0_SA_CB<6>")
	)
	(gr_poly
		(pts
			(xy 385.19481 -247.115838) (xy 385.094734 -247.016016) (xy 384.994658 -247.115838) (xy 384.994658 -247.16359)
			(xy 385.19481 -247.16359)
		)
		(stroke
			(width 0)
			(type solid)
		)
		(fill yes)
		(layer "In13.Cu")
		(net "M_H_CPU0_SA_DQS_DN<9>")
	)
	(gr_poly
		(pts
			(xy 385.19481 -246.712486) (xy 385.19481 -246.664734) (xy 384.994658 -246.664734) (xy 384.994658 -246.712486)
			(xy 385.094734 -246.812308)
		)
		(stroke
			(width 0)
			(type solid)
		)
		(fill yes)
		(layer "In13.Cu")
		(net "M_H_CPU0_SA_DQS_DN<4>")
	)
	(gr_poly
		(pts
			(xy 385.19481 -245.49608) (xy 385.094734 -245.396004) (xy 384.994658 -245.49608) (xy 384.994658 -245.54053)
			(xy 385.19481 -245.54053)
		)
		(stroke
			(width 0)
			(type solid)
		)
		(fill yes)
		(layer "In13.Cu")
		(net "M_H_CPU0_SA_CB<1>")
	)
	(gr_poly
		(pts
			(xy 385.19481 -245.09222) (xy 385.19481 -245.04777) (xy 384.994658 -245.04777) (xy 384.994658 -245.09222)
			(xy 385.094734 -245.192296)
		)
		(stroke
			(width 0)
			(type solid)
		)
		(fill yes)
		(layer "In13.Cu")
		(net "M_H_CPU0_SA_CB<2>")
	)
	(gr_poly
		(pts
			(xy 385.19481 -243.876068) (xy 385.094734 -243.775992) (xy 384.994658 -243.876068) (xy 384.994658 -243.920518)
			(xy 385.19481 -243.920518)
		)
		(stroke
			(width 0)
			(type solid)
		)
		(fill yes)
		(layer "In13.Cu")
		(net "M_H_CPU0_SA_DQ<29>")
	)
	(gr_poly
		(pts
			(xy 385.19481 -243.472208) (xy 385.19481 -243.427758) (xy 384.994658 -243.427758) (xy 384.994658 -243.472208)
			(xy 385.094734 -243.572284)
		)
		(stroke
			(width 0)
			(type solid)
		)
		(fill yes)
		(layer "In13.Cu")
		(net "M_H_CPU0_SA_DQ<30>")
	)
	(gr_poly
		(pts
			(xy 385.19481 -242.255802) (xy 385.094734 -242.15598) (xy 384.994658 -242.255802) (xy 384.994658 -242.303554)
			(xy 385.19481 -242.303554)
		)
		(stroke
			(width 0)
			(type solid)
		)
		(fill yes)
		(layer "In13.Cu")
		(net "M_H_CPU0_SA_DQS_DN<8>")
	)
	(gr_poly
		(pts
			(xy 385.19481 -241.85245) (xy 385.19481 -241.804698) (xy 384.994658 -241.804698) (xy 384.994658 -241.85245)
			(xy 385.094734 -241.952272)
		)
		(stroke
			(width 0)
			(type solid)
		)
		(fill yes)
		(layer "In13.Cu")
		(net "M_H_CPU0_SA_DQS_DN<3>")
	)
	(gr_poly
		(pts
			(xy 385.19481 -240.636044) (xy 385.094734 -240.535968) (xy 384.994658 -240.636044) (xy 384.994658 -240.680494)
			(xy 385.19481 -240.680494)
		)
		(stroke
			(width 0)
			(type solid)
		)
		(fill yes)
		(layer "In13.Cu")
		(net "M_H_CPU0_SA_DQ<25>")
	)
	(gr_poly
		(pts
			(xy 385.19481 -240.232184) (xy 385.19481 -240.187734) (xy 384.994658 -240.187734) (xy 384.994658 -240.232184)
			(xy 385.094734 -240.33226)
		)
		(stroke
			(width 0)
			(type solid)
		)
		(fill yes)
		(layer "In13.Cu")
		(net "M_H_CPU0_SA_DQ<26>")
	)
	(gr_poly
		(pts
			(xy 385.19481 -239.016032) (xy 385.094734 -238.915956) (xy 384.994658 -239.016032) (xy 384.994658 -239.060482)
			(xy 385.19481 -239.060482)
		)
		(stroke
			(width 0)
			(type solid)
		)
		(fill yes)
		(layer "In13.Cu")
		(net "M_H_CPU0_SA_DQ<21>")
	)
	(gr_poly
		(pts
			(xy 385.19481 -238.612172) (xy 385.19481 -238.567722) (xy 384.994658 -238.567722) (xy 384.994658 -238.612172)
			(xy 385.094734 -238.712248)
		)
		(stroke
			(width 0)
			(type solid)
		)
		(fill yes)
		(layer "In13.Cu")
		(net "M_H_CPU0_SA_DQ<22>")
	)
	(gr_poly
		(pts
			(xy 385.19481 -237.395766) (xy 385.094734 -237.295944) (xy 384.994658 -237.395766) (xy 384.994658 -237.443518)
			(xy 385.19481 -237.443518)
		)
		(stroke
			(width 0)
			(type solid)
		)
		(fill yes)
		(layer "In13.Cu")
		(net "M_H_CPU0_SA_DQS_DN<7>")
	)
	(gr_poly
		(pts
			(xy 385.19481 -236.992414) (xy 385.19481 -236.944662) (xy 384.994658 -236.944662) (xy 384.994658 -236.992414)
			(xy 385.094734 -237.092236)
		)
		(stroke
			(width 0)
			(type solid)
		)
		(fill yes)
		(layer "In13.Cu")
		(net "M_H_CPU0_SA_DQS_DN<2>")
	)
	(gr_poly
		(pts
			(xy 385.19481 -235.776008) (xy 385.094734 -235.675932) (xy 384.994658 -235.776008) (xy 384.994658 -235.820458)
			(xy 385.19481 -235.820458)
		)
		(stroke
			(width 0)
			(type solid)
		)
		(fill yes)
		(layer "In13.Cu")
		(net "M_H_CPU0_SA_DQ<17>")
	)
	(gr_poly
		(pts
			(xy 385.19481 -235.372148) (xy 385.19481 -235.327698) (xy 384.994658 -235.327698) (xy 384.994658 -235.372148)
			(xy 385.094734 -235.472224)
		)
		(stroke
			(width 0)
			(type solid)
		)
		(fill yes)
		(layer "In13.Cu")
		(net "M_H_CPU0_SA_DQ<18>")
	)
	(gr_poly
		(pts
			(xy 385.19481 -234.155996) (xy 385.094734 -234.05592) (xy 384.994658 -234.155996) (xy 384.994658 -234.200446)
			(xy 385.19481 -234.200446)
		)
		(stroke
			(width 0)
			(type solid)
		)
		(fill yes)
		(layer "In13.Cu")
		(net "M_H_CPU0_SA_DQ<13>")
	)
	(gr_poly
		(pts
			(xy 385.19481 -233.752136) (xy 385.19481 -233.707686) (xy 384.994658 -233.707686) (xy 384.994658 -233.752136)
			(xy 385.094734 -233.852212)
		)
		(stroke
			(width 0)
			(type solid)
		)
		(fill yes)
		(layer "In13.Cu")
		(net "M_H_CPU0_SA_DQ<14>")
	)
	(gr_poly
		(pts
			(xy 385.19481 -232.53573) (xy 385.094734 -232.435908) (xy 384.994658 -232.53573) (xy 384.994658 -232.583482)
			(xy 385.19481 -232.583482)
		)
		(stroke
			(width 0)
			(type solid)
		)
		(fill yes)
		(layer "In13.Cu")
		(net "M_H_CPU0_SA_DQS_DN<6>")
	)
	(gr_poly
		(pts
			(xy 385.19481 -232.132378) (xy 385.19481 -232.084626) (xy 384.994658 -232.084626) (xy 384.994658 -232.132378)
			(xy 385.094734 -232.2322)
		)
		(stroke
			(width 0)
			(type solid)
		)
		(fill yes)
		(layer "In13.Cu")
		(net "M_H_CPU0_SA_DQS_DN<1>")
	)
	(gr_poly
		(pts
			(xy 385.19481 -230.915972) (xy 385.094734 -230.815896) (xy 384.994658 -230.915972) (xy 384.994658 -230.960422)
			(xy 385.19481 -230.960422)
		)
		(stroke
			(width 0)
			(type solid)
		)
		(fill yes)
		(layer "In13.Cu")
		(net "M_H_CPU0_SA_DQ<9>")
	)
	(gr_poly
		(pts
			(xy 385.19481 -230.512366) (xy 385.19481 -230.467916) (xy 384.994658 -230.467916) (xy 384.994658 -230.512366)
			(xy 385.094734 -230.612188)
		)
		(stroke
			(width 0)
			(type solid)
		)
		(fill yes)
		(layer "In13.Cu")
		(net "M_H_CPU0_SA_DQ<10>")
	)
	(gr_poly
		(pts
			(xy 385.19481 -229.29596) (xy 385.094734 -229.195884) (xy 384.994658 -229.29596) (xy 384.994658 -229.34041)
			(xy 385.19481 -229.34041)
		)
		(stroke
			(width 0)
			(type solid)
		)
		(fill yes)
		(layer "In13.Cu")
		(net "M_H_CPU0_SA_DQ<5>")
	)
	(gr_poly
		(pts
			(xy 385.19481 -228.892354) (xy 385.19481 -228.847904) (xy 384.994658 -228.847904) (xy 384.994658 -228.892354)
			(xy 385.094734 -228.99243)
		)
		(stroke
			(width 0)
			(type solid)
		)
		(fill yes)
		(layer "In13.Cu")
		(net "M_H_CPU0_SA_DQ<6>")
	)
	(gr_poly
		(pts
			(xy 385.19481 -227.675948) (xy 385.094734 -227.576126) (xy 384.994658 -227.675948) (xy 384.994658 -227.7237)
			(xy 385.19481 -227.7237)
		)
		(stroke
			(width 0)
			(type solid)
		)
		(fill yes)
		(layer "In13.Cu")
		(net "M_H_CPU0_SA_DQS_DN<5>")
	)
	(gr_poly
		(pts
			(xy 385.19481 -227.272596) (xy 385.19481 -227.224844) (xy 384.994658 -227.224844) (xy 384.994658 -227.272596)
			(xy 385.094734 -227.372418)
		)
		(stroke
			(width 0)
			(type solid)
		)
		(fill yes)
		(layer "In13.Cu")
		(net "M_H_CPU0_SA_DQS_DN<0>")
	)
	(gr_poly
		(pts
			(xy 385.19481 -226.05619) (xy 385.094734 -225.956114) (xy 384.994658 -226.05619) (xy 384.994658 -226.10064)
			(xy 385.19481 -226.10064)
		)
		(stroke
			(width 0)
			(type solid)
		)
		(fill yes)
		(layer "In13.Cu")
		(net "M_H_CPU0_SA_DQ<1>")
	)
	(gr_poly
		(pts
			(xy 385.19481 -225.65233) (xy 385.19481 -225.60788) (xy 384.994658 -225.60788) (xy 384.994658 -225.65233)
			(xy 385.094734 -225.752406)
		)
		(stroke
			(width 0)
			(type solid)
		)
		(fill yes)
		(layer "In13.Cu")
		(net "M_H_CPU0_SA_DQ<2>")
	)
	(gr_poly
		(pts
			(xy 385.494784 -293.324026) (xy 385.494784 -293.279576) (xy 385.294632 -293.279576) (xy 385.294632 -293.324026)
			(xy 385.394708 -293.424102)
		)
		(stroke
			(width 0)
			(type solid)
		)
		(fill yes)
		(layer "In13.Cu")
		(net "M_H_CPU0_SB_DQ<31>")
	)
	(gr_poly
		(pts
			(xy 385.494784 -292.107874) (xy 385.394708 -292.007798) (xy 385.294632 -292.107874) (xy 385.294632 -292.152324)
			(xy 385.494784 -292.152324)
		)
		(stroke
			(width 0)
			(type solid)
		)
		(fill yes)
		(layer "In13.Cu")
		(net "M_H_CPU0_SB_DQ<28>")
	)
	(gr_poly
		(pts
			(xy 385.494784 -291.704268) (xy 385.494784 -291.656516) (xy 385.294632 -291.656516) (xy 385.294632 -291.704268)
			(xy 385.394708 -291.80409)
		)
		(stroke
			(width 0)
			(type solid)
		)
		(fill yes)
		(layer "In13.Cu")
		(net "M_H_CPU0_SB_DQS_DP<8>")
	)
	(gr_poly
		(pts
			(xy 385.494784 -290.487608) (xy 385.394708 -290.387786) (xy 385.294632 -290.487608) (xy 385.294632 -290.53536)
			(xy 385.494784 -290.53536)
		)
		(stroke
			(width 0)
			(type solid)
		)
		(fill yes)
		(layer "In13.Cu")
		(net "M_H_CPU0_SB_DQS_DP<3>")
	)
	(gr_poly
		(pts
			(xy 385.494784 -290.084002) (xy 385.494784 -290.039552) (xy 385.294632 -290.039552) (xy 385.294632 -290.084002)
			(xy 385.394708 -290.184078)
		)
		(stroke
			(width 0)
			(type solid)
		)
		(fill yes)
		(layer "In13.Cu")
		(net "M_H_CPU0_SB_DQ<27>")
	)
	(gr_poly
		(pts
			(xy 385.494784 -288.86785) (xy 385.394708 -288.767774) (xy 385.294632 -288.86785) (xy 385.294632 -288.9123)
			(xy 385.494784 -288.9123)
		)
		(stroke
			(width 0)
			(type solid)
		)
		(fill yes)
		(layer "In13.Cu")
		(net "M_H_CPU0_SB_DQ<24>")
	)
	(gr_poly
		(pts
			(xy 385.494784 -288.464244) (xy 385.494784 -288.419794) (xy 385.294632 -288.419794) (xy 385.294632 -288.464244)
			(xy 385.394708 -288.56432)
		)
		(stroke
			(width 0)
			(type solid)
		)
		(fill yes)
		(layer "In13.Cu")
		(net "M_H_CPU0_SB_DQ<23>")
	)
	(gr_poly
		(pts
			(xy 385.494784 -287.247838) (xy 385.394708 -287.148016) (xy 385.294632 -287.247838) (xy 385.294632 -287.292288)
			(xy 385.494784 -287.292288)
		)
		(stroke
			(width 0)
			(type solid)
		)
		(fill yes)
		(layer "In13.Cu")
		(net "M_H_CPU0_SB_DQ<20>")
	)
	(gr_poly
		(pts
			(xy 385.494784 -286.844232) (xy 385.494784 -286.79648) (xy 385.294632 -286.79648) (xy 385.294632 -286.844232)
			(xy 385.394708 -286.944308)
		)
		(stroke
			(width 0)
			(type solid)
		)
		(fill yes)
		(layer "In13.Cu")
		(net "M_H_CPU0_SB_DQS_DP<7>")
	)
	(gr_poly
		(pts
			(xy 385.494784 -285.627826) (xy 385.394708 -285.528004) (xy 385.294632 -285.627826) (xy 385.294632 -285.675578)
			(xy 385.494784 -285.675578)
		)
		(stroke
			(width 0)
			(type solid)
		)
		(fill yes)
		(layer "In13.Cu")
		(net "M_H_CPU0_SB_DQS_DP<2>")
	)
	(gr_poly
		(pts
			(xy 385.494784 -285.22422) (xy 385.494784 -285.17977) (xy 385.294632 -285.17977) (xy 385.294632 -285.22422)
			(xy 385.394708 -285.324296)
		)
		(stroke
			(width 0)
			(type solid)
		)
		(fill yes)
		(layer "In13.Cu")
		(net "M_H_CPU0_SB_DQ<19>")
	)
	(gr_poly
		(pts
			(xy 385.494784 -284.008068) (xy 385.394708 -283.907992) (xy 385.294632 -284.008068) (xy 385.294632 -284.052518)
			(xy 385.494784 -284.052518)
		)
		(stroke
			(width 0)
			(type solid)
		)
		(fill yes)
		(layer "In13.Cu")
		(net "M_H_CPU0_SB_DQ<16>")
	)
	(gr_poly
		(pts
			(xy 385.494784 -283.604208) (xy 385.494784 -283.559758) (xy 385.294632 -283.559758) (xy 385.294632 -283.604208)
			(xy 385.394708 -283.704284)
		)
		(stroke
			(width 0)
			(type solid)
		)
		(fill yes)
		(layer "In13.Cu")
		(net "M_H_CPU0_SB_DQ<15>")
	)
	(gr_poly
		(pts
			(xy 385.494784 -282.388056) (xy 385.394708 -282.28798) (xy 385.294632 -282.388056) (xy 385.294632 -282.432506)
			(xy 385.494784 -282.432506)
		)
		(stroke
			(width 0)
			(type solid)
		)
		(fill yes)
		(layer "In13.Cu")
		(net "M_H_CPU0_SB_DQ<12>")
	)
	(gr_poly
		(pts
			(xy 385.494784 -281.98445) (xy 385.494784 -281.936698) (xy 385.294632 -281.936698) (xy 385.294632 -281.98445)
			(xy 385.394708 -282.084272)
		)
		(stroke
			(width 0)
			(type solid)
		)
		(fill yes)
		(layer "In13.Cu")
		(net "M_H_CPU0_SB_DQS_DP<6>")
	)
	(gr_poly
		(pts
			(xy 385.494784 -280.76779) (xy 385.394708 -280.667968) (xy 385.294632 -280.76779) (xy 385.294632 -280.815542)
			(xy 385.494784 -280.815542)
		)
		(stroke
			(width 0)
			(type solid)
		)
		(fill yes)
		(layer "In13.Cu")
		(net "M_H_CPU0_SB_DQS_DP<1>")
	)
	(gr_poly
		(pts
			(xy 385.494784 -280.364184) (xy 385.494784 -280.319734) (xy 385.294632 -280.319734) (xy 385.294632 -280.364184)
			(xy 385.394708 -280.46426)
		)
		(stroke
			(width 0)
			(type solid)
		)
		(fill yes)
		(layer "In13.Cu")
		(net "M_H_CPU0_SB_DQ<11>")
	)
	(gr_poly
		(pts
			(xy 385.494784 -279.148032) (xy 385.394708 -279.047956) (xy 385.294632 -279.148032) (xy 385.294632 -279.192482)
			(xy 385.494784 -279.192482)
		)
		(stroke
			(width 0)
			(type solid)
		)
		(fill yes)
		(layer "In13.Cu")
		(net "M_H_CPU0_SB_DQ<8>")
	)
	(gr_poly
		(pts
			(xy 385.494784 -278.744172) (xy 385.494784 -278.699722) (xy 385.294632 -278.699722) (xy 385.294632 -278.744172)
			(xy 385.394708 -278.844248)
		)
		(stroke
			(width 0)
			(type solid)
		)
		(fill yes)
		(layer "In13.Cu")
		(net "M_H_CPU0_SB_DQ<7>")
	)
	(gr_poly
		(pts
			(xy 385.494784 -277.52802) (xy 385.394708 -277.427944) (xy 385.294632 -277.52802) (xy 385.294632 -277.57247)
			(xy 385.494784 -277.57247)
		)
		(stroke
			(width 0)
			(type solid)
		)
		(fill yes)
		(layer "In13.Cu")
		(net "M_H_CPU0_SB_DQ<4>")
	)
	(gr_poly
		(pts
			(xy 385.494784 -277.124414) (xy 385.494784 -277.076662) (xy 385.294632 -277.076662) (xy 385.294632 -277.124414)
			(xy 385.394708 -277.224236)
		)
		(stroke
			(width 0)
			(type solid)
		)
		(fill yes)
		(layer "In13.Cu")
		(net "M_H_CPU0_SB_DQS_DP<5>")
	)
	(gr_poly
		(pts
			(xy 385.494784 -275.907754) (xy 385.394708 -275.807932) (xy 385.294632 -275.907754) (xy 385.294632 -275.955506)
			(xy 385.494784 -275.955506)
		)
		(stroke
			(width 0)
			(type solid)
		)
		(fill yes)
		(layer "In13.Cu")
		(net "M_H_CPU0_SB_DQS_DP<0>")
	)
	(gr_poly
		(pts
			(xy 385.494784 -275.504148) (xy 385.494784 -275.459698) (xy 385.294632 -275.459698) (xy 385.294632 -275.504148)
			(xy 385.394708 -275.604224)
		)
		(stroke
			(width 0)
			(type solid)
		)
		(fill yes)
		(layer "In13.Cu")
		(net "M_H_CPU0_SB_DQ<3>")
	)
	(gr_poly
		(pts
			(xy 385.494784 -274.287996) (xy 385.394708 -274.18792) (xy 385.294632 -274.287996) (xy 385.294632 -274.332446)
			(xy 385.494784 -274.332446)
		)
		(stroke
			(width 0)
			(type solid)
		)
		(fill yes)
		(layer "In13.Cu")
		(net "M_H_CPU0_SB_DQ<0>")
	)
	(gr_poly
		(pts
			(xy 385.494784 -273.884136) (xy 385.494784 -273.839686) (xy 385.294632 -273.839686) (xy 385.294632 -273.884136)
			(xy 385.394708 -273.984212)
		)
		(stroke
			(width 0)
			(type solid)
		)
		(fill yes)
		(layer "In13.Cu")
		(net "M_H_CPU0_SB_CB<3>")
	)
	(gr_poly
		(pts
			(xy 385.494784 -272.667984) (xy 385.394708 -272.567908) (xy 385.294632 -272.667984) (xy 385.294632 -272.712434)
			(xy 385.494784 -272.712434)
		)
		(stroke
			(width 0)
			(type solid)
		)
		(fill yes)
		(layer "In13.Cu")
		(net "M_H_CPU0_SB_CB<0>")
	)
	(gr_poly
		(pts
			(xy 385.494784 -272.264378) (xy 385.494784 -272.216626) (xy 385.294632 -272.216626) (xy 385.294632 -272.264378)
			(xy 385.394708 -272.3642)
		)
		(stroke
			(width 0)
			(type solid)
		)
		(fill yes)
		(layer "In13.Cu")
		(net "M_H_CPU0_SB_DQS_DP<4>")
	)
	(gr_poly
		(pts
			(xy 385.494784 -271.047718) (xy 385.394708 -270.947896) (xy 385.294632 -271.047718) (xy 385.294632 -271.09547)
			(xy 385.494784 -271.09547)
		)
		(stroke
			(width 0)
			(type solid)
		)
		(fill yes)
		(layer "In13.Cu")
		(net "M_H_CPU0_SB_DQS_DP<9>")
	)
	(gr_poly
		(pts
			(xy 385.494784 -270.644112) (xy 385.494784 -270.599662) (xy 385.294632 -270.599662) (xy 385.294632 -270.644112)
			(xy 385.394708 -270.744188)
		)
		(stroke
			(width 0)
			(type solid)
		)
		(fill yes)
		(layer "In13.Cu")
		(net "M_H_CPU0_SB_CB<7>")
	)
	(gr_poly
		(pts
			(xy 385.494784 -269.42796) (xy 385.394708 -269.327884) (xy 385.294632 -269.42796) (xy 385.294632 -269.47241)
			(xy 385.494784 -269.47241)
		)
		(stroke
			(width 0)
			(type solid)
		)
		(fill yes)
		(layer "In13.Cu")
		(net "M_H_CPU0_SB_CB<4>")
	)
	(gr_poly
		(pts
			(xy 385.494784 -267.807948) (xy 385.394708 -267.707872) (xy 385.294632 -267.807948) (xy 385.294632 -267.852398)
			(xy 385.494784 -267.852398)
		)
		(stroke
			(width 0)
			(type solid)
		)
		(fill yes)
		(layer "In13.Cu")
		(net "M_H_CPU0_SB_RSP<0>")
	)
	(gr_poly
		(pts
			(xy 385.494784 -265.784076) (xy 385.494784 -265.739626) (xy 385.294632 -265.739626) (xy 385.294632 -265.784076)
			(xy 385.394708 -265.884152)
		)
		(stroke
			(width 0)
			(type solid)
		)
		(fill yes)
		(layer "In13.Cu")
		(net "M_H_CPU0_SB_CS_N<0>")
	)
	(gr_poly
		(pts
			(xy 385.494784 -264.567924) (xy 385.394708 -264.467848) (xy 385.294632 -264.567924) (xy 385.294632 -264.612374)
			(xy 385.494784 -264.612374)
		)
		(stroke
			(width 0)
			(type solid)
		)
		(fill yes)
		(layer "In13.Cu")
		(net "M_H_CPU0_SB_CA<6>")
	)
	(gr_poly
		(pts
			(xy 385.494784 -264.164064) (xy 385.494784 -264.119614) (xy 385.294632 -264.119614) (xy 385.294632 -264.164064)
			(xy 385.394708 -264.26414)
		)
		(stroke
			(width 0)
			(type solid)
		)
		(fill yes)
		(layer "In13.Cu")
		(net "M_H_CPU0_SB_CA<5>")
	)
	(gr_poly
		(pts
			(xy 385.494784 -262.947912) (xy 385.394708 -262.847836) (xy 385.294632 -262.947912) (xy 385.294632 -262.992362)
			(xy 385.494784 -262.992362)
		)
		(stroke
			(width 0)
			(type solid)
		)
		(fill yes)
		(layer "In13.Cu")
		(net "M_H_CPU0_SB_CA<2>")
	)
	(gr_poly
		(pts
			(xy 385.494784 -262.544052) (xy 385.494784 -262.499602) (xy 385.294632 -262.499602) (xy 385.294632 -262.544052)
			(xy 385.394708 -262.644128)
		)
		(stroke
			(width 0)
			(type solid)
		)
		(fill yes)
		(layer "In13.Cu")
		(net "M_H_CPU0_SB_CA<1>")
	)
	(gr_poly
		(pts
			(xy 385.664964 -256.025904) (xy 385.564888 -255.926082) (xy 385.464812 -256.025904) (xy 385.464812 -256.073656)
			(xy 385.664964 -256.073656)
		)
		(stroke
			(width 0)
			(type solid)
		)
		(fill yes)
		(layer "In13.Cu")
		(net "M_H_CPU0_CLK_DP<0>")
	)
	(gr_poly
		(pts
			(xy 385.664964 -255.622298) (xy 385.664964 -255.577848) (xy 385.464812 -255.577848) (xy 385.464812 -255.622298)
			(xy 385.564888 -255.722374)
		)
		(stroke
			(width 0)
			(type solid)
		)
		(fill yes)
		(layer "In13.Cu")
		(net "M_H_CPU0_SA_PAR")
	)
	(gr_poly
		(pts
			(xy 385.664964 -254.406146) (xy 385.564888 -254.30607) (xy 385.464812 -254.406146) (xy 385.464812 -254.450596)
			(xy 385.664964 -254.450596)
		)
		(stroke
			(width 0)
			(type solid)
		)
		(fill yes)
		(layer "In13.Cu")
		(net "M_H_CPU0_SA_CA<4>")
	)
	(gr_poly
		(pts
			(xy 385.664964 -254.002286) (xy 385.664964 -253.957836) (xy 385.464812 -253.957836) (xy 385.464812 -254.002286)
			(xy 385.564888 -254.102362)
		)
		(stroke
			(width 0)
			(type solid)
		)
		(fill yes)
		(layer "In13.Cu")
		(net "M_H_CPU0_SA_CA<3>")
	)
	(gr_poly
		(pts
			(xy 385.664964 -252.786134) (xy 385.564888 -252.686058) (xy 385.464812 -252.786134) (xy 385.464812 -252.830584)
			(xy 385.664964 -252.830584)
		)
		(stroke
			(width 0)
			(type solid)
		)
		(fill yes)
		(layer "In13.Cu")
		(net "M_H_CPU0_SA_CA<0>")
	)
	(gr_poly
		(pts
			(xy 385.664964 -251.166122) (xy 385.564888 -251.066046) (xy 385.464812 -251.166122) (xy 385.464812 -251.210572)
			(xy 385.664964 -251.210572)
		)
		(stroke
			(width 0)
			(type solid)
		)
		(fill yes)
		(layer "In13.Cu")
		(net "M_H_CPU0_SA_CS_N<0>")
	)
	(gr_poly
		(pts
			(xy 385.664964 -250.762262) (xy 385.664964 -250.717812) (xy 385.464812 -250.717812) (xy 385.464812 -250.762262)
			(xy 385.564888 -250.862338)
		)
		(stroke
			(width 0)
			(type solid)
		)
		(fill yes)
		(layer "In13.Cu")
		(net "M_H_CPU0_RESET_N")
	)
	(gr_poly
		(pts
			(xy 385.664964 -249.14225) (xy 385.664964 -249.0978) (xy 385.464812 -249.0978) (xy 385.464812 -249.14225)
			(xy 385.564888 -249.242326)
		)
		(stroke
			(width 0)
			(type solid)
		)
		(fill yes)
		(layer "In13.Cu")
		(net "M_H_CPU0_SA_CB<7>")
	)
	(gr_poly
		(pts
			(xy 385.664964 -247.926098) (xy 385.564888 -247.826022) (xy 385.464812 -247.926098) (xy 385.464812 -247.970548)
			(xy 385.664964 -247.970548)
		)
		(stroke
			(width 0)
			(type solid)
		)
		(fill yes)
		(layer "In13.Cu")
		(net "M_H_CPU0_SA_CB<4>")
	)
	(gr_poly
		(pts
			(xy 385.664964 -247.522492) (xy 385.664964 -247.47474) (xy 385.464812 -247.47474) (xy 385.464812 -247.522492)
			(xy 385.564888 -247.622314)
		)
		(stroke
			(width 0)
			(type solid)
		)
		(fill yes)
		(layer "In13.Cu")
		(net "M_H_CPU0_SA_DQS_DP<9>")
	)
	(gr_poly
		(pts
			(xy 385.664964 -246.305832) (xy 385.564888 -246.20601) (xy 385.464812 -246.305832) (xy 385.464812 -246.353584)
			(xy 385.664964 -246.353584)
		)
		(stroke
			(width 0)
			(type solid)
		)
		(fill yes)
		(layer "In13.Cu")
		(net "M_H_CPU0_SA_DQS_DP<4>")
	)
	(gr_poly
		(pts
			(xy 385.664964 -245.902226) (xy 385.664964 -245.857776) (xy 385.464812 -245.857776) (xy 385.464812 -245.902226)
			(xy 385.564888 -246.002302)
		)
		(stroke
			(width 0)
			(type solid)
		)
		(fill yes)
		(layer "In13.Cu")
		(net "M_H_CPU0_SA_CB<3>")
	)
	(gr_poly
		(pts
			(xy 385.664964 -244.686074) (xy 385.564888 -244.585998) (xy 385.464812 -244.686074) (xy 385.464812 -244.730524)
			(xy 385.664964 -244.730524)
		)
		(stroke
			(width 0)
			(type solid)
		)
		(fill yes)
		(layer "In13.Cu")
		(net "M_H_CPU0_SA_CB<0>")
	)
	(gr_poly
		(pts
			(xy 385.664964 -244.282214) (xy 385.664964 -244.237764) (xy 385.464812 -244.237764) (xy 385.464812 -244.282214)
			(xy 385.564888 -244.38229)
		)
		(stroke
			(width 0)
			(type solid)
		)
		(fill yes)
		(layer "In13.Cu")
		(net "M_H_CPU0_SA_DQ<31>")
	)
	(gr_poly
		(pts
			(xy 385.664964 -243.066062) (xy 385.564888 -242.965986) (xy 385.464812 -243.066062) (xy 385.464812 -243.110512)
			(xy 385.664964 -243.110512)
		)
		(stroke
			(width 0)
			(type solid)
		)
		(fill yes)
		(layer "In13.Cu")
		(net "M_H_CPU0_SA_DQ<28>")
	)
	(gr_poly
		(pts
			(xy 385.664964 -242.662456) (xy 385.664964 -242.614704) (xy 385.464812 -242.614704) (xy 385.464812 -242.662456)
			(xy 385.564888 -242.762278)
		)
		(stroke
			(width 0)
			(type solid)
		)
		(fill yes)
		(layer "In13.Cu")
		(net "M_H_CPU0_SA_DQS_DP<8>")
	)
	(gr_poly
		(pts
			(xy 385.664964 -241.445796) (xy 385.564888 -241.345974) (xy 385.464812 -241.445796) (xy 385.464812 -241.493548)
			(xy 385.664964 -241.493548)
		)
		(stroke
			(width 0)
			(type solid)
		)
		(fill yes)
		(layer "In13.Cu")
		(net "M_H_CPU0_SA_DQS_DP<3>")
	)
	(gr_poly
		(pts
			(xy 385.664964 -241.04219) (xy 385.664964 -240.99774) (xy 385.464812 -240.99774) (xy 385.464812 -241.04219)
			(xy 385.564888 -241.142266)
		)
		(stroke
			(width 0)
			(type solid)
		)
		(fill yes)
		(layer "In13.Cu")
		(net "M_H_CPU0_SA_DQ<27>")
	)
	(gr_poly
		(pts
			(xy 385.664964 -239.826038) (xy 385.564888 -239.725962) (xy 385.464812 -239.826038) (xy 385.464812 -239.870488)
			(xy 385.664964 -239.870488)
		)
		(stroke
			(width 0)
			(type solid)
		)
		(fill yes)
		(layer "In13.Cu")
		(net "M_H_CPU0_SA_DQ<24>")
	)
	(gr_poly
		(pts
			(xy 385.664964 -239.422178) (xy 385.664964 -239.377728) (xy 385.464812 -239.377728) (xy 385.464812 -239.422178)
			(xy 385.564888 -239.522254)
		)
		(stroke
			(width 0)
			(type solid)
		)
		(fill yes)
		(layer "In13.Cu")
		(net "M_H_CPU0_SA_DQ<23>")
	)
	(gr_poly
		(pts
			(xy 385.664964 -238.206026) (xy 385.564888 -238.10595) (xy 385.464812 -238.206026) (xy 385.464812 -238.250476)
			(xy 385.664964 -238.250476)
		)
		(stroke
			(width 0)
			(type solid)
		)
		(fill yes)
		(layer "In13.Cu")
		(net "M_H_CPU0_SA_DQ<20>")
	)
	(gr_poly
		(pts
			(xy 385.664964 -237.80242) (xy 385.664964 -237.754668) (xy 385.464812 -237.754668) (xy 385.464812 -237.80242)
			(xy 385.564888 -237.902242)
		)
		(stroke
			(width 0)
			(type solid)
		)
		(fill yes)
		(layer "In13.Cu")
		(net "M_H_CPU0_SA_DQS_DP<7>")
	)
	(gr_poly
		(pts
			(xy 385.664964 -236.58576) (xy 385.564888 -236.485938) (xy 385.464812 -236.58576) (xy 385.464812 -236.633512)
			(xy 385.664964 -236.633512)
		)
		(stroke
			(width 0)
			(type solid)
		)
		(fill yes)
		(layer "In13.Cu")
		(net "M_H_CPU0_SA_DQS_DP<2>")
	)
	(gr_poly
		(pts
			(xy 385.664964 -236.182154) (xy 385.664964 -236.137704) (xy 385.464812 -236.137704) (xy 385.464812 -236.182154)
			(xy 385.564888 -236.28223)
		)
		(stroke
			(width 0)
			(type solid)
		)
		(fill yes)
		(layer "In13.Cu")
		(net "M_H_CPU0_SA_DQ<19>")
	)
	(gr_poly
		(pts
			(xy 385.664964 -234.966002) (xy 385.564888 -234.865926) (xy 385.464812 -234.966002) (xy 385.464812 -235.010452)
			(xy 385.664964 -235.010452)
		)
		(stroke
			(width 0)
			(type solid)
		)
		(fill yes)
		(layer "In13.Cu")
		(net "M_H_CPU0_SA_DQ<16>")
	)
	(gr_poly
		(pts
			(xy 385.664964 -234.562142) (xy 385.664964 -234.517692) (xy 385.464812 -234.517692) (xy 385.464812 -234.562142)
			(xy 385.564888 -234.662218)
		)
		(stroke
			(width 0)
			(type solid)
		)
		(fill yes)
		(layer "In13.Cu")
		(net "M_H_CPU0_SA_DQ<15>")
	)
	(gr_poly
		(pts
			(xy 385.664964 -233.34599) (xy 385.564888 -233.245914) (xy 385.464812 -233.34599) (xy 385.464812 -233.39044)
			(xy 385.664964 -233.39044)
		)
		(stroke
			(width 0)
			(type solid)
		)
		(fill yes)
		(layer "In13.Cu")
		(net "M_H_CPU0_SA_DQ<12>")
	)
	(gr_poly
		(pts
			(xy 385.664964 -232.942384) (xy 385.664964 -232.894632) (xy 385.464812 -232.894632) (xy 385.464812 -232.942384)
			(xy 385.564888 -233.042206)
		)
		(stroke
			(width 0)
			(type solid)
		)
		(fill yes)
		(layer "In13.Cu")
		(net "M_H_CPU0_SA_DQS_DP<6>")
	)
	(gr_poly
		(pts
			(xy 385.664964 -231.725724) (xy 385.564888 -231.625902) (xy 385.464812 -231.725724) (xy 385.464812 -231.773476)
			(xy 385.664964 -231.773476)
		)
		(stroke
			(width 0)
			(type solid)
		)
		(fill yes)
		(layer "In13.Cu")
		(net "M_H_CPU0_SA_DQS_DP<1>")
	)
	(gr_poly
		(pts
			(xy 385.664964 -231.322372) (xy 385.664964 -231.277922) (xy 385.464812 -231.277922) (xy 385.464812 -231.322372)
			(xy 385.564888 -231.422448)
		)
		(stroke
			(width 0)
			(type solid)
		)
		(fill yes)
		(layer "In13.Cu")
		(net "M_H_CPU0_SA_DQ<11>")
	)
	(gr_poly
		(pts
			(xy 385.664964 -230.105966) (xy 385.564888 -230.006144) (xy 385.464812 -230.105966) (xy 385.464812 -230.150416)
			(xy 385.664964 -230.150416)
		)
		(stroke
			(width 0)
			(type solid)
		)
		(fill yes)
		(layer "In13.Cu")
		(net "M_H_CPU0_SA_DQ<8>")
	)
	(gr_poly
		(pts
			(xy 385.664964 -229.70236) (xy 385.664964 -229.65791) (xy 385.464812 -229.65791) (xy 385.464812 -229.70236)
			(xy 385.564888 -229.802436)
		)
		(stroke
			(width 0)
			(type solid)
		)
		(fill yes)
		(layer "In13.Cu")
		(net "M_H_CPU0_SA_DQ<7>")
	)
	(gr_poly
		(pts
			(xy 385.664964 -228.486208) (xy 385.564888 -228.386132) (xy 385.464812 -228.486208) (xy 385.464812 -228.530658)
			(xy 385.664964 -228.530658)
		)
		(stroke
			(width 0)
			(type solid)
		)
		(fill yes)
		(layer "In13.Cu")
		(net "M_H_CPU0_SA_DQ<4>")
	)
	(gr_poly
		(pts
			(xy 385.664964 -228.082602) (xy 385.664964 -228.03485) (xy 385.464812 -228.03485) (xy 385.464812 -228.082602)
			(xy 385.564888 -228.182424)
		)
		(stroke
			(width 0)
			(type solid)
		)
		(fill yes)
		(layer "In13.Cu")
		(net "M_H_CPU0_SA_DQS_DP<5>")
	)
	(gr_poly
		(pts
			(xy 385.664964 -226.865942) (xy 385.564888 -226.76612) (xy 385.464812 -226.865942) (xy 385.464812 -226.913694)
			(xy 385.664964 -226.913694)
		)
		(stroke
			(width 0)
			(type solid)
		)
		(fill yes)
		(layer "In13.Cu")
		(net "M_H_CPU0_SA_DQS_DP<0>")
	)
	(gr_poly
		(pts
			(xy 385.664964 -226.462336) (xy 385.664964 -226.417886) (xy 385.464812 -226.417886) (xy 385.464812 -226.462336)
			(xy 385.564888 -226.562412)
		)
		(stroke
			(width 0)
			(type solid)
		)
		(fill yes)
		(layer "In13.Cu")
		(net "M_H_CPU0_SA_DQ<3>")
	)
	(gr_poly
		(pts
			(xy 385.664964 -225.246184) (xy 385.564888 -225.146108) (xy 385.464812 -225.246184) (xy 385.464812 -225.290634)
			(xy 385.664964 -225.290634)
		)
		(stroke
			(width 0)
			(type solid)
		)
		(fill yes)
		(layer "In13.Cu")
		(net "M_H_CPU0_SA_DQ<0>")
	)
	(gr_poly
		(pts
			(xy 385.964938 -292.91788) (xy 385.864862 -292.817804) (xy 385.764786 -292.91788) (xy 385.764786 -292.96233)
			(xy 385.964938 -292.96233)
		)
		(stroke
			(width 0)
			(type solid)
		)
		(fill yes)
		(layer "In13.Cu")
		(net "M_H_CPU0_SB_DQ<29>")
	)
	(gr_poly
		(pts
			(xy 385.964938 -292.51402) (xy 385.964938 -292.46957) (xy 385.764786 -292.46957) (xy 385.764786 -292.51402)
			(xy 385.864862 -292.614096)
		)
		(stroke
			(width 0)
			(type solid)
		)
		(fill yes)
		(layer "In13.Cu")
		(net "M_H_CPU0_SB_DQ<30>")
	)
	(gr_poly
		(pts
			(xy 385.964938 -291.297614) (xy 385.864862 -291.197792) (xy 385.764786 -291.297614) (xy 385.764786 -291.345366)
			(xy 385.964938 -291.345366)
		)
		(stroke
			(width 0)
			(type solid)
		)
		(fill yes)
		(layer "In13.Cu")
		(net "M_H_CPU0_SB_DQS_DN<8>")
	)
	(gr_poly
		(pts
			(xy 385.964938 -290.894262) (xy 385.964938 -290.84651) (xy 385.764786 -290.84651) (xy 385.764786 -290.894262)
			(xy 385.864862 -290.994084)
		)
		(stroke
			(width 0)
			(type solid)
		)
		(fill yes)
		(layer "In13.Cu")
		(net "M_H_CPU0_SB_DQS_DN<3>")
	)
	(gr_poly
		(pts
			(xy 385.964938 -289.677856) (xy 385.864862 -289.57778) (xy 385.764786 -289.677856) (xy 385.764786 -289.722306)
			(xy 385.964938 -289.722306)
		)
		(stroke
			(width 0)
			(type solid)
		)
		(fill yes)
		(layer "In13.Cu")
		(net "M_H_CPU0_SB_DQ<25>")
	)
	(gr_poly
		(pts
			(xy 385.964938 -289.273996) (xy 385.964938 -289.229546) (xy 385.764786 -289.229546) (xy 385.764786 -289.273996)
			(xy 385.864862 -289.374072)
		)
		(stroke
			(width 0)
			(type solid)
		)
		(fill yes)
		(layer "In13.Cu")
		(net "M_H_CPU0_SB_DQ<26>")
	)
	(gr_poly
		(pts
			(xy 385.964938 -288.057844) (xy 385.864862 -287.957768) (xy 385.764786 -288.057844) (xy 385.764786 -288.102294)
			(xy 385.964938 -288.102294)
		)
		(stroke
			(width 0)
			(type solid)
		)
		(fill yes)
		(layer "In13.Cu")
		(net "M_H_CPU0_SB_DQ<21>")
	)
	(gr_poly
		(pts
			(xy 385.964938 -287.654238) (xy 385.964938 -287.609788) (xy 385.764786 -287.609788) (xy 385.764786 -287.654238)
			(xy 385.864862 -287.75406)
		)
		(stroke
			(width 0)
			(type solid)
		)
		(fill yes)
		(layer "In13.Cu")
		(net "M_H_CPU0_SB_DQ<22>")
	)
	(gr_poly
		(pts
			(xy 385.964938 -286.437832) (xy 385.864862 -286.337756) (xy 385.764786 -286.437832) (xy 385.764786 -286.485584)
			(xy 385.964938 -286.485584)
		)
		(stroke
			(width 0)
			(type solid)
		)
		(fill yes)
		(layer "In13.Cu")
		(net "M_H_CPU0_SB_DQS_DN<7>")
	)
	(gr_poly
		(pts
			(xy 385.964938 -286.03448) (xy 385.964938 -285.986728) (xy 385.764786 -285.986728) (xy 385.764786 -286.03448)
			(xy 385.864862 -286.134302)
		)
		(stroke
			(width 0)
			(type solid)
		)
		(fill yes)
		(layer "In13.Cu")
		(net "M_H_CPU0_SB_DQS_DN<2>")
	)
	(gr_poly
		(pts
			(xy 385.964938 -284.818074) (xy 385.864862 -284.717998) (xy 385.764786 -284.818074) (xy 385.764786 -284.862524)
			(xy 385.964938 -284.862524)
		)
		(stroke
			(width 0)
			(type solid)
		)
		(fill yes)
		(layer "In13.Cu")
		(net "M_H_CPU0_SB_DQ<17>")
	)
	(gr_poly
		(pts
			(xy 385.964938 -284.414214) (xy 385.964938 -284.369764) (xy 385.764786 -284.369764) (xy 385.764786 -284.414214)
			(xy 385.864862 -284.51429)
		)
		(stroke
			(width 0)
			(type solid)
		)
		(fill yes)
		(layer "In13.Cu")
		(net "M_H_CPU0_SB_DQ<18>")
	)
	(gr_poly
		(pts
			(xy 385.964938 -283.198062) (xy 385.864862 -283.097986) (xy 385.764786 -283.198062) (xy 385.764786 -283.242512)
			(xy 385.964938 -283.242512)
		)
		(stroke
			(width 0)
			(type solid)
		)
		(fill yes)
		(layer "In13.Cu")
		(net "M_H_CPU0_SB_DQ<13>")
	)
	(gr_poly
		(pts
			(xy 385.964938 -282.794202) (xy 385.964938 -282.749752) (xy 385.764786 -282.749752) (xy 385.764786 -282.794202)
			(xy 385.864862 -282.894278)
		)
		(stroke
			(width 0)
			(type solid)
		)
		(fill yes)
		(layer "In13.Cu")
		(net "M_H_CPU0_SB_DQ<14>")
	)
	(gr_poly
		(pts
			(xy 385.964938 -281.577796) (xy 385.864862 -281.477974) (xy 385.764786 -281.577796) (xy 385.764786 -281.625548)
			(xy 385.964938 -281.625548)
		)
		(stroke
			(width 0)
			(type solid)
		)
		(fill yes)
		(layer "In13.Cu")
		(net "M_H_CPU0_SB_DQS_DN<6>")
	)
	(gr_poly
		(pts
			(xy 385.964938 -281.174444) (xy 385.964938 -281.126692) (xy 385.764786 -281.126692) (xy 385.764786 -281.174444)
			(xy 385.864862 -281.274266)
		)
		(stroke
			(width 0)
			(type solid)
		)
		(fill yes)
		(layer "In13.Cu")
		(net "M_H_CPU0_SB_DQS_DN<1>")
	)
	(gr_poly
		(pts
			(xy 385.964938 -279.958038) (xy 385.864862 -279.857962) (xy 385.764786 -279.958038) (xy 385.764786 -280.002488)
			(xy 385.964938 -280.002488)
		)
		(stroke
			(width 0)
			(type solid)
		)
		(fill yes)
		(layer "In13.Cu")
		(net "M_H_CPU0_SB_DQ<9>")
	)
	(gr_poly
		(pts
			(xy 385.964938 -279.554178) (xy 385.964938 -279.509728) (xy 385.764786 -279.509728) (xy 385.764786 -279.554178)
			(xy 385.864862 -279.654254)
		)
		(stroke
			(width 0)
			(type solid)
		)
		(fill yes)
		(layer "In13.Cu")
		(net "M_H_CPU0_SB_DQ<10>")
	)
	(gr_poly
		(pts
			(xy 385.964938 -278.338026) (xy 385.864862 -278.23795) (xy 385.764786 -278.338026) (xy 385.764786 -278.382476)
			(xy 385.964938 -278.382476)
		)
		(stroke
			(width 0)
			(type solid)
		)
		(fill yes)
		(layer "In13.Cu")
		(net "M_H_CPU0_SB_DQ<5>")
	)
	(gr_poly
		(pts
			(xy 385.964938 -277.934166) (xy 385.964938 -277.889716) (xy 385.764786 -277.889716) (xy 385.764786 -277.934166)
			(xy 385.864862 -278.034242)
		)
		(stroke
			(width 0)
			(type solid)
		)
		(fill yes)
		(layer "In13.Cu")
		(net "M_H_CPU0_SB_DQ<6>")
	)
	(gr_poly
		(pts
			(xy 385.964938 -276.71776) (xy 385.864862 -276.617938) (xy 385.764786 -276.71776) (xy 385.764786 -276.765512)
			(xy 385.964938 -276.765512)
		)
		(stroke
			(width 0)
			(type solid)
		)
		(fill yes)
		(layer "In13.Cu")
		(net "M_H_CPU0_SB_DQS_DN<5>")
	)
	(gr_poly
		(pts
			(xy 385.964938 -276.314408) (xy 385.964938 -276.266656) (xy 385.764786 -276.266656) (xy 385.764786 -276.314408)
			(xy 385.864862 -276.41423)
		)
		(stroke
			(width 0)
			(type solid)
		)
		(fill yes)
		(layer "In13.Cu")
		(net "M_H_CPU0_SB_DQS_DN<0>")
	)
	(gr_poly
		(pts
			(xy 385.964938 -275.098002) (xy 385.864862 -274.997926) (xy 385.764786 -275.098002) (xy 385.764786 -275.142452)
			(xy 385.964938 -275.142452)
		)
		(stroke
			(width 0)
			(type solid)
		)
		(fill yes)
		(layer "In13.Cu")
		(net "M_H_CPU0_SB_DQ<1>")
	)
	(gr_poly
		(pts
			(xy 385.964938 -274.694142) (xy 385.964938 -274.649692) (xy 385.764786 -274.649692) (xy 385.764786 -274.694142)
			(xy 385.864862 -274.794218)
		)
		(stroke
			(width 0)
			(type solid)
		)
		(fill yes)
		(layer "In13.Cu")
		(net "M_H_CPU0_SB_DQ<2>")
	)
	(gr_poly
		(pts
			(xy 385.964938 -273.47799) (xy 385.864862 -273.377914) (xy 385.764786 -273.47799) (xy 385.764786 -273.52244)
			(xy 385.964938 -273.52244)
		)
		(stroke
			(width 0)
			(type solid)
		)
		(fill yes)
		(layer "In13.Cu")
		(net "M_H_CPU0_SB_CB<1>")
	)
	(gr_poly
		(pts
			(xy 385.964938 -273.07413) (xy 385.964938 -273.02968) (xy 385.764786 -273.02968) (xy 385.764786 -273.07413)
			(xy 385.864862 -273.174206)
		)
		(stroke
			(width 0)
			(type solid)
		)
		(fill yes)
		(layer "In13.Cu")
		(net "M_H_CPU0_SB_CB<2>")
	)
	(gr_poly
		(pts
			(xy 385.964938 -271.857724) (xy 385.864862 -271.757902) (xy 385.764786 -271.857724) (xy 385.764786 -271.905476)
			(xy 385.964938 -271.905476)
		)
		(stroke
			(width 0)
			(type solid)
		)
		(fill yes)
		(layer "In13.Cu")
		(net "M_H_CPU0_SB_DQS_DN<4>")
	)
	(gr_poly
		(pts
			(xy 385.964938 -271.454372) (xy 385.964938 -271.40662) (xy 385.764786 -271.40662) (xy 385.764786 -271.454372)
			(xy 385.864862 -271.554194)
		)
		(stroke
			(width 0)
			(type solid)
		)
		(fill yes)
		(layer "In13.Cu")
		(net "M_H_CPU0_SB_DQS_DN<9>")
	)
	(gr_poly
		(pts
			(xy 385.964938 -270.237966) (xy 385.864862 -270.13789) (xy 385.764786 -270.237966) (xy 385.764786 -270.282416)
			(xy 385.964938 -270.282416)
		)
		(stroke
			(width 0)
			(type solid)
		)
		(fill yes)
		(layer "In13.Cu")
		(net "M_H_CPU0_SB_CB<5>")
	)
	(gr_poly
		(pts
			(xy 385.964938 -269.834106) (xy 385.964938 -269.789656) (xy 385.764786 -269.789656) (xy 385.764786 -269.834106)
			(xy 385.864862 -269.934182)
		)
		(stroke
			(width 0)
			(type solid)
		)
		(fill yes)
		(layer "In13.Cu")
		(net "M_H_CPU0_SB_CB<6>")
	)
	(gr_poly
		(pts
			(xy 385.964938 -266.997942) (xy 385.864862 -266.897866) (xy 385.764786 -266.997942) (xy 385.764786 -267.042392)
			(xy 385.964938 -267.042392)
		)
		(stroke
			(width 0)
			(type solid)
		)
		(fill yes)
		(layer "In13.Cu")
		(net "M_H_CPU0_SA_RSP<0>")
	)
	(gr_poly
		(pts
			(xy 385.964938 -266.594082) (xy 385.964938 -266.549632) (xy 385.764786 -266.549632) (xy 385.764786 -266.594082)
			(xy 385.864862 -266.694158)
		)
		(stroke
			(width 0)
			(type solid)
		)
		(fill yes)
		(layer "In13.Cu")
		(net "M_H_CPU0_SB_CS_N<1>")
	)
	(gr_poly
		(pts
			(xy 385.964938 -265.37793) (xy 385.864862 -265.277854) (xy 385.764786 -265.37793) (xy 385.764786 -265.42238)
			(xy 385.964938 -265.42238)
		)
		(stroke
			(width 0)
			(type solid)
		)
		(fill yes)
		(layer "In13.Cu")
		(net "M_H_CPU0_SB_PAR")
	)
	(gr_poly
		(pts
			(xy 385.964938 -263.757918) (xy 385.864862 -263.657842) (xy 385.764786 -263.757918) (xy 385.764786 -263.802368)
			(xy 385.964938 -263.802368)
		)
		(stroke
			(width 0)
			(type solid)
		)
		(fill yes)
		(layer "In13.Cu")
		(net "M_H_CPU0_SB_CA<4>")
	)
	(gr_poly
		(pts
			(xy 385.964938 -263.354058) (xy 385.964938 -263.309608) (xy 385.764786 -263.309608) (xy 385.764786 -263.354058)
			(xy 385.864862 -263.454134)
		)
		(stroke
			(width 0)
			(type solid)
		)
		(fill yes)
		(layer "In13.Cu")
		(net "M_H_CPU0_SB_CA<3>")
	)
	(gr_poly
		(pts
			(xy 385.964938 -262.137906) (xy 385.864862 -262.03783) (xy 385.764786 -262.137906) (xy 385.764786 -262.182356)
			(xy 385.964938 -262.182356)
		)
		(stroke
			(width 0)
			(type solid)
		)
		(fill yes)
		(layer "In13.Cu")
		(net "M_H_CPU0_SB_CA<0>")
	)
	(gr_poly
		(pts
			(xy 386.134864 -256.432558) (xy 386.134864 -256.384806) (xy 385.934712 -256.384806) (xy 385.934712 -256.432558)
			(xy 386.034788 -256.53238)
		)
		(stroke
			(width 0)
			(type solid)
		)
		(fill yes)
		(layer "In13.Cu")
		(net "M_H_CPU0_CLK_DN<0>")
	)
	(gr_poly
		(pts
			(xy 386.134864 -255.216152) (xy 386.034788 -255.116076) (xy 385.934712 -255.216152) (xy 385.934712 -255.260602)
			(xy 386.134864 -255.260602)
		)
		(stroke
			(width 0)
			(type solid)
		)
		(fill yes)
		(layer "In13.Cu")
		(net "M_H_CPU0_SA_CA<6>")
	)
	(gr_poly
		(pts
			(xy 386.134864 -254.812292) (xy 386.134864 -254.767842) (xy 385.934712 -254.767842) (xy 385.934712 -254.812292)
			(xy 386.034788 -254.912368)
		)
		(stroke
			(width 0)
			(type solid)
		)
		(fill yes)
		(layer "In13.Cu")
		(net "M_H_CPU0_SA_CA<5>")
	)
	(gr_poly
		(pts
			(xy 386.134864 -253.59614) (xy 386.034788 -253.496064) (xy 385.934712 -253.59614) (xy 385.934712 -253.64059)
			(xy 386.134864 -253.64059)
		)
		(stroke
			(width 0)
			(type solid)
		)
		(fill yes)
		(layer "In13.Cu")
		(net "M_H_CPU0_SA_CA<2>")
	)
	(gr_poly
		(pts
			(xy 386.134864 -253.19228) (xy 386.134864 -253.14783) (xy 385.934712 -253.14783) (xy 385.934712 -253.19228)
			(xy 386.034788 -253.292356)
		)
		(stroke
			(width 0)
			(type solid)
		)
		(fill yes)
		(layer "In13.Cu")
		(net "M_H_CPU0_SA_CA<1>")
	)
	(gr_poly
		(pts
			(xy 386.134864 -251.976128) (xy 386.034788 -251.876052) (xy 385.934712 -251.976128) (xy 385.934712 -252.020578)
			(xy 386.134864 -252.020578)
		)
		(stroke
			(width 0)
			(type solid)
		)
		(fill yes)
		(layer "In13.Cu")
		(net "M_H_CPU0_SA_CS_N<1>")
	)
	(gr_poly
		(pts
			(xy 386.134864 -250.356116) (xy 386.034788 -250.25604) (xy 385.934712 -250.356116) (xy 385.934712 -250.400566)
			(xy 386.134864 -250.400566)
		)
		(stroke
			(width 0)
			(type solid)
		)
		(fill yes)
		(layer "In13.Cu")
		(net "M_H_CPU0_ALERT_R_N")
	)
	(gr_poly
		(pts
			(xy 386.134864 -248.736104) (xy 386.034788 -248.636028) (xy 385.934712 -248.736104) (xy 385.934712 -248.780554)
			(xy 386.134864 -248.780554)
		)
		(stroke
			(width 0)
			(type solid)
		)
		(fill yes)
		(layer "In13.Cu")
		(net "M_H_CPU0_SA_CB<5>")
	)
	(gr_poly
		(pts
			(xy 386.134864 -248.332244) (xy 386.134864 -248.287794) (xy 385.934712 -248.287794) (xy 385.934712 -248.332244)
			(xy 386.034788 -248.43232)
		)
		(stroke
			(width 0)
			(type solid)
		)
		(fill yes)
		(layer "In13.Cu")
		(net "M_H_CPU0_SA_CB<6>")
	)
	(gr_poly
		(pts
			(xy 386.134864 -247.115838) (xy 386.034788 -247.016016) (xy 385.934712 -247.115838) (xy 385.934712 -247.16359)
			(xy 386.134864 -247.16359)
		)
		(stroke
			(width 0)
			(type solid)
		)
		(fill yes)
		(layer "In13.Cu")
		(net "M_H_CPU0_SA_DQS_DN<9>")
	)
	(gr_poly
		(pts
			(xy 386.134864 -246.712486) (xy 386.134864 -246.664734) (xy 385.934712 -246.664734) (xy 385.934712 -246.712486)
			(xy 386.034788 -246.812308)
		)
		(stroke
			(width 0)
			(type solid)
		)
		(fill yes)
		(layer "In13.Cu")
		(net "M_H_CPU0_SA_DQS_DN<4>")
	)
	(gr_poly
		(pts
			(xy 386.134864 -245.49608) (xy 386.034788 -245.396004) (xy 385.934712 -245.49608) (xy 385.934712 -245.54053)
			(xy 386.134864 -245.54053)
		)
		(stroke
			(width 0)
			(type solid)
		)
		(fill yes)
		(layer "In13.Cu")
		(net "M_H_CPU0_SA_CB<1>")
	)
	(gr_poly
		(pts
			(xy 386.134864 -245.09222) (xy 386.134864 -245.04777) (xy 385.934712 -245.04777) (xy 385.934712 -245.09222)
			(xy 386.034788 -245.192296)
		)
		(stroke
			(width 0)
			(type solid)
		)
		(fill yes)
		(layer "In13.Cu")
		(net "M_H_CPU0_SA_CB<2>")
	)
	(gr_poly
		(pts
			(xy 386.134864 -243.876068) (xy 386.034788 -243.775992) (xy 385.934712 -243.876068) (xy 385.934712 -243.920518)
			(xy 386.134864 -243.920518)
		)
		(stroke
			(width 0)
			(type solid)
		)
		(fill yes)
		(layer "In13.Cu")
		(net "M_H_CPU0_SA_DQ<29>")
	)
	(gr_poly
		(pts
			(xy 386.134864 -243.472208) (xy 386.134864 -243.427758) (xy 385.934712 -243.427758) (xy 385.934712 -243.472208)
			(xy 386.034788 -243.572284)
		)
		(stroke
			(width 0)
			(type solid)
		)
		(fill yes)
		(layer "In13.Cu")
		(net "M_H_CPU0_SA_DQ<30>")
	)
	(gr_poly
		(pts
			(xy 386.134864 -242.255802) (xy 386.034788 -242.15598) (xy 385.934712 -242.255802) (xy 385.934712 -242.303554)
			(xy 386.134864 -242.303554)
		)
		(stroke
			(width 0)
			(type solid)
		)
		(fill yes)
		(layer "In13.Cu")
		(net "M_H_CPU0_SA_DQS_DN<8>")
	)
	(gr_poly
		(pts
			(xy 386.134864 -241.85245) (xy 386.134864 -241.804698) (xy 385.934712 -241.804698) (xy 385.934712 -241.85245)
			(xy 386.034788 -241.952272)
		)
		(stroke
			(width 0)
			(type solid)
		)
		(fill yes)
		(layer "In13.Cu")
		(net "M_H_CPU0_SA_DQS_DN<3>")
	)
	(gr_poly
		(pts
			(xy 386.134864 -240.636044) (xy 386.034788 -240.535968) (xy 385.934712 -240.636044) (xy 385.934712 -240.680494)
			(xy 386.134864 -240.680494)
		)
		(stroke
			(width 0)
			(type solid)
		)
		(fill yes)
		(layer "In13.Cu")
		(net "M_H_CPU0_SA_DQ<25>")
	)
	(gr_poly
		(pts
			(xy 386.134864 -240.232184) (xy 386.134864 -240.187734) (xy 385.934712 -240.187734) (xy 385.934712 -240.232184)
			(xy 386.034788 -240.33226)
		)
		(stroke
			(width 0)
			(type solid)
		)
		(fill yes)
		(layer "In13.Cu")
		(net "M_H_CPU0_SA_DQ<26>")
	)
	(gr_poly
		(pts
			(xy 386.134864 -239.016032) (xy 386.034788 -238.915956) (xy 385.934712 -239.016032) (xy 385.934712 -239.060482)
			(xy 386.134864 -239.060482)
		)
		(stroke
			(width 0)
			(type solid)
		)
		(fill yes)
		(layer "In13.Cu")
		(net "M_H_CPU0_SA_DQ<21>")
	)
	(gr_poly
		(pts
			(xy 386.134864 -238.612172) (xy 386.134864 -238.567722) (xy 385.934712 -238.567722) (xy 385.934712 -238.612172)
			(xy 386.034788 -238.712248)
		)
		(stroke
			(width 0)
			(type solid)
		)
		(fill yes)
		(layer "In13.Cu")
		(net "M_H_CPU0_SA_DQ<22>")
	)
	(gr_poly
		(pts
			(xy 386.134864 -237.395766) (xy 386.034788 -237.295944) (xy 385.934712 -237.395766) (xy 385.934712 -237.443518)
			(xy 386.134864 -237.443518)
		)
		(stroke
			(width 0)
			(type solid)
		)
		(fill yes)
		(layer "In13.Cu")
		(net "M_H_CPU0_SA_DQS_DN<7>")
	)
	(gr_poly
		(pts
			(xy 386.134864 -236.992414) (xy 386.134864 -236.944662) (xy 385.934712 -236.944662) (xy 385.934712 -236.992414)
			(xy 386.034788 -237.092236)
		)
		(stroke
			(width 0)
			(type solid)
		)
		(fill yes)
		(layer "In13.Cu")
		(net "M_H_CPU0_SA_DQS_DN<2>")
	)
	(gr_poly
		(pts
			(xy 386.134864 -235.776008) (xy 386.034788 -235.675932) (xy 385.934712 -235.776008) (xy 385.934712 -235.820458)
			(xy 386.134864 -235.820458)
		)
		(stroke
			(width 0)
			(type solid)
		)
		(fill yes)
		(layer "In13.Cu")
		(net "M_H_CPU0_SA_DQ<17>")
	)
	(gr_poly
		(pts
			(xy 386.134864 -235.372148) (xy 386.134864 -235.327698) (xy 385.934712 -235.327698) (xy 385.934712 -235.372148)
			(xy 386.034788 -235.472224)
		)
		(stroke
			(width 0)
			(type solid)
		)
		(fill yes)
		(layer "In13.Cu")
		(net "M_H_CPU0_SA_DQ<18>")
	)
	(gr_poly
		(pts
			(xy 386.134864 -234.155996) (xy 386.034788 -234.05592) (xy 385.934712 -234.155996) (xy 385.934712 -234.200446)
			(xy 386.134864 -234.200446)
		)
		(stroke
			(width 0)
			(type solid)
		)
		(fill yes)
		(layer "In13.Cu")
		(net "M_H_CPU0_SA_DQ<13>")
	)
	(gr_poly
		(pts
			(xy 386.134864 -233.752136) (xy 386.134864 -233.707686) (xy 385.934712 -233.707686) (xy 385.934712 -233.752136)
			(xy 386.034788 -233.852212)
		)
		(stroke
			(width 0)
			(type solid)
		)
		(fill yes)
		(layer "In13.Cu")
		(net "M_H_CPU0_SA_DQ<14>")
	)
	(gr_poly
		(pts
			(xy 386.134864 -232.53573) (xy 386.034788 -232.435908) (xy 385.934712 -232.53573) (xy 385.934712 -232.583482)
			(xy 386.134864 -232.583482)
		)
		(stroke
			(width 0)
			(type solid)
		)
		(fill yes)
		(layer "In13.Cu")
		(net "M_H_CPU0_SA_DQS_DN<6>")
	)
	(gr_poly
		(pts
			(xy 386.134864 -232.132378) (xy 386.134864 -232.084626) (xy 385.934712 -232.084626) (xy 385.934712 -232.132378)
			(xy 386.034788 -232.2322)
		)
		(stroke
			(width 0)
			(type solid)
		)
		(fill yes)
		(layer "In13.Cu")
		(net "M_H_CPU0_SA_DQS_DN<1>")
	)
	(gr_poly
		(pts
			(xy 386.134864 -230.915972) (xy 386.034788 -230.815896) (xy 385.934712 -230.915972) (xy 385.934712 -230.960422)
			(xy 386.134864 -230.960422)
		)
		(stroke
			(width 0)
			(type solid)
		)
		(fill yes)
		(layer "In13.Cu")
		(net "M_H_CPU0_SA_DQ<9>")
	)
	(gr_poly
		(pts
			(xy 386.134864 -230.512366) (xy 386.134864 -230.467916) (xy 385.934712 -230.467916) (xy 385.934712 -230.512366)
			(xy 386.034788 -230.612188)
		)
		(stroke
			(width 0)
			(type solid)
		)
		(fill yes)
		(layer "In13.Cu")
		(net "M_H_CPU0_SA_DQ<10>")
	)
	(gr_poly
		(pts
			(xy 386.134864 -229.29596) (xy 386.034788 -229.195884) (xy 385.934712 -229.29596) (xy 385.934712 -229.34041)
			(xy 386.134864 -229.34041)
		)
		(stroke
			(width 0)
			(type solid)
		)
		(fill yes)
		(layer "In13.Cu")
		(net "M_H_CPU0_SA_DQ<5>")
	)
	(gr_poly
		(pts
			(xy 386.134864 -228.892354) (xy 386.134864 -228.847904) (xy 385.934712 -228.847904) (xy 385.934712 -228.892354)
			(xy 386.034788 -228.99243)
		)
		(stroke
			(width 0)
			(type solid)
		)
		(fill yes)
		(layer "In13.Cu")
		(net "M_H_CPU0_SA_DQ<6>")
	)
	(gr_poly
		(pts
			(xy 386.134864 -227.675948) (xy 386.034788 -227.576126) (xy 385.934712 -227.675948) (xy 385.934712 -227.7237)
			(xy 386.134864 -227.7237)
		)
		(stroke
			(width 0)
			(type solid)
		)
		(fill yes)
		(layer "In13.Cu")
		(net "M_H_CPU0_SA_DQS_DN<5>")
	)
	(gr_poly
		(pts
			(xy 386.134864 -227.272596) (xy 386.134864 -227.224844) (xy 385.934712 -227.224844) (xy 385.934712 -227.272596)
			(xy 386.034788 -227.372418)
		)
		(stroke
			(width 0)
			(type solid)
		)
		(fill yes)
		(layer "In13.Cu")
		(net "M_H_CPU0_SA_DQS_DN<0>")
	)
	(gr_poly
		(pts
			(xy 386.134864 -226.05619) (xy 386.034788 -225.956114) (xy 385.934712 -226.05619) (xy 385.934712 -226.10064)
			(xy 386.134864 -226.10064)
		)
		(stroke
			(width 0)
			(type solid)
		)
		(fill yes)
		(layer "In13.Cu")
		(net "M_H_CPU0_SA_DQ<1>")
	)
	(gr_poly
		(pts
			(xy 386.134864 -225.65233) (xy 386.134864 -225.60788) (xy 385.934712 -225.60788) (xy 385.934712 -225.65233)
			(xy 386.034788 -225.752406)
		)
		(stroke
			(width 0)
			(type solid)
		)
		(fill yes)
		(layer "In13.Cu")
		(net "M_H_CPU0_SA_DQ<2>")
	)
	(gr_poly
		(pts
			(xy 386.434838 -293.324026) (xy 386.434838 -293.279576) (xy 386.234686 -293.279576) (xy 386.234686 -293.324026)
			(xy 386.334762 -293.424102)
		)
		(stroke
			(width 0)
			(type solid)
		)
		(fill yes)
		(layer "In13.Cu")
		(net "M_H_CPU0_SB_DQ<31>")
	)
	(gr_poly
		(pts
			(xy 386.434838 -292.107874) (xy 386.334762 -292.007798) (xy 386.234686 -292.107874) (xy 386.234686 -292.152324)
			(xy 386.434838 -292.152324)
		)
		(stroke
			(width 0)
			(type solid)
		)
		(fill yes)
		(layer "In13.Cu")
		(net "M_H_CPU0_SB_DQ<28>")
	)
	(gr_poly
		(pts
			(xy 386.434838 -291.704268) (xy 386.434838 -291.656516) (xy 386.234686 -291.656516) (xy 386.234686 -291.704268)
			(xy 386.334762 -291.80409)
		)
		(stroke
			(width 0)
			(type solid)
		)
		(fill yes)
		(layer "In13.Cu")
		(net "M_H_CPU0_SB_DQS_DP<8>")
	)
	(gr_poly
		(pts
			(xy 386.434838 -290.487608) (xy 386.334762 -290.387786) (xy 386.234686 -290.487608) (xy 386.234686 -290.53536)
			(xy 386.434838 -290.53536)
		)
		(stroke
			(width 0)
			(type solid)
		)
		(fill yes)
		(layer "In13.Cu")
		(net "M_H_CPU0_SB_DQS_DP<3>")
	)
	(gr_poly
		(pts
			(xy 386.434838 -290.084002) (xy 386.434838 -290.039552) (xy 386.234686 -290.039552) (xy 386.234686 -290.084002)
			(xy 386.334762 -290.184078)
		)
		(stroke
			(width 0)
			(type solid)
		)
		(fill yes)
		(layer "In13.Cu")
		(net "M_H_CPU0_SB_DQ<27>")
	)
	(gr_poly
		(pts
			(xy 386.434838 -288.86785) (xy 386.334762 -288.767774) (xy 386.234686 -288.86785) (xy 386.234686 -288.9123)
			(xy 386.434838 -288.9123)
		)
		(stroke
			(width 0)
			(type solid)
		)
		(fill yes)
		(layer "In13.Cu")
		(net "M_H_CPU0_SB_DQ<24>")
	)
	(gr_poly
		(pts
			(xy 386.434838 -288.464244) (xy 386.434838 -288.419794) (xy 386.234686 -288.419794) (xy 386.234686 -288.464244)
			(xy 386.334762 -288.56432)
		)
		(stroke
			(width 0)
			(type solid)
		)
		(fill yes)
		(layer "In13.Cu")
		(net "M_H_CPU0_SB_DQ<23>")
	)
	(gr_poly
		(pts
			(xy 386.434838 -287.247838) (xy 386.334762 -287.148016) (xy 386.234686 -287.247838) (xy 386.234686 -287.292288)
			(xy 386.434838 -287.292288)
		)
		(stroke
			(width 0)
			(type solid)
		)
		(fill yes)
		(layer "In13.Cu")
		(net "M_H_CPU0_SB_DQ<20>")
	)
	(gr_poly
		(pts
			(xy 386.434838 -286.844232) (xy 386.434838 -286.79648) (xy 386.234686 -286.79648) (xy 386.234686 -286.844232)
			(xy 386.334762 -286.944308)
		)
		(stroke
			(width 0)
			(type solid)
		)
		(fill yes)
		(layer "In13.Cu")
		(net "M_H_CPU0_SB_DQS_DP<7>")
	)
	(gr_poly
		(pts
			(xy 386.434838 -285.627826) (xy 386.334762 -285.528004) (xy 386.234686 -285.627826) (xy 386.234686 -285.675578)
			(xy 386.434838 -285.675578)
		)
		(stroke
			(width 0)
			(type solid)
		)
		(fill yes)
		(layer "In13.Cu")
		(net "M_H_CPU0_SB_DQS_DP<2>")
	)
	(gr_poly
		(pts
			(xy 386.434838 -285.22422) (xy 386.434838 -285.17977) (xy 386.234686 -285.17977) (xy 386.234686 -285.22422)
			(xy 386.334762 -285.324296)
		)
		(stroke
			(width 0)
			(type solid)
		)
		(fill yes)
		(layer "In13.Cu")
		(net "M_H_CPU0_SB_DQ<19>")
	)
	(gr_poly
		(pts
			(xy 386.434838 -284.008068) (xy 386.334762 -283.907992) (xy 386.234686 -284.008068) (xy 386.234686 -284.052518)
			(xy 386.434838 -284.052518)
		)
		(stroke
			(width 0)
			(type solid)
		)
		(fill yes)
		(layer "In13.Cu")
		(net "M_H_CPU0_SB_DQ<16>")
	)
	(gr_poly
		(pts
			(xy 386.434838 -283.604208) (xy 386.434838 -283.559758) (xy 386.234686 -283.559758) (xy 386.234686 -283.604208)
			(xy 386.334762 -283.704284)
		)
		(stroke
			(width 0)
			(type solid)
		)
		(fill yes)
		(layer "In13.Cu")
		(net "M_H_CPU0_SB_DQ<15>")
	)
	(gr_poly
		(pts
			(xy 386.434838 -282.388056) (xy 386.334762 -282.28798) (xy 386.234686 -282.388056) (xy 386.234686 -282.432506)
			(xy 386.434838 -282.432506)
		)
		(stroke
			(width 0)
			(type solid)
		)
		(fill yes)
		(layer "In13.Cu")
		(net "M_H_CPU0_SB_DQ<12>")
	)
	(gr_poly
		(pts
			(xy 386.434838 -281.98445) (xy 386.434838 -281.936698) (xy 386.234686 -281.936698) (xy 386.234686 -281.98445)
			(xy 386.334762 -282.084272)
		)
		(stroke
			(width 0)
			(type solid)
		)
		(fill yes)
		(layer "In13.Cu")
		(net "M_H_CPU0_SB_DQS_DP<6>")
	)
	(gr_poly
		(pts
			(xy 386.434838 -280.76779) (xy 386.334762 -280.667968) (xy 386.234686 -280.76779) (xy 386.234686 -280.815542)
			(xy 386.434838 -280.815542)
		)
		(stroke
			(width 0)
			(type solid)
		)
		(fill yes)
		(layer "In13.Cu")
		(net "M_H_CPU0_SB_DQS_DP<1>")
	)
	(gr_poly
		(pts
			(xy 386.434838 -280.364184) (xy 386.434838 -280.319734) (xy 386.234686 -280.319734) (xy 386.234686 -280.364184)
			(xy 386.334762 -280.46426)
		)
		(stroke
			(width 0)
			(type solid)
		)
		(fill yes)
		(layer "In13.Cu")
		(net "M_H_CPU0_SB_DQ<11>")
	)
	(gr_poly
		(pts
			(xy 386.434838 -279.148032) (xy 386.334762 -279.047956) (xy 386.234686 -279.148032) (xy 386.234686 -279.192482)
			(xy 386.434838 -279.192482)
		)
		(stroke
			(width 0)
			(type solid)
		)
		(fill yes)
		(layer "In13.Cu")
		(net "M_H_CPU0_SB_DQ<8>")
	)
	(gr_poly
		(pts
			(xy 386.434838 -278.744172) (xy 386.434838 -278.699722) (xy 386.234686 -278.699722) (xy 386.234686 -278.744172)
			(xy 386.334762 -278.844248)
		)
		(stroke
			(width 0)
			(type solid)
		)
		(fill yes)
		(layer "In13.Cu")
		(net "M_H_CPU0_SB_DQ<7>")
	)
	(gr_poly
		(pts
			(xy 386.434838 -277.52802) (xy 386.334762 -277.427944) (xy 386.234686 -277.52802) (xy 386.234686 -277.57247)
			(xy 386.434838 -277.57247)
		)
		(stroke
			(width 0)
			(type solid)
		)
		(fill yes)
		(layer "In13.Cu")
		(net "M_H_CPU0_SB_DQ<4>")
	)
	(gr_poly
		(pts
			(xy 386.434838 -277.124414) (xy 386.434838 -277.076662) (xy 386.234686 -277.076662) (xy 386.234686 -277.124414)
			(xy 386.334762 -277.224236)
		)
		(stroke
			(width 0)
			(type solid)
		)
		(fill yes)
		(layer "In13.Cu")
		(net "M_H_CPU0_SB_DQS_DP<5>")
	)
	(gr_poly
		(pts
			(xy 386.434838 -275.907754) (xy 386.334762 -275.807932) (xy 386.234686 -275.907754) (xy 386.234686 -275.955506)
			(xy 386.434838 -275.955506)
		)
		(stroke
			(width 0)
			(type solid)
		)
		(fill yes)
		(layer "In13.Cu")
		(net "M_H_CPU0_SB_DQS_DP<0>")
	)
	(gr_poly
		(pts
			(xy 386.434838 -275.504148) (xy 386.434838 -275.459698) (xy 386.234686 -275.459698) (xy 386.234686 -275.504148)
			(xy 386.334762 -275.604224)
		)
		(stroke
			(width 0)
			(type solid)
		)
		(fill yes)
		(layer "In13.Cu")
		(net "M_H_CPU0_SB_DQ<3>")
	)
	(gr_poly
		(pts
			(xy 386.434838 -274.287996) (xy 386.334762 -274.18792) (xy 386.234686 -274.287996) (xy 386.234686 -274.332446)
			(xy 386.434838 -274.332446)
		)
		(stroke
			(width 0)
			(type solid)
		)
		(fill yes)
		(layer "In13.Cu")
		(net "M_H_CPU0_SB_DQ<0>")
	)
	(gr_poly
		(pts
			(xy 386.434838 -273.884136) (xy 386.434838 -273.839686) (xy 386.234686 -273.839686) (xy 386.234686 -273.884136)
			(xy 386.334762 -273.984212)
		)
		(stroke
			(width 0)
			(type solid)
		)
		(fill yes)
		(layer "In13.Cu")
		(net "M_H_CPU0_SB_CB<3>")
	)
	(gr_poly
		(pts
			(xy 386.434838 -272.667984) (xy 386.334762 -272.567908) (xy 386.234686 -272.667984) (xy 386.234686 -272.712434)
			(xy 386.434838 -272.712434)
		)
		(stroke
			(width 0)
			(type solid)
		)
		(fill yes)
		(layer "In13.Cu")
		(net "M_H_CPU0_SB_CB<0>")
	)
	(gr_poly
		(pts
			(xy 386.434838 -272.264378) (xy 386.434838 -272.216626) (xy 386.234686 -272.216626) (xy 386.234686 -272.264378)
			(xy 386.334762 -272.3642)
		)
		(stroke
			(width 0)
			(type solid)
		)
		(fill yes)
		(layer "In13.Cu")
		(net "M_H_CPU0_SB_DQS_DP<4>")
	)
	(gr_poly
		(pts
			(xy 386.434838 -271.047718) (xy 386.334762 -270.947896) (xy 386.234686 -271.047718) (xy 386.234686 -271.09547)
			(xy 386.434838 -271.09547)
		)
		(stroke
			(width 0)
			(type solid)
		)
		(fill yes)
		(layer "In13.Cu")
		(net "M_H_CPU0_SB_DQS_DP<9>")
	)
	(gr_poly
		(pts
			(xy 386.434838 -270.644112) (xy 386.434838 -270.599662) (xy 386.234686 -270.599662) (xy 386.234686 -270.644112)
			(xy 386.334762 -270.744188)
		)
		(stroke
			(width 0)
			(type solid)
		)
		(fill yes)
		(layer "In13.Cu")
		(net "M_H_CPU0_SB_CB<7>")
	)
	(gr_poly
		(pts
			(xy 386.434838 -269.42796) (xy 386.334762 -269.327884) (xy 386.234686 -269.42796) (xy 386.234686 -269.47241)
			(xy 386.434838 -269.47241)
		)
		(stroke
			(width 0)
			(type solid)
		)
		(fill yes)
		(layer "In13.Cu")
		(net "M_H_CPU0_SB_CB<4>")
	)
	(gr_poly
		(pts
			(xy 386.434838 -267.807948) (xy 386.334762 -267.707872) (xy 386.234686 -267.807948) (xy 386.234686 -267.852398)
			(xy 386.434838 -267.852398)
		)
		(stroke
			(width 0)
			(type solid)
		)
		(fill yes)
		(layer "In13.Cu")
		(net "M_H_CPU0_SB_RSP<0>")
	)
	(gr_poly
		(pts
			(xy 386.434838 -265.784076) (xy 386.434838 -265.739626) (xy 386.234686 -265.739626) (xy 386.234686 -265.784076)
			(xy 386.334762 -265.884152)
		)
		(stroke
			(width 0)
			(type solid)
		)
		(fill yes)
		(layer "In13.Cu")
		(net "M_H_CPU0_SB_CS_N<0>")
	)
	(gr_poly
		(pts
			(xy 386.434838 -264.567924) (xy 386.334762 -264.467848) (xy 386.234686 -264.567924) (xy 386.234686 -264.612374)
			(xy 386.434838 -264.612374)
		)
		(stroke
			(width 0)
			(type solid)
		)
		(fill yes)
		(layer "In13.Cu")
		(net "M_H_CPU0_SB_CA<6>")
	)
	(gr_poly
		(pts
			(xy 386.434838 -264.164064) (xy 386.434838 -264.119614) (xy 386.234686 -264.119614) (xy 386.234686 -264.164064)
			(xy 386.334762 -264.26414)
		)
		(stroke
			(width 0)
			(type solid)
		)
		(fill yes)
		(layer "In13.Cu")
		(net "M_H_CPU0_SB_CA<5>")
	)
	(gr_poly
		(pts
			(xy 386.434838 -262.947912) (xy 386.334762 -262.847836) (xy 386.234686 -262.947912) (xy 386.234686 -262.992362)
			(xy 386.434838 -262.992362)
		)
		(stroke
			(width 0)
			(type solid)
		)
		(fill yes)
		(layer "In13.Cu")
		(net "M_H_CPU0_SB_CA<2>")
	)
	(gr_poly
		(pts
			(xy 386.434838 -262.544052) (xy 386.434838 -262.499602) (xy 386.234686 -262.499602) (xy 386.234686 -262.544052)
			(xy 386.334762 -262.644128)
		)
		(stroke
			(width 0)
			(type solid)
		)
		(fill yes)
		(layer "In13.Cu")
		(net "M_H_CPU0_SB_CA<1>")
	)
	(gr_poly
		(pts
			(xy 386.605018 -256.025904) (xy 386.504942 -255.926082) (xy 386.404866 -256.025904) (xy 386.404866 -256.073656)
			(xy 386.605018 -256.073656)
		)
		(stroke
			(width 0)
			(type solid)
		)
		(fill yes)
		(layer "In13.Cu")
		(net "M_H_CPU0_CLK_DP<0>")
	)
	(gr_poly
		(pts
			(xy 386.605018 -255.622298) (xy 386.605018 -255.577848) (xy 386.404866 -255.577848) (xy 386.404866 -255.622298)
			(xy 386.504942 -255.722374)
		)
		(stroke
			(width 0)
			(type solid)
		)
		(fill yes)
		(layer "In13.Cu")
		(net "M_H_CPU0_SA_PAR")
	)
	(gr_poly
		(pts
			(xy 386.605018 -254.406146) (xy 386.504942 -254.30607) (xy 386.404866 -254.406146) (xy 386.404866 -254.450596)
			(xy 386.605018 -254.450596)
		)
		(stroke
			(width 0)
			(type solid)
		)
		(fill yes)
		(layer "In13.Cu")
		(net "M_H_CPU0_SA_CA<4>")
	)
	(gr_poly
		(pts
			(xy 386.605018 -254.002286) (xy 386.605018 -253.957836) (xy 386.404866 -253.957836) (xy 386.404866 -254.002286)
			(xy 386.504942 -254.102362)
		)
		(stroke
			(width 0)
			(type solid)
		)
		(fill yes)
		(layer "In13.Cu")
		(net "M_H_CPU0_SA_CA<3>")
	)
	(gr_poly
		(pts
			(xy 386.605018 -252.786134) (xy 386.504942 -252.686058) (xy 386.404866 -252.786134) (xy 386.404866 -252.830584)
			(xy 386.605018 -252.830584)
		)
		(stroke
			(width 0)
			(type solid)
		)
		(fill yes)
		(layer "In13.Cu")
		(net "M_H_CPU0_SA_CA<0>")
	)
	(gr_poly
		(pts
			(xy 386.605018 -251.166122) (xy 386.504942 -251.066046) (xy 386.404866 -251.166122) (xy 386.404866 -251.210572)
			(xy 386.605018 -251.210572)
		)
		(stroke
			(width 0)
			(type solid)
		)
		(fill yes)
		(layer "In13.Cu")
		(net "M_H_CPU0_SA_CS_N<0>")
	)
	(gr_poly
		(pts
			(xy 386.605018 -250.762262) (xy 386.605018 -250.717812) (xy 386.404866 -250.717812) (xy 386.404866 -250.762262)
			(xy 386.504942 -250.862338)
		)
		(stroke
			(width 0)
			(type solid)
		)
		(fill yes)
		(layer "In13.Cu")
		(net "M_H_CPU0_RESET_N")
	)
	(gr_poly
		(pts
			(xy 386.605018 -249.14225) (xy 386.605018 -249.0978) (xy 386.404866 -249.0978) (xy 386.404866 -249.14225)
			(xy 386.504942 -249.242326)
		)
		(stroke
			(width 0)
			(type solid)
		)
		(fill yes)
		(layer "In13.Cu")
		(net "M_H_CPU0_SA_CB<7>")
	)
	(gr_poly
		(pts
			(xy 386.605018 -247.926098) (xy 386.504942 -247.826022) (xy 386.404866 -247.926098) (xy 386.404866 -247.970548)
			(xy 386.605018 -247.970548)
		)
		(stroke
			(width 0)
			(type solid)
		)
		(fill yes)
		(layer "In13.Cu")
		(net "M_H_CPU0_SA_CB<4>")
	)
	(gr_poly
		(pts
			(xy 386.605018 -247.522492) (xy 386.605018 -247.47474) (xy 386.404866 -247.47474) (xy 386.404866 -247.522492)
			(xy 386.504942 -247.622314)
		)
		(stroke
			(width 0)
			(type solid)
		)
		(fill yes)
		(layer "In13.Cu")
		(net "M_H_CPU0_SA_DQS_DP<9>")
	)
	(gr_poly
		(pts
			(xy 386.605018 -246.305832) (xy 386.504942 -246.20601) (xy 386.404866 -246.305832) (xy 386.404866 -246.353584)
			(xy 386.605018 -246.353584)
		)
		(stroke
			(width 0)
			(type solid)
		)
		(fill yes)
		(layer "In13.Cu")
		(net "M_H_CPU0_SA_DQS_DP<4>")
	)
	(gr_poly
		(pts
			(xy 386.605018 -245.902226) (xy 386.605018 -245.857776) (xy 386.404866 -245.857776) (xy 386.404866 -245.902226)
			(xy 386.504942 -246.002302)
		)
		(stroke
			(width 0)
			(type solid)
		)
		(fill yes)
		(layer "In13.Cu")
		(net "M_H_CPU0_SA_CB<3>")
	)
	(gr_poly
		(pts
			(xy 386.605018 -244.686074) (xy 386.504942 -244.585998) (xy 386.404866 -244.686074) (xy 386.404866 -244.730524)
			(xy 386.605018 -244.730524)
		)
		(stroke
			(width 0)
			(type solid)
		)
		(fill yes)
		(layer "In13.Cu")
		(net "M_H_CPU0_SA_CB<0>")
	)
	(gr_poly
		(pts
			(xy 386.605018 -244.282214) (xy 386.605018 -244.237764) (xy 386.404866 -244.237764) (xy 386.404866 -244.282214)
			(xy 386.504942 -244.38229)
		)
		(stroke
			(width 0)
			(type solid)
		)
		(fill yes)
		(layer "In13.Cu")
		(net "M_H_CPU0_SA_DQ<31>")
	)
	(gr_poly
		(pts
			(xy 386.605018 -243.066062) (xy 386.504942 -242.965986) (xy 386.404866 -243.066062) (xy 386.404866 -243.110512)
			(xy 386.605018 -243.110512)
		)
		(stroke
			(width 0)
			(type solid)
		)
		(fill yes)
		(layer "In13.Cu")
		(net "M_H_CPU0_SA_DQ<28>")
	)
	(gr_poly
		(pts
			(xy 386.605018 -242.662456) (xy 386.605018 -242.614704) (xy 386.404866 -242.614704) (xy 386.404866 -242.662456)
			(xy 386.504942 -242.762278)
		)
		(stroke
			(width 0)
			(type solid)
		)
		(fill yes)
		(layer "In13.Cu")
		(net "M_H_CPU0_SA_DQS_DP<8>")
	)
	(gr_poly
		(pts
			(xy 386.605018 -241.445796) (xy 386.504942 -241.345974) (xy 386.404866 -241.445796) (xy 386.404866 -241.493548)
			(xy 386.605018 -241.493548)
		)
		(stroke
			(width 0)
			(type solid)
		)
		(fill yes)
		(layer "In13.Cu")
		(net "M_H_CPU0_SA_DQS_DP<3>")
	)
	(gr_poly
		(pts
			(xy 386.605018 -241.04219) (xy 386.605018 -240.99774) (xy 386.404866 -240.99774) (xy 386.404866 -241.04219)
			(xy 386.504942 -241.142266)
		)
		(stroke
			(width 0)
			(type solid)
		)
		(fill yes)
		(layer "In13.Cu")
		(net "M_H_CPU0_SA_DQ<27>")
	)
	(gr_poly
		(pts
			(xy 386.605018 -239.826038) (xy 386.504942 -239.725962) (xy 386.404866 -239.826038) (xy 386.404866 -239.870488)
			(xy 386.605018 -239.870488)
		)
		(stroke
			(width 0)
			(type solid)
		)
		(fill yes)
		(layer "In13.Cu")
		(net "M_H_CPU0_SA_DQ<24>")
	)
	(gr_poly
		(pts
			(xy 386.605018 -239.422178) (xy 386.605018 -239.377728) (xy 386.404866 -239.377728) (xy 386.404866 -239.422178)
			(xy 386.504942 -239.522254)
		)
		(stroke
			(width 0)
			(type solid)
		)
		(fill yes)
		(layer "In13.Cu")
		(net "M_H_CPU0_SA_DQ<23>")
	)
	(gr_poly
		(pts
			(xy 386.605018 -238.206026) (xy 386.504942 -238.10595) (xy 386.404866 -238.206026) (xy 386.404866 -238.250476)
			(xy 386.605018 -238.250476)
		)
		(stroke
			(width 0)
			(type solid)
		)
		(fill yes)
		(layer "In13.Cu")
		(net "M_H_CPU0_SA_DQ<20>")
	)
	(gr_poly
		(pts
			(xy 386.605018 -237.80242) (xy 386.605018 -237.754668) (xy 386.404866 -237.754668) (xy 386.404866 -237.80242)
			(xy 386.504942 -237.902242)
		)
		(stroke
			(width 0)
			(type solid)
		)
		(fill yes)
		(layer "In13.Cu")
		(net "M_H_CPU0_SA_DQS_DP<7>")
	)
	(gr_poly
		(pts
			(xy 386.605018 -236.58576) (xy 386.504942 -236.485938) (xy 386.404866 -236.58576) (xy 386.404866 -236.633512)
			(xy 386.605018 -236.633512)
		)
		(stroke
			(width 0)
			(type solid)
		)
		(fill yes)
		(layer "In13.Cu")
		(net "M_H_CPU0_SA_DQS_DP<2>")
	)
	(gr_poly
		(pts
			(xy 386.605018 -236.182154) (xy 386.605018 -236.137704) (xy 386.404866 -236.137704) (xy 386.404866 -236.182154)
			(xy 386.504942 -236.28223)
		)
		(stroke
			(width 0)
			(type solid)
		)
		(fill yes)
		(layer "In13.Cu")
		(net "M_H_CPU0_SA_DQ<19>")
	)
	(gr_poly
		(pts
			(xy 386.605018 -234.966002) (xy 386.504942 -234.865926) (xy 386.404866 -234.966002) (xy 386.404866 -235.010452)
			(xy 386.605018 -235.010452)
		)
		(stroke
			(width 0)
			(type solid)
		)
		(fill yes)
		(layer "In13.Cu")
		(net "M_H_CPU0_SA_DQ<16>")
	)
	(gr_poly
		(pts
			(xy 386.605018 -234.562142) (xy 386.605018 -234.517692) (xy 386.404866 -234.517692) (xy 386.404866 -234.562142)
			(xy 386.504942 -234.662218)
		)
		(stroke
			(width 0)
			(type solid)
		)
		(fill yes)
		(layer "In13.Cu")
		(net "M_H_CPU0_SA_DQ<15>")
	)
	(gr_poly
		(pts
			(xy 386.605018 -233.34599) (xy 386.504942 -233.245914) (xy 386.404866 -233.34599) (xy 386.404866 -233.39044)
			(xy 386.605018 -233.39044)
		)
		(stroke
			(width 0)
			(type solid)
		)
		(fill yes)
		(layer "In13.Cu")
		(net "M_H_CPU0_SA_DQ<12>")
	)
	(gr_poly
		(pts
			(xy 386.605018 -232.942384) (xy 386.605018 -232.894632) (xy 386.404866 -232.894632) (xy 386.404866 -232.942384)
			(xy 386.504942 -233.042206)
		)
		(stroke
			(width 0)
			(type solid)
		)
		(fill yes)
		(layer "In13.Cu")
		(net "M_H_CPU0_SA_DQS_DP<6>")
	)
	(gr_poly
		(pts
			(xy 386.605018 -231.725724) (xy 386.504942 -231.625902) (xy 386.404866 -231.725724) (xy 386.404866 -231.773476)
			(xy 386.605018 -231.773476)
		)
		(stroke
			(width 0)
			(type solid)
		)
		(fill yes)
		(layer "In13.Cu")
		(net "M_H_CPU0_SA_DQS_DP<1>")
	)
	(gr_poly
		(pts
			(xy 386.605018 -231.322372) (xy 386.605018 -231.277922) (xy 386.404866 -231.277922) (xy 386.404866 -231.322372)
			(xy 386.504942 -231.422448)
		)
		(stroke
			(width 0)
			(type solid)
		)
		(fill yes)
		(layer "In13.Cu")
		(net "M_H_CPU0_SA_DQ<11>")
	)
	(gr_poly
		(pts
			(xy 386.605018 -230.105966) (xy 386.504942 -230.006144) (xy 386.404866 -230.105966) (xy 386.404866 -230.150416)
			(xy 386.605018 -230.150416)
		)
		(stroke
			(width 0)
			(type solid)
		)
		(fill yes)
		(layer "In13.Cu")
		(net "M_H_CPU0_SA_DQ<8>")
	)
	(gr_poly
		(pts
			(xy 386.605018 -229.70236) (xy 386.605018 -229.65791) (xy 386.404866 -229.65791) (xy 386.404866 -229.70236)
			(xy 386.504942 -229.802436)
		)
		(stroke
			(width 0)
			(type solid)
		)
		(fill yes)
		(layer "In13.Cu")
		(net "M_H_CPU0_SA_DQ<7>")
	)
	(gr_poly
		(pts
			(xy 386.605018 -228.486208) (xy 386.504942 -228.386132) (xy 386.404866 -228.486208) (xy 386.404866 -228.530658)
			(xy 386.605018 -228.530658)
		)
		(stroke
			(width 0)
			(type solid)
		)
		(fill yes)
		(layer "In13.Cu")
		(net "M_H_CPU0_SA_DQ<4>")
	)
	(gr_poly
		(pts
			(xy 386.605018 -228.082602) (xy 386.605018 -228.03485) (xy 386.404866 -228.03485) (xy 386.404866 -228.082602)
			(xy 386.504942 -228.182424)
		)
		(stroke
			(width 0)
			(type solid)
		)
		(fill yes)
		(layer "In13.Cu")
		(net "M_H_CPU0_SA_DQS_DP<5>")
	)
	(gr_poly
		(pts
			(xy 386.605018 -226.865942) (xy 386.504942 -226.76612) (xy 386.404866 -226.865942) (xy 386.404866 -226.913694)
			(xy 386.605018 -226.913694)
		)
		(stroke
			(width 0)
			(type solid)
		)
		(fill yes)
		(layer "In13.Cu")
		(net "M_H_CPU0_SA_DQS_DP<0>")
	)
	(gr_poly
		(pts
			(xy 386.605018 -226.462336) (xy 386.605018 -226.417886) (xy 386.404866 -226.417886) (xy 386.404866 -226.462336)
			(xy 386.504942 -226.562412)
		)
		(stroke
			(width 0)
			(type solid)
		)
		(fill yes)
		(layer "In13.Cu")
		(net "M_H_CPU0_SA_DQ<3>")
	)
	(gr_poly
		(pts
			(xy 386.605018 -225.246184) (xy 386.504942 -225.146108) (xy 386.404866 -225.246184) (xy 386.404866 -225.290634)
			(xy 386.605018 -225.290634)
		)
		(stroke
			(width 0)
			(type solid)
		)
		(fill yes)
		(layer "In13.Cu")
		(net "M_H_CPU0_SA_DQ<0>")
	)
	(gr_poly
		(pts
			(xy 386.904992 -292.91788) (xy 386.804916 -292.817804) (xy 386.70484 -292.91788) (xy 386.70484 -292.96233)
			(xy 386.904992 -292.96233)
		)
		(stroke
			(width 0)
			(type solid)
		)
		(fill yes)
		(layer "In13.Cu")
		(net "M_H_CPU0_SB_DQ<29>")
	)
	(gr_poly
		(pts
			(xy 386.904992 -292.51402) (xy 386.904992 -292.46957) (xy 386.70484 -292.46957) (xy 386.70484 -292.51402)
			(xy 386.804916 -292.614096)
		)
		(stroke
			(width 0)
			(type solid)
		)
		(fill yes)
		(layer "In13.Cu")
		(net "M_H_CPU0_SB_DQ<30>")
	)
	(gr_poly
		(pts
			(xy 386.904992 -291.297614) (xy 386.804916 -291.197792) (xy 386.70484 -291.297614) (xy 386.70484 -291.345366)
			(xy 386.904992 -291.345366)
		)
		(stroke
			(width 0)
			(type solid)
		)
		(fill yes)
		(layer "In13.Cu")
		(net "M_H_CPU0_SB_DQS_DN<8>")
	)
	(gr_poly
		(pts
			(xy 386.904992 -290.894262) (xy 386.904992 -290.84651) (xy 386.70484 -290.84651) (xy 386.70484 -290.894262)
			(xy 386.804916 -290.994084)
		)
		(stroke
			(width 0)
			(type solid)
		)
		(fill yes)
		(layer "In13.Cu")
		(net "M_H_CPU0_SB_DQS_DN<3>")
	)
	(gr_poly
		(pts
			(xy 386.904992 -289.677856) (xy 386.804916 -289.57778) (xy 386.70484 -289.677856) (xy 386.70484 -289.722306)
			(xy 386.904992 -289.722306)
		)
		(stroke
			(width 0)
			(type solid)
		)
		(fill yes)
		(layer "In13.Cu")
		(net "M_H_CPU0_SB_DQ<25>")
	)
	(gr_poly
		(pts
			(xy 386.904992 -289.273996) (xy 386.904992 -289.229546) (xy 386.70484 -289.229546) (xy 386.70484 -289.273996)
			(xy 386.804916 -289.374072)
		)
		(stroke
			(width 0)
			(type solid)
		)
		(fill yes)
		(layer "In13.Cu")
		(net "M_H_CPU0_SB_DQ<26>")
	)
	(gr_poly
		(pts
			(xy 386.904992 -288.057844) (xy 386.804916 -287.957768) (xy 386.70484 -288.057844) (xy 386.70484 -288.102294)
			(xy 386.904992 -288.102294)
		)
		(stroke
			(width 0)
			(type solid)
		)
		(fill yes)
		(layer "In13.Cu")
		(net "M_H_CPU0_SB_DQ<21>")
	)
	(gr_poly
		(pts
			(xy 386.904992 -287.654238) (xy 386.904992 -287.609788) (xy 386.70484 -287.609788) (xy 386.70484 -287.654238)
			(xy 386.804916 -287.75406)
		)
		(stroke
			(width 0)
			(type solid)
		)
		(fill yes)
		(layer "In13.Cu")
		(net "M_H_CPU0_SB_DQ<22>")
	)
	(gr_poly
		(pts
			(xy 386.904992 -286.437832) (xy 386.804916 -286.337756) (xy 386.70484 -286.437832) (xy 386.70484 -286.485584)
			(xy 386.904992 -286.485584)
		)
		(stroke
			(width 0)
			(type solid)
		)
		(fill yes)
		(layer "In13.Cu")
		(net "M_H_CPU0_SB_DQS_DN<7>")
	)
	(gr_poly
		(pts
			(xy 386.904992 -286.03448) (xy 386.904992 -285.986728) (xy 386.70484 -285.986728) (xy 386.70484 -286.03448)
			(xy 386.804916 -286.134302)
		)
		(stroke
			(width 0)
			(type solid)
		)
		(fill yes)
		(layer "In13.Cu")
		(net "M_H_CPU0_SB_DQS_DN<2>")
	)
	(gr_poly
		(pts
			(xy 386.904992 -284.818074) (xy 386.804916 -284.717998) (xy 386.70484 -284.818074) (xy 386.70484 -284.862524)
			(xy 386.904992 -284.862524)
		)
		(stroke
			(width 0)
			(type solid)
		)
		(fill yes)
		(layer "In13.Cu")
		(net "M_H_CPU0_SB_DQ<17>")
	)
	(gr_poly
		(pts
			(xy 386.904992 -284.414214) (xy 386.904992 -284.369764) (xy 386.70484 -284.369764) (xy 386.70484 -284.414214)
			(xy 386.804916 -284.51429)
		)
		(stroke
			(width 0)
			(type solid)
		)
		(fill yes)
		(layer "In13.Cu")
		(net "M_H_CPU0_SB_DQ<18>")
	)
	(gr_poly
		(pts
			(xy 386.904992 -283.198062) (xy 386.804916 -283.097986) (xy 386.70484 -283.198062) (xy 386.70484 -283.242512)
			(xy 386.904992 -283.242512)
		)
		(stroke
			(width 0)
			(type solid)
		)
		(fill yes)
		(layer "In13.Cu")
		(net "M_H_CPU0_SB_DQ<13>")
	)
	(gr_poly
		(pts
			(xy 386.904992 -282.794202) (xy 386.904992 -282.749752) (xy 386.70484 -282.749752) (xy 386.70484 -282.794202)
			(xy 386.804916 -282.894278)
		)
		(stroke
			(width 0)
			(type solid)
		)
		(fill yes)
		(layer "In13.Cu")
		(net "M_H_CPU0_SB_DQ<14>")
	)
	(gr_poly
		(pts
			(xy 386.904992 -281.577796) (xy 386.804916 -281.477974) (xy 386.70484 -281.577796) (xy 386.70484 -281.625548)
			(xy 386.904992 -281.625548)
		)
		(stroke
			(width 0)
			(type solid)
		)
		(fill yes)
		(layer "In13.Cu")
		(net "M_H_CPU0_SB_DQS_DN<6>")
	)
	(gr_poly
		(pts
			(xy 386.904992 -281.174444) (xy 386.904992 -281.126692) (xy 386.70484 -281.126692) (xy 386.70484 -281.174444)
			(xy 386.804916 -281.274266)
		)
		(stroke
			(width 0)
			(type solid)
		)
		(fill yes)
		(layer "In13.Cu")
		(net "M_H_CPU0_SB_DQS_DN<1>")
	)
	(gr_poly
		(pts
			(xy 386.904992 -279.958038) (xy 386.804916 -279.857962) (xy 386.70484 -279.958038) (xy 386.70484 -280.002488)
			(xy 386.904992 -280.002488)
		)
		(stroke
			(width 0)
			(type solid)
		)
		(fill yes)
		(layer "In13.Cu")
		(net "M_H_CPU0_SB_DQ<9>")
	)
	(gr_poly
		(pts
			(xy 386.904992 -279.554178) (xy 386.904992 -279.509728) (xy 386.70484 -279.509728) (xy 386.70484 -279.554178)
			(xy 386.804916 -279.654254)
		)
		(stroke
			(width 0)
			(type solid)
		)
		(fill yes)
		(layer "In13.Cu")
		(net "M_H_CPU0_SB_DQ<10>")
	)
	(gr_poly
		(pts
			(xy 386.904992 -278.338026) (xy 386.804916 -278.23795) (xy 386.70484 -278.338026) (xy 386.70484 -278.382476)
			(xy 386.904992 -278.382476)
		)
		(stroke
			(width 0)
			(type solid)
		)
		(fill yes)
		(layer "In13.Cu")
		(net "M_H_CPU0_SB_DQ<5>")
	)
	(gr_poly
		(pts
			(xy 386.904992 -277.934166) (xy 386.904992 -277.889716) (xy 386.70484 -277.889716) (xy 386.70484 -277.934166)
			(xy 386.804916 -278.034242)
		)
		(stroke
			(width 0)
			(type solid)
		)
		(fill yes)
		(layer "In13.Cu")
		(net "M_H_CPU0_SB_DQ<6>")
	)
	(gr_poly
		(pts
			(xy 386.904992 -276.71776) (xy 386.804916 -276.617938) (xy 386.70484 -276.71776) (xy 386.70484 -276.765512)
			(xy 386.904992 -276.765512)
		)
		(stroke
			(width 0)
			(type solid)
		)
		(fill yes)
		(layer "In13.Cu")
		(net "M_H_CPU0_SB_DQS_DN<5>")
	)
	(gr_poly
		(pts
			(xy 386.904992 -276.314408) (xy 386.904992 -276.266656) (xy 386.70484 -276.266656) (xy 386.70484 -276.314408)
			(xy 386.804916 -276.41423)
		)
		(stroke
			(width 0)
			(type solid)
		)
		(fill yes)
		(layer "In13.Cu")
		(net "M_H_CPU0_SB_DQS_DN<0>")
	)
	(gr_poly
		(pts
			(xy 386.904992 -275.098002) (xy 386.804916 -274.997926) (xy 386.70484 -275.098002) (xy 386.70484 -275.142452)
			(xy 386.904992 -275.142452)
		)
		(stroke
			(width 0)
			(type solid)
		)
		(fill yes)
		(layer "In13.Cu")
		(net "M_H_CPU0_SB_DQ<1>")
	)
	(gr_poly
		(pts
			(xy 386.904992 -274.694142) (xy 386.904992 -274.649692) (xy 386.70484 -274.649692) (xy 386.70484 -274.694142)
			(xy 386.804916 -274.794218)
		)
		(stroke
			(width 0)
			(type solid)
		)
		(fill yes)
		(layer "In13.Cu")
		(net "M_H_CPU0_SB_DQ<2>")
	)
	(gr_poly
		(pts
			(xy 386.904992 -273.47799) (xy 386.804916 -273.377914) (xy 386.70484 -273.47799) (xy 386.70484 -273.52244)
			(xy 386.904992 -273.52244)
		)
		(stroke
			(width 0)
			(type solid)
		)
		(fill yes)
		(layer "In13.Cu")
		(net "M_H_CPU0_SB_CB<1>")
	)
	(gr_poly
		(pts
			(xy 386.904992 -273.07413) (xy 386.904992 -273.02968) (xy 386.70484 -273.02968) (xy 386.70484 -273.07413)
			(xy 386.804916 -273.174206)
		)
		(stroke
			(width 0)
			(type solid)
		)
		(fill yes)
		(layer "In13.Cu")
		(net "M_H_CPU0_SB_CB<2>")
	)
	(gr_poly
		(pts
			(xy 386.904992 -271.857724) (xy 386.804916 -271.757902) (xy 386.70484 -271.857724) (xy 386.70484 -271.905476)
			(xy 386.904992 -271.905476)
		)
		(stroke
			(width 0)
			(type solid)
		)
		(fill yes)
		(layer "In13.Cu")
		(net "M_H_CPU0_SB_DQS_DN<4>")
	)
	(gr_poly
		(pts
			(xy 386.904992 -271.454372) (xy 386.904992 -271.40662) (xy 386.70484 -271.40662) (xy 386.70484 -271.454372)
			(xy 386.804916 -271.554194)
		)
		(stroke
			(width 0)
			(type solid)
		)
		(fill yes)
		(layer "In13.Cu")
		(net "M_H_CPU0_SB_DQS_DN<9>")
	)
	(gr_poly
		(pts
			(xy 386.904992 -270.237966) (xy 386.804916 -270.13789) (xy 386.70484 -270.237966) (xy 386.70484 -270.282416)
			(xy 386.904992 -270.282416)
		)
		(stroke
			(width 0)
			(type solid)
		)
		(fill yes)
		(layer "In13.Cu")
		(net "M_H_CPU0_SB_CB<5>")
	)
	(gr_poly
		(pts
			(xy 386.904992 -269.834106) (xy 386.904992 -269.789656) (xy 386.70484 -269.789656) (xy 386.70484 -269.834106)
			(xy 386.804916 -269.934182)
		)
		(stroke
			(width 0)
			(type solid)
		)
		(fill yes)
		(layer "In13.Cu")
		(net "M_H_CPU0_SB_CB<6>")
	)
	(gr_poly
		(pts
			(xy 386.904992 -266.997942) (xy 386.804916 -266.897866) (xy 386.70484 -266.997942) (xy 386.70484 -267.042392)
			(xy 386.904992 -267.042392)
		)
		(stroke
			(width 0)
			(type solid)
		)
		(fill yes)
		(layer "In13.Cu")
		(net "M_H_CPU0_SA_RSP<0>")
	)
	(gr_poly
		(pts
			(xy 386.904992 -266.594082) (xy 386.904992 -266.549632) (xy 386.70484 -266.549632) (xy 386.70484 -266.594082)
			(xy 386.804916 -266.694158)
		)
		(stroke
			(width 0)
			(type solid)
		)
		(fill yes)
		(layer "In13.Cu")
		(net "M_H_CPU0_SB_CS_N<1>")
	)
	(gr_poly
		(pts
			(xy 386.904992 -265.37793) (xy 386.804916 -265.277854) (xy 386.70484 -265.37793) (xy 386.70484 -265.42238)
			(xy 386.904992 -265.42238)
		)
		(stroke
			(width 0)
			(type solid)
		)
		(fill yes)
		(layer "In13.Cu")
		(net "M_H_CPU0_SB_PAR")
	)
	(gr_poly
		(pts
			(xy 386.904992 -263.757918) (xy 386.804916 -263.657842) (xy 386.70484 -263.757918) (xy 386.70484 -263.802368)
			(xy 386.904992 -263.802368)
		)
		(stroke
			(width 0)
			(type solid)
		)
		(fill yes)
		(layer "In13.Cu")
		(net "M_H_CPU0_SB_CA<4>")
	)
	(gr_poly
		(pts
			(xy 386.904992 -263.354058) (xy 386.904992 -263.309608) (xy 386.70484 -263.309608) (xy 386.70484 -263.354058)
			(xy 386.804916 -263.454134)
		)
		(stroke
			(width 0)
			(type solid)
		)
		(fill yes)
		(layer "In13.Cu")
		(net "M_H_CPU0_SB_CA<3>")
	)
	(gr_poly
		(pts
			(xy 386.904992 -262.137906) (xy 386.804916 -262.03783) (xy 386.70484 -262.137906) (xy 386.70484 -262.182356)
			(xy 386.904992 -262.182356)
		)
		(stroke
			(width 0)
			(type solid)
		)
		(fill yes)
		(layer "In13.Cu")
		(net "M_H_CPU0_SB_CA<0>")
	)
	(gr_poly
		(pts
			(xy 387.074918 -256.432558) (xy 387.074918 -256.384806) (xy 386.874766 -256.384806) (xy 386.874766 -256.432558)
			(xy 386.974842 -256.53238)
		)
		(stroke
			(width 0)
			(type solid)
		)
		(fill yes)
		(layer "In13.Cu")
		(net "M_H_CPU0_CLK_DN<0>")
	)
	(gr_poly
		(pts
			(xy 387.074918 -255.216152) (xy 386.974842 -255.116076) (xy 386.874766 -255.216152) (xy 386.874766 -255.260602)
			(xy 387.074918 -255.260602)
		)
		(stroke
			(width 0)
			(type solid)
		)
		(fill yes)
		(layer "In13.Cu")
		(net "M_H_CPU0_SA_CA<6>")
	)
	(gr_poly
		(pts
			(xy 387.074918 -254.812292) (xy 387.074918 -254.767842) (xy 386.874766 -254.767842) (xy 386.874766 -254.812292)
			(xy 386.974842 -254.912368)
		)
		(stroke
			(width 0)
			(type solid)
		)
		(fill yes)
		(layer "In13.Cu")
		(net "M_H_CPU0_SA_CA<5>")
	)
	(gr_poly
		(pts
			(xy 387.074918 -253.59614) (xy 386.974842 -253.496064) (xy 386.874766 -253.59614) (xy 386.874766 -253.64059)
			(xy 387.074918 -253.64059)
		)
		(stroke
			(width 0)
			(type solid)
		)
		(fill yes)
		(layer "In13.Cu")
		(net "M_H_CPU0_SA_CA<2>")
	)
	(gr_poly
		(pts
			(xy 387.074918 -253.19228) (xy 387.074918 -253.14783) (xy 386.874766 -253.14783) (xy 386.874766 -253.19228)
			(xy 386.974842 -253.292356)
		)
		(stroke
			(width 0)
			(type solid)
		)
		(fill yes)
		(layer "In13.Cu")
		(net "M_H_CPU0_SA_CA<1>")
	)
	(gr_poly
		(pts
			(xy 387.074918 -251.976128) (xy 386.974842 -251.876052) (xy 386.874766 -251.976128) (xy 386.874766 -252.020578)
			(xy 387.074918 -252.020578)
		)
		(stroke
			(width 0)
			(type solid)
		)
		(fill yes)
		(layer "In13.Cu")
		(net "M_H_CPU0_SA_CS_N<1>")
	)
	(gr_poly
		(pts
			(xy 387.074918 -250.356116) (xy 386.974842 -250.25604) (xy 386.874766 -250.356116) (xy 386.874766 -250.400566)
			(xy 387.074918 -250.400566)
		)
		(stroke
			(width 0)
			(type solid)
		)
		(fill yes)
		(layer "In13.Cu")
		(net "M_H_CPU0_ALERT_R_N")
	)
	(gr_poly
		(pts
			(xy 387.074918 -248.736104) (xy 386.974842 -248.636028) (xy 386.874766 -248.736104) (xy 386.874766 -248.780554)
			(xy 387.074918 -248.780554)
		)
		(stroke
			(width 0)
			(type solid)
		)
		(fill yes)
		(layer "In13.Cu")
		(net "M_H_CPU0_SA_CB<5>")
	)
	(gr_poly
		(pts
			(xy 387.074918 -248.332244) (xy 387.074918 -248.287794) (xy 386.874766 -248.287794) (xy 386.874766 -248.332244)
			(xy 386.974842 -248.43232)
		)
		(stroke
			(width 0)
			(type solid)
		)
		(fill yes)
		(layer "In13.Cu")
		(net "M_H_CPU0_SA_CB<6>")
	)
	(gr_poly
		(pts
			(xy 387.074918 -247.115838) (xy 386.974842 -247.016016) (xy 386.874766 -247.115838) (xy 386.874766 -247.16359)
			(xy 387.074918 -247.16359)
		)
		(stroke
			(width 0)
			(type solid)
		)
		(fill yes)
		(layer "In13.Cu")
		(net "M_H_CPU0_SA_DQS_DN<9>")
	)
	(gr_poly
		(pts
			(xy 387.074918 -246.712486) (xy 387.074918 -246.664734) (xy 386.874766 -246.664734) (xy 386.874766 -246.712486)
			(xy 386.974842 -246.812308)
		)
		(stroke
			(width 0)
			(type solid)
		)
		(fill yes)
		(layer "In13.Cu")
		(net "M_H_CPU0_SA_DQS_DN<4>")
	)
	(gr_poly
		(pts
			(xy 387.074918 -245.49608) (xy 386.974842 -245.396004) (xy 386.874766 -245.49608) (xy 386.874766 -245.54053)
			(xy 387.074918 -245.54053)
		)
		(stroke
			(width 0)
			(type solid)
		)
		(fill yes)
		(layer "In13.Cu")
		(net "M_H_CPU0_SA_CB<1>")
	)
	(gr_poly
		(pts
			(xy 387.074918 -245.09222) (xy 387.074918 -245.04777) (xy 386.874766 -245.04777) (xy 386.874766 -245.09222)
			(xy 386.974842 -245.192296)
		)
		(stroke
			(width 0)
			(type solid)
		)
		(fill yes)
		(layer "In13.Cu")
		(net "M_H_CPU0_SA_CB<2>")
	)
	(gr_poly
		(pts
			(xy 387.074918 -243.876068) (xy 386.974842 -243.775992) (xy 386.874766 -243.876068) (xy 386.874766 -243.920518)
			(xy 387.074918 -243.920518)
		)
		(stroke
			(width 0)
			(type solid)
		)
		(fill yes)
		(layer "In13.Cu")
		(net "M_H_CPU0_SA_DQ<29>")
	)
	(gr_poly
		(pts
			(xy 387.074918 -243.472208) (xy 387.074918 -243.427758) (xy 386.874766 -243.427758) (xy 386.874766 -243.472208)
			(xy 386.974842 -243.572284)
		)
		(stroke
			(width 0)
			(type solid)
		)
		(fill yes)
		(layer "In13.Cu")
		(net "M_H_CPU0_SA_DQ<30>")
	)
	(gr_poly
		(pts
			(xy 387.074918 -242.255802) (xy 386.974842 -242.15598) (xy 386.874766 -242.255802) (xy 386.874766 -242.303554)
			(xy 387.074918 -242.303554)
		)
		(stroke
			(width 0)
			(type solid)
		)
		(fill yes)
		(layer "In13.Cu")
		(net "M_H_CPU0_SA_DQS_DN<8>")
	)
	(gr_poly
		(pts
			(xy 387.074918 -241.85245) (xy 387.074918 -241.804698) (xy 386.874766 -241.804698) (xy 386.874766 -241.85245)
			(xy 386.974842 -241.952272)
		)
		(stroke
			(width 0)
			(type solid)
		)
		(fill yes)
		(layer "In13.Cu")
		(net "M_H_CPU0_SA_DQS_DN<3>")
	)
	(gr_poly
		(pts
			(xy 387.074918 -240.636044) (xy 386.974842 -240.535968) (xy 386.874766 -240.636044) (xy 386.874766 -240.680494)
			(xy 387.074918 -240.680494)
		)
		(stroke
			(width 0)
			(type solid)
		)
		(fill yes)
		(layer "In13.Cu")
		(net "M_H_CPU0_SA_DQ<25>")
	)
	(gr_poly
		(pts
			(xy 387.074918 -240.232184) (xy 387.074918 -240.187734) (xy 386.874766 -240.187734) (xy 386.874766 -240.232184)
			(xy 386.974842 -240.33226)
		)
		(stroke
			(width 0)
			(type solid)
		)
		(fill yes)
		(layer "In13.Cu")
		(net "M_H_CPU0_SA_DQ<26>")
	)
	(gr_poly
		(pts
			(xy 387.074918 -239.016032) (xy 386.974842 -238.915956) (xy 386.874766 -239.016032) (xy 386.874766 -239.060482)
			(xy 387.074918 -239.060482)
		)
		(stroke
			(width 0)
			(type solid)
		)
		(fill yes)
		(layer "In13.Cu")
		(net "M_H_CPU0_SA_DQ<21>")
	)
	(gr_poly
		(pts
			(xy 387.074918 -238.612172) (xy 387.074918 -238.567722) (xy 386.874766 -238.567722) (xy 386.874766 -238.612172)
			(xy 386.974842 -238.712248)
		)
		(stroke
			(width 0)
			(type solid)
		)
		(fill yes)
		(layer "In13.Cu")
		(net "M_H_CPU0_SA_DQ<22>")
	)
	(gr_poly
		(pts
			(xy 387.074918 -237.395766) (xy 386.974842 -237.295944) (xy 386.874766 -237.395766) (xy 386.874766 -237.443518)
			(xy 387.074918 -237.443518)
		)
		(stroke
			(width 0)
			(type solid)
		)
		(fill yes)
		(layer "In13.Cu")
		(net "M_H_CPU0_SA_DQS_DN<7>")
	)
	(gr_poly
		(pts
			(xy 387.074918 -236.992414) (xy 387.074918 -236.944662) (xy 386.874766 -236.944662) (xy 386.874766 -236.992414)
			(xy 386.974842 -237.092236)
		)
		(stroke
			(width 0)
			(type solid)
		)
		(fill yes)
		(layer "In13.Cu")
		(net "M_H_CPU0_SA_DQS_DN<2>")
	)
	(gr_poly
		(pts
			(xy 387.074918 -235.776008) (xy 386.974842 -235.675932) (xy 386.874766 -235.776008) (xy 386.874766 -235.820458)
			(xy 387.074918 -235.820458)
		)
		(stroke
			(width 0)
			(type solid)
		)
		(fill yes)
		(layer "In13.Cu")
		(net "M_H_CPU0_SA_DQ<17>")
	)
	(gr_poly
		(pts
			(xy 387.074918 -235.372148) (xy 387.074918 -235.327698) (xy 386.874766 -235.327698) (xy 386.874766 -235.372148)
			(xy 386.974842 -235.472224)
		)
		(stroke
			(width 0)
			(type solid)
		)
		(fill yes)
		(layer "In13.Cu")
		(net "M_H_CPU0_SA_DQ<18>")
	)
	(gr_poly
		(pts
			(xy 387.074918 -234.155996) (xy 386.974842 -234.05592) (xy 386.874766 -234.155996) (xy 386.874766 -234.200446)
			(xy 387.074918 -234.200446)
		)
		(stroke
			(width 0)
			(type solid)
		)
		(fill yes)
		(layer "In13.Cu")
		(net "M_H_CPU0_SA_DQ<13>")
	)
	(gr_poly
		(pts
			(xy 387.074918 -233.752136) (xy 387.074918 -233.707686) (xy 386.874766 -233.707686) (xy 386.874766 -233.752136)
			(xy 386.974842 -233.852212)
		)
		(stroke
			(width 0)
			(type solid)
		)
		(fill yes)
		(layer "In13.Cu")
		(net "M_H_CPU0_SA_DQ<14>")
	)
	(gr_poly
		(pts
			(xy 387.074918 -232.53573) (xy 386.974842 -232.435908) (xy 386.874766 -232.53573) (xy 386.874766 -232.583482)
			(xy 387.074918 -232.583482)
		)
		(stroke
			(width 0)
			(type solid)
		)
		(fill yes)
		(layer "In13.Cu")
		(net "M_H_CPU0_SA_DQS_DN<6>")
	)
	(gr_poly
		(pts
			(xy 387.074918 -232.132378) (xy 387.074918 -232.084626) (xy 386.874766 -232.084626) (xy 386.874766 -232.132378)
			(xy 386.974842 -232.2322)
		)
		(stroke
			(width 0)
			(type solid)
		)
		(fill yes)
		(layer "In13.Cu")
		(net "M_H_CPU0_SA_DQS_DN<1>")
	)
	(gr_poly
		(pts
			(xy 387.074918 -230.915972) (xy 386.974842 -230.815896) (xy 386.874766 -230.915972) (xy 386.874766 -230.960422)
			(xy 387.074918 -230.960422)
		)
		(stroke
			(width 0)
			(type solid)
		)
		(fill yes)
		(layer "In13.Cu")
		(net "M_H_CPU0_SA_DQ<9>")
	)
	(gr_poly
		(pts
			(xy 387.074918 -230.512366) (xy 387.074918 -230.467916) (xy 386.874766 -230.467916) (xy 386.874766 -230.512366)
			(xy 386.974842 -230.612188)
		)
		(stroke
			(width 0)
			(type solid)
		)
		(fill yes)
		(layer "In13.Cu")
		(net "M_H_CPU0_SA_DQ<10>")
	)
	(gr_poly
		(pts
			(xy 387.074918 -229.29596) (xy 386.974842 -229.195884) (xy 386.874766 -229.29596) (xy 386.874766 -229.34041)
			(xy 387.074918 -229.34041)
		)
		(stroke
			(width 0)
			(type solid)
		)
		(fill yes)
		(layer "In13.Cu")
		(net "M_H_CPU0_SA_DQ<5>")
	)
	(gr_poly
		(pts
			(xy 387.074918 -228.892354) (xy 387.074918 -228.847904) (xy 386.874766 -228.847904) (xy 386.874766 -228.892354)
			(xy 386.974842 -228.99243)
		)
		(stroke
			(width 0)
			(type solid)
		)
		(fill yes)
		(layer "In13.Cu")
		(net "M_H_CPU0_SA_DQ<6>")
	)
	(gr_poly
		(pts
			(xy 387.074918 -227.675948) (xy 386.974842 -227.576126) (xy 386.874766 -227.675948) (xy 386.874766 -227.7237)
			(xy 387.074918 -227.7237)
		)
		(stroke
			(width 0)
			(type solid)
		)
		(fill yes)
		(layer "In13.Cu")
		(net "M_H_CPU0_SA_DQS_DN<5>")
	)
	(gr_poly
		(pts
			(xy 387.074918 -227.272596) (xy 387.074918 -227.224844) (xy 386.874766 -227.224844) (xy 386.874766 -227.272596)
			(xy 386.974842 -227.372418)
		)
		(stroke
			(width 0)
			(type solid)
		)
		(fill yes)
		(layer "In13.Cu")
		(net "M_H_CPU0_SA_DQS_DN<0>")
	)
	(gr_poly
		(pts
			(xy 387.074918 -226.05619) (xy 386.974842 -225.956114) (xy 386.874766 -226.05619) (xy 386.874766 -226.10064)
			(xy 387.074918 -226.10064)
		)
		(stroke
			(width 0)
			(type solid)
		)
		(fill yes)
		(layer "In13.Cu")
		(net "M_H_CPU0_SA_DQ<1>")
	)
	(gr_poly
		(pts
			(xy 387.074918 -225.65233) (xy 387.074918 -225.60788) (xy 386.874766 -225.60788) (xy 386.874766 -225.65233)
			(xy 386.974842 -225.752406)
		)
		(stroke
			(width 0)
			(type solid)
		)
		(fill yes)
		(layer "In13.Cu")
		(net "M_H_CPU0_SA_DQ<2>")
	)
	(gr_poly
		(pts
			(xy 387.374892 -293.324026) (xy 387.374892 -293.279576) (xy 387.17474 -293.279576) (xy 387.17474 -293.324026)
			(xy 387.274816 -293.424102)
		)
		(stroke
			(width 0)
			(type solid)
		)
		(fill yes)
		(layer "In13.Cu")
		(net "M_H_CPU0_SB_DQ<31>")
	)
	(gr_poly
		(pts
			(xy 387.374892 -292.107874) (xy 387.274816 -292.007798) (xy 387.17474 -292.107874) (xy 387.17474 -292.152324)
			(xy 387.374892 -292.152324)
		)
		(stroke
			(width 0)
			(type solid)
		)
		(fill yes)
		(layer "In13.Cu")
		(net "M_H_CPU0_SB_DQ<28>")
	)
	(gr_poly
		(pts
			(xy 387.374892 -291.704268) (xy 387.374892 -291.656516) (xy 387.17474 -291.656516) (xy 387.17474 -291.704268)
			(xy 387.274816 -291.80409)
		)
		(stroke
			(width 0)
			(type solid)
		)
		(fill yes)
		(layer "In13.Cu")
		(net "M_H_CPU0_SB_DQS_DP<8>")
	)
	(gr_poly
		(pts
			(xy 387.374892 -290.487608) (xy 387.274816 -290.387786) (xy 387.17474 -290.487608) (xy 387.17474 -290.53536)
			(xy 387.374892 -290.53536)
		)
		(stroke
			(width 0)
			(type solid)
		)
		(fill yes)
		(layer "In13.Cu")
		(net "M_H_CPU0_SB_DQS_DP<3>")
	)
	(gr_poly
		(pts
			(xy 387.374892 -290.084002) (xy 387.374892 -290.039552) (xy 387.17474 -290.039552) (xy 387.17474 -290.084002)
			(xy 387.274816 -290.184078)
		)
		(stroke
			(width 0)
			(type solid)
		)
		(fill yes)
		(layer "In13.Cu")
		(net "M_H_CPU0_SB_DQ<27>")
	)
	(gr_poly
		(pts
			(xy 387.374892 -288.86785) (xy 387.274816 -288.767774) (xy 387.17474 -288.86785) (xy 387.17474 -288.9123)
			(xy 387.374892 -288.9123)
		)
		(stroke
			(width 0)
			(type solid)
		)
		(fill yes)
		(layer "In13.Cu")
		(net "M_H_CPU0_SB_DQ<24>")
	)
	(gr_poly
		(pts
			(xy 387.374892 -288.464244) (xy 387.374892 -288.419794) (xy 387.17474 -288.419794) (xy 387.17474 -288.464244)
			(xy 387.274816 -288.56432)
		)
		(stroke
			(width 0)
			(type solid)
		)
		(fill yes)
		(layer "In13.Cu")
		(net "M_H_CPU0_SB_DQ<23>")
	)
	(gr_poly
		(pts
			(xy 387.374892 -287.247838) (xy 387.274816 -287.148016) (xy 387.17474 -287.247838) (xy 387.17474 -287.292288)
			(xy 387.374892 -287.292288)
		)
		(stroke
			(width 0)
			(type solid)
		)
		(fill yes)
		(layer "In13.Cu")
		(net "M_H_CPU0_SB_DQ<20>")
	)
	(gr_poly
		(pts
			(xy 387.374892 -286.844232) (xy 387.374892 -286.79648) (xy 387.17474 -286.79648) (xy 387.17474 -286.844232)
			(xy 387.274816 -286.944308)
		)
		(stroke
			(width 0)
			(type solid)
		)
		(fill yes)
		(layer "In13.Cu")
		(net "M_H_CPU0_SB_DQS_DP<7>")
	)
	(gr_poly
		(pts
			(xy 387.374892 -285.627826) (xy 387.274816 -285.528004) (xy 387.17474 -285.627826) (xy 387.17474 -285.675578)
			(xy 387.374892 -285.675578)
		)
		(stroke
			(width 0)
			(type solid)
		)
		(fill yes)
		(layer "In13.Cu")
		(net "M_H_CPU0_SB_DQS_DP<2>")
	)
	(gr_poly
		(pts
			(xy 387.374892 -285.22422) (xy 387.374892 -285.17977) (xy 387.17474 -285.17977) (xy 387.17474 -285.22422)
			(xy 387.274816 -285.324296)
		)
		(stroke
			(width 0)
			(type solid)
		)
		(fill yes)
		(layer "In13.Cu")
		(net "M_H_CPU0_SB_DQ<19>")
	)
	(gr_poly
		(pts
			(xy 387.374892 -284.008068) (xy 387.274816 -283.907992) (xy 387.17474 -284.008068) (xy 387.17474 -284.052518)
			(xy 387.374892 -284.052518)
		)
		(stroke
			(width 0)
			(type solid)
		)
		(fill yes)
		(layer "In13.Cu")
		(net "M_H_CPU0_SB_DQ<16>")
	)
	(gr_poly
		(pts
			(xy 387.374892 -283.604208) (xy 387.374892 -283.559758) (xy 387.17474 -283.559758) (xy 387.17474 -283.604208)
			(xy 387.274816 -283.704284)
		)
		(stroke
			(width 0)
			(type solid)
		)
		(fill yes)
		(layer "In13.Cu")
		(net "M_H_CPU0_SB_DQ<15>")
	)
	(gr_poly
		(pts
			(xy 387.374892 -282.388056) (xy 387.274816 -282.28798) (xy 387.17474 -282.388056) (xy 387.17474 -282.432506)
			(xy 387.374892 -282.432506)
		)
		(stroke
			(width 0)
			(type solid)
		)
		(fill yes)
		(layer "In13.Cu")
		(net "M_H_CPU0_SB_DQ<12>")
	)
	(gr_poly
		(pts
			(xy 387.374892 -281.98445) (xy 387.374892 -281.936698) (xy 387.17474 -281.936698) (xy 387.17474 -281.98445)
			(xy 387.274816 -282.084272)
		)
		(stroke
			(width 0)
			(type solid)
		)
		(fill yes)
		(layer "In13.Cu")
		(net "M_H_CPU0_SB_DQS_DP<6>")
	)
	(gr_poly
		(pts
			(xy 387.374892 -280.76779) (xy 387.274816 -280.667968) (xy 387.17474 -280.76779) (xy 387.17474 -280.815542)
			(xy 387.374892 -280.815542)
		)
		(stroke
			(width 0)
			(type solid)
		)
		(fill yes)
		(layer "In13.Cu")
		(net "M_H_CPU0_SB_DQS_DP<1>")
	)
	(gr_poly
		(pts
			(xy 387.374892 -280.364184) (xy 387.374892 -280.319734) (xy 387.17474 -280.319734) (xy 387.17474 -280.364184)
			(xy 387.274816 -280.46426)
		)
		(stroke
			(width 0)
			(type solid)
		)
		(fill yes)
		(layer "In13.Cu")
		(net "M_H_CPU0_SB_DQ<11>")
	)
	(gr_poly
		(pts
			(xy 387.374892 -279.148032) (xy 387.274816 -279.047956) (xy 387.17474 -279.148032) (xy 387.17474 -279.192482)
			(xy 387.374892 -279.192482)
		)
		(stroke
			(width 0)
			(type solid)
		)
		(fill yes)
		(layer "In13.Cu")
		(net "M_H_CPU0_SB_DQ<8>")
	)
	(gr_poly
		(pts
			(xy 387.374892 -278.744172) (xy 387.374892 -278.699722) (xy 387.17474 -278.699722) (xy 387.17474 -278.744172)
			(xy 387.274816 -278.844248)
		)
		(stroke
			(width 0)
			(type solid)
		)
		(fill yes)
		(layer "In13.Cu")
		(net "M_H_CPU0_SB_DQ<7>")
	)
	(gr_poly
		(pts
			(xy 387.374892 -277.52802) (xy 387.274816 -277.427944) (xy 387.17474 -277.52802) (xy 387.17474 -277.57247)
			(xy 387.374892 -277.57247)
		)
		(stroke
			(width 0)
			(type solid)
		)
		(fill yes)
		(layer "In13.Cu")
		(net "M_H_CPU0_SB_DQ<4>")
	)
	(gr_poly
		(pts
			(xy 387.374892 -277.124414) (xy 387.374892 -277.076662) (xy 387.17474 -277.076662) (xy 387.17474 -277.124414)
			(xy 387.274816 -277.224236)
		)
		(stroke
			(width 0)
			(type solid)
		)
		(fill yes)
		(layer "In13.Cu")
		(net "M_H_CPU0_SB_DQS_DP<5>")
	)
	(gr_poly
		(pts
			(xy 387.374892 -275.907754) (xy 387.274816 -275.807932) (xy 387.17474 -275.907754) (xy 387.17474 -275.955506)
			(xy 387.374892 -275.955506)
		)
		(stroke
			(width 0)
			(type solid)
		)
		(fill yes)
		(layer "In13.Cu")
		(net "M_H_CPU0_SB_DQS_DP<0>")
	)
	(gr_poly
		(pts
			(xy 387.374892 -275.504148) (xy 387.374892 -275.459698) (xy 387.17474 -275.459698) (xy 387.17474 -275.504148)
			(xy 387.274816 -275.604224)
		)
		(stroke
			(width 0)
			(type solid)
		)
		(fill yes)
		(layer "In13.Cu")
		(net "M_H_CPU0_SB_DQ<3>")
	)
	(gr_poly
		(pts
			(xy 387.374892 -274.287996) (xy 387.274816 -274.18792) (xy 387.17474 -274.287996) (xy 387.17474 -274.332446)
			(xy 387.374892 -274.332446)
		)
		(stroke
			(width 0)
			(type solid)
		)
		(fill yes)
		(layer "In13.Cu")
		(net "M_H_CPU0_SB_DQ<0>")
	)
	(gr_poly
		(pts
			(xy 387.374892 -273.884136) (xy 387.374892 -273.839686) (xy 387.17474 -273.839686) (xy 387.17474 -273.884136)
			(xy 387.274816 -273.984212)
		)
		(stroke
			(width 0)
			(type solid)
		)
		(fill yes)
		(layer "In13.Cu")
		(net "M_H_CPU0_SB_CB<3>")
	)
	(gr_poly
		(pts
			(xy 387.374892 -272.667984) (xy 387.274816 -272.567908) (xy 387.17474 -272.667984) (xy 387.17474 -272.712434)
			(xy 387.374892 -272.712434)
		)
		(stroke
			(width 0)
			(type solid)
		)
		(fill yes)
		(layer "In13.Cu")
		(net "M_H_CPU0_SB_CB<0>")
	)
	(gr_poly
		(pts
			(xy 387.374892 -272.264378) (xy 387.374892 -272.216626) (xy 387.17474 -272.216626) (xy 387.17474 -272.264378)
			(xy 387.274816 -272.3642)
		)
		(stroke
			(width 0)
			(type solid)
		)
		(fill yes)
		(layer "In13.Cu")
		(net "M_H_CPU0_SB_DQS_DP<4>")
	)
	(gr_poly
		(pts
			(xy 387.374892 -271.047718) (xy 387.274816 -270.947896) (xy 387.17474 -271.047718) (xy 387.17474 -271.09547)
			(xy 387.374892 -271.09547)
		)
		(stroke
			(width 0)
			(type solid)
		)
		(fill yes)
		(layer "In13.Cu")
		(net "M_H_CPU0_SB_DQS_DP<9>")
	)
	(gr_poly
		(pts
			(xy 387.374892 -270.644112) (xy 387.374892 -270.599662) (xy 387.17474 -270.599662) (xy 387.17474 -270.644112)
			(xy 387.274816 -270.744188)
		)
		(stroke
			(width 0)
			(type solid)
		)
		(fill yes)
		(layer "In13.Cu")
		(net "M_H_CPU0_SB_CB<7>")
	)
	(gr_poly
		(pts
			(xy 387.374892 -269.42796) (xy 387.274816 -269.327884) (xy 387.17474 -269.42796) (xy 387.17474 -269.47241)
			(xy 387.374892 -269.47241)
		)
		(stroke
			(width 0)
			(type solid)
		)
		(fill yes)
		(layer "In13.Cu")
		(net "M_H_CPU0_SB_CB<4>")
	)
	(gr_poly
		(pts
			(xy 387.374892 -267.807948) (xy 387.274816 -267.707872) (xy 387.17474 -267.807948) (xy 387.17474 -267.852398)
			(xy 387.374892 -267.852398)
		)
		(stroke
			(width 0)
			(type solid)
		)
		(fill yes)
		(layer "In13.Cu")
		(net "M_H_CPU0_SB_RSP<0>")
	)
	(gr_poly
		(pts
			(xy 387.374892 -265.784076) (xy 387.374892 -265.739626) (xy 387.17474 -265.739626) (xy 387.17474 -265.784076)
			(xy 387.274816 -265.884152)
		)
		(stroke
			(width 0)
			(type solid)
		)
		(fill yes)
		(layer "In13.Cu")
		(net "M_H_CPU0_SB_CS_N<0>")
	)
	(gr_poly
		(pts
			(xy 387.374892 -264.567924) (xy 387.274816 -264.467848) (xy 387.17474 -264.567924) (xy 387.17474 -264.612374)
			(xy 387.374892 -264.612374)
		)
		(stroke
			(width 0)
			(type solid)
		)
		(fill yes)
		(layer "In13.Cu")
		(net "M_H_CPU0_SB_CA<6>")
	)
	(gr_poly
		(pts
			(xy 387.374892 -264.164064) (xy 387.374892 -264.119614) (xy 387.17474 -264.119614) (xy 387.17474 -264.164064)
			(xy 387.274816 -264.26414)
		)
		(stroke
			(width 0)
			(type solid)
		)
		(fill yes)
		(layer "In13.Cu")
		(net "M_H_CPU0_SB_CA<5>")
	)
	(gr_poly
		(pts
			(xy 387.374892 -262.947912) (xy 387.274816 -262.847836) (xy 387.17474 -262.947912) (xy 387.17474 -262.992362)
			(xy 387.374892 -262.992362)
		)
		(stroke
			(width 0)
			(type solid)
		)
		(fill yes)
		(layer "In13.Cu")
		(net "M_H_CPU0_SB_CA<2>")
	)
	(gr_poly
		(pts
			(xy 387.374892 -262.544052) (xy 387.374892 -262.499602) (xy 387.17474 -262.499602) (xy 387.17474 -262.544052)
			(xy 387.274816 -262.644128)
		)
		(stroke
			(width 0)
			(type solid)
		)
		(fill yes)
		(layer "In13.Cu")
		(net "M_H_CPU0_SB_CA<1>")
	)
	(gr_poly
		(pts
			(xy 387.544818 -256.025904) (xy 387.444742 -255.926082) (xy 387.344666 -256.025904) (xy 387.344666 -256.073656)
			(xy 387.544818 -256.073656)
		)
		(stroke
			(width 0)
			(type solid)
		)
		(fill yes)
		(layer "In13.Cu")
		(net "M_H_CPU0_CLK_DP<0>")
	)
	(gr_poly
		(pts
			(xy 387.544818 -255.622298) (xy 387.544818 -255.577848) (xy 387.344666 -255.577848) (xy 387.344666 -255.622298)
			(xy 387.444742 -255.722374)
		)
		(stroke
			(width 0)
			(type solid)
		)
		(fill yes)
		(layer "In13.Cu")
		(net "M_H_CPU0_SA_PAR")
	)
	(gr_poly
		(pts
			(xy 387.544818 -254.406146) (xy 387.444742 -254.30607) (xy 387.344666 -254.406146) (xy 387.344666 -254.450596)
			(xy 387.544818 -254.450596)
		)
		(stroke
			(width 0)
			(type solid)
		)
		(fill yes)
		(layer "In13.Cu")
		(net "M_H_CPU0_SA_CA<4>")
	)
	(gr_poly
		(pts
			(xy 387.544818 -254.002286) (xy 387.544818 -253.957836) (xy 387.344666 -253.957836) (xy 387.344666 -254.002286)
			(xy 387.444742 -254.102362)
		)
		(stroke
			(width 0)
			(type solid)
		)
		(fill yes)
		(layer "In13.Cu")
		(net "M_H_CPU0_SA_CA<3>")
	)
	(gr_poly
		(pts
			(xy 387.544818 -252.786134) (xy 387.444742 -252.686058) (xy 387.344666 -252.786134) (xy 387.344666 -252.830584)
			(xy 387.544818 -252.830584)
		)
		(stroke
			(width 0)
			(type solid)
		)
		(fill yes)
		(layer "In13.Cu")
		(net "M_H_CPU0_SA_CA<0>")
	)
	(gr_poly
		(pts
			(xy 387.544818 -251.166122) (xy 387.444742 -251.066046) (xy 387.344666 -251.166122) (xy 387.344666 -251.210572)
			(xy 387.544818 -251.210572)
		)
		(stroke
			(width 0)
			(type solid)
		)
		(fill yes)
		(layer "In13.Cu")
		(net "M_H_CPU0_SA_CS_N<0>")
	)
	(gr_poly
		(pts
			(xy 387.544818 -250.762262) (xy 387.544818 -250.717812) (xy 387.344666 -250.717812) (xy 387.344666 -250.762262)
			(xy 387.444742 -250.862338)
		)
		(stroke
			(width 0)
			(type solid)
		)
		(fill yes)
		(layer "In13.Cu")
		(net "M_H_CPU0_RESET_N")
	)
	(gr_poly
		(pts
			(xy 387.544818 -249.14225) (xy 387.544818 -249.0978) (xy 387.344666 -249.0978) (xy 387.344666 -249.14225)
			(xy 387.444742 -249.242326)
		)
		(stroke
			(width 0)
			(type solid)
		)
		(fill yes)
		(layer "In13.Cu")
		(net "M_H_CPU0_SA_CB<7>")
	)
	(gr_poly
		(pts
			(xy 387.544818 -247.926098) (xy 387.444742 -247.826022) (xy 387.344666 -247.926098) (xy 387.344666 -247.970548)
			(xy 387.544818 -247.970548)
		)
		(stroke
			(width 0)
			(type solid)
		)
		(fill yes)
		(layer "In13.Cu")
		(net "M_H_CPU0_SA_CB<4>")
	)
	(gr_poly
		(pts
			(xy 387.544818 -247.522492) (xy 387.544818 -247.47474) (xy 387.344666 -247.47474) (xy 387.344666 -247.522492)
			(xy 387.444742 -247.622314)
		)
		(stroke
			(width 0)
			(type solid)
		)
		(fill yes)
		(layer "In13.Cu")
		(net "M_H_CPU0_SA_DQS_DP<9>")
	)
	(gr_poly
		(pts
			(xy 387.544818 -246.305832) (xy 387.444742 -246.20601) (xy 387.344666 -246.305832) (xy 387.344666 -246.353584)
			(xy 387.544818 -246.353584)
		)
		(stroke
			(width 0)
			(type solid)
		)
		(fill yes)
		(layer "In13.Cu")
		(net "M_H_CPU0_SA_DQS_DP<4>")
	)
	(gr_poly
		(pts
			(xy 387.544818 -245.902226) (xy 387.544818 -245.857776) (xy 387.344666 -245.857776) (xy 387.344666 -245.902226)
			(xy 387.444742 -246.002302)
		)
		(stroke
			(width 0)
			(type solid)
		)
		(fill yes)
		(layer "In13.Cu")
		(net "M_H_CPU0_SA_CB<3>")
	)
	(gr_poly
		(pts
			(xy 387.544818 -244.686074) (xy 387.444742 -244.585998) (xy 387.344666 -244.686074) (xy 387.344666 -244.730524)
			(xy 387.544818 -244.730524)
		)
		(stroke
			(width 0)
			(type solid)
		)
		(fill yes)
		(layer "In13.Cu")
		(net "M_H_CPU0_SA_CB<0>")
	)
	(gr_poly
		(pts
			(xy 387.544818 -244.282214) (xy 387.544818 -244.237764) (xy 387.344666 -244.237764) (xy 387.344666 -244.282214)
			(xy 387.444742 -244.38229)
		)
		(stroke
			(width 0)
			(type solid)
		)
		(fill yes)
		(layer "In13.Cu")
		(net "M_H_CPU0_SA_DQ<31>")
	)
	(gr_poly
		(pts
			(xy 387.544818 -243.066062) (xy 387.444742 -242.965986) (xy 387.344666 -243.066062) (xy 387.344666 -243.110512)
			(xy 387.544818 -243.110512)
		)
		(stroke
			(width 0)
			(type solid)
		)
		(fill yes)
		(layer "In13.Cu")
		(net "M_H_CPU0_SA_DQ<28>")
	)
	(gr_poly
		(pts
			(xy 387.544818 -242.662456) (xy 387.544818 -242.614704) (xy 387.344666 -242.614704) (xy 387.344666 -242.662456)
			(xy 387.444742 -242.762278)
		)
		(stroke
			(width 0)
			(type solid)
		)
		(fill yes)
		(layer "In13.Cu")
		(net "M_H_CPU0_SA_DQS_DP<8>")
	)
	(gr_poly
		(pts
			(xy 387.544818 -241.445796) (xy 387.444742 -241.345974) (xy 387.344666 -241.445796) (xy 387.344666 -241.493548)
			(xy 387.544818 -241.493548)
		)
		(stroke
			(width 0)
			(type solid)
		)
		(fill yes)
		(layer "In13.Cu")
		(net "M_H_CPU0_SA_DQS_DP<3>")
	)
	(gr_poly
		(pts
			(xy 387.544818 -241.04219) (xy 387.544818 -240.99774) (xy 387.344666 -240.99774) (xy 387.344666 -241.04219)
			(xy 387.444742 -241.142266)
		)
		(stroke
			(width 0)
			(type solid)
		)
		(fill yes)
		(layer "In13.Cu")
		(net "M_H_CPU0_SA_DQ<27>")
	)
	(gr_poly
		(pts
			(xy 387.544818 -239.826038) (xy 387.444742 -239.725962) (xy 387.344666 -239.826038) (xy 387.344666 -239.870488)
			(xy 387.544818 -239.870488)
		)
		(stroke
			(width 0)
			(type solid)
		)
		(fill yes)
		(layer "In13.Cu")
		(net "M_H_CPU0_SA_DQ<24>")
	)
	(gr_poly
		(pts
			(xy 387.544818 -239.422178) (xy 387.544818 -239.377728) (xy 387.344666 -239.377728) (xy 387.344666 -239.422178)
			(xy 387.444742 -239.522254)
		)
		(stroke
			(width 0)
			(type solid)
		)
		(fill yes)
		(layer "In13.Cu")
		(net "M_H_CPU0_SA_DQ<23>")
	)
	(gr_poly
		(pts
			(xy 387.544818 -238.206026) (xy 387.444742 -238.10595) (xy 387.344666 -238.206026) (xy 387.344666 -238.250476)
			(xy 387.544818 -238.250476)
		)
		(stroke
			(width 0)
			(type solid)
		)
		(fill yes)
		(layer "In13.Cu")
		(net "M_H_CPU0_SA_DQ<20>")
	)
	(gr_poly
		(pts
			(xy 387.544818 -237.80242) (xy 387.544818 -237.754668) (xy 387.344666 -237.754668) (xy 387.344666 -237.80242)
			(xy 387.444742 -237.902242)
		)
		(stroke
			(width 0)
			(type solid)
		)
		(fill yes)
		(layer "In13.Cu")
		(net "M_H_CPU0_SA_DQS_DP<7>")
	)
	(gr_poly
		(pts
			(xy 387.544818 -236.58576) (xy 387.444742 -236.485938) (xy 387.344666 -236.58576) (xy 387.344666 -236.633512)
			(xy 387.544818 -236.633512)
		)
		(stroke
			(width 0)
			(type solid)
		)
		(fill yes)
		(layer "In13.Cu")
		(net "M_H_CPU0_SA_DQS_DP<2>")
	)
	(gr_poly
		(pts
			(xy 387.544818 -236.182154) (xy 387.544818 -236.137704) (xy 387.344666 -236.137704) (xy 387.344666 -236.182154)
			(xy 387.444742 -236.28223)
		)
		(stroke
			(width 0)
			(type solid)
		)
		(fill yes)
		(layer "In13.Cu")
		(net "M_H_CPU0_SA_DQ<19>")
	)
	(gr_poly
		(pts
			(xy 387.544818 -234.966002) (xy 387.444742 -234.865926) (xy 387.344666 -234.966002) (xy 387.344666 -235.010452)
			(xy 387.544818 -235.010452)
		)
		(stroke
			(width 0)
			(type solid)
		)
		(fill yes)
		(layer "In13.Cu")
		(net "M_H_CPU0_SA_DQ<16>")
	)
	(gr_poly
		(pts
			(xy 387.544818 -234.562142) (xy 387.544818 -234.517692) (xy 387.344666 -234.517692) (xy 387.344666 -234.562142)
			(xy 387.444742 -234.662218)
		)
		(stroke
			(width 0)
			(type solid)
		)
		(fill yes)
		(layer "In13.Cu")
		(net "M_H_CPU0_SA_DQ<15>")
	)
	(gr_poly
		(pts
			(xy 387.544818 -233.34599) (xy 387.444742 -233.245914) (xy 387.344666 -233.34599) (xy 387.344666 -233.39044)
			(xy 387.544818 -233.39044)
		)
		(stroke
			(width 0)
			(type solid)
		)
		(fill yes)
		(layer "In13.Cu")
		(net "M_H_CPU0_SA_DQ<12>")
	)
	(gr_poly
		(pts
			(xy 387.544818 -232.942384) (xy 387.544818 -232.894632) (xy 387.344666 -232.894632) (xy 387.344666 -232.942384)
			(xy 387.444742 -233.042206)
		)
		(stroke
			(width 0)
			(type solid)
		)
		(fill yes)
		(layer "In13.Cu")
		(net "M_H_CPU0_SA_DQS_DP<6>")
	)
	(gr_poly
		(pts
			(xy 387.544818 -231.725724) (xy 387.444742 -231.625902) (xy 387.344666 -231.725724) (xy 387.344666 -231.773476)
			(xy 387.544818 -231.773476)
		)
		(stroke
			(width 0)
			(type solid)
		)
		(fill yes)
		(layer "In13.Cu")
		(net "M_H_CPU0_SA_DQS_DP<1>")
	)
	(gr_poly
		(pts
			(xy 387.544818 -231.322372) (xy 387.544818 -231.277922) (xy 387.344666 -231.277922) (xy 387.344666 -231.322372)
			(xy 387.444742 -231.422448)
		)
		(stroke
			(width 0)
			(type solid)
		)
		(fill yes)
		(layer "In13.Cu")
		(net "M_H_CPU0_SA_DQ<11>")
	)
	(gr_poly
		(pts
			(xy 387.544818 -230.105966) (xy 387.444742 -230.006144) (xy 387.344666 -230.105966) (xy 387.344666 -230.150416)
			(xy 387.544818 -230.150416)
		)
		(stroke
			(width 0)
			(type solid)
		)
		(fill yes)
		(layer "In13.Cu")
		(net "M_H_CPU0_SA_DQ<8>")
	)
	(gr_poly
		(pts
			(xy 387.544818 -229.70236) (xy 387.544818 -229.65791) (xy 387.344666 -229.65791) (xy 387.344666 -229.70236)
			(xy 387.444742 -229.802436)
		)
		(stroke
			(width 0)
			(type solid)
		)
		(fill yes)
		(layer "In13.Cu")
		(net "M_H_CPU0_SA_DQ<7>")
	)
	(gr_poly
		(pts
			(xy 387.544818 -228.486208) (xy 387.444742 -228.386132) (xy 387.344666 -228.486208) (xy 387.344666 -228.530658)
			(xy 387.544818 -228.530658)
		)
		(stroke
			(width 0)
			(type solid)
		)
		(fill yes)
		(layer "In13.Cu")
		(net "M_H_CPU0_SA_DQ<4>")
	)
	(gr_poly
		(pts
			(xy 387.544818 -228.082602) (xy 387.544818 -228.03485) (xy 387.344666 -228.03485) (xy 387.344666 -228.082602)
			(xy 387.444742 -228.182424)
		)
		(stroke
			(width 0)
			(type solid)
		)
		(fill yes)
		(layer "In13.Cu")
		(net "M_H_CPU0_SA_DQS_DP<5>")
	)
	(gr_poly
		(pts
			(xy 387.544818 -226.865942) (xy 387.444742 -226.76612) (xy 387.344666 -226.865942) (xy 387.344666 -226.913694)
			(xy 387.544818 -226.913694)
		)
		(stroke
			(width 0)
			(type solid)
		)
		(fill yes)
		(layer "In13.Cu")
		(net "M_H_CPU0_SA_DQS_DP<0>")
	)
	(gr_poly
		(pts
			(xy 387.544818 -226.462336) (xy 387.544818 -226.417886) (xy 387.344666 -226.417886) (xy 387.344666 -226.462336)
			(xy 387.444742 -226.562412)
		)
		(stroke
			(width 0)
			(type solid)
		)
		(fill yes)
		(layer "In13.Cu")
		(net "M_H_CPU0_SA_DQ<3>")
	)
	(gr_poly
		(pts
			(xy 387.544818 -225.246184) (xy 387.444742 -225.146108) (xy 387.344666 -225.246184) (xy 387.344666 -225.290634)
			(xy 387.544818 -225.290634)
		)
		(stroke
			(width 0)
			(type solid)
		)
		(fill yes)
		(layer "In13.Cu")
		(net "M_H_CPU0_SA_DQ<0>")
	)
	(gr_poly
		(pts
			(xy 387.844792 -292.91788) (xy 387.744716 -292.817804) (xy 387.64464 -292.91788) (xy 387.64464 -292.96233)
			(xy 387.844792 -292.96233)
		)
		(stroke
			(width 0)
			(type solid)
		)
		(fill yes)
		(layer "In13.Cu")
		(net "M_H_CPU0_SB_DQ<29>")
	)
	(gr_poly
		(pts
			(xy 387.844792 -292.51402) (xy 387.844792 -292.46957) (xy 387.64464 -292.46957) (xy 387.64464 -292.51402)
			(xy 387.744716 -292.614096)
		)
		(stroke
			(width 0)
			(type solid)
		)
		(fill yes)
		(layer "In13.Cu")
		(net "M_H_CPU0_SB_DQ<30>")
	)
	(gr_poly
		(pts
			(xy 387.844792 -291.297614) (xy 387.744716 -291.197792) (xy 387.64464 -291.297614) (xy 387.64464 -291.345366)
			(xy 387.844792 -291.345366)
		)
		(stroke
			(width 0)
			(type solid)
		)
		(fill yes)
		(layer "In13.Cu")
		(net "M_H_CPU0_SB_DQS_DN<8>")
	)
	(gr_poly
		(pts
			(xy 387.844792 -290.894262) (xy 387.844792 -290.84651) (xy 387.64464 -290.84651) (xy 387.64464 -290.894262)
			(xy 387.744716 -290.994084)
		)
		(stroke
			(width 0)
			(type solid)
		)
		(fill yes)
		(layer "In13.Cu")
		(net "M_H_CPU0_SB_DQS_DN<3>")
	)
	(gr_poly
		(pts
			(xy 387.844792 -289.677856) (xy 387.744716 -289.57778) (xy 387.64464 -289.677856) (xy 387.64464 -289.722306)
			(xy 387.844792 -289.722306)
		)
		(stroke
			(width 0)
			(type solid)
		)
		(fill yes)
		(layer "In13.Cu")
		(net "M_H_CPU0_SB_DQ<25>")
	)
	(gr_poly
		(pts
			(xy 387.844792 -289.273996) (xy 387.844792 -289.229546) (xy 387.64464 -289.229546) (xy 387.64464 -289.273996)
			(xy 387.744716 -289.374072)
		)
		(stroke
			(width 0)
			(type solid)
		)
		(fill yes)
		(layer "In13.Cu")
		(net "M_H_CPU0_SB_DQ<26>")
	)
	(gr_poly
		(pts
			(xy 387.844792 -288.057844) (xy 387.744716 -287.957768) (xy 387.64464 -288.057844) (xy 387.64464 -288.102294)
			(xy 387.844792 -288.102294)
		)
		(stroke
			(width 0)
			(type solid)
		)
		(fill yes)
		(layer "In13.Cu")
		(net "M_H_CPU0_SB_DQ<21>")
	)
	(gr_poly
		(pts
			(xy 387.844792 -287.654238) (xy 387.844792 -287.609788) (xy 387.64464 -287.609788) (xy 387.64464 -287.654238)
			(xy 387.744716 -287.75406)
		)
		(stroke
			(width 0)
			(type solid)
		)
		(fill yes)
		(layer "In13.Cu")
		(net "M_H_CPU0_SB_DQ<22>")
	)
	(gr_poly
		(pts
			(xy 387.844792 -286.437832) (xy 387.744716 -286.337756) (xy 387.64464 -286.437832) (xy 387.64464 -286.485584)
			(xy 387.844792 -286.485584)
		)
		(stroke
			(width 0)
			(type solid)
		)
		(fill yes)
		(layer "In13.Cu")
		(net "M_H_CPU0_SB_DQS_DN<7>")
	)
	(gr_poly
		(pts
			(xy 387.844792 -286.03448) (xy 387.844792 -285.986728) (xy 387.64464 -285.986728) (xy 387.64464 -286.03448)
			(xy 387.744716 -286.134302)
		)
		(stroke
			(width 0)
			(type solid)
		)
		(fill yes)
		(layer "In13.Cu")
		(net "M_H_CPU0_SB_DQS_DN<2>")
	)
	(gr_poly
		(pts
			(xy 387.844792 -284.818074) (xy 387.744716 -284.717998) (xy 387.64464 -284.818074) (xy 387.64464 -284.862524)
			(xy 387.844792 -284.862524)
		)
		(stroke
			(width 0)
			(type solid)
		)
		(fill yes)
		(layer "In13.Cu")
		(net "M_H_CPU0_SB_DQ<17>")
	)
	(gr_poly
		(pts
			(xy 387.844792 -284.414214) (xy 387.844792 -284.369764) (xy 387.64464 -284.369764) (xy 387.64464 -284.414214)
			(xy 387.744716 -284.51429)
		)
		(stroke
			(width 0)
			(type solid)
		)
		(fill yes)
		(layer "In13.Cu")
		(net "M_H_CPU0_SB_DQ<18>")
	)
	(gr_poly
		(pts
			(xy 387.844792 -283.198062) (xy 387.744716 -283.097986) (xy 387.64464 -283.198062) (xy 387.64464 -283.242512)
			(xy 387.844792 -283.242512)
		)
		(stroke
			(width 0)
			(type solid)
		)
		(fill yes)
		(layer "In13.Cu")
		(net "M_H_CPU0_SB_DQ<13>")
	)
	(gr_poly
		(pts
			(xy 387.844792 -282.794202) (xy 387.844792 -282.749752) (xy 387.64464 -282.749752) (xy 387.64464 -282.794202)
			(xy 387.744716 -282.894278)
		)
		(stroke
			(width 0)
			(type solid)
		)
		(fill yes)
		(layer "In13.Cu")
		(net "M_H_CPU0_SB_DQ<14>")
	)
	(gr_poly
		(pts
			(xy 387.844792 -281.577796) (xy 387.744716 -281.477974) (xy 387.64464 -281.577796) (xy 387.64464 -281.625548)
			(xy 387.844792 -281.625548)
		)
		(stroke
			(width 0)
			(type solid)
		)
		(fill yes)
		(layer "In13.Cu")
		(net "M_H_CPU0_SB_DQS_DN<6>")
	)
	(gr_poly
		(pts
			(xy 387.844792 -281.174444) (xy 387.844792 -281.126692) (xy 387.64464 -281.126692) (xy 387.64464 -281.174444)
			(xy 387.744716 -281.274266)
		)
		(stroke
			(width 0)
			(type solid)
		)
		(fill yes)
		(layer "In13.Cu")
		(net "M_H_CPU0_SB_DQS_DN<1>")
	)
	(gr_poly
		(pts
			(xy 387.844792 -279.958038) (xy 387.744716 -279.857962) (xy 387.64464 -279.958038) (xy 387.64464 -280.002488)
			(xy 387.844792 -280.002488)
		)
		(stroke
			(width 0)
			(type solid)
		)
		(fill yes)
		(layer "In13.Cu")
		(net "M_H_CPU0_SB_DQ<9>")
	)
	(gr_poly
		(pts
			(xy 387.844792 -279.554178) (xy 387.844792 -279.509728) (xy 387.64464 -279.509728) (xy 387.64464 -279.554178)
			(xy 387.744716 -279.654254)
		)
		(stroke
			(width 0)
			(type solid)
		)
		(fill yes)
		(layer "In13.Cu")
		(net "M_H_CPU0_SB_DQ<10>")
	)
	(gr_poly
		(pts
			(xy 387.844792 -278.338026) (xy 387.744716 -278.23795) (xy 387.64464 -278.338026) (xy 387.64464 -278.382476)
			(xy 387.844792 -278.382476)
		)
		(stroke
			(width 0)
			(type solid)
		)
		(fill yes)
		(layer "In13.Cu")
		(net "M_H_CPU0_SB_DQ<5>")
	)
	(gr_poly
		(pts
			(xy 387.844792 -277.934166) (xy 387.844792 -277.889716) (xy 387.64464 -277.889716) (xy 387.64464 -277.934166)
			(xy 387.744716 -278.034242)
		)
		(stroke
			(width 0)
			(type solid)
		)
		(fill yes)
		(layer "In13.Cu")
		(net "M_H_CPU0_SB_DQ<6>")
	)
	(gr_poly
		(pts
			(xy 387.844792 -276.71776) (xy 387.744716 -276.617938) (xy 387.64464 -276.71776) (xy 387.64464 -276.765512)
			(xy 387.844792 -276.765512)
		)
		(stroke
			(width 0)
			(type solid)
		)
		(fill yes)
		(layer "In13.Cu")
		(net "M_H_CPU0_SB_DQS_DN<5>")
	)
	(gr_poly
		(pts
			(xy 387.844792 -276.314408) (xy 387.844792 -276.266656) (xy 387.64464 -276.266656) (xy 387.64464 -276.314408)
			(xy 387.744716 -276.41423)
		)
		(stroke
			(width 0)
			(type solid)
		)
		(fill yes)
		(layer "In13.Cu")
		(net "M_H_CPU0_SB_DQS_DN<0>")
	)
	(gr_poly
		(pts
			(xy 387.844792 -275.098002) (xy 387.744716 -274.997926) (xy 387.64464 -275.098002) (xy 387.64464 -275.142452)
			(xy 387.844792 -275.142452)
		)
		(stroke
			(width 0)
			(type solid)
		)
		(fill yes)
		(layer "In13.Cu")
		(net "M_H_CPU0_SB_DQ<1>")
	)
	(gr_poly
		(pts
			(xy 387.844792 -274.694142) (xy 387.844792 -274.649692) (xy 387.64464 -274.649692) (xy 387.64464 -274.694142)
			(xy 387.744716 -274.794218)
		)
		(stroke
			(width 0)
			(type solid)
		)
		(fill yes)
		(layer "In13.Cu")
		(net "M_H_CPU0_SB_DQ<2>")
	)
	(gr_poly
		(pts
			(xy 387.844792 -273.47799) (xy 387.744716 -273.377914) (xy 387.64464 -273.47799) (xy 387.64464 -273.52244)
			(xy 387.844792 -273.52244)
		)
		(stroke
			(width 0)
			(type solid)
		)
		(fill yes)
		(layer "In13.Cu")
		(net "M_H_CPU0_SB_CB<1>")
	)
	(gr_poly
		(pts
			(xy 387.844792 -273.07413) (xy 387.844792 -273.02968) (xy 387.64464 -273.02968) (xy 387.64464 -273.07413)
			(xy 387.744716 -273.174206)
		)
		(stroke
			(width 0)
			(type solid)
		)
		(fill yes)
		(layer "In13.Cu")
		(net "M_H_CPU0_SB_CB<2>")
	)
	(gr_poly
		(pts
			(xy 387.844792 -271.857724) (xy 387.744716 -271.757902) (xy 387.64464 -271.857724) (xy 387.64464 -271.905476)
			(xy 387.844792 -271.905476)
		)
		(stroke
			(width 0)
			(type solid)
		)
		(fill yes)
		(layer "In13.Cu")
		(net "M_H_CPU0_SB_DQS_DN<4>")
	)
	(gr_poly
		(pts
			(xy 387.844792 -271.454372) (xy 387.844792 -271.40662) (xy 387.64464 -271.40662) (xy 387.64464 -271.454372)
			(xy 387.744716 -271.554194)
		)
		(stroke
			(width 0)
			(type solid)
		)
		(fill yes)
		(layer "In13.Cu")
		(net "M_H_CPU0_SB_DQS_DN<9>")
	)
	(gr_poly
		(pts
			(xy 387.844792 -270.237966) (xy 387.744716 -270.13789) (xy 387.64464 -270.237966) (xy 387.64464 -270.282416)
			(xy 387.844792 -270.282416)
		)
		(stroke
			(width 0)
			(type solid)
		)
		(fill yes)
		(layer "In13.Cu")
		(net "M_H_CPU0_SB_CB<5>")
	)
	(gr_poly
		(pts
			(xy 387.844792 -269.834106) (xy 387.844792 -269.789656) (xy 387.64464 -269.789656) (xy 387.64464 -269.834106)
			(xy 387.744716 -269.934182)
		)
		(stroke
			(width 0)
			(type solid)
		)
		(fill yes)
		(layer "In13.Cu")
		(net "M_H_CPU0_SB_CB<6>")
	)
	(gr_poly
		(pts
			(xy 387.844792 -266.997942) (xy 387.744716 -266.897866) (xy 387.64464 -266.997942) (xy 387.64464 -267.042392)
			(xy 387.844792 -267.042392)
		)
		(stroke
			(width 0)
			(type solid)
		)
		(fill yes)
		(layer "In13.Cu")
		(net "M_H_CPU0_SA_RSP<0>")
	)
	(gr_poly
		(pts
			(xy 387.844792 -266.594082) (xy 387.844792 -266.549632) (xy 387.64464 -266.549632) (xy 387.64464 -266.594082)
			(xy 387.744716 -266.694158)
		)
		(stroke
			(width 0)
			(type solid)
		)
		(fill yes)
		(layer "In13.Cu")
		(net "M_H_CPU0_SB_CS_N<1>")
	)
	(gr_poly
		(pts
			(xy 387.844792 -265.37793) (xy 387.744716 -265.277854) (xy 387.64464 -265.37793) (xy 387.64464 -265.42238)
			(xy 387.844792 -265.42238)
		)
		(stroke
			(width 0)
			(type solid)
		)
		(fill yes)
		(layer "In13.Cu")
		(net "M_H_CPU0_SB_PAR")
	)
	(gr_poly
		(pts
			(xy 387.844792 -263.757918) (xy 387.744716 -263.657842) (xy 387.64464 -263.757918) (xy 387.64464 -263.802368)
			(xy 387.844792 -263.802368)
		)
		(stroke
			(width 0)
			(type solid)
		)
		(fill yes)
		(layer "In13.Cu")
		(net "M_H_CPU0_SB_CA<4>")
	)
	(gr_poly
		(pts
			(xy 387.844792 -263.354058) (xy 387.844792 -263.309608) (xy 387.64464 -263.309608) (xy 387.64464 -263.354058)
			(xy 387.744716 -263.454134)
		)
		(stroke
			(width 0)
			(type solid)
		)
		(fill yes)
		(layer "In13.Cu")
		(net "M_H_CPU0_SB_CA<3>")
	)
	(gr_poly
		(pts
			(xy 387.844792 -262.137906) (xy 387.744716 -262.03783) (xy 387.64464 -262.137906) (xy 387.64464 -262.182356)
			(xy 387.844792 -262.182356)
		)
		(stroke
			(width 0)
			(type solid)
		)
		(fill yes)
		(layer "In13.Cu")
		(net "M_H_CPU0_SB_CA<0>")
	)
	(gr_poly
		(pts
			(xy 388.014972 -256.432558) (xy 388.014972 -256.384806) (xy 387.81482 -256.384806) (xy 387.81482 -256.432558)
			(xy 387.914896 -256.53238)
		)
		(stroke
			(width 0)
			(type solid)
		)
		(fill yes)
		(layer "In13.Cu")
		(net "M_H_CPU0_CLK_DN<0>")
	)
	(gr_poly
		(pts
			(xy 388.014972 -255.216152) (xy 387.914896 -255.116076) (xy 387.81482 -255.216152) (xy 387.81482 -255.260602)
			(xy 388.014972 -255.260602)
		)
		(stroke
			(width 0)
			(type solid)
		)
		(fill yes)
		(layer "In13.Cu")
		(net "M_H_CPU0_SA_CA<6>")
	)
	(gr_poly
		(pts
			(xy 388.014972 -254.812292) (xy 388.014972 -254.767842) (xy 387.81482 -254.767842) (xy 387.81482 -254.812292)
			(xy 387.914896 -254.912368)
		)
		(stroke
			(width 0)
			(type solid)
		)
		(fill yes)
		(layer "In13.Cu")
		(net "M_H_CPU0_SA_CA<5>")
	)
	(gr_poly
		(pts
			(xy 388.014972 -253.59614) (xy 387.914896 -253.496064) (xy 387.81482 -253.59614) (xy 387.81482 -253.64059)
			(xy 388.014972 -253.64059)
		)
		(stroke
			(width 0)
			(type solid)
		)
		(fill yes)
		(layer "In13.Cu")
		(net "M_H_CPU0_SA_CA<2>")
	)
	(gr_poly
		(pts
			(xy 388.014972 -253.19228) (xy 388.014972 -253.14783) (xy 387.81482 -253.14783) (xy 387.81482 -253.19228)
			(xy 387.914896 -253.292356)
		)
		(stroke
			(width 0)
			(type solid)
		)
		(fill yes)
		(layer "In13.Cu")
		(net "M_H_CPU0_SA_CA<1>")
	)
	(gr_poly
		(pts
			(xy 388.014972 -251.976128) (xy 387.914896 -251.876052) (xy 387.81482 -251.976128) (xy 387.81482 -252.020578)
			(xy 388.014972 -252.020578)
		)
		(stroke
			(width 0)
			(type solid)
		)
		(fill yes)
		(layer "In13.Cu")
		(net "M_H_CPU0_SA_CS_N<1>")
	)
	(gr_poly
		(pts
			(xy 388.014972 -250.356116) (xy 387.914896 -250.25604) (xy 387.81482 -250.356116) (xy 387.81482 -250.400566)
			(xy 388.014972 -250.400566)
		)
		(stroke
			(width 0)
			(type solid)
		)
		(fill yes)
		(layer "In13.Cu")
		(net "M_H_CPU0_ALERT_R_N")
	)
	(gr_poly
		(pts
			(xy 388.014972 -248.736104) (xy 387.914896 -248.636028) (xy 387.81482 -248.736104) (xy 387.81482 -248.780554)
			(xy 388.014972 -248.780554)
		)
		(stroke
			(width 0)
			(type solid)
		)
		(fill yes)
		(layer "In13.Cu")
		(net "M_H_CPU0_SA_CB<5>")
	)
	(gr_poly
		(pts
			(xy 388.014972 -248.332244) (xy 388.014972 -248.287794) (xy 387.81482 -248.287794) (xy 387.81482 -248.332244)
			(xy 387.914896 -248.43232)
		)
		(stroke
			(width 0)
			(type solid)
		)
		(fill yes)
		(layer "In13.Cu")
		(net "M_H_CPU0_SA_CB<6>")
	)
	(gr_poly
		(pts
			(xy 388.014972 -247.115838) (xy 387.914896 -247.016016) (xy 387.81482 -247.115838) (xy 387.81482 -247.16359)
			(xy 388.014972 -247.16359)
		)
		(stroke
			(width 0)
			(type solid)
		)
		(fill yes)
		(layer "In13.Cu")
		(net "M_H_CPU0_SA_DQS_DN<9>")
	)
	(gr_poly
		(pts
			(xy 388.014972 -246.712486) (xy 388.014972 -246.664734) (xy 387.81482 -246.664734) (xy 387.81482 -246.712486)
			(xy 387.914896 -246.812308)
		)
		(stroke
			(width 0)
			(type solid)
		)
		(fill yes)
		(layer "In13.Cu")
		(net "M_H_CPU0_SA_DQS_DN<4>")
	)
	(gr_poly
		(pts
			(xy 388.014972 -245.49608) (xy 387.914896 -245.396004) (xy 387.81482 -245.49608) (xy 387.81482 -245.54053)
			(xy 388.014972 -245.54053)
		)
		(stroke
			(width 0)
			(type solid)
		)
		(fill yes)
		(layer "In13.Cu")
		(net "M_H_CPU0_SA_CB<1>")
	)
	(gr_poly
		(pts
			(xy 388.014972 -245.09222) (xy 388.014972 -245.04777) (xy 387.81482 -245.04777) (xy 387.81482 -245.09222)
			(xy 387.914896 -245.192296)
		)
		(stroke
			(width 0)
			(type solid)
		)
		(fill yes)
		(layer "In13.Cu")
		(net "M_H_CPU0_SA_CB<2>")
	)
	(gr_poly
		(pts
			(xy 388.014972 -243.876068) (xy 387.914896 -243.775992) (xy 387.81482 -243.876068) (xy 387.81482 -243.920518)
			(xy 388.014972 -243.920518)
		)
		(stroke
			(width 0)
			(type solid)
		)
		(fill yes)
		(layer "In13.Cu")
		(net "M_H_CPU0_SA_DQ<29>")
	)
	(gr_poly
		(pts
			(xy 388.014972 -243.472208) (xy 388.014972 -243.427758) (xy 387.81482 -243.427758) (xy 387.81482 -243.472208)
			(xy 387.914896 -243.572284)
		)
		(stroke
			(width 0)
			(type solid)
		)
		(fill yes)
		(layer "In13.Cu")
		(net "M_H_CPU0_SA_DQ<30>")
	)
	(gr_poly
		(pts
			(xy 388.014972 -242.255802) (xy 387.914896 -242.15598) (xy 387.81482 -242.255802) (xy 387.81482 -242.303554)
			(xy 388.014972 -242.303554)
		)
		(stroke
			(width 0)
			(type solid)
		)
		(fill yes)
		(layer "In13.Cu")
		(net "M_H_CPU0_SA_DQS_DN<8>")
	)
	(gr_poly
		(pts
			(xy 388.014972 -241.85245) (xy 388.014972 -241.804698) (xy 387.81482 -241.804698) (xy 387.81482 -241.85245)
			(xy 387.914896 -241.952272)
		)
		(stroke
			(width 0)
			(type solid)
		)
		(fill yes)
		(layer "In13.Cu")
		(net "M_H_CPU0_SA_DQS_DN<3>")
	)
	(gr_poly
		(pts
			(xy 388.014972 -240.636044) (xy 387.914896 -240.535968) (xy 387.81482 -240.636044) (xy 387.81482 -240.680494)
			(xy 388.014972 -240.680494)
		)
		(stroke
			(width 0)
			(type solid)
		)
		(fill yes)
		(layer "In13.Cu")
		(net "M_H_CPU0_SA_DQ<25>")
	)
	(gr_poly
		(pts
			(xy 388.014972 -240.232184) (xy 388.014972 -240.187734) (xy 387.81482 -240.187734) (xy 387.81482 -240.232184)
			(xy 387.914896 -240.33226)
		)
		(stroke
			(width 0)
			(type solid)
		)
		(fill yes)
		(layer "In13.Cu")
		(net "M_H_CPU0_SA_DQ<26>")
	)
	(gr_poly
		(pts
			(xy 388.014972 -239.016032) (xy 387.914896 -238.915956) (xy 387.81482 -239.016032) (xy 387.81482 -239.060482)
			(xy 388.014972 -239.060482)
		)
		(stroke
			(width 0)
			(type solid)
		)
		(fill yes)
		(layer "In13.Cu")
		(net "M_H_CPU0_SA_DQ<21>")
	)
	(gr_poly
		(pts
			(xy 388.014972 -238.612172) (xy 388.014972 -238.567722) (xy 387.81482 -238.567722) (xy 387.81482 -238.612172)
			(xy 387.914896 -238.712248)
		)
		(stroke
			(width 0)
			(type solid)
		)
		(fill yes)
		(layer "In13.Cu")
		(net "M_H_CPU0_SA_DQ<22>")
	)
	(gr_poly
		(pts
			(xy 388.014972 -237.395766) (xy 387.914896 -237.295944) (xy 387.81482 -237.395766) (xy 387.81482 -237.443518)
			(xy 388.014972 -237.443518)
		)
		(stroke
			(width 0)
			(type solid)
		)
		(fill yes)
		(layer "In13.Cu")
		(net "M_H_CPU0_SA_DQS_DN<7>")
	)
	(gr_poly
		(pts
			(xy 388.014972 -236.992414) (xy 388.014972 -236.944662) (xy 387.81482 -236.944662) (xy 387.81482 -236.992414)
			(xy 387.914896 -237.092236)
		)
		(stroke
			(width 0)
			(type solid)
		)
		(fill yes)
		(layer "In13.Cu")
		(net "M_H_CPU0_SA_DQS_DN<2>")
	)
	(gr_poly
		(pts
			(xy 388.014972 -235.776008) (xy 387.914896 -235.675932) (xy 387.81482 -235.776008) (xy 387.81482 -235.820458)
			(xy 388.014972 -235.820458)
		)
		(stroke
			(width 0)
			(type solid)
		)
		(fill yes)
		(layer "In13.Cu")
		(net "M_H_CPU0_SA_DQ<17>")
	)
	(gr_poly
		(pts
			(xy 388.014972 -235.372148) (xy 388.014972 -235.327698) (xy 387.81482 -235.327698) (xy 387.81482 -235.372148)
			(xy 387.914896 -235.472224)
		)
		(stroke
			(width 0)
			(type solid)
		)
		(fill yes)
		(layer "In13.Cu")
		(net "M_H_CPU0_SA_DQ<18>")
	)
	(gr_poly
		(pts
			(xy 388.014972 -234.155996) (xy 387.914896 -234.05592) (xy 387.81482 -234.155996) (xy 387.81482 -234.200446)
			(xy 388.014972 -234.200446)
		)
		(stroke
			(width 0)
			(type solid)
		)
		(fill yes)
		(layer "In13.Cu")
		(net "M_H_CPU0_SA_DQ<13>")
	)
	(gr_poly
		(pts
			(xy 388.014972 -233.752136) (xy 388.014972 -233.707686) (xy 387.81482 -233.707686) (xy 387.81482 -233.752136)
			(xy 387.914896 -233.852212)
		)
		(stroke
			(width 0)
			(type solid)
		)
		(fill yes)
		(layer "In13.Cu")
		(net "M_H_CPU0_SA_DQ<14>")
	)
	(gr_poly
		(pts
			(xy 388.014972 -232.53573) (xy 387.914896 -232.435908) (xy 387.81482 -232.53573) (xy 387.81482 -232.583482)
			(xy 388.014972 -232.583482)
		)
		(stroke
			(width 0)
			(type solid)
		)
		(fill yes)
		(layer "In13.Cu")
		(net "M_H_CPU0_SA_DQS_DN<6>")
	)
	(gr_poly
		(pts
			(xy 388.014972 -232.132378) (xy 388.014972 -232.084626) (xy 387.81482 -232.084626) (xy 387.81482 -232.132378)
			(xy 387.914896 -232.2322)
		)
		(stroke
			(width 0)
			(type solid)
		)
		(fill yes)
		(layer "In13.Cu")
		(net "M_H_CPU0_SA_DQS_DN<1>")
	)
	(gr_poly
		(pts
			(xy 388.014972 -230.915972) (xy 387.914896 -230.815896) (xy 387.81482 -230.915972) (xy 387.81482 -230.960422)
			(xy 388.014972 -230.960422)
		)
		(stroke
			(width 0)
			(type solid)
		)
		(fill yes)
		(layer "In13.Cu")
		(net "M_H_CPU0_SA_DQ<9>")
	)
	(gr_poly
		(pts
			(xy 388.014972 -230.512366) (xy 388.014972 -230.467916) (xy 387.81482 -230.467916) (xy 387.81482 -230.512366)
			(xy 387.914896 -230.612188)
		)
		(stroke
			(width 0)
			(type solid)
		)
		(fill yes)
		(layer "In13.Cu")
		(net "M_H_CPU0_SA_DQ<10>")
	)
	(gr_poly
		(pts
			(xy 388.014972 -229.29596) (xy 387.914896 -229.195884) (xy 387.81482 -229.29596) (xy 387.81482 -229.34041)
			(xy 388.014972 -229.34041)
		)
		(stroke
			(width 0)
			(type solid)
		)
		(fill yes)
		(layer "In13.Cu")
		(net "M_H_CPU0_SA_DQ<5>")
	)
	(gr_poly
		(pts
			(xy 388.014972 -228.892354) (xy 388.014972 -228.847904) (xy 387.81482 -228.847904) (xy 387.81482 -228.892354)
			(xy 387.914896 -228.99243)
		)
		(stroke
			(width 0)
			(type solid)
		)
		(fill yes)
		(layer "In13.Cu")
		(net "M_H_CPU0_SA_DQ<6>")
	)
	(gr_poly
		(pts
			(xy 388.014972 -227.675948) (xy 387.914896 -227.576126) (xy 387.81482 -227.675948) (xy 387.81482 -227.7237)
			(xy 388.014972 -227.7237)
		)
		(stroke
			(width 0)
			(type solid)
		)
		(fill yes)
		(layer "In13.Cu")
		(net "M_H_CPU0_SA_DQS_DN<5>")
	)
	(gr_poly
		(pts
			(xy 388.014972 -227.272596) (xy 388.014972 -227.224844) (xy 387.81482 -227.224844) (xy 387.81482 -227.272596)
			(xy 387.914896 -227.372418)
		)
		(stroke
			(width 0)
			(type solid)
		)
		(fill yes)
		(layer "In13.Cu")
		(net "M_H_CPU0_SA_DQS_DN<0>")
	)
	(gr_poly
		(pts
			(xy 388.014972 -226.05619) (xy 387.914896 -225.956114) (xy 387.81482 -226.05619) (xy 387.81482 -226.10064)
			(xy 388.014972 -226.10064)
		)
		(stroke
			(width 0)
			(type solid)
		)
		(fill yes)
		(layer "In13.Cu")
		(net "M_H_CPU0_SA_DQ<1>")
	)
	(gr_poly
		(pts
			(xy 388.014972 -225.65233) (xy 388.014972 -225.60788) (xy 387.81482 -225.60788) (xy 387.81482 -225.65233)
			(xy 387.914896 -225.752406)
		)
		(stroke
			(width 0)
			(type solid)
		)
		(fill yes)
		(layer "In13.Cu")
		(net "M_H_CPU0_SA_DQ<2>")
	)
	(gr_poly
		(pts
			(xy 388.314946 -293.324026) (xy 388.314946 -293.279576) (xy 388.114794 -293.279576) (xy 388.114794 -293.324026)
			(xy 388.21487 -293.424102)
		)
		(stroke
			(width 0)
			(type solid)
		)
		(fill yes)
		(layer "In13.Cu")
		(net "M_H_CPU0_SB_DQ<31>")
	)
	(gr_poly
		(pts
			(xy 388.314946 -292.107874) (xy 388.21487 -292.007798) (xy 388.114794 -292.107874) (xy 388.114794 -292.152324)
			(xy 388.314946 -292.152324)
		)
		(stroke
			(width 0)
			(type solid)
		)
		(fill yes)
		(layer "In13.Cu")
		(net "M_H_CPU0_SB_DQ<28>")
	)
	(gr_poly
		(pts
			(xy 388.314946 -291.704268) (xy 388.314946 -291.656516) (xy 388.114794 -291.656516) (xy 388.114794 -291.704268)
			(xy 388.21487 -291.80409)
		)
		(stroke
			(width 0)
			(type solid)
		)
		(fill yes)
		(layer "In13.Cu")
		(net "M_H_CPU0_SB_DQS_DP<8>")
	)
	(gr_poly
		(pts
			(xy 388.314946 -290.487608) (xy 388.21487 -290.387786) (xy 388.114794 -290.487608) (xy 388.114794 -290.53536)
			(xy 388.314946 -290.53536)
		)
		(stroke
			(width 0)
			(type solid)
		)
		(fill yes)
		(layer "In13.Cu")
		(net "M_H_CPU0_SB_DQS_DP<3>")
	)
	(gr_poly
		(pts
			(xy 388.314946 -290.084002) (xy 388.314946 -290.039552) (xy 388.114794 -290.039552) (xy 388.114794 -290.084002)
			(xy 388.21487 -290.184078)
		)
		(stroke
			(width 0)
			(type solid)
		)
		(fill yes)
		(layer "In13.Cu")
		(net "M_H_CPU0_SB_DQ<27>")
	)
	(gr_poly
		(pts
			(xy 388.314946 -288.86785) (xy 388.21487 -288.767774) (xy 388.114794 -288.86785) (xy 388.114794 -288.9123)
			(xy 388.314946 -288.9123)
		)
		(stroke
			(width 0)
			(type solid)
		)
		(fill yes)
		(layer "In13.Cu")
		(net "M_H_CPU0_SB_DQ<24>")
	)
	(gr_poly
		(pts
			(xy 388.314946 -288.464244) (xy 388.314946 -288.419794) (xy 388.114794 -288.419794) (xy 388.114794 -288.464244)
			(xy 388.21487 -288.56432)
		)
		(stroke
			(width 0)
			(type solid)
		)
		(fill yes)
		(layer "In13.Cu")
		(net "M_H_CPU0_SB_DQ<23>")
	)
	(gr_poly
		(pts
			(xy 388.314946 -287.247838) (xy 388.21487 -287.148016) (xy 388.114794 -287.247838) (xy 388.114794 -287.292288)
			(xy 388.314946 -287.292288)
		)
		(stroke
			(width 0)
			(type solid)
		)
		(fill yes)
		(layer "In13.Cu")
		(net "M_H_CPU0_SB_DQ<20>")
	)
	(gr_poly
		(pts
			(xy 388.314946 -286.844232) (xy 388.314946 -286.79648) (xy 388.114794 -286.79648) (xy 388.114794 -286.844232)
			(xy 388.21487 -286.944308)
		)
		(stroke
			(width 0)
			(type solid)
		)
		(fill yes)
		(layer "In13.Cu")
		(net "M_H_CPU0_SB_DQS_DP<7>")
	)
	(gr_poly
		(pts
			(xy 388.314946 -285.627826) (xy 388.21487 -285.528004) (xy 388.114794 -285.627826) (xy 388.114794 -285.675578)
			(xy 388.314946 -285.675578)
		)
		(stroke
			(width 0)
			(type solid)
		)
		(fill yes)
		(layer "In13.Cu")
		(net "M_H_CPU0_SB_DQS_DP<2>")
	)
	(gr_poly
		(pts
			(xy 388.314946 -285.22422) (xy 388.314946 -285.17977) (xy 388.114794 -285.17977) (xy 388.114794 -285.22422)
			(xy 388.21487 -285.324296)
		)
		(stroke
			(width 0)
			(type solid)
		)
		(fill yes)
		(layer "In13.Cu")
		(net "M_H_CPU0_SB_DQ<19>")
	)
	(gr_poly
		(pts
			(xy 388.314946 -284.008068) (xy 388.21487 -283.907992) (xy 388.114794 -284.008068) (xy 388.114794 -284.052518)
			(xy 388.314946 -284.052518)
		)
		(stroke
			(width 0)
			(type solid)
		)
		(fill yes)
		(layer "In13.Cu")
		(net "M_H_CPU0_SB_DQ<16>")
	)
	(gr_poly
		(pts
			(xy 388.314946 -283.604208) (xy 388.314946 -283.559758) (xy 388.114794 -283.559758) (xy 388.114794 -283.604208)
			(xy 388.21487 -283.704284)
		)
		(stroke
			(width 0)
			(type solid)
		)
		(fill yes)
		(layer "In13.Cu")
		(net "M_H_CPU0_SB_DQ<15>")
	)
	(gr_poly
		(pts
			(xy 388.314946 -282.388056) (xy 388.21487 -282.28798) (xy 388.114794 -282.388056) (xy 388.114794 -282.432506)
			(xy 388.314946 -282.432506)
		)
		(stroke
			(width 0)
			(type solid)
		)
		(fill yes)
		(layer "In13.Cu")
		(net "M_H_CPU0_SB_DQ<12>")
	)
	(gr_poly
		(pts
			(xy 388.314946 -281.98445) (xy 388.314946 -281.936698) (xy 388.114794 -281.936698) (xy 388.114794 -281.98445)
			(xy 388.21487 -282.084272)
		)
		(stroke
			(width 0)
			(type solid)
		)
		(fill yes)
		(layer "In13.Cu")
		(net "M_H_CPU0_SB_DQS_DP<6>")
	)
	(gr_poly
		(pts
			(xy 388.314946 -280.76779) (xy 388.21487 -280.667968) (xy 388.114794 -280.76779) (xy 388.114794 -280.815542)
			(xy 388.314946 -280.815542)
		)
		(stroke
			(width 0)
			(type solid)
		)
		(fill yes)
		(layer "In13.Cu")
		(net "M_H_CPU0_SB_DQS_DP<1>")
	)
	(gr_poly
		(pts
			(xy 388.314946 -280.364184) (xy 388.314946 -280.319734) (xy 388.114794 -280.319734) (xy 388.114794 -280.364184)
			(xy 388.21487 -280.46426)
		)
		(stroke
			(width 0)
			(type solid)
		)
		(fill yes)
		(layer "In13.Cu")
		(net "M_H_CPU0_SB_DQ<11>")
	)
	(gr_poly
		(pts
			(xy 388.314946 -279.148032) (xy 388.21487 -279.047956) (xy 388.114794 -279.148032) (xy 388.114794 -279.192482)
			(xy 388.314946 -279.192482)
		)
		(stroke
			(width 0)
			(type solid)
		)
		(fill yes)
		(layer "In13.Cu")
		(net "M_H_CPU0_SB_DQ<8>")
	)
	(gr_poly
		(pts
			(xy 388.314946 -278.744172) (xy 388.314946 -278.699722) (xy 388.114794 -278.699722) (xy 388.114794 -278.744172)
			(xy 388.21487 -278.844248)
		)
		(stroke
			(width 0)
			(type solid)
		)
		(fill yes)
		(layer "In13.Cu")
		(net "M_H_CPU0_SB_DQ<7>")
	)
	(gr_poly
		(pts
			(xy 388.314946 -277.52802) (xy 388.21487 -277.427944) (xy 388.114794 -277.52802) (xy 388.114794 -277.57247)
			(xy 388.314946 -277.57247)
		)
		(stroke
			(width 0)
			(type solid)
		)
		(fill yes)
		(layer "In13.Cu")
		(net "M_H_CPU0_SB_DQ<4>")
	)
	(gr_poly
		(pts
			(xy 388.314946 -277.124414) (xy 388.314946 -277.076662) (xy 388.114794 -277.076662) (xy 388.114794 -277.124414)
			(xy 388.21487 -277.224236)
		)
		(stroke
			(width 0)
			(type solid)
		)
		(fill yes)
		(layer "In13.Cu")
		(net "M_H_CPU0_SB_DQS_DP<5>")
	)
	(gr_poly
		(pts
			(xy 388.314946 -275.907754) (xy 388.21487 -275.807932) (xy 388.114794 -275.907754) (xy 388.114794 -275.955506)
			(xy 388.314946 -275.955506)
		)
		(stroke
			(width 0)
			(type solid)
		)
		(fill yes)
		(layer "In13.Cu")
		(net "M_H_CPU0_SB_DQS_DP<0>")
	)
	(gr_poly
		(pts
			(xy 388.314946 -275.504148) (xy 388.314946 -275.459698) (xy 388.114794 -275.459698) (xy 388.114794 -275.504148)
			(xy 388.21487 -275.604224)
		)
		(stroke
			(width 0)
			(type solid)
		)
		(fill yes)
		(layer "In13.Cu")
		(net "M_H_CPU0_SB_DQ<3>")
	)
	(gr_poly
		(pts
			(xy 388.314946 -274.287996) (xy 388.21487 -274.18792) (xy 388.114794 -274.287996) (xy 388.114794 -274.332446)
			(xy 388.314946 -274.332446)
		)
		(stroke
			(width 0)
			(type solid)
		)
		(fill yes)
		(layer "In13.Cu")
		(net "M_H_CPU0_SB_DQ<0>")
	)
	(gr_poly
		(pts
			(xy 388.314946 -273.884136) (xy 388.314946 -273.839686) (xy 388.114794 -273.839686) (xy 388.114794 -273.884136)
			(xy 388.21487 -273.984212)
		)
		(stroke
			(width 0)
			(type solid)
		)
		(fill yes)
		(layer "In13.Cu")
		(net "M_H_CPU0_SB_CB<3>")
	)
	(gr_poly
		(pts
			(xy 388.314946 -272.667984) (xy 388.21487 -272.567908) (xy 388.114794 -272.667984) (xy 388.114794 -272.712434)
			(xy 388.314946 -272.712434)
		)
		(stroke
			(width 0)
			(type solid)
		)
		(fill yes)
		(layer "In13.Cu")
		(net "M_H_CPU0_SB_CB<0>")
	)
	(gr_poly
		(pts
			(xy 388.314946 -272.264378) (xy 388.314946 -272.216626) (xy 388.114794 -272.216626) (xy 388.114794 -272.264378)
			(xy 388.21487 -272.3642)
		)
		(stroke
			(width 0)
			(type solid)
		)
		(fill yes)
		(layer "In13.Cu")
		(net "M_H_CPU0_SB_DQS_DP<4>")
	)
	(gr_poly
		(pts
			(xy 388.314946 -271.047718) (xy 388.21487 -270.947896) (xy 388.114794 -271.047718) (xy 388.114794 -271.09547)
			(xy 388.314946 -271.09547)
		)
		(stroke
			(width 0)
			(type solid)
		)
		(fill yes)
		(layer "In13.Cu")
		(net "M_H_CPU0_SB_DQS_DP<9>")
	)
	(gr_poly
		(pts
			(xy 388.314946 -270.644112) (xy 388.314946 -270.599662) (xy 388.114794 -270.599662) (xy 388.114794 -270.644112)
			(xy 388.21487 -270.744188)
		)
		(stroke
			(width 0)
			(type solid)
		)
		(fill yes)
		(layer "In13.Cu")
		(net "M_H_CPU0_SB_CB<7>")
	)
	(gr_poly
		(pts
			(xy 388.314946 -269.42796) (xy 388.21487 -269.327884) (xy 388.114794 -269.42796) (xy 388.114794 -269.47241)
			(xy 388.314946 -269.47241)
		)
		(stroke
			(width 0)
			(type solid)
		)
		(fill yes)
		(layer "In13.Cu")
		(net "M_H_CPU0_SB_CB<4>")
	)
	(gr_poly
		(pts
			(xy 388.314946 -267.807948) (xy 388.21487 -267.707872) (xy 388.114794 -267.807948) (xy 388.114794 -267.852398)
			(xy 388.314946 -267.852398)
		)
		(stroke
			(width 0)
			(type solid)
		)
		(fill yes)
		(layer "In13.Cu")
		(net "M_H_CPU0_SB_RSP<0>")
	)
	(gr_poly
		(pts
			(xy 388.314946 -265.784076) (xy 388.314946 -265.739626) (xy 388.114794 -265.739626) (xy 388.114794 -265.784076)
			(xy 388.21487 -265.884152)
		)
		(stroke
			(width 0)
			(type solid)
		)
		(fill yes)
		(layer "In13.Cu")
		(net "M_H_CPU0_SB_CS_N<0>")
	)
	(gr_poly
		(pts
			(xy 388.314946 -264.567924) (xy 388.21487 -264.467848) (xy 388.114794 -264.567924) (xy 388.114794 -264.612374)
			(xy 388.314946 -264.612374)
		)
		(stroke
			(width 0)
			(type solid)
		)
		(fill yes)
		(layer "In13.Cu")
		(net "M_H_CPU0_SB_CA<6>")
	)
	(gr_poly
		(pts
			(xy 388.314946 -264.164064) (xy 388.314946 -264.119614) (xy 388.114794 -264.119614) (xy 388.114794 -264.164064)
			(xy 388.21487 -264.26414)
		)
		(stroke
			(width 0)
			(type solid)
		)
		(fill yes)
		(layer "In13.Cu")
		(net "M_H_CPU0_SB_CA<5>")
	)
	(gr_poly
		(pts
			(xy 388.314946 -262.947912) (xy 388.21487 -262.847836) (xy 388.114794 -262.947912) (xy 388.114794 -262.992362)
			(xy 388.314946 -262.992362)
		)
		(stroke
			(width 0)
			(type solid)
		)
		(fill yes)
		(layer "In13.Cu")
		(net "M_H_CPU0_SB_CA<2>")
	)
	(gr_poly
		(pts
			(xy 388.314946 -262.544052) (xy 388.314946 -262.499602) (xy 388.114794 -262.499602) (xy 388.114794 -262.544052)
			(xy 388.21487 -262.644128)
		)
		(stroke
			(width 0)
			(type solid)
		)
		(fill yes)
		(layer "In13.Cu")
		(net "M_H_CPU0_SB_CA<1>")
	)
	(gr_poly
		(pts
			(xy 388.4041 -224.695512) (xy 388.365492 -224.67316) (xy 388.229094 -224.709736) (xy 388.26567 -224.846388)
			(xy 388.304024 -224.86874)
		)
		(stroke
			(width 0)
			(type solid)
		)
		(fill yes)
		(layer "In13.Cu")
		(net "M_H_CPU0_SA_DQ<0>")
	)
	(gr_poly
		(pts
			(xy 388.484872 -256.025904) (xy 388.384796 -255.926082) (xy 388.28472 -256.025904) (xy 388.28472 -256.073656)
			(xy 388.484872 -256.073656)
		)
		(stroke
			(width 0)
			(type solid)
		)
		(fill yes)
		(layer "In13.Cu")
		(net "M_H_CPU0_CLK_DP<0>")
	)
	(gr_poly
		(pts
			(xy 388.484872 -255.622298) (xy 388.484872 -255.577848) (xy 388.28472 -255.577848) (xy 388.28472 -255.622298)
			(xy 388.384796 -255.722374)
		)
		(stroke
			(width 0)
			(type solid)
		)
		(fill yes)
		(layer "In13.Cu")
		(net "M_H_CPU0_SA_PAR")
	)
	(gr_poly
		(pts
			(xy 388.484872 -254.406146) (xy 388.384796 -254.30607) (xy 388.28472 -254.406146) (xy 388.28472 -254.450596)
			(xy 388.484872 -254.450596)
		)
		(stroke
			(width 0)
			(type solid)
		)
		(fill yes)
		(layer "In13.Cu")
		(net "M_H_CPU0_SA_CA<4>")
	)
	(gr_poly
		(pts
			(xy 388.484872 -254.002286) (xy 388.484872 -253.957836) (xy 388.28472 -253.957836) (xy 388.28472 -254.002286)
			(xy 388.384796 -254.102362)
		)
		(stroke
			(width 0)
			(type solid)
		)
		(fill yes)
		(layer "In13.Cu")
		(net "M_H_CPU0_SA_CA<3>")
	)
	(gr_poly
		(pts
			(xy 388.484872 -252.786134) (xy 388.384796 -252.686058) (xy 388.28472 -252.786134) (xy 388.28472 -252.830584)
			(xy 388.484872 -252.830584)
		)
		(stroke
			(width 0)
			(type solid)
		)
		(fill yes)
		(layer "In13.Cu")
		(net "M_H_CPU0_SA_CA<0>")
	)
	(gr_poly
		(pts
			(xy 388.484872 -251.166122) (xy 388.384796 -251.066046) (xy 388.28472 -251.166122) (xy 388.28472 -251.210572)
			(xy 388.484872 -251.210572)
		)
		(stroke
			(width 0)
			(type solid)
		)
		(fill yes)
		(layer "In13.Cu")
		(net "M_H_CPU0_SA_CS_N<0>")
	)
	(gr_poly
		(pts
			(xy 388.484872 -250.762262) (xy 388.484872 -250.717812) (xy 388.28472 -250.717812) (xy 388.28472 -250.762262)
			(xy 388.384796 -250.862338)
		)
		(stroke
			(width 0)
			(type solid)
		)
		(fill yes)
		(layer "In13.Cu")
		(net "M_H_CPU0_RESET_N")
	)
	(gr_poly
		(pts
			(xy 388.484872 -249.14225) (xy 388.484872 -249.0978) (xy 388.28472 -249.0978) (xy 388.28472 -249.14225)
			(xy 388.384796 -249.242326)
		)
		(stroke
			(width 0)
			(type solid)
		)
		(fill yes)
		(layer "In13.Cu")
		(net "M_H_CPU0_SA_CB<7>")
	)
	(gr_poly
		(pts
			(xy 388.484872 -247.926098) (xy 388.384796 -247.826022) (xy 388.28472 -247.926098) (xy 388.28472 -247.970548)
			(xy 388.484872 -247.970548)
		)
		(stroke
			(width 0)
			(type solid)
		)
		(fill yes)
		(layer "In13.Cu")
		(net "M_H_CPU0_SA_CB<4>")
	)
	(gr_poly
		(pts
			(xy 388.484872 -247.522492) (xy 388.484872 -247.47474) (xy 388.28472 -247.47474) (xy 388.28472 -247.522492)
			(xy 388.384796 -247.622314)
		)
		(stroke
			(width 0)
			(type solid)
		)
		(fill yes)
		(layer "In13.Cu")
		(net "M_H_CPU0_SA_DQS_DP<9>")
	)
	(gr_poly
		(pts
			(xy 388.484872 -246.305832) (xy 388.384796 -246.20601) (xy 388.28472 -246.305832) (xy 388.28472 -246.353584)
			(xy 388.484872 -246.353584)
		)
		(stroke
			(width 0)
			(type solid)
		)
		(fill yes)
		(layer "In13.Cu")
		(net "M_H_CPU0_SA_DQS_DP<4>")
	)
	(gr_poly
		(pts
			(xy 388.484872 -245.902226) (xy 388.484872 -245.857776) (xy 388.28472 -245.857776) (xy 388.28472 -245.902226)
			(xy 388.384796 -246.002302)
		)
		(stroke
			(width 0)
			(type solid)
		)
		(fill yes)
		(layer "In13.Cu")
		(net "M_H_CPU0_SA_CB<3>")
	)
	(gr_poly
		(pts
			(xy 388.484872 -244.686074) (xy 388.384796 -244.585998) (xy 388.28472 -244.686074) (xy 388.28472 -244.730524)
			(xy 388.484872 -244.730524)
		)
		(stroke
			(width 0)
			(type solid)
		)
		(fill yes)
		(layer "In13.Cu")
		(net "M_H_CPU0_SA_CB<0>")
	)
	(gr_poly
		(pts
			(xy 388.484872 -244.282214) (xy 388.484872 -244.237764) (xy 388.28472 -244.237764) (xy 388.28472 -244.282214)
			(xy 388.384796 -244.38229)
		)
		(stroke
			(width 0)
			(type solid)
		)
		(fill yes)
		(layer "In13.Cu")
		(net "M_H_CPU0_SA_DQ<31>")
	)
	(gr_poly
		(pts
			(xy 388.484872 -243.066062) (xy 388.384796 -242.965986) (xy 388.28472 -243.066062) (xy 388.28472 -243.110512)
			(xy 388.484872 -243.110512)
		)
		(stroke
			(width 0)
			(type solid)
		)
		(fill yes)
		(layer "In13.Cu")
		(net "M_H_CPU0_SA_DQ<28>")
	)
	(gr_poly
		(pts
			(xy 388.484872 -242.662456) (xy 388.484872 -242.614704) (xy 388.28472 -242.614704) (xy 388.28472 -242.662456)
			(xy 388.384796 -242.762278)
		)
		(stroke
			(width 0)
			(type solid)
		)
		(fill yes)
		(layer "In13.Cu")
		(net "M_H_CPU0_SA_DQS_DP<8>")
	)
	(gr_poly
		(pts
			(xy 388.484872 -241.445796) (xy 388.384796 -241.345974) (xy 388.28472 -241.445796) (xy 388.28472 -241.493548)
			(xy 388.484872 -241.493548)
		)
		(stroke
			(width 0)
			(type solid)
		)
		(fill yes)
		(layer "In13.Cu")
		(net "M_H_CPU0_SA_DQS_DP<3>")
	)
	(gr_poly
		(pts
			(xy 388.484872 -241.04219) (xy 388.484872 -240.99774) (xy 388.28472 -240.99774) (xy 388.28472 -241.04219)
			(xy 388.384796 -241.142266)
		)
		(stroke
			(width 0)
			(type solid)
		)
		(fill yes)
		(layer "In13.Cu")
		(net "M_H_CPU0_SA_DQ<27>")
	)
	(gr_poly
		(pts
			(xy 388.484872 -239.826038) (xy 388.384796 -239.725962) (xy 388.28472 -239.826038) (xy 388.28472 -239.870488)
			(xy 388.484872 -239.870488)
		)
		(stroke
			(width 0)
			(type solid)
		)
		(fill yes)
		(layer "In13.Cu")
		(net "M_H_CPU0_SA_DQ<24>")
	)
	(gr_poly
		(pts
			(xy 388.484872 -239.422178) (xy 388.484872 -239.377728) (xy 388.28472 -239.377728) (xy 388.28472 -239.422178)
			(xy 388.384796 -239.522254)
		)
		(stroke
			(width 0)
			(type solid)
		)
		(fill yes)
		(layer "In13.Cu")
		(net "M_H_CPU0_SA_DQ<23>")
	)
	(gr_poly
		(pts
			(xy 388.484872 -238.206026) (xy 388.384796 -238.10595) (xy 388.28472 -238.206026) (xy 388.28472 -238.250476)
			(xy 388.484872 -238.250476)
		)
		(stroke
			(width 0)
			(type solid)
		)
		(fill yes)
		(layer "In13.Cu")
		(net "M_H_CPU0_SA_DQ<20>")
	)
	(gr_poly
		(pts
			(xy 388.484872 -237.80242) (xy 388.484872 -237.754668) (xy 388.28472 -237.754668) (xy 388.28472 -237.80242)
			(xy 388.384796 -237.902242)
		)
		(stroke
			(width 0)
			(type solid)
		)
		(fill yes)
		(layer "In13.Cu")
		(net "M_H_CPU0_SA_DQS_DP<7>")
	)
	(gr_poly
		(pts
			(xy 388.484872 -236.58576) (xy 388.384796 -236.485938) (xy 388.28472 -236.58576) (xy 388.28472 -236.633512)
			(xy 388.484872 -236.633512)
		)
		(stroke
			(width 0)
			(type solid)
		)
		(fill yes)
		(layer "In13.Cu")
		(net "M_H_CPU0_SA_DQS_DP<2>")
	)
	(gr_poly
		(pts
			(xy 388.484872 -236.182154) (xy 388.484872 -236.137704) (xy 388.28472 -236.137704) (xy 388.28472 -236.182154)
			(xy 388.384796 -236.28223)
		)
		(stroke
			(width 0)
			(type solid)
		)
		(fill yes)
		(layer "In13.Cu")
		(net "M_H_CPU0_SA_DQ<19>")
	)
	(gr_poly
		(pts
			(xy 388.484872 -234.966002) (xy 388.384796 -234.865926) (xy 388.28472 -234.966002) (xy 388.28472 -235.010452)
			(xy 388.484872 -235.010452)
		)
		(stroke
			(width 0)
			(type solid)
		)
		(fill yes)
		(layer "In13.Cu")
		(net "M_H_CPU0_SA_DQ<16>")
	)
	(gr_poly
		(pts
			(xy 388.484872 -234.562142) (xy 388.484872 -234.517692) (xy 388.28472 -234.517692) (xy 388.28472 -234.562142)
			(xy 388.384796 -234.662218)
		)
		(stroke
			(width 0)
			(type solid)
		)
		(fill yes)
		(layer "In13.Cu")
		(net "M_H_CPU0_SA_DQ<15>")
	)
	(gr_poly
		(pts
			(xy 388.484872 -233.34599) (xy 388.384796 -233.245914) (xy 388.28472 -233.34599) (xy 388.28472 -233.39044)
			(xy 388.484872 -233.39044)
		)
		(stroke
			(width 0)
			(type solid)
		)
		(fill yes)
		(layer "In13.Cu")
		(net "M_H_CPU0_SA_DQ<12>")
	)
	(gr_poly
		(pts
			(xy 388.484872 -232.942384) (xy 388.484872 -232.894632) (xy 388.28472 -232.894632) (xy 388.28472 -232.942384)
			(xy 388.384796 -233.042206)
		)
		(stroke
			(width 0)
			(type solid)
		)
		(fill yes)
		(layer "In13.Cu")
		(net "M_H_CPU0_SA_DQS_DP<6>")
	)
	(gr_poly
		(pts
			(xy 388.484872 -231.725724) (xy 388.384796 -231.625902) (xy 388.28472 -231.725724) (xy 388.28472 -231.773476)
			(xy 388.484872 -231.773476)
		)
		(stroke
			(width 0)
			(type solid)
		)
		(fill yes)
		(layer "In13.Cu")
		(net "M_H_CPU0_SA_DQS_DP<1>")
	)
	(gr_poly
		(pts
			(xy 388.484872 -231.322372) (xy 388.484872 -231.277922) (xy 388.28472 -231.277922) (xy 388.28472 -231.322372)
			(xy 388.384796 -231.422448)
		)
		(stroke
			(width 0)
			(type solid)
		)
		(fill yes)
		(layer "In13.Cu")
		(net "M_H_CPU0_SA_DQ<11>")
	)
	(gr_poly
		(pts
			(xy 388.484872 -230.105966) (xy 388.384796 -230.006144) (xy 388.28472 -230.105966) (xy 388.28472 -230.150416)
			(xy 388.484872 -230.150416)
		)
		(stroke
			(width 0)
			(type solid)
		)
		(fill yes)
		(layer "In13.Cu")
		(net "M_H_CPU0_SA_DQ<8>")
	)
	(gr_poly
		(pts
			(xy 388.484872 -229.70236) (xy 388.484872 -229.65791) (xy 388.28472 -229.65791) (xy 388.28472 -229.70236)
			(xy 388.384796 -229.802436)
		)
		(stroke
			(width 0)
			(type solid)
		)
		(fill yes)
		(layer "In13.Cu")
		(net "M_H_CPU0_SA_DQ<7>")
	)
	(gr_poly
		(pts
			(xy 388.484872 -228.486208) (xy 388.384796 -228.386132) (xy 388.28472 -228.486208) (xy 388.28472 -228.530658)
			(xy 388.484872 -228.530658)
		)
		(stroke
			(width 0)
			(type solid)
		)
		(fill yes)
		(layer "In13.Cu")
		(net "M_H_CPU0_SA_DQ<4>")
	)
	(gr_poly
		(pts
			(xy 388.484872 -228.082602) (xy 388.484872 -228.03485) (xy 388.28472 -228.03485) (xy 388.28472 -228.082602)
			(xy 388.384796 -228.182424)
		)
		(stroke
			(width 0)
			(type solid)
		)
		(fill yes)
		(layer "In13.Cu")
		(net "M_H_CPU0_SA_DQS_DP<5>")
	)
	(gr_poly
		(pts
			(xy 388.484872 -226.865942) (xy 388.384796 -226.76612) (xy 388.28472 -226.865942) (xy 388.28472 -226.913694)
			(xy 388.484872 -226.913694)
		)
		(stroke
			(width 0)
			(type solid)
		)
		(fill yes)
		(layer "In13.Cu")
		(net "M_H_CPU0_SA_DQS_DP<0>")
	)
	(gr_poly
		(pts
			(xy 388.484872 -226.462336) (xy 388.484872 -226.417886) (xy 388.28472 -226.417886) (xy 388.28472 -226.462336)
			(xy 388.384796 -226.562412)
		)
		(stroke
			(width 0)
			(type solid)
		)
		(fill yes)
		(layer "In13.Cu")
		(net "M_H_CPU0_SA_DQ<3>")
	)
	(gr_poly
		(pts
			(xy 388.541006 -225.378772) (xy 388.504176 -225.24212) (xy 388.465822 -225.219768) (xy 388.365746 -225.392996)
			(xy 388.404354 -225.415348)
		)
		(stroke
			(width 0)
			(type solid)
		)
		(fill yes)
		(layer "In13.Cu")
		(net "M_H_CPU0_SA_DQ<2>")
	)
	(gr_poly
		(pts
			(xy 388.784846 -292.91788) (xy 388.68477 -292.817804) (xy 388.584694 -292.91788) (xy 388.584694 -292.96233)
			(xy 388.784846 -292.96233)
		)
		(stroke
			(width 0)
			(type solid)
		)
		(fill yes)
		(layer "In13.Cu")
		(net "M_H_CPU0_SB_DQ<29>")
	)
	(gr_poly
		(pts
			(xy 388.784846 -292.51402) (xy 388.784846 -292.46957) (xy 388.584694 -292.46957) (xy 388.584694 -292.51402)
			(xy 388.68477 -292.614096)
		)
		(stroke
			(width 0)
			(type solid)
		)
		(fill yes)
		(layer "In13.Cu")
		(net "M_H_CPU0_SB_DQ<30>")
	)
	(gr_poly
		(pts
			(xy 388.784846 -291.297614) (xy 388.68477 -291.197792) (xy 388.584694 -291.297614) (xy 388.584694 -291.345366)
			(xy 388.784846 -291.345366)
		)
		(stroke
			(width 0)
			(type solid)
		)
		(fill yes)
		(layer "In13.Cu")
		(net "M_H_CPU0_SB_DQS_DN<8>")
	)
	(gr_poly
		(pts
			(xy 388.784846 -290.894262) (xy 388.784846 -290.84651) (xy 388.584694 -290.84651) (xy 388.584694 -290.894262)
			(xy 388.68477 -290.994084)
		)
		(stroke
			(width 0)
			(type solid)
		)
		(fill yes)
		(layer "In13.Cu")
		(net "M_H_CPU0_SB_DQS_DN<3>")
	)
	(gr_poly
		(pts
			(xy 388.784846 -289.677856) (xy 388.68477 -289.57778) (xy 388.584694 -289.677856) (xy 388.584694 -289.722306)
			(xy 388.784846 -289.722306)
		)
		(stroke
			(width 0)
			(type solid)
		)
		(fill yes)
		(layer "In13.Cu")
		(net "M_H_CPU0_SB_DQ<25>")
	)
	(gr_poly
		(pts
			(xy 388.784846 -289.273996) (xy 388.784846 -289.229546) (xy 388.584694 -289.229546) (xy 388.584694 -289.273996)
			(xy 388.68477 -289.374072)
		)
		(stroke
			(width 0)
			(type solid)
		)
		(fill yes)
		(layer "In13.Cu")
		(net "M_H_CPU0_SB_DQ<26>")
	)
	(gr_poly
		(pts
			(xy 388.784846 -288.057844) (xy 388.68477 -287.957768) (xy 388.584694 -288.057844) (xy 388.584694 -288.102294)
			(xy 388.784846 -288.102294)
		)
		(stroke
			(width 0)
			(type solid)
		)
		(fill yes)
		(layer "In13.Cu")
		(net "M_H_CPU0_SB_DQ<21>")
	)
	(gr_poly
		(pts
			(xy 388.784846 -287.654238) (xy 388.784846 -287.609788) (xy 388.584694 -287.609788) (xy 388.584694 -287.654238)
			(xy 388.68477 -287.75406)
		)
		(stroke
			(width 0)
			(type solid)
		)
		(fill yes)
		(layer "In13.Cu")
		(net "M_H_CPU0_SB_DQ<22>")
	)
	(gr_poly
		(pts
			(xy 388.784846 -286.437832) (xy 388.68477 -286.337756) (xy 388.584694 -286.437832) (xy 388.584694 -286.485584)
			(xy 388.784846 -286.485584)
		)
		(stroke
			(width 0)
			(type solid)
		)
		(fill yes)
		(layer "In13.Cu")
		(net "M_H_CPU0_SB_DQS_DN<7>")
	)
	(gr_poly
		(pts
			(xy 388.784846 -286.03448) (xy 388.784846 -285.986728) (xy 388.584694 -285.986728) (xy 388.584694 -286.03448)
			(xy 388.68477 -286.134302)
		)
		(stroke
			(width 0)
			(type solid)
		)
		(fill yes)
		(layer "In13.Cu")
		(net "M_H_CPU0_SB_DQS_DN<2>")
	)
	(gr_poly
		(pts
			(xy 388.784846 -284.818074) (xy 388.68477 -284.717998) (xy 388.584694 -284.818074) (xy 388.584694 -284.862524)
			(xy 388.784846 -284.862524)
		)
		(stroke
			(width 0)
			(type solid)
		)
		(fill yes)
		(layer "In13.Cu")
		(net "M_H_CPU0_SB_DQ<17>")
	)
	(gr_poly
		(pts
			(xy 388.784846 -284.414214) (xy 388.784846 -284.369764) (xy 388.584694 -284.369764) (xy 388.584694 -284.414214)
			(xy 388.68477 -284.51429)
		)
		(stroke
			(width 0)
			(type solid)
		)
		(fill yes)
		(layer "In13.Cu")
		(net "M_H_CPU0_SB_DQ<18>")
	)
	(gr_poly
		(pts
			(xy 388.784846 -283.198062) (xy 388.68477 -283.097986) (xy 388.584694 -283.198062) (xy 388.584694 -283.242512)
			(xy 388.784846 -283.242512)
		)
		(stroke
			(width 0)
			(type solid)
		)
		(fill yes)
		(layer "In13.Cu")
		(net "M_H_CPU0_SB_DQ<13>")
	)
	(gr_poly
		(pts
			(xy 388.784846 -282.794202) (xy 388.784846 -282.749752) (xy 388.584694 -282.749752) (xy 388.584694 -282.794202)
			(xy 388.68477 -282.894278)
		)
		(stroke
			(width 0)
			(type solid)
		)
		(fill yes)
		(layer "In13.Cu")
		(net "M_H_CPU0_SB_DQ<14>")
	)
	(gr_poly
		(pts
			(xy 388.784846 -281.577796) (xy 388.68477 -281.477974) (xy 388.584694 -281.577796) (xy 388.584694 -281.625548)
			(xy 388.784846 -281.625548)
		)
		(stroke
			(width 0)
			(type solid)
		)
		(fill yes)
		(layer "In13.Cu")
		(net "M_H_CPU0_SB_DQS_DN<6>")
	)
	(gr_poly
		(pts
			(xy 388.784846 -281.174444) (xy 388.784846 -281.126692) (xy 388.584694 -281.126692) (xy 388.584694 -281.174444)
			(xy 388.68477 -281.274266)
		)
		(stroke
			(width 0)
			(type solid)
		)
		(fill yes)
		(layer "In13.Cu")
		(net "M_H_CPU0_SB_DQS_DN<1>")
	)
	(gr_poly
		(pts
			(xy 388.784846 -279.958038) (xy 388.68477 -279.857962) (xy 388.584694 -279.958038) (xy 388.584694 -280.002488)
			(xy 388.784846 -280.002488)
		)
		(stroke
			(width 0)
			(type solid)
		)
		(fill yes)
		(layer "In13.Cu")
		(net "M_H_CPU0_SB_DQ<9>")
	)
	(gr_poly
		(pts
			(xy 388.784846 -279.554178) (xy 388.784846 -279.509728) (xy 388.584694 -279.509728) (xy 388.584694 -279.554178)
			(xy 388.68477 -279.654254)
		)
		(stroke
			(width 0)
			(type solid)
		)
		(fill yes)
		(layer "In13.Cu")
		(net "M_H_CPU0_SB_DQ<10>")
	)
	(gr_poly
		(pts
			(xy 388.784846 -278.338026) (xy 388.68477 -278.23795) (xy 388.584694 -278.338026) (xy 388.584694 -278.382476)
			(xy 388.784846 -278.382476)
		)
		(stroke
			(width 0)
			(type solid)
		)
		(fill yes)
		(layer "In13.Cu")
		(net "M_H_CPU0_SB_DQ<5>")
	)
	(gr_poly
		(pts
			(xy 388.784846 -277.934166) (xy 388.784846 -277.889716) (xy 388.584694 -277.889716) (xy 388.584694 -277.934166)
			(xy 388.68477 -278.034242)
		)
		(stroke
			(width 0)
			(type solid)
		)
		(fill yes)
		(layer "In13.Cu")
		(net "M_H_CPU0_SB_DQ<6>")
	)
	(gr_poly
		(pts
			(xy 388.784846 -276.71776) (xy 388.68477 -276.617938) (xy 388.584694 -276.71776) (xy 388.584694 -276.765512)
			(xy 388.784846 -276.765512)
		)
		(stroke
			(width 0)
			(type solid)
		)
		(fill yes)
		(layer "In13.Cu")
		(net "M_H_CPU0_SB_DQS_DN<5>")
	)
	(gr_poly
		(pts
			(xy 388.784846 -276.314408) (xy 388.784846 -276.266656) (xy 388.584694 -276.266656) (xy 388.584694 -276.314408)
			(xy 388.68477 -276.41423)
		)
		(stroke
			(width 0)
			(type solid)
		)
		(fill yes)
		(layer "In13.Cu")
		(net "M_H_CPU0_SB_DQS_DN<0>")
	)
	(gr_poly
		(pts
			(xy 388.784846 -275.098002) (xy 388.68477 -274.997926) (xy 388.584694 -275.098002) (xy 388.584694 -275.142452)
			(xy 388.784846 -275.142452)
		)
		(stroke
			(width 0)
			(type solid)
		)
		(fill yes)
		(layer "In13.Cu")
		(net "M_H_CPU0_SB_DQ<1>")
	)
	(gr_poly
		(pts
			(xy 388.784846 -274.694142) (xy 388.784846 -274.649692) (xy 388.584694 -274.649692) (xy 388.584694 -274.694142)
			(xy 388.68477 -274.794218)
		)
		(stroke
			(width 0)
			(type solid)
		)
		(fill yes)
		(layer "In13.Cu")
		(net "M_H_CPU0_SB_DQ<2>")
	)
	(gr_poly
		(pts
			(xy 388.784846 -273.47799) (xy 388.68477 -273.377914) (xy 388.584694 -273.47799) (xy 388.584694 -273.52244)
			(xy 388.784846 -273.52244)
		)
		(stroke
			(width 0)
			(type solid)
		)
		(fill yes)
		(layer "In13.Cu")
		(net "M_H_CPU0_SB_CB<1>")
	)
	(gr_poly
		(pts
			(xy 388.784846 -273.07413) (xy 388.784846 -273.02968) (xy 388.584694 -273.02968) (xy 388.584694 -273.07413)
			(xy 388.68477 -273.174206)
		)
		(stroke
			(width 0)
			(type solid)
		)
		(fill yes)
		(layer "In13.Cu")
		(net "M_H_CPU0_SB_CB<2>")
	)
	(gr_poly
		(pts
			(xy 388.784846 -271.857724) (xy 388.68477 -271.757902) (xy 388.584694 -271.857724) (xy 388.584694 -271.905476)
			(xy 388.784846 -271.905476)
		)
		(stroke
			(width 0)
			(type solid)
		)
		(fill yes)
		(layer "In13.Cu")
		(net "M_H_CPU0_SB_DQS_DN<4>")
	)
	(gr_poly
		(pts
			(xy 388.784846 -271.454372) (xy 388.784846 -271.40662) (xy 388.584694 -271.40662) (xy 388.584694 -271.454372)
			(xy 388.68477 -271.554194)
		)
		(stroke
			(width 0)
			(type solid)
		)
		(fill yes)
		(layer "In13.Cu")
		(net "M_H_CPU0_SB_DQS_DN<9>")
	)
	(gr_poly
		(pts
			(xy 388.784846 -270.237966) (xy 388.68477 -270.13789) (xy 388.584694 -270.237966) (xy 388.584694 -270.282416)
			(xy 388.784846 -270.282416)
		)
		(stroke
			(width 0)
			(type solid)
		)
		(fill yes)
		(layer "In13.Cu")
		(net "M_H_CPU0_SB_CB<5>")
	)
	(gr_poly
		(pts
			(xy 388.784846 -269.834106) (xy 388.784846 -269.789656) (xy 388.584694 -269.789656) (xy 388.584694 -269.834106)
			(xy 388.68477 -269.934182)
		)
		(stroke
			(width 0)
			(type solid)
		)
		(fill yes)
		(layer "In13.Cu")
		(net "M_H_CPU0_SB_CB<6>")
	)
	(gr_poly
		(pts
			(xy 388.784846 -266.997942) (xy 388.68477 -266.897866) (xy 388.584694 -266.997942) (xy 388.584694 -267.042392)
			(xy 388.784846 -267.042392)
		)
		(stroke
			(width 0)
			(type solid)
		)
		(fill yes)
		(layer "In13.Cu")
		(net "M_H_CPU0_SA_RSP<0>")
	)
	(gr_poly
		(pts
			(xy 388.784846 -266.594082) (xy 388.784846 -266.549632) (xy 388.584694 -266.549632) (xy 388.584694 -266.594082)
			(xy 388.68477 -266.694158)
		)
		(stroke
			(width 0)
			(type solid)
		)
		(fill yes)
		(layer "In13.Cu")
		(net "M_H_CPU0_SB_CS_N<1>")
	)
	(gr_poly
		(pts
			(xy 388.784846 -265.37793) (xy 388.68477 -265.277854) (xy 388.584694 -265.37793) (xy 388.584694 -265.42238)
			(xy 388.784846 -265.42238)
		)
		(stroke
			(width 0)
			(type solid)
		)
		(fill yes)
		(layer "In13.Cu")
		(net "M_H_CPU0_SB_PAR")
	)
	(gr_poly
		(pts
			(xy 388.784846 -263.757918) (xy 388.68477 -263.657842) (xy 388.584694 -263.757918) (xy 388.584694 -263.802368)
			(xy 388.784846 -263.802368)
		)
		(stroke
			(width 0)
			(type solid)
		)
		(fill yes)
		(layer "In13.Cu")
		(net "M_H_CPU0_SB_CA<4>")
	)
	(gr_poly
		(pts
			(xy 388.784846 -263.354058) (xy 388.784846 -263.309608) (xy 388.584694 -263.309608) (xy 388.584694 -263.354058)
			(xy 388.68477 -263.454134)
		)
		(stroke
			(width 0)
			(type solid)
		)
		(fill yes)
		(layer "In13.Cu")
		(net "M_H_CPU0_SB_CA<3>")
	)
	(gr_poly
		(pts
			(xy 388.784846 -262.137906) (xy 388.68477 -262.03783) (xy 388.584694 -262.137906) (xy 388.584694 -262.182356)
			(xy 388.784846 -262.182356)
		)
		(stroke
			(width 0)
			(type solid)
		)
		(fill yes)
		(layer "In13.Cu")
		(net "M_H_CPU0_SB_CA<0>")
	)
	(gr_poly
		(pts
			(xy 388.874 -225.505518) (xy 388.835392 -225.483166) (xy 388.698994 -225.519742) (xy 388.73557 -225.656394)
			(xy 388.773924 -225.678746)
		)
		(stroke
			(width 0)
			(type solid)
		)
		(fill yes)
		(layer "In13.Cu")
		(net "M_H_CPU0_SA_DQ<1>")
	)
	(gr_poly
		(pts
			(xy 388.874508 -223.884744) (xy 388.836154 -223.862392) (xy 388.699502 -223.898968) (xy 388.736078 -224.03562)
			(xy 388.774686 -224.057972)
		)
		(stroke
			(width 0)
			(type solid)
		)
		(fill yes)
		(layer "In13.Cu")
		(net "M_H_CPU0_SA_DQ<0>")
	)
	(gr_poly
		(pts
			(xy 388.955026 -256.432558) (xy 388.955026 -256.384806) (xy 388.754874 -256.384806) (xy 388.754874 -256.432558)
			(xy 388.85495 -256.53238)
		)
		(stroke
			(width 0)
			(type solid)
		)
		(fill yes)
		(layer "In13.Cu")
		(net "M_H_CPU0_CLK_DN<0>")
	)
	(gr_poly
		(pts
			(xy 388.955026 -255.216152) (xy 388.85495 -255.116076) (xy 388.754874 -255.216152) (xy 388.754874 -255.260602)
			(xy 388.955026 -255.260602)
		)
		(stroke
			(width 0)
			(type solid)
		)
		(fill yes)
		(layer "In13.Cu")
		(net "M_H_CPU0_SA_CA<6>")
	)
	(gr_poly
		(pts
			(xy 388.955026 -254.812292) (xy 388.955026 -254.767842) (xy 388.754874 -254.767842) (xy 388.754874 -254.812292)
			(xy 388.85495 -254.912368)
		)
		(stroke
			(width 0)
			(type solid)
		)
		(fill yes)
		(layer "In13.Cu")
		(net "M_H_CPU0_SA_CA<5>")
	)
	(gr_poly
		(pts
			(xy 388.955026 -253.59614) (xy 388.85495 -253.496064) (xy 388.754874 -253.59614) (xy 388.754874 -253.64059)
			(xy 388.955026 -253.64059)
		)
		(stroke
			(width 0)
			(type solid)
		)
		(fill yes)
		(layer "In13.Cu")
		(net "M_H_CPU0_SA_CA<2>")
	)
	(gr_poly
		(pts
			(xy 388.955026 -253.19228) (xy 388.955026 -253.14783) (xy 388.754874 -253.14783) (xy 388.754874 -253.19228)
			(xy 388.85495 -253.292356)
		)
		(stroke
			(width 0)
			(type solid)
		)
		(fill yes)
		(layer "In13.Cu")
		(net "M_H_CPU0_SA_CA<1>")
	)
	(gr_poly
		(pts
			(xy 388.955026 -251.976128) (xy 388.85495 -251.876052) (xy 388.754874 -251.976128) (xy 388.754874 -252.020578)
			(xy 388.955026 -252.020578)
		)
		(stroke
			(width 0)
			(type solid)
		)
		(fill yes)
		(layer "In13.Cu")
		(net "M_H_CPU0_SA_CS_N<1>")
	)
	(gr_poly
		(pts
			(xy 388.955026 -250.356116) (xy 388.85495 -250.25604) (xy 388.754874 -250.356116) (xy 388.754874 -250.400566)
			(xy 388.955026 -250.400566)
		)
		(stroke
			(width 0)
			(type solid)
		)
		(fill yes)
		(layer "In13.Cu")
		(net "M_H_CPU0_ALERT_R_N")
	)
	(gr_poly
		(pts
			(xy 388.955026 -248.736104) (xy 388.85495 -248.636028) (xy 388.754874 -248.736104) (xy 388.754874 -248.780554)
			(xy 388.955026 -248.780554)
		)
		(stroke
			(width 0)
			(type solid)
		)
		(fill yes)
		(layer "In13.Cu")
		(net "M_H_CPU0_SA_CB<5>")
	)
	(gr_poly
		(pts
			(xy 388.955026 -248.332244) (xy 388.955026 -248.287794) (xy 388.754874 -248.287794) (xy 388.754874 -248.332244)
			(xy 388.85495 -248.43232)
		)
		(stroke
			(width 0)
			(type solid)
		)
		(fill yes)
		(layer "In13.Cu")
		(net "M_H_CPU0_SA_CB<6>")
	)
	(gr_poly
		(pts
			(xy 388.955026 -247.115838) (xy 388.85495 -247.016016) (xy 388.754874 -247.115838) (xy 388.754874 -247.16359)
			(xy 388.955026 -247.16359)
		)
		(stroke
			(width 0)
			(type solid)
		)
		(fill yes)
		(layer "In13.Cu")
		(net "M_H_CPU0_SA_DQS_DN<9>")
	)
	(gr_poly
		(pts
			(xy 388.955026 -246.712486) (xy 388.955026 -246.664734) (xy 388.754874 -246.664734) (xy 388.754874 -246.712486)
			(xy 388.85495 -246.812308)
		)
		(stroke
			(width 0)
			(type solid)
		)
		(fill yes)
		(layer "In13.Cu")
		(net "M_H_CPU0_SA_DQS_DN<4>")
	)
	(gr_poly
		(pts
			(xy 388.955026 -245.49608) (xy 388.85495 -245.396004) (xy 388.754874 -245.49608) (xy 388.754874 -245.54053)
			(xy 388.955026 -245.54053)
		)
		(stroke
			(width 0)
			(type solid)
		)
		(fill yes)
		(layer "In13.Cu")
		(net "M_H_CPU0_SA_CB<1>")
	)
	(gr_poly
		(pts
			(xy 388.955026 -245.09222) (xy 388.955026 -245.04777) (xy 388.754874 -245.04777) (xy 388.754874 -245.09222)
			(xy 388.85495 -245.192296)
		)
		(stroke
			(width 0)
			(type solid)
		)
		(fill yes)
		(layer "In13.Cu")
		(net "M_H_CPU0_SA_CB<2>")
	)
	(gr_poly
		(pts
			(xy 388.955026 -243.876068) (xy 388.85495 -243.775992) (xy 388.754874 -243.876068) (xy 388.754874 -243.920518)
			(xy 388.955026 -243.920518)
		)
		(stroke
			(width 0)
			(type solid)
		)
		(fill yes)
		(layer "In13.Cu")
		(net "M_H_CPU0_SA_DQ<29>")
	)
	(gr_poly
		(pts
			(xy 388.955026 -243.472208) (xy 388.955026 -243.427758) (xy 388.754874 -243.427758) (xy 388.754874 -243.472208)
			(xy 388.85495 -243.572284)
		)
		(stroke
			(width 0)
			(type solid)
		)
		(fill yes)
		(layer "In13.Cu")
		(net "M_H_CPU0_SA_DQ<30>")
	)
	(gr_poly
		(pts
			(xy 388.955026 -242.255802) (xy 388.85495 -242.15598) (xy 388.754874 -242.255802) (xy 388.754874 -242.303554)
			(xy 388.955026 -242.303554)
		)
		(stroke
			(width 0)
			(type solid)
		)
		(fill yes)
		(layer "In13.Cu")
		(net "M_H_CPU0_SA_DQS_DN<8>")
	)
	(gr_poly
		(pts
			(xy 388.955026 -241.85245) (xy 388.955026 -241.804698) (xy 388.754874 -241.804698) (xy 388.754874 -241.85245)
			(xy 388.85495 -241.952272)
		)
		(stroke
			(width 0)
			(type solid)
		)
		(fill yes)
		(layer "In13.Cu")
		(net "M_H_CPU0_SA_DQS_DN<3>")
	)
	(gr_poly
		(pts
			(xy 388.955026 -240.636044) (xy 388.85495 -240.535968) (xy 388.754874 -240.636044) (xy 388.754874 -240.680494)
			(xy 388.955026 -240.680494)
		)
		(stroke
			(width 0)
			(type solid)
		)
		(fill yes)
		(layer "In13.Cu")
		(net "M_H_CPU0_SA_DQ<25>")
	)
	(gr_poly
		(pts
			(xy 388.955026 -240.232184) (xy 388.955026 -240.187734) (xy 388.754874 -240.187734) (xy 388.754874 -240.232184)
			(xy 388.85495 -240.33226)
		)
		(stroke
			(width 0)
			(type solid)
		)
		(fill yes)
		(layer "In13.Cu")
		(net "M_H_CPU0_SA_DQ<26>")
	)
	(gr_poly
		(pts
			(xy 388.955026 -239.016032) (xy 388.85495 -238.915956) (xy 388.754874 -239.016032) (xy 388.754874 -239.060482)
			(xy 388.955026 -239.060482)
		)
		(stroke
			(width 0)
			(type solid)
		)
		(fill yes)
		(layer "In13.Cu")
		(net "M_H_CPU0_SA_DQ<21>")
	)
	(gr_poly
		(pts
			(xy 388.955026 -238.612172) (xy 388.955026 -238.567722) (xy 388.754874 -238.567722) (xy 388.754874 -238.612172)
			(xy 388.85495 -238.712248)
		)
		(stroke
			(width 0)
			(type solid)
		)
		(fill yes)
		(layer "In13.Cu")
		(net "M_H_CPU0_SA_DQ<22>")
	)
	(gr_poly
		(pts
			(xy 388.955026 -237.395766) (xy 388.85495 -237.295944) (xy 388.754874 -237.395766) (xy 388.754874 -237.443518)
			(xy 388.955026 -237.443518)
		)
		(stroke
			(width 0)
			(type solid)
		)
		(fill yes)
		(layer "In13.Cu")
		(net "M_H_CPU0_SA_DQS_DN<7>")
	)
	(gr_poly
		(pts
			(xy 388.955026 -236.992414) (xy 388.955026 -236.944662) (xy 388.754874 -236.944662) (xy 388.754874 -236.992414)
			(xy 388.85495 -237.092236)
		)
		(stroke
			(width 0)
			(type solid)
		)
		(fill yes)
		(layer "In13.Cu")
		(net "M_H_CPU0_SA_DQS_DN<2>")
	)
	(gr_poly
		(pts
			(xy 388.955026 -235.776008) (xy 388.85495 -235.675932) (xy 388.754874 -235.776008) (xy 388.754874 -235.820458)
			(xy 388.955026 -235.820458)
		)
		(stroke
			(width 0)
			(type solid)
		)
		(fill yes)
		(layer "In13.Cu")
		(net "M_H_CPU0_SA_DQ<17>")
	)
	(gr_poly
		(pts
			(xy 388.955026 -235.372148) (xy 388.955026 -235.327698) (xy 388.754874 -235.327698) (xy 388.754874 -235.372148)
			(xy 388.85495 -235.472224)
		)
		(stroke
			(width 0)
			(type solid)
		)
		(fill yes)
		(layer "In13.Cu")
		(net "M_H_CPU0_SA_DQ<18>")
	)
	(gr_poly
		(pts
			(xy 388.955026 -234.155996) (xy 388.85495 -234.05592) (xy 388.754874 -234.155996) (xy 388.754874 -234.200446)
			(xy 388.955026 -234.200446)
		)
		(stroke
			(width 0)
			(type solid)
		)
		(fill yes)
		(layer "In13.Cu")
		(net "M_H_CPU0_SA_DQ<13>")
	)
	(gr_poly
		(pts
			(xy 388.955026 -233.752136) (xy 388.955026 -233.707686) (xy 388.754874 -233.707686) (xy 388.754874 -233.752136)
			(xy 388.85495 -233.852212)
		)
		(stroke
			(width 0)
			(type solid)
		)
		(fill yes)
		(layer "In13.Cu")
		(net "M_H_CPU0_SA_DQ<14>")
	)
	(gr_poly
		(pts
			(xy 388.955026 -232.53573) (xy 388.85495 -232.435908) (xy 388.754874 -232.53573) (xy 388.754874 -232.583482)
			(xy 388.955026 -232.583482)
		)
		(stroke
			(width 0)
			(type solid)
		)
		(fill yes)
		(layer "In13.Cu")
		(net "M_H_CPU0_SA_DQS_DN<6>")
	)
	(gr_poly
		(pts
			(xy 388.955026 -232.132378) (xy 388.955026 -232.084626) (xy 388.754874 -232.084626) (xy 388.754874 -232.132378)
			(xy 388.85495 -232.2322)
		)
		(stroke
			(width 0)
			(type solid)
		)
		(fill yes)
		(layer "In13.Cu")
		(net "M_H_CPU0_SA_DQS_DN<1>")
	)
	(gr_poly
		(pts
			(xy 388.955026 -230.915972) (xy 388.85495 -230.815896) (xy 388.754874 -230.915972) (xy 388.754874 -230.960422)
			(xy 388.955026 -230.960422)
		)
		(stroke
			(width 0)
			(type solid)
		)
		(fill yes)
		(layer "In13.Cu")
		(net "M_H_CPU0_SA_DQ<9>")
	)
	(gr_poly
		(pts
			(xy 388.955026 -230.512366) (xy 388.955026 -230.467916) (xy 388.754874 -230.467916) (xy 388.754874 -230.512366)
			(xy 388.85495 -230.612188)
		)
		(stroke
			(width 0)
			(type solid)
		)
		(fill yes)
		(layer "In13.Cu")
		(net "M_H_CPU0_SA_DQ<10>")
	)
	(gr_poly
		(pts
			(xy 388.955026 -229.29596) (xy 388.85495 -229.195884) (xy 388.754874 -229.29596) (xy 388.754874 -229.34041)
			(xy 388.955026 -229.34041)
		)
		(stroke
			(width 0)
			(type solid)
		)
		(fill yes)
		(layer "In13.Cu")
		(net "M_H_CPU0_SA_DQ<5>")
	)
	(gr_poly
		(pts
			(xy 388.955026 -228.892354) (xy 388.955026 -228.847904) (xy 388.754874 -228.847904) (xy 388.754874 -228.892354)
			(xy 388.85495 -228.99243)
		)
		(stroke
			(width 0)
			(type solid)
		)
		(fill yes)
		(layer "In13.Cu")
		(net "M_H_CPU0_SA_DQ<6>")
	)
	(gr_poly
		(pts
			(xy 388.955026 -227.675948) (xy 388.85495 -227.576126) (xy 388.754874 -227.675948) (xy 388.754874 -227.7237)
			(xy 388.955026 -227.7237)
		)
		(stroke
			(width 0)
			(type solid)
		)
		(fill yes)
		(layer "In13.Cu")
		(net "M_H_CPU0_SA_DQS_DN<5>")
	)
	(gr_poly
		(pts
			(xy 388.955026 -227.272596) (xy 388.955026 -227.224844) (xy 388.754874 -227.224844) (xy 388.754874 -227.272596)
			(xy 388.85495 -227.372418)
		)
		(stroke
			(width 0)
			(type solid)
		)
		(fill yes)
		(layer "In13.Cu")
		(net "M_H_CPU0_SA_DQS_DN<0>")
	)
	(gr_poly
		(pts
			(xy 389.010144 -224.570036) (xy 388.973568 -224.433384) (xy 388.93496 -224.411286) (xy 388.834884 -224.584514)
			(xy 388.873492 -224.606612)
		)
		(stroke
			(width 0)
			(type solid)
		)
		(fill yes)
		(layer "In13.Cu")
		(net "M_H_CPU0_SA_DQ<2>")
	)
	(gr_poly
		(pts
			(xy 389.010906 -226.188778) (xy 388.974076 -226.052126) (xy 388.935722 -226.029774) (xy 388.835646 -226.203002)
			(xy 388.874254 -226.225354)
		)
		(stroke
			(width 0)
			(type solid)
		)
		(fill yes)
		(layer "In13.Cu")
		(net "M_H_CPU0_SA_DQ<3>")
	)
	(gr_poly
		(pts
			(xy 389.255 -293.324026) (xy 389.255 -293.279576) (xy 389.054848 -293.279576) (xy 389.054848 -293.324026)
			(xy 389.154924 -293.424102)
		)
		(stroke
			(width 0)
			(type solid)
		)
		(fill yes)
		(layer "In13.Cu")
		(net "M_H_CPU0_SB_DQ<31>")
	)
	(gr_poly
		(pts
			(xy 389.255 -292.107874) (xy 389.154924 -292.007798) (xy 389.054848 -292.107874) (xy 389.054848 -292.152324)
			(xy 389.255 -292.152324)
		)
		(stroke
			(width 0)
			(type solid)
		)
		(fill yes)
		(layer "In13.Cu")
		(net "M_H_CPU0_SB_DQ<28>")
	)
	(gr_poly
		(pts
			(xy 389.255 -291.704268) (xy 389.255 -291.656516) (xy 389.054848 -291.656516) (xy 389.054848 -291.704268)
			(xy 389.154924 -291.80409)
		)
		(stroke
			(width 0)
			(type solid)
		)
		(fill yes)
		(layer "In13.Cu")
		(net "M_H_CPU0_SB_DQS_DP<8>")
	)
	(gr_poly
		(pts
			(xy 389.255 -290.487608) (xy 389.154924 -290.387786) (xy 389.054848 -290.487608) (xy 389.054848 -290.53536)
			(xy 389.255 -290.53536)
		)
		(stroke
			(width 0)
			(type solid)
		)
		(fill yes)
		(layer "In13.Cu")
		(net "M_H_CPU0_SB_DQS_DP<3>")
	)
	(gr_poly
		(pts
			(xy 389.255 -290.084002) (xy 389.255 -290.039552) (xy 389.054848 -290.039552) (xy 389.054848 -290.084002)
			(xy 389.154924 -290.184078)
		)
		(stroke
			(width 0)
			(type solid)
		)
		(fill yes)
		(layer "In13.Cu")
		(net "M_H_CPU0_SB_DQ<27>")
	)
	(gr_poly
		(pts
			(xy 389.255 -288.86785) (xy 389.154924 -288.767774) (xy 389.054848 -288.86785) (xy 389.054848 -288.9123)
			(xy 389.255 -288.9123)
		)
		(stroke
			(width 0)
			(type solid)
		)
		(fill yes)
		(layer "In13.Cu")
		(net "M_H_CPU0_SB_DQ<24>")
	)
	(gr_poly
		(pts
			(xy 389.255 -288.464244) (xy 389.255 -288.419794) (xy 389.054848 -288.419794) (xy 389.054848 -288.464244)
			(xy 389.154924 -288.56432)
		)
		(stroke
			(width 0)
			(type solid)
		)
		(fill yes)
		(layer "In13.Cu")
		(net "M_H_CPU0_SB_DQ<23>")
	)
	(gr_poly
		(pts
			(xy 389.255 -287.247838) (xy 389.154924 -287.148016) (xy 389.054848 -287.247838) (xy 389.054848 -287.292288)
			(xy 389.255 -287.292288)
		)
		(stroke
			(width 0)
			(type solid)
		)
		(fill yes)
		(layer "In13.Cu")
		(net "M_H_CPU0_SB_DQ<20>")
	)
	(gr_poly
		(pts
			(xy 389.255 -286.844232) (xy 389.255 -286.79648) (xy 389.054848 -286.79648) (xy 389.054848 -286.844232)
			(xy 389.154924 -286.944308)
		)
		(stroke
			(width 0)
			(type solid)
		)
		(fill yes)
		(layer "In13.Cu")
		(net "M_H_CPU0_SB_DQS_DP<7>")
	)
	(gr_poly
		(pts
			(xy 389.255 -285.627826) (xy 389.154924 -285.528004) (xy 389.054848 -285.627826) (xy 389.054848 -285.675578)
			(xy 389.255 -285.675578)
		)
		(stroke
			(width 0)
			(type solid)
		)
		(fill yes)
		(layer "In13.Cu")
		(net "M_H_CPU0_SB_DQS_DP<2>")
	)
	(gr_poly
		(pts
			(xy 389.255 -285.22422) (xy 389.255 -285.17977) (xy 389.054848 -285.17977) (xy 389.054848 -285.22422)
			(xy 389.154924 -285.324296)
		)
		(stroke
			(width 0)
			(type solid)
		)
		(fill yes)
		(layer "In13.Cu")
		(net "M_H_CPU0_SB_DQ<19>")
	)
	(gr_poly
		(pts
			(xy 389.255 -284.008068) (xy 389.154924 -283.907992) (xy 389.054848 -284.008068) (xy 389.054848 -284.052518)
			(xy 389.255 -284.052518)
		)
		(stroke
			(width 0)
			(type solid)
		)
		(fill yes)
		(layer "In13.Cu")
		(net "M_H_CPU0_SB_DQ<16>")
	)
	(gr_poly
		(pts
			(xy 389.255 -283.604208) (xy 389.255 -283.559758) (xy 389.054848 -283.559758) (xy 389.054848 -283.604208)
			(xy 389.154924 -283.704284)
		)
		(stroke
			(width 0)
			(type solid)
		)
		(fill yes)
		(layer "In13.Cu")
		(net "M_H_CPU0_SB_DQ<15>")
	)
	(gr_poly
		(pts
			(xy 389.255 -282.388056) (xy 389.154924 -282.28798) (xy 389.054848 -282.388056) (xy 389.054848 -282.432506)
			(xy 389.255 -282.432506)
		)
		(stroke
			(width 0)
			(type solid)
		)
		(fill yes)
		(layer "In13.Cu")
		(net "M_H_CPU0_SB_DQ<12>")
	)
	(gr_poly
		(pts
			(xy 389.255 -281.98445) (xy 389.255 -281.936698) (xy 389.054848 -281.936698) (xy 389.054848 -281.98445)
			(xy 389.154924 -282.084272)
		)
		(stroke
			(width 0)
			(type solid)
		)
		(fill yes)
		(layer "In13.Cu")
		(net "M_H_CPU0_SB_DQS_DP<6>")
	)
	(gr_poly
		(pts
			(xy 389.255 -280.76779) (xy 389.154924 -280.667968) (xy 389.054848 -280.76779) (xy 389.054848 -280.815542)
			(xy 389.255 -280.815542)
		)
		(stroke
			(width 0)
			(type solid)
		)
		(fill yes)
		(layer "In13.Cu")
		(net "M_H_CPU0_SB_DQS_DP<1>")
	)
	(gr_poly
		(pts
			(xy 389.255 -280.364184) (xy 389.255 -280.319734) (xy 389.054848 -280.319734) (xy 389.054848 -280.364184)
			(xy 389.154924 -280.46426)
		)
		(stroke
			(width 0)
			(type solid)
		)
		(fill yes)
		(layer "In13.Cu")
		(net "M_H_CPU0_SB_DQ<11>")
	)
	(gr_poly
		(pts
			(xy 389.255 -279.148032) (xy 389.154924 -279.047956) (xy 389.054848 -279.148032) (xy 389.054848 -279.192482)
			(xy 389.255 -279.192482)
		)
		(stroke
			(width 0)
			(type solid)
		)
		(fill yes)
		(layer "In13.Cu")
		(net "M_H_CPU0_SB_DQ<8>")
	)
	(gr_poly
		(pts
			(xy 389.255 -278.744172) (xy 389.255 -278.699722) (xy 389.054848 -278.699722) (xy 389.054848 -278.744172)
			(xy 389.154924 -278.844248)
		)
		(stroke
			(width 0)
			(type solid)
		)
		(fill yes)
		(layer "In13.Cu")
		(net "M_H_CPU0_SB_DQ<7>")
	)
	(gr_poly
		(pts
			(xy 389.255 -277.52802) (xy 389.154924 -277.427944) (xy 389.054848 -277.52802) (xy 389.054848 -277.57247)
			(xy 389.255 -277.57247)
		)
		(stroke
			(width 0)
			(type solid)
		)
		(fill yes)
		(layer "In13.Cu")
		(net "M_H_CPU0_SB_DQ<4>")
	)
	(gr_poly
		(pts
			(xy 389.255 -277.124414) (xy 389.255 -277.076662) (xy 389.054848 -277.076662) (xy 389.054848 -277.124414)
			(xy 389.154924 -277.224236)
		)
		(stroke
			(width 0)
			(type solid)
		)
		(fill yes)
		(layer "In13.Cu")
		(net "M_H_CPU0_SB_DQS_DP<5>")
	)
	(gr_poly
		(pts
			(xy 389.255 -275.907754) (xy 389.154924 -275.807932) (xy 389.054848 -275.907754) (xy 389.054848 -275.955506)
			(xy 389.255 -275.955506)
		)
		(stroke
			(width 0)
			(type solid)
		)
		(fill yes)
		(layer "In13.Cu")
		(net "M_H_CPU0_SB_DQS_DP<0>")
	)
	(gr_poly
		(pts
			(xy 389.255 -275.504148) (xy 389.255 -275.459698) (xy 389.054848 -275.459698) (xy 389.054848 -275.504148)
			(xy 389.154924 -275.604224)
		)
		(stroke
			(width 0)
			(type solid)
		)
		(fill yes)
		(layer "In13.Cu")
		(net "M_H_CPU0_SB_DQ<3>")
	)
	(gr_poly
		(pts
			(xy 389.255 -274.287996) (xy 389.154924 -274.18792) (xy 389.054848 -274.287996) (xy 389.054848 -274.332446)
			(xy 389.255 -274.332446)
		)
		(stroke
			(width 0)
			(type solid)
		)
		(fill yes)
		(layer "In13.Cu")
		(net "M_H_CPU0_SB_DQ<0>")
	)
	(gr_poly
		(pts
			(xy 389.255 -273.884136) (xy 389.255 -273.839686) (xy 389.054848 -273.839686) (xy 389.054848 -273.884136)
			(xy 389.154924 -273.984212)
		)
		(stroke
			(width 0)
			(type solid)
		)
		(fill yes)
		(layer "In13.Cu")
		(net "M_H_CPU0_SB_CB<3>")
	)
	(gr_poly
		(pts
			(xy 389.255 -272.667984) (xy 389.154924 -272.567908) (xy 389.054848 -272.667984) (xy 389.054848 -272.712434)
			(xy 389.255 -272.712434)
		)
		(stroke
			(width 0)
			(type solid)
		)
		(fill yes)
		(layer "In13.Cu")
		(net "M_H_CPU0_SB_CB<0>")
	)
	(gr_poly
		(pts
			(xy 389.255 -272.264378) (xy 389.255 -272.216626) (xy 389.054848 -272.216626) (xy 389.054848 -272.264378)
			(xy 389.154924 -272.3642)
		)
		(stroke
			(width 0)
			(type solid)
		)
		(fill yes)
		(layer "In13.Cu")
		(net "M_H_CPU0_SB_DQS_DP<4>")
	)
	(gr_poly
		(pts
			(xy 389.255 -271.047718) (xy 389.154924 -270.947896) (xy 389.054848 -271.047718) (xy 389.054848 -271.09547)
			(xy 389.255 -271.09547)
		)
		(stroke
			(width 0)
			(type solid)
		)
		(fill yes)
		(layer "In13.Cu")
		(net "M_H_CPU0_SB_DQS_DP<9>")
	)
	(gr_poly
		(pts
			(xy 389.255 -270.644112) (xy 389.255 -270.599662) (xy 389.054848 -270.599662) (xy 389.054848 -270.644112)
			(xy 389.154924 -270.744188)
		)
		(stroke
			(width 0)
			(type solid)
		)
		(fill yes)
		(layer "In13.Cu")
		(net "M_H_CPU0_SB_CB<7>")
	)
	(gr_poly
		(pts
			(xy 389.255 -269.42796) (xy 389.154924 -269.327884) (xy 389.054848 -269.42796) (xy 389.054848 -269.47241)
			(xy 389.255 -269.47241)
		)
		(stroke
			(width 0)
			(type solid)
		)
		(fill yes)
		(layer "In13.Cu")
		(net "M_H_CPU0_SB_CB<4>")
	)
	(gr_poly
		(pts
			(xy 389.255 -267.807948) (xy 389.154924 -267.707872) (xy 389.054848 -267.807948) (xy 389.054848 -267.852398)
			(xy 389.255 -267.852398)
		)
		(stroke
			(width 0)
			(type solid)
		)
		(fill yes)
		(layer "In13.Cu")
		(net "M_H_CPU0_SB_RSP<0>")
	)
	(gr_poly
		(pts
			(xy 389.255 -265.784076) (xy 389.255 -265.739626) (xy 389.054848 -265.739626) (xy 389.054848 -265.784076)
			(xy 389.154924 -265.884152)
		)
		(stroke
			(width 0)
			(type solid)
		)
		(fill yes)
		(layer "In13.Cu")
		(net "M_H_CPU0_SB_CS_N<0>")
	)
	(gr_poly
		(pts
			(xy 389.255 -264.567924) (xy 389.154924 -264.467848) (xy 389.054848 -264.567924) (xy 389.054848 -264.612374)
			(xy 389.255 -264.612374)
		)
		(stroke
			(width 0)
			(type solid)
		)
		(fill yes)
		(layer "In13.Cu")
		(net "M_H_CPU0_SB_CA<6>")
	)
	(gr_poly
		(pts
			(xy 389.255 -264.164064) (xy 389.255 -264.119614) (xy 389.054848 -264.119614) (xy 389.054848 -264.164064)
			(xy 389.154924 -264.26414)
		)
		(stroke
			(width 0)
			(type solid)
		)
		(fill yes)
		(layer "In13.Cu")
		(net "M_H_CPU0_SB_CA<5>")
	)
	(gr_poly
		(pts
			(xy 389.255 -262.947912) (xy 389.154924 -262.847836) (xy 389.054848 -262.947912) (xy 389.054848 -262.992362)
			(xy 389.255 -262.992362)
		)
		(stroke
			(width 0)
			(type solid)
		)
		(fill yes)
		(layer "In13.Cu")
		(net "M_H_CPU0_SB_CA<2>")
	)
	(gr_poly
		(pts
			(xy 389.255 -262.544052) (xy 389.255 -262.499602) (xy 389.054848 -262.499602) (xy 389.054848 -262.544052)
			(xy 389.154924 -262.644128)
		)
		(stroke
			(width 0)
			(type solid)
		)
		(fill yes)
		(layer "In13.Cu")
		(net "M_H_CPU0_SB_CA<1>")
	)
	(gr_poly
		(pts
			(xy 389.344662 -223.074738) (xy 389.306308 -223.052386) (xy 389.169656 -223.088962) (xy 389.206232 -223.225614)
			(xy 389.24484 -223.247966)
		)
		(stroke
			(width 0)
			(type solid)
		)
		(fill yes)
		(layer "In13.Cu")
		(net "M_H_CPU0_SA_DQ<0>")
	)
	(gr_poly
		(pts
			(xy 389.344916 -224.693988) (xy 389.306308 -224.67189) (xy 389.169656 -224.708466) (xy 389.206232 -224.845118)
			(xy 389.24484 -224.867216)
		)
		(stroke
			(width 0)
			(type solid)
		)
		(fill yes)
		(layer "In13.Cu")
		(net "M_H_CPU0_SA_DQ<1>")
	)
	(gr_poly
		(pts
			(xy 389.347964 -226.315016) (xy 389.306562 -226.29114) (xy 389.16991 -226.32797) (xy 389.20674 -226.464368)
			(xy 389.247888 -226.488244)
		)
		(stroke
			(width 0)
			(type solid)
		)
		(fill yes)
		(layer "In13.Cu")
		(net "M_H_CPU0_SA_DQS_DP<0>")
	)
	(gr_poly
		(pts
			(xy 389.424926 -256.025904) (xy 389.32485 -255.926082) (xy 389.224774 -256.025904) (xy 389.224774 -256.073656)
			(xy 389.424926 -256.073656)
		)
		(stroke
			(width 0)
			(type solid)
		)
		(fill yes)
		(layer "In13.Cu")
		(net "M_H_CPU0_CLK_DP<0>")
	)
	(gr_poly
		(pts
			(xy 389.424926 -255.622298) (xy 389.424926 -255.577848) (xy 389.224774 -255.577848) (xy 389.224774 -255.622298)
			(xy 389.32485 -255.722374)
		)
		(stroke
			(width 0)
			(type solid)
		)
		(fill yes)
		(layer "In13.Cu")
		(net "M_H_CPU0_SA_PAR")
	)
	(gr_poly
		(pts
			(xy 389.424926 -254.406146) (xy 389.32485 -254.30607) (xy 389.224774 -254.406146) (xy 389.224774 -254.450596)
			(xy 389.424926 -254.450596)
		)
		(stroke
			(width 0)
			(type solid)
		)
		(fill yes)
		(layer "In13.Cu")
		(net "M_H_CPU0_SA_CA<4>")
	)
	(gr_poly
		(pts
			(xy 389.424926 -254.002286) (xy 389.424926 -253.957836) (xy 389.224774 -253.957836) (xy 389.224774 -254.002286)
			(xy 389.32485 -254.102362)
		)
		(stroke
			(width 0)
			(type solid)
		)
		(fill yes)
		(layer "In13.Cu")
		(net "M_H_CPU0_SA_CA<3>")
	)
	(gr_poly
		(pts
			(xy 389.424926 -252.786134) (xy 389.32485 -252.686058) (xy 389.224774 -252.786134) (xy 389.224774 -252.830584)
			(xy 389.424926 -252.830584)
		)
		(stroke
			(width 0)
			(type solid)
		)
		(fill yes)
		(layer "In13.Cu")
		(net "M_H_CPU0_SA_CA<0>")
	)
	(gr_poly
		(pts
			(xy 389.424926 -251.166122) (xy 389.32485 -251.066046) (xy 389.224774 -251.166122) (xy 389.224774 -251.210572)
			(xy 389.424926 -251.210572)
		)
		(stroke
			(width 0)
			(type solid)
		)
		(fill yes)
		(layer "In13.Cu")
		(net "M_H_CPU0_SA_CS_N<0>")
	)
	(gr_poly
		(pts
			(xy 389.424926 -250.762262) (xy 389.424926 -250.717812) (xy 389.224774 -250.717812) (xy 389.224774 -250.762262)
			(xy 389.32485 -250.862338)
		)
		(stroke
			(width 0)
			(type solid)
		)
		(fill yes)
		(layer "In13.Cu")
		(net "M_H_CPU0_RESET_N")
	)
	(gr_poly
		(pts
			(xy 389.424926 -249.14225) (xy 389.424926 -249.0978) (xy 389.224774 -249.0978) (xy 389.224774 -249.14225)
			(xy 389.32485 -249.242326)
		)
		(stroke
			(width 0)
			(type solid)
		)
		(fill yes)
		(layer "In13.Cu")
		(net "M_H_CPU0_SA_CB<7>")
	)
	(gr_poly
		(pts
			(xy 389.424926 -247.926098) (xy 389.32485 -247.826022) (xy 389.224774 -247.926098) (xy 389.224774 -247.970548)
			(xy 389.424926 -247.970548)
		)
		(stroke
			(width 0)
			(type solid)
		)
		(fill yes)
		(layer "In13.Cu")
		(net "M_H_CPU0_SA_CB<4>")
	)
	(gr_poly
		(pts
			(xy 389.424926 -247.522492) (xy 389.424926 -247.47474) (xy 389.224774 -247.47474) (xy 389.224774 -247.522492)
			(xy 389.32485 -247.622314)
		)
		(stroke
			(width 0)
			(type solid)
		)
		(fill yes)
		(layer "In13.Cu")
		(net "M_H_CPU0_SA_DQS_DP<9>")
	)
	(gr_poly
		(pts
			(xy 389.424926 -246.305832) (xy 389.32485 -246.20601) (xy 389.224774 -246.305832) (xy 389.224774 -246.353584)
			(xy 389.424926 -246.353584)
		)
		(stroke
			(width 0)
			(type solid)
		)
		(fill yes)
		(layer "In13.Cu")
		(net "M_H_CPU0_SA_DQS_DP<4>")
	)
	(gr_poly
		(pts
			(xy 389.424926 -245.902226) (xy 389.424926 -245.857776) (xy 389.224774 -245.857776) (xy 389.224774 -245.902226)
			(xy 389.32485 -246.002302)
		)
		(stroke
			(width 0)
			(type solid)
		)
		(fill yes)
		(layer "In13.Cu")
		(net "M_H_CPU0_SA_CB<3>")
	)
	(gr_poly
		(pts
			(xy 389.424926 -244.686074) (xy 389.32485 -244.585998) (xy 389.224774 -244.686074) (xy 389.224774 -244.730524)
			(xy 389.424926 -244.730524)
		)
		(stroke
			(width 0)
			(type solid)
		)
		(fill yes)
		(layer "In13.Cu")
		(net "M_H_CPU0_SA_CB<0>")
	)
	(gr_poly
		(pts
			(xy 389.424926 -244.282214) (xy 389.424926 -244.237764) (xy 389.224774 -244.237764) (xy 389.224774 -244.282214)
			(xy 389.32485 -244.38229)
		)
		(stroke
			(width 0)
			(type solid)
		)
		(fill yes)
		(layer "In13.Cu")
		(net "M_H_CPU0_SA_DQ<31>")
	)
	(gr_poly
		(pts
			(xy 389.424926 -243.066062) (xy 389.32485 -242.965986) (xy 389.224774 -243.066062) (xy 389.224774 -243.110512)
			(xy 389.424926 -243.110512)
		)
		(stroke
			(width 0)
			(type solid)
		)
		(fill yes)
		(layer "In13.Cu")
		(net "M_H_CPU0_SA_DQ<28>")
	)
	(gr_poly
		(pts
			(xy 389.424926 -242.662456) (xy 389.424926 -242.614704) (xy 389.224774 -242.614704) (xy 389.224774 -242.662456)
			(xy 389.32485 -242.762278)
		)
		(stroke
			(width 0)
			(type solid)
		)
		(fill yes)
		(layer "In13.Cu")
		(net "M_H_CPU0_SA_DQS_DP<8>")
	)
	(gr_poly
		(pts
			(xy 389.424926 -241.445796) (xy 389.32485 -241.345974) (xy 389.224774 -241.445796) (xy 389.224774 -241.493548)
			(xy 389.424926 -241.493548)
		)
		(stroke
			(width 0)
			(type solid)
		)
		(fill yes)
		(layer "In13.Cu")
		(net "M_H_CPU0_SA_DQS_DP<3>")
	)
	(gr_poly
		(pts
			(xy 389.424926 -241.04219) (xy 389.424926 -240.99774) (xy 389.224774 -240.99774) (xy 389.224774 -241.04219)
			(xy 389.32485 -241.142266)
		)
		(stroke
			(width 0)
			(type solid)
		)
		(fill yes)
		(layer "In13.Cu")
		(net "M_H_CPU0_SA_DQ<27>")
	)
	(gr_poly
		(pts
			(xy 389.424926 -239.826038) (xy 389.32485 -239.725962) (xy 389.224774 -239.826038) (xy 389.224774 -239.870488)
			(xy 389.424926 -239.870488)
		)
		(stroke
			(width 0)
			(type solid)
		)
		(fill yes)
		(layer "In13.Cu")
		(net "M_H_CPU0_SA_DQ<24>")
	)
	(gr_poly
		(pts
			(xy 389.424926 -239.422178) (xy 389.424926 -239.377728) (xy 389.224774 -239.377728) (xy 389.224774 -239.422178)
			(xy 389.32485 -239.522254)
		)
		(stroke
			(width 0)
			(type solid)
		)
		(fill yes)
		(layer "In13.Cu")
		(net "M_H_CPU0_SA_DQ<23>")
	)
	(gr_poly
		(pts
			(xy 389.424926 -238.206026) (xy 389.32485 -238.10595) (xy 389.224774 -238.206026) (xy 389.224774 -238.250476)
			(xy 389.424926 -238.250476)
		)
		(stroke
			(width 0)
			(type solid)
		)
		(fill yes)
		(layer "In13.Cu")
		(net "M_H_CPU0_SA_DQ<20>")
	)
	(gr_poly
		(pts
			(xy 389.424926 -237.80242) (xy 389.424926 -237.754668) (xy 389.224774 -237.754668) (xy 389.224774 -237.80242)
			(xy 389.32485 -237.902242)
		)
		(stroke
			(width 0)
			(type solid)
		)
		(fill yes)
		(layer "In13.Cu")
		(net "M_H_CPU0_SA_DQS_DP<7>")
	)
	(gr_poly
		(pts
			(xy 389.424926 -236.58576) (xy 389.32485 -236.485938) (xy 389.224774 -236.58576) (xy 389.224774 -236.633512)
			(xy 389.424926 -236.633512)
		)
		(stroke
			(width 0)
			(type solid)
		)
		(fill yes)
		(layer "In13.Cu")
		(net "M_H_CPU0_SA_DQS_DP<2>")
	)
	(gr_poly
		(pts
			(xy 389.424926 -236.182154) (xy 389.424926 -236.137704) (xy 389.224774 -236.137704) (xy 389.224774 -236.182154)
			(xy 389.32485 -236.28223)
		)
		(stroke
			(width 0)
			(type solid)
		)
		(fill yes)
		(layer "In13.Cu")
		(net "M_H_CPU0_SA_DQ<19>")
	)
	(gr_poly
		(pts
			(xy 389.424926 -234.966002) (xy 389.32485 -234.865926) (xy 389.224774 -234.966002) (xy 389.224774 -235.010452)
			(xy 389.424926 -235.010452)
		)
		(stroke
			(width 0)
			(type solid)
		)
		(fill yes)
		(layer "In13.Cu")
		(net "M_H_CPU0_SA_DQ<16>")
	)
	(gr_poly
		(pts
			(xy 389.424926 -234.562142) (xy 389.424926 -234.517692) (xy 389.224774 -234.517692) (xy 389.224774 -234.562142)
			(xy 389.32485 -234.662218)
		)
		(stroke
			(width 0)
			(type solid)
		)
		(fill yes)
		(layer "In13.Cu")
		(net "M_H_CPU0_SA_DQ<15>")
	)
	(gr_poly
		(pts
			(xy 389.424926 -233.34599) (xy 389.32485 -233.245914) (xy 389.224774 -233.34599) (xy 389.224774 -233.39044)
			(xy 389.424926 -233.39044)
		)
		(stroke
			(width 0)
			(type solid)
		)
		(fill yes)
		(layer "In13.Cu")
		(net "M_H_CPU0_SA_DQ<12>")
	)
	(gr_poly
		(pts
			(xy 389.424926 -232.942384) (xy 389.424926 -232.894632) (xy 389.224774 -232.894632) (xy 389.224774 -232.942384)
			(xy 389.32485 -233.042206)
		)
		(stroke
			(width 0)
			(type solid)
		)
		(fill yes)
		(layer "In13.Cu")
		(net "M_H_CPU0_SA_DQS_DP<6>")
	)
	(gr_poly
		(pts
			(xy 389.424926 -231.725724) (xy 389.32485 -231.625902) (xy 389.224774 -231.725724) (xy 389.224774 -231.773476)
			(xy 389.424926 -231.773476)
		)
		(stroke
			(width 0)
			(type solid)
		)
		(fill yes)
		(layer "In13.Cu")
		(net "M_H_CPU0_SA_DQS_DP<1>")
	)
	(gr_poly
		(pts
			(xy 389.424926 -231.322372) (xy 389.424926 -231.277922) (xy 389.224774 -231.277922) (xy 389.224774 -231.322372)
			(xy 389.32485 -231.422448)
		)
		(stroke
			(width 0)
			(type solid)
		)
		(fill yes)
		(layer "In13.Cu")
		(net "M_H_CPU0_SA_DQ<11>")
	)
	(gr_poly
		(pts
			(xy 389.424926 -230.105966) (xy 389.32485 -230.006144) (xy 389.224774 -230.105966) (xy 389.224774 -230.150416)
			(xy 389.424926 -230.150416)
		)
		(stroke
			(width 0)
			(type solid)
		)
		(fill yes)
		(layer "In13.Cu")
		(net "M_H_CPU0_SA_DQ<8>")
	)
	(gr_poly
		(pts
			(xy 389.424926 -229.70236) (xy 389.424926 -229.65791) (xy 389.224774 -229.65791) (xy 389.224774 -229.70236)
			(xy 389.32485 -229.802436)
		)
		(stroke
			(width 0)
			(type solid)
		)
		(fill yes)
		(layer "In13.Cu")
		(net "M_H_CPU0_SA_DQ<7>")
	)
	(gr_poly
		(pts
			(xy 389.424926 -228.486208) (xy 389.32485 -228.386132) (xy 389.224774 -228.486208) (xy 389.224774 -228.530658)
			(xy 389.424926 -228.530658)
		)
		(stroke
			(width 0)
			(type solid)
		)
		(fill yes)
		(layer "In13.Cu")
		(net "M_H_CPU0_SA_DQ<4>")
	)
	(gr_poly
		(pts
			(xy 389.424926 -228.082602) (xy 389.424926 -228.03485) (xy 389.224774 -228.03485) (xy 389.224774 -228.082602)
			(xy 389.32485 -228.182424)
		)
		(stroke
			(width 0)
			(type solid)
		)
		(fill yes)
		(layer "In13.Cu")
		(net "M_H_CPU0_SA_DQS_DP<5>")
	)
	(gr_poly
		(pts
			(xy 389.47979 -227.000816) (xy 389.44296 -226.864164) (xy 389.401812 -226.840288) (xy 389.301736 -227.013516)
			(xy 389.343138 -227.037392)
		)
		(stroke
			(width 0)
			(type solid)
		)
		(fill yes)
		(layer "In13.Cu")
		(net "M_H_CPU0_SA_DQS_DN<0>")
	)
	(gr_poly
		(pts
			(xy 389.480044 -225.380042) (xy 389.443468 -225.24339) (xy 389.40486 -225.221292) (xy 389.304784 -225.39452)
			(xy 389.343392 -225.416618)
		)
		(stroke
			(width 0)
			(type solid)
		)
		(fill yes)
		(layer "In13.Cu")
		(net "M_H_CPU0_SA_DQ<3>")
	)
	(gr_poly
		(pts
			(xy 389.481314 -223.757998) (xy 389.444738 -223.6216) (xy 389.406384 -223.599248) (xy 389.306308 -223.772476)
			(xy 389.344916 -223.794828)
		)
		(stroke
			(width 0)
			(type solid)
		)
		(fill yes)
		(layer "In13.Cu")
		(net "M_H_CPU0_SA_DQ<2>")
	)
	(gr_poly
		(pts
			(xy 389.7249 -292.91788) (xy 389.624824 -292.817804) (xy 389.524748 -292.91788) (xy 389.524748 -292.96233)
			(xy 389.7249 -292.96233)
		)
		(stroke
			(width 0)
			(type solid)
		)
		(fill yes)
		(layer "In13.Cu")
		(net "M_H_CPU0_SB_DQ<29>")
	)
	(gr_poly
		(pts
			(xy 389.7249 -292.51402) (xy 389.7249 -292.46957) (xy 389.524748 -292.46957) (xy 389.524748 -292.51402)
			(xy 389.624824 -292.614096)
		)
		(stroke
			(width 0)
			(type solid)
		)
		(fill yes)
		(layer "In13.Cu")
		(net "M_H_CPU0_SB_DQ<30>")
	)
	(gr_poly
		(pts
			(xy 389.7249 -291.297614) (xy 389.624824 -291.197792) (xy 389.524748 -291.297614) (xy 389.524748 -291.345366)
			(xy 389.7249 -291.345366)
		)
		(stroke
			(width 0)
			(type solid)
		)
		(fill yes)
		(layer "In13.Cu")
		(net "M_H_CPU0_SB_DQS_DN<8>")
	)
	(gr_poly
		(pts
			(xy 389.7249 -290.894262) (xy 389.7249 -290.84651) (xy 389.524748 -290.84651) (xy 389.524748 -290.894262)
			(xy 389.624824 -290.994084)
		)
		(stroke
			(width 0)
			(type solid)
		)
		(fill yes)
		(layer "In13.Cu")
		(net "M_H_CPU0_SB_DQS_DN<3>")
	)
	(gr_poly
		(pts
			(xy 389.7249 -289.677856) (xy 389.624824 -289.57778) (xy 389.524748 -289.677856) (xy 389.524748 -289.722306)
			(xy 389.7249 -289.722306)
		)
		(stroke
			(width 0)
			(type solid)
		)
		(fill yes)
		(layer "In13.Cu")
		(net "M_H_CPU0_SB_DQ<25>")
	)
	(gr_poly
		(pts
			(xy 389.7249 -289.273996) (xy 389.7249 -289.229546) (xy 389.524748 -289.229546) (xy 389.524748 -289.273996)
			(xy 389.624824 -289.374072)
		)
		(stroke
			(width 0)
			(type solid)
		)
		(fill yes)
		(layer "In13.Cu")
		(net "M_H_CPU0_SB_DQ<26>")
	)
	(gr_poly
		(pts
			(xy 389.7249 -288.057844) (xy 389.624824 -287.957768) (xy 389.524748 -288.057844) (xy 389.524748 -288.102294)
			(xy 389.7249 -288.102294)
		)
		(stroke
			(width 0)
			(type solid)
		)
		(fill yes)
		(layer "In13.Cu")
		(net "M_H_CPU0_SB_DQ<21>")
	)
	(gr_poly
		(pts
			(xy 389.7249 -287.654238) (xy 389.7249 -287.609788) (xy 389.524748 -287.609788) (xy 389.524748 -287.654238)
			(xy 389.624824 -287.75406)
		)
		(stroke
			(width 0)
			(type solid)
		)
		(fill yes)
		(layer "In13.Cu")
		(net "M_H_CPU0_SB_DQ<22>")
	)
	(gr_poly
		(pts
			(xy 389.7249 -286.437832) (xy 389.624824 -286.337756) (xy 389.524748 -286.437832) (xy 389.524748 -286.485584)
			(xy 389.7249 -286.485584)
		)
		(stroke
			(width 0)
			(type solid)
		)
		(fill yes)
		(layer "In13.Cu")
		(net "M_H_CPU0_SB_DQS_DN<7>")
	)
	(gr_poly
		(pts
			(xy 389.7249 -286.03448) (xy 389.7249 -285.986728) (xy 389.524748 -285.986728) (xy 389.524748 -286.03448)
			(xy 389.624824 -286.134302)
		)
		(stroke
			(width 0)
			(type solid)
		)
		(fill yes)
		(layer "In13.Cu")
		(net "M_H_CPU0_SB_DQS_DN<2>")
	)
	(gr_poly
		(pts
			(xy 389.7249 -284.818074) (xy 389.624824 -284.717998) (xy 389.524748 -284.818074) (xy 389.524748 -284.862524)
			(xy 389.7249 -284.862524)
		)
		(stroke
			(width 0)
			(type solid)
		)
		(fill yes)
		(layer "In13.Cu")
		(net "M_H_CPU0_SB_DQ<17>")
	)
	(gr_poly
		(pts
			(xy 389.7249 -284.414214) (xy 389.7249 -284.369764) (xy 389.524748 -284.369764) (xy 389.524748 -284.414214)
			(xy 389.624824 -284.51429)
		)
		(stroke
			(width 0)
			(type solid)
		)
		(fill yes)
		(layer "In13.Cu")
		(net "M_H_CPU0_SB_DQ<18>")
	)
	(gr_poly
		(pts
			(xy 389.7249 -283.198062) (xy 389.624824 -283.097986) (xy 389.524748 -283.198062) (xy 389.524748 -283.242512)
			(xy 389.7249 -283.242512)
		)
		(stroke
			(width 0)
			(type solid)
		)
		(fill yes)
		(layer "In13.Cu")
		(net "M_H_CPU0_SB_DQ<13>")
	)
	(gr_poly
		(pts
			(xy 389.7249 -282.794202) (xy 389.7249 -282.749752) (xy 389.524748 -282.749752) (xy 389.524748 -282.794202)
			(xy 389.624824 -282.894278)
		)
		(stroke
			(width 0)
			(type solid)
		)
		(fill yes)
		(layer "In13.Cu")
		(net "M_H_CPU0_SB_DQ<14>")
	)
	(gr_poly
		(pts
			(xy 389.7249 -281.577796) (xy 389.624824 -281.477974) (xy 389.524748 -281.577796) (xy 389.524748 -281.625548)
			(xy 389.7249 -281.625548)
		)
		(stroke
			(width 0)
			(type solid)
		)
		(fill yes)
		(layer "In13.Cu")
		(net "M_H_CPU0_SB_DQS_DN<6>")
	)
	(gr_poly
		(pts
			(xy 389.7249 -281.174444) (xy 389.7249 -281.126692) (xy 389.524748 -281.126692) (xy 389.524748 -281.174444)
			(xy 389.624824 -281.274266)
		)
		(stroke
			(width 0)
			(type solid)
		)
		(fill yes)
		(layer "In13.Cu")
		(net "M_H_CPU0_SB_DQS_DN<1>")
	)
	(gr_poly
		(pts
			(xy 389.7249 -279.958038) (xy 389.624824 -279.857962) (xy 389.524748 -279.958038) (xy 389.524748 -280.002488)
			(xy 389.7249 -280.002488)
		)
		(stroke
			(width 0)
			(type solid)
		)
		(fill yes)
		(layer "In13.Cu")
		(net "M_H_CPU0_SB_DQ<9>")
	)
	(gr_poly
		(pts
			(xy 389.7249 -279.554178) (xy 389.7249 -279.509728) (xy 389.524748 -279.509728) (xy 389.524748 -279.554178)
			(xy 389.624824 -279.654254)
		)
		(stroke
			(width 0)
			(type solid)
		)
		(fill yes)
		(layer "In13.Cu")
		(net "M_H_CPU0_SB_DQ<10>")
	)
	(gr_poly
		(pts
			(xy 389.7249 -278.338026) (xy 389.624824 -278.23795) (xy 389.524748 -278.338026) (xy 389.524748 -278.382476)
			(xy 389.7249 -278.382476)
		)
		(stroke
			(width 0)
			(type solid)
		)
		(fill yes)
		(layer "In13.Cu")
		(net "M_H_CPU0_SB_DQ<5>")
	)
	(gr_poly
		(pts
			(xy 389.7249 -277.934166) (xy 389.7249 -277.889716) (xy 389.524748 -277.889716) (xy 389.524748 -277.934166)
			(xy 389.624824 -278.034242)
		)
		(stroke
			(width 0)
			(type solid)
		)
		(fill yes)
		(layer "In13.Cu")
		(net "M_H_CPU0_SB_DQ<6>")
	)
	(gr_poly
		(pts
			(xy 389.7249 -276.71776) (xy 389.624824 -276.617938) (xy 389.524748 -276.71776) (xy 389.524748 -276.765512)
			(xy 389.7249 -276.765512)
		)
		(stroke
			(width 0)
			(type solid)
		)
		(fill yes)
		(layer "In13.Cu")
		(net "M_H_CPU0_SB_DQS_DN<5>")
	)
	(gr_poly
		(pts
			(xy 389.7249 -276.314408) (xy 389.7249 -276.266656) (xy 389.524748 -276.266656) (xy 389.524748 -276.314408)
			(xy 389.624824 -276.41423)
		)
		(stroke
			(width 0)
			(type solid)
		)
		(fill yes)
		(layer "In13.Cu")
		(net "M_H_CPU0_SB_DQS_DN<0>")
	)
	(gr_poly
		(pts
			(xy 389.7249 -275.098002) (xy 389.624824 -274.997926) (xy 389.524748 -275.098002) (xy 389.524748 -275.142452)
			(xy 389.7249 -275.142452)
		)
		(stroke
			(width 0)
			(type solid)
		)
		(fill yes)
		(layer "In13.Cu")
		(net "M_H_CPU0_SB_DQ<1>")
	)
	(gr_poly
		(pts
			(xy 389.7249 -274.694142) (xy 389.7249 -274.649692) (xy 389.524748 -274.649692) (xy 389.524748 -274.694142)
			(xy 389.624824 -274.794218)
		)
		(stroke
			(width 0)
			(type solid)
		)
		(fill yes)
		(layer "In13.Cu")
		(net "M_H_CPU0_SB_DQ<2>")
	)
	(gr_poly
		(pts
			(xy 389.7249 -273.47799) (xy 389.624824 -273.377914) (xy 389.524748 -273.47799) (xy 389.524748 -273.52244)
			(xy 389.7249 -273.52244)
		)
		(stroke
			(width 0)
			(type solid)
		)
		(fill yes)
		(layer "In13.Cu")
		(net "M_H_CPU0_SB_CB<1>")
	)
	(gr_poly
		(pts
			(xy 389.7249 -273.07413) (xy 389.7249 -273.02968) (xy 389.524748 -273.02968) (xy 389.524748 -273.07413)
			(xy 389.624824 -273.174206)
		)
		(stroke
			(width 0)
			(type solid)
		)
		(fill yes)
		(layer "In13.Cu")
		(net "M_H_CPU0_SB_CB<2>")
	)
	(gr_poly
		(pts
			(xy 389.7249 -271.857724) (xy 389.624824 -271.757902) (xy 389.524748 -271.857724) (xy 389.524748 -271.905476)
			(xy 389.7249 -271.905476)
		)
		(stroke
			(width 0)
			(type solid)
		)
		(fill yes)
		(layer "In13.Cu")
		(net "M_H_CPU0_SB_DQS_DN<4>")
	)
	(gr_poly
		(pts
			(xy 389.7249 -271.454372) (xy 389.7249 -271.40662) (xy 389.524748 -271.40662) (xy 389.524748 -271.454372)
			(xy 389.624824 -271.554194)
		)
		(stroke
			(width 0)
			(type solid)
		)
		(fill yes)
		(layer "In13.Cu")
		(net "M_H_CPU0_SB_DQS_DN<9>")
	)
	(gr_poly
		(pts
			(xy 389.7249 -270.237966) (xy 389.624824 -270.13789) (xy 389.524748 -270.237966) (xy 389.524748 -270.282416)
			(xy 389.7249 -270.282416)
		)
		(stroke
			(width 0)
			(type solid)
		)
		(fill yes)
		(layer "In13.Cu")
		(net "M_H_CPU0_SB_CB<5>")
	)
	(gr_poly
		(pts
			(xy 389.7249 -269.834106) (xy 389.7249 -269.789656) (xy 389.524748 -269.789656) (xy 389.524748 -269.834106)
			(xy 389.624824 -269.934182)
		)
		(stroke
			(width 0)
			(type solid)
		)
		(fill yes)
		(layer "In13.Cu")
		(net "M_H_CPU0_SB_CB<6>")
	)
	(gr_poly
		(pts
			(xy 389.7249 -266.997942) (xy 389.624824 -266.897866) (xy 389.524748 -266.997942) (xy 389.524748 -267.042392)
			(xy 389.7249 -267.042392)
		)
		(stroke
			(width 0)
			(type solid)
		)
		(fill yes)
		(layer "In13.Cu")
		(net "M_H_CPU0_SA_RSP<0>")
	)
	(gr_poly
		(pts
			(xy 389.7249 -266.594082) (xy 389.7249 -266.549632) (xy 389.524748 -266.549632) (xy 389.524748 -266.594082)
			(xy 389.624824 -266.694158)
		)
		(stroke
			(width 0)
			(type solid)
		)
		(fill yes)
		(layer "In13.Cu")
		(net "M_H_CPU0_SB_CS_N<1>")
	)
	(gr_poly
		(pts
			(xy 389.7249 -265.37793) (xy 389.624824 -265.277854) (xy 389.524748 -265.37793) (xy 389.524748 -265.42238)
			(xy 389.7249 -265.42238)
		)
		(stroke
			(width 0)
			(type solid)
		)
		(fill yes)
		(layer "In13.Cu")
		(net "M_H_CPU0_SB_PAR")
	)
	(gr_poly
		(pts
			(xy 389.7249 -263.757918) (xy 389.624824 -263.657842) (xy 389.524748 -263.757918) (xy 389.524748 -263.802368)
			(xy 389.7249 -263.802368)
		)
		(stroke
			(width 0)
			(type solid)
		)
		(fill yes)
		(layer "In13.Cu")
		(net "M_H_CPU0_SB_CA<4>")
	)
	(gr_poly
		(pts
			(xy 389.7249 -263.354058) (xy 389.7249 -263.309608) (xy 389.524748 -263.309608) (xy 389.524748 -263.354058)
			(xy 389.624824 -263.454134)
		)
		(stroke
			(width 0)
			(type solid)
		)
		(fill yes)
		(layer "In13.Cu")
		(net "M_H_CPU0_SB_CA<3>")
	)
	(gr_poly
		(pts
			(xy 389.7249 -262.137906) (xy 389.624824 -262.03783) (xy 389.524748 -262.137906) (xy 389.524748 -262.182356)
			(xy 389.7249 -262.182356)
		)
		(stroke
			(width 0)
			(type solid)
		)
		(fill yes)
		(layer "In13.Cu")
		(net "M_H_CPU0_SB_CA<0>")
	)
	(gr_poly
		(pts
			(xy 389.8138 -223.886014) (xy 389.775192 -223.863916) (xy 389.638794 -223.900492) (xy 389.67537 -224.037144)
			(xy 389.713724 -224.059242)
		)
		(stroke
			(width 0)
			(type solid)
		)
		(fill yes)
		(layer "In13.Cu")
		(net "M_H_CPU0_SA_DQ<1>")
	)
	(gr_poly
		(pts
			(xy 389.816848 -227.126292) (xy 389.7757 -227.10267) (xy 389.639048 -227.139246) (xy 389.675624 -227.275644)
			(xy 389.717026 -227.29952)
		)
		(stroke
			(width 0)
			(type solid)
		)
		(fill yes)
		(layer "In13.Cu")
		(net "M_H_CPU0_SA_DQS_DN<5>")
	)
	(gr_poly
		(pts
			(xy 389.816848 -225.50628) (xy 389.7757 -225.482404) (xy 389.639048 -225.519234) (xy 389.675624 -225.655632)
			(xy 389.717026 -225.679508)
		)
		(stroke
			(width 0)
			(type solid)
		)
		(fill yes)
		(layer "In13.Cu")
		(net "M_H_CPU0_SA_DQS_DP<0>")
	)
	(gr_poly
		(pts
			(xy 389.894826 -256.432558) (xy 389.894826 -256.384806) (xy 389.694674 -256.384806) (xy 389.694674 -256.432558)
			(xy 389.79475 -256.53238)
		)
		(stroke
			(width 0)
			(type solid)
		)
		(fill yes)
		(layer "In13.Cu")
		(net "M_H_CPU0_CLK_DN<0>")
	)
	(gr_poly
		(pts
			(xy 389.894826 -255.216152) (xy 389.79475 -255.116076) (xy 389.694674 -255.216152) (xy 389.694674 -255.260602)
			(xy 389.894826 -255.260602)
		)
		(stroke
			(width 0)
			(type solid)
		)
		(fill yes)
		(layer "In13.Cu")
		(net "M_H_CPU0_SA_CA<6>")
	)
	(gr_poly
		(pts
			(xy 389.894826 -254.812292) (xy 389.894826 -254.767842) (xy 389.694674 -254.767842) (xy 389.694674 -254.812292)
			(xy 389.79475 -254.912368)
		)
		(stroke
			(width 0)
			(type solid)
		)
		(fill yes)
		(layer "In13.Cu")
		(net "M_H_CPU0_SA_CA<5>")
	)
	(gr_poly
		(pts
			(xy 389.894826 -253.59614) (xy 389.79475 -253.496064) (xy 389.694674 -253.59614) (xy 389.694674 -253.64059)
			(xy 389.894826 -253.64059)
		)
		(stroke
			(width 0)
			(type solid)
		)
		(fill yes)
		(layer "In13.Cu")
		(net "M_H_CPU0_SA_CA<2>")
	)
	(gr_poly
		(pts
			(xy 389.894826 -253.19228) (xy 389.894826 -253.14783) (xy 389.694674 -253.14783) (xy 389.694674 -253.19228)
			(xy 389.79475 -253.292356)
		)
		(stroke
			(width 0)
			(type solid)
		)
		(fill yes)
		(layer "In13.Cu")
		(net "M_H_CPU0_SA_CA<1>")
	)
	(gr_poly
		(pts
			(xy 389.894826 -251.976128) (xy 389.79475 -251.876052) (xy 389.694674 -251.976128) (xy 389.694674 -252.020578)
			(xy 389.894826 -252.020578)
		)
		(stroke
			(width 0)
			(type solid)
		)
		(fill yes)
		(layer "In13.Cu")
		(net "M_H_CPU0_SA_CS_N<1>")
	)
	(gr_poly
		(pts
			(xy 389.894826 -250.356116) (xy 389.79475 -250.25604) (xy 389.694674 -250.356116) (xy 389.694674 -250.400566)
			(xy 389.894826 -250.400566)
		)
		(stroke
			(width 0)
			(type solid)
		)
		(fill yes)
		(layer "In13.Cu")
		(net "M_H_CPU0_ALERT_R_N")
	)
	(gr_poly
		(pts
			(xy 389.894826 -248.736104) (xy 389.79475 -248.636028) (xy 389.694674 -248.736104) (xy 389.694674 -248.780554)
			(xy 389.894826 -248.780554)
		)
		(stroke
			(width 0)
			(type solid)
		)
		(fill yes)
		(layer "In13.Cu")
		(net "M_H_CPU0_SA_CB<5>")
	)
	(gr_poly
		(pts
			(xy 389.894826 -248.332244) (xy 389.894826 -248.287794) (xy 389.694674 -248.287794) (xy 389.694674 -248.332244)
			(xy 389.79475 -248.43232)
		)
		(stroke
			(width 0)
			(type solid)
		)
		(fill yes)
		(layer "In13.Cu")
		(net "M_H_CPU0_SA_CB<6>")
	)
	(gr_poly
		(pts
			(xy 389.894826 -247.115838) (xy 389.79475 -247.016016) (xy 389.694674 -247.115838) (xy 389.694674 -247.16359)
			(xy 389.894826 -247.16359)
		)
		(stroke
			(width 0)
			(type solid)
		)
		(fill yes)
		(layer "In13.Cu")
		(net "M_H_CPU0_SA_DQS_DN<9>")
	)
	(gr_poly
		(pts
			(xy 389.894826 -246.712486) (xy 389.894826 -246.664734) (xy 389.694674 -246.664734) (xy 389.694674 -246.712486)
			(xy 389.79475 -246.812308)
		)
		(stroke
			(width 0)
			(type solid)
		)
		(fill yes)
		(layer "In13.Cu")
		(net "M_H_CPU0_SA_DQS_DN<4>")
	)
	(gr_poly
		(pts
			(xy 389.894826 -245.49608) (xy 389.79475 -245.396004) (xy 389.694674 -245.49608) (xy 389.694674 -245.54053)
			(xy 389.894826 -245.54053)
		)
		(stroke
			(width 0)
			(type solid)
		)
		(fill yes)
		(layer "In13.Cu")
		(net "M_H_CPU0_SA_CB<1>")
	)
	(gr_poly
		(pts
			(xy 389.894826 -245.09222) (xy 389.894826 -245.04777) (xy 389.694674 -245.04777) (xy 389.694674 -245.09222)
			(xy 389.79475 -245.192296)
		)
		(stroke
			(width 0)
			(type solid)
		)
		(fill yes)
		(layer "In13.Cu")
		(net "M_H_CPU0_SA_CB<2>")
	)
	(gr_poly
		(pts
			(xy 389.894826 -243.876068) (xy 389.79475 -243.775992) (xy 389.694674 -243.876068) (xy 389.694674 -243.920518)
			(xy 389.894826 -243.920518)
		)
		(stroke
			(width 0)
			(type solid)
		)
		(fill yes)
		(layer "In13.Cu")
		(net "M_H_CPU0_SA_DQ<29>")
	)
	(gr_poly
		(pts
			(xy 389.894826 -243.472208) (xy 389.894826 -243.427758) (xy 389.694674 -243.427758) (xy 389.694674 -243.472208)
			(xy 389.79475 -243.572284)
		)
		(stroke
			(width 0)
			(type solid)
		)
		(fill yes)
		(layer "In13.Cu")
		(net "M_H_CPU0_SA_DQ<30>")
	)
	(gr_poly
		(pts
			(xy 389.894826 -242.255802) (xy 389.79475 -242.15598) (xy 389.694674 -242.255802) (xy 389.694674 -242.303554)
			(xy 389.894826 -242.303554)
		)
		(stroke
			(width 0)
			(type solid)
		)
		(fill yes)
		(layer "In13.Cu")
		(net "M_H_CPU0_SA_DQS_DN<8>")
	)
	(gr_poly
		(pts
			(xy 389.894826 -241.85245) (xy 389.894826 -241.804698) (xy 389.694674 -241.804698) (xy 389.694674 -241.85245)
			(xy 389.79475 -241.952272)
		)
		(stroke
			(width 0)
			(type solid)
		)
		(fill yes)
		(layer "In13.Cu")
		(net "M_H_CPU0_SA_DQS_DN<3>")
	)
	(gr_poly
		(pts
			(xy 389.894826 -240.636044) (xy 389.79475 -240.535968) (xy 389.694674 -240.636044) (xy 389.694674 -240.680494)
			(xy 389.894826 -240.680494)
		)
		(stroke
			(width 0)
			(type solid)
		)
		(fill yes)
		(layer "In13.Cu")
		(net "M_H_CPU0_SA_DQ<25>")
	)
	(gr_poly
		(pts
			(xy 389.894826 -240.232184) (xy 389.894826 -240.187734) (xy 389.694674 -240.187734) (xy 389.694674 -240.232184)
			(xy 389.79475 -240.33226)
		)
		(stroke
			(width 0)
			(type solid)
		)
		(fill yes)
		(layer "In13.Cu")
		(net "M_H_CPU0_SA_DQ<26>")
	)
	(gr_poly
		(pts
			(xy 389.894826 -239.016032) (xy 389.79475 -238.915956) (xy 389.694674 -239.016032) (xy 389.694674 -239.060482)
			(xy 389.894826 -239.060482)
		)
		(stroke
			(width 0)
			(type solid)
		)
		(fill yes)
		(layer "In13.Cu")
		(net "M_H_CPU0_SA_DQ<21>")
	)
	(gr_poly
		(pts
			(xy 389.894826 -238.612172) (xy 389.894826 -238.567722) (xy 389.694674 -238.567722) (xy 389.694674 -238.612172)
			(xy 389.79475 -238.712248)
		)
		(stroke
			(width 0)
			(type solid)
		)
		(fill yes)
		(layer "In13.Cu")
		(net "M_H_CPU0_SA_DQ<22>")
	)
	(gr_poly
		(pts
			(xy 389.894826 -237.395766) (xy 389.79475 -237.295944) (xy 389.694674 -237.395766) (xy 389.694674 -237.443518)
			(xy 389.894826 -237.443518)
		)
		(stroke
			(width 0)
			(type solid)
		)
		(fill yes)
		(layer "In13.Cu")
		(net "M_H_CPU0_SA_DQS_DN<7>")
	)
	(gr_poly
		(pts
			(xy 389.894826 -236.992414) (xy 389.894826 -236.944662) (xy 389.694674 -236.944662) (xy 389.694674 -236.992414)
			(xy 389.79475 -237.092236)
		)
		(stroke
			(width 0)
			(type solid)
		)
		(fill yes)
		(layer "In13.Cu")
		(net "M_H_CPU0_SA_DQS_DN<2>")
	)
	(gr_poly
		(pts
			(xy 389.894826 -235.776008) (xy 389.79475 -235.675932) (xy 389.694674 -235.776008) (xy 389.694674 -235.820458)
			(xy 389.894826 -235.820458)
		)
		(stroke
			(width 0)
			(type solid)
		)
		(fill yes)
		(layer "In13.Cu")
		(net "M_H_CPU0_SA_DQ<17>")
	)
	(gr_poly
		(pts
			(xy 389.894826 -235.372148) (xy 389.894826 -235.327698) (xy 389.694674 -235.327698) (xy 389.694674 -235.372148)
			(xy 389.79475 -235.472224)
		)
		(stroke
			(width 0)
			(type solid)
		)
		(fill yes)
		(layer "In13.Cu")
		(net "M_H_CPU0_SA_DQ<18>")
	)
	(gr_poly
		(pts
			(xy 389.894826 -234.155996) (xy 389.79475 -234.05592) (xy 389.694674 -234.155996) (xy 389.694674 -234.200446)
			(xy 389.894826 -234.200446)
		)
		(stroke
			(width 0)
			(type solid)
		)
		(fill yes)
		(layer "In13.Cu")
		(net "M_H_CPU0_SA_DQ<13>")
	)
	(gr_poly
		(pts
			(xy 389.894826 -233.752136) (xy 389.894826 -233.707686) (xy 389.694674 -233.707686) (xy 389.694674 -233.752136)
			(xy 389.79475 -233.852212)
		)
		(stroke
			(width 0)
			(type solid)
		)
		(fill yes)
		(layer "In13.Cu")
		(net "M_H_CPU0_SA_DQ<14>")
	)
	(gr_poly
		(pts
			(xy 389.894826 -232.53573) (xy 389.79475 -232.435908) (xy 389.694674 -232.53573) (xy 389.694674 -232.583482)
			(xy 389.894826 -232.583482)
		)
		(stroke
			(width 0)
			(type solid)
		)
		(fill yes)
		(layer "In13.Cu")
		(net "M_H_CPU0_SA_DQS_DN<6>")
	)
	(gr_poly
		(pts
			(xy 389.894826 -232.132378) (xy 389.894826 -232.084626) (xy 389.694674 -232.084626) (xy 389.694674 -232.132378)
			(xy 389.79475 -232.2322)
		)
		(stroke
			(width 0)
			(type solid)
		)
		(fill yes)
		(layer "In13.Cu")
		(net "M_H_CPU0_SA_DQS_DN<1>")
	)
	(gr_poly
		(pts
			(xy 389.894826 -230.915972) (xy 389.79475 -230.815896) (xy 389.694674 -230.915972) (xy 389.694674 -230.960422)
			(xy 389.894826 -230.960422)
		)
		(stroke
			(width 0)
			(type solid)
		)
		(fill yes)
		(layer "In13.Cu")
		(net "M_H_CPU0_SA_DQ<9>")
	)
	(gr_poly
		(pts
			(xy 389.894826 -230.512366) (xy 389.894826 -230.467916) (xy 389.694674 -230.467916) (xy 389.694674 -230.512366)
			(xy 389.79475 -230.612188)
		)
		(stroke
			(width 0)
			(type solid)
		)
		(fill yes)
		(layer "In13.Cu")
		(net "M_H_CPU0_SA_DQ<10>")
	)
	(gr_poly
		(pts
			(xy 389.894826 -229.29596) (xy 389.79475 -229.195884) (xy 389.694674 -229.29596) (xy 389.694674 -229.34041)
			(xy 389.894826 -229.34041)
		)
		(stroke
			(width 0)
			(type solid)
		)
		(fill yes)
		(layer "In13.Cu")
		(net "M_H_CPU0_SA_DQ<5>")
	)
	(gr_poly
		(pts
			(xy 389.894826 -228.892354) (xy 389.894826 -228.847904) (xy 389.694674 -228.847904) (xy 389.694674 -228.892354)
			(xy 389.79475 -228.99243)
		)
		(stroke
			(width 0)
			(type solid)
		)
		(fill yes)
		(layer "In13.Cu")
		(net "M_H_CPU0_SA_DQ<6>")
	)
	(gr_poly
		(pts
			(xy 389.950706 -227.809298) (xy 389.91413 -227.6729) (xy 389.872728 -227.649024) (xy 389.772906 -227.822252)
			(xy 389.814054 -227.846128)
		)
		(stroke
			(width 0)
			(type solid)
		)
		(fill yes)
		(layer "In13.Cu")
		(net "M_H_CPU0_SA_DQS_DP<5>")
	)
	(gr_poly
		(pts
			(xy 389.950706 -226.189286) (xy 389.91413 -226.052888) (xy 389.872728 -226.029012) (xy 389.772906 -226.20224)
			(xy 389.814054 -226.226116)
		)
		(stroke
			(width 0)
			(type solid)
		)
		(fill yes)
		(layer "In13.Cu")
		(net "M_H_CPU0_SA_DQS_DN<0>")
	)
	(gr_poly
		(pts
			(xy 389.950706 -224.568766) (xy 389.91413 -224.432114) (xy 389.875776 -224.409762) (xy 389.7757 -224.58299)
			(xy 389.814308 -224.605342)
		)
		(stroke
			(width 0)
			(type solid)
		)
		(fill yes)
		(layer "In13.Cu")
		(net "M_H_CPU0_SA_DQ<3>")
	)
	(gr_poly
		(pts
			(xy 389.951468 -222.947992) (xy 389.914892 -222.81134) (xy 389.876284 -222.789242) (xy 389.776462 -222.96247)
			(xy 389.814816 -222.984568)
		)
		(stroke
			(width 0)
			(type solid)
		)
		(fill yes)
		(layer "In13.Cu")
		(net "M_H_CPU0_SA_DQ<2>")
	)
	(gr_poly
		(pts
			(xy 390.1948 -293.324026) (xy 390.1948 -293.279576) (xy 389.994648 -293.279576) (xy 389.994648 -293.324026)
			(xy 390.094724 -293.424102)
		)
		(stroke
			(width 0)
			(type solid)
		)
		(fill yes)
		(layer "In13.Cu")
		(net "M_H_CPU0_SB_DQ<31>")
	)
	(gr_poly
		(pts
			(xy 390.1948 -292.107874) (xy 390.094724 -292.007798) (xy 389.994648 -292.107874) (xy 389.994648 -292.152324)
			(xy 390.1948 -292.152324)
		)
		(stroke
			(width 0)
			(type solid)
		)
		(fill yes)
		(layer "In13.Cu")
		(net "M_H_CPU0_SB_DQ<28>")
	)
	(gr_poly
		(pts
			(xy 390.1948 -291.704268) (xy 390.1948 -291.656516) (xy 389.994648 -291.656516) (xy 389.994648 -291.704268)
			(xy 390.094724 -291.80409)
		)
		(stroke
			(width 0)
			(type solid)
		)
		(fill yes)
		(layer "In13.Cu")
		(net "M_H_CPU0_SB_DQS_DP<8>")
	)
	(gr_poly
		(pts
			(xy 390.1948 -290.487608) (xy 390.094724 -290.387786) (xy 389.994648 -290.487608) (xy 389.994648 -290.53536)
			(xy 390.1948 -290.53536)
		)
		(stroke
			(width 0)
			(type solid)
		)
		(fill yes)
		(layer "In13.Cu")
		(net "M_H_CPU0_SB_DQS_DP<3>")
	)
	(gr_poly
		(pts
			(xy 390.1948 -290.084002) (xy 390.1948 -290.039552) (xy 389.994648 -290.039552) (xy 389.994648 -290.084002)
			(xy 390.094724 -290.184078)
		)
		(stroke
			(width 0)
			(type solid)
		)
		(fill yes)
		(layer "In13.Cu")
		(net "M_H_CPU0_SB_DQ<27>")
	)
	(gr_poly
		(pts
			(xy 390.1948 -288.86785) (xy 390.094724 -288.767774) (xy 389.994648 -288.86785) (xy 389.994648 -288.9123)
			(xy 390.1948 -288.9123)
		)
		(stroke
			(width 0)
			(type solid)
		)
		(fill yes)
		(layer "In13.Cu")
		(net "M_H_CPU0_SB_DQ<24>")
	)
	(gr_poly
		(pts
			(xy 390.1948 -288.464244) (xy 390.1948 -288.419794) (xy 389.994648 -288.419794) (xy 389.994648 -288.464244)
			(xy 390.094724 -288.56432)
		)
		(stroke
			(width 0)
			(type solid)
		)
		(fill yes)
		(layer "In13.Cu")
		(net "M_H_CPU0_SB_DQ<23>")
	)
	(gr_poly
		(pts
			(xy 390.1948 -287.247838) (xy 390.094724 -287.148016) (xy 389.994648 -287.247838) (xy 389.994648 -287.292288)
			(xy 390.1948 -287.292288)
		)
		(stroke
			(width 0)
			(type solid)
		)
		(fill yes)
		(layer "In13.Cu")
		(net "M_H_CPU0_SB_DQ<20>")
	)
	(gr_poly
		(pts
			(xy 390.1948 -286.844232) (xy 390.1948 -286.79648) (xy 389.994648 -286.79648) (xy 389.994648 -286.844232)
			(xy 390.094724 -286.944308)
		)
		(stroke
			(width 0)
			(type solid)
		)
		(fill yes)
		(layer "In13.Cu")
		(net "M_H_CPU0_SB_DQS_DP<7>")
	)
	(gr_poly
		(pts
			(xy 390.1948 -285.627826) (xy 390.094724 -285.528004) (xy 389.994648 -285.627826) (xy 389.994648 -285.675578)
			(xy 390.1948 -285.675578)
		)
		(stroke
			(width 0)
			(type solid)
		)
		(fill yes)
		(layer "In13.Cu")
		(net "M_H_CPU0_SB_DQS_DP<2>")
	)
	(gr_poly
		(pts
			(xy 390.1948 -285.22422) (xy 390.1948 -285.17977) (xy 389.994648 -285.17977) (xy 389.994648 -285.22422)
			(xy 390.094724 -285.324296)
		)
		(stroke
			(width 0)
			(type solid)
		)
		(fill yes)
		(layer "In13.Cu")
		(net "M_H_CPU0_SB_DQ<19>")
	)
	(gr_poly
		(pts
			(xy 390.1948 -284.008068) (xy 390.094724 -283.907992) (xy 389.994648 -284.008068) (xy 389.994648 -284.052518)
			(xy 390.1948 -284.052518)
		)
		(stroke
			(width 0)
			(type solid)
		)
		(fill yes)
		(layer "In13.Cu")
		(net "M_H_CPU0_SB_DQ<16>")
	)
	(gr_poly
		(pts
			(xy 390.1948 -283.604208) (xy 390.1948 -283.559758) (xy 389.994648 -283.559758) (xy 389.994648 -283.604208)
			(xy 390.094724 -283.704284)
		)
		(stroke
			(width 0)
			(type solid)
		)
		(fill yes)
		(layer "In13.Cu")
		(net "M_H_CPU0_SB_DQ<15>")
	)
	(gr_poly
		(pts
			(xy 390.1948 -282.388056) (xy 390.094724 -282.28798) (xy 389.994648 -282.388056) (xy 389.994648 -282.432506)
			(xy 390.1948 -282.432506)
		)
		(stroke
			(width 0)
			(type solid)
		)
		(fill yes)
		(layer "In13.Cu")
		(net "M_H_CPU0_SB_DQ<12>")
	)
	(gr_poly
		(pts
			(xy 390.1948 -281.98445) (xy 390.1948 -281.936698) (xy 389.994648 -281.936698) (xy 389.994648 -281.98445)
			(xy 390.094724 -282.084272)
		)
		(stroke
			(width 0)
			(type solid)
		)
		(fill yes)
		(layer "In13.Cu")
		(net "M_H_CPU0_SB_DQS_DP<6>")
	)
	(gr_poly
		(pts
			(xy 390.1948 -280.76779) (xy 390.094724 -280.667968) (xy 389.994648 -280.76779) (xy 389.994648 -280.815542)
			(xy 390.1948 -280.815542)
		)
		(stroke
			(width 0)
			(type solid)
		)
		(fill yes)
		(layer "In13.Cu")
		(net "M_H_CPU0_SB_DQS_DP<1>")
	)
	(gr_poly
		(pts
			(xy 390.1948 -280.364184) (xy 390.1948 -280.319734) (xy 389.994648 -280.319734) (xy 389.994648 -280.364184)
			(xy 390.094724 -280.46426)
		)
		(stroke
			(width 0)
			(type solid)
		)
		(fill yes)
		(layer "In13.Cu")
		(net "M_H_CPU0_SB_DQ<11>")
	)
	(gr_poly
		(pts
			(xy 390.1948 -279.148032) (xy 390.094724 -279.047956) (xy 389.994648 -279.148032) (xy 389.994648 -279.192482)
			(xy 390.1948 -279.192482)
		)
		(stroke
			(width 0)
			(type solid)
		)
		(fill yes)
		(layer "In13.Cu")
		(net "M_H_CPU0_SB_DQ<8>")
	)
	(gr_poly
		(pts
			(xy 390.1948 -278.744172) (xy 390.1948 -278.699722) (xy 389.994648 -278.699722) (xy 389.994648 -278.744172)
			(xy 390.094724 -278.844248)
		)
		(stroke
			(width 0)
			(type solid)
		)
		(fill yes)
		(layer "In13.Cu")
		(net "M_H_CPU0_SB_DQ<7>")
	)
	(gr_poly
		(pts
			(xy 390.1948 -277.52802) (xy 390.094724 -277.427944) (xy 389.994648 -277.52802) (xy 389.994648 -277.57247)
			(xy 390.1948 -277.57247)
		)
		(stroke
			(width 0)
			(type solid)
		)
		(fill yes)
		(layer "In13.Cu")
		(net "M_H_CPU0_SB_DQ<4>")
	)
	(gr_poly
		(pts
			(xy 390.1948 -277.124414) (xy 390.1948 -277.076662) (xy 389.994648 -277.076662) (xy 389.994648 -277.124414)
			(xy 390.094724 -277.224236)
		)
		(stroke
			(width 0)
			(type solid)
		)
		(fill yes)
		(layer "In13.Cu")
		(net "M_H_CPU0_SB_DQS_DP<5>")
	)
	(gr_poly
		(pts
			(xy 390.1948 -275.907754) (xy 390.094724 -275.807932) (xy 389.994648 -275.907754) (xy 389.994648 -275.955506)
			(xy 390.1948 -275.955506)
		)
		(stroke
			(width 0)
			(type solid)
		)
		(fill yes)
		(layer "In13.Cu")
		(net "M_H_CPU0_SB_DQS_DP<0>")
	)
	(gr_poly
		(pts
			(xy 390.1948 -275.504148) (xy 390.1948 -275.459698) (xy 389.994648 -275.459698) (xy 389.994648 -275.504148)
			(xy 390.094724 -275.604224)
		)
		(stroke
			(width 0)
			(type solid)
		)
		(fill yes)
		(layer "In13.Cu")
		(net "M_H_CPU0_SB_DQ<3>")
	)
	(gr_poly
		(pts
			(xy 390.1948 -274.287996) (xy 390.094724 -274.18792) (xy 389.994648 -274.287996) (xy 389.994648 -274.332446)
			(xy 390.1948 -274.332446)
		)
		(stroke
			(width 0)
			(type solid)
		)
		(fill yes)
		(layer "In13.Cu")
		(net "M_H_CPU0_SB_DQ<0>")
	)
	(gr_poly
		(pts
			(xy 390.1948 -273.884136) (xy 390.1948 -273.839686) (xy 389.994648 -273.839686) (xy 389.994648 -273.884136)
			(xy 390.094724 -273.984212)
		)
		(stroke
			(width 0)
			(type solid)
		)
		(fill yes)
		(layer "In13.Cu")
		(net "M_H_CPU0_SB_CB<3>")
	)
	(gr_poly
		(pts
			(xy 390.1948 -272.667984) (xy 390.094724 -272.567908) (xy 389.994648 -272.667984) (xy 389.994648 -272.712434)
			(xy 390.1948 -272.712434)
		)
		(stroke
			(width 0)
			(type solid)
		)
		(fill yes)
		(layer "In13.Cu")
		(net "M_H_CPU0_SB_CB<0>")
	)
	(gr_poly
		(pts
			(xy 390.1948 -272.264378) (xy 390.1948 -272.216626) (xy 389.994648 -272.216626) (xy 389.994648 -272.264378)
			(xy 390.094724 -272.3642)
		)
		(stroke
			(width 0)
			(type solid)
		)
		(fill yes)
		(layer "In13.Cu")
		(net "M_H_CPU0_SB_DQS_DP<4>")
	)
	(gr_poly
		(pts
			(xy 390.1948 -271.047718) (xy 390.094724 -270.947896) (xy 389.994648 -271.047718) (xy 389.994648 -271.09547)
			(xy 390.1948 -271.09547)
		)
		(stroke
			(width 0)
			(type solid)
		)
		(fill yes)
		(layer "In13.Cu")
		(net "M_H_CPU0_SB_DQS_DP<9>")
	)
	(gr_poly
		(pts
			(xy 390.1948 -270.644112) (xy 390.1948 -270.599662) (xy 389.994648 -270.599662) (xy 389.994648 -270.644112)
			(xy 390.094724 -270.744188)
		)
		(stroke
			(width 0)
			(type solid)
		)
		(fill yes)
		(layer "In13.Cu")
		(net "M_H_CPU0_SB_CB<7>")
	)
	(gr_poly
		(pts
			(xy 390.1948 -269.42796) (xy 390.094724 -269.327884) (xy 389.994648 -269.42796) (xy 389.994648 -269.47241)
			(xy 390.1948 -269.47241)
		)
		(stroke
			(width 0)
			(type solid)
		)
		(fill yes)
		(layer "In13.Cu")
		(net "M_H_CPU0_SB_CB<4>")
	)
	(gr_poly
		(pts
			(xy 390.1948 -267.807948) (xy 390.094724 -267.707872) (xy 389.994648 -267.807948) (xy 389.994648 -267.852398)
			(xy 390.1948 -267.852398)
		)
		(stroke
			(width 0)
			(type solid)
		)
		(fill yes)
		(layer "In13.Cu")
		(net "M_H_CPU0_SB_RSP<0>")
	)
	(gr_poly
		(pts
			(xy 390.1948 -265.784076) (xy 390.1948 -265.739626) (xy 389.994648 -265.739626) (xy 389.994648 -265.784076)
			(xy 390.094724 -265.884152)
		)
		(stroke
			(width 0)
			(type solid)
		)
		(fill yes)
		(layer "In13.Cu")
		(net "M_H_CPU0_SB_CS_N<0>")
	)
	(gr_poly
		(pts
			(xy 390.1948 -264.567924) (xy 390.094724 -264.467848) (xy 389.994648 -264.567924) (xy 389.994648 -264.612374)
			(xy 390.1948 -264.612374)
		)
		(stroke
			(width 0)
			(type solid)
		)
		(fill yes)
		(layer "In13.Cu")
		(net "M_H_CPU0_SB_CA<6>")
	)
	(gr_poly
		(pts
			(xy 390.1948 -264.164064) (xy 390.1948 -264.119614) (xy 389.994648 -264.119614) (xy 389.994648 -264.164064)
			(xy 390.094724 -264.26414)
		)
		(stroke
			(width 0)
			(type solid)
		)
		(fill yes)
		(layer "In13.Cu")
		(net "M_H_CPU0_SB_CA<5>")
	)
	(gr_poly
		(pts
			(xy 390.1948 -262.947912) (xy 390.094724 -262.847836) (xy 389.994648 -262.947912) (xy 389.994648 -262.992362)
			(xy 390.1948 -262.992362)
		)
		(stroke
			(width 0)
			(type solid)
		)
		(fill yes)
		(layer "In13.Cu")
		(net "M_H_CPU0_SB_CA<2>")
	)
	(gr_poly
		(pts
			(xy 390.1948 -262.544052) (xy 390.1948 -262.499602) (xy 389.994648 -262.499602) (xy 389.994648 -262.544052)
			(xy 390.094724 -262.644128)
		)
		(stroke
			(width 0)
			(type solid)
		)
		(fill yes)
		(layer "In13.Cu")
		(net "M_H_CPU0_SB_CA<1>")
	)
	(gr_poly
		(pts
			(xy 390.283954 -227.935536) (xy 390.245346 -227.913184) (xy 390.108694 -227.94976) (xy 390.145524 -228.086412)
			(xy 390.183878 -228.108764)
		)
		(stroke
			(width 0)
			(type solid)
		)
		(fill yes)
		(layer "In13.Cu")
		(net "M_H_CPU0_SA_DQ<4>")
	)
	(gr_poly
		(pts
			(xy 390.285986 -223.072452) (xy 390.247378 -223.050354) (xy 390.11098 -223.08693) (xy 390.147556 -223.223582)
			(xy 390.18591 -223.24568)
		)
		(stroke
			(width 0)
			(type solid)
		)
		(fill yes)
		(layer "In13.Cu")
		(net "M_H_CPU0_SA_DQ<1>")
	)
	(gr_poly
		(pts
			(xy 390.286748 -226.316286) (xy 390.2456 -226.292664) (xy 390.108948 -226.32924) (xy 390.145524 -226.465638)
			(xy 390.186926 -226.489514)
		)
		(stroke
			(width 0)
			(type solid)
		)
		(fill yes)
		(layer "In13.Cu")
		(net "M_H_CPU0_SA_DQS_DN<5>")
	)
	(gr_poly
		(pts
			(xy 390.286748 -224.696274) (xy 390.2456 -224.672652) (xy 390.108948 -224.709228) (xy 390.145524 -224.845626)
			(xy 390.186926 -224.869502)
		)
		(stroke
			(width 0)
			(type solid)
		)
		(fill yes)
		(layer "In13.Cu")
		(net "M_H_CPU0_SA_DQS_DP<0>")
	)
	(gr_poly
		(pts
			(xy 390.36498 -256.025904) (xy 390.264904 -255.926082) (xy 390.164828 -256.025904) (xy 390.164828 -256.073656)
			(xy 390.36498 -256.073656)
		)
		(stroke
			(width 0)
			(type solid)
		)
		(fill yes)
		(layer "In13.Cu")
		(net "M_H_CPU0_CLK_DP<0>")
	)
	(gr_poly
		(pts
			(xy 390.36498 -255.622298) (xy 390.36498 -255.577848) (xy 390.164828 -255.577848) (xy 390.164828 -255.622298)
			(xy 390.264904 -255.722374)
		)
		(stroke
			(width 0)
			(type solid)
		)
		(fill yes)
		(layer "In13.Cu")
		(net "M_H_CPU0_SA_PAR")
	)
	(gr_poly
		(pts
			(xy 390.36498 -254.406146) (xy 390.264904 -254.30607) (xy 390.164828 -254.406146) (xy 390.164828 -254.450596)
			(xy 390.36498 -254.450596)
		)
		(stroke
			(width 0)
			(type solid)
		)
		(fill yes)
		(layer "In13.Cu")
		(net "M_H_CPU0_SA_CA<4>")
	)
	(gr_poly
		(pts
			(xy 390.36498 -254.002286) (xy 390.36498 -253.957836) (xy 390.164828 -253.957836) (xy 390.164828 -254.002286)
			(xy 390.264904 -254.102362)
		)
		(stroke
			(width 0)
			(type solid)
		)
		(fill yes)
		(layer "In13.Cu")
		(net "M_H_CPU0_SA_CA<3>")
	)
	(gr_poly
		(pts
			(xy 390.36498 -252.786134) (xy 390.264904 -252.686058) (xy 390.164828 -252.786134) (xy 390.164828 -252.830584)
			(xy 390.36498 -252.830584)
		)
		(stroke
			(width 0)
			(type solid)
		)
		(fill yes)
		(layer "In13.Cu")
		(net "M_H_CPU0_SA_CA<0>")
	)
	(gr_poly
		(pts
			(xy 390.36498 -251.166122) (xy 390.264904 -251.066046) (xy 390.164828 -251.166122) (xy 390.164828 -251.210572)
			(xy 390.36498 -251.210572)
		)
		(stroke
			(width 0)
			(type solid)
		)
		(fill yes)
		(layer "In13.Cu")
		(net "M_H_CPU0_SA_CS_N<0>")
	)
	(gr_poly
		(pts
			(xy 390.36498 -250.762262) (xy 390.36498 -250.717812) (xy 390.164828 -250.717812) (xy 390.164828 -250.762262)
			(xy 390.264904 -250.862338)
		)
		(stroke
			(width 0)
			(type solid)
		)
		(fill yes)
		(layer "In13.Cu")
		(net "M_H_CPU0_RESET_N")
	)
	(gr_poly
		(pts
			(xy 390.36498 -249.14225) (xy 390.36498 -249.0978) (xy 390.164828 -249.0978) (xy 390.164828 -249.14225)
			(xy 390.264904 -249.242326)
		)
		(stroke
			(width 0)
			(type solid)
		)
		(fill yes)
		(layer "In13.Cu")
		(net "M_H_CPU0_SA_CB<7>")
	)
	(gr_poly
		(pts
			(xy 390.36498 -247.926098) (xy 390.264904 -247.826022) (xy 390.164828 -247.926098) (xy 390.164828 -247.970548)
			(xy 390.36498 -247.970548)
		)
		(stroke
			(width 0)
			(type solid)
		)
		(fill yes)
		(layer "In13.Cu")
		(net "M_H_CPU0_SA_CB<4>")
	)
	(gr_poly
		(pts
			(xy 390.36498 -247.522492) (xy 390.36498 -247.47474) (xy 390.164828 -247.47474) (xy 390.164828 -247.522492)
			(xy 390.264904 -247.622314)
		)
		(stroke
			(width 0)
			(type solid)
		)
		(fill yes)
		(layer "In13.Cu")
		(net "M_H_CPU0_SA_DQS_DP<9>")
	)
	(gr_poly
		(pts
			(xy 390.36498 -246.305832) (xy 390.264904 -246.20601) (xy 390.164828 -246.305832) (xy 390.164828 -246.353584)
			(xy 390.36498 -246.353584)
		)
		(stroke
			(width 0)
			(type solid)
		)
		(fill yes)
		(layer "In13.Cu")
		(net "M_H_CPU0_SA_DQS_DP<4>")
	)
	(gr_poly
		(pts
			(xy 390.36498 -245.902226) (xy 390.36498 -245.857776) (xy 390.164828 -245.857776) (xy 390.164828 -245.902226)
			(xy 390.264904 -246.002302)
		)
		(stroke
			(width 0)
			(type solid)
		)
		(fill yes)
		(layer "In13.Cu")
		(net "M_H_CPU0_SA_CB<3>")
	)
	(gr_poly
		(pts
			(xy 390.36498 -244.686074) (xy 390.264904 -244.585998) (xy 390.164828 -244.686074) (xy 390.164828 -244.730524)
			(xy 390.36498 -244.730524)
		)
		(stroke
			(width 0)
			(type solid)
		)
		(fill yes)
		(layer "In13.Cu")
		(net "M_H_CPU0_SA_CB<0>")
	)
	(gr_poly
		(pts
			(xy 390.36498 -244.282214) (xy 390.36498 -244.237764) (xy 390.164828 -244.237764) (xy 390.164828 -244.282214)
			(xy 390.264904 -244.38229)
		)
		(stroke
			(width 0)
			(type solid)
		)
		(fill yes)
		(layer "In13.Cu")
		(net "M_H_CPU0_SA_DQ<31>")
	)
	(gr_poly
		(pts
			(xy 390.36498 -243.066062) (xy 390.264904 -242.965986) (xy 390.164828 -243.066062) (xy 390.164828 -243.110512)
			(xy 390.36498 -243.110512)
		)
		(stroke
			(width 0)
			(type solid)
		)
		(fill yes)
		(layer "In13.Cu")
		(net "M_H_CPU0_SA_DQ<28>")
	)
	(gr_poly
		(pts
			(xy 390.36498 -242.662456) (xy 390.36498 -242.614704) (xy 390.164828 -242.614704) (xy 390.164828 -242.662456)
			(xy 390.264904 -242.762278)
		)
		(stroke
			(width 0)
			(type solid)
		)
		(fill yes)
		(layer "In13.Cu")
		(net "M_H_CPU0_SA_DQS_DP<8>")
	)
	(gr_poly
		(pts
			(xy 390.36498 -241.445796) (xy 390.264904 -241.345974) (xy 390.164828 -241.445796) (xy 390.164828 -241.493548)
			(xy 390.36498 -241.493548)
		)
		(stroke
			(width 0)
			(type solid)
		)
		(fill yes)
		(layer "In13.Cu")
		(net "M_H_CPU0_SA_DQS_DP<3>")
	)
	(gr_poly
		(pts
			(xy 390.36498 -241.04219) (xy 390.36498 -240.99774) (xy 390.164828 -240.99774) (xy 390.164828 -241.04219)
			(xy 390.264904 -241.142266)
		)
		(stroke
			(width 0)
			(type solid)
		)
		(fill yes)
		(layer "In13.Cu")
		(net "M_H_CPU0_SA_DQ<27>")
	)
	(gr_poly
		(pts
			(xy 390.36498 -239.826038) (xy 390.264904 -239.725962) (xy 390.164828 -239.826038) (xy 390.164828 -239.870488)
			(xy 390.36498 -239.870488)
		)
		(stroke
			(width 0)
			(type solid)
		)
		(fill yes)
		(layer "In13.Cu")
		(net "M_H_CPU0_SA_DQ<24>")
	)
	(gr_poly
		(pts
			(xy 390.36498 -239.422178) (xy 390.36498 -239.377728) (xy 390.164828 -239.377728) (xy 390.164828 -239.422178)
			(xy 390.264904 -239.522254)
		)
		(stroke
			(width 0)
			(type solid)
		)
		(fill yes)
		(layer "In13.Cu")
		(net "M_H_CPU0_SA_DQ<23>")
	)
	(gr_poly
		(pts
			(xy 390.36498 -238.206026) (xy 390.264904 -238.10595) (xy 390.164828 -238.206026) (xy 390.164828 -238.250476)
			(xy 390.36498 -238.250476)
		)
		(stroke
			(width 0)
			(type solid)
		)
		(fill yes)
		(layer "In13.Cu")
		(net "M_H_CPU0_SA_DQ<20>")
	)
	(gr_poly
		(pts
			(xy 390.36498 -237.80242) (xy 390.36498 -237.754668) (xy 390.164828 -237.754668) (xy 390.164828 -237.80242)
			(xy 390.264904 -237.902242)
		)
		(stroke
			(width 0)
			(type solid)
		)
		(fill yes)
		(layer "In13.Cu")
		(net "M_H_CPU0_SA_DQS_DP<7>")
	)
	(gr_poly
		(pts
			(xy 390.36498 -236.58576) (xy 390.264904 -236.485938) (xy 390.164828 -236.58576) (xy 390.164828 -236.633512)
			(xy 390.36498 -236.633512)
		)
		(stroke
			(width 0)
			(type solid)
		)
		(fill yes)
		(layer "In13.Cu")
		(net "M_H_CPU0_SA_DQS_DP<2>")
	)
	(gr_poly
		(pts
			(xy 390.36498 -236.182154) (xy 390.36498 -236.137704) (xy 390.164828 -236.137704) (xy 390.164828 -236.182154)
			(xy 390.264904 -236.28223)
		)
		(stroke
			(width 0)
			(type solid)
		)
		(fill yes)
		(layer "In13.Cu")
		(net "M_H_CPU0_SA_DQ<19>")
	)
	(gr_poly
		(pts
			(xy 390.36498 -234.966002) (xy 390.264904 -234.865926) (xy 390.164828 -234.966002) (xy 390.164828 -235.010452)
			(xy 390.36498 -235.010452)
		)
		(stroke
			(width 0)
			(type solid)
		)
		(fill yes)
		(layer "In13.Cu")
		(net "M_H_CPU0_SA_DQ<16>")
	)
	(gr_poly
		(pts
			(xy 390.36498 -234.562142) (xy 390.36498 -234.517692) (xy 390.164828 -234.517692) (xy 390.164828 -234.562142)
			(xy 390.264904 -234.662218)
		)
		(stroke
			(width 0)
			(type solid)
		)
		(fill yes)
		(layer "In13.Cu")
		(net "M_H_CPU0_SA_DQ<15>")
	)
	(gr_poly
		(pts
			(xy 390.36498 -233.34599) (xy 390.264904 -233.245914) (xy 390.164828 -233.34599) (xy 390.164828 -233.39044)
			(xy 390.36498 -233.39044)
		)
		(stroke
			(width 0)
			(type solid)
		)
		(fill yes)
		(layer "In13.Cu")
		(net "M_H_CPU0_SA_DQ<12>")
	)
	(gr_poly
		(pts
			(xy 390.36498 -232.942384) (xy 390.36498 -232.894632) (xy 390.164828 -232.894632) (xy 390.164828 -232.942384)
			(xy 390.264904 -233.042206)
		)
		(stroke
			(width 0)
			(type solid)
		)
		(fill yes)
		(layer "In13.Cu")
		(net "M_H_CPU0_SA_DQS_DP<6>")
	)
	(gr_poly
		(pts
			(xy 390.36498 -231.725724) (xy 390.264904 -231.625902) (xy 390.164828 -231.725724) (xy 390.164828 -231.773476)
			(xy 390.36498 -231.773476)
		)
		(stroke
			(width 0)
			(type solid)
		)
		(fill yes)
		(layer "In13.Cu")
		(net "M_H_CPU0_SA_DQS_DP<1>")
	)
	(gr_poly
		(pts
			(xy 390.36498 -231.322372) (xy 390.36498 -231.277922) (xy 390.164828 -231.277922) (xy 390.164828 -231.322372)
			(xy 390.264904 -231.422448)
		)
		(stroke
			(width 0)
			(type solid)
		)
		(fill yes)
		(layer "In13.Cu")
		(net "M_H_CPU0_SA_DQ<11>")
	)
	(gr_poly
		(pts
			(xy 390.36498 -230.105966) (xy 390.264904 -230.006144) (xy 390.164828 -230.105966) (xy 390.164828 -230.150416)
			(xy 390.36498 -230.150416)
		)
		(stroke
			(width 0)
			(type solid)
		)
		(fill yes)
		(layer "In13.Cu")
		(net "M_H_CPU0_SA_DQ<8>")
	)
	(gr_poly
		(pts
			(xy 390.36498 -229.70236) (xy 390.36498 -229.65791) (xy 390.164828 -229.65791) (xy 390.164828 -229.70236)
			(xy 390.264904 -229.802436)
		)
		(stroke
			(width 0)
			(type solid)
		)
		(fill yes)
		(layer "In13.Cu")
		(net "M_H_CPU0_SA_DQ<7>")
	)
	(gr_poly
		(pts
			(xy 390.419844 -223.760792) (xy 390.383268 -223.62414) (xy 390.34466 -223.601788) (xy 390.244838 -223.77527)
			(xy 390.283192 -223.797368)
		)
		(stroke
			(width 0)
			(type solid)
		)
		(fill yes)
		(layer "In13.Cu")
		(net "M_H_CPU0_SA_DQ<3>")
	)
	(gr_poly
		(pts
			(xy 390.420606 -228.618796) (xy 390.38403 -228.482144) (xy 390.345676 -228.459792) (xy 390.2456 -228.63302)
			(xy 390.284208 -228.655372)
		)
		(stroke
			(width 0)
			(type solid)
		)
		(fill yes)
		(layer "In13.Cu")
		(net "M_H_CPU0_SA_DQ<6>")
	)
	(gr_poly
		(pts
			(xy 390.420606 -226.999292) (xy 390.38403 -226.862894) (xy 390.342628 -226.839018) (xy 390.242806 -227.012246)
			(xy 390.283954 -227.035868)
		)
		(stroke
			(width 0)
			(type solid)
		)
		(fill yes)
		(layer "In13.Cu")
		(net "M_H_CPU0_SA_DQS_DP<5>")
	)
	(gr_poly
		(pts
			(xy 390.420606 -225.37928) (xy 390.38403 -225.242882) (xy 390.342628 -225.219006) (xy 390.242806 -225.392234)
			(xy 390.283954 -225.415856)
		)
		(stroke
			(width 0)
			(type solid)
		)
		(fill yes)
		(layer "In13.Cu")
		(net "M_H_CPU0_SA_DQS_DN<0>")
	)
	(gr_poly
		(pts
			(xy 390.664954 -292.91788) (xy 390.564878 -292.817804) (xy 390.464802 -292.91788) (xy 390.464802 -292.96233)
			(xy 390.664954 -292.96233)
		)
		(stroke
			(width 0)
			(type solid)
		)
		(fill yes)
		(layer "In13.Cu")
		(net "M_H_CPU0_SB_DQ<29>")
	)
	(gr_poly
		(pts
			(xy 390.664954 -292.51402) (xy 390.664954 -292.46957) (xy 390.464802 -292.46957) (xy 390.464802 -292.51402)
			(xy 390.564878 -292.614096)
		)
		(stroke
			(width 0)
			(type solid)
		)
		(fill yes)
		(layer "In13.Cu")
		(net "M_H_CPU0_SB_DQ<30>")
	)
	(gr_poly
		(pts
			(xy 390.664954 -291.297614) (xy 390.564878 -291.197792) (xy 390.464802 -291.297614) (xy 390.464802 -291.345366)
			(xy 390.664954 -291.345366)
		)
		(stroke
			(width 0)
			(type solid)
		)
		(fill yes)
		(layer "In13.Cu")
		(net "M_H_CPU0_SB_DQS_DN<8>")
	)
	(gr_poly
		(pts
			(xy 390.664954 -290.894262) (xy 390.664954 -290.84651) (xy 390.464802 -290.84651) (xy 390.464802 -290.894262)
			(xy 390.564878 -290.994084)
		)
		(stroke
			(width 0)
			(type solid)
		)
		(fill yes)
		(layer "In13.Cu")
		(net "M_H_CPU0_SB_DQS_DN<3>")
	)
	(gr_poly
		(pts
			(xy 390.664954 -289.677856) (xy 390.564878 -289.57778) (xy 390.464802 -289.677856) (xy 390.464802 -289.722306)
			(xy 390.664954 -289.722306)
		)
		(stroke
			(width 0)
			(type solid)
		)
		(fill yes)
		(layer "In13.Cu")
		(net "M_H_CPU0_SB_DQ<25>")
	)
	(gr_poly
		(pts
			(xy 390.664954 -289.273996) (xy 390.664954 -289.229546) (xy 390.464802 -289.229546) (xy 390.464802 -289.273996)
			(xy 390.564878 -289.374072)
		)
		(stroke
			(width 0)
			(type solid)
		)
		(fill yes)
		(layer "In13.Cu")
		(net "M_H_CPU0_SB_DQ<26>")
	)
	(gr_poly
		(pts
			(xy 390.664954 -288.057844) (xy 390.564878 -287.957768) (xy 390.464802 -288.057844) (xy 390.464802 -288.102294)
			(xy 390.664954 -288.102294)
		)
		(stroke
			(width 0)
			(type solid)
		)
		(fill yes)
		(layer "In13.Cu")
		(net "M_H_CPU0_SB_DQ<21>")
	)
	(gr_poly
		(pts
			(xy 390.664954 -287.654238) (xy 390.664954 -287.609788) (xy 390.464802 -287.609788) (xy 390.464802 -287.654238)
			(xy 390.564878 -287.75406)
		)
		(stroke
			(width 0)
			(type solid)
		)
		(fill yes)
		(layer "In13.Cu")
		(net "M_H_CPU0_SB_DQ<22>")
	)
	(gr_poly
		(pts
			(xy 390.664954 -286.437832) (xy 390.564878 -286.337756) (xy 390.464802 -286.437832) (xy 390.464802 -286.485584)
			(xy 390.664954 -286.485584)
		)
		(stroke
			(width 0)
			(type solid)
		)
		(fill yes)
		(layer "In13.Cu")
		(net "M_H_CPU0_SB_DQS_DN<7>")
	)
	(gr_poly
		(pts
			(xy 390.664954 -286.03448) (xy 390.664954 -285.986728) (xy 390.464802 -285.986728) (xy 390.464802 -286.03448)
			(xy 390.564878 -286.134302)
		)
		(stroke
			(width 0)
			(type solid)
		)
		(fill yes)
		(layer "In13.Cu")
		(net "M_H_CPU0_SB_DQS_DN<2>")
	)
	(gr_poly
		(pts
			(xy 390.664954 -284.818074) (xy 390.564878 -284.717998) (xy 390.464802 -284.818074) (xy 390.464802 -284.862524)
			(xy 390.664954 -284.862524)
		)
		(stroke
			(width 0)
			(type solid)
		)
		(fill yes)
		(layer "In13.Cu")
		(net "M_H_CPU0_SB_DQ<17>")
	)
	(gr_poly
		(pts
			(xy 390.664954 -284.414214) (xy 390.664954 -284.369764) (xy 390.464802 -284.369764) (xy 390.464802 -284.414214)
			(xy 390.564878 -284.51429)
		)
		(stroke
			(width 0)
			(type solid)
		)
		(fill yes)
		(layer "In13.Cu")
		(net "M_H_CPU0_SB_DQ<18>")
	)
	(gr_poly
		(pts
			(xy 390.664954 -283.198062) (xy 390.564878 -283.097986) (xy 390.464802 -283.198062) (xy 390.464802 -283.242512)
			(xy 390.664954 -283.242512)
		)
		(stroke
			(width 0)
			(type solid)
		)
		(fill yes)
		(layer "In13.Cu")
		(net "M_H_CPU0_SB_DQ<13>")
	)
	(gr_poly
		(pts
			(xy 390.664954 -282.794202) (xy 390.664954 -282.749752) (xy 390.464802 -282.749752) (xy 390.464802 -282.794202)
			(xy 390.564878 -282.894278)
		)
		(stroke
			(width 0)
			(type solid)
		)
		(fill yes)
		(layer "In13.Cu")
		(net "M_H_CPU0_SB_DQ<14>")
	)
	(gr_poly
		(pts
			(xy 390.664954 -281.577796) (xy 390.564878 -281.477974) (xy 390.464802 -281.577796) (xy 390.464802 -281.625548)
			(xy 390.664954 -281.625548)
		)
		(stroke
			(width 0)
			(type solid)
		)
		(fill yes)
		(layer "In13.Cu")
		(net "M_H_CPU0_SB_DQS_DN<6>")
	)
	(gr_poly
		(pts
			(xy 390.664954 -281.174444) (xy 390.664954 -281.126692) (xy 390.464802 -281.126692) (xy 390.464802 -281.174444)
			(xy 390.564878 -281.274266)
		)
		(stroke
			(width 0)
			(type solid)
		)
		(fill yes)
		(layer "In13.Cu")
		(net "M_H_CPU0_SB_DQS_DN<1>")
	)
	(gr_poly
		(pts
			(xy 390.664954 -279.958038) (xy 390.564878 -279.857962) (xy 390.464802 -279.958038) (xy 390.464802 -280.002488)
			(xy 390.664954 -280.002488)
		)
		(stroke
			(width 0)
			(type solid)
		)
		(fill yes)
		(layer "In13.Cu")
		(net "M_H_CPU0_SB_DQ<9>")
	)
	(gr_poly
		(pts
			(xy 390.664954 -279.554178) (xy 390.664954 -279.509728) (xy 390.464802 -279.509728) (xy 390.464802 -279.554178)
			(xy 390.564878 -279.654254)
		)
		(stroke
			(width 0)
			(type solid)
		)
		(fill yes)
		(layer "In13.Cu")
		(net "M_H_CPU0_SB_DQ<10>")
	)
	(gr_poly
		(pts
			(xy 390.664954 -278.338026) (xy 390.564878 -278.23795) (xy 390.464802 -278.338026) (xy 390.464802 -278.382476)
			(xy 390.664954 -278.382476)
		)
		(stroke
			(width 0)
			(type solid)
		)
		(fill yes)
		(layer "In13.Cu")
		(net "M_H_CPU0_SB_DQ<5>")
	)
	(gr_poly
		(pts
			(xy 390.664954 -277.934166) (xy 390.664954 -277.889716) (xy 390.464802 -277.889716) (xy 390.464802 -277.934166)
			(xy 390.564878 -278.034242)
		)
		(stroke
			(width 0)
			(type solid)
		)
		(fill yes)
		(layer "In13.Cu")
		(net "M_H_CPU0_SB_DQ<6>")
	)
	(gr_poly
		(pts
			(xy 390.664954 -276.71776) (xy 390.564878 -276.617938) (xy 390.464802 -276.71776) (xy 390.464802 -276.765512)
			(xy 390.664954 -276.765512)
		)
		(stroke
			(width 0)
			(type solid)
		)
		(fill yes)
		(layer "In13.Cu")
		(net "M_H_CPU0_SB_DQS_DN<5>")
	)
	(gr_poly
		(pts
			(xy 390.664954 -276.314408) (xy 390.664954 -276.266656) (xy 390.464802 -276.266656) (xy 390.464802 -276.314408)
			(xy 390.564878 -276.41423)
		)
		(stroke
			(width 0)
			(type solid)
		)
		(fill yes)
		(layer "In13.Cu")
		(net "M_H_CPU0_SB_DQS_DN<0>")
	)
	(gr_poly
		(pts
			(xy 390.664954 -275.098002) (xy 390.564878 -274.997926) (xy 390.464802 -275.098002) (xy 390.464802 -275.142452)
			(xy 390.664954 -275.142452)
		)
		(stroke
			(width 0)
			(type solid)
		)
		(fill yes)
		(layer "In13.Cu")
		(net "M_H_CPU0_SB_DQ<1>")
	)
	(gr_poly
		(pts
			(xy 390.664954 -274.694142) (xy 390.664954 -274.649692) (xy 390.464802 -274.649692) (xy 390.464802 -274.694142)
			(xy 390.564878 -274.794218)
		)
		(stroke
			(width 0)
			(type solid)
		)
		(fill yes)
		(layer "In13.Cu")
		(net "M_H_CPU0_SB_DQ<2>")
	)
	(gr_poly
		(pts
			(xy 390.664954 -273.47799) (xy 390.564878 -273.377914) (xy 390.464802 -273.47799) (xy 390.464802 -273.52244)
			(xy 390.664954 -273.52244)
		)
		(stroke
			(width 0)
			(type solid)
		)
		(fill yes)
		(layer "In13.Cu")
		(net "M_H_CPU0_SB_CB<1>")
	)
	(gr_poly
		(pts
			(xy 390.664954 -273.07413) (xy 390.664954 -273.02968) (xy 390.464802 -273.02968) (xy 390.464802 -273.07413)
			(xy 390.564878 -273.174206)
		)
		(stroke
			(width 0)
			(type solid)
		)
		(fill yes)
		(layer "In13.Cu")
		(net "M_H_CPU0_SB_CB<2>")
	)
	(gr_poly
		(pts
			(xy 390.664954 -271.857724) (xy 390.564878 -271.757902) (xy 390.464802 -271.857724) (xy 390.464802 -271.905476)
			(xy 390.664954 -271.905476)
		)
		(stroke
			(width 0)
			(type solid)
		)
		(fill yes)
		(layer "In13.Cu")
		(net "M_H_CPU0_SB_DQS_DN<4>")
	)
	(gr_poly
		(pts
			(xy 390.664954 -271.454372) (xy 390.664954 -271.40662) (xy 390.464802 -271.40662) (xy 390.464802 -271.454372)
			(xy 390.564878 -271.554194)
		)
		(stroke
			(width 0)
			(type solid)
		)
		(fill yes)
		(layer "In13.Cu")
		(net "M_H_CPU0_SB_DQS_DN<9>")
	)
	(gr_poly
		(pts
			(xy 390.664954 -270.237966) (xy 390.564878 -270.13789) (xy 390.464802 -270.237966) (xy 390.464802 -270.282416)
			(xy 390.664954 -270.282416)
		)
		(stroke
			(width 0)
			(type solid)
		)
		(fill yes)
		(layer "In13.Cu")
		(net "M_H_CPU0_SB_CB<5>")
	)
	(gr_poly
		(pts
			(xy 390.664954 -269.834106) (xy 390.664954 -269.789656) (xy 390.464802 -269.789656) (xy 390.464802 -269.834106)
			(xy 390.564878 -269.934182)
		)
		(stroke
			(width 0)
			(type solid)
		)
		(fill yes)
		(layer "In13.Cu")
		(net "M_H_CPU0_SB_CB<6>")
	)
	(gr_poly
		(pts
			(xy 390.664954 -266.997942) (xy 390.564878 -266.897866) (xy 390.464802 -266.997942) (xy 390.464802 -267.042392)
			(xy 390.664954 -267.042392)
		)
		(stroke
			(width 0)
			(type solid)
		)
		(fill yes)
		(layer "In13.Cu")
		(net "M_H_CPU0_SA_RSP<0>")
	)
	(gr_poly
		(pts
			(xy 390.664954 -266.594082) (xy 390.664954 -266.549632) (xy 390.464802 -266.549632) (xy 390.464802 -266.594082)
			(xy 390.564878 -266.694158)
		)
		(stroke
			(width 0)
			(type solid)
		)
		(fill yes)
		(layer "In13.Cu")
		(net "M_H_CPU0_SB_CS_N<1>")
	)
	(gr_poly
		(pts
			(xy 390.664954 -265.37793) (xy 390.564878 -265.277854) (xy 390.464802 -265.37793) (xy 390.464802 -265.42238)
			(xy 390.664954 -265.42238)
		)
		(stroke
			(width 0)
			(type solid)
		)
		(fill yes)
		(layer "In13.Cu")
		(net "M_H_CPU0_SB_PAR")
	)
	(gr_poly
		(pts
			(xy 390.664954 -263.757918) (xy 390.564878 -263.657842) (xy 390.464802 -263.757918) (xy 390.464802 -263.802368)
			(xy 390.664954 -263.802368)
		)
		(stroke
			(width 0)
			(type solid)
		)
		(fill yes)
		(layer "In13.Cu")
		(net "M_H_CPU0_SB_CA<4>")
	)
	(gr_poly
		(pts
			(xy 390.664954 -263.354058) (xy 390.664954 -263.309608) (xy 390.464802 -263.309608) (xy 390.464802 -263.354058)
			(xy 390.564878 -263.454134)
		)
		(stroke
			(width 0)
			(type solid)
		)
		(fill yes)
		(layer "In13.Cu")
		(net "M_H_CPU0_SB_CA<3>")
	)
	(gr_poly
		(pts
			(xy 390.664954 -262.137906) (xy 390.564878 -262.03783) (xy 390.464802 -262.137906) (xy 390.464802 -262.182356)
			(xy 390.664954 -262.182356)
		)
		(stroke
			(width 0)
			(type solid)
		)
		(fill yes)
		(layer "In13.Cu")
		(net "M_H_CPU0_SB_CA<0>")
	)
	(gr_poly
		(pts
			(xy 390.75487 -228.744018) (xy 390.716262 -228.72192) (xy 390.57961 -228.758496) (xy 390.616186 -228.895148)
			(xy 390.654794 -228.917246)
		)
		(stroke
			(width 0)
			(type solid)
		)
		(fill yes)
		(layer "In13.Cu")
		(net "M_H_CPU0_SA_DQ<5>")
	)
	(gr_poly
		(pts
			(xy 390.75487 -227.124006) (xy 390.716262 -227.101908) (xy 390.57961 -227.138484) (xy 390.616186 -227.275136)
			(xy 390.654794 -227.297234)
		)
		(stroke
			(width 0)
			(type solid)
		)
		(fill yes)
		(layer "In13.Cu")
		(net "M_H_CPU0_SA_DQ<4>")
	)
	(gr_poly
		(pts
			(xy 390.811258 -236.991906) (xy 390.811258 -236.944154) (xy 390.611106 -236.944154) (xy 390.611106 -236.991906)
			(xy 390.711182 -237.091982)
		)
		(stroke
			(width 0)
			(type solid)
		)
		(fill yes)
		(layer "In13.Cu")
		(net "M_H_CPU0_SA_DQS_DN<2>")
	)
	(gr_poly
		(pts
			(xy 390.83488 -256.432558) (xy 390.83488 -256.384806) (xy 390.634728 -256.384806) (xy 390.634728 -256.432558)
			(xy 390.734804 -256.53238)
		)
		(stroke
			(width 0)
			(type solid)
		)
		(fill yes)
		(layer "In13.Cu")
		(net "M_H_CPU0_CLK_DN<0>")
	)
	(gr_poly
		(pts
			(xy 390.83488 -255.216152) (xy 390.734804 -255.116076) (xy 390.634728 -255.216152) (xy 390.634728 -255.260602)
			(xy 390.83488 -255.260602)
		)
		(stroke
			(width 0)
			(type solid)
		)
		(fill yes)
		(layer "In13.Cu")
		(net "M_H_CPU0_SA_CA<6>")
	)
	(gr_poly
		(pts
			(xy 390.83488 -254.812292) (xy 390.83488 -254.767842) (xy 390.634728 -254.767842) (xy 390.634728 -254.812292)
			(xy 390.734804 -254.912368)
		)
		(stroke
			(width 0)
			(type solid)
		)
		(fill yes)
		(layer "In13.Cu")
		(net "M_H_CPU0_SA_CA<5>")
	)
	(gr_poly
		(pts
			(xy 390.83488 -253.59614) (xy 390.734804 -253.496064) (xy 390.634728 -253.59614) (xy 390.634728 -253.64059)
			(xy 390.83488 -253.64059)
		)
		(stroke
			(width 0)
			(type solid)
		)
		(fill yes)
		(layer "In13.Cu")
		(net "M_H_CPU0_SA_CA<2>")
	)
	(gr_poly
		(pts
			(xy 390.83488 -253.19228) (xy 390.83488 -253.14783) (xy 390.634728 -253.14783) (xy 390.634728 -253.19228)
			(xy 390.734804 -253.292356)
		)
		(stroke
			(width 0)
			(type solid)
		)
		(fill yes)
		(layer "In13.Cu")
		(net "M_H_CPU0_SA_CA<1>")
	)
	(gr_poly
		(pts
			(xy 390.83488 -251.976128) (xy 390.734804 -251.876052) (xy 390.634728 -251.976128) (xy 390.634728 -252.020578)
			(xy 390.83488 -252.020578)
		)
		(stroke
			(width 0)
			(type solid)
		)
		(fill yes)
		(layer "In13.Cu")
		(net "M_H_CPU0_SA_CS_N<1>")
	)
	(gr_poly
		(pts
			(xy 390.83488 -250.356116) (xy 390.734804 -250.25604) (xy 390.634728 -250.356116) (xy 390.634728 -250.400566)
			(xy 390.83488 -250.400566)
		)
		(stroke
			(width 0)
			(type solid)
		)
		(fill yes)
		(layer "In13.Cu")
		(net "M_H_CPU0_ALERT_R_N")
	)
	(gr_poly
		(pts
			(xy 390.83488 -248.736104) (xy 390.734804 -248.636028) (xy 390.634728 -248.736104) (xy 390.634728 -248.780554)
			(xy 390.83488 -248.780554)
		)
		(stroke
			(width 0)
			(type solid)
		)
		(fill yes)
		(layer "In13.Cu")
		(net "M_H_CPU0_SA_CB<5>")
	)
	(gr_poly
		(pts
			(xy 390.83488 -248.332244) (xy 390.83488 -248.287794) (xy 390.634728 -248.287794) (xy 390.634728 -248.332244)
			(xy 390.734804 -248.43232)
		)
		(stroke
			(width 0)
			(type solid)
		)
		(fill yes)
		(layer "In13.Cu")
		(net "M_H_CPU0_SA_CB<6>")
	)
	(gr_poly
		(pts
			(xy 390.83488 -247.115838) (xy 390.734804 -247.016016) (xy 390.634728 -247.115838) (xy 390.634728 -247.16359)
			(xy 390.83488 -247.16359)
		)
		(stroke
			(width 0)
			(type solid)
		)
		(fill yes)
		(layer "In13.Cu")
		(net "M_H_CPU0_SA_DQS_DN<9>")
	)
	(gr_poly
		(pts
			(xy 390.83488 -246.712486) (xy 390.83488 -246.664734) (xy 390.634728 -246.664734) (xy 390.634728 -246.712486)
			(xy 390.734804 -246.812308)
		)
		(stroke
			(width 0)
			(type solid)
		)
		(fill yes)
		(layer "In13.Cu")
		(net "M_H_CPU0_SA_DQS_DN<4>")
	)
	(gr_poly
		(pts
			(xy 390.83488 -245.49608) (xy 390.734804 -245.396004) (xy 390.634728 -245.49608) (xy 390.634728 -245.54053)
			(xy 390.83488 -245.54053)
		)
		(stroke
			(width 0)
			(type solid)
		)
		(fill yes)
		(layer "In13.Cu")
		(net "M_H_CPU0_SA_CB<1>")
	)
	(gr_poly
		(pts
			(xy 390.83488 -245.09222) (xy 390.83488 -245.04777) (xy 390.634728 -245.04777) (xy 390.634728 -245.09222)
			(xy 390.734804 -245.192296)
		)
		(stroke
			(width 0)
			(type solid)
		)
		(fill yes)
		(layer "In13.Cu")
		(net "M_H_CPU0_SA_CB<2>")
	)
	(gr_poly
		(pts
			(xy 390.83488 -243.876068) (xy 390.734804 -243.775992) (xy 390.634728 -243.876068) (xy 390.634728 -243.920518)
			(xy 390.83488 -243.920518)
		)
		(stroke
			(width 0)
			(type solid)
		)
		(fill yes)
		(layer "In13.Cu")
		(net "M_H_CPU0_SA_DQ<29>")
	)
	(gr_poly
		(pts
			(xy 390.83488 -243.472208) (xy 390.83488 -243.427758) (xy 390.634728 -243.427758) (xy 390.634728 -243.472208)
			(xy 390.734804 -243.572284)
		)
		(stroke
			(width 0)
			(type solid)
		)
		(fill yes)
		(layer "In13.Cu")
		(net "M_H_CPU0_SA_DQ<30>")
	)
	(gr_poly
		(pts
			(xy 390.83488 -242.255802) (xy 390.734804 -242.15598) (xy 390.634728 -242.255802) (xy 390.634728 -242.303554)
			(xy 390.83488 -242.303554)
		)
		(stroke
			(width 0)
			(type solid)
		)
		(fill yes)
		(layer "In13.Cu")
		(net "M_H_CPU0_SA_DQS_DN<8>")
	)
	(gr_poly
		(pts
			(xy 390.83488 -241.85245) (xy 390.83488 -241.804698) (xy 390.634728 -241.804698) (xy 390.634728 -241.85245)
			(xy 390.734804 -241.952272)
		)
		(stroke
			(width 0)
			(type solid)
		)
		(fill yes)
		(layer "In13.Cu")
		(net "M_H_CPU0_SA_DQS_DN<3>")
	)
	(gr_poly
		(pts
			(xy 390.83488 -240.636044) (xy 390.734804 -240.535968) (xy 390.634728 -240.636044) (xy 390.634728 -240.680494)
			(xy 390.83488 -240.680494)
		)
		(stroke
			(width 0)
			(type solid)
		)
		(fill yes)
		(layer "In13.Cu")
		(net "M_H_CPU0_SA_DQ<25>")
	)
	(gr_poly
		(pts
			(xy 390.83488 -240.232184) (xy 390.83488 -240.187734) (xy 390.634728 -240.187734) (xy 390.634728 -240.232184)
			(xy 390.734804 -240.33226)
		)
		(stroke
			(width 0)
			(type solid)
		)
		(fill yes)
		(layer "In13.Cu")
		(net "M_H_CPU0_SA_DQ<26>")
	)
	(gr_poly
		(pts
			(xy 390.83488 -239.016032) (xy 390.734804 -238.915956) (xy 390.634728 -239.016032) (xy 390.634728 -239.060482)
			(xy 390.83488 -239.060482)
		)
		(stroke
			(width 0)
			(type solid)
		)
		(fill yes)
		(layer "In13.Cu")
		(net "M_H_CPU0_SA_DQ<21>")
	)
	(gr_poly
		(pts
			(xy 390.83488 -238.612172) (xy 390.83488 -238.567722) (xy 390.634728 -238.567722) (xy 390.634728 -238.612172)
			(xy 390.734804 -238.712248)
		)
		(stroke
			(width 0)
			(type solid)
		)
		(fill yes)
		(layer "In13.Cu")
		(net "M_H_CPU0_SA_DQ<22>")
	)
	(gr_poly
		(pts
			(xy 390.83488 -237.395766) (xy 390.734804 -237.295944) (xy 390.634728 -237.395766) (xy 390.634728 -237.443518)
			(xy 390.83488 -237.443518)
		)
		(stroke
			(width 0)
			(type solid)
		)
		(fill yes)
		(layer "In13.Cu")
		(net "M_H_CPU0_SA_DQS_DN<7>")
	)
	(gr_poly
		(pts
			(xy 390.83488 -235.776008) (xy 390.734804 -235.675932) (xy 390.634728 -235.776008) (xy 390.634728 -235.820458)
			(xy 390.83488 -235.820458)
		)
		(stroke
			(width 0)
			(type solid)
		)
		(fill yes)
		(layer "In13.Cu")
		(net "M_H_CPU0_SA_DQ<17>")
	)
	(gr_poly
		(pts
			(xy 390.83488 -235.372148) (xy 390.83488 -235.327698) (xy 390.634728 -235.327698) (xy 390.634728 -235.372148)
			(xy 390.734804 -235.472224)
		)
		(stroke
			(width 0)
			(type solid)
		)
		(fill yes)
		(layer "In13.Cu")
		(net "M_H_CPU0_SA_DQ<18>")
	)
	(gr_poly
		(pts
			(xy 390.83488 -234.155996) (xy 390.734804 -234.05592) (xy 390.634728 -234.155996) (xy 390.634728 -234.200446)
			(xy 390.83488 -234.200446)
		)
		(stroke
			(width 0)
			(type solid)
		)
		(fill yes)
		(layer "In13.Cu")
		(net "M_H_CPU0_SA_DQ<13>")
	)
	(gr_poly
		(pts
			(xy 390.83488 -233.752136) (xy 390.83488 -233.707686) (xy 390.634728 -233.707686) (xy 390.634728 -233.752136)
			(xy 390.734804 -233.852212)
		)
		(stroke
			(width 0)
			(type solid)
		)
		(fill yes)
		(layer "In13.Cu")
		(net "M_H_CPU0_SA_DQ<14>")
	)
	(gr_poly
		(pts
			(xy 390.83488 -232.53573) (xy 390.734804 -232.435908) (xy 390.634728 -232.53573) (xy 390.634728 -232.583482)
			(xy 390.83488 -232.583482)
		)
		(stroke
			(width 0)
			(type solid)
		)
		(fill yes)
		(layer "In13.Cu")
		(net "M_H_CPU0_SA_DQS_DN<6>")
	)
	(gr_poly
		(pts
			(xy 390.83488 -232.132378) (xy 390.83488 -232.084626) (xy 390.634728 -232.084626) (xy 390.634728 -232.132378)
			(xy 390.734804 -232.2322)
		)
		(stroke
			(width 0)
			(type solid)
		)
		(fill yes)
		(layer "In13.Cu")
		(net "M_H_CPU0_SA_DQS_DN<1>")
	)
	(gr_poly
		(pts
			(xy 390.83488 -230.915972) (xy 390.734804 -230.815896) (xy 390.634728 -230.915972) (xy 390.634728 -230.960422)
			(xy 390.83488 -230.960422)
		)
		(stroke
			(width 0)
			(type solid)
		)
		(fill yes)
		(layer "In13.Cu")
		(net "M_H_CPU0_SA_DQ<9>")
	)
	(gr_poly
		(pts
			(xy 390.83488 -230.512366) (xy 390.83488 -230.467916) (xy 390.634728 -230.467916) (xy 390.634728 -230.512366)
			(xy 390.734804 -230.612188)
		)
		(stroke
			(width 0)
			(type solid)
		)
		(fill yes)
		(layer "In13.Cu")
		(net "M_H_CPU0_SA_DQ<10>")
	)
	(gr_poly
		(pts
			(xy 390.88949 -222.951548) (xy 390.852914 -222.814896) (xy 390.81456 -222.792798) (xy 390.714484 -222.966026)
			(xy 390.752838 -222.988124)
		)
		(stroke
			(width 0)
			(type solid)
		)
		(fill yes)
		(layer "In13.Cu")
		(net "M_H_CPU0_SA_DQ<3>")
	)
	(gr_poly
		(pts
			(xy 390.889998 -229.430072) (xy 390.853422 -229.29342) (xy 390.814814 -229.271322) (xy 390.714738 -229.44455)
			(xy 390.753346 -229.466648)
		)
		(stroke
			(width 0)
			(type solid)
		)
		(fill yes)
		(layer "In13.Cu")
		(net "M_H_CPU0_SA_DQ<7>")
	)
	(gr_poly
		(pts
			(xy 390.889998 -227.81006) (xy 390.853422 -227.673408) (xy 390.814814 -227.65131) (xy 390.714738 -227.824538)
			(xy 390.753346 -227.846636)
		)
		(stroke
			(width 0)
			(type solid)
		)
		(fill yes)
		(layer "In13.Cu")
		(net "M_H_CPU0_SA_DQ<6>")
	)
	(gr_poly
		(pts
			(xy 391.134854 -293.324026) (xy 391.134854 -293.279576) (xy 390.934702 -293.279576) (xy 390.934702 -293.324026)
			(xy 391.034778 -293.424102)
		)
		(stroke
			(width 0)
			(type solid)
		)
		(fill yes)
		(layer "In13.Cu")
		(net "M_H_CPU0_SB_DQ<31>")
	)
	(gr_poly
		(pts
			(xy 391.134854 -292.107874) (xy 391.034778 -292.007798) (xy 390.934702 -292.107874) (xy 390.934702 -292.152324)
			(xy 391.134854 -292.152324)
		)
		(stroke
			(width 0)
			(type solid)
		)
		(fill yes)
		(layer "In13.Cu")
		(net "M_H_CPU0_SB_DQ<28>")
	)
	(gr_poly
		(pts
			(xy 391.134854 -291.704268) (xy 391.134854 -291.656516) (xy 390.934702 -291.656516) (xy 390.934702 -291.704268)
			(xy 391.034778 -291.80409)
		)
		(stroke
			(width 0)
			(type solid)
		)
		(fill yes)
		(layer "In13.Cu")
		(net "M_H_CPU0_SB_DQS_DP<8>")
	)
	(gr_poly
		(pts
			(xy 391.134854 -290.487608) (xy 391.034778 -290.387786) (xy 390.934702 -290.487608) (xy 390.934702 -290.53536)
			(xy 391.134854 -290.53536)
		)
		(stroke
			(width 0)
			(type solid)
		)
		(fill yes)
		(layer "In13.Cu")
		(net "M_H_CPU0_SB_DQS_DP<3>")
	)
	(gr_poly
		(pts
			(xy 391.134854 -290.084002) (xy 391.134854 -290.039552) (xy 390.934702 -290.039552) (xy 390.934702 -290.084002)
			(xy 391.034778 -290.184078)
		)
		(stroke
			(width 0)
			(type solid)
		)
		(fill yes)
		(layer "In13.Cu")
		(net "M_H_CPU0_SB_DQ<27>")
	)
	(gr_poly
		(pts
			(xy 391.134854 -288.86785) (xy 391.034778 -288.767774) (xy 390.934702 -288.86785) (xy 390.934702 -288.9123)
			(xy 391.134854 -288.9123)
		)
		(stroke
			(width 0)
			(type solid)
		)
		(fill yes)
		(layer "In13.Cu")
		(net "M_H_CPU0_SB_DQ<24>")
	)
	(gr_poly
		(pts
			(xy 391.134854 -288.464244) (xy 391.134854 -288.419794) (xy 390.934702 -288.419794) (xy 390.934702 -288.464244)
			(xy 391.034778 -288.56432)
		)
		(stroke
			(width 0)
			(type solid)
		)
		(fill yes)
		(layer "In13.Cu")
		(net "M_H_CPU0_SB_DQ<23>")
	)
	(gr_poly
		(pts
			(xy 391.134854 -287.247838) (xy 391.034778 -287.148016) (xy 390.934702 -287.247838) (xy 390.934702 -287.292288)
			(xy 391.134854 -287.292288)
		)
		(stroke
			(width 0)
			(type solid)
		)
		(fill yes)
		(layer "In13.Cu")
		(net "M_H_CPU0_SB_DQ<20>")
	)
	(gr_poly
		(pts
			(xy 391.134854 -286.844232) (xy 391.134854 -286.79648) (xy 390.934702 -286.79648) (xy 390.934702 -286.844232)
			(xy 391.034778 -286.944308)
		)
		(stroke
			(width 0)
			(type solid)
		)
		(fill yes)
		(layer "In13.Cu")
		(net "M_H_CPU0_SB_DQS_DP<7>")
	)
	(gr_poly
		(pts
			(xy 391.134854 -285.627826) (xy 391.034778 -285.528004) (xy 390.934702 -285.627826) (xy 390.934702 -285.675578)
			(xy 391.134854 -285.675578)
		)
		(stroke
			(width 0)
			(type solid)
		)
		(fill yes)
		(layer "In13.Cu")
		(net "M_H_CPU0_SB_DQS_DP<2>")
	)
	(gr_poly
		(pts
			(xy 391.134854 -285.22422) (xy 391.134854 -285.17977) (xy 390.934702 -285.17977) (xy 390.934702 -285.22422)
			(xy 391.034778 -285.324296)
		)
		(stroke
			(width 0)
			(type solid)
		)
		(fill yes)
		(layer "In13.Cu")
		(net "M_H_CPU0_SB_DQ<19>")
	)
	(gr_poly
		(pts
			(xy 391.134854 -284.008068) (xy 391.034778 -283.907992) (xy 390.934702 -284.008068) (xy 390.934702 -284.052518)
			(xy 391.134854 -284.052518)
		)
		(stroke
			(width 0)
			(type solid)
		)
		(fill yes)
		(layer "In13.Cu")
		(net "M_H_CPU0_SB_DQ<16>")
	)
	(gr_poly
		(pts
			(xy 391.134854 -283.604208) (xy 391.134854 -283.559758) (xy 390.934702 -283.559758) (xy 390.934702 -283.604208)
			(xy 391.034778 -283.704284)
		)
		(stroke
			(width 0)
			(type solid)
		)
		(fill yes)
		(layer "In13.Cu")
		(net "M_H_CPU0_SB_DQ<15>")
	)
	(gr_poly
		(pts
			(xy 391.134854 -282.388056) (xy 391.034778 -282.28798) (xy 390.934702 -282.388056) (xy 390.934702 -282.432506)
			(xy 391.134854 -282.432506)
		)
		(stroke
			(width 0)
			(type solid)
		)
		(fill yes)
		(layer "In13.Cu")
		(net "M_H_CPU0_SB_DQ<12>")
	)
	(gr_poly
		(pts
			(xy 391.134854 -281.98445) (xy 391.134854 -281.936698) (xy 390.934702 -281.936698) (xy 390.934702 -281.98445)
			(xy 391.034778 -282.084272)
		)
		(stroke
			(width 0)
			(type solid)
		)
		(fill yes)
		(layer "In13.Cu")
		(net "M_H_CPU0_SB_DQS_DP<6>")
	)
	(gr_poly
		(pts
			(xy 391.134854 -280.76779) (xy 391.034778 -280.667968) (xy 390.934702 -280.76779) (xy 390.934702 -280.815542)
			(xy 391.134854 -280.815542)
		)
		(stroke
			(width 0)
			(type solid)
		)
		(fill yes)
		(layer "In13.Cu")
		(net "M_H_CPU0_SB_DQS_DP<1>")
	)
	(gr_poly
		(pts
			(xy 391.134854 -280.364184) (xy 391.134854 -280.319734) (xy 390.934702 -280.319734) (xy 390.934702 -280.364184)
			(xy 391.034778 -280.46426)
		)
		(stroke
			(width 0)
			(type solid)
		)
		(fill yes)
		(layer "In13.Cu")
		(net "M_H_CPU0_SB_DQ<11>")
	)
	(gr_poly
		(pts
			(xy 391.134854 -279.148032) (xy 391.034778 -279.047956) (xy 390.934702 -279.148032) (xy 390.934702 -279.192482)
			(xy 391.134854 -279.192482)
		)
		(stroke
			(width 0)
			(type solid)
		)
		(fill yes)
		(layer "In13.Cu")
		(net "M_H_CPU0_SB_DQ<8>")
	)
	(gr_poly
		(pts
			(xy 391.134854 -278.744172) (xy 391.134854 -278.699722) (xy 390.934702 -278.699722) (xy 390.934702 -278.744172)
			(xy 391.034778 -278.844248)
		)
		(stroke
			(width 0)
			(type solid)
		)
		(fill yes)
		(layer "In13.Cu")
		(net "M_H_CPU0_SB_DQ<7>")
	)
	(gr_poly
		(pts
			(xy 391.134854 -277.52802) (xy 391.034778 -277.427944) (xy 390.934702 -277.52802) (xy 390.934702 -277.57247)
			(xy 391.134854 -277.57247)
		)
		(stroke
			(width 0)
			(type solid)
		)
		(fill yes)
		(layer "In13.Cu")
		(net "M_H_CPU0_SB_DQ<4>")
	)
	(gr_poly
		(pts
			(xy 391.134854 -277.124414) (xy 391.134854 -277.076662) (xy 390.934702 -277.076662) (xy 390.934702 -277.124414)
			(xy 391.034778 -277.224236)
		)
		(stroke
			(width 0)
			(type solid)
		)
		(fill yes)
		(layer "In13.Cu")
		(net "M_H_CPU0_SB_DQS_DP<5>")
	)
	(gr_poly
		(pts
			(xy 391.134854 -275.907754) (xy 391.034778 -275.807932) (xy 390.934702 -275.907754) (xy 390.934702 -275.955506)
			(xy 391.134854 -275.955506)
		)
		(stroke
			(width 0)
			(type solid)
		)
		(fill yes)
		(layer "In13.Cu")
		(net "M_H_CPU0_SB_DQS_DP<0>")
	)
	(gr_poly
		(pts
			(xy 391.134854 -275.504148) (xy 391.134854 -275.459698) (xy 390.934702 -275.459698) (xy 390.934702 -275.504148)
			(xy 391.034778 -275.604224)
		)
		(stroke
			(width 0)
			(type solid)
		)
		(fill yes)
		(layer "In13.Cu")
		(net "M_H_CPU0_SB_DQ<3>")
	)
	(gr_poly
		(pts
			(xy 391.134854 -274.287996) (xy 391.034778 -274.18792) (xy 390.934702 -274.287996) (xy 390.934702 -274.332446)
			(xy 391.134854 -274.332446)
		)
		(stroke
			(width 0)
			(type solid)
		)
		(fill yes)
		(layer "In13.Cu")
		(net "M_H_CPU0_SB_DQ<0>")
	)
	(gr_poly
		(pts
			(xy 391.134854 -273.884136) (xy 391.134854 -273.839686) (xy 390.934702 -273.839686) (xy 390.934702 -273.884136)
			(xy 391.034778 -273.984212)
		)
		(stroke
			(width 0)
			(type solid)
		)
		(fill yes)
		(layer "In13.Cu")
		(net "M_H_CPU0_SB_CB<3>")
	)
	(gr_poly
		(pts
			(xy 391.134854 -272.667984) (xy 391.034778 -272.567908) (xy 390.934702 -272.667984) (xy 390.934702 -272.712434)
			(xy 391.134854 -272.712434)
		)
		(stroke
			(width 0)
			(type solid)
		)
		(fill yes)
		(layer "In13.Cu")
		(net "M_H_CPU0_SB_CB<0>")
	)
	(gr_poly
		(pts
			(xy 391.134854 -272.264378) (xy 391.134854 -272.216626) (xy 390.934702 -272.216626) (xy 390.934702 -272.264378)
			(xy 391.034778 -272.3642)
		)
		(stroke
			(width 0)
			(type solid)
		)
		(fill yes)
		(layer "In13.Cu")
		(net "M_H_CPU0_SB_DQS_DP<4>")
	)
	(gr_poly
		(pts
			(xy 391.134854 -271.047718) (xy 391.034778 -270.947896) (xy 390.934702 -271.047718) (xy 390.934702 -271.09547)
			(xy 391.134854 -271.09547)
		)
		(stroke
			(width 0)
			(type solid)
		)
		(fill yes)
		(layer "In13.Cu")
		(net "M_H_CPU0_SB_DQS_DP<9>")
	)
	(gr_poly
		(pts
			(xy 391.134854 -270.644112) (xy 391.134854 -270.599662) (xy 390.934702 -270.599662) (xy 390.934702 -270.644112)
			(xy 391.034778 -270.744188)
		)
		(stroke
			(width 0)
			(type solid)
		)
		(fill yes)
		(layer "In13.Cu")
		(net "M_H_CPU0_SB_CB<7>")
	)
	(gr_poly
		(pts
			(xy 391.134854 -269.42796) (xy 391.034778 -269.327884) (xy 390.934702 -269.42796) (xy 390.934702 -269.47241)
			(xy 391.134854 -269.47241)
		)
		(stroke
			(width 0)
			(type solid)
		)
		(fill yes)
		(layer "In13.Cu")
		(net "M_H_CPU0_SB_CB<4>")
	)
	(gr_poly
		(pts
			(xy 391.134854 -267.807948) (xy 391.034778 -267.707872) (xy 390.934702 -267.807948) (xy 390.934702 -267.852398)
			(xy 391.134854 -267.852398)
		)
		(stroke
			(width 0)
			(type solid)
		)
		(fill yes)
		(layer "In13.Cu")
		(net "M_H_CPU0_SB_RSP<0>")
	)
	(gr_poly
		(pts
			(xy 391.134854 -265.784076) (xy 391.134854 -265.739626) (xy 390.934702 -265.739626) (xy 390.934702 -265.784076)
			(xy 391.034778 -265.884152)
		)
		(stroke
			(width 0)
			(type solid)
		)
		(fill yes)
		(layer "In13.Cu")
		(net "M_H_CPU0_SB_CS_N<0>")
	)
	(gr_poly
		(pts
			(xy 391.134854 -264.567924) (xy 391.034778 -264.467848) (xy 390.934702 -264.567924) (xy 390.934702 -264.612374)
			(xy 391.134854 -264.612374)
		)
		(stroke
			(width 0)
			(type solid)
		)
		(fill yes)
		(layer "In13.Cu")
		(net "M_H_CPU0_SB_CA<6>")
	)
	(gr_poly
		(pts
			(xy 391.134854 -264.164064) (xy 391.134854 -264.119614) (xy 390.934702 -264.119614) (xy 390.934702 -264.164064)
			(xy 391.034778 -264.26414)
		)
		(stroke
			(width 0)
			(type solid)
		)
		(fill yes)
		(layer "In13.Cu")
		(net "M_H_CPU0_SB_CA<5>")
	)
	(gr_poly
		(pts
			(xy 391.134854 -262.947912) (xy 391.034778 -262.847836) (xy 390.934702 -262.947912) (xy 390.934702 -262.992362)
			(xy 391.134854 -262.992362)
		)
		(stroke
			(width 0)
			(type solid)
		)
		(fill yes)
		(layer "In13.Cu")
		(net "M_H_CPU0_SB_CA<2>")
	)
	(gr_poly
		(pts
			(xy 391.134854 -262.544052) (xy 391.134854 -262.499602) (xy 390.934702 -262.499602) (xy 390.934702 -262.544052)
			(xy 391.034778 -262.644128)
		)
		(stroke
			(width 0)
			(type solid)
		)
		(fill yes)
		(layer "In13.Cu")
		(net "M_H_CPU0_SB_CA<1>")
	)
	(gr_poly
		(pts
			(xy 391.224008 -229.555294) (xy 391.1854 -229.532942) (xy 391.049002 -229.569518) (xy 391.085578 -229.70617)
			(xy 391.123932 -229.728522)
		)
		(stroke
			(width 0)
			(type solid)
		)
		(fill yes)
		(layer "In13.Cu")
		(net "M_H_CPU0_SA_DQ<8>")
	)
	(gr_poly
		(pts
			(xy 391.224008 -227.935536) (xy 391.1854 -227.913184) (xy 391.049002 -227.94976) (xy 391.085578 -228.086412)
			(xy 391.123932 -228.108764)
		)
		(stroke
			(width 0)
			(type solid)
		)
		(fill yes)
		(layer "In13.Cu")
		(net "M_H_CPU0_SA_DQ<5>")
	)
	(gr_poly
		(pts
			(xy 391.224008 -226.315524) (xy 391.1854 -226.293172) (xy 391.049002 -226.329748) (xy 391.085578 -226.4664)
			(xy 391.123932 -226.488752)
		)
		(stroke
			(width 0)
			(type solid)
		)
		(fill yes)
		(layer "In13.Cu")
		(net "M_H_CPU0_SA_DQ<4>")
	)
	(gr_poly
		(pts
			(xy 391.226802 -224.696274) (xy 391.185654 -224.672652) (xy 391.049002 -224.709228) (xy 391.085578 -224.845626)
			(xy 391.12698 -224.869502)
		)
		(stroke
			(width 0)
			(type solid)
		)
		(fill yes)
		(layer "In13.Cu")
		(net "M_H_CPU0_SA_DQS_DN<5>")
	)
	(gr_poly
		(pts
			(xy 391.226802 -223.076262) (xy 391.185654 -223.05264) (xy 391.049002 -223.089216) (xy 391.085578 -223.225614)
			(xy 391.12698 -223.24949)
		)
		(stroke
			(width 0)
			(type solid)
		)
		(fill yes)
		(layer "In13.Cu")
		(net "M_H_CPU0_SA_DQS_DP<0>")
	)
	(gr_poly
		(pts
			(xy 391.280904 -236.586268) (xy 391.180828 -236.486192) (xy 391.081006 -236.586268) (xy 391.081006 -236.633766)
			(xy 391.280904 -236.633766)
		)
		(stroke
			(width 0)
			(type solid)
		)
		(fill yes)
		(layer "In13.Cu")
		(net "M_H_CPU0_SA_DQS_DP<2>")
	)
	(gr_poly
		(pts
			(xy 391.30478 -256.025904) (xy 391.204704 -255.926082) (xy 391.104628 -256.025904) (xy 391.104628 -256.073656)
			(xy 391.30478 -256.073656)
		)
		(stroke
			(width 0)
			(type solid)
		)
		(fill yes)
		(layer "In13.Cu")
		(net "M_H_CPU0_CLK_DP<0>")
	)
	(gr_poly
		(pts
			(xy 391.30478 -255.622298) (xy 391.30478 -255.577848) (xy 391.104628 -255.577848) (xy 391.104628 -255.622298)
			(xy 391.204704 -255.722374)
		)
		(stroke
			(width 0)
			(type solid)
		)
		(fill yes)
		(layer "In13.Cu")
		(net "M_H_CPU0_SA_PAR")
	)
	(gr_poly
		(pts
			(xy 391.30478 -254.406146) (xy 391.204704 -254.30607) (xy 391.104628 -254.406146) (xy 391.104628 -254.450596)
			(xy 391.30478 -254.450596)
		)
		(stroke
			(width 0)
			(type solid)
		)
		(fill yes)
		(layer "In13.Cu")
		(net "M_H_CPU0_SA_CA<4>")
	)
	(gr_poly
		(pts
			(xy 391.30478 -254.002286) (xy 391.30478 -253.957836) (xy 391.104628 -253.957836) (xy 391.104628 -254.002286)
			(xy 391.204704 -254.102362)
		)
		(stroke
			(width 0)
			(type solid)
		)
		(fill yes)
		(layer "In13.Cu")
		(net "M_H_CPU0_SA_CA<3>")
	)
	(gr_poly
		(pts
			(xy 391.30478 -252.786134) (xy 391.204704 -252.686058) (xy 391.104628 -252.786134) (xy 391.104628 -252.830584)
			(xy 391.30478 -252.830584)
		)
		(stroke
			(width 0)
			(type solid)
		)
		(fill yes)
		(layer "In13.Cu")
		(net "M_H_CPU0_SA_CA<0>")
	)
	(gr_poly
		(pts
			(xy 391.30478 -251.166122) (xy 391.204704 -251.066046) (xy 391.104628 -251.166122) (xy 391.104628 -251.210572)
			(xy 391.30478 -251.210572)
		)
		(stroke
			(width 0)
			(type solid)
		)
		(fill yes)
		(layer "In13.Cu")
		(net "M_H_CPU0_SA_CS_N<0>")
	)
	(gr_poly
		(pts
			(xy 391.30478 -250.762262) (xy 391.30478 -250.717812) (xy 391.104628 -250.717812) (xy 391.104628 -250.762262)
			(xy 391.204704 -250.862338)
		)
		(stroke
			(width 0)
			(type solid)
		)
		(fill yes)
		(layer "In13.Cu")
		(net "M_H_CPU0_RESET_N")
	)
	(gr_poly
		(pts
			(xy 391.30478 -249.14225) (xy 391.30478 -249.0978) (xy 391.104628 -249.0978) (xy 391.104628 -249.14225)
			(xy 391.204704 -249.242326)
		)
		(stroke
			(width 0)
			(type solid)
		)
		(fill yes)
		(layer "In13.Cu")
		(net "M_H_CPU0_SA_CB<7>")
	)
	(gr_poly
		(pts
			(xy 391.30478 -247.926098) (xy 391.204704 -247.826022) (xy 391.104628 -247.926098) (xy 391.104628 -247.970548)
			(xy 391.30478 -247.970548)
		)
		(stroke
			(width 0)
			(type solid)
		)
		(fill yes)
		(layer "In13.Cu")
		(net "M_H_CPU0_SA_CB<4>")
	)
	(gr_poly
		(pts
			(xy 391.30478 -247.522492) (xy 391.30478 -247.47474) (xy 391.104628 -247.47474) (xy 391.104628 -247.522492)
			(xy 391.204704 -247.622314)
		)
		(stroke
			(width 0)
			(type solid)
		)
		(fill yes)
		(layer "In13.Cu")
		(net "M_H_CPU0_SA_DQS_DP<9>")
	)
	(gr_poly
		(pts
			(xy 391.30478 -246.305832) (xy 391.204704 -246.20601) (xy 391.104628 -246.305832) (xy 391.104628 -246.353584)
			(xy 391.30478 -246.353584)
		)
		(stroke
			(width 0)
			(type solid)
		)
		(fill yes)
		(layer "In13.Cu")
		(net "M_H_CPU0_SA_DQS_DP<4>")
	)
	(gr_poly
		(pts
			(xy 391.30478 -245.902226) (xy 391.30478 -245.857776) (xy 391.104628 -245.857776) (xy 391.104628 -245.902226)
			(xy 391.204704 -246.002302)
		)
		(stroke
			(width 0)
			(type solid)
		)
		(fill yes)
		(layer "In13.Cu")
		(net "M_H_CPU0_SA_CB<3>")
	)
	(gr_poly
		(pts
			(xy 391.30478 -244.686074) (xy 391.204704 -244.585998) (xy 391.104628 -244.686074) (xy 391.104628 -244.730524)
			(xy 391.30478 -244.730524)
		)
		(stroke
			(width 0)
			(type solid)
		)
		(fill yes)
		(layer "In13.Cu")
		(net "M_H_CPU0_SA_CB<0>")
	)
	(gr_poly
		(pts
			(xy 391.30478 -244.282214) (xy 391.30478 -244.237764) (xy 391.104628 -244.237764) (xy 391.104628 -244.282214)
			(xy 391.204704 -244.38229)
		)
		(stroke
			(width 0)
			(type solid)
		)
		(fill yes)
		(layer "In13.Cu")
		(net "M_H_CPU0_SA_DQ<31>")
	)
	(gr_poly
		(pts
			(xy 391.30478 -243.066062) (xy 391.204704 -242.965986) (xy 391.104628 -243.066062) (xy 391.104628 -243.110512)
			(xy 391.30478 -243.110512)
		)
		(stroke
			(width 0)
			(type solid)
		)
		(fill yes)
		(layer "In13.Cu")
		(net "M_H_CPU0_SA_DQ<28>")
	)
	(gr_poly
		(pts
			(xy 391.30478 -242.662456) (xy 391.30478 -242.614704) (xy 391.104628 -242.614704) (xy 391.104628 -242.662456)
			(xy 391.204704 -242.762278)
		)
		(stroke
			(width 0)
			(type solid)
		)
		(fill yes)
		(layer "In13.Cu")
		(net "M_H_CPU0_SA_DQS_DP<8>")
	)
	(gr_poly
		(pts
			(xy 391.30478 -241.445796) (xy 391.204704 -241.345974) (xy 391.104628 -241.445796) (xy 391.104628 -241.493548)
			(xy 391.30478 -241.493548)
		)
		(stroke
			(width 0)
			(type solid)
		)
		(fill yes)
		(layer "In13.Cu")
		(net "M_H_CPU0_SA_DQS_DP<3>")
	)
	(gr_poly
		(pts
			(xy 391.30478 -241.04219) (xy 391.30478 -240.99774) (xy 391.104628 -240.99774) (xy 391.104628 -241.04219)
			(xy 391.204704 -241.142266)
		)
		(stroke
			(width 0)
			(type solid)
		)
		(fill yes)
		(layer "In13.Cu")
		(net "M_H_CPU0_SA_DQ<27>")
	)
	(gr_poly
		(pts
			(xy 391.30478 -239.826038) (xy 391.204704 -239.725962) (xy 391.104628 -239.826038) (xy 391.104628 -239.870488)
			(xy 391.30478 -239.870488)
		)
		(stroke
			(width 0)
			(type solid)
		)
		(fill yes)
		(layer "In13.Cu")
		(net "M_H_CPU0_SA_DQ<24>")
	)
	(gr_poly
		(pts
			(xy 391.30478 -239.422178) (xy 391.30478 -239.377728) (xy 391.104628 -239.377728) (xy 391.104628 -239.422178)
			(xy 391.204704 -239.522254)
		)
		(stroke
			(width 0)
			(type solid)
		)
		(fill yes)
		(layer "In13.Cu")
		(net "M_H_CPU0_SA_DQ<23>")
	)
	(gr_poly
		(pts
			(xy 391.30478 -238.206026) (xy 391.204704 -238.10595) (xy 391.104628 -238.206026) (xy 391.104628 -238.250476)
			(xy 391.30478 -238.250476)
		)
		(stroke
			(width 0)
			(type solid)
		)
		(fill yes)
		(layer "In13.Cu")
		(net "M_H_CPU0_SA_DQ<20>")
	)
	(gr_poly
		(pts
			(xy 391.30478 -237.80242) (xy 391.30478 -237.754668) (xy 391.104628 -237.754668) (xy 391.104628 -237.80242)
			(xy 391.204704 -237.902242)
		)
		(stroke
			(width 0)
			(type solid)
		)
		(fill yes)
		(layer "In13.Cu")
		(net "M_H_CPU0_SA_DQS_DP<7>")
	)
	(gr_poly
		(pts
			(xy 391.30478 -236.182154) (xy 391.30478 -236.137704) (xy 391.104628 -236.137704) (xy 391.104628 -236.182154)
			(xy 391.204704 -236.28223)
		)
		(stroke
			(width 0)
			(type solid)
		)
		(fill yes)
		(layer "In13.Cu")
		(net "M_H_CPU0_SA_DQ<19>")
	)
	(gr_poly
		(pts
			(xy 391.30478 -234.966002) (xy 391.204704 -234.865926) (xy 391.104628 -234.966002) (xy 391.104628 -235.010452)
			(xy 391.30478 -235.010452)
		)
		(stroke
			(width 0)
			(type solid)
		)
		(fill yes)
		(layer "In13.Cu")
		(net "M_H_CPU0_SA_DQ<16>")
	)
	(gr_poly
		(pts
			(xy 391.30478 -234.562142) (xy 391.30478 -234.517692) (xy 391.104628 -234.517692) (xy 391.104628 -234.562142)
			(xy 391.204704 -234.662218)
		)
		(stroke
			(width 0)
			(type solid)
		)
		(fill yes)
		(layer "In13.Cu")
		(net "M_H_CPU0_SA_DQ<15>")
	)
	(gr_poly
		(pts
			(xy 391.30478 -233.34599) (xy 391.204704 -233.245914) (xy 391.104628 -233.34599) (xy 391.104628 -233.39044)
			(xy 391.30478 -233.39044)
		)
		(stroke
			(width 0)
			(type solid)
		)
		(fill yes)
		(layer "In13.Cu")
		(net "M_H_CPU0_SA_DQ<12>")
	)
	(gr_poly
		(pts
			(xy 391.30478 -232.942384) (xy 391.30478 -232.894632) (xy 391.104628 -232.894632) (xy 391.104628 -232.942384)
			(xy 391.204704 -233.042206)
		)
		(stroke
			(width 0)
			(type solid)
		)
		(fill yes)
		(layer "In13.Cu")
		(net "M_H_CPU0_SA_DQS_DP<6>")
	)
	(gr_poly
		(pts
			(xy 391.30478 -231.725724) (xy 391.204704 -231.625902) (xy 391.104628 -231.725724) (xy 391.104628 -231.773476)
			(xy 391.30478 -231.773476)
		)
		(stroke
			(width 0)
			(type solid)
		)
		(fill yes)
		(layer "In13.Cu")
		(net "M_H_CPU0_SA_DQS_DP<1>")
	)
	(gr_poly
		(pts
			(xy 391.30478 -231.322372) (xy 391.30478 -231.277922) (xy 391.104628 -231.277922) (xy 391.104628 -231.322372)
			(xy 391.204704 -231.422448)
		)
		(stroke
			(width 0)
			(type solid)
		)
		(fill yes)
		(layer "In13.Cu")
		(net "M_H_CPU0_SA_DQ<11>")
	)
	(gr_poly
		(pts
			(xy 391.360152 -230.239824) (xy 391.323576 -230.103172) (xy 391.284968 -230.081074) (xy 391.184892 -230.254302)
			(xy 391.2235 -230.2764)
		)
		(stroke
			(width 0)
			(type solid)
		)
		(fill yes)
		(layer "In13.Cu")
		(net "M_H_CPU0_SA_DQ<10>")
	)
	(gr_poly
		(pts
			(xy 391.36066 -225.37928) (xy 391.324084 -225.242882) (xy 391.282682 -225.219006) (xy 391.18286 -225.392234)
			(xy 391.224008 -225.415856)
		)
		(stroke
			(width 0)
			(type solid)
		)
		(fill yes)
		(layer "In13.Cu")
		(net "M_H_CPU0_SA_DQS_DP<5>")
	)
	(gr_poly
		(pts
			(xy 391.36066 -223.759268) (xy 391.324084 -223.62287) (xy 391.282682 -223.598994) (xy 391.18286 -223.772222)
			(xy 391.224008 -223.795844)
		)
		(stroke
			(width 0)
			(type solid)
		)
		(fill yes)
		(layer "In13.Cu")
		(net "M_H_CPU0_SA_DQS_DN<0>")
	)
	(gr_poly
		(pts
			(xy 391.360914 -228.618796) (xy 391.324084 -228.482144) (xy 391.28573 -228.459792) (xy 391.185654 -228.63302)
			(xy 391.224262 -228.655372)
		)
		(stroke
			(width 0)
			(type solid)
		)
		(fill yes)
		(layer "In13.Cu")
		(net "M_H_CPU0_SA_DQ<7>")
	)
	(gr_poly
		(pts
			(xy 391.360914 -226.998784) (xy 391.324084 -226.862132) (xy 391.28573 -226.83978) (xy 391.185654 -227.013008)
			(xy 391.224262 -227.03536)
		)
		(stroke
			(width 0)
			(type solid)
		)
		(fill yes)
		(layer "In13.Cu")
		(net "M_H_CPU0_SA_DQ<6>")
	)
	(gr_poly
		(pts
			(xy 391.604754 -292.91788) (xy 391.504678 -292.817804) (xy 391.404602 -292.91788) (xy 391.404602 -292.96233)
			(xy 391.604754 -292.96233)
		)
		(stroke
			(width 0)
			(type solid)
		)
		(fill yes)
		(layer "In13.Cu")
		(net "M_H_CPU0_SB_DQ<29>")
	)
	(gr_poly
		(pts
			(xy 391.604754 -292.51402) (xy 391.604754 -292.46957) (xy 391.404602 -292.46957) (xy 391.404602 -292.51402)
			(xy 391.504678 -292.614096)
		)
		(stroke
			(width 0)
			(type solid)
		)
		(fill yes)
		(layer "In13.Cu")
		(net "M_H_CPU0_SB_DQ<30>")
	)
	(gr_poly
		(pts
			(xy 391.604754 -291.297614) (xy 391.504678 -291.197792) (xy 391.404602 -291.297614) (xy 391.404602 -291.345366)
			(xy 391.604754 -291.345366)
		)
		(stroke
			(width 0)
			(type solid)
		)
		(fill yes)
		(layer "In13.Cu")
		(net "M_H_CPU0_SB_DQS_DN<8>")
	)
	(gr_poly
		(pts
			(xy 391.604754 -290.894262) (xy 391.604754 -290.84651) (xy 391.404602 -290.84651) (xy 391.404602 -290.894262)
			(xy 391.504678 -290.994084)
		)
		(stroke
			(width 0)
			(type solid)
		)
		(fill yes)
		(layer "In13.Cu")
		(net "M_H_CPU0_SB_DQS_DN<3>")
	)
	(gr_poly
		(pts
			(xy 391.604754 -289.677856) (xy 391.504678 -289.57778) (xy 391.404602 -289.677856) (xy 391.404602 -289.722306)
			(xy 391.604754 -289.722306)
		)
		(stroke
			(width 0)
			(type solid)
		)
		(fill yes)
		(layer "In13.Cu")
		(net "M_H_CPU0_SB_DQ<25>")
	)
	(gr_poly
		(pts
			(xy 391.604754 -289.273996) (xy 391.604754 -289.229546) (xy 391.404602 -289.229546) (xy 391.404602 -289.273996)
			(xy 391.504678 -289.374072)
		)
		(stroke
			(width 0)
			(type solid)
		)
		(fill yes)
		(layer "In13.Cu")
		(net "M_H_CPU0_SB_DQ<26>")
	)
	(gr_poly
		(pts
			(xy 391.604754 -288.057844) (xy 391.504678 -287.957768) (xy 391.404602 -288.057844) (xy 391.404602 -288.102294)
			(xy 391.604754 -288.102294)
		)
		(stroke
			(width 0)
			(type solid)
		)
		(fill yes)
		(layer "In13.Cu")
		(net "M_H_CPU0_SB_DQ<21>")
	)
	(gr_poly
		(pts
			(xy 391.604754 -287.654238) (xy 391.604754 -287.609788) (xy 391.404602 -287.609788) (xy 391.404602 -287.654238)
			(xy 391.504678 -287.75406)
		)
		(stroke
			(width 0)
			(type solid)
		)
		(fill yes)
		(layer "In13.Cu")
		(net "M_H_CPU0_SB_DQ<22>")
	)
	(gr_poly
		(pts
			(xy 391.604754 -286.437832) (xy 391.504678 -286.337756) (xy 391.404602 -286.437832) (xy 391.404602 -286.485584)
			(xy 391.604754 -286.485584)
		)
		(stroke
			(width 0)
			(type solid)
		)
		(fill yes)
		(layer "In13.Cu")
		(net "M_H_CPU0_SB_DQS_DN<7>")
	)
	(gr_poly
		(pts
			(xy 391.604754 -286.03448) (xy 391.604754 -285.986728) (xy 391.404602 -285.986728) (xy 391.404602 -286.03448)
			(xy 391.504678 -286.134302)
		)
		(stroke
			(width 0)
			(type solid)
		)
		(fill yes)
		(layer "In13.Cu")
		(net "M_H_CPU0_SB_DQS_DN<2>")
	)
	(gr_poly
		(pts
			(xy 391.604754 -284.818074) (xy 391.504678 -284.717998) (xy 391.404602 -284.818074) (xy 391.404602 -284.862524)
			(xy 391.604754 -284.862524)
		)
		(stroke
			(width 0)
			(type solid)
		)
		(fill yes)
		(layer "In13.Cu")
		(net "M_H_CPU0_SB_DQ<17>")
	)
	(gr_poly
		(pts
			(xy 391.604754 -284.414214) (xy 391.604754 -284.369764) (xy 391.404602 -284.369764) (xy 391.404602 -284.414214)
			(xy 391.504678 -284.51429)
		)
		(stroke
			(width 0)
			(type solid)
		)
		(fill yes)
		(layer "In13.Cu")
		(net "M_H_CPU0_SB_DQ<18>")
	)
	(gr_poly
		(pts
			(xy 391.604754 -283.198062) (xy 391.504678 -283.097986) (xy 391.404602 -283.198062) (xy 391.404602 -283.242512)
			(xy 391.604754 -283.242512)
		)
		(stroke
			(width 0)
			(type solid)
		)
		(fill yes)
		(layer "In13.Cu")
		(net "M_H_CPU0_SB_DQ<13>")
	)
	(gr_poly
		(pts
			(xy 391.604754 -282.794202) (xy 391.604754 -282.749752) (xy 391.404602 -282.749752) (xy 391.404602 -282.794202)
			(xy 391.504678 -282.894278)
		)
		(stroke
			(width 0)
			(type solid)
		)
		(fill yes)
		(layer "In13.Cu")
		(net "M_H_CPU0_SB_DQ<14>")
	)
	(gr_poly
		(pts
			(xy 391.604754 -281.577796) (xy 391.504678 -281.477974) (xy 391.404602 -281.577796) (xy 391.404602 -281.625548)
			(xy 391.604754 -281.625548)
		)
		(stroke
			(width 0)
			(type solid)
		)
		(fill yes)
		(layer "In13.Cu")
		(net "M_H_CPU0_SB_DQS_DN<6>")
	)
	(gr_poly
		(pts
			(xy 391.604754 -281.174444) (xy 391.604754 -281.126692) (xy 391.404602 -281.126692) (xy 391.404602 -281.174444)
			(xy 391.504678 -281.274266)
		)
		(stroke
			(width 0)
			(type solid)
		)
		(fill yes)
		(layer "In13.Cu")
		(net "M_H_CPU0_SB_DQS_DN<1>")
	)
	(gr_poly
		(pts
			(xy 391.604754 -279.958038) (xy 391.504678 -279.857962) (xy 391.404602 -279.958038) (xy 391.404602 -280.002488)
			(xy 391.604754 -280.002488)
		)
		(stroke
			(width 0)
			(type solid)
		)
		(fill yes)
		(layer "In13.Cu")
		(net "M_H_CPU0_SB_DQ<9>")
	)
	(gr_poly
		(pts
			(xy 391.604754 -279.554178) (xy 391.604754 -279.509728) (xy 391.404602 -279.509728) (xy 391.404602 -279.554178)
			(xy 391.504678 -279.654254)
		)
		(stroke
			(width 0)
			(type solid)
		)
		(fill yes)
		(layer "In13.Cu")
		(net "M_H_CPU0_SB_DQ<10>")
	)
	(gr_poly
		(pts
			(xy 391.604754 -278.338026) (xy 391.504678 -278.23795) (xy 391.404602 -278.338026) (xy 391.404602 -278.382476)
			(xy 391.604754 -278.382476)
		)
		(stroke
			(width 0)
			(type solid)
		)
		(fill yes)
		(layer "In13.Cu")
		(net "M_H_CPU0_SB_DQ<5>")
	)
	(gr_poly
		(pts
			(xy 391.604754 -277.934166) (xy 391.604754 -277.889716) (xy 391.404602 -277.889716) (xy 391.404602 -277.934166)
			(xy 391.504678 -278.034242)
		)
		(stroke
			(width 0)
			(type solid)
		)
		(fill yes)
		(layer "In13.Cu")
		(net "M_H_CPU0_SB_DQ<6>")
	)
	(gr_poly
		(pts
			(xy 391.604754 -276.71776) (xy 391.504678 -276.617938) (xy 391.404602 -276.71776) (xy 391.404602 -276.765512)
			(xy 391.604754 -276.765512)
		)
		(stroke
			(width 0)
			(type solid)
		)
		(fill yes)
		(layer "In13.Cu")
		(net "M_H_CPU0_SB_DQS_DN<5>")
	)
	(gr_poly
		(pts
			(xy 391.604754 -276.314408) (xy 391.604754 -276.266656) (xy 391.404602 -276.266656) (xy 391.404602 -276.314408)
			(xy 391.504678 -276.41423)
		)
		(stroke
			(width 0)
			(type solid)
		)
		(fill yes)
		(layer "In13.Cu")
		(net "M_H_CPU0_SB_DQS_DN<0>")
	)
	(gr_poly
		(pts
			(xy 391.604754 -275.098002) (xy 391.504678 -274.997926) (xy 391.404602 -275.098002) (xy 391.404602 -275.142452)
			(xy 391.604754 -275.142452)
		)
		(stroke
			(width 0)
			(type solid)
		)
		(fill yes)
		(layer "In13.Cu")
		(net "M_H_CPU0_SB_DQ<1>")
	)
	(gr_poly
		(pts
			(xy 391.604754 -274.694142) (xy 391.604754 -274.649692) (xy 391.404602 -274.649692) (xy 391.404602 -274.694142)
			(xy 391.504678 -274.794218)
		)
		(stroke
			(width 0)
			(type solid)
		)
		(fill yes)
		(layer "In13.Cu")
		(net "M_H_CPU0_SB_DQ<2>")
	)
	(gr_poly
		(pts
			(xy 391.604754 -273.47799) (xy 391.504678 -273.377914) (xy 391.404602 -273.47799) (xy 391.404602 -273.52244)
			(xy 391.604754 -273.52244)
		)
		(stroke
			(width 0)
			(type solid)
		)
		(fill yes)
		(layer "In13.Cu")
		(net "M_H_CPU0_SB_CB<1>")
	)
	(gr_poly
		(pts
			(xy 391.604754 -273.07413) (xy 391.604754 -273.02968) (xy 391.404602 -273.02968) (xy 391.404602 -273.07413)
			(xy 391.504678 -273.174206)
		)
		(stroke
			(width 0)
			(type solid)
		)
		(fill yes)
		(layer "In13.Cu")
		(net "M_H_CPU0_SB_CB<2>")
	)
	(gr_poly
		(pts
			(xy 391.604754 -271.857724) (xy 391.504678 -271.757902) (xy 391.404602 -271.857724) (xy 391.404602 -271.905476)
			(xy 391.604754 -271.905476)
		)
		(stroke
			(width 0)
			(type solid)
		)
		(fill yes)
		(layer "In13.Cu")
		(net "M_H_CPU0_SB_DQS_DN<4>")
	)
	(gr_poly
		(pts
			(xy 391.604754 -271.454372) (xy 391.604754 -271.40662) (xy 391.404602 -271.40662) (xy 391.404602 -271.454372)
			(xy 391.504678 -271.554194)
		)
		(stroke
			(width 0)
			(type solid)
		)
		(fill yes)
		(layer "In13.Cu")
		(net "M_H_CPU0_SB_DQS_DN<9>")
	)
	(gr_poly
		(pts
			(xy 391.604754 -270.237966) (xy 391.504678 -270.13789) (xy 391.404602 -270.237966) (xy 391.404602 -270.282416)
			(xy 391.604754 -270.282416)
		)
		(stroke
			(width 0)
			(type solid)
		)
		(fill yes)
		(layer "In13.Cu")
		(net "M_H_CPU0_SB_CB<5>")
	)
	(gr_poly
		(pts
			(xy 391.604754 -269.834106) (xy 391.604754 -269.789656) (xy 391.404602 -269.789656) (xy 391.404602 -269.834106)
			(xy 391.504678 -269.934182)
		)
		(stroke
			(width 0)
			(type solid)
		)
		(fill yes)
		(layer "In13.Cu")
		(net "M_H_CPU0_SB_CB<6>")
	)
	(gr_poly
		(pts
			(xy 391.604754 -266.997942) (xy 391.504678 -266.897866) (xy 391.404602 -266.997942) (xy 391.404602 -267.042392)
			(xy 391.604754 -267.042392)
		)
		(stroke
			(width 0)
			(type solid)
		)
		(fill yes)
		(layer "In13.Cu")
		(net "M_H_CPU0_SA_RSP<0>")
	)
	(gr_poly
		(pts
			(xy 391.604754 -266.594082) (xy 391.604754 -266.549632) (xy 391.404602 -266.549632) (xy 391.404602 -266.594082)
			(xy 391.504678 -266.694158)
		)
		(stroke
			(width 0)
			(type solid)
		)
		(fill yes)
		(layer "In13.Cu")
		(net "M_H_CPU0_SB_CS_N<1>")
	)
	(gr_poly
		(pts
			(xy 391.604754 -265.37793) (xy 391.504678 -265.277854) (xy 391.404602 -265.37793) (xy 391.404602 -265.42238)
			(xy 391.604754 -265.42238)
		)
		(stroke
			(width 0)
			(type solid)
		)
		(fill yes)
		(layer "In13.Cu")
		(net "M_H_CPU0_SB_PAR")
	)
	(gr_poly
		(pts
			(xy 391.604754 -263.757918) (xy 391.504678 -263.657842) (xy 391.404602 -263.757918) (xy 391.404602 -263.802368)
			(xy 391.604754 -263.802368)
		)
		(stroke
			(width 0)
			(type solid)
		)
		(fill yes)
		(layer "In13.Cu")
		(net "M_H_CPU0_SB_CA<4>")
	)
	(gr_poly
		(pts
			(xy 391.604754 -263.354058) (xy 391.604754 -263.309608) (xy 391.404602 -263.309608) (xy 391.404602 -263.354058)
			(xy 391.504678 -263.454134)
		)
		(stroke
			(width 0)
			(type solid)
		)
		(fill yes)
		(layer "In13.Cu")
		(net "M_H_CPU0_SB_CA<3>")
	)
	(gr_poly
		(pts
			(xy 391.604754 -262.137906) (xy 391.504678 -262.03783) (xy 391.404602 -262.137906) (xy 391.404602 -262.182356)
			(xy 391.604754 -262.182356)
		)
		(stroke
			(width 0)
			(type solid)
		)
		(fill yes)
		(layer "In13.Cu")
		(net "M_H_CPU0_SB_CA<0>")
	)
	(gr_poly
		(pts
			(xy 391.693908 -225.505518) (xy 391.6553 -225.483166) (xy 391.518902 -225.519742) (xy 391.555478 -225.656394)
			(xy 391.593832 -225.678746)
		)
		(stroke
			(width 0)
			(type solid)
		)
		(fill yes)
		(layer "In13.Cu")
		(net "M_H_CPU0_SA_DQ<4>")
	)
	(gr_poly
		(pts
			(xy 391.694924 -230.36403) (xy 391.656316 -230.341932) (xy 391.519664 -230.378508) (xy 391.55624 -230.51516)
			(xy 391.594848 -230.537258)
		)
		(stroke
			(width 0)
			(type solid)
		)
		(fill yes)
		(layer "In13.Cu")
		(net "M_H_CPU0_SA_DQ<9>")
	)
	(gr_poly
		(pts
			(xy 391.696702 -223.886268) (xy 391.655554 -223.862392) (xy 391.518902 -223.899222) (xy 391.555478 -224.03562)
			(xy 391.59688 -224.059496)
		)
		(stroke
			(width 0)
			(type solid)
		)
		(fill yes)
		(layer "In13.Cu")
		(net "M_H_CPU0_SA_DQS_DN<5>")
	)
	(gr_poly
		(pts
			(xy 391.741152 -235.381038) (xy 391.744962 -235.336842) (xy 391.545826 -235.31957) (xy 391.542016 -235.363766)
			(xy 391.632948 -235.47197)
		)
		(stroke
			(width 0)
			(type solid)
		)
		(fill yes)
		(layer "In13.Cu")
		(net "M_H_CPU0_SA_DQ<18>")
	)
	(gr_poly
		(pts
			(xy 391.768838 -237.395766) (xy 391.668762 -237.295944) (xy 391.568686 -237.395766) (xy 391.568686 -237.443518)
			(xy 391.768838 -237.443518)
		)
		(stroke
			(width 0)
			(type solid)
		)
		(fill yes)
		(layer "In13.Cu")
		(net "M_H_CPU0_SA_DQS_DN<7>")
	)
	(gr_poly
		(pts
			(xy 391.768838 -232.132378) (xy 391.768838 -232.084626) (xy 391.568686 -232.084626) (xy 391.568686 -232.132378)
			(xy 391.668762 -232.2322)
		)
		(stroke
			(width 0)
			(type solid)
		)
		(fill yes)
		(layer "In13.Cu")
		(net "M_H_CPU0_SA_DQS_DN<1>")
	)
	(gr_poly
		(pts
			(xy 391.774934 -256.432558) (xy 391.774934 -256.384806) (xy 391.574782 -256.384806) (xy 391.574782 -256.432558)
			(xy 391.674858 -256.53238)
		)
		(stroke
			(width 0)
			(type solid)
		)
		(fill yes)
		(layer "In13.Cu")
		(net "M_H_CPU0_CLK_DN<0>")
	)
	(gr_poly
		(pts
			(xy 391.78103 -254.812292) (xy 391.78103 -254.767842) (xy 391.580878 -254.767842) (xy 391.580878 -254.812292)
			(xy 391.680954 -254.912368)
		)
		(stroke
			(width 0)
			(type solid)
		)
		(fill yes)
		(layer "In13.Cu")
		(net "M_H_CPU0_SA_CA<5>")
	)
	(gr_poly
		(pts
			(xy 391.78103 -253.19228) (xy 391.78103 -253.14783) (xy 391.580878 -253.14783) (xy 391.580878 -253.19228)
			(xy 391.680954 -253.292356)
		)
		(stroke
			(width 0)
			(type solid)
		)
		(fill yes)
		(layer "In13.Cu")
		(net "M_H_CPU0_SA_CA<1>")
	)
	(gr_poly
		(pts
			(xy 391.78103 -248.332244) (xy 391.78103 -248.287794) (xy 391.580878 -248.287794) (xy 391.580878 -248.332244)
			(xy 391.680954 -248.43232)
		)
		(stroke
			(width 0)
			(type solid)
		)
		(fill yes)
		(layer "In13.Cu")
		(net "M_H_CPU0_SA_CB<6>")
	)
	(gr_poly
		(pts
			(xy 391.78103 -246.712486) (xy 391.78103 -246.664988) (xy 391.580878 -246.664988) (xy 391.580878 -246.712486)
			(xy 391.680954 -246.812562)
		)
		(stroke
			(width 0)
			(type solid)
		)
		(fill yes)
		(layer "In13.Cu")
		(net "M_H_CPU0_SA_DQS_DN<4>")
	)
	(gr_poly
		(pts
			(xy 391.78103 -245.09222) (xy 391.78103 -245.04777) (xy 391.580878 -245.04777) (xy 391.580878 -245.09222)
			(xy 391.680954 -245.192296)
		)
		(stroke
			(width 0)
			(type solid)
		)
		(fill yes)
		(layer "In13.Cu")
		(net "M_H_CPU0_SA_CB<2>")
	)
	(gr_poly
		(pts
			(xy 391.78103 -243.472208) (xy 391.78103 -243.427758) (xy 391.580878 -243.427758) (xy 391.580878 -243.472208)
			(xy 391.680954 -243.572284)
		)
		(stroke
			(width 0)
			(type solid)
		)
		(fill yes)
		(layer "In13.Cu")
		(net "M_H_CPU0_SA_DQ<30>")
	)
	(gr_poly
		(pts
			(xy 391.78103 -241.85245) (xy 391.78103 -241.804952) (xy 391.580878 -241.804952) (xy 391.580878 -241.85245)
			(xy 391.680954 -241.952526)
		)
		(stroke
			(width 0)
			(type solid)
		)
		(fill yes)
		(layer "In13.Cu")
		(net "M_H_CPU0_SA_DQS_DN<3>")
	)
	(gr_poly
		(pts
			(xy 391.78103 -240.232184) (xy 391.78103 -240.187734) (xy 391.580878 -240.187734) (xy 391.580878 -240.232184)
			(xy 391.680954 -240.33226)
		)
		(stroke
			(width 0)
			(type solid)
		)
		(fill yes)
		(layer "In13.Cu")
		(net "M_H_CPU0_SA_DQ<26>")
	)
	(gr_poly
		(pts
			(xy 391.78103 -238.612172) (xy 391.78103 -238.567722) (xy 391.580878 -238.567722) (xy 391.580878 -238.612172)
			(xy 391.680954 -238.712248)
		)
		(stroke
			(width 0)
			(type solid)
		)
		(fill yes)
		(layer "In13.Cu")
		(net "M_H_CPU0_SA_DQ<22>")
	)
	(gr_poly
		(pts
			(xy 391.78103 -233.752136) (xy 391.78103 -233.707686) (xy 391.580878 -233.707686) (xy 391.580878 -233.752136)
			(xy 391.680954 -233.852212)
		)
		(stroke
			(width 0)
			(type solid)
		)
		(fill yes)
		(layer "In13.Cu")
		(net "M_H_CPU0_SA_DQ<14>")
	)
	(gr_poly
		(pts
			(xy 391.78357 -255.215898) (xy 391.683494 -255.116076) (xy 391.583672 -255.215898) (xy 391.583672 -255.260348)
			(xy 391.78357 -255.260348)
		)
		(stroke
			(width 0)
			(type solid)
		)
		(fill yes)
		(layer "In13.Cu")
		(net "M_H_CPU0_SA_CA<6>")
	)
	(gr_poly
		(pts
			(xy 391.78357 -253.595886) (xy 391.683494 -253.496064) (xy 391.583672 -253.595886) (xy 391.583672 -253.640336)
			(xy 391.78357 -253.640336)
		)
		(stroke
			(width 0)
			(type solid)
		)
		(fill yes)
		(layer "In13.Cu")
		(net "M_H_CPU0_SA_CA<2>")
	)
	(gr_poly
		(pts
			(xy 391.78357 -251.975874) (xy 391.683494 -251.876052) (xy 391.583672 -251.975874) (xy 391.583672 -252.020324)
			(xy 391.78357 -252.020324)
		)
		(stroke
			(width 0)
			(type solid)
		)
		(fill yes)
		(layer "In13.Cu")
		(net "M_H_CPU0_SA_CS_N<1>")
	)
	(gr_poly
		(pts
			(xy 391.78357 -250.355862) (xy 391.683494 -250.25604) (xy 391.583672 -250.355862) (xy 391.583672 -250.400312)
			(xy 391.78357 -250.400312)
		)
		(stroke
			(width 0)
			(type solid)
		)
		(fill yes)
		(layer "In13.Cu")
		(net "M_H_CPU0_ALERT_R_N")
	)
	(gr_poly
		(pts
			(xy 391.78357 -248.73585) (xy 391.683494 -248.636028) (xy 391.583672 -248.73585) (xy 391.583672 -248.7803)
			(xy 391.78357 -248.7803)
		)
		(stroke
			(width 0)
			(type solid)
		)
		(fill yes)
		(layer "In13.Cu")
		(net "M_H_CPU0_SA_CB<5>")
	)
	(gr_poly
		(pts
			(xy 391.78357 -247.115584) (xy 391.683494 -247.015762) (xy 391.583672 -247.115584) (xy 391.583672 -247.163336)
			(xy 391.78357 -247.163336)
		)
		(stroke
			(width 0)
			(type solid)
		)
		(fill yes)
		(layer "In13.Cu")
		(net "M_H_CPU0_SA_DQS_DN<9>")
	)
	(gr_poly
		(pts
			(xy 391.78357 -245.495826) (xy 391.683494 -245.396004) (xy 391.583672 -245.495826) (xy 391.583672 -245.540276)
			(xy 391.78357 -245.540276)
		)
		(stroke
			(width 0)
			(type solid)
		)
		(fill yes)
		(layer "In13.Cu")
		(net "M_H_CPU0_SA_CB<1>")
	)
	(gr_poly
		(pts
			(xy 391.78357 -243.875814) (xy 391.683494 -243.775738) (xy 391.583672 -243.875814) (xy 391.583672 -243.920264)
			(xy 391.78357 -243.920264)
		)
		(stroke
			(width 0)
			(type solid)
		)
		(fill yes)
		(layer "In13.Cu")
		(net "M_H_CPU0_SA_DQ<29>")
	)
	(gr_poly
		(pts
			(xy 391.78357 -242.255548) (xy 391.683494 -242.155726) (xy 391.583672 -242.255548) (xy 391.583672 -242.3033)
			(xy 391.78357 -242.3033)
		)
		(stroke
			(width 0)
			(type solid)
		)
		(fill yes)
		(layer "In13.Cu")
		(net "M_H_CPU0_SA_DQS_DN<8>")
	)
	(gr_poly
		(pts
			(xy 391.78357 -240.63579) (xy 391.683494 -240.535968) (xy 391.583672 -240.63579) (xy 391.583672 -240.68024)
			(xy 391.78357 -240.68024)
		)
		(stroke
			(width 0)
			(type solid)
		)
		(fill yes)
		(layer "In13.Cu")
		(net "M_H_CPU0_SA_DQ<25>")
	)
	(gr_poly
		(pts
			(xy 391.78357 -239.015778) (xy 391.683494 -238.915702) (xy 391.583672 -239.015778) (xy 391.583672 -239.060228)
			(xy 391.78357 -239.060228)
		)
		(stroke
			(width 0)
			(type solid)
		)
		(fill yes)
		(layer "In13.Cu")
		(net "M_H_CPU0_SA_DQ<21>")
	)
	(gr_poly
		(pts
			(xy 391.78357 -235.775754) (xy 391.683494 -235.675932) (xy 391.583672 -235.775754) (xy 391.583672 -235.820204)
			(xy 391.78357 -235.820204)
		)
		(stroke
			(width 0)
			(type solid)
		)
		(fill yes)
		(layer "In13.Cu")
		(net "M_H_CPU0_SA_DQ<17>")
	)
	(gr_poly
		(pts
			(xy 391.78611 -236.972348) (xy 391.78611 -236.924596) (xy 391.586212 -236.924596) (xy 391.586212 -236.972348)
			(xy 391.686288 -237.07217)
		)
		(stroke
			(width 0)
			(type solid)
		)
		(fill yes)
		(layer "In13.Cu")
		(net "M_H_CPU0_SA_DQS_DN<2>")
	)
	(gr_poly
		(pts
			(xy 391.83056 -224.569274) (xy 391.793984 -224.432876) (xy 391.752582 -224.409) (xy 391.65276 -224.582228)
			(xy 391.693908 -224.606104)
		)
		(stroke
			(width 0)
			(type solid)
		)
		(fill yes)
		(layer "In13.Cu")
		(net "M_H_CPU0_SA_DQS_DP<5>")
	)
	(gr_poly
		(pts
			(xy 391.83056 -222.949262) (xy 391.793984 -222.812864) (xy 391.752582 -222.788988) (xy 391.65276 -222.962216)
			(xy 391.693908 -222.985838)
		)
		(stroke
			(width 0)
			(type solid)
		)
		(fill yes)
		(layer "In13.Cu")
		(net "M_H_CPU0_SA_DQS_DN<0>")
	)
	(gr_poly
		(pts
			(xy 391.830814 -231.048814) (xy 391.793984 -230.912162) (xy 391.75563 -230.88981) (xy 391.655554 -231.063038)
			(xy 391.694162 -231.08539)
		)
		(stroke
			(width 0)
			(type solid)
		)
		(fill yes)
		(layer "In13.Cu")
		(net "M_H_CPU0_SA_DQ<11>")
	)
	(gr_poly
		(pts
			(xy 391.830814 -226.188778) (xy 391.793984 -226.052126) (xy 391.75563 -226.029774) (xy 391.655554 -226.203002)
			(xy 391.694162 -226.225354)
		)
		(stroke
			(width 0)
			(type solid)
		)
		(fill yes)
		(layer "In13.Cu")
		(net "M_H_CPU0_SA_DQ<6>")
	)
	(gr_poly
		(pts
			(xy 391.993882 -293.874698) (xy 391.893806 -293.70147) (xy 391.855452 -293.723822) (xy 391.818622 -293.860474)
			(xy 391.955274 -293.89705)
		)
		(stroke
			(width 0)
			(type solid)
		)
		(fill yes)
		(layer "In13.Cu")
		(net "M_H_CPU0_SB_DQ<31>")
	)
	(gr_poly
		(pts
			(xy 391.993882 -268.877288) (xy 391.955274 -268.854936) (xy 391.818622 -268.891512) (xy 391.855452 -269.028164)
			(xy 391.893806 -269.050516)
		)
		(stroke
			(width 0)
			(type solid)
		)
		(fill yes)
		(layer "In13.Cu")
		(net "M_H_CPU0_SB_CB<4>")
	)
	(gr_poly
		(pts
			(xy 392.059414 -290.487862) (xy 391.959592 -290.387786) (xy 391.859516 -290.487862) (xy 391.859516 -290.53536)
			(xy 392.059414 -290.53536)
		)
		(stroke
			(width 0)
			(type solid)
		)
		(fill yes)
		(layer "In13.Cu")
		(net "M_H_CPU0_SB_DQS_DP<3>")
	)
	(gr_poly
		(pts
			(xy 392.059414 -285.62808) (xy 391.959592 -285.528004) (xy 391.859516 -285.62808) (xy 391.859516 -285.675578)
			(xy 392.059414 -285.675578)
		)
		(stroke
			(width 0)
			(type solid)
		)
		(fill yes)
		(layer "In13.Cu")
		(net "M_H_CPU0_SB_DQS_DP<2>")
	)
	(gr_poly
		(pts
			(xy 392.059414 -280.768044) (xy 391.959592 -280.667968) (xy 391.859516 -280.768044) (xy 391.859516 -280.815542)
			(xy 392.059414 -280.815542)
		)
		(stroke
			(width 0)
			(type solid)
		)
		(fill yes)
		(layer "In13.Cu")
		(net "M_H_CPU0_SB_DQS_DP<1>")
	)
	(gr_poly
		(pts
			(xy 392.059414 -275.908008) (xy 391.959592 -275.807932) (xy 391.859516 -275.908008) (xy 391.859516 -275.955506)
			(xy 392.059414 -275.955506)
		)
		(stroke
			(width 0)
			(type solid)
		)
		(fill yes)
		(layer "In13.Cu")
		(net "M_H_CPU0_SB_DQS_DP<0>")
	)
	(gr_poly
		(pts
			(xy 392.059414 -271.047972) (xy 391.959592 -270.947896) (xy 391.859516 -271.047972) (xy 391.859516 -271.09547)
			(xy 392.059414 -271.09547)
		)
		(stroke
			(width 0)
			(type solid)
		)
		(fill yes)
		(layer "In13.Cu")
		(net "M_H_CPU0_SB_DQS_DP<9>")
	)
	(gr_poly
		(pts
			(xy 392.0617 -288.868104) (xy 391.961624 -288.768028) (xy 391.861548 -288.868104) (xy 391.861548 -288.912554)
			(xy 392.0617 -288.912554)
		)
		(stroke
			(width 0)
			(type solid)
		)
		(fill yes)
		(layer "In13.Cu")
		(net "M_H_CPU0_SB_DQ<24>")
	)
	(gr_poly
		(pts
			(xy 392.0617 -284.008322) (xy 391.961624 -283.908246) (xy 391.861548 -284.008322) (xy 391.861548 -284.052772)
			(xy 392.0617 -284.052772)
		)
		(stroke
			(width 0)
			(type solid)
		)
		(fill yes)
		(layer "In13.Cu")
		(net "M_H_CPU0_SB_DQ<16>")
	)
	(gr_poly
		(pts
			(xy 392.0617 -282.38831) (xy 391.961624 -282.288234) (xy 391.861548 -282.38831) (xy 391.861548 -282.43276)
			(xy 392.0617 -282.43276)
		)
		(stroke
			(width 0)
			(type solid)
		)
		(fill yes)
		(layer "In13.Cu")
		(net "M_H_CPU0_SB_DQ<12>")
	)
	(gr_poly
		(pts
			(xy 392.0617 -279.148286) (xy 391.961624 -279.04821) (xy 391.861548 -279.148286) (xy 391.861548 -279.192736)
			(xy 392.0617 -279.192736)
		)
		(stroke
			(width 0)
			(type solid)
		)
		(fill yes)
		(layer "In13.Cu")
		(net "M_H_CPU0_SB_DQ<8>")
	)
	(gr_poly
		(pts
			(xy 392.0617 -277.528274) (xy 391.961624 -277.428198) (xy 391.861548 -277.528274) (xy 391.861548 -277.572724)
			(xy 392.0617 -277.572724)
		)
		(stroke
			(width 0)
			(type solid)
		)
		(fill yes)
		(layer "In13.Cu")
		(net "M_H_CPU0_SB_DQ<4>")
	)
	(gr_poly
		(pts
			(xy 392.0617 -274.28825) (xy 391.961624 -274.188174) (xy 391.861548 -274.28825) (xy 391.861548 -274.3327)
			(xy 392.0617 -274.3327)
		)
		(stroke
			(width 0)
			(type solid)
		)
		(fill yes)
		(layer "In13.Cu")
		(net "M_H_CPU0_SB_DQ<0>")
	)
	(gr_poly
		(pts
			(xy 392.0617 -272.668238) (xy 391.961624 -272.568162) (xy 391.861548 -272.668238) (xy 391.861548 -272.712688)
			(xy 392.0617 -272.712688)
		)
		(stroke
			(width 0)
			(type solid)
		)
		(fill yes)
		(layer "In13.Cu")
		(net "M_H_CPU0_SB_CB<0>")
	)
	(gr_poly
		(pts
			(xy 392.0617 -267.808202) (xy 391.961624 -267.708126) (xy 391.861548 -267.808202) (xy 391.861548 -267.852652)
			(xy 392.0617 -267.852652)
		)
		(stroke
			(width 0)
			(type solid)
		)
		(fill yes)
		(layer "In13.Cu")
		(net "M_H_CPU0_SB_RSP<0>")
	)
	(gr_poly
		(pts
			(xy 392.0617 -264.568178) (xy 391.961624 -264.468102) (xy 391.861548 -264.568178) (xy 391.861548 -264.612628)
			(xy 392.0617 -264.612628)
		)
		(stroke
			(width 0)
			(type solid)
		)
		(fill yes)
		(layer "In13.Cu")
		(net "M_H_CPU0_SB_CA<6>")
	)
	(gr_poly
		(pts
			(xy 392.0617 -262.948166) (xy 391.961624 -262.84809) (xy 391.861548 -262.948166) (xy 391.861548 -262.992616)
			(xy 392.0617 -262.992616)
		)
		(stroke
			(width 0)
			(type solid)
		)
		(fill yes)
		(layer "In13.Cu")
		(net "M_H_CPU0_SB_CA<2>")
	)
	(gr_poly
		(pts
			(xy 392.074908 -292.107874) (xy 391.974832 -292.007798) (xy 391.874756 -292.107874) (xy 391.874756 -292.152324)
			(xy 392.074908 -292.152324)
		)
		(stroke
			(width 0)
			(type solid)
		)
		(fill yes)
		(layer "In13.Cu")
		(net "M_H_CPU0_SB_DQ<28>")
	)
	(gr_poly
		(pts
			(xy 392.074908 -291.704268) (xy 392.074908 -291.656516) (xy 391.874756 -291.656516) (xy 391.874756 -291.704268)
			(xy 391.974832 -291.80409)
		)
		(stroke
			(width 0)
			(type solid)
		)
		(fill yes)
		(layer "In13.Cu")
		(net "M_H_CPU0_SB_DQS_DP<8>")
	)
	(gr_poly
		(pts
			(xy 392.074908 -270.644112) (xy 392.074908 -270.599662) (xy 391.874756 -270.599662) (xy 391.874756 -270.644112)
			(xy 391.974832 -270.744188)
		)
		(stroke
			(width 0)
			(type solid)
		)
		(fill yes)
		(layer "In13.Cu")
		(net "M_H_CPU0_SB_CB<7>")
	)
	(gr_poly
		(pts
			(xy 392.081004 -286.844232) (xy 392.081004 -286.796734) (xy 391.881106 -286.796734) (xy 391.881106 -286.844232)
			(xy 391.980928 -286.944308)
		)
		(stroke
			(width 0)
			(type solid)
		)
		(fill yes)
		(layer "In13.Cu")
		(net "M_H_CPU0_SB_DQS_DP<7>")
	)
	(gr_poly
		(pts
			(xy 392.081004 -285.22422) (xy 392.081004 -285.17977) (xy 391.881106 -285.17977) (xy 391.881106 -285.22422)
			(xy 391.980928 -285.324296)
		)
		(stroke
			(width 0)
			(type solid)
		)
		(fill yes)
		(layer "In13.Cu")
		(net "M_H_CPU0_SB_DQ<19>")
	)
	(gr_poly
		(pts
			(xy 392.081004 -283.604208) (xy 392.081004 -283.559758) (xy 391.881106 -283.559758) (xy 391.881106 -283.604208)
			(xy 391.980928 -283.704284)
		)
		(stroke
			(width 0)
			(type solid)
		)
		(fill yes)
		(layer "In13.Cu")
		(net "M_H_CPU0_SB_DQ<15>")
	)
	(gr_poly
		(pts
			(xy 392.081004 -281.98445) (xy 392.081004 -281.936952) (xy 391.881106 -281.936952) (xy 391.881106 -281.98445)
			(xy 391.980928 -282.084526)
		)
		(stroke
			(width 0)
			(type solid)
		)
		(fill yes)
		(layer "In13.Cu")
		(net "M_H_CPU0_SB_DQS_DP<6>")
	)
	(gr_poly
		(pts
			(xy 392.081004 -280.364184) (xy 392.081004 -280.319734) (xy 391.881106 -280.319734) (xy 391.881106 -280.364184)
			(xy 391.980928 -280.46426)
		)
		(stroke
			(width 0)
			(type solid)
		)
		(fill yes)
		(layer "In13.Cu")
		(net "M_H_CPU0_SB_DQ<11>")
	)
	(gr_poly
		(pts
			(xy 392.081004 -278.744172) (xy 392.081004 -278.699722) (xy 391.881106 -278.699722) (xy 391.881106 -278.744172)
			(xy 391.980928 -278.844248)
		)
		(stroke
			(width 0)
			(type solid)
		)
		(fill yes)
		(layer "In13.Cu")
		(net "M_H_CPU0_SB_DQ<7>")
	)
	(gr_poly
		(pts
			(xy 392.081004 -277.124414) (xy 392.081004 -277.076916) (xy 391.881106 -277.076916) (xy 391.881106 -277.124414)
			(xy 391.980928 -277.22449)
		)
		(stroke
			(width 0)
			(type solid)
		)
		(fill yes)
		(layer "In13.Cu")
		(net "M_H_CPU0_SB_DQS_DP<5>")
	)
	(gr_poly
		(pts
			(xy 392.081004 -275.504148) (xy 392.081004 -275.459698) (xy 391.881106 -275.459698) (xy 391.881106 -275.504148)
			(xy 391.980928 -275.604224)
		)
		(stroke
			(width 0)
			(type solid)
		)
		(fill yes)
		(layer "In13.Cu")
		(net "M_H_CPU0_SB_DQ<3>")
	)
	(gr_poly
		(pts
			(xy 392.081004 -273.884136) (xy 392.081004 -273.839686) (xy 391.881106 -273.839686) (xy 391.881106 -273.884136)
			(xy 391.980928 -273.984212)
		)
		(stroke
			(width 0)
			(type solid)
		)
		(fill yes)
		(layer "In13.Cu")
		(net "M_H_CPU0_SB_CB<3>")
	)
	(gr_poly
		(pts
			(xy 392.081004 -272.264378) (xy 392.081004 -272.21688) (xy 391.881106 -272.21688) (xy 391.881106 -272.264378)
			(xy 391.980928 -272.364454)
		)
		(stroke
			(width 0)
			(type solid)
		)
		(fill yes)
		(layer "In13.Cu")
		(net "M_H_CPU0_SB_DQS_DP<4>")
	)
	(gr_poly
		(pts
			(xy 392.081004 -265.784076) (xy 392.081004 -265.739626) (xy 391.881106 -265.739626) (xy 391.881106 -265.784076)
			(xy 391.980928 -265.884152)
		)
		(stroke
			(width 0)
			(type solid)
		)
		(fill yes)
		(layer "In13.Cu")
		(net "M_H_CPU0_SB_CS_N<0>")
	)
	(gr_poly
		(pts
			(xy 392.081004 -264.164064) (xy 392.081004 -264.119614) (xy 391.881106 -264.119614) (xy 391.881106 -264.164064)
			(xy 391.980928 -264.26414)
		)
		(stroke
			(width 0)
			(type solid)
		)
		(fill yes)
		(layer "In13.Cu")
		(net "M_H_CPU0_SB_CA<5>")
	)
	(gr_poly
		(pts
			(xy 392.081004 -262.544052) (xy 392.081004 -262.499602) (xy 391.881106 -262.499602) (xy 391.881106 -262.544052)
			(xy 391.980928 -262.644128)
		)
		(stroke
			(width 0)
			(type solid)
		)
		(fill yes)
		(layer "In13.Cu")
		(net "M_H_CPU0_SB_CA<1>")
	)
	(gr_poly
		(pts
			(xy 392.093958 -293.32809) (xy 392.130534 -293.191438) (xy 391.994136 -293.154862) (xy 391.955528 -293.177214)
			(xy 392.055604 -293.350442)
		)
		(stroke
			(width 0)
			(type solid)
		)
		(fill yes)
		(layer "In13.Cu")
		(net "M_H_CPU0_SB_DQ<29>")
	)
	(gr_poly
		(pts
			(xy 392.130534 -269.560548) (xy 392.093958 -269.423896) (xy 392.055604 -269.401544) (xy 391.955528 -269.574772)
			(xy 391.994136 -269.597124)
		)
		(stroke
			(width 0)
			(type solid)
		)
		(fill yes)
		(layer "In13.Cu")
		(net "M_H_CPU0_SB_CB<6>")
	)
	(gr_poly
		(pts
			(xy 392.164062 -224.695512) (xy 392.125454 -224.67316) (xy 391.988802 -224.709736) (xy 392.025632 -224.846388)
			(xy 392.063986 -224.86874)
		)
		(stroke
			(width 0)
			(type solid)
		)
		(fill yes)
		(layer "In13.Cu")
		(net "M_H_CPU0_SA_DQ<4>")
	)
	(gr_poly
		(pts
			(xy 392.166856 -223.076262) (xy 392.125708 -223.05264) (xy 391.989056 -223.089216) (xy 392.025632 -223.225614)
			(xy 392.067034 -223.24949)
		)
		(stroke
			(width 0)
			(type solid)
		)
		(fill yes)
		(layer "In13.Cu")
		(net "M_H_CPU0_SA_DQS_DN<5>")
	)
	(gr_poly
		(pts
			(xy 392.23696 -255.622552) (xy 392.23696 -255.578102) (xy 392.037062 -255.578102) (xy 392.037062 -255.622552)
			(xy 392.137138 -255.722628)
		)
		(stroke
			(width 0)
			(type solid)
		)
		(fill yes)
		(layer "In13.Cu")
		(net "M_H_CPU0_SA_PAR")
	)
	(gr_poly
		(pts
			(xy 392.23696 -254.00254) (xy 392.23696 -253.95809) (xy 392.037062 -253.95809) (xy 392.037062 -254.00254)
			(xy 392.137138 -254.102616)
		)
		(stroke
			(width 0)
			(type solid)
		)
		(fill yes)
		(layer "In13.Cu")
		(net "M_H_CPU0_SA_CA<3>")
	)
	(gr_poly
		(pts
			(xy 392.23696 -250.762516) (xy 392.23696 -250.718066) (xy 392.037062 -250.718066) (xy 392.037062 -250.762516)
			(xy 392.137138 -250.862338)
		)
		(stroke
			(width 0)
			(type solid)
		)
		(fill yes)
		(layer "In13.Cu")
		(net "M_H_CPU0_RESET_N")
	)
	(gr_poly
		(pts
			(xy 392.23696 -249.142504) (xy 392.23696 -249.098054) (xy 392.037062 -249.098054) (xy 392.037062 -249.142504)
			(xy 392.137138 -249.24258)
		)
		(stroke
			(width 0)
			(type solid)
		)
		(fill yes)
		(layer "In13.Cu")
		(net "M_H_CPU0_SA_CB<7>")
	)
	(gr_poly
		(pts
			(xy 392.23696 -247.522746) (xy 392.23696 -247.474994) (xy 392.037062 -247.474994) (xy 392.037062 -247.522746)
			(xy 392.137138 -247.622568)
		)
		(stroke
			(width 0)
			(type solid)
		)
		(fill yes)
		(layer "In13.Cu")
		(net "M_H_CPU0_SA_DQS_DP<9>")
	)
	(gr_poly
		(pts
			(xy 392.23696 -245.90248) (xy 392.23696 -245.85803) (xy 392.037062 -245.85803) (xy 392.037062 -245.90248)
			(xy 392.137138 -246.002302)
		)
		(stroke
			(width 0)
			(type solid)
		)
		(fill yes)
		(layer "In13.Cu")
		(net "M_H_CPU0_SA_CB<3>")
	)
	(gr_poly
		(pts
			(xy 392.23696 -244.282468) (xy 392.23696 -244.238018) (xy 392.037062 -244.238018) (xy 392.037062 -244.282468)
			(xy 392.137138 -244.382544)
		)
		(stroke
			(width 0)
			(type solid)
		)
		(fill yes)
		(layer "In13.Cu")
		(net "M_H_CPU0_SA_DQ<31>")
	)
	(gr_poly
		(pts
			(xy 392.23696 -241.042444) (xy 392.23696 -240.997994) (xy 392.037062 -240.997994) (xy 392.037062 -241.042444)
			(xy 392.137138 -241.14252)
		)
		(stroke
			(width 0)
			(type solid)
		)
		(fill yes)
		(layer "In13.Cu")
		(net "M_H_CPU0_SA_DQ<27>")
	)
	(gr_poly
		(pts
			(xy 392.23696 -239.422432) (xy 392.23696 -239.377982) (xy 392.037062 -239.377982) (xy 392.037062 -239.422432)
			(xy 392.137138 -239.522508)
		)
		(stroke
			(width 0)
			(type solid)
		)
		(fill yes)
		(layer "In13.Cu")
		(net "M_H_CPU0_SA_DQ<23>")
	)
	(gr_poly
		(pts
			(xy 392.239246 -254.406146) (xy 392.139424 -254.30607) (xy 392.039348 -254.406146) (xy 392.039348 -254.450596)
			(xy 392.239246 -254.450596)
		)
		(stroke
			(width 0)
			(type solid)
		)
		(fill yes)
		(layer "In13.Cu")
		(net "M_H_CPU0_SA_CA<4>")
	)
	(gr_poly
		(pts
			(xy 392.239246 -252.786134) (xy 392.139424 -252.686058) (xy 392.039348 -252.786134) (xy 392.039348 -252.830584)
			(xy 392.239246 -252.830584)
		)
		(stroke
			(width 0)
			(type solid)
		)
		(fill yes)
		(layer "In13.Cu")
		(net "M_H_CPU0_SA_CA<0>")
	)
	(gr_poly
		(pts
			(xy 392.239246 -251.166122) (xy 392.139424 -251.066046) (xy 392.039348 -251.166122) (xy 392.039348 -251.210572)
			(xy 392.239246 -251.210572)
		)
		(stroke
			(width 0)
			(type solid)
		)
		(fill yes)
		(layer "In13.Cu")
		(net "M_H_CPU0_SA_CS_N<0>")
	)
	(gr_poly
		(pts
			(xy 392.239246 -247.926098) (xy 392.139424 -247.826022) (xy 392.039348 -247.926098) (xy 392.039348 -247.970548)
			(xy 392.239246 -247.970548)
		)
		(stroke
			(width 0)
			(type solid)
		)
		(fill yes)
		(layer "In13.Cu")
		(net "M_H_CPU0_SA_CB<4>")
	)
	(gr_poly
		(pts
			(xy 392.239246 -246.305832) (xy 392.139424 -246.205756) (xy 392.039348 -246.305832) (xy 392.039348 -246.35333)
			(xy 392.239246 -246.35333)
		)
		(stroke
			(width 0)
			(type solid)
		)
		(fill yes)
		(layer "In13.Cu")
		(net "M_H_CPU0_SA_DQS_DP<4>")
	)
	(gr_poly
		(pts
			(xy 392.239246 -244.686074) (xy 392.139424 -244.585998) (xy 392.039348 -244.686074) (xy 392.039348 -244.730524)
			(xy 392.239246 -244.730524)
		)
		(stroke
			(width 0)
			(type solid)
		)
		(fill yes)
		(layer "In13.Cu")
		(net "M_H_CPU0_SA_CB<0>")
	)
	(gr_poly
		(pts
			(xy 392.239246 -243.066062) (xy 392.139424 -242.965986) (xy 392.039348 -243.066062) (xy 392.039348 -243.110512)
			(xy 392.239246 -243.110512)
		)
		(stroke
			(width 0)
			(type solid)
		)
		(fill yes)
		(layer "In13.Cu")
		(net "M_H_CPU0_SA_DQ<28>")
	)
	(gr_poly
		(pts
			(xy 392.239246 -241.445796) (xy 392.139424 -241.34572) (xy 392.039348 -241.445796) (xy 392.039348 -241.493294)
			(xy 392.239246 -241.493294)
		)
		(stroke
			(width 0)
			(type solid)
		)
		(fill yes)
		(layer "In13.Cu")
		(net "M_H_CPU0_SA_DQS_DP<3>")
	)
	(gr_poly
		(pts
			(xy 392.239246 -239.826038) (xy 392.139424 -239.725962) (xy 392.039348 -239.826038) (xy 392.039348 -239.870488)
			(xy 392.239246 -239.870488)
		)
		(stroke
			(width 0)
			(type solid)
		)
		(fill yes)
		(layer "In13.Cu")
		(net "M_H_CPU0_SA_DQ<24>")
	)
	(gr_poly
		(pts
			(xy 392.239246 -238.206026) (xy 392.139424 -238.10595) (xy 392.039348 -238.206026) (xy 392.039348 -238.250476)
			(xy 392.239246 -238.250476)
		)
		(stroke
			(width 0)
			(type solid)
		)
		(fill yes)
		(layer "In13.Cu")
		(net "M_H_CPU0_SA_DQ<20>")
	)
	(gr_poly
		(pts
			(xy 392.250676 -237.80242) (xy 392.250676 -237.754668) (xy 392.050778 -237.754668) (xy 392.050778 -237.80242)
			(xy 392.1506 -237.902242)
		)
		(stroke
			(width 0)
			(type solid)
		)
		(fill yes)
		(layer "In13.Cu")
		(net "M_H_CPU0_SA_DQS_DP<7>")
	)
	(gr_poly
		(pts
			(xy 392.25347 -256.02565) (xy 392.153394 -255.925828) (xy 392.053572 -256.02565) (xy 392.053572 -256.073402)
			(xy 392.25347 -256.073402)
		)
		(stroke
			(width 0)
			(type solid)
		)
		(fill yes)
		(layer "In13.Cu")
		(net "M_H_CPU0_CLK_DP<0>")
	)
	(gr_poly
		(pts
			(xy 392.300714 -225.378772) (xy 392.264138 -225.24212) (xy 392.225784 -225.219768) (xy 392.125708 -225.392996)
			(xy 392.164316 -225.415348)
		)
		(stroke
			(width 0)
			(type solid)
		)
		(fill yes)
		(layer "In13.Cu")
		(net "M_H_CPU0_SA_DQ<6>")
	)
	(gr_poly
		(pts
			(xy 392.300714 -223.759268) (xy 392.264138 -223.62287) (xy 392.222736 -223.598994) (xy 392.122914 -223.772222)
			(xy 392.164062 -223.795844)
		)
		(stroke
			(width 0)
			(type solid)
		)
		(fill yes)
		(layer "In13.Cu")
		(net "M_H_CPU0_SA_DQS_DP<5>")
	)
	(gr_poly
		(pts
			(xy 392.463782 -294.684704) (xy 392.363706 -294.511476) (xy 392.325352 -294.533828) (xy 392.288522 -294.67048)
			(xy 392.425174 -294.707056)
		)
		(stroke
			(width 0)
			(type solid)
		)
		(fill yes)
		(layer "In13.Cu")
		(net "M_H_CPU0_SB_DQ<31>")
	)
	(gr_poly
		(pts
			(xy 392.464036 -293.064692) (xy 392.36396 -292.891464) (xy 392.325606 -292.913816) (xy 392.28903 -293.050468)
			(xy 392.425428 -293.087044)
		)
		(stroke
			(width 0)
			(type solid)
		)
		(fill yes)
		(layer "In13.Cu")
		(net "M_H_CPU0_SB_DQ<30>")
	)
	(gr_poly
		(pts
			(xy 392.464036 -269.687294) (xy 392.425428 -269.664942) (xy 392.28903 -269.701518) (xy 392.325606 -269.83817)
			(xy 392.36396 -269.860522)
		)
		(stroke
			(width 0)
			(type solid)
		)
		(fill yes)
		(layer "In13.Cu")
		(net "M_H_CPU0_SB_CB<5>")
	)
	(gr_poly
		(pts
			(xy 392.539474 -284.818074) (xy 392.439398 -284.717998) (xy 392.339322 -284.818074) (xy 392.339322 -284.862524)
			(xy 392.539474 -284.862524)
		)
		(stroke
			(width 0)
			(type solid)
		)
		(fill yes)
		(layer "In13.Cu")
		(net "M_H_CPU0_SB_DQ<17>")
	)
	(gr_poly
		(pts
			(xy 392.539474 -283.198062) (xy 392.439398 -283.097986) (xy 392.339322 -283.198062) (xy 392.339322 -283.242512)
			(xy 392.539474 -283.242512)
		)
		(stroke
			(width 0)
			(type solid)
		)
		(fill yes)
		(layer "In13.Cu")
		(net "M_H_CPU0_SB_DQ<13>")
	)
	(gr_poly
		(pts
			(xy 392.539474 -281.577796) (xy 392.439398 -281.47772) (xy 392.339322 -281.577796) (xy 392.339322 -281.625294)
			(xy 392.539474 -281.625294)
		)
		(stroke
			(width 0)
			(type solid)
		)
		(fill yes)
		(layer "In13.Cu")
		(net "M_H_CPU0_SB_DQS_DN<6>")
	)
	(gr_poly
		(pts
			(xy 392.539474 -279.958038) (xy 392.439398 -279.857962) (xy 392.339322 -279.958038) (xy 392.339322 -280.002488)
			(xy 392.539474 -280.002488)
		)
		(stroke
			(width 0)
			(type solid)
		)
		(fill yes)
		(layer "In13.Cu")
		(net "M_H_CPU0_SB_DQ<9>")
	)
	(gr_poly
		(pts
			(xy 392.539474 -278.338026) (xy 392.439398 -278.23795) (xy 392.339322 -278.338026) (xy 392.339322 -278.382476)
			(xy 392.539474 -278.382476)
		)
		(stroke
			(width 0)
			(type solid)
		)
		(fill yes)
		(layer "In13.Cu")
		(net "M_H_CPU0_SB_DQ<5>")
	)
	(gr_poly
		(pts
			(xy 392.539474 -276.71776) (xy 392.439398 -276.617684) (xy 392.339322 -276.71776) (xy 392.339322 -276.765258)
			(xy 392.539474 -276.765258)
		)
		(stroke
			(width 0)
			(type solid)
		)
		(fill yes)
		(layer "In13.Cu")
		(net "M_H_CPU0_SB_DQS_DN<5>")
	)
	(gr_poly
		(pts
			(xy 392.539474 -275.098002) (xy 392.439398 -274.997926) (xy 392.339322 -275.098002) (xy 392.339322 -275.142452)
			(xy 392.539474 -275.142452)
		)
		(stroke
			(width 0)
			(type solid)
		)
		(fill yes)
		(layer "In13.Cu")
		(net "M_H_CPU0_SB_DQ<1>")
	)
	(gr_poly
		(pts
			(xy 392.539474 -273.47799) (xy 392.439398 -273.377914) (xy 392.339322 -273.47799) (xy 392.339322 -273.52244)
			(xy 392.539474 -273.52244)
		)
		(stroke
			(width 0)
			(type solid)
		)
		(fill yes)
		(layer "In13.Cu")
		(net "M_H_CPU0_SB_CB<1>")
	)
	(gr_poly
		(pts
			(xy 392.539474 -266.997942) (xy 392.439398 -266.897866) (xy 392.339322 -266.997942) (xy 392.339322 -267.042392)
			(xy 392.539474 -267.042392)
		)
		(stroke
			(width 0)
			(type solid)
		)
		(fill yes)
		(layer "In13.Cu")
		(net "M_H_CPU0_SA_RSP<0>")
	)
	(gr_poly
		(pts
			(xy 392.539474 -265.37793) (xy 392.439398 -265.277854) (xy 392.339322 -265.37793) (xy 392.339322 -265.42238)
			(xy 392.539474 -265.42238)
		)
		(stroke
			(width 0)
			(type solid)
		)
		(fill yes)
		(layer "In13.Cu")
		(net "M_H_CPU0_SB_PAR")
	)
	(gr_poly
		(pts
			(xy 392.539474 -263.757918) (xy 392.439398 -263.657842) (xy 392.339322 -263.757918) (xy 392.339322 -263.802368)
			(xy 392.539474 -263.802368)
		)
		(stroke
			(width 0)
			(type solid)
		)
		(fill yes)
		(layer "In13.Cu")
		(net "M_H_CPU0_SB_CA<4>")
	)
	(gr_poly
		(pts
			(xy 392.539474 -262.137906) (xy 392.439398 -262.03783) (xy 392.339322 -262.137906) (xy 392.339322 -262.182356)
			(xy 392.539474 -262.182356)
		)
		(stroke
			(width 0)
			(type solid)
		)
		(fill yes)
		(layer "In13.Cu")
		(net "M_H_CPU0_SB_CA<0>")
	)
	(gr_poly
		(pts
			(xy 392.544808 -291.297614) (xy 392.444732 -291.197792) (xy 392.344656 -291.297614) (xy 392.344656 -291.345366)
			(xy 392.544808 -291.345366)
		)
		(stroke
			(width 0)
			(type solid)
		)
		(fill yes)
		(layer "In13.Cu")
		(net "M_H_CPU0_SB_DQS_DN<8>")
	)
	(gr_poly
		(pts
			(xy 392.544808 -271.454372) (xy 392.544808 -271.40662) (xy 392.344656 -271.40662) (xy 392.344656 -271.454372)
			(xy 392.444732 -271.554194)
		)
		(stroke
			(width 0)
			(type solid)
		)
		(fill yes)
		(layer "In13.Cu")
		(net "M_H_CPU0_SB_DQS_DN<9>")
	)
	(gr_poly
		(pts
			(xy 392.544808 -268.617954) (xy 392.444732 -268.517878) (xy 392.344656 -268.617954) (xy 392.344656 -268.662404)
			(xy 392.544808 -268.662404)
		)
		(stroke
			(width 0)
			(type solid)
		)
		(fill yes)
		(layer "In13.Cu")
		(net "M_H_CPU0_SB_CB<4>")
	)
	(gr_poly
		(pts
			(xy 392.55573 -284.41396) (xy 392.55573 -284.36951) (xy 392.355578 -284.36951) (xy 392.355578 -284.41396)
			(xy 392.455654 -284.514036)
		)
		(stroke
			(width 0)
			(type solid)
		)
		(fill yes)
		(layer "In13.Cu")
		(net "M_H_CPU0_SB_DQ<18>")
	)
	(gr_poly
		(pts
			(xy 392.55573 -282.793948) (xy 392.55573 -282.749498) (xy 392.355578 -282.749498) (xy 392.355578 -282.793948)
			(xy 392.455654 -282.894024)
		)
		(stroke
			(width 0)
			(type solid)
		)
		(fill yes)
		(layer "In13.Cu")
		(net "M_H_CPU0_SB_DQ<14>")
	)
	(gr_poly
		(pts
			(xy 392.55573 -279.553924) (xy 392.55573 -279.509474) (xy 392.355578 -279.509474) (xy 392.355578 -279.553924)
			(xy 392.455654 -279.654)
		)
		(stroke
			(width 0)
			(type solid)
		)
		(fill yes)
		(layer "In13.Cu")
		(net "M_H_CPU0_SB_DQ<10>")
	)
	(gr_poly
		(pts
			(xy 392.55573 -277.933912) (xy 392.55573 -277.889462) (xy 392.355578 -277.889462) (xy 392.355578 -277.933912)
			(xy 392.455654 -278.033988)
		)
		(stroke
			(width 0)
			(type solid)
		)
		(fill yes)
		(layer "In13.Cu")
		(net "M_H_CPU0_SB_DQ<6>")
	)
	(gr_poly
		(pts
			(xy 392.55573 -274.693888) (xy 392.55573 -274.649438) (xy 392.355578 -274.649438) (xy 392.355578 -274.693888)
			(xy 392.455654 -274.793964)
		)
		(stroke
			(width 0)
			(type solid)
		)
		(fill yes)
		(layer "In13.Cu")
		(net "M_H_CPU0_SB_DQ<2>")
	)
	(gr_poly
		(pts
			(xy 392.55573 -273.073876) (xy 392.55573 -273.029426) (xy 392.355578 -273.029426) (xy 392.355578 -273.073876)
			(xy 392.455654 -273.173952)
		)
		(stroke
			(width 0)
			(type solid)
		)
		(fill yes)
		(layer "In13.Cu")
		(net "M_H_CPU0_SB_CB<2>")
	)
	(gr_poly
		(pts
			(xy 392.55573 -266.593828) (xy 392.55573 -266.549378) (xy 392.355578 -266.549378) (xy 392.355578 -266.593828)
			(xy 392.455654 -266.693904)
		)
		(stroke
			(width 0)
			(type solid)
		)
		(fill yes)
		(layer "In13.Cu")
		(net "M_H_CPU0_SB_CS_N<1>")
	)
	(gr_poly
		(pts
			(xy 392.55573 -263.353804) (xy 392.55573 -263.309354) (xy 392.355578 -263.309354) (xy 392.355578 -263.353804)
			(xy 392.455654 -263.45388)
		)
		(stroke
			(width 0)
			(type solid)
		)
		(fill yes)
		(layer "In13.Cu")
		(net "M_H_CPU0_SB_CA<3>")
	)
	(gr_poly
		(pts
			(xy 392.557762 -290.894008) (xy 392.557762 -290.84651) (xy 392.357864 -290.84651) (xy 392.357864 -290.894008)
			(xy 392.457686 -290.994084)
		)
		(stroke
			(width 0)
			(type solid)
		)
		(fill yes)
		(layer "In13.Cu")
		(net "M_H_CPU0_SB_DQS_DN<3>")
	)
	(gr_poly
		(pts
			(xy 392.557762 -286.034226) (xy 392.557762 -285.986728) (xy 392.357864 -285.986728) (xy 392.357864 -286.034226)
			(xy 392.457686 -286.134302)
		)
		(stroke
			(width 0)
			(type solid)
		)
		(fill yes)
		(layer "In13.Cu")
		(net "M_H_CPU0_SB_DQS_DN<2>")
	)
	(gr_poly
		(pts
			(xy 392.557762 -281.17419) (xy 392.557762 -281.126692) (xy 392.357864 -281.126692) (xy 392.357864 -281.17419)
			(xy 392.457686 -281.274266)
		)
		(stroke
			(width 0)
			(type solid)
		)
		(fill yes)
		(layer "In13.Cu")
		(net "M_H_CPU0_SB_DQS_DN<1>")
	)
	(gr_poly
		(pts
			(xy 392.557762 -276.314154) (xy 392.557762 -276.266656) (xy 392.357864 -276.266656) (xy 392.357864 -276.314154)
			(xy 392.457686 -276.41423)
		)
		(stroke
			(width 0)
			(type solid)
		)
		(fill yes)
		(layer "In13.Cu")
		(net "M_H_CPU0_SB_DQS_DN<0>")
	)
	(gr_poly
		(pts
			(xy 392.563858 -294.138096) (xy 392.600434 -294.001444) (xy 392.464036 -293.964868) (xy 392.425428 -293.98722)
			(xy 392.525504 -294.160448)
		)
		(stroke
			(width 0)
			(type solid)
		)
		(fill yes)
		(layer "In13.Cu")
		(net "M_H_CPU0_SB_DQ<29>")
	)
	(gr_poly
		(pts
			(xy 392.564112 -292.518084) (xy 392.600942 -292.381432) (xy 392.46429 -292.344856) (xy 392.425682 -292.367208)
			(xy 392.525758 -292.540436)
		)
		(stroke
			(width 0)
			(type solid)
		)
		(fill yes)
		(layer "In13.Cu")
		(net "M_H_CPU0_SB_DQ<28>")
	)
	(gr_poly
		(pts
			(xy 392.600942 -270.370554) (xy 392.564112 -270.233902) (xy 392.525758 -270.21155) (xy 392.425682 -270.384778)
			(xy 392.46429 -270.40713)
		)
		(stroke
			(width 0)
			(type solid)
		)
		(fill yes)
		(layer "In13.Cu")
		(net "M_H_CPU0_SB_CB<7>")
	)
	(gr_poly
		(pts
			(xy 392.633962 -223.885506) (xy 392.595354 -223.863154) (xy 392.458702 -223.89973) (xy 392.495532 -224.036382)
			(xy 392.533886 -224.058734)
		)
		(stroke
			(width 0)
			(type solid)
		)
		(fill yes)
		(layer "In13.Cu")
		(net "M_H_CPU0_SA_DQ<4>")
	)
	(gr_poly
		(pts
			(xy 392.70305 -256.432558) (xy 392.70305 -256.38506) (xy 392.503152 -256.38506) (xy 392.503152 -256.432558)
			(xy 392.603228 -256.532634)
		)
		(stroke
			(width 0)
			(type solid)
		)
		(fill yes)
		(layer "In13.Cu")
		(net "M_H_CPU0_CLK_DN<0>")
	)
	(gr_poly
		(pts
			(xy 392.70686 -247.115838) (xy 392.607038 -247.016016) (xy 392.506962 -247.115838) (xy 392.506962 -247.16359)
			(xy 392.70686 -247.16359)
		)
		(stroke
			(width 0)
			(type solid)
		)
		(fill yes)
		(layer "In13.Cu")
		(net "M_H_CPU0_SA_DQS_DN<9>")
	)
	(gr_poly
		(pts
			(xy 392.70686 -246.712486) (xy 392.70686 -246.664734) (xy 392.506962 -246.664734) (xy 392.506962 -246.712486)
			(xy 392.607038 -246.812308)
		)
		(stroke
			(width 0)
			(type solid)
		)
		(fill yes)
		(layer "In13.Cu")
		(net "M_H_CPU0_SA_DQS_DN<4>")
	)
	(gr_poly
		(pts
			(xy 392.70686 -241.85245) (xy 392.70686 -241.804698) (xy 392.506962 -241.804698) (xy 392.506962 -241.85245)
			(xy 392.607038 -241.952272)
		)
		(stroke
			(width 0)
			(type solid)
		)
		(fill yes)
		(layer "In13.Cu")
		(net "M_H_CPU0_SA_DQS_DN<3>")
	)
	(gr_poly
		(pts
			(xy 392.712194 -255.216152) (xy 392.612118 -255.116076) (xy 392.512042 -255.216152) (xy 392.512042 -255.260602)
			(xy 392.712194 -255.260602)
		)
		(stroke
			(width 0)
			(type solid)
		)
		(fill yes)
		(layer "In13.Cu")
		(net "M_H_CPU0_SA_CA<6>")
	)
	(gr_poly
		(pts
			(xy 392.712194 -254.812292) (xy 392.712194 -254.767842) (xy 392.512042 -254.767842) (xy 392.512042 -254.812292)
			(xy 392.612118 -254.912368)
		)
		(stroke
			(width 0)
			(type solid)
		)
		(fill yes)
		(layer "In13.Cu")
		(net "M_H_CPU0_SA_CA<5>")
	)
	(gr_poly
		(pts
			(xy 392.712194 -253.59614) (xy 392.612118 -253.496064) (xy 392.512042 -253.59614) (xy 392.512042 -253.64059)
			(xy 392.712194 -253.64059)
		)
		(stroke
			(width 0)
			(type solid)
		)
		(fill yes)
		(layer "In13.Cu")
		(net "M_H_CPU0_SA_CA<2>")
	)
	(gr_poly
		(pts
			(xy 392.712194 -253.19228) (xy 392.712194 -253.14783) (xy 392.512042 -253.14783) (xy 392.512042 -253.19228)
			(xy 392.612118 -253.292356)
		)
		(stroke
			(width 0)
			(type solid)
		)
		(fill yes)
		(layer "In13.Cu")
		(net "M_H_CPU0_SA_CA<1>")
	)
	(gr_poly
		(pts
			(xy 392.712194 -251.976128) (xy 392.612118 -251.876052) (xy 392.512042 -251.976128) (xy 392.512042 -252.020578)
			(xy 392.712194 -252.020578)
		)
		(stroke
			(width 0)
			(type solid)
		)
		(fill yes)
		(layer "In13.Cu")
		(net "M_H_CPU0_SA_CS_N<1>")
	)
	(gr_poly
		(pts
			(xy 392.712194 -250.356116) (xy 392.612118 -250.25604) (xy 392.512042 -250.356116) (xy 392.512042 -250.400566)
			(xy 392.712194 -250.400566)
		)
		(stroke
			(width 0)
			(type solid)
		)
		(fill yes)
		(layer "In13.Cu")
		(net "M_H_CPU0_ALERT_R_N")
	)
	(gr_poly
		(pts
			(xy 392.712194 -248.736104) (xy 392.612118 -248.636028) (xy 392.512042 -248.736104) (xy 392.512042 -248.780554)
			(xy 392.712194 -248.780554)
		)
		(stroke
			(width 0)
			(type solid)
		)
		(fill yes)
		(layer "In13.Cu")
		(net "M_H_CPU0_SA_CB<5>")
	)
	(gr_poly
		(pts
			(xy 392.712194 -248.332244) (xy 392.712194 -248.287794) (xy 392.512042 -248.287794) (xy 392.512042 -248.332244)
			(xy 392.612118 -248.43232)
		)
		(stroke
			(width 0)
			(type solid)
		)
		(fill yes)
		(layer "In13.Cu")
		(net "M_H_CPU0_SA_CB<6>")
	)
	(gr_poly
		(pts
			(xy 392.712194 -245.49608) (xy 392.612118 -245.396004) (xy 392.512042 -245.49608) (xy 392.512042 -245.54053)
			(xy 392.712194 -245.54053)
		)
		(stroke
			(width 0)
			(type solid)
		)
		(fill yes)
		(layer "In13.Cu")
		(net "M_H_CPU0_SA_CB<1>")
	)
	(gr_poly
		(pts
			(xy 392.712194 -245.09222) (xy 392.712194 -245.04777) (xy 392.512042 -245.04777) (xy 392.512042 -245.09222)
			(xy 392.612118 -245.192296)
		)
		(stroke
			(width 0)
			(type solid)
		)
		(fill yes)
		(layer "In13.Cu")
		(net "M_H_CPU0_SA_CB<2>")
	)
	(gr_poly
		(pts
			(xy 392.712194 -243.876068) (xy 392.612118 -243.775992) (xy 392.512042 -243.876068) (xy 392.512042 -243.920518)
			(xy 392.712194 -243.920518)
		)
		(stroke
			(width 0)
			(type solid)
		)
		(fill yes)
		(layer "In13.Cu")
		(net "M_H_CPU0_SA_DQ<29>")
	)
	(gr_poly
		(pts
			(xy 392.712194 -243.472208) (xy 392.712194 -243.427758) (xy 392.512042 -243.427758) (xy 392.512042 -243.472208)
			(xy 392.612118 -243.572284)
		)
		(stroke
			(width 0)
			(type solid)
		)
		(fill yes)
		(layer "In13.Cu")
		(net "M_H_CPU0_SA_DQ<30>")
	)
	(gr_poly
		(pts
			(xy 392.712194 -240.636044) (xy 392.612118 -240.535968) (xy 392.512042 -240.636044) (xy 392.512042 -240.680494)
			(xy 392.712194 -240.680494)
		)
		(stroke
			(width 0)
			(type solid)
		)
		(fill yes)
		(layer "In13.Cu")
		(net "M_H_CPU0_SA_DQ<25>")
	)
	(gr_poly
		(pts
			(xy 392.712194 -240.232184) (xy 392.712194 -240.187734) (xy 392.512042 -240.187734) (xy 392.512042 -240.232184)
			(xy 392.612118 -240.33226)
		)
		(stroke
			(width 0)
			(type solid)
		)
		(fill yes)
		(layer "In13.Cu")
		(net "M_H_CPU0_SA_DQ<26>")
	)
	(gr_poly
		(pts
			(xy 392.712194 -239.016032) (xy 392.612118 -238.915956) (xy 392.512042 -239.016032) (xy 392.512042 -239.060482)
			(xy 392.712194 -239.060482)
		)
		(stroke
			(width 0)
			(type solid)
		)
		(fill yes)
		(layer "In13.Cu")
		(net "M_H_CPU0_SA_DQ<21>")
	)
	(gr_poly
		(pts
			(xy 392.712194 -238.612172) (xy 392.712194 -238.567722) (xy 392.512042 -238.567722) (xy 392.512042 -238.612172)
			(xy 392.612118 -238.712248)
		)
		(stroke
			(width 0)
			(type solid)
		)
		(fill yes)
		(layer "In13.Cu")
		(net "M_H_CPU0_SA_DQ<22>")
	)
	(gr_poly
		(pts
			(xy 392.720576 -237.395766) (xy 392.6205 -237.29569) (xy 392.520678 -237.395766) (xy 392.520678 -237.443264)
			(xy 392.720576 -237.443264)
		)
		(stroke
			(width 0)
			(type solid)
		)
		(fill yes)
		(layer "In13.Cu")
		(net "M_H_CPU0_SA_DQS_DN<7>")
	)
	(gr_poly
		(pts
			(xy 392.763756 -236.936026) (xy 392.759692 -236.888528) (xy 392.560302 -236.906054) (xy 392.56462 -236.953552)
			(xy 392.672824 -237.044484)
		)
		(stroke
			(width 0)
			(type solid)
		)
		(fill yes)
		(layer "In13.Cu")
		(net "M_H_CPU0_SA_DQS_DN<2>")
	)
	(gr_poly
		(pts
			(xy 392.768582 -222.95231) (xy 392.732006 -222.815658) (xy 392.690604 -222.791782) (xy 392.590528 -222.96501)
			(xy 392.63193 -222.988886)
		)
		(stroke
			(width 0)
			(type solid)
		)
		(fill yes)
		(layer "In13.Cu")
		(net "M_H_CPU0_SA_DQS_DP<5>")
	)
	(gr_poly
		(pts
			(xy 392.770614 -224.568766) (xy 392.734038 -224.432114) (xy 392.695684 -224.409762) (xy 392.595608 -224.58299)
			(xy 392.634216 -224.605342)
		)
		(stroke
			(width 0)
			(type solid)
		)
		(fill yes)
		(layer "In13.Cu")
		(net "M_H_CPU0_SA_DQ<6>")
	)
	(gr_poly
		(pts
			(xy 392.933936 -295.49471) (xy 392.83386 -295.321482) (xy 392.795506 -295.343834) (xy 392.75893 -295.480486)
			(xy 392.895328 -295.517062)
		)
		(stroke
			(width 0)
			(type solid)
		)
		(fill yes)
		(layer "In13.Cu")
		(net "M_H_CPU0_SB_DQ<31>")
	)
	(gr_poly
		(pts
			(xy 392.933936 -293.874698) (xy 392.83386 -293.70147) (xy 392.795506 -293.723822) (xy 392.75893 -293.860474)
			(xy 392.895328 -293.89705)
		)
		(stroke
			(width 0)
			(type solid)
		)
		(fill yes)
		(layer "In13.Cu")
		(net "M_H_CPU0_SB_DQ<30>")
	)
	(gr_poly
		(pts
			(xy 392.93673 -270.498062) (xy 392.895582 -270.47444) (xy 392.75893 -270.511016) (xy 392.795506 -270.647414)
			(xy 392.836908 -270.67129)
		)
		(stroke
			(width 0)
			(type solid)
		)
		(fill yes)
		(layer "In13.Cu")
		(net "M_H_CPU0_SB_DQS_DP<9>")
	)
	(gr_poly
		(pts
			(xy 392.996166 -277.121366) (xy 392.996166 -277.073868) (xy 392.796014 -277.073868) (xy 392.796014 -277.121366)
			(xy 392.89609 -277.221442)
		)
		(stroke
			(width 0)
			(type solid)
		)
		(fill yes)
		(layer "In13.Cu")
		(net "M_H_CPU0_SB_DQS_DP<5>")
	)
	(gr_poly
		(pts
			(xy 393.012168 -285.22422) (xy 393.012168 -285.17977) (xy 392.812016 -285.17977) (xy 392.812016 -285.22422)
			(xy 392.912092 -285.324296)
		)
		(stroke
			(width 0)
			(type solid)
		)
		(fill yes)
		(layer "In13.Cu")
		(net "M_H_CPU0_SB_DQ<19>")
	)
	(gr_poly
		(pts
			(xy 393.012168 -283.604208) (xy 393.012168 -283.559758) (xy 392.812016 -283.559758) (xy 392.812016 -283.604208)
			(xy 392.912092 -283.704284)
		)
		(stroke
			(width 0)
			(type solid)
		)
		(fill yes)
		(layer "In13.Cu")
		(net "M_H_CPU0_SB_DQ<15>")
	)
	(gr_poly
		(pts
			(xy 393.012168 -280.364184) (xy 393.012168 -280.319734) (xy 392.812016 -280.319734) (xy 392.812016 -280.364184)
			(xy 392.912092 -280.46426)
		)
		(stroke
			(width 0)
			(type solid)
		)
		(fill yes)
		(layer "In13.Cu")
		(net "M_H_CPU0_SB_DQ<11>")
	)
	(gr_poly
		(pts
			(xy 393.012168 -278.744172) (xy 393.012168 -278.699722) (xy 392.812016 -278.699722) (xy 392.812016 -278.744172)
			(xy 392.912092 -278.844248)
		)
		(stroke
			(width 0)
			(type solid)
		)
		(fill yes)
		(layer "In13.Cu")
		(net "M_H_CPU0_SB_DQ<7>")
	)
	(gr_poly
		(pts
			(xy 393.012168 -275.504148) (xy 393.012168 -275.459698) (xy 392.812016 -275.459698) (xy 392.812016 -275.504148)
			(xy 392.912092 -275.604224)
		)
		(stroke
			(width 0)
			(type solid)
		)
		(fill yes)
		(layer "In13.Cu")
		(net "M_H_CPU0_SB_DQ<3>")
	)
	(gr_poly
		(pts
			(xy 393.012168 -273.884136) (xy 393.012168 -273.839686) (xy 392.812016 -273.839686) (xy 392.812016 -273.884136)
			(xy 392.912092 -273.984212)
		)
		(stroke
			(width 0)
			(type solid)
		)
		(fill yes)
		(layer "In13.Cu")
		(net "M_H_CPU0_SB_CB<3>")
	)
	(gr_poly
		(pts
			(xy 393.012168 -265.784076) (xy 393.012168 -265.739626) (xy 392.812016 -265.739626) (xy 392.812016 -265.784076)
			(xy 392.912092 -265.884152)
		)
		(stroke
			(width 0)
			(type solid)
		)
		(fill yes)
		(layer "In13.Cu")
		(net "M_H_CPU0_SB_CS_N<0>")
	)
	(gr_poly
		(pts
			(xy 393.012168 -264.164064) (xy 393.012168 -264.119614) (xy 392.812016 -264.119614) (xy 392.812016 -264.164064)
			(xy 392.912092 -264.26414)
		)
		(stroke
			(width 0)
			(type solid)
		)
		(fill yes)
		(layer "In13.Cu")
		(net "M_H_CPU0_SB_CA<5>")
	)
	(gr_poly
		(pts
			(xy 393.012168 -262.544052) (xy 393.012168 -262.499602) (xy 392.812016 -262.499602) (xy 392.812016 -262.544052)
			(xy 392.912092 -262.644128)
		)
		(stroke
			(width 0)
			(type solid)
		)
		(fill yes)
		(layer "In13.Cu")
		(net "M_H_CPU0_SB_CA<1>")
	)
	(gr_poly
		(pts
			(xy 393.014962 -269.42796) (xy 392.914886 -269.327884) (xy 392.81481 -269.42796) (xy 392.81481 -269.47241)
			(xy 393.014962 -269.47241)
		)
		(stroke
			(width 0)
			(type solid)
		)
		(fill yes)
		(layer "In13.Cu")
		(net "M_H_CPU0_SB_CB<5>")
	)
	(gr_poly
		(pts
			(xy 393.014962 -269.0241) (xy 393.014962 -268.97965) (xy 392.81481 -268.97965) (xy 392.81481 -269.0241)
			(xy 392.914886 -269.124176)
		)
		(stroke
			(width 0)
			(type solid)
		)
		(fill yes)
		(layer "In13.Cu")
		(net "M_H_CPU0_SB_CB<6>")
	)
	(gr_poly
		(pts
			(xy 393.026392 -290.487354) (xy 392.926316 -290.387278) (xy 392.826494 -290.487354) (xy 392.826494 -290.534852)
			(xy 393.026392 -290.534852)
		)
		(stroke
			(width 0)
			(type solid)
		)
		(fill yes)
		(layer "In13.Cu")
		(net "M_H_CPU0_SB_DQS_DP<3>")
	)
	(gr_poly
		(pts
			(xy 393.026392 -285.627572) (xy 392.926316 -285.527496) (xy 392.826494 -285.627572) (xy 392.826494 -285.67507)
			(xy 393.026392 -285.67507)
		)
		(stroke
			(width 0)
			(type solid)
		)
		(fill yes)
		(layer "In13.Cu")
		(net "M_H_CPU0_SB_DQS_DP<2>")
	)
	(gr_poly
		(pts
			(xy 393.026392 -284.00756) (xy 392.926316 -283.907484) (xy 392.826494 -284.00756) (xy 392.826494 -284.05201)
			(xy 393.026392 -284.05201)
		)
		(stroke
			(width 0)
			(type solid)
		)
		(fill yes)
		(layer "In13.Cu")
		(net "M_H_CPU0_SB_DQ<16>")
	)
	(gr_poly
		(pts
			(xy 393.026392 -282.387548) (xy 392.926316 -282.287472) (xy 392.826494 -282.387548) (xy 392.826494 -282.431998)
			(xy 393.026392 -282.431998)
		)
		(stroke
			(width 0)
			(type solid)
		)
		(fill yes)
		(layer "In13.Cu")
		(net "M_H_CPU0_SB_DQ<12>")
	)
	(gr_poly
		(pts
			(xy 393.026392 -280.767536) (xy 392.926316 -280.66746) (xy 392.826494 -280.767536) (xy 392.826494 -280.815034)
			(xy 393.026392 -280.815034)
		)
		(stroke
			(width 0)
			(type solid)
		)
		(fill yes)
		(layer "In13.Cu")
		(net "M_H_CPU0_SB_DQS_DP<1>")
	)
	(gr_poly
		(pts
			(xy 393.026392 -279.147524) (xy 392.926316 -279.047448) (xy 392.826494 -279.147524) (xy 392.826494 -279.191974)
			(xy 393.026392 -279.191974)
		)
		(stroke
			(width 0)
			(type solid)
		)
		(fill yes)
		(layer "In13.Cu")
		(net "M_H_CPU0_SB_DQ<8>")
	)
	(gr_poly
		(pts
			(xy 393.026392 -277.527512) (xy 392.926316 -277.427436) (xy 392.826494 -277.527512) (xy 392.826494 -277.571962)
			(xy 393.026392 -277.571962)
		)
		(stroke
			(width 0)
			(type solid)
		)
		(fill yes)
		(layer "In13.Cu")
		(net "M_H_CPU0_SB_DQ<4>")
	)
	(gr_poly
		(pts
			(xy 393.026392 -275.9075) (xy 392.926316 -275.807424) (xy 392.826494 -275.9075) (xy 392.826494 -275.954998)
			(xy 393.026392 -275.954998)
		)
		(stroke
			(width 0)
			(type solid)
		)
		(fill yes)
		(layer "In13.Cu")
		(net "M_H_CPU0_SB_DQS_DP<0>")
	)
	(gr_poly
		(pts
			(xy 393.026392 -274.287488) (xy 392.926316 -274.187412) (xy 392.826494 -274.287488) (xy 392.826494 -274.331938)
			(xy 393.026392 -274.331938)
		)
		(stroke
			(width 0)
			(type solid)
		)
		(fill yes)
		(layer "In13.Cu")
		(net "M_H_CPU0_SB_DQ<0>")
	)
	(gr_poly
		(pts
			(xy 393.026392 -272.667476) (xy 392.926316 -272.5674) (xy 392.826494 -272.667476) (xy 392.826494 -272.711926)
			(xy 393.026392 -272.711926)
		)
		(stroke
			(width 0)
			(type solid)
		)
		(fill yes)
		(layer "In13.Cu")
		(net "M_H_CPU0_SB_CB<0>")
	)
	(gr_poly
		(pts
			(xy 393.026392 -267.80744) (xy 392.926316 -267.707364) (xy 392.826494 -267.80744) (xy 392.826494 -267.85189)
			(xy 393.026392 -267.85189)
		)
		(stroke
			(width 0)
			(type solid)
		)
		(fill yes)
		(layer "In13.Cu")
		(net "M_H_CPU0_SB_RSP<0>")
	)
	(gr_poly
		(pts
			(xy 393.026392 -264.567416) (xy 392.926316 -264.46734) (xy 392.826494 -264.567416) (xy 392.826494 -264.611866)
			(xy 393.026392 -264.611866)
		)
		(stroke
			(width 0)
			(type solid)
		)
		(fill yes)
		(layer "In13.Cu")
		(net "M_H_CPU0_SB_CA<6>")
	)
	(gr_poly
		(pts
			(xy 393.026392 -262.947404) (xy 392.926316 -262.847328) (xy 392.826494 -262.947404) (xy 392.826494 -262.991854)
			(xy 393.026392 -262.991854)
		)
		(stroke
			(width 0)
			(type solid)
		)
		(fill yes)
		(layer "In13.Cu")
		(net "M_H_CPU0_SB_CA<2>")
	)
	(gr_poly
		(pts
			(xy 393.033758 -294.948102) (xy 393.070334 -294.81145) (xy 392.933936 -294.774874) (xy 392.895328 -294.797226)
			(xy 392.995404 -294.970454)
		)
		(stroke
			(width 0)
			(type solid)
		)
		(fill yes)
		(layer "In13.Cu")
		(net "M_H_CPU0_SB_DQ<29>")
	)
	(gr_poly
		(pts
			(xy 393.034012 -293.32809) (xy 393.070842 -293.191438) (xy 392.93419 -293.154862) (xy 392.895582 -293.177214)
			(xy 392.995658 -293.350442)
		)
		(stroke
			(width 0)
			(type solid)
		)
		(fill yes)
		(layer "In13.Cu")
		(net "M_H_CPU0_SB_DQ<28>")
	)
	(gr_poly
		(pts
			(xy 393.034012 -291.707316) (xy 393.070588 -291.570918) (xy 392.933936 -291.534088) (xy 392.892788 -291.557964)
			(xy 392.99261 -291.731192)
		)
		(stroke
			(width 0)
			(type solid)
		)
		(fill yes)
		(layer "In13.Cu")
		(net "M_H_CPU0_SB_DQS_DN<8>")
	)
	(gr_poly
		(pts
			(xy 393.070588 -271.181068) (xy 393.034012 -271.04467) (xy 392.99261 -271.020794) (xy 392.892788 -271.194022)
			(xy 392.933936 -271.217644)
		)
		(stroke
			(width 0)
			(type solid)
		)
		(fill yes)
		(layer "In13.Cu")
		(net "M_H_CPU0_SB_DQS_DN<9>")
	)
	(gr_poly
		(pts
			(xy 393.104624 -223.074484) (xy 393.066016 -223.052386) (xy 392.929364 -223.088962) (xy 392.96594 -223.225614)
			(xy 393.004548 -223.247966)
		)
		(stroke
			(width 0)
			(type solid)
		)
		(fill yes)
		(layer "In13.Cu")
		(net "M_H_CPU0_SA_DQ<4>")
	)
	(gr_poly
		(pts
			(xy 393.175998 -237.80242) (xy 393.175998 -237.754922) (xy 392.9761 -237.754922) (xy 392.9761 -237.80242)
			(xy 393.076176 -237.902496)
		)
		(stroke
			(width 0)
			(type solid)
		)
		(fill yes)
		(layer "In13.Cu")
		(net "M_H_CPU0_SA_DQS_DP<7>")
	)
	(gr_poly
		(pts
			(xy 393.194286 -254.405892) (xy 393.094464 -254.30607) (xy 392.994388 -254.405892) (xy 392.994388 -254.450342)
			(xy 393.194286 -254.450342)
		)
		(stroke
			(width 0)
			(type solid)
		)
		(fill yes)
		(layer "In13.Cu")
		(net "M_H_CPU0_SA_CA<4>")
	)
	(gr_poly
		(pts
			(xy 393.194286 -254.00254) (xy 393.194286 -253.95809) (xy 392.994388 -253.95809) (xy 392.994388 -254.00254)
			(xy 393.094464 -254.102362)
		)
		(stroke
			(width 0)
			(type solid)
		)
		(fill yes)
		(layer "In13.Cu")
		(net "M_H_CPU0_SA_CA<3>")
	)
	(gr_poly
		(pts
			(xy 393.194286 -252.78588) (xy 393.094464 -252.686058) (xy 392.994388 -252.78588) (xy 392.994388 -252.83033)
			(xy 393.194286 -252.83033)
		)
		(stroke
			(width 0)
			(type solid)
		)
		(fill yes)
		(layer "In13.Cu")
		(net "M_H_CPU0_SA_CA<0>")
	)
	(gr_poly
		(pts
			(xy 393.194286 -251.165868) (xy 393.094464 -251.066046) (xy 392.994388 -251.165868) (xy 392.994388 -251.210318)
			(xy 393.194286 -251.210318)
		)
		(stroke
			(width 0)
			(type solid)
		)
		(fill yes)
		(layer "In13.Cu")
		(net "M_H_CPU0_SA_CS_N<0>")
	)
	(gr_poly
		(pts
			(xy 393.194286 -249.142504) (xy 393.194286 -249.098054) (xy 392.994388 -249.098054) (xy 392.994388 -249.142504)
			(xy 393.094464 -249.242326)
		)
		(stroke
			(width 0)
			(type solid)
		)
		(fill yes)
		(layer "In13.Cu")
		(net "M_H_CPU0_SA_CB<7>")
	)
	(gr_poly
		(pts
			(xy 393.194286 -247.925844) (xy 393.094464 -247.826022) (xy 392.994388 -247.925844) (xy 392.994388 -247.970294)
			(xy 393.194286 -247.970294)
		)
		(stroke
			(width 0)
			(type solid)
		)
		(fill yes)
		(layer "In13.Cu")
		(net "M_H_CPU0_SA_CB<4>")
	)
	(gr_poly
		(pts
			(xy 393.194286 -245.90248) (xy 393.194286 -245.85803) (xy 392.994388 -245.85803) (xy 392.994388 -245.90248)
			(xy 393.094464 -246.002302)
		)
		(stroke
			(width 0)
			(type solid)
		)
		(fill yes)
		(layer "In13.Cu")
		(net "M_H_CPU0_SA_CB<3>")
	)
	(gr_poly
		(pts
			(xy 393.197334 -256.025904) (xy 393.097258 -255.925828) (xy 392.997182 -256.025904) (xy 392.997182 -256.073402)
			(xy 393.197334 -256.073402)
		)
		(stroke
			(width 0)
			(type solid)
		)
		(fill yes)
		(layer "In13.Cu")
		(net "M_H_CPU0_CLK_DP<0>")
	)
	(gr_poly
		(pts
			(xy 393.197334 -247.522492) (xy 393.197334 -247.474994) (xy 392.997182 -247.474994) (xy 392.997182 -247.522492)
			(xy 393.097258 -247.622568)
		)
		(stroke
			(width 0)
			(type solid)
		)
		(fill yes)
		(layer "In13.Cu")
		(net "M_H_CPU0_SA_DQS_DP<9>")
	)
	(gr_poly
		(pts
			(xy 393.197334 -246.305832) (xy 393.097258 -246.205756) (xy 392.997182 -246.305832) (xy 392.997182 -246.35333)
			(xy 393.197334 -246.35333)
		)
		(stroke
			(width 0)
			(type solid)
		)
		(fill yes)
		(layer "In13.Cu")
		(net "M_H_CPU0_SA_DQS_DP<4>")
	)
	(gr_poly
		(pts
			(xy 393.240006 -223.76003) (xy 393.20343 -223.623378) (xy 393.164822 -223.60128) (xy 393.064746 -223.774508)
			(xy 393.103354 -223.796606)
		)
		(stroke
			(width 0)
			(type solid)
		)
		(fill yes)
		(layer "In13.Cu")
		(net "M_H_CPU0_SA_DQ<6>")
	)
	(gr_poly
		(pts
			(xy 393.403836 -294.684704) (xy 393.30376 -294.511476) (xy 393.265406 -294.533828) (xy 393.22883 -294.67048)
			(xy 393.365228 -294.707056)
		)
		(stroke
			(width 0)
			(type solid)
		)
		(fill yes)
		(layer "In13.Cu")
		(net "M_H_CPU0_SB_DQ<30>")
	)
	(gr_poly
		(pts
			(xy 393.463526 -276.314662) (xy 393.463526 -276.267164) (xy 393.263628 -276.267164) (xy 393.263628 -276.314662)
			(xy 393.363704 -276.414738)
		)
		(stroke
			(width 0)
			(type solid)
		)
		(fill yes)
		(layer "In13.Cu")
		(net "M_H_CPU0_SB_DQS_DN<0>")
	)
	(gr_poly
		(pts
			(xy 393.46505 -273.074384) (xy 393.46505 -273.029934) (xy 393.265152 -273.029934) (xy 393.265152 -273.074384)
			(xy 393.365228 -273.17446)
		)
		(stroke
			(width 0)
			(type solid)
		)
		(fill yes)
		(layer "In13.Cu")
		(net "M_H_CPU0_SB_CB<2>")
	)
	(gr_poly
		(pts
			(xy 393.484862 -269.834106) (xy 393.484862 -269.789656) (xy 393.28471 -269.789656) (xy 393.28471 -269.834106)
			(xy 393.384786 -269.934182)
		)
		(stroke
			(width 0)
			(type solid)
		)
		(fill yes)
		(layer "In13.Cu")
		(net "M_H_CPU0_SB_CB<7>")
	)
	(gr_poly
		(pts
			(xy 393.503912 -294.138096) (xy 393.540742 -294.001444) (xy 393.40409 -293.964868) (xy 393.365482 -293.98722)
			(xy 393.465558 -294.160448)
		)
		(stroke
			(width 0)
			(type solid)
		)
		(fill yes)
		(layer "In13.Cu")
		(net "M_H_CPU0_SB_DQ<28>")
	)
	(gr_poly
		(pts
			(xy 393.646914 -253.595886) (xy 393.547092 -253.496064) (xy 393.447016 -253.595886) (xy 393.447016 -253.640336)
			(xy 393.646914 -253.640336)
		)
		(stroke
			(width 0)
			(type solid)
		)
		(fill yes)
		(layer "In13.Cu")
		(net "M_H_CPU0_SA_CA<2>")
	)
	(gr_poly
		(pts
			(xy 393.646914 -248.73585) (xy 393.547092 -248.636028) (xy 393.447016 -248.73585) (xy 393.447016 -248.7803)
			(xy 393.646914 -248.7803)
		)
		(stroke
			(width 0)
			(type solid)
		)
		(fill yes)
		(layer "In13.Cu")
		(net "M_H_CPU0_SA_CB<5>")
	)
	(gr_poly
		(pts
			(xy 393.646914 -245.495826) (xy 393.547092 -245.396004) (xy 393.447016 -245.495826) (xy 393.447016 -245.540276)
			(xy 393.646914 -245.540276)
		)
		(stroke
			(width 0)
			(type solid)
		)
		(fill yes)
		(layer "In13.Cu")
		(net "M_H_CPU0_SA_CB<1>")
	)
	(gr_poly
		(pts
			(xy 393.648184 -247.115584) (xy 393.548362 -247.015762) (xy 393.448286 -247.115584) (xy 393.448286 -247.163336)
			(xy 393.648184 -247.163336)
		)
		(stroke
			(width 0)
			(type solid)
		)
		(fill yes)
		(layer "In13.Cu")
		(net "M_H_CPU0_SA_DQS_DN<9>")
	)
	(gr_poly
		(pts
			(xy 393.973304 -294.946832) (xy 394.00988 -294.81018) (xy 393.873228 -294.773604) (xy 393.83462 -294.795702)
			(xy 393.934696 -294.96893)
		)
		(stroke
			(width 0)
			(type solid)
		)
		(fill yes)
		(layer "In13.Cu")
		(net "M_H_CPU0_SB_DQ<28>")
	)
	(gr_poly
		(pts
			(xy 78.526894 -224.841308) (xy 78.56347 -224.70491) (xy 78.56347 -224.704656) (xy 78.427072 -224.66808)
			(xy 78.388464 -224.690432) (xy 78.48854 -224.86366)
		)
		(stroke
			(width 0)
			(type solid)
		)
		(fill yes)
		(layer "In13.Cu")
		(net "M_B_CPU1_SA_DQ<5>")
	)
	(gr_poly
		(pts
			(xy 78.532228 -256.025904) (xy 78.432406 -255.925828) (xy 78.432152 -255.925828) (xy 78.33233 -256.025904)
			(xy 78.33233 -256.073402) (xy 78.532228 -256.073402)
		)
		(stroke
			(width 0)
			(type solid)
		)
		(fill yes)
		(layer "In13.Cu")
		(net "M_B_CPU1_CLK_DP<0>")
	)
	(gr_poly
		(pts
			(xy 78.532228 -246.305832) (xy 78.432406 -246.205756) (xy 78.432152 -246.205756) (xy 78.33233 -246.305832)
			(xy 78.33233 -246.353584) (xy 78.532228 -246.353584)
		)
		(stroke
			(width 0)
			(type solid)
		)
		(fill yes)
		(layer "In13.Cu")
		(net "M_B_CPU1_SA_DQS_DP<4>")
	)
	(gr_poly
		(pts
			(xy 79.43723 -237.80242) (xy 79.43723 -237.754922) (xy 79.237332 -237.754922) (xy 79.237332 -237.80242)
			(xy 79.337154 -237.902496) (xy 79.337408 -237.902496)
		)
		(stroke
			(width 0)
			(type solid)
		)
		(fill yes)
		(layer "In13.Cu")
		(net "M_B_CPU1_SA_DQS_DP<7>")
	)
	(gr_poly
		(pts
			(xy 79.93761 -237.396274) (xy 79.837788 -237.296198) (xy 79.837534 -237.296198) (xy 79.737712 -237.396274)
			(xy 79.737712 -237.443772) (xy 79.93761 -237.443772)
		)
		(stroke
			(width 0)
			(type solid)
		)
		(fill yes)
		(layer "In13.Cu")
		(net "M_B_CPU1_SA_DQS_DN<7>")
	)
	(gr_poly
		(pts
			(xy 142.81785 -225.505264) (xy 142.776448 -225.481388) (xy 142.64005 -225.517964) (xy 142.639796 -225.517964)
			(xy 142.676626 -225.654616) (xy 142.717774 -225.678492)
		)
		(stroke
			(width 0)
			(type solid)
		)
		(fill yes)
		(layer "In13.Cu")
		(net "M_H_CPU1_SA_DQS_DN<5>")
	)
	(gr_poly
		(pts
			(xy 142.81785 -223.885252) (xy 142.776448 -223.861376) (xy 142.64005 -223.897952) (xy 142.639796 -223.897952)
			(xy 142.676626 -224.034604) (xy 142.717774 -224.05848)
		)
		(stroke
			(width 0)
			(type solid)
		)
		(fill yes)
		(layer "In13.Cu")
		(net "M_H_CPU1_SA_DQS_DP<0>")
	)
	(gr_poly
		(pts
			(xy 142.949422 -226.191064) (xy 142.949676 -226.191064) (xy 142.912846 -226.054412) (xy 142.871698 -226.030536)
			(xy 142.771622 -226.203764) (xy 142.813024 -226.22764)
		)
		(stroke
			(width 0)
			(type solid)
		)
		(fill yes)
		(layer "In13.Cu")
		(net "M_H_CPU1_SA_DQS_DP<5>")
	)
	(gr_poly
		(pts
			(xy 142.949422 -224.571052) (xy 142.949676 -224.571052) (xy 142.912846 -224.4344) (xy 142.871698 -224.410524)
			(xy 142.771622 -224.583752) (xy 142.813024 -224.607628)
		)
		(stroke
			(width 0)
			(type solid)
		)
		(fill yes)
		(layer "In13.Cu")
		(net "M_H_CPU1_SA_DQS_DN<0>")
	)
	(gr_poly
		(pts
			(xy 326.466962 -224.841054) (xy 326.503538 -224.704656) (xy 326.503538 -224.704402) (xy 326.36714 -224.667826)
			(xy 326.328532 -224.690178) (xy 326.428608 -224.863406)
		)
		(stroke
			(width 0)
			(type solid)
		)
		(fill yes)
		(layer "In13.Cu")
		(net "M_B_CPU0_SA_DQ<5>")
	)
	(gr_poly
		(pts
			(xy 327.377298 -237.802166) (xy 327.377298 -237.754668) (xy 327.1774 -237.754668) (xy 327.1774 -237.802166)
			(xy 327.277222 -237.902242) (xy 327.277476 -237.902242)
		)
		(stroke
			(width 0)
			(type solid)
		)
		(fill yes)
		(layer "In13.Cu")
		(net "M_B_CPU0_SA_DQS_DP<7>")
	)
	(gr_poly
		(pts
			(xy 327.877678 -237.39602) (xy 327.777856 -237.295944) (xy 327.777602 -237.295944) (xy 327.67778 -237.39602)
			(xy 327.67778 -237.443518) (xy 327.877678 -237.443518)
		)
		(stroke
			(width 0)
			(type solid)
		)
		(fill yes)
		(layer "In13.Cu")
		(net "M_B_CPU0_SA_DQS_DN<7>")
	)
	(gr_poly
		(pts
			(xy 327.879456 -227.274628) (xy 327.916032 -227.13823) (xy 327.916032 -227.137976) (xy 327.77938 -227.1014)
			(xy 327.740772 -227.123752) (xy 327.840848 -227.29698)
		)
		(stroke
			(width 0)
			(type solid)
		)
		(fill yes)
		(layer "In13.Cu")
		(net "M_B_CPU0_SA_DQ<5>")
	)
	(gr_poly
		(pts
			(xy 390.757918 -225.50501) (xy 390.716516 -225.481134) (xy 390.580118 -225.517964) (xy 390.579864 -225.517964)
			(xy 390.616694 -225.654362) (xy 390.657842 -225.678238)
		)
		(stroke
			(width 0)
			(type solid)
		)
		(fill yes)
		(layer "In13.Cu")
		(net "M_H_CPU0_SA_DQS_DN<5>")
	)
	(gr_poly
		(pts
			(xy 390.757918 -223.884998) (xy 390.716516 -223.861122) (xy 390.580118 -223.897952) (xy 390.579864 -223.897952)
			(xy 390.616694 -224.03435) (xy 390.657842 -224.058226)
		)
		(stroke
			(width 0)
			(type solid)
		)
		(fill yes)
		(layer "In13.Cu")
		(net "M_H_CPU0_SA_DQS_DP<0>")
	)
	(gr_poly
		(pts
			(xy 390.88949 -226.190556) (xy 390.889744 -226.190556) (xy 390.852914 -226.054158) (xy 390.811766 -226.030282)
			(xy 390.71169 -226.20351) (xy 390.753092 -226.227386)
		)
		(stroke
			(width 0)
			(type solid)
		)
		(fill yes)
		(layer "In13.Cu")
		(net "M_H_CPU0_SA_DQS_DP<5>")
	)
	(gr_poly
		(pts
			(xy 390.88949 -224.570544) (xy 390.889744 -224.570544) (xy 390.852914 -224.434146) (xy 390.811766 -224.41027)
			(xy 390.71169 -224.583498) (xy 390.753092 -224.607374)
		)
		(stroke
			(width 0)
			(type solid)
		)
		(fill yes)
		(layer "In13.Cu")
		(net "M_H_CPU0_SA_DQS_DN<0>")
	)
	(gr_poly
		(pts
			(xy 392.230864 -236.602016) (xy 392.131042 -236.50194) (xy 392.130788 -236.50194) (xy 392.030966 -236.602016)
			(xy 392.030966 -236.649514) (xy 392.230864 -236.649514)
		)
		(stroke
			(width 0)
			(type solid)
		)
		(fill yes)
		(layer "In13.Cu")
		(net "M_H_CPU0_SA_DQS_DP<2>")
	)
	(gr_poly
		(pts
			(xy 393.006834 -281.98445) (xy 393.006834 -281.936698) (xy 392.806936 -281.936698) (xy 392.806936 -281.98445)
			(xy 392.906758 -282.084272) (xy 392.907012 -282.084272)
		)
		(stroke
			(width 0)
			(type solid)
		)
		(fill yes)
		(layer "In13.Cu")
		(net "M_H_CPU0_SB_DQS_DP<6>")
	)
	(gr_poly
		(pts
			(xy 17.178782 -411.961584) (xy 17.178782 -408.532584) (xy 17.051782 -408.405584) (xy 13.241782 -408.405584)
			(xy 13.114782 -408.532584) (xy 13.114782 -411.961584) (xy 13.241782 -412.088584) (xy 17.051782 -412.088584)
		)
		(stroke
			(width 0)
			(type solid)
		)
		(fill yes)
		(layer "In13.Cu")
		(net "GND")
	)
	(gr_poly
		(pts
			(xy 446.395602 -425.69511) (xy 446.395602 -422.26611) (xy 446.268602 -422.13911) (xy 442.458602 -422.13911)
			(xy 442.331602 -422.26611) (xy 442.331602 -425.69511) (xy 442.458602 -425.82211) (xy 446.268602 -425.82211)
		)
		(stroke
			(width 0)
			(type solid)
		)
		(fill yes)
		(layer "In13.Cu")
		(net "GND")
	)
	(gr_poly
		(pts
			(xy 32.7152 -366.31753) (xy 32.7152 -362.1024) (xy 32.7152 -361.8992) (xy 32.6898 -361.8738) (xy 28.2956 -361.8738)
			(xy 28.245308 -361.924092) (xy 28.245308 -362.086144) (xy 28.245308 -366.318292) (xy 28.2702 -366.34293)
			(xy 32.6898 -366.34293)
		)
		(stroke
			(width 0)
			(type solid)
		)
		(fill yes)
		(layer "In13.Cu")
		(net "GND")
	)
	(gr_poly
		(pts
			(xy 312.3692 -362.88853) (xy 312.3692 -358.6734) (xy 312.3692 -358.668574) (xy 312.230262 -358.529636)
			(xy 308.013862 -358.529636) (xy 307.899308 -358.64419) (xy 307.899308 -358.657144) (xy 307.899308 -362.889292)
			(xy 307.9242 -362.91393) (xy 312.3438 -362.91393)
		)
		(stroke
			(width 0)
			(type solid)
		)
		(fill yes)
		(layer "In13.Cu")
		(net "GND")
	)
	(gr_poly
		(pts
			(xy 8.62076 -102.117144) (xy 8.887968 -101.849936) (xy 8.887968 -97.430844) (xy 8.669528 -97.212404)
			(xy 6.003544 -97.212404) (xy 5.494782 -97.721166) (xy 5.36956 -97.846388) (xy 5.084572 -98.131376)
			(xy 5.084572 -101.832156) (xy 5.36956 -102.117144) (xy 5.494782 -102.242366) (xy 8.495538 -102.242366)
		)
		(stroke
			(width 0)
			(type solid)
		)
		(fill yes)
		(layer "In13.Cu")
		(net "GND")
	)
	(gr_poly
		(pts
			(xy 441.045092 -43.578018) (xy 441.045092 -43.451018) (xy 441.045092 -38.853618) (xy 440.918092 -38.726618)
			(xy 434.288692 -38.726618) (xy 433.780692 -38.726618) (xy 433.628292 -38.879018) (xy 433.628292 -43.001946)
			(xy 433.628292 -43.618658) (xy 433.780692 -43.771058) (xy 438.893458 -43.771058) (xy 440.852052 -43.771058)
		)
		(stroke
			(width 0)
			(type solid)
		)
		(fill yes)
		(layer "In13.Cu")
		(net "P12V_AUX")
	)
	(gr_poly
		(pts
			(xy 155.952952 -319.820798) (xy 155.952952 -316.907418) (xy 155.693364 -316.64783) (xy 151.944832 -316.64783)
			(xy 151.40559 -316.108588) (xy 151.40559 -315.483494) (xy 151.140414 -315.218318) (xy 147.148804 -315.218318)
			(xy 147.023582 -315.34354) (xy 146.703796 -315.663326) (xy 146.703796 -318.473074) (xy 147.209256 -318.978534)
			(xy 150.965154 -318.978534) (xy 151.2951 -319.30848) (xy 151.2951 -319.870074) (xy 151.382476 -319.95745)
			(xy 151.549608 -319.95745) (xy 155.8163 -319.95745)
		)
		(stroke
			(width 0)
			(type solid)
		)
		(fill yes)
		(layer "In13.Cu")
		(net "GND")
	)
	(gr_poly
		(pts
			(xy 137.305034 -44.07916) (xy 137.305034 -40.835834) (xy 136.802114 -40.332914) (xy 136.802114 -34.82594)
			(xy 137.358374 -34.26968) (xy 138.14298 -34.26968) (xy 138.29538 -34.11728) (xy 138.29538 -33.89884)
			(xy 138.1506 -33.75406) (xy 137.3378 -32.94126) (xy 136.8044 -32.94126) (xy 136.57834 -32.94126)
			(xy 136.167114 -33.352486) (xy 135.432292 -34.087308) (xy 135.432292 -39.445692) (xy 133.743446 -41.134792)
			(xy 132.255768 -41.134792) (xy 132.19557 -41.19499) (xy 132.19557 -42.08907) (xy 134.24916 -44.14266)
			(xy 137.241534 -44.14266)
		)
		(stroke
			(width 0)
			(type solid)
		)
		(fill yes)
		(layer "In13.Cu")
		(net "P1V2_CPU0_USB_DVDD12")
	)
	(gr_poly
		(pts
			(arc
				(start 25.630632 -372.366032)
				(mid 25.658819 -372.357495)
				(end 25.677622 -372.33479)
			)
			(xy 25.683464 -372.320312) (xy 25.677622 -372.290594)
			(arc
				(start 24.550116 -371.163088)
				(mid 24.53367 -371.152162)
				(end 24.514302 -371.148356)
			)
			(arc
				(start 19.935698 -371.148356)
				(mid 19.884988 -371.144178)
				(end 19.835622 -371.131846)
			)
			(xy 19.823938 -371.127782) (xy 19.799808 -371.131592)
			(arc
				(start 19.722846 -371.18671)
				(mid 19.707314 -371.204864)
				(end 19.701764 -371.228112)
			)
			(arc
				(start 19.701764 -371.30863)
				(mid 19.705597 -371.327987)
				(end 19.716496 -371.344444)
			)
			(arc
				(start 20.723352 -372.3513)
				(mid 20.739798 -372.362226)
				(end 20.759166 -372.366032)
			)
		)
		(stroke
			(width 0)
			(type solid)
		)
		(fill yes)
		(layer "In13.Cu")
		(net "GND")
	)
	(gr_poly
		(pts
			(arc
				(start 161.33699 -171.42206)
				(mid 161.003742 -171.42206)
				(end 161.33699 -171.42206)
			)
		)
		(stroke
			(width 0)
			(type solid)
		)
		(fill yes)
		(layer "In13.Cu")
		(net "GND")
	)
	(gr_poly
		(pts
			(arc
				(start 162.75939 -171.42206)
				(mid 162.426142 -171.42206)
				(end 162.75939 -171.42206)
			)
		)
		(stroke
			(width 0)
			(type solid)
		)
		(fill yes)
		(layer "In13.Cu")
		(net "GND")
	)
	(gr_poly
		(pts
			(arc
				(start 182.387748 -14.502892)
				(mid 182.021988 -14.502892)
				(end 182.387748 -14.502892)
			)
		)
		(stroke
			(width 0)
			(type solid)
		)
		(fill yes)
		(layer "In13.Cu")
		(net "GND")
	)
	(gr_poly
		(pts
			(arc
				(start 300.26991 -150.588472)
				(mid 299.90415 -150.588472)
				(end 300.26991 -150.588472)
			)
		)
		(stroke
			(width 0)
			(type solid)
		)
		(fill yes)
		(layer "In13.Cu")
		(net "GND")
	)
	(gr_poly
		(pts
			(arc
				(start 303.898046 -150.119588)
				(mid 303.532286 -150.119588)
				(end 303.898046 -150.119588)
			)
		)
		(stroke
			(width 0)
			(type solid)
		)
		(fill yes)
		(layer "In13.Cu")
		(net "GND")
	)
	(gr_poly
		(pts
			(arc
				(start 403.689058 -318.63284)
				(mid 403.708581 -318.628939)
				(end 403.725126 -318.617854)
			)
			(arc
				(start 404.128986 -318.213994)
				(mid 404.140097 -318.19746)
				(end 404.143972 -318.177926)
			)
			(arc
				(start 404.143972 -316.060328)
				(mid 404.140071 -316.040805)
				(end 404.128986 -316.02426)
			)
			(arc
				(start 403.106128 -315.001402)
				(mid 403.089594 -314.990291)
				(end 403.07006 -314.986416)
			)
			(arc
				(start 394.962634 -314.986416)
				(mid 394.943111 -314.990317)
				(end 394.926566 -315.001402)
			)
			(arc
				(start 394.817092 -315.110876)
				(mid 394.805981 -315.12741)
				(end 394.802106 -315.146944)
			)
			(arc
				(start 394.802106 -317.735458)
				(mid 394.806007 -317.754981)
				(end 394.817092 -317.771526)
			)
			(arc
				(start 395.66342 -318.617854)
				(mid 395.679954 -318.628965)
				(end 395.699488 -318.63284)
			)
		)
		(stroke
			(width 0)
			(type solid)
		)
		(fill yes)
		(layer "In13.Cu")
		(net "GND")
	)
	(gr_poly
		(pts
			(xy 229.6795 -435.74208) (xy 229.6795 -422.049194) (xy 234.763056 -416.965638) (xy 272.06448 -416.965638)
			(xy 280.05024 -408.979878)
			(arc
				(start 280.05024 -394.963396)
				(mid 280.046339 -394.943873)
				(end 280.035254 -394.927328)
			)
			(arc
				(start 279.651206 -394.54328)
				(mid 279.634672 -394.532169)
				(end 279.615138 -394.528294)
			)
			(xy 278.21382 -394.528294) (xy 241.711734 -394.528294) (xy 240.424208 -394.528294) (xy 239.91189 -395.040612)
			(xy 239.91189 -404.086822) (xy 239.91189 -405.227536) (xy 239.91189 -405.609298) (xy 234.87634 -410.644848)
			(xy 229.69855 -410.644848) (xy 229.676198 -410.6672) (xy 227.067872 -413.275526) (xy 196.769482 -413.275526)
			(xy 196.26072 -413.784288) (xy 196.26072 -414.072832) (xy 196.26072 -421.757602)
			(arc
				(start 206.039974 -431.536856)
				(mid 206.051085 -431.55339)
				(end 206.05496 -431.572924)
			)
			(xy 206.05496 -435.09946) (xy 207.43418 -436.47868) (xy 228.9429 -436.47868)
		)
		(stroke
			(width 0)
			(type solid)
		)
		(fill yes)
		(layer "In13.Cu")
		(net "P12V_PSU")
	)
	(gr_poly
		(pts
			(arc
				(start 81.154778 -2.750312)
				(mid 81.182917 -2.732466)
				(end 81.193894 -2.701036)
			)
			(arc
				(start 81.193894 -0.5588)
				(mid 81.179015 -0.522879)
				(end 81.143094 -0.508)
			)
			(arc
				(start 13.660882 -0.508)
				(mid 13.624961 -0.522879)
				(end 13.610082 -0.5588)
			)
			(arc
				(start 13.610082 -2.701036)
				(mid 13.621129 -2.732411)
				(end 13.649198 -2.750312)
			)
			(xy 13.762482 -2.77749) (xy 13.794486 -2.762504)
			(arc
				(start 13.80236 -2.746756)
				(mid 13.928356 -2.557713)
				(end 14.095984 -2.404364)
			)
			(xy 14.11732 -2.363216) (xy 14.11732 -1.014984) (xy 80.686656 -1.014984) (xy 80.686656 -2.363216)
			(arc
				(start 80.707992 -2.404364)
				(mid 80.875659 -2.55768)
				(end 81.001616 -2.746756)
			)
			(xy 81.00949 -2.762504) (xy 81.041494 -2.77749)
		)
		(stroke
			(width 0)
			(type solid)
		)
		(fill yes)
		(layer "In13.Cu")
		(net "GND")
	)
	(gr_poly
		(pts
			(arc
				(start 194.154806 -8.03021)
				(mid 194.182945 -8.012364)
				(end 194.193922 -7.980934)
			)
			(arc
				(start 194.193922 -5.838698)
				(mid 194.179043 -5.802777)
				(end 194.143122 -5.787898)
			)
			(arc
				(start 126.66091 -5.787898)
				(mid 126.624989 -5.802777)
				(end 126.61011 -5.838698)
			)
			(arc
				(start 126.61011 -7.980934)
				(mid 126.621157 -8.012309)
				(end 126.649226 -8.03021)
			)
			(xy 126.76251 -8.057388) (xy 126.794514 -8.042402)
			(arc
				(start 126.802388 -8.026654)
				(mid 126.928384 -7.837611)
				(end 127.096012 -7.684262)
			)
			(xy 127.117348 -7.643114) (xy 127.117348 -6.295136) (xy 193.686684 -6.295136) (xy 193.686684 -7.643114)
			(arc
				(start 193.70802 -7.684262)
				(mid 193.875687 -7.837578)
				(end 194.001644 -8.026654)
			)
			(xy 194.009518 -8.042402) (xy 194.041522 -8.057388)
		)
		(stroke
			(width 0)
			(type solid)
		)
		(fill yes)
		(layer "In13.Cu")
		(net "GND")
	)
	(gr_poly
		(pts
			(arc
				(start 455.654918 -2.75082)
				(mid 455.683057 -2.732974)
				(end 455.694034 -2.701544)
			)
			(arc
				(start 455.694034 -0.5588)
				(mid 455.679155 -0.522879)
				(end 455.643234 -0.508)
			)
			(arc
				(start 388.160768 -0.508)
				(mid 388.124847 -0.522879)
				(end 388.109968 -0.5588)
			)
			(arc
				(start 388.109968 -2.701036)
				(mid 388.121015 -2.732411)
				(end 388.149084 -2.750312)
			)
			(xy 388.262368 -2.77749) (xy 388.294372 -2.762504)
			(arc
				(start 388.302246 -2.746756)
				(mid 388.428345 -2.557672)
				(end 388.596124 -2.404364)
			)
			(arc
				(start 388.596124 -2.404364)
				(mid 388.610195 -2.388884)
				(end 388.616952 -2.369058)
			)
			(xy 388.616952 -1.014984) (xy 455.186796 -1.014984) (xy 455.186796 -2.36347)
			(arc
				(start 455.208132 -2.404618)
				(mid 455.3758 -2.558068)
				(end 455.501756 -2.747264)
			)
			(xy 455.50963 -2.763012) (xy 455.54138 -2.777744)
		)
		(stroke
			(width 0)
			(type solid)
		)
		(fill yes)
		(layer "In13.Cu")
		(net "GND")
	)
	(gr_poly
		(pts
			(arc
				(start 5.850128 -404.747984)
				(mid 5.886049 -404.733105)
				(end 5.900928 -404.697184)
			)
			(arc
				(start 5.900928 -396.193264)
				(mid 5.924646 -396.073555)
				(end 5.992368 -395.97203)
			)
			(arc
				(start 9.981946 -391.982452)
				(mid 9.993008 -391.966035)
				(end 9.996932 -391.946638)
			)
			(arc
				(start 9.996932 -388.805928)
				(mid 9.992982 -388.786541)
				(end 9.981946 -388.770114)
			)
			(arc
				(start 8.025384 -386.813552)
				(mid 8.008938 -386.802626)
				(end 7.98957 -386.79882)
			)
			(arc
				(start 6.565138 -386.79882)
				(mid 6.4454 -386.774985)
				(end 6.343904 -386.707126)
			)
			(arc
				(start 4.670044 -385.033012)
				(mid 4.63414 -385.018252)
				(end 4.598162 -385.033012)
			)
			(arc
				(start 4.041394 -385.58978)
				(mid 4.030283 -385.606314)
				(end 4.026408 -385.625848)
			)
			(arc
				(start 4.026408 -403.307042)
				(mid 4.030309 -403.326565)
				(end 4.041394 -403.34311)
			)
			(arc
				(start 5.431282 -404.732998)
				(mid 5.447816 -404.744109)
				(end 5.46735 -404.747984)
			)
		)
		(stroke
			(width 0)
			(type solid)
		)
		(fill yes)
		(layer "In13.Cu")
		(net "GND")
	)
	(gr_poly
		(pts
			(arc
				(start 7.548626 -137.9601)
				(mid 7.568149 -137.956199)
				(end 7.584694 -137.945114)
			)
			(arc
				(start 7.679944 -137.849864)
				(mid 7.691055 -137.83333)
				(end 7.69493 -137.813796)
			)
			(xy 7.69493 -135.794496) (xy 7.67461 -135.767572)
			(arc
				(start 7.6581 -135.762746)
				(mid 7.381151 -135.39597)
				(end 7.6581 -135.029194)
			)
			(xy 7.67461 -135.024368) (xy 7.69493 -134.997444)
			(arc
				(start 7.69493 -132.962396)
				(mid 7.691029 -132.942873)
				(end 7.679944 -132.926328)
			)
			(arc
				(start 7.584694 -132.831078)
				(mid 7.56816 -132.819967)
				(end 7.548626 -132.816092)
			)
			(arc
				(start 4.00177 -132.816092)
				(mid 3.982247 -132.819993)
				(end 3.965702 -132.831078)
			)
			(arc
				(start 3.870452 -132.926328)
				(mid 3.859341 -132.942862)
				(end 3.855466 -132.962396)
			)
			(arc
				(start 3.855466 -137.813796)
				(mid 3.859367 -137.833319)
				(end 3.870452 -137.849864)
			)
			(arc
				(start 3.965702 -137.945114)
				(mid 3.982236 -137.956225)
				(end 4.00177 -137.9601)
			)
		)
		(stroke
			(width 0)
			(type solid)
		)
		(fill yes)
		(layer "In13.Cu")
		(net "GND")
	)
	(gr_poly
		(pts
			(xy 108.436918 -24.151082) (xy 108.6612 -23.9268) (xy 108.6612 -20.1422) (xy 108.3564 -19.8374) (xy 105.204768 -19.8374)
			(xy 104.6226 -19.8374) (xy 103.8352 -20.6248) (xy 103.8352 -24.54148) (xy 104.799891 -24.54148) (xy 104.803956 -24.485932)
			(xy 104.816066 -24.431567) (xy 104.835963 -24.379546) (xy 104.863222 -24.330975) (xy 104.897262 -24.286892)
			(xy 104.937359 -24.248234) (xy 104.982656 -24.215826) (xy 105.03219 -24.190359) (xy 105.084904 -24.172376)
			(xy 105.139674 -24.162259) (xy 105.195333 -24.160225) (xy 105.250696 -24.166317) (xy 105.304582 -24.180404)
			(xy 105.355842 -24.202188) (xy 105.403385 -24.231202) (xy 105.446196 -24.26683) (xy 105.483363 -24.308311)
			(xy 105.514095 -24.354762) (xy 105.537736 -24.405193) (xy 105.553782 -24.458528) (xy 105.561892 -24.513632)
			(xy 105.5624 -24.54148) (xy 106.273091 -24.54148) (xy 106.277156 -24.485932) (xy 106.289266 -24.431567)
			(xy 106.309163 -24.379546) (xy 106.336422 -24.330975) (xy 106.370462 -24.286892) (xy 106.410559 -24.248234)
			(xy 106.455856 -24.215826) (xy 106.50539 -24.190359) (xy 106.558104 -24.172376) (xy 106.612874 -24.162259)
			(xy 106.668533 -24.160225) (xy 106.723896 -24.166317) (xy 106.777782 -24.180404) (xy 106.829042 -24.202188)
			(xy 106.876585 -24.231202) (xy 106.919396 -24.26683) (xy 106.956563 -24.308311) (xy 106.987295 -24.354762)
			(xy 107.010936 -24.405193) (xy 107.026982 -24.458528) (xy 107.035092 -24.513632) (xy 107.0356 -24.54148)
			(xy 107.035092 -24.569328) (xy 107.026982 -24.624432) (xy 107.010936 -24.677767) (xy 106.987295 -24.728198)
			(xy 106.956563 -24.774649) (xy 106.919396 -24.81613) (xy 106.876585 -24.851758) (xy 106.829042 -24.880772)
			(xy 106.777782 -24.902556) (xy 106.723896 -24.916643) (xy 106.668533 -24.922735) (xy 106.612874 -24.920701)
			(xy 106.558104 -24.910584) (xy 106.50539 -24.892601) (xy 106.455856 -24.867134) (xy 106.410559 -24.834726)
			(xy 106.370462 -24.796068) (xy 106.336422 -24.751985) (xy 106.309163 -24.703414) (xy 106.289266 -24.651393)
			(xy 106.277156 -24.597028) (xy 106.273091 -24.54148) (xy 105.5624 -24.54148) (xy 105.561892 -24.569328)
			(xy 105.553782 -24.624432) (xy 105.537736 -24.677767) (xy 105.514095 -24.728198) (xy 105.483363 -24.774649)
			(xy 105.446196 -24.81613) (xy 105.403385 -24.851758) (xy 105.355842 -24.880772) (xy 105.304582 -24.902556)
			(xy 105.250696 -24.916643) (xy 105.195333 -24.922735) (xy 105.139674 -24.920701) (xy 105.084904 -24.910584)
			(xy 105.03219 -24.892601) (xy 104.982656 -24.867134) (xy 104.937359 -24.834726) (xy 104.897262 -24.796068)
			(xy 104.863222 -24.751985) (xy 104.835963 -24.703414) (xy 104.816066 -24.651393) (xy 104.803956 -24.597028)
			(xy 104.799891 -24.54148) (xy 103.8352 -24.54148) (xy 103.8352 -25.3746) (xy 104.0384 -25.5778) (xy 107.0102 -25.5778)
		)
		(stroke
			(width 0)
			(type solid)
		)
		(fill yes)
		(layer "In13.Cu")
		(net "GND")
	)
	(gr_poly
		(pts
			(xy 125.505718 -31.1658) (xy 125.515787 -31.165373) (xy 125.534386 -31.157654) (xy 125.541786 -31.150814)
			(xy 125.918214 -30.774386) (xy 125.925609 -30.767532) (xy 125.944208 -30.75979) (xy 125.954282 -30.7594)
			(xy 127.156718 -30.7594) (xy 127.166787 -30.758973) (xy 127.185386 -30.751254) (xy 127.192786 -30.744414)
			(xy 128.026414 -29.910786) (xy 128.033268 -29.903391) (xy 128.04101 -29.884792) (xy 128.0414 -29.874718)
			(xy 128.0414 -28.682696) (xy 128.041074 -28.6738) (xy 128.034999 -28.65708) (xy 128.023555 -28.643459)
			(xy 128.016 -28.638754) (xy 127.927862 -28.5877) (xy 127.900938 -28.5877) (xy 127.889 -28.594558)
			(xy 127.867202 -28.606699) (xy 127.821109 -28.625802) (xy 127.772916 -28.638722) (xy 127.723448 -28.645238)
			(xy 127.6985 -28.645612) (xy 127.671248 -28.645126) (xy 127.6173 -28.63737) (xy 127.565005 -28.622014)
			(xy 127.515427 -28.599373) (xy 127.469576 -28.569906) (xy 127.428386 -28.534214) (xy 127.392694 -28.493024)
			(xy 127.363227 -28.447173) (xy 127.340586 -28.397595) (xy 127.32523 -28.3453) (xy 127.317474 -28.291352)
			(xy 127.317474 -28.236848) (xy 127.32523 -28.1829) (xy 127.340586 -28.130605) (xy 127.363227 -28.081027)
			(xy 127.392694 -28.035176) (xy 127.428386 -27.993986) (xy 127.469576 -27.958294) (xy 127.515427 -27.928827)
			(xy 127.565005 -27.906186) (xy 127.6173 -27.89083) (xy 127.671248 -27.883074) (xy 127.6985 -27.882596)
			(xy 127.723443 -27.883026) (xy 127.772899 -27.889566) (xy 127.821083 -27.902484) (xy 127.867179 -27.92156)
			(xy 127.889 -27.93365) (xy 127.900938 -27.940508) (xy 127.927862 -27.940508) (xy 128.016 -27.889454)
			(xy 128.023493 -27.884675) (xy 128.034908 -27.871071) (xy 128.041 -27.85439) (xy 128.0414 -27.845512)
			(xy 128.0414 -27.072082) (xy 128.040973 -27.062013) (xy 128.033254 -27.043414) (xy 128.026414 -27.036014)
			(xy 127.548386 -26.557986) (xy 127.540991 -26.551132) (xy 127.522392 -26.54339) (xy 127.512318 -26.543)
			(xy 123.490482 -26.543) (xy 123.480413 -26.543427) (xy 123.461814 -26.551146) (xy 123.454414 -26.557986)
			(xy 122.468386 -27.544014) (xy 122.461532 -27.551409) (xy 122.45379 -27.570008) (xy 122.4534 -27.580082)
			(xy 122.4534 -29.530294) (xy 126.789178 -29.530294) (xy 126.793249 -29.474672) (xy 126.805375 -29.420235)
			(xy 126.825298 -29.368144) (xy 126.852594 -29.319509) (xy 126.88668 -29.275366) (xy 126.926829 -29.236657)
			(xy 126.972187 -29.204206) (xy 127.021787 -29.178705) (xy 127.074571 -29.160698) (xy 127.129414 -29.150568)
			(xy 127.185148 -29.148531) (xy 127.240585 -29.154631) (xy 127.294542 -29.168737) (xy 127.345871 -29.190549)
			(xy 127.393477 -29.219603) (xy 127.436345 -29.255278) (xy 127.473562 -29.296815) (xy 127.504335 -29.343328)
			(xy 127.528007 -29.393825) (xy 127.544075 -29.447232) (xy 127.552195 -29.502408) (xy 127.552704 -29.530294)
			(xy 127.552195 -29.55818) (xy 127.544075 -29.613356) (xy 127.528007 -29.666763) (xy 127.504335 -29.71726)
			(xy 127.473562 -29.763773) (xy 127.436345 -29.80531) (xy 127.393477 -29.840985) (xy 127.345871 -29.870039)
			(xy 127.294542 -29.891851) (xy 127.240585 -29.905957) (xy 127.185148 -29.912057) (xy 127.129414 -29.91002)
			(xy 127.074571 -29.89989) (xy 127.021787 -29.881883) (xy 126.972187 -29.856382) (xy 126.926829 -29.823931)
			(xy 126.88668 -29.785222) (xy 126.852594 -29.741079) (xy 126.825298 -29.692444) (xy 126.805375 -29.640353)
			(xy 126.793249 -29.585916) (xy 126.789178 -29.530294) (xy 122.4534 -29.530294) (xy 122.4534 -30.255718)
			(xy 122.453827 -30.265787) (xy 122.461546 -30.284386) (xy 122.468386 -30.291786) (xy 123.327414 -31.150814)
			(xy 123.334809 -31.157668) (xy 123.353408 -31.16541) (xy 123.363482 -31.1658)
		)
		(stroke
			(width 0)
			(type solid)
		)
		(fill yes)
		(layer "In13.Cu")
		(net "GND")
	)
	(gr_poly
		(pts
			(arc
				(start 86.147656 -139.597892)
				(mid 86.16715 -139.594108)
				(end 86.183724 -139.58316)
			)
			(xy 86.657942 -139.108688) (xy 86.66099 -139.071604)
			(arc
				(start 86.650068 -139.056364)
				(mid 86.599045 -138.955461)
				(end 86.581488 -138.843766)
			)
			(arc
				(start 86.581488 -138.678666)
				(mid 86.609141 -138.539556)
				(end 86.687914 -138.421618)
			)
			(arc
				(start 86.822788 -138.286744)
				(mid 86.940708 -138.20786)
				(end 87.079836 -138.180064)
			)
			(arc
				(start 87.130636 -138.180064)
				(mid 87.166557 -138.165185)
				(end 87.181436 -138.129264)
			)
			(arc
				(start 87.181436 -138.078718)
				(mid 87.186469 -138.018188)
				(end 87.201502 -137.959338)
			)
			(xy 87.205566 -137.947654) (xy 87.20201 -137.923524)
			(arc
				(start 87.146892 -137.8458)
				(mid 87.128782 -137.8301)
				(end 87.10549 -137.824464)
			)
			(arc
				(start 83.240372 -137.824464)
				(mid 83.221015 -137.828297)
				(end 83.204558 -137.839196)
			)
			(xy 83.146392 -137.897362) (xy 83.138772 -137.915396)
			(arc
				(start 83.138772 -137.92581)
				(mid 82.757264 -138.306557)
				(end 82.375756 -137.92581)
			)
			(xy 82.375756 -137.915396) (xy 82.368136 -137.897362)
			(arc
				(start 82.30997 -137.839196)
				(mid 82.293524 -137.82827)
				(end 82.274156 -137.824464)
			)
			(arc
				(start 80.080358 -137.824464)
				(mid 80.060835 -137.828365)
				(end 80.04429 -137.83945)
			)
			(arc
				(start 79.82331 -138.06043)
				(mid 79.809003 -138.088044)
				(end 79.813404 -138.11885)
			)
			(xy 79.86268 -138.219942) (xy 79.891128 -138.235182)
			(arc
				(start 79.907384 -138.23315)
				(mid 79.930709 -138.231043)
				(end 79.95412 -138.230356)
			)
			(arc
				(start 79.95412 -138.230356)
				(mid 80.223887 -138.881631)
				(end 79.572612 -138.611864)
			)
			(arc
				(start 79.572612 -138.611864)
				(mid 79.573284 -138.588452)
				(end 79.575406 -138.565128)
			)
			(xy 79.577438 -138.548872) (xy 79.562198 -138.520424)
			(arc
				(start 79.461106 -138.471148)
				(mid 79.430289 -138.466686)
				(end 79.402686 -138.481054)
			)
			(arc
				(start 78.372462 -139.511278)
				(mid 78.358456 -139.537269)
				(end 78.361286 -139.56665)
			)
			(xy 78.367382 -139.581128) (xy 78.392782 -139.597892)
		)
		(stroke
			(width 0)
			(type solid)
		)
		(fill yes)
		(layer "In13.Cu")
		(net "GND")
	)
	(gr_poly
		(pts
			(arc
				(start 88.723978 -140.019532)
				(mid 88.746267 -140.014505)
				(end 88.76411 -140.000228)
			)
			(xy 88.820498 -139.9286) (xy 88.825578 -139.90574)
			(arc
				(start 88.822784 -139.89431)
				(mid 88.814947 -139.850167)
				(end 88.81237 -139.80541)
			)
			(arc
				(start 88.81237 -139.80541)
				(mid 89.193878 -139.423902)
				(end 89.575386 -139.80541)
			)
			(arc
				(start 89.575386 -139.80541)
				(mid 89.572782 -139.850164)
				(end 89.564972 -139.89431)
			)
			(xy 89.562178 -139.90574) (xy 89.567258 -139.9286)
			(arc
				(start 89.623646 -140.000228)
				(mid 89.641483 -140.014519)
				(end 89.663778 -140.019532)
			)
			(arc
				(start 90.894916 -140.019532)
				(mid 90.91441 -140.015748)
				(end 90.930984 -140.0048)
			)
			(arc
				(start 92.321126 -138.614404)
				(mid 92.335961 -138.57859)
				(end 92.321126 -138.542776)
			)
			(arc
				(start 91.736164 -137.95756)
				(mid 91.719601 -137.946586)
				(end 91.700096 -137.942828)
			)
			(arc
				(start 90.619834 -137.942828)
				(mid 90.594699 -137.949337)
				(end 90.576146 -137.967466)
			)
			(xy 90.524584 -138.054334) (xy 90.524076 -138.08075)
			(arc
				(start 90.53068 -138.092942)
				(mid 90.565178 -138.181112)
				(end 90.576908 -138.27506)
			)
			(arc
				(start 90.576908 -138.27506)
				(mid 90.1954 -138.656568)
				(end 89.813892 -138.27506)
			)
			(arc
				(start 89.813892 -138.27506)
				(mid 89.825632 -138.181114)
				(end 89.86012 -138.092942)
			)
			(xy 89.861644 -138.089894) (xy 88.705182 -138.089894)
			(arc
				(start 88.430608 -138.364468)
				(mid 88.312688 -138.443352)
				(end 88.17356 -138.471148)
			)
			(arc
				(start 88.12276 -138.471148)
				(mid 88.086839 -138.486027)
				(end 88.07196 -138.521948)
			)
			(arc
				(start 88.07196 -138.572494)
				(mid 88.044307 -138.711604)
				(end 87.965534 -138.829542)
			)
			(arc
				(start 87.83066 -138.964416)
				(mid 87.71274 -139.0433)
				(end 87.573612 -139.071096)
			)
			(arc
				(start 87.522812 -139.071096)
				(mid 87.486891 -139.085975)
				(end 87.472012 -139.121896)
			)
			(arc
				(start 87.472012 -139.172442)
				(mid 87.444359 -139.311552)
				(end 87.365586 -139.42949)
			)
			(arc
				(start 86.862158 -139.932918)
				(mid 86.848348 -139.958947)
				(end 86.851236 -139.98829)
			)
			(xy 86.857078 -140.002768) (xy 86.882478 -140.019532)
		)
		(stroke
			(width 0)
			(type solid)
		)
		(fill yes)
		(layer "In13.Cu")
		(net "GND")
	)
	(gr_poly
		(pts
			(arc
				(start 124.102114 -12.795504)
				(mid 126.234222 -11.912198)
				(end 127.117348 -9.780016)
			)
			(arc
				(start 127.117348 -9.256776)
				(mid 127.111697 -9.233491)
				(end 127.096012 -9.215374)
			)
			(arc
				(start 127.096012 -9.215374)
				(mid 126.928345 -9.062058)
				(end 126.802388 -8.872982)
			)
			(xy 126.794514 -8.857234) (xy 126.76251 -8.842248)
			(arc
				(start 126.649226 -8.869426)
				(mid 126.621087 -8.887272)
				(end 126.61011 -8.918702)
			)
			(arc
				(start 126.61011 -9.780016)
				(mid 125.875535 -11.553437)
				(end 124.102114 -12.288012)
			)
			(arc
				(start 83.70189 -12.288012)
				(mid 81.928469 -11.553437)
				(end 81.193894 -9.780016)
			)
			(arc
				(start 81.193894 -3.638804)
				(mid 81.182847 -3.607429)
				(end 81.154778 -3.589528)
			)
			(xy 81.041494 -3.56235) (xy 81.00949 -3.577336)
			(arc
				(start 81.001616 -3.593084)
				(mid 80.87562 -3.782127)
				(end 80.707992 -3.935476)
			)
			(arc
				(start 80.707992 -3.935476)
				(mid 80.692292 -3.953586)
				(end 80.686656 -3.976878)
			)
			(arc
				(start 80.686656 -9.780524)
				(mid 81.569887 -11.912452)
				(end 83.70189 -12.795504)
			)
		)
		(stroke
			(width 0)
			(type solid)
		)
		(fill yes)
		(layer "In13.Cu")
		(net "GND")
	)
	(gr_poly
		(pts
			(xy 113.577116 -171.643802) (xy 115.254278 -171.643802) (xy 115.290854 -171.607226) (xy 115.290854 -169.674286)
			(xy 115.290854 -169.629074) (xy 114.39906 -168.73728) (xy 114.39906 -165.691058) (xy 114.65052 -165.439598)
			(xy 115.13058 -165.439598) (xy 118.482364 -165.439598) (xy 118.95836 -164.963602) (xy 121.806716 -164.963602)
			(xy 121.857516 -164.912802) (xy 123.560078 -164.912802) (xy 123.584716 -164.888164) (xy 123.584716 -162.952684)
			(xy 123.584716 -162.863276) (xy 122.70994 -161.9885) (xy 122.70994 -160.958022) (xy 122.70994 -159.71012)
			(xy 123.081542 -159.338518) (xy 123.0884 -159.338518) (xy 126.124716 -156.302202) (xy 127.36576 -156.302202)
			(xy 130.264916 -156.302202) (xy 130.315716 -156.251402) (xy 132.013198 -156.251402) (xy 132.042916 -156.221684)
			(xy 132.042916 -154.291284) (xy 132.042916 -154.196796) (xy 131.17322 -153.3271) (xy 131.17322 -150.215092)
			(xy 130.518154 -149.560026) (xy 130.01498 -149.056852) (xy 129.593848 -148.63572) (xy 107.678474 -148.63572)
			(xy 105.95102 -150.363174) (xy 105.95102 -150.984134) (xy 109.251492 -150.984134) (xy 109.251492 -150.899438)
			(xy 109.259543 -150.815124) (xy 109.275572 -150.731958) (xy 109.299433 -150.650691) (xy 109.330912 -150.572061)
			(xy 109.369723 -150.49678) (xy 109.415513 -150.425528) (xy 109.467869 -150.358952) (xy 109.526317 -150.297654)
			(xy 109.590327 -150.242189) (xy 109.659319 -150.19306) (xy 109.732669 -150.150711) (xy 109.809712 -150.115527)
			(xy 109.889751 -150.087825) (xy 109.97206 -150.067857) (xy 110.055895 -150.055804) (xy 110.140496 -150.051774)
			(xy 110.225097 -150.055804) (xy 110.308932 -150.067857) (xy 110.391241 -150.087825) (xy 110.47128 -150.115527)
			(xy 110.548323 -150.150711) (xy 110.621673 -150.19306) (xy 110.690665 -150.242189) (xy 110.754675 -150.297654)
			(xy 110.813123 -150.358952) (xy 110.865479 -150.425528) (xy 110.911269 -150.49678) (xy 110.95008 -150.572061)
			(xy 110.981559 -150.650691) (xy 111.00542 -150.731958) (xy 111.021449 -150.815124) (xy 111.0295 -150.899438)
			(xy 111.030004 -150.941786) (xy 111.0295 -150.984134) (xy 111.751614 -150.984134) (xy 111.751614 -150.899438)
			(xy 111.759665 -150.815124) (xy 111.775694 -150.731958) (xy 111.799555 -150.650691) (xy 111.831034 -150.572061)
			(xy 111.869845 -150.49678) (xy 111.915635 -150.425528) (xy 111.967991 -150.358952) (xy 112.026439 -150.297654)
			(xy 112.090449 -150.242189) (xy 112.159441 -150.19306) (xy 112.232791 -150.150711) (xy 112.309834 -150.115527)
			(xy 112.389873 -150.087825) (xy 112.472182 -150.067857) (xy 112.556017 -150.055804) (xy 112.640618 -150.051774)
			(xy 112.725219 -150.055804) (xy 112.809054 -150.067857) (xy 112.891363 -150.087825) (xy 112.971402 -150.115527)
			(xy 113.048445 -150.150711) (xy 113.121795 -150.19306) (xy 113.190787 -150.242189) (xy 113.254797 -150.297654)
			(xy 113.313245 -150.358952) (xy 113.365601 -150.425528) (xy 113.411391 -150.49678) (xy 113.450202 -150.572061)
			(xy 113.481681 -150.650691) (xy 113.505542 -150.731958) (xy 113.521571 -150.815124) (xy 113.529622 -150.899438)
			(xy 113.530126 -150.941786) (xy 113.529622 -150.984134) (xy 113.521571 -151.068448) (xy 113.505542 -151.151614)
			(xy 113.481681 -151.232881) (xy 113.450202 -151.311511) (xy 113.411391 -151.386792) (xy 113.365601 -151.458044)
			(xy 113.313245 -151.52462) (xy 113.254797 -151.585918) (xy 113.190787 -151.641383) (xy 113.121795 -151.690512)
			(xy 113.048445 -151.732861) (xy 112.971402 -151.768045) (xy 112.891363 -151.795747) (xy 112.809054 -151.815715)
			(xy 112.725219 -151.827768) (xy 112.640618 -151.831799) (xy 112.556017 -151.827768) (xy 112.472182 -151.815715)
			(xy 112.389873 -151.795747) (xy 112.309834 -151.768045) (xy 112.232791 -151.732861) (xy 112.159441 -151.690512)
			(xy 112.090449 -151.641383) (xy 112.026439 -151.585918) (xy 111.967991 -151.52462) (xy 111.915635 -151.458044)
			(xy 111.869845 -151.386792) (xy 111.831034 -151.311511) (xy 111.799555 -151.232881) (xy 111.775694 -151.151614)
			(xy 111.759665 -151.068448) (xy 111.751614 -150.984134) (xy 111.0295 -150.984134) (xy 111.021449 -151.068448)
			(xy 111.00542 -151.151614) (xy 110.981559 -151.232881) (xy 110.95008 -151.311511) (xy 110.911269 -151.386792)
			(xy 110.865479 -151.458044) (xy 110.813123 -151.52462) (xy 110.754675 -151.585918) (xy 110.690665 -151.641383)
			(xy 110.621673 -151.690512) (xy 110.548323 -151.732861) (xy 110.47128 -151.768045) (xy 110.391241 -151.795747)
			(xy 110.308932 -151.815715) (xy 110.225097 -151.827768) (xy 110.140496 -151.831799) (xy 110.055895 -151.827768)
			(xy 109.97206 -151.815715) (xy 109.889751 -151.795747) (xy 109.809712 -151.768045) (xy 109.732669 -151.732861)
			(xy 109.659319 -151.690512) (xy 109.590327 -151.641383) (xy 109.526317 -151.585918) (xy 109.467869 -151.52462)
			(xy 109.415513 -151.458044) (xy 109.369723 -151.386792) (xy 109.330912 -151.311511) (xy 109.299433 -151.232881)
			(xy 109.275572 -151.151614) (xy 109.259543 -151.068448) (xy 109.251492 -150.984134) (xy 105.95102 -150.984134)
			(xy 105.95102 -160.753552) (xy 110.096554 -164.899086) (xy 110.096554 -171.248832) (xy 110.52556 -171.677838)
			(xy 113.54308 -171.677838)
		)
		(stroke
			(width 0)
			(type solid)
		)
		(fill yes)
		(layer "In13.Cu")
		(net "SW_P12V_AUX_PVDDCR_SOC_P1_FLT")
	)
	(gr_poly
		(pts
			(xy 201.178922 -32.19196) (xy 201.1888 -32.191501) (xy 201.207103 -32.184063) (xy 201.214482 -32.177482)
			(xy 201.214736 -32.177228) (xy 202.558904 -30.83306) (xy 202.559412 -30.832552) (xy 202.565999 -30.825173)
			(xy 202.573458 -30.806873) (xy 202.57389 -30.796992) (xy 202.57389 -29.589984) (xy 202.573464 -29.579915)
			(xy 202.565744 -29.561316) (xy 202.558904 -29.553916) (xy 197.780148 -24.77516) (xy 197.773303 -24.767762)
			(xy 197.765575 -24.749163) (xy 197.765162 -24.739092) (xy 197.765162 -16.100552) (xy 197.764729 -16.090486)
			(xy 197.756998 -16.071898) (xy 197.750176 -16.064484) (xy 194.126612 -12.44092) (xy 194.1195 -12.433554)
			(xy 194.100704 -12.425934) (xy 191.947038 -12.425934) (xy 191.936974 -12.426369) (xy 191.918389 -12.434103)
			(xy 191.91097 -12.44092) (xy 191.253872 -13.098018) (xy 191.246506 -13.10513) (xy 191.238886 -13.123926)
			(xy 191.238886 -14.481556) (xy 191.239353 -14.49143) (xy 191.246804 -14.50972) (xy 191.253364 -14.517116)
			(xy 191.253618 -14.51737) (xy 191.567308 -14.83106) (xy 191.574144 -14.838462) (xy 191.581856 -14.85706)
			(xy 191.582294 -14.867128) (xy 191.582294 -18.150586) (xy 191.582766 -18.160458) (xy 191.590226 -18.178739)
			(xy 191.596772 -18.186146) (xy 191.597026 -18.1864) (xy 192.552066 -19.14144) (xy 195.064632 -19.14144)
			(xy 195.068703 -19.085818) (xy 195.080829 -19.031381) (xy 195.100752 -18.97929) (xy 195.128048 -18.930655)
			(xy 195.162134 -18.886512) (xy 195.202283 -18.847803) (xy 195.247641 -18.815352) (xy 195.297241 -18.789851)
			(xy 195.350025 -18.771844) (xy 195.404868 -18.761714) (xy 195.460602 -18.759677) (xy 195.516039 -18.765777)
			(xy 195.569996 -18.779883) (xy 195.621325 -18.801695) (xy 195.668931 -18.830749) (xy 195.711799 -18.866424)
			(xy 195.749016 -18.907961) (xy 195.779789 -18.954474) (xy 195.803461 -19.004971) (xy 195.819529 -19.058378)
			(xy 195.827649 -19.113554) (xy 195.828158 -19.14144) (xy 195.827649 -19.169326) (xy 195.819529 -19.224502)
			(xy 195.803461 -19.277909) (xy 195.779789 -19.328406) (xy 195.749016 -19.374919) (xy 195.711799 -19.416456)
			(xy 195.668931 -19.452131) (xy 195.621325 -19.481185) (xy 195.569996 -19.502997) (xy 195.516039 -19.517103)
			(xy 195.460602 -19.523203) (xy 195.404868 -19.521166) (xy 195.350025 -19.511036) (xy 195.297241 -19.493029)
			(xy 195.247641 -19.467528) (xy 195.202283 -19.435077) (xy 195.162134 -19.396368) (xy 195.128048 -19.352225)
			(xy 195.100752 -19.30359) (xy 195.080829 -19.251499) (xy 195.068703 -19.197062) (xy 195.064632 -19.14144)
			(xy 192.552066 -19.14144) (xy 193.251582 -19.840956) (xy 193.258421 -19.848357) (xy 193.266138 -19.866955)
			(xy 193.266568 -19.877024) (xy 193.266568 -24.546306) (xy 193.266667 -24.551466) (xy 193.268722 -24.561577)
			(xy 193.270632 -24.566372) (xy 193.288142 -24.608258) (xy 193.315526 -24.694819) (xy 193.333944 -24.783721)
			(xy 193.343205 -24.874037) (xy 193.343784 -24.919432) (xy 193.343784 -24.920448) (xy 193.343361 -24.958806)
			(xy 193.336711 -25.035235) (xy 193.323499 -25.110806) (xy 193.303825 -25.184958) (xy 193.291206 -25.221184)
			(xy 193.289682 -25.225248) (xy 193.288158 -25.233884) (xy 193.287476 -25.238239) (xy 193.287484 -25.247053)
			(xy 193.288158 -25.25141) (xy 193.289682 -25.260046) (xy 193.291206 -25.26411) (xy 193.303817 -25.300338)
			(xy 193.323487 -25.374491) (xy 193.336701 -25.450061) (xy 193.34336 -25.526488) (xy 193.343784 -25.564846)
			(xy 193.343784 -25.565862) (xy 193.343204 -25.611257) (xy 193.333935 -25.701572) (xy 193.31552 -25.790474)
			(xy 193.28815 -25.87704) (xy 193.270632 -25.918922) (xy 193.266568 -25.928574) (xy 193.266568 -26.156412)
			(xy 193.287904 -26.183844) (xy 193.304922 -26.188162) (xy 193.345659 -26.198864) (xy 193.425073 -26.226946)
			(xy 193.501477 -26.262411) (xy 193.574185 -26.30494) (xy 193.642546 -26.354153) (xy 193.705949 -26.409608)
			(xy 193.763825 -26.47081) (xy 193.815655 -26.537209) (xy 193.860976 -26.608211) (xy 193.899381 -26.683179)
			(xy 193.930526 -26.761443) (xy 193.954132 -26.8423) (xy 193.969988 -26.925028) (xy 193.977952 -27.008883)
			(xy 193.977952 -27.093117) (xy 193.969988 -27.176972) (xy 193.954132 -27.2597) (xy 193.930526 -27.340557)
			(xy 193.899381 -27.418821) (xy 193.860976 -27.493789) (xy 193.815655 -27.564791) (xy 193.763825 -27.63119)
			(xy 193.705949 -27.692392) (xy 193.642546 -27.747847) (xy 193.574185 -27.79706) (xy 193.501477 -27.839589)
			(xy 193.425073 -27.875054) (xy 193.345659 -27.903136) (xy 193.304922 -27.913838) (xy 193.287904 -27.918156)
			(xy 193.266568 -27.945588) (xy 193.266568 -28.307792) (xy 193.269108 -28.315666) (xy 193.283288 -28.360692)
			(xy 193.303171 -28.452977) (xy 193.313177 -28.546849) (xy 193.313812 -28.59405) (xy 193.313192 -28.641252)
			(xy 193.303192 -28.735126) (xy 193.283298 -28.827411) (xy 193.269108 -28.872434) (xy 193.266568 -28.880308)
			(xy 193.266568 -28.921456) (xy 193.267034 -28.931331) (xy 193.274483 -28.949622) (xy 193.281046 -28.957016)
			(xy 193.2813 -28.95727) (xy 196.501004 -32.176974) (xy 196.501512 -32.177482) (xy 196.508892 -32.184068)
			(xy 196.527191 -32.191528) (xy 196.537072 -32.19196)
		)
		(stroke
			(width 0)
			(type solid)
		)
		(fill yes)
		(layer "In13.Cu")
		(net "P12V_SCM")
	)
	(gr_poly
		(pts
			(xy 3.015488 -334.834992)
			(arc
				(start 3.015488 -81.32826)
				(mid 2.785816 -80.174473)
				(end 2.132076 -79.196438)
			)
			(arc
				(start 1.303528 -78.36789)
				(mid 1.090411 -78.048655)
				(end 1.015492 -77.672184)
			)
			(arc
				(start 1.015492 -13.780008)
				(mid 1.303847 -13.083859)
				(end 1.999996 -12.795504)
			)
			(arc
				(start 11.102086 -12.795504)
				(mid 13.234194 -11.912198)
				(end 14.11732 -9.780016)
			)
			(arc
				(start 14.11732 -3.98907)
				(mid 14.115908 -3.977177)
				(end 14.111732 -3.965956)
			)
			(xy 14.099032 -3.941064) (xy 14.091412 -3.932428)
			(arc
				(start 14.086586 -3.928872)
				(mid 13.924547 -3.777841)
				(end 13.80236 -3.593084)
			)
			(arc
				(start 13.80236 -3.59283)
				(mid 13.778355 -3.569807)
				(end 13.74521 -3.566414)
			)
			(xy 13.649198 -3.589274)
			(arc
				(start 13.646404 -3.590036)
				(mid 13.620112 -3.608379)
				(end 13.610082 -3.638804)
			)
			(arc
				(start 13.610082 -9.780016)
				(mid 12.875507 -11.553437)
				(end 11.102086 -12.288012)
			)
			(arc
				(start 1.999996 -12.288012)
				(mid 0.944996 -12.725008)
				(end 0.508 -13.780008)
			)
			(arc
				(start 0.508 -77.67193)
				(mid 0.621601 -78.242658)
				(end 0.94488 -78.726538)
			)
			(arc
				(start 1.773428 -79.555086)
				(mid 2.317047 -80.368624)
				(end 2.507996 -81.32826)
			)
			(xy 2.507996 -335.03362) (xy 2.586736 -335.11236) (xy 2.73812 -335.11236)
		)
		(stroke
			(width 0)
			(type solid)
		)
		(fill yes)
		(layer "In13.Cu")
		(net "GND")
	)
	(gr_poly
		(pts
			(arc
				(start 467.613746 -357.546402)
				(mid 467.725971 -357.574992)
				(end 467.792054 -357.479854)
			)
			(arc
				(start 467.792054 -82.82813)
				(mid 467.983012 -81.868498)
				(end 468.526622 -81.054956)
			)
			(arc
				(start 470.85504 -78.726538)
				(mid 471.178373 -78.242681)
				(end 471.29192 -77.67193)
			)
			(arc
				(start 471.29192 -13.780008)
				(mid 470.854924 -12.725008)
				(end 469.799924 -12.288012)
			)
			(arc
				(start 458.20203 -12.288012)
				(mid 456.428609 -11.553437)
				(end 455.694034 -9.780016)
			)
			(xy 455.694034 -3.620262) (xy 455.67219 -3.59283) (xy 455.654918 -3.588766) (xy 455.558906 -3.565906)
			(xy 455.553064 -3.56489) (xy 455.54138 -3.562096) (xy 455.529188 -3.567684) (xy 455.52233 -3.570986)
			(xy 455.50963 -3.576828) (xy 455.50201 -3.591814)
			(arc
				(start 455.499978 -3.595878)
				(mid 455.374567 -3.783198)
				(end 455.208132 -3.935222)
			)
			(arc
				(start 455.208132 -3.935222)
				(mid 455.192432 -3.953332)
				(end 455.186796 -3.976624)
			)
			(arc
				(start 455.186796 -9.780524)
				(mid 456.070027 -11.912452)
				(end 458.20203 -12.795504)
			)
			(arc
				(start 469.799924 -12.795504)
				(mid 470.496073 -13.083859)
				(end 470.784428 -13.780008)
			)
			(arc
				(start 470.784428 -77.672184)
				(mid 470.70959 -78.048688)
				(end 470.496392 -78.36789)
			)
			(arc
				(start 468.167974 -80.696308)
				(mid 467.514407 -81.674395)
				(end 467.284816 -82.82813)
			)
			(arc
				(start 467.284816 -357.024432)
				(mid 467.287226 -357.039893)
				(end 467.294214 -357.053896)
			)
			(arc
				(start 467.294214 -357.053896)
				(mid 467.453819 -357.289102)
				(end 467.602824 -357.531162)
			)
			(xy 467.607142 -357.53802) (xy 467.61146 -357.545386)
		)
		(stroke
			(width 0)
			(type solid)
		)
		(fill yes)
		(layer "In13.Cu")
		(net "GND")
	)
	(gr_poly
		(pts
			(arc
				(start 299.776388 -359.772458)
				(mid 299.795911 -359.768557)
				(end 299.812456 -359.757472)
			)
			(arc
				(start 300.262036 -359.307892)
				(mid 300.273147 -359.291358)
				(end 300.277022 -359.271824)
			)
			(arc
				(start 300.277022 -354.574602)
				(mid 300.280923 -354.555079)
				(end 300.292008 -354.538534)
			)
			(arc
				(start 300.47692 -354.353622)
				(mid 300.493454 -354.342511)
				(end 300.512988 -354.338636)
			)
			(xy 300.906688 -354.338636)
			(arc
				(start 300.912022 -354.33762)
				(mid 300.950802 -354.331558)
				(end 300.99 -354.329492)
			)
			(arc
				(start 300.99 -354.329492)
				(mid 301.0292 -354.331537)
				(end 301.067978 -354.33762)
			)
			(xy 301.073312 -354.338636)
			(arc
				(start 302.51146 -354.338636)
				(mid 302.538119 -354.331079)
				(end 302.556926 -354.310696)
			)
			(arc
				(start 302.556926 -354.310696)
				(mid 302.731985 -354.072336)
				(end 302.975518 -353.90455)
			)
			(arc
				(start 302.975518 -353.90455)
				(mid 302.98318 -353.900218)
				(end 302.989996 -353.894644)
			)
			(arc
				(start 303.045876 -353.838764)
				(mid 303.06241 -353.827653)
				(end 303.081944 -353.823778)
			)
			(arc
				(start 303.289208 -353.823778)
				(mid 303.320176 -353.822095)
				(end 303.351184 -353.821492)
			)
			(arc
				(start 303.351184 -353.821492)
				(mid 303.382192 -353.822095)
				(end 303.41316 -353.823778)
			)
			(arc
				(start 303.90592 -353.823778)
				(mid 303.925443 -353.819877)
				(end 303.941988 -353.808792)
			)
			(arc
				(start 304.37836 -353.37242)
				(mid 304.389471 -353.355886)
				(end 304.393346 -353.336352)
			)
			(arc
				(start 304.393346 -348.864682)
				(mid 304.389445 -348.845159)
				(end 304.37836 -348.828614)
			)
			(arc
				(start 303.958498 -348.408752)
				(mid 303.947387 -348.392218)
				(end 303.943512 -348.372684)
			)
			(arc
				(start 303.943512 -347.157802)
				(mid 303.939611 -347.138279)
				(end 303.928526 -347.121734)
			)
			(arc
				(start 303.80051 -346.993718)
				(mid 303.783976 -346.982607)
				(end 303.764442 -346.978732)
			)
			(arc
				(start 300.824392 -346.978732)
				(mid 300.804869 -346.982633)
				(end 300.788324 -346.993718)
			)
			(arc
				(start 300.763432 -347.01861)
				(mid 300.752321 -347.035144)
				(end 300.748446 -347.054678)
			)
			(arc
				(start 300.748446 -348.992952)
				(mid 300.752347 -349.012475)
				(end 300.763432 -349.02902)
			)
			(arc
				(start 301.634906 -349.900494)
				(mid 301.646017 -349.917028)
				(end 301.649892 -349.936562)
			)
			(arc
				(start 301.649892 -352.26117)
				(mid 301.645991 -352.280693)
				(end 301.634906 -352.297238)
			)
			(arc
				(start 301.296578 -352.635566)
				(mid 301.280044 -352.646677)
				(end 301.26051 -352.650552)
			)
			(arc
				(start 296.880026 -352.650552)
				(mid 296.860503 -352.646651)
				(end 296.843958 -352.635566)
			)
			(arc
				(start 296.051732 -351.84334)
				(mid 296.040621 -351.826806)
				(end 296.036746 -351.807272)
			)
			(arc
				(start 296.036746 -348.872302)
				(mid 296.032845 -348.852779)
				(end 296.02176 -348.836234)
			)
			(arc
				(start 295.579038 -348.393512)
				(mid 295.567927 -348.376978)
				(end 295.564052 -348.357444)
			)
			(arc
				(start 295.564052 -347.233494)
				(mid 295.560151 -347.213971)
				(end 295.549066 -347.197426)
			)
			(arc
				(start 295.370758 -347.019118)
				(mid 295.354224 -347.008007)
				(end 295.33469 -347.004132)
			)
			(arc
				(start 292.470332 -347.004132)
				(mid 292.450809 -347.008033)
				(end 292.434264 -347.019118)
			)
			(arc
				(start 292.406832 -347.04655)
				(mid 292.395721 -347.063084)
				(end 292.391846 -347.082618)
			)
			(arc
				(start 292.391846 -349.033592)
				(mid 292.395747 -349.053115)
				(end 292.406832 -349.06966)
			)
			(arc
				(start 293.263066 -349.925894)
				(mid 293.274177 -349.942428)
				(end 293.278052 -349.961962)
			)
			(arc
				(start 293.278052 -352.24847)
				(mid 293.274151 -352.267993)
				(end 293.263066 -352.284538)
			)
			(arc
				(start 292.830758 -352.716846)
				(mid 292.814224 -352.727957)
				(end 292.79469 -352.731832)
			)
			(arc
				(start 288.594546 -352.731832)
				(mid 288.575023 -352.727931)
				(end 288.558478 -352.716846)
			)
			(arc
				(start 287.720532 -351.8789)
				(mid 287.709421 -351.862366)
				(end 287.705546 -351.842832)
			)
			(arc
				(start 287.705546 -348.872302)
				(mid 287.701645 -348.852779)
				(end 287.69056 -348.836234)
			)
			(arc
				(start 287.301178 -348.446852)
				(mid 287.290067 -348.430318)
				(end 287.286192 -348.410784)
			)
			(arc
				(start 287.286192 -347.234002)
				(mid 287.282291 -347.214479)
				(end 287.271206 -347.197934)
			)
			(arc
				(start 287.11271 -347.039438)
				(mid 287.096176 -347.028327)
				(end 287.076642 -347.024452)
			)
			(arc
				(start 284.174692 -347.024452)
				(mid 284.155169 -347.028353)
				(end 284.138624 -347.039438)
			)
			(arc
				(start 284.101032 -347.07703)
				(mid 284.089921 -347.093564)
				(end 284.086046 -347.113098)
			)
			(arc
				(start 284.086046 -349.020892)
				(mid 284.089947 -349.040415)
				(end 284.101032 -349.05696)
			)
			(arc
				(start 284.975046 -349.930974)
				(mid 284.986157 -349.947508)
				(end 284.990032 -349.967042)
			)
			(arc
				(start 284.990032 -352.279458)
				(mid 284.986131 -352.298981)
				(end 284.975046 -352.315526)
			)
			(arc
				(start 284.670246 -352.620326)
				(mid 284.653712 -352.631437)
				(end 284.634178 -352.635312)
			)
			(arc
				(start 280.156666 -352.635312)
				(mid 280.137143 -352.631411)
				(end 280.120598 -352.620326)
			)
			(arc
				(start 279.440132 -351.93986)
				(mid 279.429021 -351.923326)
				(end 279.425146 -351.903792)
			)
			(arc
				(start 279.425146 -348.829122)
				(mid 279.421245 -348.809599)
				(end 279.41016 -348.793054)
			)
			(arc
				(start 278.969978 -348.352872)
				(mid 278.958867 -348.336338)
				(end 278.954992 -348.316804)
			)
			(arc
				(start 278.954992 -347.142562)
				(mid 278.951091 -347.123039)
				(end 278.940006 -347.106494)
			)
			(arc
				(start 278.88311 -347.049598)
				(mid 278.866576 -347.038487)
				(end 278.847042 -347.034612)
			)
			(arc
				(start 275.871432 -347.034612)
				(mid 275.851909 -347.038513)
				(end 275.835364 -347.049598)
			)
			(arc
				(start 275.820632 -347.06433)
				(mid 275.809521 -347.080864)
				(end 275.805646 -347.100398)
			)
			(xy 275.805646 -348.972378)
			(arc
				(start 275.809456 -348.981268)
				(mid 275.812329 -348.990858)
				(end 275.813266 -349.000826)
			)
			(arc
				(start 275.813266 -349.048832)
				(mid 275.817167 -349.068355)
				(end 275.828252 -349.0849)
			)
			(arc
				(start 276.687026 -349.943674)
				(mid 276.698137 -349.960208)
				(end 276.702012 -349.979742)
			)
			(arc
				(start 276.702012 -359.40873)
				(mid 276.705913 -359.428253)
				(end 276.716998 -359.444798)
			)
			(arc
				(start 277.029672 -359.757472)
				(mid 277.046206 -359.768583)
				(end 277.06574 -359.772458)
			)
		)
		(stroke
			(width 0)
			(type solid)
		)
		(fill yes)
		(layer "In13.Cu")
		(net "SW_P12V_AUX_PVDDIO_P0_FLT")
	)
	(gr_poly
		(pts
			(xy 395.334744 -176.942242) (xy 395.664944 -176.942242) (xy 395.674949 -176.941747) (xy 395.693433 -176.934081)
			(xy 395.707582 -176.919931) (xy 395.715247 -176.901447) (xy 395.715744 -176.891442) (xy 397.392144 -176.891442)
			(xy 397.402149 -176.890947) (xy 397.420633 -176.883281) (xy 397.434782 -176.869131) (xy 397.442447 -176.850647)
			(xy 397.442944 -176.840642) (xy 397.442944 -174.893224) (xy 396.47368 -173.92396) (xy 396.47368 -170.9039)
			(xy 398.996154 -168.381426) (xy 400.79549 -168.381426) (xy 400.802887 -168.374575) (xy 400.821485 -168.366833)
			(xy 400.831558 -168.36644) (xy 403.658324 -168.36644) (xy 403.658324 -168.364916) (xy 403.988524 -168.364916)
			(xy 403.99853 -168.364424) (xy 404.017016 -168.356761) (xy 404.031165 -168.342609) (xy 404.038826 -168.324122)
			(xy 404.039324 -168.314116) (xy 405.715724 -168.314116) (xy 405.72573 -168.313624) (xy 405.744216 -168.305961)
			(xy 405.758365 -168.291809) (xy 405.766026 -168.273322) (xy 405.766524 -168.263316) (xy 405.766524 -166.384224)
			(xy 404.982172 -165.599872) (xy 404.982172 -162.627056) (xy 405.40559 -162.203638) (xy 409.095702 -162.203638)
			(xy 409.105771 -162.204062) (xy 409.124372 -162.211781) (xy 409.13177 -162.218624) (xy 409.495498 -162.582352)
			(xy 409.502337 -162.589753) (xy 409.510052 -162.608351) (xy 409.510484 -162.61842) (xy 409.510484 -163.475924)
			(xy 409.518104 -163.49472) (xy 409.52547 -163.501832) (xy 409.574492 -163.550854) (xy 409.581888 -163.557707)
			(xy 409.600486 -163.565451) (xy 409.61056 -163.56584) (xy 414.101788 -163.56584) (xy 414.120584 -163.55822)
			(xy 414.127696 -163.550854) (xy 414.133538 -163.545012) (xy 414.140904 -163.5379) (xy 414.148524 -163.519104)
			(xy 414.148524 -161.482532) (xy 413.26816 -160.602168) (xy 413.26816 -157.903164) (xy 411.8991 -156.534104)
			(xy 411.880304 -156.526484) (xy 397.681958 -156.526484) (xy 392.714226 -151.558752) (xy 386.014468 -151.558752)
			(xy 385.5466 -152.02662) (xy 385.5466 -154.162252) (xy 393.797026 -154.162252) (xy 393.801099 -154.106593)
			(xy 393.813234 -154.05212) (xy 393.83317 -153.999994) (xy 393.860484 -153.951326) (xy 393.894592 -153.907154)
			(xy 393.934769 -153.868419) (xy 393.980157 -153.835947) (xy 394.029789 -153.810429) (xy 394.082609 -153.79241)
			(xy 394.137488 -153.782273) (xy 394.193259 -153.780235) (xy 394.248733 -153.786338) (xy 394.302726 -153.800454)
			(xy 394.354089 -153.822281) (xy 394.401727 -153.851354) (xy 394.444623 -153.887053) (xy 394.481865 -153.928617)
			(xy 394.512659 -153.975161) (xy 394.536347 -154.025692) (xy 394.552425 -154.079134) (xy 394.560551 -154.134348)
			(xy 394.56106 -154.162252) (xy 394.560551 -154.190156) (xy 394.552425 -154.24537) (xy 394.536347 -154.298812)
			(xy 394.512659 -154.349343) (xy 394.481865 -154.395887) (xy 394.444623 -154.437451) (xy 394.401727 -154.47315)
			(xy 394.354089 -154.502223) (xy 394.302726 -154.52405) (xy 394.248733 -154.538166) (xy 394.193259 -154.544269)
			(xy 394.137488 -154.542231) (xy 394.082609 -154.532094) (xy 394.029789 -154.514075) (xy 393.980157 -154.488557)
			(xy 393.934769 -154.456085) (xy 393.894592 -154.41735) (xy 393.860484 -154.373178) (xy 393.83317 -154.32451)
			(xy 393.813234 -154.272384) (xy 393.801099 -154.217911) (xy 393.797026 -154.162252) (xy 385.5466 -154.162252)
			(xy 385.5466 -162.695058) (xy 386.317994 -162.695058) (xy 386.317994 -162.610362) (xy 386.326045 -162.526048)
			(xy 386.342074 -162.442882) (xy 386.365935 -162.361615) (xy 386.397414 -162.282985) (xy 386.436225 -162.207704)
			(xy 386.482015 -162.136452) (xy 386.534371 -162.069876) (xy 386.592819 -162.008578) (xy 386.656829 -161.953113)
			(xy 386.725821 -161.903984) (xy 386.799171 -161.861635) (xy 386.876214 -161.826451) (xy 386.956253 -161.798749)
			(xy 387.038562 -161.778781) (xy 387.122397 -161.766728) (xy 387.206998 -161.762698) (xy 387.291599 -161.766728)
			(xy 387.375434 -161.778781) (xy 387.457743 -161.798749) (xy 387.537782 -161.826451) (xy 387.614825 -161.861635)
			(xy 387.688175 -161.903984) (xy 387.757167 -161.953113) (xy 387.821177 -162.008578) (xy 387.879625 -162.069876)
			(xy 387.931981 -162.136452) (xy 387.977771 -162.207704) (xy 388.016582 -162.282985) (xy 388.048061 -162.361615)
			(xy 388.071922 -162.442882) (xy 388.087951 -162.526048) (xy 388.096002 -162.610362) (xy 388.096506 -162.65271)
			(xy 388.096002 -162.695058) (xy 388.087951 -162.779372) (xy 388.071922 -162.862538) (xy 388.048061 -162.943805)
			(xy 388.016582 -163.022435) (xy 387.977771 -163.097716) (xy 387.931981 -163.168968) (xy 387.879625 -163.235544)
			(xy 387.821177 -163.296842) (xy 387.757167 -163.352307) (xy 387.688175 -163.401436) (xy 387.614825 -163.443785)
			(xy 387.537782 -163.478969) (xy 387.457743 -163.506671) (xy 387.375434 -163.526639) (xy 387.291599 -163.538692)
			(xy 387.206998 -163.542723) (xy 387.122397 -163.538692) (xy 387.038562 -163.526639) (xy 386.956253 -163.506671)
			(xy 386.876214 -163.478969) (xy 386.799171 -163.443785) (xy 386.725821 -163.401436) (xy 386.656829 -163.352307)
			(xy 386.592819 -163.296842) (xy 386.534371 -163.235544) (xy 386.482015 -163.168968) (xy 386.436225 -163.097716)
			(xy 386.397414 -163.022435) (xy 386.365935 -162.943805) (xy 386.342074 -162.862538) (xy 386.326045 -162.779372)
			(xy 386.317994 -162.695058) (xy 385.5466 -162.695058) (xy 385.5466 -165.195193) (xy 386.31774 -165.195193)
			(xy 386.31774 -165.110471) (xy 386.325793 -165.026134) (xy 386.341827 -164.942944) (xy 386.365695 -164.861654)
			(xy 386.397183 -164.783002) (xy 386.436005 -164.707699) (xy 386.481808 -164.636427) (xy 386.534179 -164.569831)
			(xy 386.592644 -164.508516) (xy 386.656672 -164.453035) (xy 386.725684 -164.403892) (xy 386.799054 -164.361532)
			(xy 386.876119 -164.326337) (xy 386.956181 -164.298628) (xy 387.038514 -164.278654) (xy 387.122373 -164.266597)
			(xy 387.206998 -164.262566) (xy 387.291623 -164.266597) (xy 387.375482 -164.278654) (xy 387.457815 -164.298628)
			(xy 387.537877 -164.326337) (xy 387.614942 -164.361532) (xy 387.688312 -164.403892) (xy 387.757324 -164.453035)
			(xy 387.821352 -164.508516) (xy 387.879817 -164.569831) (xy 387.932188 -164.636427) (xy 387.977991 -164.707699)
			(xy 388.016813 -164.783002) (xy 388.048301 -164.861654) (xy 388.072169 -164.942944) (xy 388.088203 -165.026134)
			(xy 388.096256 -165.110471) (xy 388.09676 -165.152832) (xy 388.096256 -165.195193) (xy 388.088203 -165.27953)
			(xy 388.072169 -165.36272) (xy 388.048301 -165.44401) (xy 388.016813 -165.522662) (xy 387.977991 -165.597965)
			(xy 387.932188 -165.669237) (xy 387.879817 -165.735833) (xy 387.821352 -165.797148) (xy 387.757324 -165.852629)
			(xy 387.688312 -165.901772) (xy 387.614942 -165.944132) (xy 387.537877 -165.979327) (xy 387.457815 -166.007036)
			(xy 387.375482 -166.02701) (xy 387.291623 -166.039067) (xy 387.206998 -166.043099) (xy 387.122373 -166.039067)
			(xy 387.038514 -166.02701) (xy 386.956181 -166.007036) (xy 386.876119 -165.979327) (xy 386.799054 -165.944132)
			(xy 386.725684 -165.901772) (xy 386.656672 -165.852629) (xy 386.592644 -165.797148) (xy 386.534179 -165.735833)
			(xy 386.481808 -165.669237) (xy 386.436005 -165.597965) (xy 386.397183 -165.522662) (xy 386.365695 -165.44401)
			(xy 386.341827 -165.36272) (xy 386.325793 -165.27953) (xy 386.31774 -165.195193) (xy 385.5466 -165.195193)
			(xy 385.5466 -167.804592) (xy 387.28396 -169.541952) (xy 390.823958 -169.541952) (xy 392.855958 -171.573952)
			(xy 392.855958 -176.870106) (xy 392.932158 -176.946306) (xy 395.334744 -176.946306)
		)
		(stroke
			(width 0)
			(type solid)
		)
		(fill yes)
		(layer "In13.Cu")
		(net "SW_P12V_AUX_PVDDCR_SOC_P0_FLT")
	)
	(gr_poly
		(pts
			(xy 453.286114 -30.026102) (xy 453.296183 -30.025676) (xy 453.314784 -30.017958) (xy 453.322182 -30.011116)
			(xy 454.64603 -28.687268) (xy 454.652879 -28.679871) (xy 454.660613 -28.661272) (xy 454.661016 -28.6512)
			(xy 454.661016 -23.702518) (xy 454.660578 -23.692454) (xy 454.652845 -23.67387) (xy 454.64603 -23.66645)
			(xy 454.288906 -23.309326) (xy 454.281794 -23.30196) (xy 454.262998 -23.29434) (xy 452.604886 -23.29434)
			(xy 452.601584 -23.294848) (xy 452.573447 -23.298204) (xy 452.516889 -23.301765) (xy 452.488554 -23.30196)
			(xy 452.445482 -23.301451) (xy 452.359741 -23.293118) (xy 452.275208 -23.276533) (xy 452.192675 -23.251852)
			(xy 452.112915 -23.219307) (xy 452.036675 -23.179203) (xy 451.96467 -23.131914) (xy 451.897575 -23.077886)
			(xy 451.836018 -23.017623) (xy 451.780576 -22.95169) (xy 451.731769 -22.880706) (xy 451.690054 -22.805335)
			(xy 451.672452 -22.76602) (xy 451.668064 -22.757162) (xy 451.653898 -22.743402) (xy 451.635591 -22.735992)
			(xy 451.625716 -22.73554) (xy 451.362064 -22.73554) (xy 451.351922 -22.735986) (xy 451.333213 -22.743829)
			(xy 451.318982 -22.758285) (xy 451.31482 -22.767544) (xy 451.299294 -22.805242) (xy 451.262291 -22.877896)
			(xy 451.218794 -22.946858) (xy 451.169168 -23.01155) (xy 451.11383 -23.071429) (xy 451.053243 -23.125992)
			(xy 450.987918 -23.174782) (xy 450.918401 -23.217387) (xy 450.845277 -23.253452) (xy 450.769159 -23.282674)
			(xy 450.690686 -23.304806) (xy 450.610517 -23.319664) (xy 450.529325 -23.327122) (xy 450.488558 -23.327614)
			(xy 450.445165 -23.32709) (xy 450.358793 -23.318637) (xy 450.273653 -23.301815) (xy 450.190556 -23.276784)
			(xy 450.110291 -23.243781) (xy 450.03362 -23.203121) (xy 449.961271 -23.15519) (xy 449.893933 -23.100443)
			(xy 449.862702 -23.070312) (xy 449.847716 -23.05558) (xy 449.80606 -23.05558) (xy 449.537074 -23.324566)
			(xy 449.530382 -23.331976) (xy 449.522771 -23.350413) (xy 449.522765 -23.370359) (xy 449.530366 -23.3888)
			(xy 449.537074 -23.396194) (xy 449.54444 -23.40356) (xy 449.54825 -23.412704) (xy 449.550024 -23.417332)
			(xy 449.551943 -23.427053) (xy 449.55206 -23.432008) (xy 449.55206 -24.025098) (xy 449.551636 -24.035167)
			(xy 449.543918 -24.053769) (xy 449.537074 -24.061166) (xy 449.422266 -24.175974) (xy 449.414867 -24.182818)
			(xy 449.396269 -24.190544) (xy 449.386198 -24.19096) (xy 446.685162 -24.19096) (xy 446.675096 -24.191392)
			(xy 446.656507 -24.199122) (xy 446.649094 -24.205946) (xy 446.348866 -24.506174) (xy 446.3415 -24.513286)
			(xy 446.33388 -24.532082) (xy 446.33388 -26.033476) (xy 446.333443 -26.04354) (xy 446.325706 -26.062122)
			(xy 446.318894 -26.069544) (xy 445.890904 -26.497534) (xy 445.883509 -26.504388) (xy 445.86491 -26.512135)
			(xy 445.854836 -26.51252) (xy 444.927736 -26.51252) (xy 444.917746 -26.513051) (xy 444.899306 -26.520758)
			(xy 444.891922 -26.527506) (xy 444.762382 -26.657046) (xy 444.734788 -26.683945) (xy 444.674572 -26.732038)
			(xy 444.609348 -26.773084) (xy 444.539939 -26.806568) (xy 444.467216 -26.832068) (xy 444.392094 -26.849263)
			(xy 444.31552 -26.857936) (xy 444.276988 -26.858468) (xy 443.062614 -26.858468) (xy 443.058296 -26.858976)
			(xy 443.020932 -26.865006) (xy 442.945519 -26.871491) (xy 442.907674 -26.87193) (xy 442.869828 -26.871515)
			(xy 442.794414 -26.865026) (xy 442.757052 -26.858976) (xy 442.752734 -26.858468) (xy 442.173614 -26.858468)
			(xy 442.169296 -26.858976) (xy 442.131932 -26.865006) (xy 442.056519 -26.871491) (xy 442.018674 -26.87193)
			(xy 441.980828 -26.871515) (xy 441.905414 -26.865026) (xy 441.868052 -26.858976) (xy 441.863734 -26.858468)
			(xy 441.284614 -26.858468) (xy 441.280296 -26.858976) (xy 441.242932 -26.865006) (xy 441.167519 -26.871491)
			(xy 441.129674 -26.87193) (xy 441.091828 -26.871515) (xy 441.016414 -26.865026) (xy 440.979052 -26.858976)
			(xy 440.974734 -26.858468) (xy 440.782964 -26.858468) (xy 440.772897 -26.858038) (xy 440.754305 -26.85031)
			(xy 440.746896 -26.843482) (xy 440.602116 -26.698702) (xy 440.599068 -26.696416) (xy 440.564554 -26.670117)
			(xy 440.500276 -26.61182) (xy 440.44198 -26.547541) (xy 440.41568 -26.513028) (xy 440.413394 -26.50998)
			(xy 440.199018 -26.295604) (xy 440.192169 -26.288206) (xy 440.18443 -26.269608) (xy 440.184032 -26.259536)
			(xy 440.184032 -23.310088) (xy 440.183542 -23.30008) (xy 440.175882 -23.281586) (xy 440.16173 -23.267429)
			(xy 440.14324 -23.259762) (xy 440.133232 -23.259288) (xy 438.944004 -23.259288) (xy 438.933934 -23.258865)
			(xy 438.915329 -23.251151) (xy 438.907936 -23.244302) (xy 437.684418 -23.244302) (xy 437.674355 -23.24474)
			(xy 437.655772 -23.252476) (xy 437.64835 -23.259288) (xy 437.195722 -23.711916) (xy 437.188356 -23.719028)
			(xy 437.180736 -23.737824) (xy 437.180736 -26.153872) (xy 438.228738 -26.153872) (xy 438.232809 -26.09825)
			(xy 438.244935 -26.043813) (xy 438.264858 -25.991722) (xy 438.292154 -25.943087) (xy 438.32624 -25.898944)
			(xy 438.366389 -25.860235) (xy 438.411747 -25.827784) (xy 438.461347 -25.802283) (xy 438.514131 -25.784276)
			(xy 438.568974 -25.774146) (xy 438.624708 -25.772109) (xy 438.680145 -25.778209) (xy 438.734102 -25.792315)
			(xy 438.785431 -25.814127) (xy 438.833037 -25.843181) (xy 438.875905 -25.878856) (xy 438.913122 -25.920393)
			(xy 438.943895 -25.966906) (xy 438.967567 -26.017403) (xy 438.983635 -26.07081) (xy 438.991755 -26.125986)
			(xy 438.992264 -26.153872) (xy 438.991755 -26.181758) (xy 438.983635 -26.236934) (xy 438.967567 -26.290341)
			(xy 438.943895 -26.340838) (xy 438.913122 -26.387351) (xy 438.875905 -26.428888) (xy 438.833037 -26.464563)
			(xy 438.785431 -26.493617) (xy 438.734102 -26.515429) (xy 438.680145 -26.529535) (xy 438.624708 -26.535635)
			(xy 438.568974 -26.533598) (xy 438.514131 -26.523468) (xy 438.461347 -26.505461) (xy 438.411747 -26.47996)
			(xy 438.366389 -26.447509) (xy 438.32624 -26.4088) (xy 438.292154 -26.364657) (xy 438.264858 -26.316022)
			(xy 438.244935 -26.263931) (xy 438.232809 -26.209494) (xy 438.228738 -26.153872) (xy 437.180736 -26.153872)
			(xy 437.180736 -26.160476) (xy 437.18062 -26.165431) (xy 437.178706 -26.175155) (xy 437.176926 -26.17978)
			(xy 437.17083 -26.194512) (xy 437.169058 -26.19914) (xy 437.167141 -26.208862) (xy 437.16702 -26.213816)
			(xy 437.16702 -27.639772) (xy 437.167435 -27.649795) (xy 437.175101 -27.668318) (xy 437.189275 -27.682495)
			(xy 437.207797 -27.690163) (xy 437.21782 -27.690572) (xy 437.511952 -27.690572) (xy 437.550484 -27.691108)
			(xy 437.627059 -27.699772) (xy 437.70218 -27.716963) (xy 437.774902 -27.742464) (xy 437.844309 -27.775954)
			(xy 437.909525 -27.817011) (xy 437.969729 -27.865118) (xy 437.997346 -27.891994) (xy 438.251346 -28.145994)
			(xy 438.258693 -28.152798) (xy 438.277156 -28.160515) (xy 438.28716 -28.16098) (xy 438.426352 -28.16098)
			(xy 438.447434 -28.15082) (xy 438.454546 -28.141422) (xy 438.481093 -28.108055) (xy 438.539599 -28.04602)
			(xy 438.603774 -27.989869) (xy 438.673027 -27.940116) (xy 438.746724 -27.897219) (xy 438.824188 -27.861571)
			(xy 438.904707 -27.8335) (xy 438.987543 -27.813264) (xy 439.071936 -27.801047) (xy 439.15711 -27.796962)
			(xy 439.242284 -27.801047) (xy 439.326677 -27.813264) (xy 439.409513 -27.8335) (xy 439.490032 -27.861571)
			(xy 439.567496 -27.897219) (xy 439.641193 -27.940116) (xy 439.710446 -27.989869) (xy 439.774621 -28.04602)
			(xy 439.833127 -28.108055) (xy 439.859674 -28.141422) (xy 439.866786 -28.15082) (xy 439.887868 -28.16098)
			(xy 439.917332 -28.16098) (xy 439.9274 -28.161408) (xy 439.945998 -28.169129) (xy 439.9534 -28.175966)
			(xy 440.64555 -28.868116) (xy 440.652947 -28.874964) (xy 440.671546 -28.882693) (xy 440.681618 -28.883102)
			(xy 445.131698 -28.883102) (xy 445.141768 -28.883525) (xy 445.160373 -28.891239) (xy 445.167766 -28.898088)
			(xy 446.280794 -30.011116) (xy 446.288188 -30.017972) (xy 446.306787 -30.025722) (xy 446.316862 -30.026102)
		)
		(stroke
			(width 0)
			(type solid)
		)
		(fill yes)
		(layer "In13.Cu")
		(net "P12V_AUX")
	)
	(gr_poly
		(pts
			(xy 440.133232 -22.572218) (xy 440.143237 -22.571725) (xy 440.161721 -22.56406) (xy 440.175868 -22.549909)
			(xy 440.183528 -22.531423) (xy 440.184032 -22.521418) (xy 440.184032 -22.328886) (xy 440.184458 -22.318818)
			(xy 440.19218 -22.30022) (xy 440.199018 -22.292818) (xy 441.374022 -21.117814) (xy 441.380843 -21.110473)
			(xy 441.388593 -21.09201) (xy 441.389008 -21.082) (xy 441.389008 -14.679676) (xy 441.389459 -14.66965)
			(xy 441.397052 -14.651094) (xy 441.40374 -14.643608) (xy 441.74791 -14.299438) (xy 441.75471 -14.292089)
			(xy 441.762418 -14.273626) (xy 441.762896 -14.263624) (xy 441.762896 -10.64514) (xy 441.762462 -10.635075)
			(xy 441.754732 -10.616487) (xy 441.74791 -10.609072) (xy 441.360052 -10.221214) (xy 441.352652 -10.214373)
			(xy 441.334053 -10.206654) (xy 441.323984 -10.206228) (xy 437.480964 -10.206228) (xy 437.470897 -10.206658)
			(xy 437.452305 -10.214385) (xy 437.444896 -10.221214) (xy 436.91429 -10.75182) (xy 436.907437 -10.759215)
			(xy 436.899695 -10.777814) (xy 436.899304 -10.787888) (xy 436.899304 -14.484096) (xy 438.361836 -14.484096)
			(xy 438.362291 -14.456725) (xy 438.37011 -14.402545) (xy 438.385601 -14.350042) (xy 438.408446 -14.300295)
			(xy 438.438173 -14.254329) (xy 438.455816 -14.233398) (xy 438.461912 -14.226286) (xy 438.468262 -14.209268)
			(xy 438.468262 -14.123924) (xy 438.461912 -14.106906) (xy 438.455816 -14.099794) (xy 438.438163 -14.078873)
			(xy 438.408453 -14.032897) (xy 438.385619 -13.983147) (xy 438.370131 -13.930644) (xy 438.362308 -13.876466)
			(xy 438.361836 -13.849096) (xy 438.362252 -13.821841) (xy 438.37001 -13.767886) (xy 438.385369 -13.715585)
			(xy 438.408015 -13.666002) (xy 438.437488 -13.620146) (xy 438.473187 -13.578953) (xy 438.514385 -13.543259)
			(xy 438.560244 -13.513792) (xy 438.60983 -13.491152) (xy 438.662133 -13.4758) (xy 438.716089 -13.468048)
			(xy 438.743344 -13.467588) (xy 438.770713 -13.46809) (xy 438.82489 -13.475899) (xy 438.877393 -13.49138)
			(xy 438.92714 -13.514214) (xy 438.973109 -13.543931) (xy 438.994042 -13.561568) (xy 439.001154 -13.567664)
			(xy 439.018172 -13.574014) (xy 439.103516 -13.574014) (xy 439.120534 -13.567664) (xy 439.127646 -13.561568)
			(xy 439.148584 -13.543936) (xy 439.194555 -13.514224) (xy 439.244302 -13.491387) (xy 439.296801 -13.475894)
			(xy 439.350975 -13.468064) (xy 439.378344 -13.467588) (xy 439.405596 -13.468037) (xy 439.459545 -13.475799)
			(xy 439.51184 -13.49116) (xy 439.561417 -13.513806) (xy 439.607267 -13.543276) (xy 439.648457 -13.578971)
			(xy 439.684148 -13.620165) (xy 439.713613 -13.666018) (xy 439.736254 -13.715597) (xy 439.751609 -13.767894)
			(xy 439.759366 -13.821844) (xy 439.759852 -13.849096) (xy 439.759395 -13.876467) (xy 439.751577 -13.930647)
			(xy 439.736086 -13.98315) (xy 439.713242 -14.032897) (xy 439.683515 -14.078863) (xy 439.665872 -14.099794)
			(xy 439.659776 -14.106906) (xy 439.653426 -14.123924) (xy 439.653426 -14.209268) (xy 439.659776 -14.226286)
			(xy 439.665872 -14.233398) (xy 439.683519 -14.254324) (xy 439.713231 -14.300298) (xy 439.736066 -14.350047)
			(xy 439.751555 -14.402549) (xy 439.75938 -14.456726) (xy 439.759852 -14.484096) (xy 439.759319 -14.511345)
			(xy 439.751564 -14.565289) (xy 439.736211 -14.61758) (xy 439.713574 -14.667154) (xy 439.684112 -14.713003)
			(xy 439.648426 -14.754192) (xy 439.607241 -14.789883) (xy 439.561397 -14.819351) (xy 439.511825 -14.841995)
			(xy 439.459536 -14.857354) (xy 439.405593 -14.865115) (xy 439.378344 -14.865604) (xy 439.350975 -14.865111)
			(xy 439.296797 -14.8573) (xy 439.244294 -14.841817) (xy 439.194547 -14.818981) (xy 439.148579 -14.789262)
			(xy 439.127646 -14.771624) (xy 439.120534 -14.765528) (xy 439.103516 -14.759178) (xy 439.018172 -14.759178)
			(xy 439.001154 -14.765528) (xy 438.994042 -14.771624) (xy 438.973108 -14.789261) (xy 438.927135 -14.818972)
			(xy 438.877388 -14.841808) (xy 438.824888 -14.8573) (xy 438.770713 -14.865129) (xy 438.743344 -14.865604)
			(xy 438.716092 -14.865104) (xy 438.662142 -14.857353) (xy 438.609845 -14.842002) (xy 438.560265 -14.819364)
			(xy 438.514411 -14.789901) (xy 438.473218 -14.754211) (xy 438.437523 -14.713021) (xy 438.408055 -14.667171)
			(xy 438.385412 -14.617593) (xy 438.370056 -14.565297) (xy 438.362299 -14.511348) (xy 438.361836 -14.484096)
			(xy 436.899304 -14.484096) (xy 436.899304 -16.328136) (xy 438.173876 -16.328136) (xy 438.174345 -16.300766)
			(xy 438.182159 -16.246586) (xy 438.197646 -16.194082) (xy 438.220488 -16.144335) (xy 438.250214 -16.098369)
			(xy 438.267856 -16.077438) (xy 438.273952 -16.070326) (xy 438.280302 -16.053308) (xy 438.280302 -15.967964)
			(xy 438.273952 -15.950946) (xy 438.267856 -15.943834) (xy 438.250212 -15.922906) (xy 438.220502 -15.876931)
			(xy 438.197668 -15.827183) (xy 438.182178 -15.774681) (xy 438.17435 -15.720505) (xy 438.173876 -15.693136)
			(xy 438.174362 -15.665885) (xy 438.182118 -15.611937) (xy 438.197473 -15.559642) (xy 438.220115 -15.510065)
			(xy 438.249581 -15.464215) (xy 438.285272 -15.423024) (xy 438.326463 -15.387333) (xy 438.372313 -15.357867)
			(xy 438.42189 -15.335225) (xy 438.474185 -15.31987) (xy 438.528133 -15.312114) (xy 438.582635 -15.312114)
			(xy 438.636583 -15.31987) (xy 438.688878 -15.335225) (xy 438.738455 -15.357867) (xy 438.784305 -15.387333)
			(xy 438.825496 -15.423024) (xy 438.861187 -15.464215) (xy 438.890653 -15.510065) (xy 438.913295 -15.559642)
			(xy 438.92865 -15.611937) (xy 438.936406 -15.665885) (xy 438.936892 -15.693136) (xy 438.936449 -15.720507)
			(xy 438.928626 -15.774687) (xy 438.913132 -15.827191) (xy 438.890285 -15.876937) (xy 438.860555 -15.922903)
			(xy 438.842912 -15.943834) (xy 438.836816 -15.950946) (xy 438.830466 -15.967964) (xy 438.830466 -16.053308)
			(xy 438.836816 -16.070326) (xy 438.842912 -16.077438) (xy 438.860537 -16.098381) (xy 438.890251 -16.144351)
			(xy 438.913089 -16.194096) (xy 438.928584 -16.246594) (xy 438.936416 -16.300768) (xy 438.936892 -16.328136)
			(xy 438.936406 -16.355387) (xy 438.92865 -16.409335) (xy 438.913295 -16.46163) (xy 438.890653 -16.511207)
			(xy 438.861187 -16.557057) (xy 438.825496 -16.598248) (xy 438.784305 -16.633939) (xy 438.738455 -16.663405)
			(xy 438.688878 -16.686047) (xy 438.636583 -16.701402) (xy 438.582635 -16.709158) (xy 438.528133 -16.709158)
			(xy 438.474185 -16.701402) (xy 438.42189 -16.686047) (xy 438.372313 -16.663405) (xy 438.326463 -16.633939)
			(xy 438.285272 -16.598248) (xy 438.249581 -16.557057) (xy 438.220115 -16.511207) (xy 438.197473 -16.46163)
			(xy 438.182118 -16.409335) (xy 438.174362 -16.355387) (xy 438.173876 -16.328136) (xy 436.899304 -16.328136)
			(xy 436.899304 -16.92021) (xy 436.899704 -16.929697) (xy 436.906602 -16.947376) (xy 436.919425 -16.961364)
			(xy 436.927752 -16.96593) (xy 437.023002 -17.012412) (xy 437.051704 -17.009364) (xy 437.063388 -17.000474)
			(xy 437.083573 -16.985229) (xy 437.127204 -16.959637) (xy 437.173837 -16.940041) (xy 437.222652 -16.926786)
			(xy 437.272792 -16.920105) (xy 437.298084 -16.919702) (xy 437.325337 -16.920164) (xy 437.379288 -16.927919)
			(xy 437.431587 -16.943273) (xy 437.481167 -16.965914) (xy 437.527021 -16.995381) (xy 437.568215 -17.031074)
			(xy 437.603909 -17.072266) (xy 437.633378 -17.118119) (xy 437.656021 -17.167698) (xy 437.671377 -17.219996)
			(xy 437.679135 -17.273947) (xy 437.679135 -17.328453) (xy 437.671377 -17.382404) (xy 437.656021 -17.434702)
			(xy 437.633378 -17.484281) (xy 437.603909 -17.530134) (xy 437.568215 -17.571326) (xy 437.527021 -17.607019)
			(xy 437.481167 -17.636486) (xy 437.431587 -17.659127) (xy 437.379288 -17.674481) (xy 437.325337 -17.682236)
			(xy 437.298084 -17.682718) (xy 437.272793 -17.682305) (xy 437.222656 -17.675618) (xy 437.173842 -17.662362)
			(xy 437.127209 -17.64277) (xy 437.083575 -17.617187) (xy 437.063388 -17.601946) (xy 437.051704 -17.593056)
			(xy 437.023002 -17.590008) (xy 436.927752 -17.63649) (xy 436.919381 -17.641003) (xy 436.906513 -17.654987)
			(xy 436.899643 -17.672706) (xy 436.899304 -17.68221) (xy 436.899304 -22.102826) (xy 436.899732 -22.112894)
			(xy 436.907454 -22.131491) (xy 436.91429 -22.138894) (xy 437.332628 -22.557232) (xy 437.340025 -22.564081)
			(xy 437.358624 -22.571816) (xy 437.368696 -22.572218)
		)
		(stroke
			(width 0)
			(type solid)
		)
		(fill yes)
		(layer "In13.Cu")
		(net "P12V_OCP_SFF_R")
	)
	(gr_poly
		(pts
			(arc
				(start 256.800604 -37.135308)
				(mid 258.932532 -36.252077)
				(end 259.815584 -34.120074)
			)
			(arc
				(start 259.815584 -13.780008)
				(mid 260.103939 -13.083859)
				(end 260.800088 -12.795504)
			)
			(arc
				(start 385.601972 -12.795504)
				(mid 387.734244 -11.912288)
				(end 388.61746 -9.780016)
			)
			(arc
				(start 388.61746 -3.976878)
				(mid 388.611809 -3.953593)
				(end 388.596124 -3.935476)
			)
			(arc
				(start 388.596124 -3.935476)
				(mid 388.428347 -3.782165)
				(end 388.302246 -3.593084)
			)
			(xy 388.294372 -3.577336) (xy 388.262368 -3.56235)
			(arc
				(start 388.149084 -3.589528)
				(mid 388.120945 -3.607374)
				(end 388.109968 -3.638804)
			)
			(arc
				(start 388.109968 -9.780016)
				(mid 387.375393 -11.553437)
				(end 385.601972 -12.288012)
			)
			(arc
				(start 260.800088 -12.288012)
				(mid 259.745088 -12.725008)
				(end 259.308092 -13.780008)
			)
			(arc
				(start 259.308092 -34.120074)
				(mid 258.573517 -35.893495)
				(end 256.800096 -36.62807)
			)
			(arc
				(start 225.300032 -36.62807)
				(mid 223.526611 -35.893495)
				(end 222.792036 -34.120074)
			)
			(arc
				(start 222.792036 -13.780008)
				(mid 222.35504 -12.725008)
				(end 221.30004 -12.288012)
			)
			(arc
				(start 196.701918 -12.288012)
				(mid 194.928497 -11.553437)
				(end 194.193922 -9.780016)
			)
			(arc
				(start 194.193922 -8.918702)
				(mid 194.182875 -8.887327)
				(end 194.154806 -8.869426)
			)
			(xy 194.041522 -8.842248) (xy 194.009518 -8.857234)
			(arc
				(start 194.001644 -8.872982)
				(mid 193.875648 -9.062025)
				(end 193.70802 -9.215374)
			)
			(arc
				(start 193.70802 -9.215374)
				(mid 193.69232 -9.233484)
				(end 193.686684 -9.256776)
			)
			(arc
				(start 193.686684 -9.780524)
				(mid 194.569915 -11.912452)
				(end 196.701918 -12.795504)
			)
			(arc
				(start 221.30004 -12.795504)
				(mid 221.996189 -13.083859)
				(end 222.284544 -13.780008)
			)
			(arc
				(start 222.284544 -34.120074)
				(mid 223.16785 -36.252182)
				(end 225.300032 -37.135308)
			)
		)
		(stroke
			(width 0)
			(type solid)
		)
		(fill yes)
		(layer "In13.Cu")
		(net "GND")
	)
	(gr_poly
		(pts
			(xy 380.696724 -180.526182) (xy 379.80366 -179.633118) (xy 379.80366 -177.22596) (xy 380.22022 -176.8094)
			(xy 384.52298 -176.8094) (xy 385.308094 -177.59426) (xy 385.308094 -180.553614) (xy 385.94538 -181.1909)
			(xy 385.94538 -182.337964) (xy 386.09778 -182.490364) (xy 389.016494 -182.490364) (xy 389.027924 -182.478934)
			(xy 389.027924 -180.526182) (xy 388.15772 -179.655978) (xy 388.15772 -176.774094) (xy 387.46303 -176.079404)
			(xy 387.161278 -175.777652) (xy 386.155438 -174.771812) (xy 386.155438 -170.080432) (xy 384.092958 -168.017952)
			(xy 384.092958 -160.016952) (xy 383.711958 -159.635952) (xy 365.421418 -159.635952) (xy 364.534958 -158.749492)
			(xy 364.534958 -150.042372) (xy 363.531658 -149.039072) (xy 352.823018 -149.039072) (xy 350.326452 -151.535638)
			(xy 340.642956 -151.535638) (xy 340.254844 -151.92375) (xy 340.254844 -152.754768) (xy 358.696256 -152.754768)
			(xy 358.696256 -152.670072) (xy 358.704307 -152.585758) (xy 358.720336 -152.502592) (xy 358.744197 -152.421325)
			(xy 358.775676 -152.342695) (xy 358.814487 -152.267414) (xy 358.860277 -152.196162) (xy 358.912633 -152.129586)
			(xy 358.971081 -152.068288) (xy 359.035091 -152.012823) (xy 359.104083 -151.963694) (xy 359.177433 -151.921345)
			(xy 359.254476 -151.886161) (xy 359.334515 -151.858459) (xy 359.416824 -151.838491) (xy 359.500659 -151.826438)
			(xy 359.58526 -151.822408) (xy 359.669861 -151.826438) (xy 359.753696 -151.838491) (xy 359.836005 -151.858459)
			(xy 359.916044 -151.886161) (xy 359.993087 -151.921345) (xy 360.066437 -151.963694) (xy 360.135429 -152.012823)
			(xy 360.199439 -152.068288) (xy 360.257887 -152.129586) (xy 360.310243 -152.196162) (xy 360.356033 -152.267414)
			(xy 360.394844 -152.342695) (xy 360.426323 -152.421325) (xy 360.450184 -152.502592) (xy 360.466213 -152.585758)
			(xy 360.474264 -152.670072) (xy 360.474768 -152.71242) (xy 360.474264 -152.754768) (xy 360.474263 -152.754781)
			(xy 361.196124 -152.754781) (xy 361.196124 -152.670059) (xy 361.204177 -152.585722) (xy 361.220211 -152.502532)
			(xy 361.244079 -152.421242) (xy 361.275567 -152.34259) (xy 361.314389 -152.267287) (xy 361.360192 -152.196015)
			(xy 361.412563 -152.129419) (xy 361.471028 -152.068104) (xy 361.535056 -152.012623) (xy 361.604068 -151.96348)
			(xy 361.677438 -151.92112) (xy 361.754503 -151.885925) (xy 361.834565 -151.858216) (xy 361.916898 -151.838242)
			(xy 362.000757 -151.826185) (xy 362.085382 -151.822154) (xy 362.170007 -151.826185) (xy 362.253866 -151.838242)
			(xy 362.336199 -151.858216) (xy 362.416261 -151.885925) (xy 362.493326 -151.92112) (xy 362.566696 -151.96348)
			(xy 362.635708 -152.012623) (xy 362.699736 -152.068104) (xy 362.758201 -152.129419) (xy 362.810572 -152.196015)
			(xy 362.856375 -152.267287) (xy 362.895197 -152.34259) (xy 362.926685 -152.421242) (xy 362.950553 -152.502532)
			(xy 362.966587 -152.585722) (xy 362.97464 -152.670059) (xy 362.975144 -152.71242) (xy 362.97464 -152.754781)
			(xy 362.966587 -152.839118) (xy 362.950553 -152.922308) (xy 362.926685 -153.003598) (xy 362.895197 -153.08225)
			(xy 362.856375 -153.157553) (xy 362.810572 -153.228825) (xy 362.758201 -153.295421) (xy 362.699736 -153.356736)
			(xy 362.635708 -153.412217) (xy 362.566696 -153.46136) (xy 362.493326 -153.50372) (xy 362.416261 -153.538915)
			(xy 362.336199 -153.566624) (xy 362.253866 -153.586598) (xy 362.170007 -153.598655) (xy 362.085382 -153.602687)
			(xy 362.000757 -153.598655) (xy 361.916898 -153.586598) (xy 361.834565 -153.566624) (xy 361.754503 -153.538915)
			(xy 361.677438 -153.50372) (xy 361.604068 -153.46136) (xy 361.535056 -153.412217) (xy 361.471028 -153.356736)
			(xy 361.412563 -153.295421) (xy 361.360192 -153.228825) (xy 361.314389 -153.157553) (xy 361.275567 -153.08225)
			(xy 361.244079 -153.003598) (xy 361.220211 -152.922308) (xy 361.204177 -152.839118) (xy 361.196124 -152.754781)
			(xy 360.474263 -152.754781) (xy 360.466213 -152.839082) (xy 360.450184 -152.922248) (xy 360.426323 -153.003515)
			(xy 360.394844 -153.082145) (xy 360.356033 -153.157426) (xy 360.310243 -153.228678) (xy 360.257887 -153.295254)
			(xy 360.199439 -153.356552) (xy 360.135429 -153.412017) (xy 360.066437 -153.461146) (xy 359.993087 -153.503495)
			(xy 359.916044 -153.538679) (xy 359.836005 -153.566381) (xy 359.753696 -153.586349) (xy 359.669861 -153.598402)
			(xy 359.58526 -153.602433) (xy 359.500659 -153.598402) (xy 359.416824 -153.586349) (xy 359.334515 -153.566381)
			(xy 359.254476 -153.538679) (xy 359.177433 -153.503495) (xy 359.104083 -153.461146) (xy 359.035091 -153.412017)
			(xy 358.971081 -153.356552) (xy 358.912633 -153.295254) (xy 358.860277 -153.228678) (xy 358.814487 -153.157426)
			(xy 358.775676 -153.082145) (xy 358.744197 -153.003515) (xy 358.720336 -152.922248) (xy 358.704307 -152.839082)
			(xy 358.696256 -152.754768) (xy 340.254844 -152.754768) (xy 340.254844 -160.55086) (xy 340.614508 -160.910524)
			(xy 345.568524 -160.910524) (xy 345.619324 -160.859724) (xy 347.346524 -160.859724) (xy 347.346524 -158.894018)
			(xy 347.346524 -158.830264) (xy 346.47378 -157.95752) (xy 346.47378 -155.477464) (xy 347.07322 -154.878024)
			(xy 351.54743 -154.878024) (xy 352.034094 -155.364688) (xy 352.034094 -158.592774) (xy 352.65106 -159.20974)
			(xy 352.65106 -160.609534) (xy 352.034094 -161.2265) (xy 352.034094 -162.635946) (xy 352.034094 -162.639178)
			(xy 376.980954 -162.639178) (xy 376.980954 -162.554482) (xy 376.989005 -162.470168) (xy 377.005034 -162.387002)
			(xy 377.028895 -162.305735) (xy 377.060374 -162.227105) (xy 377.099185 -162.151824) (xy 377.144975 -162.080572)
			(xy 377.197331 -162.013996) (xy 377.255779 -161.952698) (xy 377.319789 -161.897233) (xy 377.388781 -161.848104)
			(xy 377.462131 -161.805755) (xy 377.539174 -161.770571) (xy 377.619213 -161.742869) (xy 377.701522 -161.722901)
			(xy 377.785357 -161.710848) (xy 377.869958 -161.706818) (xy 377.954559 -161.710848) (xy 378.038394 -161.722901)
			(xy 378.120703 -161.742869) (xy 378.200742 -161.770571) (xy 378.277785 -161.805755) (xy 378.351135 -161.848104)
			(xy 378.420127 -161.897233) (xy 378.484137 -161.952698) (xy 378.542585 -162.013996) (xy 378.594941 -162.080572)
			(xy 378.640731 -162.151824) (xy 378.679542 -162.227105) (xy 378.711021 -162.305735) (xy 378.734882 -162.387002)
			(xy 378.750911 -162.470168) (xy 378.758962 -162.554482) (xy 378.759466 -162.59683) (xy 378.758962 -162.639178)
			(xy 378.750911 -162.723492) (xy 378.734882 -162.806658) (xy 378.711021 -162.887925) (xy 378.679542 -162.966555)
			(xy 378.640731 -163.041836) (xy 378.594941 -163.113088) (xy 378.542585 -163.179664) (xy 378.484137 -163.240962)
			(xy 378.420127 -163.296427) (xy 378.351135 -163.345556) (xy 378.277785 -163.387905) (xy 378.200742 -163.423089)
			(xy 378.120703 -163.450791) (xy 378.038394 -163.470759) (xy 377.954559 -163.482812) (xy 377.869958 -163.486843)
			(xy 377.785357 -163.482812) (xy 377.701522 -163.470759) (xy 377.619213 -163.450791) (xy 377.539174 -163.423089)
			(xy 377.462131 -163.387905) (xy 377.388781 -163.345556) (xy 377.319789 -163.296427) (xy 377.255779 -163.240962)
			(xy 377.197331 -163.179664) (xy 377.144975 -163.113088) (xy 377.099185 -163.041836) (xy 377.060374 -162.966555)
			(xy 377.028895 -162.887925) (xy 377.005034 -162.806658) (xy 376.989005 -162.723492) (xy 376.980954 -162.639178)
			(xy 352.034094 -162.639178) (xy 352.034094 -165.209728) (xy 352.034094 -169.14876) (xy 352.152458 -169.267124)
			(xy 353.874324 -169.267124) (xy 353.925124 -169.216324) (xy 355.652324 -169.216324) (xy 355.652324 -167.235632)
			(xy 354.743766 -166.327074) (xy 354.743766 -163.890706) (xy 354.903278 -163.731194) (xy 355.030278 -163.604194)
			(xy 355.95052 -162.683952) (xy 358.8512 -162.683952) (xy 360.364278 -164.19703) (xy 360.364278 -165.139313)
			(xy 376.9807 -165.139313) (xy 376.9807 -165.054591) (xy 376.988753 -164.970254) (xy 377.004787 -164.887064)
			(xy 377.028655 -164.805774) (xy 377.060143 -164.727122) (xy 377.098965 -164.651819) (xy 377.144768 -164.580547)
			(xy 377.197139 -164.513951) (xy 377.255604 -164.452636) (xy 377.319632 -164.397155) (xy 377.388644 -164.348012)
			(xy 377.462014 -164.305652) (xy 377.539079 -164.270457) (xy 377.619141 -164.242748) (xy 377.701474 -164.222774)
			(xy 377.785333 -164.210717) (xy 377.869958 -164.206686) (xy 377.954583 -164.210717) (xy 378.038442 -164.222774)
			(xy 378.120775 -164.242748) (xy 378.200837 -164.270457) (xy 378.277902 -164.305652) (xy 378.351272 -164.348012)
			(xy 378.420284 -164.397155) (xy 378.484312 -164.452636) (xy 378.542777 -164.513951) (xy 378.595148 -164.580547)
			(xy 378.640951 -164.651819) (xy 378.679773 -164.727122) (xy 378.711261 -164.805774) (xy 378.735129 -164.887064)
			(xy 378.751163 -164.970254) (xy 378.759216 -165.054591) (xy 378.75972 -165.096952) (xy 378.759216 -165.139313)
			(xy 378.751163 -165.22365) (xy 378.735129 -165.30684) (xy 378.711261 -165.38813) (xy 378.679773 -165.466782)
			(xy 378.640951 -165.542085) (xy 378.595148 -165.613357) (xy 378.542777 -165.679953) (xy 378.484312 -165.741268)
			(xy 378.420284 -165.796749) (xy 378.351272 -165.845892) (xy 378.277902 -165.888252) (xy 378.200837 -165.923447)
			(xy 378.120775 -165.951156) (xy 378.038442 -165.97113) (xy 377.954583 -165.983187) (xy 377.869958 -165.987219)
			(xy 377.785333 -165.983187) (xy 377.701474 -165.97113) (xy 377.619141 -165.951156) (xy 377.539079 -165.923447)
			(xy 377.462014 -165.888252) (xy 377.388644 -165.845892) (xy 377.319632 -165.796749) (xy 377.255604 -165.741268)
			(xy 377.197139 -165.679953) (xy 377.144768 -165.613357) (xy 377.098965 -165.542085) (xy 377.060143 -165.466782)
			(xy 377.028655 -165.38813) (xy 377.004787 -165.30684) (xy 376.988753 -165.22365) (xy 376.9807 -165.139313)
			(xy 360.364278 -165.139313) (xy 360.364278 -166.81704) (xy 360.8832 -167.335962) (xy 360.8832 -168.878758)
			(xy 360.364278 -169.39768) (xy 360.364278 -171.01693) (xy 360.364278 -173.541944) (xy 360.364278 -177.35931)
			(xy 360.542078 -177.53711) (xy 362.205524 -177.53711) (xy 362.205524 -177.491644) (xy 363.932724 -177.491644)
			(xy 363.932724 -175.510952) (xy 363.92866 -175.510952) (xy 363.03458 -174.616872) (xy 363.03458 -172.64126)
			(xy 364.53953 -171.13631) (xy 367.417858 -171.13631) (xy 368.569494 -172.287946) (xy 368.569494 -175.06188)
			(xy 369.02898 -175.521366) (xy 369.02898 -177.208434) (xy 368.569494 -177.66792) (xy 368.569494 -179.217066)
			(xy 368.569494 -182.19039) (xy 368.746278 -182.367174) (xy 368.848894 -182.46979) (xy 370.566696 -182.46979)
			(xy 370.566696 -182.464202) (xy 372.293896 -182.464202) (xy 372.293896 -180.48351) (xy 371.414294 -179.603908)
			(xy 371.414294 -177.104294) (xy 371.679978 -176.83861) (xy 372.429278 -176.08931) (xy 375.782078 -176.08931)
			(xy 377.014994 -177.322226) (xy 377.014994 -180.60162) (xy 377.53036 -181.116986) (xy 377.53036 -182.3085)
			(xy 377.712224 -182.490364) (xy 380.696724 -182.490364)
		)
		(stroke
			(width 0)
			(type solid)
		)
		(fill yes)
		(layer "In13.Cu")
		(net "SW_P12V_AUX_PVDDCR_CPU0_P0_FLT")
	)
	(gr_poly
		(pts
			(xy 350.668082 -356.115366) (xy 350.675194 -356.108) (xy 350.709738 -356.073456) (xy 350.718428 -356.065635)
			(xy 350.740547 -356.058135) (xy 350.763712 -356.061109) (xy 350.773746 -356.067106) (xy 350.78035 -356.071424)
			(xy 350.79432 -356.075742) (xy 352.91776 -356.075742) (xy 352.936556 -356.068122) (xy 352.943668 -356.060756)
			(xy 357.030274 -351.97415) (xy 357.037115 -351.96675) (xy 357.044835 -351.948152) (xy 357.04526 -351.938082)
			(xy 357.04526 -340.678262) (xy 357.03764 -340.659466) (xy 357.030274 -340.652354) (xy 356.640638 -340.262718)
			(xy 356.633237 -340.25588) (xy 356.614639 -340.248165) (xy 356.60457 -340.247732) (xy 352.148394 -340.247732)
			(xy 352.129598 -340.255352) (xy 352.122486 -340.262718) (xy 352.06305 -340.322154) (xy 352.056207 -340.329553)
			(xy 352.048484 -340.348152) (xy 352.048064 -340.358222) (xy 352.048064 -342.255856) (xy 352.055684 -342.274652)
			(xy 352.06305 -342.281764) (xy 352.93046 -343.149174) (xy 352.937299 -343.156575) (xy 352.945013 -343.175173)
			(xy 352.945446 -343.185242) (xy 352.945446 -345.47429) (xy 352.945023 -345.48436) (xy 352.937305 -345.502962)
			(xy 352.93046 -345.510358) (xy 352.513392 -345.927426) (xy 352.505997 -345.934279) (xy 352.487398 -345.942022)
			(xy 352.477324 -345.942412) (xy 347.786706 -345.942412) (xy 347.776635 -345.94199) (xy 347.758028 -345.934279)
			(xy 347.750638 -345.927426) (xy 347.229684 -345.406472) (xy 347.222833 -345.399076) (xy 347.215095 -345.380477)
			(xy 347.214698 -345.370404) (xy 347.214698 -342.547194) (xy 347.207078 -342.528398) (xy 347.199712 -342.521286)
			(xy 346.981272 -342.302846) (xy 346.974426 -342.295448) (xy 346.9667 -342.276849) (xy 346.966286 -342.266778)
			(xy 346.966286 -340.477348) (xy 346.966718 -340.467282) (xy 346.974444 -340.44869) (xy 346.981272 -340.44128)
			(xy 347.403166 -340.019386) (xy 347.410014 -340.011988) (xy 347.417749 -339.99339) (xy 347.418152 -339.983318)
			(xy 347.418152 -335.491328) (xy 347.410532 -335.472532) (xy 347.403166 -335.46542) (xy 347.262704 -335.324958)
			(xy 347.255592 -335.317846) (xy 347.236796 -335.309972) (xy 343.847166 -335.309972) (xy 343.837098 -335.310401)
			(xy 343.8185 -335.31812) (xy 343.811098 -335.324958) (xy 343.787222 -335.348834) (xy 343.779856 -335.355946)
			(xy 343.772236 -335.374742) (xy 343.772236 -337.358228) (xy 343.779856 -337.377024) (xy 343.787222 -337.384136)
			(xy 344.66022 -338.257134) (xy 344.66707 -338.26453) (xy 344.674805 -338.28313) (xy 344.675206 -338.293202)
			(xy 344.675206 -340.684358) (xy 344.674773 -340.694424) (xy 344.667044 -340.713014) (xy 344.66022 -340.720426)
			(xy 344.456512 -340.924134) (xy 344.449117 -340.93099) (xy 344.430519 -340.938739) (xy 344.420444 -340.93912)
			(xy 339.949028 -340.93912) (xy 339.938963 -340.938684) (xy 339.920376 -340.930954) (xy 339.91296 -340.924134)
			(xy 339.038438 -340.049612) (xy 339.031586 -340.042216) (xy 339.023841 -340.023618) (xy 339.023452 -340.013544)
			(xy 339.023452 -337.066382) (xy 339.015832 -337.047586) (xy 339.008466 -337.040474) (xy 338.667852 -336.69986)
			(xy 338.661006 -336.692462) (xy 338.653278 -336.673863) (xy 338.652866 -336.663792) (xy 338.652866 -335.420462)
			(xy 338.645246 -335.401666) (xy 338.63788 -335.394554) (xy 338.480146 -335.23682) (xy 338.472745 -335.22998)
			(xy 338.454147 -335.222262) (xy 338.444078 -335.221834) (xy 335.52003 -335.221834) (xy 335.509966 -335.222271)
			(xy 335.491383 -335.230007) (xy 335.483962 -335.23682) (xy 335.456022 -335.26476) (xy 335.448656 -335.271872)
			(xy 335.441036 -335.290668) (xy 335.441036 -337.215988) (xy 335.448656 -337.234784) (xy 335.456022 -337.241896)
			(xy 336.30108 -338.086954) (xy 336.30792 -338.094355) (xy 336.315638 -338.112953) (xy 336.316066 -338.123022)
			(xy 336.316066 -340.531958) (xy 336.315632 -340.542023) (xy 336.307899 -340.560609) (xy 336.30108 -340.568026)
			(xy 335.983072 -340.886034) (xy 335.975675 -340.892883) (xy 335.957076 -340.900618) (xy 335.947004 -340.90102)
			(xy 331.549248 -340.90102) (xy 331.539182 -340.900588) (xy 331.520589 -340.892863) (xy 331.51318 -340.886034)
			(xy 330.681838 -340.054692) (xy 330.674989 -340.047295) (xy 330.667251 -340.028696) (xy 330.666852 -340.018624)
			(xy 330.666852 -337.081622) (xy 330.659232 -337.062826) (xy 330.651866 -337.055714) (xy 330.321412 -336.72526)
			(xy 330.314571 -336.71786) (xy 330.306849 -336.699262) (xy 330.306426 -336.689192) (xy 330.306426 -335.49082)
			(xy 330.087478 -335.271872) (xy 327.145142 -335.271872) (xy 327.135076 -335.272305) (xy 327.116484 -335.280031)
			(xy 327.109074 -335.286858) (xy 327.098406 -335.297526) (xy 327.09104 -335.304638) (xy 327.08342 -335.323434)
			(xy 327.08342 -337.260692) (xy 327.09104 -337.279488) (xy 327.098406 -337.2866) (xy 327.9648 -338.152994)
			(xy 327.971647 -338.160392) (xy 327.979384 -338.17899) (xy 327.979786 -338.189062) (xy 327.979786 -340.524338)
			(xy 327.979356 -340.534405) (xy 327.97163 -340.552998) (xy 327.9648 -340.560406) (xy 327.621392 -340.903814)
			(xy 327.613997 -340.910668) (xy 327.595398 -340.918414) (xy 327.585324 -340.9188) (xy 323.149468 -340.9188)
			(xy 323.1394 -340.918371) (xy 323.120804 -340.910648) (xy 323.1134 -340.903814) (xy 322.419726 -340.21014)
			(xy 322.412886 -340.202739) (xy 322.40517 -340.184141) (xy 322.40474 -340.174072) (xy 322.40474 -337.173062)
			(xy 322.39712 -337.154266) (xy 322.389754 -337.147154) (xy 321.972432 -336.729832) (xy 321.965593 -336.722431)
			(xy 321.957878 -336.703833) (xy 321.957446 -336.693764) (xy 321.957446 -335.473294) (xy 321.949826 -335.454498)
			(xy 321.94246 -335.447386) (xy 321.812412 -335.317338) (xy 321.805016 -335.310486) (xy 321.786418 -335.302741)
			(xy 321.776344 -335.302352) (xy 318.835278 -335.302352) (xy 318.825211 -335.302781) (xy 318.806617 -335.310506)
			(xy 318.79921 -335.317338) (xy 318.742822 -335.373726) (xy 318.735456 -335.380838) (xy 318.727836 -335.399634)
			(xy 318.727836 -337.279488) (xy 318.735456 -337.298284) (xy 318.742822 -337.305396) (xy 319.61582 -338.178394)
			(xy 319.622676 -338.185788) (xy 319.630425 -338.204387) (xy 319.630806 -338.214462) (xy 319.630806 -339.993478)
			(xy 319.638426 -340.012274) (xy 319.645792 -340.019386) (xy 320.276474 -340.650068) (xy 320.283312 -340.657469)
			(xy 320.291026 -340.676067) (xy 320.29146 -340.686136) (xy 320.29146 -342.213946) (xy 320.29908 -342.232742)
			(xy 320.306446 -342.239854) (xy 321.476878 -343.410286) (xy 321.483713 -343.417688) (xy 321.49142 -343.436287)
			(xy 321.491864 -343.446354) (xy 321.491864 -346.25153) (xy 321.491435 -346.261597) (xy 321.483709 -346.28019)
			(xy 321.476878 -346.287598) (xy 319.59169 -348.172786) (xy 319.584291 -348.179632) (xy 319.565693 -348.187365)
			(xy 319.555622 -348.187772) (xy 314.880752 -348.187772) (xy 314.870686 -348.187339) (xy 314.852097 -348.17961)
			(xy 314.844684 -348.172786) (xy 313.680094 -347.008196) (xy 313.672695 -347.001351) (xy 313.654097 -346.993619)
			(xy 313.644026 -346.99321) (xy 309.399178 -346.99321) (xy 309.380382 -347.00083) (xy 309.37327 -347.008196)
			(xy 309.129176 -347.25229) (xy 309.12232 -347.259684) (xy 309.114569 -347.278283) (xy 309.11419 -347.288358)
			(xy 309.11419 -349.477584) (xy 309.12181 -349.49638) (xy 309.129176 -349.503492) (xy 310.611774 -350.98609)
			(xy 310.619176 -350.992926) (xy 310.637774 -351.000635) (xy 310.647842 -351.001076) (xy 311.412128 -351.001076)
			(xy 311.412382 -351.00133) (xy 314.235592 -351.00133) (xy 314.245662 -351.001752) (xy 314.264266 -351.009468)
			(xy 314.27166 -351.016316) (xy 315.229424 -351.97408) (xy 327.06208 -351.97408) (xy 327.06208 -351.889384)
			(xy 327.070131 -351.80507) (xy 327.08616 -351.721904) (xy 327.110021 -351.640637) (xy 327.1415 -351.562007)
			(xy 327.180311 -351.486726) (xy 327.226101 -351.415474) (xy 327.278457 -351.348898) (xy 327.336905 -351.2876)
			(xy 327.400915 -351.232135) (xy 327.469907 -351.183006) (xy 327.543257 -351.140657) (xy 327.6203 -351.105473)
			(xy 327.700339 -351.077771) (xy 327.782648 -351.057803) (xy 327.866483 -351.04575) (xy 327.951084 -351.04172)
			(xy 328.035685 -351.04575) (xy 328.11952 -351.057803) (xy 328.201829 -351.077771) (xy 328.281868 -351.105473)
			(xy 328.358911 -351.140657) (xy 328.432261 -351.183006) (xy 328.501253 -351.232135) (xy 328.565263 -351.2876)
			(xy 328.623711 -351.348898) (xy 328.676067 -351.415474) (xy 328.721857 -351.486726) (xy 328.760668 -351.562007)
			(xy 328.792147 -351.640637) (xy 328.816008 -351.721904) (xy 328.832037 -351.80507) (xy 328.840088 -351.889384)
			(xy 328.840592 -351.931732) (xy 328.840088 -351.97408) (xy 334.52206 -351.97408) (xy 334.52206 -351.889384)
			(xy 334.530111 -351.80507) (xy 334.54614 -351.721904) (xy 334.570001 -351.640637) (xy 334.60148 -351.562007)
			(xy 334.640291 -351.486726) (xy 334.686081 -351.415474) (xy 334.738437 -351.348898) (xy 334.796885 -351.2876)
			(xy 334.860895 -351.232135) (xy 334.929887 -351.183006) (xy 335.003237 -351.140657) (xy 335.08028 -351.105473)
			(xy 335.160319 -351.077771) (xy 335.242628 -351.057803) (xy 335.326463 -351.04575) (xy 335.411064 -351.04172)
			(xy 335.495665 -351.04575) (xy 335.5795 -351.057803) (xy 335.661809 -351.077771) (xy 335.741848 -351.105473)
			(xy 335.818891 -351.140657) (xy 335.892241 -351.183006) (xy 335.961233 -351.232135) (xy 336.025243 -351.2876)
			(xy 336.083691 -351.348898) (xy 336.136047 -351.415474) (xy 336.181837 -351.486726) (xy 336.220648 -351.562007)
			(xy 336.252127 -351.640637) (xy 336.275988 -351.721904) (xy 336.292017 -351.80507) (xy 336.300068 -351.889384)
			(xy 336.300572 -351.931732) (xy 336.300068 -351.97408) (xy 336.292017 -352.058394) (xy 336.275988 -352.14156)
			(xy 336.252127 -352.222827) (xy 336.220648 -352.301457) (xy 336.181837 -352.376738) (xy 336.136047 -352.44799)
			(xy 336.083691 -352.514566) (xy 336.025243 -352.575864) (xy 335.961233 -352.631329) (xy 335.892241 -352.680458)
			(xy 335.818891 -352.722807) (xy 335.741848 -352.757991) (xy 335.661809 -352.785693) (xy 335.5795 -352.805661)
			(xy 335.495665 -352.817714) (xy 335.411064 -352.821745) (xy 335.326463 -352.817714) (xy 335.242628 -352.805661)
			(xy 335.160319 -352.785693) (xy 335.08028 -352.757991) (xy 335.003237 -352.722807) (xy 334.929887 -352.680458)
			(xy 334.860895 -352.631329) (xy 334.796885 -352.575864) (xy 334.738437 -352.514566) (xy 334.686081 -352.44799)
			(xy 334.640291 -352.376738) (xy 334.60148 -352.301457) (xy 334.570001 -352.222827) (xy 334.54614 -352.14156)
			(xy 334.530111 -352.058394) (xy 334.52206 -351.97408) (xy 328.840088 -351.97408) (xy 328.832037 -352.058394)
			(xy 328.816008 -352.14156) (xy 328.792147 -352.222827) (xy 328.760668 -352.301457) (xy 328.721857 -352.376738)
			(xy 328.676067 -352.44799) (xy 328.623711 -352.514566) (xy 328.565263 -352.575864) (xy 328.501253 -352.631329)
			(xy 328.432261 -352.680458) (xy 328.358911 -352.722807) (xy 328.281868 -352.757991) (xy 328.201829 -352.785693)
			(xy 328.11952 -352.805661) (xy 328.035685 -352.817714) (xy 327.951084 -352.821745) (xy 327.866483 -352.817714)
			(xy 327.782648 -352.805661) (xy 327.700339 -352.785693) (xy 327.6203 -352.757991) (xy 327.543257 -352.722807)
			(xy 327.469907 -352.680458) (xy 327.400915 -352.631329) (xy 327.336905 -352.575864) (xy 327.278457 -352.514566)
			(xy 327.226101 -352.44799) (xy 327.180311 -352.376738) (xy 327.1415 -352.301457) (xy 327.110021 -352.222827)
			(xy 327.08616 -352.14156) (xy 327.070131 -352.058394) (xy 327.06208 -351.97408) (xy 315.229424 -351.97408)
			(xy 319.363344 -356.108) (xy 319.370745 -356.11484) (xy 319.389343 -356.122558) (xy 319.399412 -356.122986)
			(xy 350.649286 -356.122986)
		)
		(stroke
			(width 0)
			(type solid)
		)
		(fill yes)
		(layer "In13.Cu")
		(net "SW_P12V_AUX_PVDDCR_CPU1_P0_FLT")
	)
	(gr_poly
		(pts
			(xy 444.276734 -26.22296) (xy 444.286801 -26.222529) (xy 444.305392 -26.214802) (xy 444.312802 -26.207974)
			(xy 444.46825 -26.052526) (xy 444.47509 -26.045126) (xy 444.482806 -26.026527) (xy 444.483236 -26.016458)
			(xy 444.483236 -25.193244) (xy 444.48367 -25.183179) (xy 444.491403 -25.164593) (xy 444.498222 -25.157176)
			(xy 445.08547 -24.569928) (xy 445.092871 -24.56309) (xy 445.11147 -24.555376) (xy 445.121538 -24.554942)
			(xy 445.158622 -24.554942) (xy 445.168689 -24.554513) (xy 445.187282 -24.546787) (xy 445.19469 -24.539956)
			(xy 445.681608 -24.053038) (xy 445.689005 -24.046189) (xy 445.707604 -24.038451) (xy 445.717676 -24.038052)
			(xy 445.740282 -24.038052) (xy 445.750344 -24.037612) (xy 445.768923 -24.029872) (xy 445.77635 -24.023066)
			(xy 445.835278 -23.964138) (xy 445.842117 -23.956737) (xy 445.849832 -23.938139) (xy 445.850264 -23.92807)
			(xy 445.850264 -19.062954) (xy 445.849938 -19.053873) (xy 445.843686 -19.036826) (xy 445.838072 -19.02968)
			(xy 445.809056 -18.995106) (xy 445.757418 -18.92107) (xy 445.713548 -18.842183) (xy 445.677898 -18.759256)
			(xy 445.650834 -18.673143) (xy 445.632635 -18.584731) (xy 445.623489 -18.494931) (xy 445.622934 -18.449798)
			(xy 445.623503 -18.404667) (xy 445.63267 -18.314871) (xy 445.65088 -18.226465) (xy 445.677945 -18.140356)
			(xy 445.713587 -18.057429) (xy 445.757441 -17.978536) (xy 445.809055 -17.904487) (xy 445.838072 -17.869916)
			(xy 445.843694 -17.862776) (xy 445.849946 -17.845724) (xy 445.850264 -17.836642) (xy 445.850264 -17.183354)
			(xy 445.850697 -17.173289) (xy 445.858431 -17.154703) (xy 445.86525 -17.147286) (xy 446.037208 -16.975328)
			(xy 446.044606 -16.96848) (xy 446.063204 -16.960744) (xy 446.073276 -16.960342) (xy 450.688964 -16.960342)
			(xy 450.688964 -16.966692) (xy 451.362318 -17.640046) (xy 451.369166 -17.647443) (xy 451.376897 -17.666042)
			(xy 451.377304 -17.676114) (xy 451.377304 -18.602198) (xy 451.377727 -18.612268) (xy 451.385441 -18.630873)
			(xy 451.39229 -18.638266) (xy 451.720458 -18.966434) (xy 451.727856 -18.973279) (xy 451.746455 -18.981002)
			(xy 451.756526 -18.98142) (xy 452.519542 -18.98142) (xy 452.529609 -18.98099) (xy 452.548205 -18.973267)
			(xy 452.55561 -18.966434) (xy 452.604378 -18.917666) (xy 452.611222 -18.910267) (xy 452.618947 -18.891668)
			(xy 452.619364 -18.881598) (xy 452.619364 -18.623534) (xy 452.619801 -18.613471) (xy 452.627539 -18.59489)
			(xy 452.63435 -18.587466) (xy 454.246488 -16.975328) (xy 454.253885 -16.968477) (xy 454.272483 -16.960734)
			(xy 454.282556 -16.960342) (xy 455.233024 -16.960342) (xy 455.243091 -16.959913) (xy 455.261684 -16.952186)
			(xy 455.269092 -16.945356) (xy 455.41819 -16.796258) (xy 455.425031 -16.788858) (xy 455.432752 -16.770259)
			(xy 455.433176 -16.76019) (xy 455.433176 -14.170406) (xy 455.432753 -14.160336) (xy 455.425038 -14.141732)
			(xy 455.41819 -14.134338) (xy 455.24039 -13.956538) (xy 455.233278 -13.949172) (xy 455.214482 -13.941552)
			(xy 453.10171 -13.941552) (xy 453.07377 -13.964666) (xy 453.070214 -13.982954) (xy 453.062122 -14.023189)
			(xy 453.0395 -14.102087) (xy 453.009706 -14.178565) (xy 452.972993 -14.251973) (xy 452.929674 -14.321687)
			(xy 452.880116 -14.387114) (xy 452.824742 -14.447697) (xy 452.764023 -14.502921) (xy 452.698474 -14.552317)
			(xy 452.628653 -14.595464) (xy 452.555154 -14.631995) (xy 452.478603 -14.6616) (xy 452.39965 -14.684027)
			(xy 452.318966 -14.699085) (xy 452.237238 -14.706646) (xy 452.1962 -14.707108) (xy 452.155213 -14.706643)
			(xy 452.073585 -14.699108) (xy 451.992997 -14.684093) (xy 451.914133 -14.661724) (xy 451.837662 -14.632193)
			(xy 451.764234 -14.595749) (xy 451.694471 -14.552703) (xy 451.628966 -14.503418) (xy 451.568274 -14.448315)
			(xy 451.512912 -14.387859) (xy 451.463348 -14.322565) (xy 451.420003 -14.252987) (xy 451.383246 -14.179715)
			(xy 451.367906 -14.141704) (xy 451.364707 -14.134204) (xy 451.354344 -14.121628) (xy 451.347586 -14.117066)
			(xy 451.326164 -14.103223) (xy 451.286878 -14.070696) (xy 451.252288 -14.033213) (xy 451.223013 -13.991447)
			(xy 451.210934 -13.968984) (xy 451.206307 -13.960904) (xy 451.192427 -13.948517) (xy 451.175026 -13.941937)
			(xy 451.165722 -13.941552) (xy 450.277484 -13.941552) (xy 450.249798 -13.963904) (xy 450.245988 -13.98143)
			(xy 450.236326 -14.023439) (xy 450.209931 -14.105505) (xy 450.175721 -14.184632) (xy 450.134015 -14.260078)
			(xy 450.085205 -14.331134) (xy 450.02975 -14.397136) (xy 449.968169 -14.457462) (xy 449.90104 -14.511547)
			(xy 449.828994 -14.558883) (xy 449.752705 -14.599027) (xy 449.672891 -14.631602) (xy 449.590299 -14.656302)
			(xy 449.505705 -14.672895) (xy 449.419903 -14.681226) (xy 449.3768 -14.681708) (xy 449.332888 -14.681174)
			(xy 449.245491 -14.672516) (xy 449.159371 -14.655293) (xy 449.075366 -14.629673) (xy 448.994292 -14.595906)
			(xy 448.916938 -14.554318) (xy 448.844055 -14.505316) (xy 448.809872 -14.477746) (xy 448.802736 -14.472372)
			(xy 448.785909 -14.466416) (xy 448.76806 -14.466562) (xy 448.75958 -14.469364) (xy 448.7186 -14.484381)
			(xy 448.634374 -14.507284) (xy 448.591432 -14.515084) (xy 448.58226 -14.517053) (xy 448.566103 -14.526557)
			(xy 448.559936 -14.533626) (xy 448.54114 -14.557502) (xy 448.535826 -14.564815) (xy 448.530229 -14.581991)
			(xy 448.530218 -14.59103) (xy 448.530472 -14.607032) (xy 448.529986 -14.634283) (xy 448.52223 -14.688231)
			(xy 448.506875 -14.740526) (xy 448.484233 -14.790103) (xy 448.454767 -14.835953) (xy 448.419076 -14.877144)
			(xy 448.377885 -14.912835) (xy 448.332035 -14.942301) (xy 448.282458 -14.964943) (xy 448.230163 -14.980298)
			(xy 448.176215 -14.988054) (xy 448.121713 -14.988054) (xy 448.067765 -14.980298) (xy 448.01547 -14.964943)
			(xy 447.965893 -14.942301) (xy 447.920043 -14.912835) (xy 447.878852 -14.877144) (xy 447.843161 -14.835953)
			(xy 447.813695 -14.790103) (xy 447.791053 -14.740526) (xy 447.775698 -14.688231) (xy 447.767942 -14.634283)
			(xy 447.767456 -14.607032) (xy 447.768023 -14.576842) (xy 447.777532 -14.517216) (xy 447.796332 -14.459838)
			(xy 447.823953 -14.406146) (xy 447.84137 -14.38148) (xy 447.846407 -14.37394) (xy 447.851353 -14.356506)
			(xy 447.851022 -14.347444) (xy 447.848482 -14.317218) (xy 447.847402 -14.307878) (xy 447.839308 -14.290921)
			(xy 447.832734 -14.284198) (xy 447.798686 -14.251142) (xy 447.73708 -14.178954) (xy 447.683507 -14.100619)
			(xy 447.638575 -14.017028) (xy 447.620136 -13.973302) (xy 447.615926 -13.964093) (xy 447.601683 -13.949725)
			(xy 447.583008 -13.941943) (xy 447.572892 -13.941552) (xy 443.02553 -13.941552) (xy 443.015467 -13.941989)
			(xy 442.996886 -13.949727) (xy 442.989462 -13.956538) (xy 442.288168 -14.657832) (xy 446.573146 -14.657832)
			(xy 446.577217 -14.60221) (xy 446.589343 -14.547773) (xy 446.609266 -14.495682) (xy 446.636562 -14.447047)
			(xy 446.670648 -14.402904) (xy 446.710797 -14.364195) (xy 446.756155 -14.331744) (xy 446.805755 -14.306243)
			(xy 446.858539 -14.288236) (xy 446.913382 -14.278106) (xy 446.969116 -14.276069) (xy 447.024553 -14.282169)
			(xy 447.07851 -14.296275) (xy 447.129839 -14.318087) (xy 447.177445 -14.347141) (xy 447.220313 -14.382816)
			(xy 447.25753 -14.424353) (xy 447.288303 -14.470866) (xy 447.311975 -14.521363) (xy 447.328043 -14.57477)
			(xy 447.336163 -14.629946) (xy 447.336672 -14.657832) (xy 447.336163 -14.685718) (xy 447.328043 -14.740894)
			(xy 447.311975 -14.794301) (xy 447.288303 -14.844798) (xy 447.25753 -14.891311) (xy 447.220313 -14.932848)
			(xy 447.177445 -14.968523) (xy 447.129839 -14.997577) (xy 447.07851 -15.019389) (xy 447.024553 -15.033495)
			(xy 446.969116 -15.039595) (xy 446.913382 -15.037558) (xy 446.858539 -15.027428) (xy 446.805755 -15.009421)
			(xy 446.756155 -14.98392) (xy 446.710797 -14.951469) (xy 446.670648 -14.91276) (xy 446.636562 -14.868617)
			(xy 446.609266 -14.819982) (xy 446.589343 -14.767891) (xy 446.577217 -14.713454) (xy 446.573146 -14.657832)
			(xy 442.288168 -14.657832) (xy 442.039248 -14.906752) (xy 442.032405 -14.914151) (xy 442.024682 -14.93275)
			(xy 442.024262 -14.94282) (xy 442.024262 -21.345144) (xy 442.02383 -21.35521) (xy 442.0161 -21.373799)
			(xy 442.009276 -21.381212) (xy 440.834526 -22.555962) (xy 440.827687 -22.563363) (xy 440.819971 -22.581961)
			(xy 440.81954 -22.59203) (xy 440.81954 -23.5781) (xy 441.09303 -23.5781) (xy 441.09706 -23.493493)
			(xy 441.109115 -23.409651) (xy 441.129085 -23.327336) (xy 441.156789 -23.247291) (xy 441.191976 -23.170243)
			(xy 441.234328 -23.096888) (xy 441.283461 -23.027891) (xy 441.338931 -22.963876) (xy 441.400234 -22.905425)
			(xy 441.466816 -22.853065) (xy 441.538073 -22.807272) (xy 441.613361 -22.76846) (xy 441.691997 -22.73698)
			(xy 441.77327 -22.713117) (xy 441.856442 -22.697088) (xy 441.940762 -22.689038) (xy 441.983114 -22.68855)
			(xy 442.025557 -22.689042) (xy 442.110058 -22.69713) (xy 442.193403 -22.713231) (xy 442.274836 -22.737198)
			(xy 442.353615 -22.768813) (xy 442.391546 -22.787864) (xy 442.40271 -22.792845) (xy 442.427118 -22.792845)
			(xy 442.438282 -22.787864) (xy 442.476212 -22.768812) (xy 442.554991 -22.737195) (xy 442.636424 -22.713228)
			(xy 442.71977 -22.697128) (xy 442.804271 -22.689042) (xy 442.846714 -22.68855) (xy 442.88906 -22.689138)
			(xy 442.973369 -22.69719) (xy 443.05653 -22.713219) (xy 443.137791 -22.737081) (xy 443.216416 -22.768559)
			(xy 443.291693 -22.807368) (xy 443.36294 -22.853156) (xy 443.429513 -22.90551) (xy 443.490807 -22.963955)
			(xy 443.546268 -23.027961) (xy 443.595394 -23.09695) (xy 443.637739 -23.170296) (xy 443.672921 -23.247335)
			(xy 443.700621 -23.327369) (xy 443.720588 -23.409674) (xy 443.732641 -23.493504) (xy 443.736671 -23.5781)
			(xy 443.732641 -23.662696) (xy 443.720588 -23.746526) (xy 443.700621 -23.828831) (xy 443.672921 -23.908865)
			(xy 443.637739 -23.985904) (xy 443.595394 -24.05925) (xy 443.546268 -24.128239) (xy 443.490807 -24.192245)
			(xy 443.429513 -24.25069) (xy 443.36294 -24.303044) (xy 443.291693 -24.348832) (xy 443.216416 -24.387641)
			(xy 443.137791 -24.419119) (xy 443.05653 -24.442981) (xy 442.973369 -24.45901) (xy 442.88906 -24.467062)
			(xy 442.846714 -24.467566) (xy 442.804271 -24.467061) (xy 442.719771 -24.458976) (xy 442.636426 -24.442878)
			(xy 442.554993 -24.418914) (xy 442.476213 -24.387301) (xy 442.438282 -24.368252) (xy 442.427118 -24.363271)
			(xy 442.40271 -24.363271) (xy 442.391546 -24.368252) (xy 442.353611 -24.387295) (xy 442.274834 -24.418913)
			(xy 442.193402 -24.442882) (xy 442.110057 -24.458984) (xy 442.025557 -24.467073) (xy 441.983114 -24.467566)
			(xy 441.940762 -24.467162) (xy 441.856442 -24.459112) (xy 441.77327 -24.443083) (xy 441.691997 -24.41922)
			(xy 441.613361 -24.38774) (xy 441.538073 -24.348928) (xy 441.466816 -24.303135) (xy 441.400234 -24.250775)
			(xy 441.338931 -24.192324) (xy 441.283461 -24.128309) (xy 441.234328 -24.059312) (xy 441.191976 -23.985957)
			(xy 441.156789 -23.908909) (xy 441.129085 -23.828864) (xy 441.109115 -23.746549) (xy 441.09706 -23.662707)
			(xy 441.09303 -23.5781) (xy 440.81954 -23.5781) (xy 440.81954 -25.996392) (xy 440.819963 -26.006462)
			(xy 440.82768 -26.025065) (xy 440.834526 -26.03246) (xy 441.01004 -26.207974) (xy 441.017439 -26.214817)
			(xy 441.036038 -26.222541) (xy 441.046108 -26.22296)
		)
		(stroke
			(width 0)
			(type solid)
		)
		(fill yes)
		(layer "In13.Cu")
		(net "P12V_OCP_SFF")
	)
	(gr_poly
		(pts
			(xy 80.104234 -182.515002) (xy 80.114301 -182.514573) (xy 80.132897 -182.50685) (xy 80.140302 -182.500016)
			(xy 80.16113 -182.479188) (xy 80.168526 -182.472337) (xy 80.187125 -182.464599) (xy 80.197198 -182.464202)
			(xy 81.852516 -182.464202) (xy 81.862522 -182.463711) (xy 81.881008 -182.456049) (xy 81.895157 -182.441896)
			(xy 81.902814 -182.423408) (xy 81.903316 -182.413402) (xy 81.903316 -180.53431) (xy 81.903316 -180.432456)
			(xy 80.75422 -179.28336) (xy 80.75422 -176.60112) (xy 80.971898 -176.383442) (xy 81.964784 -176.383442)
			(xy 82.364072 -176.78273) (xy 82.371471 -176.789573) (xy 82.39007 -176.797292) (xy 82.40014 -176.797716)
			(xy 86.228428 -176.797716) (xy 86.238496 -176.798145) (xy 86.257091 -176.805868) (xy 86.264496 -176.812702)
			(xy 86.510368 -177.058574) (xy 86.517206 -177.065975) (xy 86.524919 -177.084574) (xy 86.525354 -177.094642)
			(xy 86.525354 -180.467) (xy 87.18804 -181.129686) (xy 87.18804 -182.152544) (xy 87.46998 -182.434484)
			(xy 88.514174 -182.434484) (xy 88.524238 -182.434047) (xy 88.542821 -182.426312) (xy 88.550242 -182.419498)
			(xy 88.573356 -182.396384) (xy 88.573356 -182.39613) (xy 90.246454 -182.39613) (xy 90.256484 -182.395719)
			(xy 90.275022 -182.388058) (xy 90.289216 -182.373885) (xy 90.296904 -182.355359) (xy 90.297254 -182.34533)
			(xy 90.297254 -180.466238) (xy 90.297254 -180.398674) (xy 89.41054 -179.51196) (xy 89.41054 -177.145442)
			(xy 89.81186 -176.744122) (xy 94.674182 -176.744122) (xy 94.684245 -176.744561) (xy 94.702826 -176.752298)
			(xy 94.71025 -176.759108) (xy 94.955868 -177.004726) (xy 94.962714 -177.012124) (xy 94.970444 -177.030723)
			(xy 94.970854 -177.040794) (xy 94.970854 -180.53558) (xy 95.55734 -181.122066) (xy 95.55734 -182.238904)
			(xy 95.77832 -182.459884) (xy 96.897952 -182.459884) (xy 96.908018 -182.459451) (xy 96.926607 -182.451721)
			(xy 96.93402 -182.444898) (xy 96.95053 -182.428388) (xy 96.957926 -182.421537) (xy 96.976525 -182.413799)
			(xy 96.986598 -182.413402) (xy 98.641154 -182.413402) (xy 98.651182 -182.41299) (xy 98.669715 -182.405329)
			(xy 98.683902 -182.391155) (xy 98.691581 -182.372629) (xy 98.691954 -182.362602) (xy 98.691954 -180.48351)
			(xy 98.691954 -180.431694) (xy 97.79254 -179.53228) (xy 97.79254 -177.13198) (xy 98.165412 -176.759108)
			(xy 101.3587 -176.759108) (xy 101.722428 -176.39538) (xy 102.61092 -176.39538) (xy 102.974648 -176.759108)
			(xy 102.9843 -176.76876) (xy 103.43388 -177.218086) (xy 103.548688 -177.332894) (xy 103.555537 -177.340292)
			(xy 103.563275 -177.35889) (xy 103.563674 -177.368962) (xy 103.563674 -177.889916) (xy 103.564099 -177.899985)
			(xy 103.571815 -177.918588) (xy 103.57866 -177.925984) (xy 103.580692 -177.928016) (xy 103.588086 -177.934873)
			(xy 103.606685 -177.942623) (xy 103.61676 -177.943002) (xy 105.275634 -177.943002) (xy 105.285701 -177.942573)
			(xy 105.304297 -177.93485) (xy 105.311702 -177.928016) (xy 105.33253 -177.907188) (xy 105.339926 -177.900337)
			(xy 105.358525 -177.892599) (xy 105.368598 -177.892202) (xy 107.023916 -177.892202) (xy 107.033922 -177.891711)
			(xy 107.052408 -177.884049) (xy 107.066557 -177.869896) (xy 107.074214 -177.851408) (xy 107.074716 -177.841402)
			(xy 107.074716 -175.96231) (xy 107.074716 -175.860456) (xy 106.18724 -174.97298) (xy 106.18724 -171.002198)
			(xy 105.53573 -170.350688) (xy 105.053892 -169.86885) (xy 103.051864 -167.866822) (xy 103.045023 -167.859422)
			(xy 103.037307 -167.840823) (xy 103.036878 -167.830754) (xy 103.036878 -159.09163) (xy 102.59822 -158.652972)
			(xy 80.630268 -158.652972) (xy 79.78902 -159.49422) (xy 61.2648 -159.49422) (xy 60.3504 -160.40862)
			(xy 60.3504 -168.380664) (xy 60.66282 -168.693084) (xy 63.473838 -168.693084) (xy 63.483905 -168.692654)
			(xy 63.502498 -168.684928) (xy 63.509906 -168.678098) (xy 63.52413 -168.663874) (xy 63.531527 -168.657024)
			(xy 63.550126 -168.649289) (xy 63.560198 -168.648888) (xy 65.213992 -168.648888) (xy 65.224063 -168.648466)
			(xy 65.242668 -168.640752) (xy 65.25006 -168.633902) (xy 65.25133 -168.632632) (xy 65.258173 -168.625233)
			(xy 65.265894 -168.606634) (xy 65.266316 -168.596564) (xy 65.266316 -166.718996) (xy 65.266316 -166.650416)
			(xy 64.24168 -165.62578) (xy 64.24168 -162.90544) (xy 64.426084 -162.721036) (xy 65.520824 -162.721036)
			(xy 65.893696 -163.093654) (xy 65.901092 -163.100506) (xy 65.919691 -163.108249) (xy 65.929764 -163.10864)
			(xy 69.371464 -163.10864) (xy 69.381528 -163.109076) (xy 69.400112 -163.116811) (xy 69.407532 -163.123626)
			(xy 69.889878 -163.606226) (xy 69.889878 -166.004424) (xy 82.10067 -166.004424) (xy 82.10067 -165.919728)
			(xy 82.108721 -165.835414) (xy 82.12475 -165.752248) (xy 82.148611 -165.670981) (xy 82.18009 -165.592351)
			(xy 82.218901 -165.51707) (xy 82.264691 -165.445818) (xy 82.317047 -165.379242) (xy 82.375495 -165.317944)
			(xy 82.439505 -165.262479) (xy 82.508497 -165.21335) (xy 82.581847 -165.171001) (xy 82.65889 -165.135817)
			(xy 82.738929 -165.108115) (xy 82.821238 -165.088147) (xy 82.905073 -165.076094) (xy 82.989674 -165.072064)
			(xy 83.074275 -165.076094) (xy 83.15811 -165.088147) (xy 83.240419 -165.108115) (xy 83.320458 -165.135817)
			(xy 83.397501 -165.171001) (xy 83.470851 -165.21335) (xy 83.539843 -165.262479) (xy 83.603853 -165.317944)
			(xy 83.662301 -165.379242) (xy 83.714657 -165.445818) (xy 83.760447 -165.51707) (xy 83.799258 -165.592351)
			(xy 83.830737 -165.670981) (xy 83.854598 -165.752248) (xy 83.870627 -165.835414) (xy 83.878678 -165.919728)
			(xy 83.879182 -165.962076) (xy 83.878678 -166.004424) (xy 91.49867 -166.004424) (xy 91.49867 -165.919728)
			(xy 91.506721 -165.835414) (xy 91.52275 -165.752248) (xy 91.546611 -165.670981) (xy 91.57809 -165.592351)
			(xy 91.616901 -165.51707) (xy 91.662691 -165.445818) (xy 91.715047 -165.379242) (xy 91.773495 -165.317944)
			(xy 91.837505 -165.262479) (xy 91.906497 -165.21335) (xy 91.979847 -165.171001) (xy 92.05689 -165.135817)
			(xy 92.136929 -165.108115) (xy 92.219238 -165.088147) (xy 92.303073 -165.076094) (xy 92.387674 -165.072064)
			(xy 92.472275 -165.076094) (xy 92.55611 -165.088147) (xy 92.638419 -165.108115) (xy 92.718458 -165.135817)
			(xy 92.795501 -165.171001) (xy 92.868851 -165.21335) (xy 92.937843 -165.262479) (xy 93.001853 -165.317944)
			(xy 93.060301 -165.379242) (xy 93.112657 -165.445818) (xy 93.158447 -165.51707) (xy 93.197258 -165.592351)
			(xy 93.228737 -165.670981) (xy 93.252598 -165.752248) (xy 93.268627 -165.835414) (xy 93.276678 -165.919728)
			(xy 93.277182 -165.962076) (xy 93.276678 -166.004424) (xy 93.268627 -166.088738) (xy 93.252598 -166.171904)
			(xy 93.228737 -166.253171) (xy 93.197258 -166.331801) (xy 93.158447 -166.407082) (xy 93.112657 -166.478334)
			(xy 93.060301 -166.54491) (xy 93.001853 -166.606208) (xy 92.937843 -166.661673) (xy 92.868851 -166.710802)
			(xy 92.795501 -166.753151) (xy 92.718458 -166.788335) (xy 92.638419 -166.816037) (xy 92.55611 -166.836005)
			(xy 92.472275 -166.848058) (xy 92.387674 -166.852089) (xy 92.303073 -166.848058) (xy 92.219238 -166.836005)
			(xy 92.136929 -166.816037) (xy 92.05689 -166.788335) (xy 91.979847 -166.753151) (xy 91.906497 -166.710802)
			(xy 91.837505 -166.661673) (xy 91.773495 -166.606208) (xy 91.715047 -166.54491) (xy 91.662691 -166.478334)
			(xy 91.616901 -166.407082) (xy 91.57809 -166.331801) (xy 91.546611 -166.253171) (xy 91.52275 -166.171904)
			(xy 91.506721 -166.088738) (xy 91.49867 -166.004424) (xy 83.878678 -166.004424) (xy 83.870627 -166.088738)
			(xy 83.854598 -166.171904) (xy 83.830737 -166.253171) (xy 83.799258 -166.331801) (xy 83.760447 -166.407082)
			(xy 83.714657 -166.478334) (xy 83.662301 -166.54491) (xy 83.603853 -166.606208) (xy 83.539843 -166.661673)
			(xy 83.470851 -166.710802) (xy 83.397501 -166.753151) (xy 83.320458 -166.788335) (xy 83.240419 -166.816037)
			(xy 83.15811 -166.836005) (xy 83.074275 -166.848058) (xy 82.989674 -166.852089) (xy 82.905073 -166.848058)
			(xy 82.821238 -166.836005) (xy 82.738929 -166.816037) (xy 82.65889 -166.788335) (xy 82.581847 -166.753151)
			(xy 82.508497 -166.710802) (xy 82.439505 -166.661673) (xy 82.375495 -166.606208) (xy 82.317047 -166.54491)
			(xy 82.264691 -166.478334) (xy 82.218901 -166.407082) (xy 82.18009 -166.331801) (xy 82.148611 -166.253171)
			(xy 82.12475 -166.171904) (xy 82.108721 -166.088738) (xy 82.10067 -166.004424) (xy 69.889878 -166.004424)
			(xy 69.889878 -166.249858) (xy 70.36562 -166.7256) (xy 70.36562 -168.4655) (xy 70.326574 -168.504546)
			(xy 82.10067 -168.504546) (xy 82.10067 -168.41985) (xy 82.108721 -168.335536) (xy 82.12475 -168.25237)
			(xy 82.148611 -168.171103) (xy 82.18009 -168.092473) (xy 82.218901 -168.017192) (xy 82.264691 -167.94594)
			(xy 82.317047 -167.879364) (xy 82.375495 -167.818066) (xy 82.439505 -167.762601) (xy 82.508497 -167.713472)
			(xy 82.581847 -167.671123) (xy 82.65889 -167.635939) (xy 82.738929 -167.608237) (xy 82.821238 -167.588269)
			(xy 82.905073 -167.576216) (xy 82.989674 -167.572186) (xy 83.074275 -167.576216) (xy 83.15811 -167.588269)
			(xy 83.240419 -167.608237) (xy 83.320458 -167.635939) (xy 83.397501 -167.671123) (xy 83.470851 -167.713472)
			(xy 83.539843 -167.762601) (xy 83.603853 -167.818066) (xy 83.662301 -167.879364) (xy 83.714657 -167.94594)
			(xy 83.760447 -168.017192) (xy 83.799258 -168.092473) (xy 83.830737 -168.171103) (xy 83.854598 -168.25237)
			(xy 83.870627 -168.335536) (xy 83.878678 -168.41985) (xy 83.879182 -168.462198) (xy 83.878678 -168.504546)
			(xy 91.49867 -168.504546) (xy 91.49867 -168.41985) (xy 91.506721 -168.335536) (xy 91.52275 -168.25237)
			(xy 91.546611 -168.171103) (xy 91.57809 -168.092473) (xy 91.616901 -168.017192) (xy 91.662691 -167.94594)
			(xy 91.715047 -167.879364) (xy 91.773495 -167.818066) (xy 91.837505 -167.762601) (xy 91.906497 -167.713472)
			(xy 91.979847 -167.671123) (xy 92.05689 -167.635939) (xy 92.136929 -167.608237) (xy 92.219238 -167.588269)
			(xy 92.303073 -167.576216) (xy 92.387674 -167.572186) (xy 92.472275 -167.576216) (xy 92.55611 -167.588269)
			(xy 92.638419 -167.608237) (xy 92.718458 -167.635939) (xy 92.795501 -167.671123) (xy 92.868851 -167.713472)
			(xy 92.937843 -167.762601) (xy 93.001853 -167.818066) (xy 93.060301 -167.879364) (xy 93.112657 -167.94594)
			(xy 93.158447 -168.017192) (xy 93.197258 -168.092473) (xy 93.228737 -168.171103) (xy 93.252598 -168.25237)
			(xy 93.268627 -168.335536) (xy 93.276678 -168.41985) (xy 93.277182 -168.462198) (xy 93.276678 -168.504546)
			(xy 93.268627 -168.58886) (xy 93.252598 -168.672026) (xy 93.228737 -168.753293) (xy 93.197258 -168.831923)
			(xy 93.158447 -168.907204) (xy 93.112657 -168.978456) (xy 93.060301 -169.045032) (xy 93.001853 -169.10633)
			(xy 92.937843 -169.161795) (xy 92.868851 -169.210924) (xy 92.795501 -169.253273) (xy 92.718458 -169.288457)
			(xy 92.638419 -169.316159) (xy 92.55611 -169.336127) (xy 92.472275 -169.34818) (xy 92.387674 -169.352211)
			(xy 92.303073 -169.34818) (xy 92.219238 -169.336127) (xy 92.136929 -169.316159) (xy 92.05689 -169.288457)
			(xy 91.979847 -169.253273) (xy 91.906497 -169.210924) (xy 91.837505 -169.161795) (xy 91.773495 -169.10633)
			(xy 91.715047 -169.045032) (xy 91.662691 -168.978456) (xy 91.616901 -168.907204) (xy 91.57809 -168.831923)
			(xy 91.546611 -168.753293) (xy 91.52275 -168.672026) (xy 91.506721 -168.58886) (xy 91.49867 -168.504546)
			(xy 83.878678 -168.504546) (xy 83.870627 -168.58886) (xy 83.854598 -168.672026) (xy 83.830737 -168.753293)
			(xy 83.799258 -168.831923) (xy 83.760447 -168.907204) (xy 83.714657 -168.978456) (xy 83.662301 -169.045032)
			(xy 83.603853 -169.10633) (xy 83.539843 -169.161795) (xy 83.470851 -169.210924) (xy 83.397501 -169.253273)
			(xy 83.320458 -169.288457) (xy 83.240419 -169.316159) (xy 83.15811 -169.336127) (xy 83.074275 -169.34818)
			(xy 82.989674 -169.352211) (xy 82.905073 -169.34818) (xy 82.821238 -169.336127) (xy 82.738929 -169.316159)
			(xy 82.65889 -169.288457) (xy 82.581847 -169.253273) (xy 82.508497 -169.210924) (xy 82.439505 -169.161795)
			(xy 82.375495 -169.10633) (xy 82.317047 -169.045032) (xy 82.264691 -168.978456) (xy 82.218901 -168.907204)
			(xy 82.18009 -168.831923) (xy 82.148611 -168.753293) (xy 82.12475 -168.672026) (xy 82.108721 -168.58886)
			(xy 82.10067 -168.504546) (xy 70.326574 -168.504546) (xy 69.889878 -168.941242) (xy 69.889878 -177.206402)
			(xy 69.890301 -177.216473) (xy 69.898013 -177.235079) (xy 69.904864 -177.24247) (xy 70.027292 -177.364898)
			(xy 70.034404 -177.372264) (xy 70.0532 -177.379884) (xy 71.797672 -177.379884) (xy 71.807736 -177.379447)
			(xy 71.82632 -177.371713) (xy 71.83374 -177.364898) (xy 71.83755 -177.361088) (xy 71.844947 -177.35424)
			(xy 71.863546 -177.34651) (xy 71.873618 -177.346102) (xy 73.528936 -177.346102) (xy 73.538939 -177.345608)
			(xy 73.557419 -177.337942) (xy 73.571561 -177.32379) (xy 73.579214 -177.305305) (xy 73.579736 -177.295302)
			(xy 73.579736 -175.41621) (xy 73.579736 -175.357536) (xy 72.7075 -174.4853) (xy 72.7075 -170.9039)
			(xy 72.888602 -170.722798) (xy 73.440798 -170.722798) (xy 73.450868 -170.723221) (xy 73.469473 -170.730934)
			(xy 73.476866 -170.737784) (xy 74.373486 -171.634404) (xy 74.380889 -171.641236) (xy 74.399488 -171.648939)
			(xy 74.409554 -171.64939) (xy 77.587094 -171.64939) (xy 77.597165 -171.649812) (xy 77.615772 -171.657523)
			(xy 77.623162 -171.664376) (xy 78.256892 -172.298106) (xy 78.263738 -172.305505) (xy 78.271472 -172.324103)
			(xy 78.271878 -172.334174) (xy 78.271878 -174.97552) (xy 78.73746 -175.441102) (xy 78.73746 -176.933098)
			(xy 78.271878 -177.39868) (xy 78.271878 -179.105814) (xy 78.271878 -181.713886) (xy 78.271878 -182.388002)
			(xy 78.272301 -182.398073) (xy 78.280013 -182.416679) (xy 78.286864 -182.42407) (xy 78.36281 -182.500016)
			(xy 78.369922 -182.507382) (xy 78.388718 -182.515002)
		)
		(stroke
			(width 0)
			(type solid)
		)
		(fill yes)
		(layer "In13.Cu")
		(net "SW_P12V_AUX_PVDDCR_CPU0_P1_FLT")
	)
	(gr_poly
		(pts
			(arc
				(start 194.446144 -441.481972)
				(mid 194.482065 -441.467093)
				(end 194.496944 -441.431172)
			)
			(arc
				(start 194.496944 -441.17006)
				(mid 194.792217 -440.457207)
				(end 195.50507 -440.161934)
			)
			(arc
				(start 276.314916 -440.161934)
				(mid 277.027769 -440.457207)
				(end 277.323042 -441.17006)
			)
			(arc
				(start 277.323042 -441.431172)
				(mid 277.337921 -441.467093)
				(end 277.373842 -441.481972)
			)
			(arc
				(start 463.300064 -441.481972)
				(mid 464.355064 -441.044976)
				(end 464.79206 -439.989976)
			)
			(arc
				(start 464.79206 -409.528264)
				(mid 464.983018 -408.568632)
				(end 465.526628 -407.75509)
			)
			(arc
				(start 467.355174 -405.926544)
				(mid 467.678507 -405.442687)
				(end 467.792054 -404.871936)
			)
			(xy 467.792054 -364.162594) (xy 467.7537 -364.12424) (xy 467.665816 -364.12424) (xy 467.284816 -364.50524)
			(arc
				(start 467.284816 -404.871936)
				(mid 467.209909 -405.248606)
				(end 466.996526 -405.567896)
			)
			(arc
				(start 465.16798 -407.396442)
				(mid 464.51433 -408.374514)
				(end 464.284568 -409.528264)
			)
			(arc
				(start 464.284568 -439.989976)
				(mid 463.996213 -440.686125)
				(end 463.300064 -440.97448)
			)
			(xy 410.91104 -440.97448)
			(arc
				(start 410.90342 -440.976766)
				(mid 410.82774 -440.99441)
				(end 410.750258 -441.000388)
			)
			(arc
				(start 410.74975 -441.000388)
				(mid 410.672265 -440.994435)
				(end 410.596588 -440.976766)
			)
			(xy 410.588968 -440.97448) (xy 406.911048 -440.97448)
			(arc
				(start 406.903428 -440.976766)
				(mid 406.827748 -440.99441)
				(end 406.750266 -441.000388)
			)
			(arc
				(start 406.749758 -441.000388)
				(mid 406.672273 -440.994435)
				(end 406.596596 -440.976766)
			)
			(xy 406.588976 -440.97448) (xy 402.911056 -440.97448)
			(arc
				(start 402.903436 -440.976766)
				(mid 402.827756 -440.99441)
				(end 402.750274 -441.000388)
			)
			(arc
				(start 402.749766 -441.000388)
				(mid 402.672281 -440.994435)
				(end 402.596604 -440.976766)
			)
			(xy 402.588984 -440.97448) (xy 398.911064 -440.97448)
			(arc
				(start 398.903444 -440.976766)
				(mid 398.827764 -440.99441)
				(end 398.750282 -441.000388)
			)
			(arc
				(start 398.749774 -441.000388)
				(mid 398.672289 -440.994435)
				(end 398.596612 -440.976766)
			)
			(xy 398.588992 -440.97448) (xy 393.91082 -440.97448)
			(arc
				(start 393.9032 -440.976766)
				(mid 393.82752 -440.99441)
				(end 393.750038 -441.000388)
			)
			(arc
				(start 393.74953 -441.000388)
				(mid 393.672045 -440.994435)
				(end 393.596368 -440.976766)
			)
			(xy 393.588748 -440.97448) (xy 389.910828 -440.97448)
			(arc
				(start 389.903208 -440.976766)
				(mid 389.827528 -440.99441)
				(end 389.750046 -441.000388)
			)
			(arc
				(start 389.749538 -441.000388)
				(mid 389.672053 -440.994435)
				(end 389.596376 -440.976766)
			)
			(xy 389.588756 -440.97448) (xy 385.910836 -440.97448)
			(arc
				(start 385.903216 -440.976766)
				(mid 385.827536 -440.99441)
				(end 385.750054 -441.000388)
			)
			(arc
				(start 385.749546 -441.000388)
				(mid 385.672061 -440.994435)
				(end 385.596384 -440.976766)
			)
			(xy 385.588764 -440.97448) (xy 381.910844 -440.97448)
			(arc
				(start 381.903224 -440.976766)
				(mid 381.827544 -440.99441)
				(end 381.750062 -441.000388)
			)
			(arc
				(start 381.749554 -441.000388)
				(mid 381.672069 -440.994435)
				(end 381.596392 -440.976766)
			)
			(xy 381.588772 -440.97448) (xy 343.810844 -440.97448)
			(arc
				(start 343.803224 -440.976766)
				(mid 343.727544 -440.99441)
				(end 343.650062 -441.000388)
			)
			(arc
				(start 343.649554 -441.000388)
				(mid 343.572069 -440.994435)
				(end 343.496392 -440.976766)
			)
			(xy 343.488772 -440.97448) (xy 339.810852 -440.97448)
			(arc
				(start 339.803232 -440.976766)
				(mid 339.727552 -440.99441)
				(end 339.65007 -441.000388)
			)
			(arc
				(start 339.649562 -441.000388)
				(mid 339.572077 -440.994435)
				(end 339.4964 -440.976766)
			)
			(xy 339.48878 -440.97448) (xy 335.81086 -440.97448)
			(arc
				(start 335.80324 -440.976766)
				(mid 335.72756 -440.99441)
				(end 335.650078 -441.000388)
			)
			(arc
				(start 335.64957 -441.000388)
				(mid 335.572085 -440.994435)
				(end 335.496408 -440.976766)
			)
			(xy 335.488788 -440.97448) (xy 331.810868 -440.97448)
			(arc
				(start 331.803248 -440.976766)
				(mid 331.727568 -440.99441)
				(end 331.650086 -441.000388)
			)
			(arc
				(start 331.649578 -441.000388)
				(mid 331.572093 -440.994435)
				(end 331.496416 -440.976766)
			)
			(xy 331.488796 -440.97448) (xy 326.810878 -440.97448)
			(arc
				(start 326.803258 -440.976766)
				(mid 326.727578 -440.99441)
				(end 326.650096 -441.000388)
			)
			(arc
				(start 326.649588 -441.000388)
				(mid 326.572103 -440.994435)
				(end 326.496426 -440.976766)
			)
			(xy 326.488806 -440.97448) (xy 322.810886 -440.97448)
			(arc
				(start 322.803266 -440.976766)
				(mid 322.727586 -440.99441)
				(end 322.650104 -441.000388)
			)
			(arc
				(start 322.649596 -441.000388)
				(mid 322.572111 -440.994435)
				(end 322.496434 -440.976766)
			)
			(xy 322.488814 -440.97448) (xy 318.810894 -440.97448)
			(arc
				(start 318.803274 -440.976766)
				(mid 318.727594 -440.99441)
				(end 318.650112 -441.000388)
			)
			(arc
				(start 318.649604 -441.000388)
				(mid 318.572119 -440.994435)
				(end 318.496442 -440.976766)
			)
			(xy 318.488822 -440.97448) (xy 314.810902 -440.97448)
			(arc
				(start 314.803282 -440.976766)
				(mid 314.727602 -440.99441)
				(end 314.65012 -441.000388)
			)
			(arc
				(start 314.649612 -441.000388)
				(mid 314.572127 -440.994435)
				(end 314.49645 -440.976766)
			)
			(xy 314.48883 -440.97448)
			(arc
				(start 277.817834 -440.97448)
				(mid 277.314992 -440.031472)
				(end 276.314916 -439.654696)
			)
			(arc
				(start 195.50507 -439.654696)
				(mid 194.504998 -440.031475)
				(end 194.002152 -440.97448)
			)
			(xy 154.911044 -440.97448)
			(arc
				(start 154.903424 -440.976766)
				(mid 154.827744 -440.99441)
				(end 154.750262 -441.000388)
			)
			(arc
				(start 154.749754 -441.000388)
				(mid 154.672269 -440.994435)
				(end 154.596592 -440.976766)
			)
			(xy 154.588972 -440.97448) (xy 150.911052 -440.97448)
			(arc
				(start 150.903432 -440.976766)
				(mid 150.827752 -440.99441)
				(end 150.75027 -441.000388)
			)
			(arc
				(start 150.749762 -441.000388)
				(mid 150.672277 -440.994435)
				(end 150.5966 -440.976766)
			)
			(xy 150.58898 -440.97448) (xy 146.91106 -440.97448)
			(arc
				(start 146.90344 -440.976766)
				(mid 146.82776 -440.99441)
				(end 146.750278 -441.000388)
			)
			(arc
				(start 146.74977 -441.000388)
				(mid 146.672285 -440.994435)
				(end 146.596608 -440.976766)
			)
			(xy 146.588988 -440.97448) (xy 142.911068 -440.97448)
			(arc
				(start 142.903448 -440.976766)
				(mid 142.827768 -440.99441)
				(end 142.750286 -441.000388)
			)
			(arc
				(start 142.749778 -441.000388)
				(mid 142.672293 -440.994435)
				(end 142.596616 -440.976766)
			)
			(xy 142.588996 -440.97448) (xy 137.910824 -440.97448)
			(arc
				(start 137.903204 -440.976766)
				(mid 137.827524 -440.99441)
				(end 137.750042 -441.000388)
			)
			(arc
				(start 137.749534 -441.000388)
				(mid 137.672049 -440.994435)
				(end 137.596372 -440.976766)
			)
			(xy 137.588752 -440.97448) (xy 133.910832 -440.97448)
			(arc
				(start 133.903212 -440.976766)
				(mid 133.827532 -440.99441)
				(end 133.75005 -441.000388)
			)
			(arc
				(start 133.749542 -441.000388)
				(mid 133.672057 -440.994435)
				(end 133.59638 -440.976766)
			)
			(xy 133.58876 -440.97448) (xy 129.91084 -440.97448)
			(arc
				(start 129.90322 -440.976766)
				(mid 129.82754 -440.99441)
				(end 129.750058 -441.000388)
			)
			(arc
				(start 129.74955 -441.000388)
				(mid 129.672065 -440.994435)
				(end 129.596388 -440.976766)
			)
			(xy 129.588768 -440.97448) (xy 125.910848 -440.97448)
			(arc
				(start 125.903228 -440.976766)
				(mid 125.827548 -440.99441)
				(end 125.750066 -441.000388)
			)
			(arc
				(start 125.749558 -441.000388)
				(mid 125.672073 -440.994435)
				(end 125.596396 -440.976766)
			)
			(xy 125.588776 -440.97448) (xy 87.811102 -440.97448)
			(arc
				(start 87.803482 -440.976766)
				(mid 87.727802 -440.99441)
				(end 87.65032 -441.000388)
			)
			(arc
				(start 87.649812 -441.000388)
				(mid 87.572327 -440.994435)
				(end 87.49665 -440.976766)
			)
			(xy 87.48903 -440.97448) (xy 83.81111 -440.97448)
			(arc
				(start 83.80349 -440.976766)
				(mid 83.72781 -440.99441)
				(end 83.650328 -441.000388)
			)
			(arc
				(start 83.64982 -441.000388)
				(mid 83.572335 -440.994435)
				(end 83.496658 -440.976766)
			)
			(xy 83.489038 -440.97448) (xy 79.811118 -440.97448)
			(arc
				(start 79.803498 -440.976766)
				(mid 79.727818 -440.99441)
				(end 79.650336 -441.000388)
			)
			(arc
				(start 79.649828 -441.000388)
				(mid 79.572343 -440.994435)
				(end 79.496666 -440.976766)
			)
			(xy 79.489046 -440.97448) (xy 75.811126 -440.97448)
			(arc
				(start 75.803506 -440.976766)
				(mid 75.727826 -440.99441)
				(end 75.650344 -441.000388)
			)
			(arc
				(start 75.649836 -441.000388)
				(mid 75.572351 -440.994435)
				(end 75.496674 -440.976766)
			)
			(xy 75.489054 -440.97448) (xy 70.810882 -440.97448)
			(arc
				(start 70.803262 -440.976766)
				(mid 70.727582 -440.99441)
				(end 70.6501 -441.000388)
			)
			(arc
				(start 70.649592 -441.000388)
				(mid 70.572107 -440.994435)
				(end 70.49643 -440.976766)
			)
			(xy 70.48881 -440.97448) (xy 66.81089 -440.97448)
			(arc
				(start 66.80327 -440.976766)
				(mid 66.72759 -440.99441)
				(end 66.650108 -441.000388)
			)
			(arc
				(start 66.6496 -441.000388)
				(mid 66.572115 -440.994435)
				(end 66.496438 -440.976766)
			)
			(xy 66.488818 -440.97448) (xy 62.810898 -440.97448)
			(arc
				(start 62.803278 -440.976766)
				(mid 62.727598 -440.99441)
				(end 62.650116 -441.000388)
			)
			(arc
				(start 62.649608 -441.000388)
				(mid 62.572123 -440.994435)
				(end 62.496446 -440.976766)
			)
			(xy 62.488826 -440.97448) (xy 58.810906 -440.97448)
			(arc
				(start 58.803286 -440.976766)
				(mid 58.727606 -440.99441)
				(end 58.650124 -441.000388)
			)
			(arc
				(start 58.649616 -441.000388)
				(mid 58.572131 -440.994435)
				(end 58.496454 -440.976766)
			)
			(xy 58.488834 -440.97448)
			(arc
				(start 8.50011 -440.97448)
				(mid 7.803871 -440.686141)
				(end 7.515352 -439.989976)
			)
			(arc
				(start 7.515352 -409.528518)
				(mid 7.285694 -408.374511)
				(end 6.63194 -407.396188)
			)
			(arc
				(start 3.303778 -404.068026)
				(mid 3.090447 -403.748703)
				(end 3.015488 -403.372066)
			)
			(xy 3.015488 -364.592108) (xy 2.67462 -364.25124) (xy 2.558796 -364.25124) (xy 2.507996 -364.30204)
			(arc
				(start 2.507996 -403.371812)
				(mid 2.621533 -403.942691)
				(end 2.944876 -404.426674)
			)
			(arc
				(start 6.273292 -407.75509)
				(mid 6.817042 -408.568731)
				(end 7.008114 -409.528518)
			)
			(arc
				(start 7.008114 -439.989976)
				(mid 7.44511 -441.044976)
				(end 8.50011 -441.481972)
			)
		)
		(stroke
			(width 0)
			(type solid)
		)
		(fill yes)
		(layer "In13.Cu")
		(net "GND")
	)
	(gr_poly
		(pts
			(xy 123.556014 -57.2516) (xy 123.560288 -57.251544) (xy 123.568719 -57.250145) (xy 123.572778 -57.248806)
			(xy 123.596146 -57.240424) (xy 123.602496 -57.235598) (xy 123.624869 -57.21901) (xy 123.673466 -57.191805)
			(xy 123.725501 -57.17195) (xy 123.779868 -57.159865) (xy 123.835414 -57.155809) (xy 123.89096 -57.159865)
			(xy 123.945327 -57.17195) (xy 123.997362 -57.191805) (xy 124.045959 -57.21901) (xy 124.068332 -57.235598)
			(xy 124.074682 -57.240424) (xy 124.09805 -57.248806) (xy 124.102119 -57.250108) (xy 124.110543 -57.251518)
			(xy 124.114814 -57.2516) (xy 124.367036 -57.2516) (xy 124.393198 -57.233566) (xy 124.398786 -57.21858)
			(xy 124.410641 -57.188323) (xy 124.440955 -57.130843) (xy 124.478342 -57.077691) (xy 124.522194 -57.029734)
			(xy 124.571797 -56.987752) (xy 124.626343 -56.95243) (xy 124.684943 -56.924342) (xy 124.746643 -56.903945)
			(xy 124.810438 -56.891573) (xy 124.87529 -56.887427) (xy 124.940142 -56.891573) (xy 125.003937 -56.903945)
			(xy 125.065637 -56.924342) (xy 125.124237 -56.95243) (xy 125.178783 -56.987752) (xy 125.228386 -57.029734)
			(xy 125.272238 -57.077691) (xy 125.309625 -57.130843) (xy 125.339939 -57.188323) (xy 125.351794 -57.21858)
			(xy 125.357382 -57.233566) (xy 125.383544 -57.2516) (xy 126.585472 -57.2516) (xy 126.595256 -57.251148)
			(xy 126.613402 -57.243822) (xy 126.620778 -57.237376) (xy 126.67869 -57.18175) (xy 126.686818 -57.16397)
			(xy 126.687072 -57.15381) (xy 126.687994 -57.134956) (xy 126.693083 -57.097549) (xy 126.697232 -57.079134)
			(xy 126.697994 -57.07634) (xy 126.698756 -57.069736) (xy 126.699356 -57.06235) (xy 126.696775 -57.047765)
			(xy 126.693676 -57.041034) (xy 126.680468 -57.01411) (xy 126.678665 -57.010777) (xy 126.674205 -57.004649)
			(xy 126.671578 -57.001918) (xy 126.667742 -56.998063) (xy 126.658779 -56.991907) (xy 126.653798 -56.989726)
			(xy 126.622754 -56.976735) (xy 126.564101 -56.943738) (xy 126.510313 -56.903294) (xy 126.46233 -56.856109)
			(xy 126.42099 -56.803006) (xy 126.387014 -56.744915) (xy 126.360998 -56.682851) (xy 126.343395 -56.617897)
			(xy 126.334514 -56.551188) (xy 126.334012 -56.51754) (xy 126.334455 -56.486807) (xy 126.34186 -56.425788)
			(xy 126.356566 -56.366107) (xy 126.37836 -56.308634) (xy 126.406922 -56.254207) (xy 126.441837 -56.203619)
			(xy 126.482596 -56.15761) (xy 126.528604 -56.11685) (xy 126.579189 -56.081933) (xy 126.633615 -56.053368)
			(xy 126.691088 -56.031572) (xy 126.750768 -56.016864) (xy 126.811787 -56.009457) (xy 126.84252 -56.009032)
			(xy 126.87325 -56.009479) (xy 126.934263 -56.01689) (xy 126.993937 -56.031601) (xy 127.051403 -56.053398)
			(xy 127.105823 -56.081963) (xy 127.156402 -56.11688) (xy 127.202404 -56.157639) (xy 127.243157 -56.203645)
			(xy 127.278068 -56.254229) (xy 127.306627 -56.308652) (xy 127.328417 -56.36612) (xy 127.343121 -56.425796)
			(xy 127.350525 -56.486809) (xy 127.351028 -56.51754) (xy 127.350458 -56.550696) (xy 127.341772 -56.616437)
			(xy 127.324618 -56.680492) (xy 127.299286 -56.741775) (xy 127.28321 -56.770778) (xy 127.278973 -56.779057)
			(xy 127.276106 -56.797417) (xy 127.277622 -56.806592) (xy 127.28194 -56.827674) (xy 127.282956 -56.832028)
			(xy 127.28628 -56.840328) (xy 127.288544 -56.844184) (xy 127.302006 -56.866282) (xy 127.308864 -56.871616)
			(xy 127.329606 -56.889068) (xy 127.36643 -56.928848) (xy 127.397249 -56.973442) (xy 127.421444 -57.02195)
			(xy 127.438525 -57.073395) (xy 127.448151 -57.126741) (xy 127.44958 -57.15381) (xy 127.449834 -57.16397)
			(xy 127.457962 -57.18175) (xy 127.515874 -57.237376) (xy 127.523228 -57.24385) (xy 127.541391 -57.25115)
			(xy 127.55118 -57.2516) (xy 129.354326 -57.2516) (xy 129.364572 -57.251136) (xy 129.383443 -57.243145)
			(xy 129.390902 -57.236106) (xy 129.449068 -57.175908) (xy 129.456434 -57.156858) (xy 129.455926 -57.146444)
			(xy 129.455672 -57.13222) (xy 129.456131 -57.10544) (xy 129.463641 -57.05241) (xy 129.478501 -57.000953)
			(xy 129.500419 -56.952084) (xy 129.528963 -56.906764) (xy 129.563571 -56.865887) (xy 129.60356 -56.830258)
			(xy 129.648145 -56.800579) (xy 129.67208 -56.788558) (xy 129.672334 -56.788304) (xy 129.672842 -56.78805)
			(xy 129.678473 -56.785045) (xy 129.688109 -56.776681) (xy 129.691892 -56.77154) (xy 129.692146 -56.771286)
			(xy 129.695847 -56.765552) (xy 129.700358 -56.752677) (xy 129.701036 -56.745886) (xy 129.708148 -56.644286)
			(xy 129.69621 -56.619902) (xy 129.68478 -56.612282) (xy 129.6592 -56.594581) (xy 129.612127 -56.553912)
			(xy 129.570366 -56.507806) (xy 129.534539 -56.456951) (xy 129.505182 -56.402106) (xy 129.493518 -56.373268)
			(xy 129.4892 -56.362092) (xy 129.471674 -56.34609) (xy 129.382266 -56.320436) (xy 129.37087 -56.317723)
			(xy 129.347838 -56.321841) (xy 129.33807 -56.32831) (xy 129.337816 -56.328564) (xy 129.311301 -56.347868)
			(xy 129.254249 -56.380224) (xy 129.19351 -56.404972) (xy 129.130091 -56.4217) (xy 129.065048 -56.430132)
			(xy 129.032254 -56.430672) (xy 129.000297 -56.430167) (xy 128.936888 -56.422152) (xy 128.874983 -56.406252)
			(xy 128.815559 -56.38272) (xy 128.759553 -56.351926) (xy 128.707848 -56.314355) (xy 128.661258 -56.270601)
			(xy 128.62052 -56.221353) (xy 128.586275 -56.167387) (xy 128.559063 -56.109556) (xy 128.539314 -56.04877)
			(xy 128.527338 -55.985988) (xy 128.523325 -55.9222) (xy 128.527338 -55.858412) (xy 128.539314 -55.79563)
			(xy 128.559063 -55.734844) (xy 128.586275 -55.677013) (xy 128.62052 -55.623047) (xy 128.661258 -55.573799)
			(xy 128.707848 -55.530045) (xy 128.759553 -55.492474) (xy 128.815559 -55.46168) (xy 128.874983 -55.438148)
			(xy 128.936888 -55.422248) (xy 129.000297 -55.414233) (xy 129.032254 -55.413656) (xy 129.062806 -55.414112)
			(xy 129.12347 -55.421441) (xy 129.182819 -55.435986) (xy 129.239997 -55.457538) (xy 129.294181 -55.485787)
			(xy 129.344589 -55.520325) (xy 129.390495 -55.560654) (xy 129.431237 -55.606194) (xy 129.466229 -55.656288)
			(xy 129.494966 -55.710214) (xy 129.506472 -55.738522) (xy 129.51079 -55.749698) (xy 129.528316 -55.7657)
			(xy 129.617724 -55.791354) (xy 129.62912 -55.79407) (xy 129.652155 -55.789955) (xy 129.66192 -55.78348)
			(xy 129.662174 -55.783226) (xy 129.688689 -55.763922) (xy 129.745741 -55.731566) (xy 129.80648 -55.706817)
			(xy 129.869898 -55.690087) (xy 129.934942 -55.681655) (xy 129.967736 -55.681118) (xy 130.000656 -55.681634)
			(xy 130.065946 -55.690128) (xy 130.129592 -55.70698) (xy 130.19053 -55.73191) (xy 130.247739 -55.7645)
			(xy 130.30026 -55.804204) (xy 130.324098 -55.826914) (xy 130.324352 -55.827168) (xy 130.330577 -55.832859)
			(xy 130.345798 -55.840106) (xy 130.362552 -55.841967) (xy 130.370834 -55.840376) (xy 130.453892 -55.82158)
			(xy 130.46617 -55.818076) (xy 130.485352 -55.801275) (xy 130.490468 -55.789576) (xy 130.501069 -55.762562)
			(xy 130.529258 -55.71184) (xy 130.564799 -55.665968) (xy 130.606872 -55.626003) (xy 130.654508 -55.592865)
			(xy 130.706611 -55.567318) (xy 130.76198 -55.549951) (xy 130.81934 -55.541162) (xy 130.848354 -55.540656)
			(xy 130.875612 -55.541116) (xy 130.929573 -55.548868) (xy 130.981881 -55.564222) (xy 131.031472 -55.586864)
			(xy 131.077335 -55.616333) (xy 131.118537 -55.65203) (xy 131.154239 -55.693228) (xy 131.183714 -55.739088)
			(xy 131.206362 -55.788676) (xy 131.221722 -55.840982) (xy 131.229481 -55.894942) (xy 131.229481 -55.949458)
			(xy 131.221722 -56.003418) (xy 131.206362 -56.055724) (xy 131.183714 -56.105312) (xy 131.154239 -56.151172)
			(xy 131.118537 -56.19237) (xy 131.077335 -56.228067) (xy 131.031472 -56.257536) (xy 130.981881 -56.280178)
			(xy 130.929573 -56.295532) (xy 130.875612 -56.303284) (xy 130.848354 -56.303672) (xy 130.8481 -56.303672)
			(xy 130.818228 -56.303098) (xy 130.759215 -56.293791) (xy 130.702377 -56.275388) (xy 130.649108 -56.248341)
			(xy 130.62458 -56.231282) (xy 130.613912 -56.223662) (xy 130.588766 -56.22036) (xy 130.497072 -56.25592)
			(xy 130.489313 -56.259186) (xy 130.476377 -56.269946) (xy 130.467664 -56.28434) (xy 130.465576 -56.292496)
			(xy 130.465576 -56.293004) (xy 130.465576 -56.293258) (xy 130.458247 -56.32586) (xy 130.436177 -56.388932)
			(xy 130.406042 -56.448573) (xy 130.368359 -56.503756) (xy 130.323778 -56.553533) (xy 130.273065 -56.597046)
			(xy 130.217094 -56.633547) (xy 130.156826 -56.662409) (xy 130.125216 -56.673242) (xy 130.112008 -56.67756)
			(xy 130.093974 -56.69788) (xy 130.070352 -56.81091) (xy 130.078988 -56.836818) (xy 130.089402 -56.845962)
			(xy 130.109343 -56.864155) (xy 130.144409 -56.905192) (xy 130.17334 -56.950763) (xy 130.195559 -56.999956)
			(xy 130.210622 -57.051791) (xy 130.218228 -57.105231) (xy 130.218688 -57.13222) (xy 130.218434 -57.146444)
			(xy 130.217926 -57.156858) (xy 130.225292 -57.175908) (xy 130.283458 -57.236106) (xy 130.290909 -57.24316)
			(xy 130.309784 -57.251156) (xy 130.320034 -57.2516) (xy 133.506718 -57.2516) (xy 133.516787 -57.251173)
			(xy 133.535386 -57.243454) (xy 133.542786 -57.236614) (xy 135.900414 -54.878986) (xy 135.907809 -54.872132)
			(xy 135.926408 -54.86439) (xy 135.936482 -54.864) (xy 137.156698 -54.864) (xy 137.16508 -54.860952)
			(xy 137.192664 -54.851505) (xy 137.249448 -54.838264) (xy 137.307376 -54.831619) (xy 137.33653 -54.831234)
			(xy 137.365682 -54.831642) (xy 137.423605 -54.838305) (xy 137.48039 -54.851529) (xy 137.50798 -54.860952)
			(xy 137.516362 -54.864) (xy 143.361918 -54.864) (xy 143.371987 -54.864427) (xy 143.390586 -54.872146)
			(xy 143.397986 -54.878986) (xy 144.369282 -55.850282) (xy 144.377954 -55.858114) (xy 144.400048 -55.86565)
			(xy 144.4117 -55.86476) (xy 144.42757 -55.862861) (xy 144.459471 -55.860826) (xy 144.475454 -55.860696)
			(xy 144.476216 -55.860696) (xy 144.508335 -55.861194) (xy 144.572058 -55.869299) (xy 144.634254 -55.885365)
			(xy 144.693931 -55.909136) (xy 144.750139 -55.940234) (xy 144.801983 -55.978164) (xy 144.848637 -56.022321)
			(xy 144.889358 -56.072002) (xy 144.923498 -56.126416) (xy 144.93748 -56.155336) (xy 144.941507 -56.163207)
			(xy 144.953911 -56.175786) (xy 144.969867 -56.183367) (xy 144.978628 -56.184546) (xy 144.983708 -56.1848)
			(xy 145.470118 -56.1848) (xy 145.480187 -56.184373) (xy 145.498786 -56.176654) (xy 145.506186 -56.169814)
			(xy 145.730214 -55.945786) (xy 145.737068 -55.938391) (xy 145.74481 -55.919792) (xy 145.7452 -55.909718)
			(xy 145.7452 -54.304184) (xy 145.722086 -54.276244) (xy 145.703798 -54.272942) (xy 145.676486 -54.267358)
			(xy 145.62374 -54.249322) (xy 145.57418 -54.223802) (xy 145.528861 -54.191341) (xy 145.488748 -54.152632)
			(xy 145.454695 -54.108497) (xy 145.427428 -54.059877) (xy 145.407525 -54.007806) (xy 145.395412 -53.953393)
			(xy 145.391345 -53.897797) (xy 145.395413 -53.842201) (xy 145.407527 -53.787788) (xy 145.42743 -53.735718)
			(xy 145.454699 -53.687098) (xy 145.488752 -53.642964) (xy 145.528866 -53.604255) (xy 145.574185 -53.571795)
			(xy 145.623745 -53.546276) (xy 145.676492 -53.52824) (xy 145.703798 -53.522626) (xy 145.722086 -53.519324)
			(xy 145.7452 -53.491384) (xy 145.7452 -52.929282) (xy 145.744773 -52.919213) (xy 145.737054 -52.900614)
			(xy 145.730214 -52.893214) (xy 145.302986 -52.465986) (xy 145.295874 -52.45862) (xy 145.277078 -52.451)
			(xy 132.436616 -52.451) (xy 132.424768 -52.451616) (xy 132.403572 -52.462207) (xy 132.395976 -52.47132)
			(xy 132.347208 -52.536344) (xy 132.340612 -52.546129) (xy 132.336364 -52.569311) (xy 132.33908 -52.580794)
			(xy 132.33908 -52.581048) (xy 132.33908 -52.581302) (xy 132.346292 -52.607512) (xy 132.354071 -52.661311)
			(xy 132.354574 -52.68849) (xy 132.354111 -52.715742) (xy 132.346355 -52.769693) (xy 132.331 -52.82199)
			(xy 132.308357 -52.871569) (xy 132.278889 -52.917421) (xy 132.243195 -52.958612) (xy 132.202002 -52.994304)
			(xy 132.156148 -53.023769) (xy 132.106567 -53.046408) (xy 132.054269 -53.06176) (xy 132.000318 -53.069513)
			(xy 131.973066 -53.069998) (xy 131.945817 -53.069509) (xy 131.891873 -53.061749) (xy 131.839583 -53.046391)
			(xy 131.790011 -53.023748) (xy 131.744166 -52.99428) (xy 131.70298 -52.958589) (xy 131.667293 -52.917399)
			(xy 131.637831 -52.87155) (xy 131.615194 -52.821976) (xy 131.599842 -52.769684) (xy 131.592087 -52.715739)
			(xy 131.591558 -52.68849) (xy 131.592078 -52.661312) (xy 131.599856 -52.607515) (xy 131.607052 -52.581302)
			(xy 131.607052 -52.581048) (xy 131.607052 -52.580794) (xy 131.609709 -52.569308) (xy 131.605479 -52.546142)
			(xy 131.598924 -52.536344) (xy 131.550156 -52.47132) (xy 131.542554 -52.462212) (xy 131.521363 -52.45161)
			(xy 131.509516 -52.451) (xy 130.602228 -52.451) (xy 130.57378 -52.475892) (xy 130.57124 -52.494942)
			(xy 130.566488 -52.526351) (xy 130.550179 -52.587747) (xy 130.526351 -52.646633) (xy 130.495373 -52.702093)
			(xy 130.45773 -52.753264) (xy 130.414007 -52.799347) (xy 130.364884 -52.839626) (xy 130.311127 -52.873473)
			(xy 130.253574 -52.900362) (xy 130.193119 -52.919872) (xy 130.130705 -52.931702) (xy 130.067304 -52.935665)
			(xy 130.003903 -52.931702) (xy 129.941489 -52.919872) (xy 129.881034 -52.900362) (xy 129.823481 -52.873473)
			(xy 129.769724 -52.839626) (xy 129.720601 -52.799347) (xy 129.676878 -52.753264) (xy 129.639235 -52.702093)
			(xy 129.608257 -52.646633) (xy 129.584429 -52.587747) (xy 129.56812 -52.526351) (xy 129.563368 -52.494942)
			(xy 129.560828 -52.475892) (xy 129.53238 -52.451) (xy 126.559564 -52.451) (xy 126.55055 -52.451366)
			(xy 126.533642 -52.457622) (xy 126.526544 -52.463192) (xy 126.501314 -52.484217) (xy 126.446422 -52.520278)
			(xy 126.387344 -52.548968) (xy 126.325062 -52.56981) (xy 126.260614 -52.582455) (xy 126.195074 -52.586694)
			(xy 126.129534 -52.582455) (xy 126.065086 -52.56981) (xy 126.002804 -52.548968) (xy 125.943726 -52.520278)
			(xy 125.888834 -52.484217) (xy 125.863604 -52.463192) (xy 125.856517 -52.457607) (xy 125.8396 -52.451365)
			(xy 125.830584 -52.451) (xy 122.144282 -52.451) (xy 122.134213 -52.451427) (xy 122.115614 -52.459146)
			(xy 122.108214 -52.465986) (xy 121.579386 -52.994814) (xy 121.57202 -53.001926) (xy 121.5644 -53.020722)
			(xy 121.5644 -53.27777) (xy 122.4186 -53.27777) (xy 122.422671 -53.222148) (xy 122.434797 -53.167711)
			(xy 122.45472 -53.11562) (xy 122.482016 -53.066985) (xy 122.516102 -53.022842) (xy 122.556251 -52.984133)
			(xy 122.601609 -52.951682) (xy 122.651209 -52.926181) (xy 122.703993 -52.908174) (xy 122.758836 -52.898044)
			(xy 122.81457 -52.896007) (xy 122.870007 -52.902107) (xy 122.923964 -52.916213) (xy 122.975293 -52.938025)
			(xy 123.022899 -52.967079) (xy 123.065767 -53.002754) (xy 123.102984 -53.044291) (xy 123.133757 -53.090804)
			(xy 123.157429 -53.141301) (xy 123.16257 -53.15839) (xy 126.307086 -53.15839) (xy 126.311157 -53.102768)
			(xy 126.323283 -53.048331) (xy 126.343206 -52.99624) (xy 126.370502 -52.947605) (xy 126.404588 -52.903462)
			(xy 126.444737 -52.864753) (xy 126.490095 -52.832302) (xy 126.539695 -52.806801) (xy 126.592479 -52.788794)
			(xy 126.647322 -52.778664) (xy 126.703056 -52.776627) (xy 126.758493 -52.782727) (xy 126.81245 -52.796833)
			(xy 126.863779 -52.818645) (xy 126.911385 -52.847699) (xy 126.954253 -52.883374) (xy 126.99147 -52.924911)
			(xy 127.022243 -52.971424) (xy 127.045915 -53.021921) (xy 127.061983 -53.075328) (xy 127.070103 -53.130504)
			(xy 127.070612 -53.15839) (xy 127.070103 -53.186276) (xy 127.061983 -53.241452) (xy 127.045915 -53.294859)
			(xy 127.022243 -53.345356) (xy 126.99147 -53.391869) (xy 126.954253 -53.433406) (xy 126.911385 -53.469081)
			(xy 126.863779 -53.498135) (xy 126.81245 -53.519947) (xy 126.758493 -53.534053) (xy 126.703056 -53.540153)
			(xy 126.647322 -53.538116) (xy 126.592479 -53.527986) (xy 126.539695 -53.509979) (xy 126.490095 -53.484478)
			(xy 126.444737 -53.452027) (xy 126.404588 -53.413318) (xy 126.370502 -53.369175) (xy 126.343206 -53.32054)
			(xy 126.323283 -53.268449) (xy 126.311157 -53.214012) (xy 126.307086 -53.15839) (xy 123.16257 -53.15839)
			(xy 123.173497 -53.194708) (xy 123.181617 -53.249884) (xy 123.182126 -53.27777) (xy 123.181617 -53.305656)
			(xy 123.173497 -53.360832) (xy 123.157429 -53.414239) (xy 123.133757 -53.464736) (xy 123.102984 -53.511249)
			(xy 123.065767 -53.552786) (xy 123.022899 -53.588461) (xy 122.975293 -53.617515) (xy 122.923964 -53.639327)
			(xy 122.870007 -53.653433) (xy 122.81457 -53.659533) (xy 122.758836 -53.657496) (xy 122.703993 -53.647366)
			(xy 122.651209 -53.629359) (xy 122.601609 -53.603858) (xy 122.556251 -53.571407) (xy 122.516102 -53.532698)
			(xy 122.482016 -53.488555) (xy 122.45472 -53.43992) (xy 122.434797 -53.387829) (xy 122.422671 -53.333392)
			(xy 122.4186 -53.27777) (xy 121.5644 -53.27777) (xy 121.5644 -54.775608) (xy 124.366782 -54.775608)
			(xy 124.367293 -54.74276) (xy 124.375746 -54.677612) (xy 124.392525 -54.614096) (xy 124.417351 -54.553272)
			(xy 124.449808 -54.496155) (xy 124.489357 -54.443698) (xy 124.535336 -54.396775) (xy 124.560838 -54.376066)
			(xy 124.568712 -54.369716) (xy 124.573538 -54.36108) (xy 124.575935 -54.356626) (xy 124.57913 -54.347031)
			(xy 124.579888 -54.34203) (xy 124.589286 -54.260242) (xy 124.583698 -54.240684) (xy 124.577348 -54.23281)
			(xy 124.561593 -54.212445) (xy 124.53513 -54.168277) (xy 124.514851 -54.12095) (xy 124.501126 -54.071324)
			(xy 124.494203 -54.020303) (xy 124.493782 -53.994558) (xy 124.494268 -53.967307) (xy 124.502024 -53.913359)
			(xy 124.517379 -53.861064) (xy 124.540021 -53.811487) (xy 124.569487 -53.765637) (xy 124.605178 -53.724446)
			(xy 124.646369 -53.688755) (xy 124.692219 -53.659289) (xy 124.741796 -53.636647) (xy 124.794091 -53.621292)
			(xy 124.848039 -53.613536) (xy 124.902541 -53.613536) (xy 124.956489 -53.621292) (xy 125.008784 -53.636647)
			(xy 125.058361 -53.659289) (xy 125.104211 -53.688755) (xy 125.145402 -53.724446) (xy 125.181093 -53.765637)
			(xy 125.210559 -53.811487) (xy 125.233201 -53.861064) (xy 125.248556 -53.913359) (xy 125.256312 -53.967307)
			(xy 125.256798 -53.994558) (xy 125.256347 -54.0203) (xy 125.249418 -54.071317) (xy 125.235694 -54.120939)
			(xy 125.215424 -54.168266) (xy 125.211757 -54.17439) (xy 126.307086 -54.17439) (xy 126.311157 -54.118768)
			(xy 126.323283 -54.064331) (xy 126.343206 -54.01224) (xy 126.370502 -53.963605) (xy 126.404588 -53.919462)
			(xy 126.444737 -53.880753) (xy 126.490095 -53.848302) (xy 126.539695 -53.822801) (xy 126.592479 -53.804794)
			(xy 126.647322 -53.794664) (xy 126.703056 -53.792627) (xy 126.758493 -53.798727) (xy 126.81245 -53.812833)
			(xy 126.863779 -53.834645) (xy 126.884829 -53.847492) (xy 131.183124 -53.847492) (xy 131.187195 -53.79187)
			(xy 131.199321 -53.737433) (xy 131.219244 -53.685342) (xy 131.24654 -53.636707) (xy 131.280626 -53.592564)
			(xy 131.320775 -53.553855) (xy 131.366133 -53.521404) (xy 131.415733 -53.495903) (xy 131.468517 -53.477896)
			(xy 131.52336 -53.467766) (xy 131.579094 -53.465729) (xy 131.634531 -53.471829) (xy 131.688488 -53.485935)
			(xy 131.739817 -53.507747) (xy 131.787423 -53.536801) (xy 131.830291 -53.572476) (xy 131.831825 -53.574188)
			(xy 134.563102 -53.574188) (xy 134.567173 -53.518566) (xy 134.579299 -53.464129) (xy 134.599222 -53.412038)
			(xy 134.626518 -53.363403) (xy 134.660604 -53.31926) (xy 134.700753 -53.280551) (xy 134.746111 -53.2481)
			(xy 134.795711 -53.222599) (xy 134.848495 -53.204592) (xy 134.903338 -53.194462) (xy 134.959072 -53.192425)
			(xy 135.014509 -53.198525) (xy 135.068466 -53.212631) (xy 135.119795 -53.234443) (xy 135.167401 -53.263497)
			(xy 135.210269 -53.299172) (xy 135.247486 -53.340709) (xy 135.278259 -53.387222) (xy 135.301931 -53.437719)
			(xy 135.317999 -53.491126) (xy 135.326119 -53.546302) (xy 135.326628 -53.574188) (xy 135.326119 -53.602074)
			(xy 135.317999 -53.65725) (xy 135.301931 -53.710657) (xy 135.278259 -53.761154) (xy 135.247486 -53.807667)
			(xy 135.210269 -53.849204) (xy 135.185805 -53.869563) (xy 135.902694 -53.869563) (xy 135.902694 -53.805609)
			(xy 135.910709 -53.742159) (xy 135.926614 -53.680214) (xy 135.950157 -53.620752) (xy 135.980967 -53.564708)
			(xy 136.018559 -53.512968) (xy 136.062338 -53.466348) (xy 136.111616 -53.425582) (xy 136.165614 -53.391314)
			(xy 136.223481 -53.364083) (xy 136.284305 -53.34432) (xy 136.347126 -53.332337) (xy 136.410954 -53.328321)
			(xy 136.474782 -53.332337) (xy 136.537603 -53.34432) (xy 136.598427 -53.364083) (xy 136.656294 -53.391314)
			(xy 136.710292 -53.425582) (xy 136.75957 -53.466348) (xy 136.803349 -53.512968) (xy 136.840941 -53.564708)
			(xy 136.871751 -53.620752) (xy 136.895294 -53.680214) (xy 136.911199 -53.742159) (xy 136.919214 -53.805609)
			(xy 136.919716 -53.837586) (xy 136.919214 -53.869563) (xy 136.911199 -53.933013) (xy 136.895294 -53.994958)
			(xy 136.871751 -54.05442) (xy 136.840941 -54.110464) (xy 136.803349 -54.162204) (xy 136.75957 -54.208824)
			(xy 136.710292 -54.24959) (xy 136.656294 -54.283858) (xy 136.598427 -54.311089) (xy 136.537603 -54.330852)
			(xy 136.474782 -54.342835) (xy 136.410954 -54.346851) (xy 136.347126 -54.342835) (xy 136.284305 -54.330852)
			(xy 136.223481 -54.311089) (xy 136.165614 -54.283858) (xy 136.111616 -54.24959) (xy 136.062338 -54.208824)
			(xy 136.018559 -54.162204) (xy 135.980967 -54.110464) (xy 135.950157 -54.05442) (xy 135.926614 -53.994958)
			(xy 135.910709 -53.933013) (xy 135.902694 -53.869563) (xy 135.185805 -53.869563) (xy 135.167401 -53.884879)
			(xy 135.119795 -53.913933) (xy 135.068466 -53.935745) (xy 135.014509 -53.949851) (xy 134.959072 -53.955951)
			(xy 134.903338 -53.953914) (xy 134.848495 -53.943784) (xy 134.795711 -53.925777) (xy 134.746111 -53.900276)
			(xy 134.700753 -53.867825) (xy 134.660604 -53.829116) (xy 134.626518 -53.784973) (xy 134.599222 -53.736338)
			(xy 134.579299 -53.684247) (xy 134.567173 -53.62981) (xy 134.563102 -53.574188) (xy 131.831825 -53.574188)
			(xy 131.867508 -53.614013) (xy 131.898281 -53.660526) (xy 131.921953 -53.711023) (xy 131.938021 -53.76443)
			(xy 131.946141 -53.819606) (xy 131.94665 -53.847492) (xy 131.946141 -53.875378) (xy 131.938021 -53.930554)
			(xy 131.921953 -53.983961) (xy 131.898281 -54.034458) (xy 131.867508 -54.080971) (xy 131.830291 -54.122508)
			(xy 131.787423 -54.158183) (xy 131.739817 -54.187237) (xy 131.688488 -54.209049) (xy 131.634531 -54.223155)
			(xy 131.579094 -54.229255) (xy 131.52336 -54.227218) (xy 131.468517 -54.217088) (xy 131.415733 -54.199081)
			(xy 131.366133 -54.17358) (xy 131.320775 -54.141129) (xy 131.280626 -54.10242) (xy 131.24654 -54.058277)
			(xy 131.219244 -54.009642) (xy 131.199321 -53.957551) (xy 131.187195 -53.903114) (xy 131.183124 -53.847492)
			(xy 126.884829 -53.847492) (xy 126.911385 -53.863699) (xy 126.954253 -53.899374) (xy 126.99147 -53.940911)
			(xy 127.022243 -53.987424) (xy 127.045915 -54.037921) (xy 127.061983 -54.091328) (xy 127.070103 -54.146504)
			(xy 127.070612 -54.17439) (xy 127.070103 -54.202276) (xy 127.061983 -54.257452) (xy 127.045915 -54.310859)
			(xy 127.022243 -54.361356) (xy 126.99147 -54.407869) (xy 126.954253 -54.449406) (xy 126.911385 -54.485081)
			(xy 126.863779 -54.514135) (xy 126.81245 -54.535947) (xy 126.758493 -54.550053) (xy 126.703056 -54.556153)
			(xy 126.647322 -54.554116) (xy 126.592479 -54.543986) (xy 126.539695 -54.525979) (xy 126.490095 -54.500478)
			(xy 126.444737 -54.468027) (xy 126.404588 -54.429318) (xy 126.370502 -54.385175) (xy 126.343206 -54.33654)
			(xy 126.323283 -54.284449) (xy 126.311157 -54.230012) (xy 126.307086 -54.17439) (xy 125.211757 -54.17439)
			(xy 125.188975 -54.212438) (xy 125.173232 -54.23281) (xy 125.166882 -54.240684) (xy 125.161294 -54.260242)
			(xy 125.170692 -54.34203) (xy 125.171421 -54.347038) (xy 125.174622 -54.356636) (xy 125.177042 -54.36108)
			(xy 125.181868 -54.369716) (xy 125.189742 -54.376066) (xy 125.215257 -54.396758) (xy 125.261224 -54.443692)
			(xy 125.300764 -54.496155) (xy 125.333215 -54.553275) (xy 125.358039 -54.614099) (xy 125.374822 -54.677613)
			(xy 125.383283 -54.742761) (xy 125.383798 -54.775608) (xy 125.383296 -54.807569) (xy 125.375285 -54.870987)
			(xy 125.359388 -54.932901) (xy 125.335856 -54.992334) (xy 125.305062 -55.048349) (xy 125.267489 -55.100064)
			(xy 125.223732 -55.146661) (xy 125.174479 -55.187406) (xy 125.120508 -55.221657) (xy 125.062669 -55.248874)
			(xy 125.001876 -55.268627) (xy 124.939086 -55.280605) (xy 124.87529 -55.284619) (xy 124.811494 -55.280605)
			(xy 124.748704 -55.268627) (xy 124.687911 -55.248874) (xy 124.630072 -55.221657) (xy 124.576101 -55.187406)
			(xy 124.526848 -55.146661) (xy 124.483091 -55.100064) (xy 124.445518 -55.048349) (xy 124.414724 -54.992334)
			(xy 124.391192 -54.932901) (xy 124.375295 -54.870987) (xy 124.367284 -54.807569) (xy 124.366782 -54.775608)
			(xy 121.5644 -54.775608) (xy 121.5644 -56.259941) (xy 125.00457 -56.259941) (xy 125.00457 -56.196019)
			(xy 125.012581 -56.132601) (xy 125.028478 -56.070687) (xy 125.05201 -56.011254) (xy 125.082804 -55.955239)
			(xy 125.120377 -55.903524) (xy 125.164134 -55.856927) (xy 125.213387 -55.816182) (xy 125.267358 -55.781931)
			(xy 125.325197 -55.754714) (xy 125.38599 -55.734961) (xy 125.44878 -55.722983) (xy 125.512576 -55.71897)
			(xy 125.576372 -55.722983) (xy 125.639162 -55.734961) (xy 125.699955 -55.754714) (xy 125.757794 -55.781931)
			(xy 125.811765 -55.816182) (xy 125.861018 -55.856927) (xy 125.904775 -55.903524) (xy 125.942348 -55.955239)
			(xy 125.973142 -56.011254) (xy 125.996674 -56.070687) (xy 126.012571 -56.132601) (xy 126.020582 -56.196019)
			(xy 126.021084 -56.22798) (xy 126.020582 -56.259941) (xy 126.012571 -56.323359) (xy 125.996674 -56.385273)
			(xy 125.973142 -56.444706) (xy 125.942348 -56.500721) (xy 125.904775 -56.552436) (xy 125.861018 -56.599033)
			(xy 125.811765 -56.639778) (xy 125.757794 -56.674029) (xy 125.699955 -56.701246) (xy 125.639162 -56.720999)
			(xy 125.576372 -56.732977) (xy 125.512576 -56.736991) (xy 125.44878 -56.732977) (xy 125.38599 -56.720999)
			(xy 125.325197 -56.701246) (xy 125.267358 -56.674029) (xy 125.213387 -56.639778) (xy 125.164134 -56.599033)
			(xy 125.120377 -56.552436) (xy 125.082804 -56.500721) (xy 125.05201 -56.444706) (xy 125.028478 -56.385273)
			(xy 125.012581 -56.323359) (xy 125.00457 -56.259941) (xy 121.5644 -56.259941) (xy 121.5644 -56.697118)
			(xy 121.564827 -56.707187) (xy 121.572546 -56.725786) (xy 121.579386 -56.733186) (xy 122.082814 -57.236614)
			(xy 122.090209 -57.243468) (xy 122.108808 -57.25121) (xy 122.118882 -57.2516)
		)
		(stroke
			(width 0)
			(type solid)
		)
		(fill yes)
		(layer "In13.Cu")
		(net "PVDD18_S5_P0")
	)
	(gr_poly
		(pts
			(xy 34.555176 -367.609882) (xy 34.56524 -367.609445) (xy 34.583822 -367.601709) (xy 34.591244 -367.594896)
			(xy 34.600642 -367.585498) (xy 34.603436 -367.581434) (xy 34.609786 -367.573814) (xy 34.677096 -367.506504)
			(xy 34.682915 -367.50015) (xy 34.690307 -367.484596) (xy 34.692153 -367.467475) (xy 34.690558 -367.459006)
			(xy 34.681071 -367.41607) (xy 34.670879 -367.328729) (xy 34.670238 -367.284762) (xy 34.670238 -367.284)
			(xy 34.670761 -367.244053) (xy 34.679112 -367.164596) (xy 34.695723 -367.086447) (xy 34.720412 -367.010463)
			(xy 34.752908 -366.937476) (xy 34.792855 -366.868285) (xy 34.839816 -366.803649) (xy 34.893276 -366.744276)
			(xy 34.952649 -366.690816) (xy 35.017285 -366.643855) (xy 35.086476 -366.603908) (xy 35.159463 -366.571412)
			(xy 35.235447 -366.546723) (xy 35.313596 -366.530112) (xy 35.393053 -366.521761) (xy 35.433 -366.521238)
			(xy 35.433762 -366.521238) (xy 35.477727 -366.521903) (xy 35.565068 -366.532087) (xy 35.608006 -366.541558)
			(xy 35.616472 -366.543215) (xy 35.633613 -366.541384) (xy 35.649166 -366.533948) (xy 35.655504 -366.528096)
			(xy 35.68319 -366.50041) (xy 35.690302 -366.486694) (xy 35.691572 -366.478566) (xy 35.696318 -366.452656)
			(xy 35.712004 -366.402369) (xy 35.734457 -366.354718) (xy 35.763251 -366.310609) (xy 35.797839 -366.27088)
			(xy 35.837563 -366.236286) (xy 35.881668 -366.207485) (xy 35.929316 -366.185025) (xy 35.9796 -366.169332)
			(xy 36.005516 -366.164622) (xy 36.013644 -366.163352) (xy 36.02736 -366.15624) (xy 36.144454 -366.039146)
			(xy 36.147248 -366.001808) (xy 36.136072 -365.986568) (xy 36.118551 -365.961799) (xy 36.090746 -365.907879)
			(xy 36.071816 -365.850241) (xy 36.062239 -365.790334) (xy 36.06165 -365.76) (xy 36.062113 -365.732729)
			(xy 36.069876 -365.678743) (xy 36.085242 -365.626411) (xy 36.1079 -365.576799) (xy 36.137388 -365.530916)
			(xy 36.173105 -365.489697) (xy 36.214326 -365.45398) (xy 36.260209 -365.424494) (xy 36.309822 -365.401838)
			(xy 36.362155 -365.386473) (xy 36.416141 -365.378713) (xy 36.443412 -365.378238) (xy 36.465587 -365.378517)
			(xy 36.509642 -365.383613) (xy 36.531296 -365.388398) (xy 36.535614 -365.389414) (xy 36.550114 -365.391098)
			(xy 36.579013 -365.387067) (xy 36.605591 -365.375025) (xy 36.627678 -365.355958) (xy 36.64347 -365.331421)
			(xy 36.651676 -365.30342) (xy 36.6522 -365.28883) (xy 36.6522 -359.631234) (xy 36.651858 -359.622627)
			(xy 36.646163 -359.606381) (xy 36.635432 -359.592921) (xy 36.628324 -359.588054) (xy 36.602141 -359.571062)
			(xy 36.555169 -359.529962) (xy 36.534852 -359.506266) (xy 36.524659 -359.4947) (xy 36.49889 -359.477803)
			(xy 36.469255 -359.469359) (xy 36.43845 -359.470136) (xy 36.409279 -359.480064) (xy 36.384395 -359.498239)
			(xy 36.374832 -359.51033) (xy 36.356684 -359.533856) (xy 36.314332 -359.575525) (xy 36.266039 -359.610134)
			(xy 36.21297 -359.636849) (xy 36.156404 -359.655026) (xy 36.097707 -359.664225) (xy 36.068 -359.664762)
			(xy 36.040731 -359.664276) (xy 35.986747 -359.656514) (xy 35.934417 -359.641149) (xy 35.884807 -359.618492)
			(xy 35.838926 -359.589006) (xy 35.797709 -359.553291) (xy 35.761994 -359.512074) (xy 35.732508 -359.466193)
			(xy 35.709851 -359.416583) (xy 35.694486 -359.364253) (xy 35.686724 -359.310269) (xy 35.686238 -359.283)
			(xy 35.686681 -359.256655) (xy 35.693925 -359.204465) (xy 35.708276 -359.153767) (xy 35.72946 -359.105524)
			(xy 35.74288 -359.082848) (xy 35.749612 -359.071136) (xy 35.757268 -359.04524) (xy 35.757866 -359.018243)
			(xy 35.751365 -358.992033) (xy 35.738219 -358.968444) (xy 35.719348 -358.949128) (xy 35.696073 -358.935435)
			(xy 35.670022 -358.928324) (xy 35.65652 -358.927908) (xy 35.5473 -358.927908) (xy 35.541938 -358.928024)
			(xy 35.531437 -358.930198) (xy 35.526472 -358.932226) (xy 35.499294 -358.944418) (xy 35.492182 -358.952038)
			(xy 35.465143 -358.980301) (xy 35.406217 -359.031744) (xy 35.342338 -359.076888) (xy 35.274175 -359.115259)
			(xy 35.202444 -359.146455) (xy 35.127897 -359.170149) (xy 35.051317 -359.186091) (xy 34.973509 -359.194114)
			(xy 34.934398 -359.194608) (xy 34.895285 -359.194116) (xy 34.81747 -359.186116) (xy 34.740884 -359.170189)
			(xy 34.66633 -359.146504) (xy 34.594594 -359.115309) (xy 34.52643 -359.076932) (xy 34.462553 -359.031777)
			(xy 34.403637 -358.980319) (xy 34.376614 -358.952038) (xy 34.369502 -358.944418) (xy 34.342324 -358.932226)
			(xy 34.337365 -358.930177) (xy 34.326861 -358.928005) (xy 34.321496 -358.927908) (xy 33.381188 -358.927908)
			(xy 33.356187 -358.927315) (xy 33.307152 -358.917518) (xy 33.260971 -358.898344) (xy 33.219419 -358.870527)
			(xy 33.201356 -358.853232) (xy 32.452818 -358.104694) (xy 32.445706 -358.097328) (xy 32.42691 -358.089708)
			(xy 30.8356 -358.089708) (xy 30.828488 -358.089454) (xy 30.827472 -358.089454) (xy 30.751272 -358.089454)
			(xy 30.741288 -358.08891) (xy 30.722868 -358.081184) (xy 30.715458 -358.074468) (xy 30.69463 -358.053894)
			(xy 30.694122 -358.053386) (xy 30.693868 -358.053132) (xy 30.686516 -358.046651) (xy 30.668354 -358.039334)
			(xy 30.658562 -358.038908) (xy 30.6578 -358.038908) (xy 30.630549 -358.038422) (xy 30.576601 -358.030666)
			(xy 30.524306 -358.015311) (xy 30.474729 -357.992669) (xy 30.428879 -357.963203) (xy 30.387688 -357.927512)
			(xy 30.351997 -357.886321) (xy 30.322531 -357.840471) (xy 30.299889 -357.790894) (xy 30.284534 -357.738599)
			(xy 30.276778 -357.684651) (xy 30.276778 -357.630149) (xy 30.284534 -357.576201) (xy 30.299889 -357.523906)
			(xy 30.322531 -357.474329) (xy 30.351997 -357.428479) (xy 30.387688 -357.387288) (xy 30.428879 -357.351597)
			(xy 30.474729 -357.322131) (xy 30.524306 -357.299489) (xy 30.576601 -357.284134) (xy 30.630549 -357.276378)
			(xy 30.6578 -357.275892) (xy 30.684757 -357.276358) (xy 30.738133 -357.28395) (xy 30.789908 -357.298983)
			(xy 30.83905 -357.321157) (xy 30.88458 -357.35003) (xy 30.92559 -357.385028) (xy 30.961264 -357.425452)
			(xy 30.990889 -357.470496) (xy 31.013875 -357.519264) (xy 31.02229 -357.544878) (xy 31.02737 -357.561134)
			(xy 31.05404 -357.580692) (xy 32.542988 -357.580692) (xy 32.5501 -357.580946) (xy 32.551116 -357.580946)
			(xy 32.627316 -357.580946) (xy 32.637301 -357.581488) (xy 32.655725 -357.58921) (xy 32.66313 -357.595932)
			(xy 32.718502 -357.65105) (xy 32.822134 -357.754682) (xy 32.822642 -357.75519) (xy 32.830024 -357.76177)
			(xy 32.848323 -357.769219) (xy 32.858202 -357.769668) (xy 33.756092 -357.769668) (xy 33.769562 -357.769215)
			(xy 33.795548 -357.762096) (xy 33.818768 -357.74843) (xy 33.837607 -357.729168) (xy 33.850755 -357.70565)
			(xy 33.857296 -357.679513) (xy 33.857438 -357.666036) (xy 33.857438 -357.665274) (xy 33.857438 -357.66502)
			(xy 33.857438 -357.657908) (xy 33.857438 -357.657654) (xy 33.857438 -357.657146) (xy 33.857942 -357.629888)
			(xy 33.865733 -357.575932) (xy 33.88112 -357.523633) (xy 33.903791 -357.474055) (xy 33.933284 -357.428206)
			(xy 33.968999 -357.387019) (xy 34.01021 -357.351331) (xy 34.056078 -357.321869) (xy 34.105672 -357.299231)
			(xy 34.157981 -357.283879) (xy 34.211942 -357.276124) (xy 34.2392 -357.275638) (xy 34.266752 -357.276128)
			(xy 34.321282 -357.284061) (xy 34.374106 -357.299747) (xy 34.424128 -357.322861) (xy 34.47031 -357.352924)
			(xy 34.511692 -357.38931) (xy 34.547415 -357.431266) (xy 34.57674 -357.477919) (xy 34.599055 -357.528303)
			(xy 34.613899 -357.58137) (xy 34.617914 -357.608632) (xy 34.619438 -357.619554) (xy 34.630868 -357.637842)
			(xy 34.701988 -357.685848) (xy 34.709566 -357.690555) (xy 34.72687 -357.694847) (xy 34.73577 -357.69423)
			(xy 34.743898 -357.693468) (xy 34.747454 -357.692452) (xy 34.793416 -357.68153) (xy 34.887161 -357.669814)
			(xy 34.934398 -357.669084) (xy 34.934652 -357.669084) (xy 34.973101 -357.669576) (xy 35.049607 -357.677344)
			(xy 35.124942 -357.692775) (xy 35.19834 -357.715712) (xy 35.269056 -357.745923) (xy 35.302952 -357.76408)
			(xy 35.315906 -357.76408) (xy 36.499038 -357.76408) (xy 36.509105 -357.763649) (xy 36.527697 -357.755923)
			(xy 36.535106 -357.749094) (xy 36.637214 -357.646986) (xy 36.637722 -357.646478) (xy 36.644312 -357.6391)
			(xy 36.651779 -357.620801) (xy 36.6522 -357.610918) (xy 36.6522 -357.022908) (xy 36.651782 -357.012886)
			(xy 36.644113 -356.994366) (xy 36.629941 -356.980191) (xy 36.611422 -356.97252) (xy 36.6014 -356.972108)
			(xy 31.1658 -356.972108) (xy 31.158688 -356.971854) (xy 31.157672 -356.971854) (xy 31.081472 -356.971854)
			(xy 31.071577 -356.971328) (xy 31.053293 -356.963736) (xy 31.045912 -356.957122) (xy 31.045658 -356.956868)
			(xy 31.037022 -356.948486) (xy 31.029641 -356.941903) (xy 31.011342 -356.934456) (xy 31.001462 -356.934008)
			(xy 31.0007 -356.934008) (xy 30.973449 -356.933522) (xy 30.919501 -356.925766) (xy 30.867206 -356.910411)
			(xy 30.817629 -356.887769) (xy 30.771779 -356.858303) (xy 30.730588 -356.822612) (xy 30.694897 -356.781421)
			(xy 30.665431 -356.735571) (xy 30.642789 -356.685994) (xy 30.627434 -356.633699) (xy 30.619678 -356.579751)
			(xy 30.619678 -356.525249) (xy 30.627434 -356.471301) (xy 30.642789 -356.419006) (xy 30.665431 -356.369429)
			(xy 30.694897 -356.323579) (xy 30.730588 -356.282388) (xy 30.771779 -356.246697) (xy 30.817629 -356.217231)
			(xy 30.867206 -356.194589) (xy 30.919501 -356.179234) (xy 30.973449 -356.171478) (xy 31.0007 -356.170992)
			(xy 31.027008 -356.171433) (xy 31.079125 -356.178661) (xy 31.129754 -356.192981) (xy 31.177936 -356.214121)
			(xy 31.222757 -356.24168) (xy 31.263367 -356.275135) (xy 31.298995 -356.313852) (xy 31.328967 -356.357097)
			(xy 31.352713 -356.404049) (xy 31.361634 -356.428802) (xy 31.366968 -356.444296) (xy 31.39313 -356.463092)
			(xy 35.1282 -356.463092) (xy 35.138221 -356.462672) (xy 35.156736 -356.455002) (xy 35.170907 -356.44083)
			(xy 35.178574 -356.422313) (xy 35.179 -356.412292) (xy 35.179 -356.235) (xy 35.178556 -356.221234)
			(xy 35.17121 -356.194702) (xy 35.157029 -356.171104) (xy 35.137047 -356.152166) (xy 35.112724 -356.13927)
			(xy 35.085836 -356.133357) (xy 35.072066 -356.133654) (xy 35.052508 -356.134162) (xy 35.052 -356.134162)
			(xy 35.024731 -356.133676) (xy 34.970747 -356.125914) (xy 34.918417 -356.110549) (xy 34.868807 -356.087892)
			(xy 34.822926 -356.058406) (xy 34.781709 -356.022691) (xy 34.745994 -355.981474) (xy 34.716508 -355.935593)
			(xy 34.693851 -355.885983) (xy 34.678486 -355.833653) (xy 34.670724 -355.779669) (xy 34.670724 -355.725131)
			(xy 34.678486 -355.671147) (xy 34.693851 -355.618817) (xy 34.716508 -355.569207) (xy 34.745994 -355.523326)
			(xy 34.781709 -355.482109) (xy 34.822926 -355.446394) (xy 34.868807 -355.416908) (xy 34.918417 -355.394251)
			(xy 34.970747 -355.378886) (xy 35.024731 -355.371124) (xy 35.052 -355.370638) (xy 35.052508 -355.370638)
			(xy 35.072066 -355.371146) (xy 35.085823 -355.371403) (xy 35.112674 -355.365439) (xy 35.13696 -355.352528)
			(xy 35.156922 -355.333606) (xy 35.171112 -355.310045) (xy 35.178502 -355.283551) (xy 35.179 -355.2698)
			(xy 35.179 -355.149404) (xy 35.178577 -355.139333) (xy 35.170864 -355.120728) (xy 35.164014 -355.113336)
			(xy 35.081464 -355.030786) (xy 35.074352 -355.02342) (xy 35.055556 -355.0158) (xy 30.652974 -355.0158)
			(xy 30.647941 -355.015939) (xy 30.638085 -355.017982) (xy 30.633416 -355.019864) (xy 30.621732 -355.02469)
			(xy 30.617104 -355.026466) (xy 30.607383 -355.02839) (xy 30.602428 -355.0285) (xy 30.056582 -355.0285)
			(xy 30.046513 -355.028927) (xy 30.027914 -355.036646) (xy 30.020514 -355.043486) (xy 29.21 -355.854)
			(xy 31.291528 -355.854) (xy 31.295601 -355.798341) (xy 31.307736 -355.743868) (xy 31.327672 -355.691742)
			(xy 31.354986 -355.643074) (xy 31.389094 -355.598902) (xy 31.429271 -355.560167) (xy 31.474659 -355.527695)
			(xy 31.524291 -355.502177) (xy 31.577111 -355.484158) (xy 31.63199 -355.474021) (xy 31.687761 -355.471983)
			(xy 31.743235 -355.478086) (xy 31.797228 -355.492202) (xy 31.848591 -355.514029) (xy 31.896229 -355.543102)
			(xy 31.939125 -355.578801) (xy 31.976367 -355.620365) (xy 32.007161 -355.666909) (xy 32.030849 -355.71744)
			(xy 32.046927 -355.770882) (xy 32.055053 -355.826096) (xy 32.055562 -355.854) (xy 32.434528 -355.854)
			(xy 32.438601 -355.798341) (xy 32.450736 -355.743868) (xy 32.470672 -355.691742) (xy 32.497986 -355.643074)
			(xy 32.532094 -355.598902) (xy 32.572271 -355.560167) (xy 32.617659 -355.527695) (xy 32.667291 -355.502177)
			(xy 32.720111 -355.484158) (xy 32.77499 -355.474021) (xy 32.830761 -355.471983) (xy 32.886235 -355.478086)
			(xy 32.940228 -355.492202) (xy 32.991591 -355.514029) (xy 33.039229 -355.543102) (xy 33.082125 -355.578801)
			(xy 33.119367 -355.620365) (xy 33.150161 -355.666909) (xy 33.173849 -355.71744) (xy 33.189927 -355.770882)
			(xy 33.198053 -355.826096) (xy 33.198562 -355.854) (xy 33.198053 -355.881904) (xy 33.189927 -355.937118)
			(xy 33.173849 -355.99056) (xy 33.150161 -356.041091) (xy 33.119367 -356.087635) (xy 33.082125 -356.129199)
			(xy 33.039229 -356.164898) (xy 32.991591 -356.193971) (xy 32.940228 -356.215798) (xy 32.886235 -356.229914)
			(xy 32.830761 -356.236017) (xy 32.77499 -356.233979) (xy 32.720111 -356.223842) (xy 32.667291 -356.205823)
			(xy 32.617659 -356.180305) (xy 32.572271 -356.147833) (xy 32.532094 -356.109098) (xy 32.497986 -356.064926)
			(xy 32.470672 -356.016258) (xy 32.450736 -355.964132) (xy 32.438601 -355.909659) (xy 32.434528 -355.854)
			(xy 32.055562 -355.854) (xy 32.055053 -355.881904) (xy 32.046927 -355.937118) (xy 32.030849 -355.99056)
			(xy 32.007161 -356.041091) (xy 31.976367 -356.087635) (xy 31.939125 -356.129199) (xy 31.896229 -356.164898)
			(xy 31.848591 -356.193971) (xy 31.797228 -356.215798) (xy 31.743235 -356.229914) (xy 31.687761 -356.236017)
			(xy 31.63199 -356.233979) (xy 31.577111 -356.223842) (xy 31.524291 -356.205823) (xy 31.474659 -356.180305)
			(xy 31.429271 -356.147833) (xy 31.389094 -356.109098) (xy 31.354986 -356.064926) (xy 31.327672 -356.016258)
			(xy 31.307736 -355.964132) (xy 31.295601 -355.909659) (xy 31.291528 -355.854) (xy 29.21 -355.854)
			(xy 28.734004 -356.329996) (xy 28.726384 -356.350316) (xy 28.727146 -356.361238) (xy 28.727908 -356.3874)
			(xy 28.727473 -356.413626) (xy 28.720294 -356.465583) (xy 28.706069 -356.516069) (xy 28.685068 -356.564132)
			(xy 28.657685 -356.608868) (xy 28.624437 -356.649435) (xy 28.60548 -356.667562) (xy 28.597606 -356.674674)
			(xy 28.585668 -356.70236) (xy 28.58135 -356.712266) (xy 28.58135 -358.267) (xy 29.259782 -358.267)
			(xy 29.263853 -358.211378) (xy 29.275979 -358.156941) (xy 29.295902 -358.10485) (xy 29.323198 -358.056215)
			(xy 29.357284 -358.012072) (xy 29.397433 -357.973363) (xy 29.442791 -357.940912) (xy 29.492391 -357.915411)
			(xy 29.545175 -357.897404) (xy 29.600018 -357.887274) (xy 29.655752 -357.885237) (xy 29.711189 -357.891337)
			(xy 29.765146 -357.905443) (xy 29.816475 -357.927255) (xy 29.864081 -357.956309) (xy 29.906949 -357.991984)
			(xy 29.944166 -358.033521) (xy 29.974939 -358.080034) (xy 29.998611 -358.130531) (xy 30.014679 -358.183938)
			(xy 30.022799 -358.239114) (xy 30.023308 -358.267) (xy 30.022799 -358.294886) (xy 30.014679 -358.350062)
			(xy 29.998611 -358.403469) (xy 29.974939 -358.453966) (xy 29.944166 -358.500479) (xy 29.906949 -358.542016)
			(xy 29.864081 -358.577691) (xy 29.816475 -358.606745) (xy 29.765146 -358.628557) (xy 29.711189 -358.642663)
			(xy 29.655752 -358.648763) (xy 29.600018 -358.646726) (xy 29.545175 -358.636596) (xy 29.492391 -358.618589)
			(xy 29.442791 -358.593088) (xy 29.397433 -358.560637) (xy 29.357284 -358.521928) (xy 29.323198 -358.477785)
			(xy 29.295902 -358.42915) (xy 29.275979 -358.377059) (xy 29.263853 -358.322622) (xy 29.259782 -358.267)
			(xy 28.58135 -358.267) (xy 28.58135 -359.156) (xy 31.241492 -359.156) (xy 31.241981 -359.117355)
			(xy 31.249801 -359.040461) (xy 31.265359 -358.964753) (xy 31.288497 -358.891007) (xy 31.318977 -358.81998)
			(xy 31.356486 -358.752402) (xy 31.40064 -358.688964) (xy 31.450985 -358.63032) (xy 31.507004 -358.577069)
			(xy 31.568123 -358.529759) (xy 31.633716 -358.488875) (xy 31.703107 -358.454837) (xy 31.775587 -358.427994)
			(xy 31.85041 -358.408621) (xy 31.926809 -358.396917) (xy 32.004 -358.393002) (xy 32.081191 -358.396917)
			(xy 32.15759 -358.408621) (xy 32.232413 -358.427994) (xy 32.304893 -358.454837) (xy 32.374284 -358.488875)
			(xy 32.439877 -358.529759) (xy 32.500996 -358.577069) (xy 32.557015 -358.63032) (xy 32.60736 -358.688964)
			(xy 32.651514 -358.752402) (xy 32.689023 -358.81998) (xy 32.719503 -358.891007) (xy 32.742641 -358.964753)
			(xy 32.758199 -359.040461) (xy 32.766019 -359.117355) (xy 32.766508 -359.156) (xy 32.766035 -359.193304)
			(xy 32.758739 -359.267555) (xy 32.744226 -359.340739) (xy 32.722636 -359.412155) (xy 32.694175 -359.481122)
			(xy 32.659114 -359.546979) (xy 32.617789 -359.609098) (xy 32.570596 -359.666884) (xy 32.517984 -359.719784)
			(xy 32.460458 -359.767294) (xy 32.398567 -359.808959) (xy 32.36595 -359.827068) (xy 32.357568 -359.83164)
			(xy 32.351472 -359.838752) (xy 32.347841 -359.843195) (xy 32.342447 -359.85332) (xy 32.340804 -359.858818)
			(xy 32.319214 -359.940606) (xy 32.322262 -359.961434) (xy 32.32785 -359.970324) (xy 32.341513 -359.99312)
			(xy 32.363068 -360.041697) (xy 32.377674 -360.092796) (xy 32.385049 -360.145427) (xy 32.385508 -360.172)
			(xy 32.385022 -360.199251) (xy 32.377266 -360.253199) (xy 32.361911 -360.305494) (xy 32.339269 -360.355071)
			(xy 32.309803 -360.400921) (xy 32.274112 -360.442112) (xy 32.232921 -360.477803) (xy 32.187071 -360.507269)
			(xy 32.137494 -360.529911) (xy 32.085199 -360.545266) (xy 32.031251 -360.553022) (xy 31.976749 -360.553022)
			(xy 31.922801 -360.545266) (xy 31.870506 -360.529911) (xy 31.820929 -360.507269) (xy 31.775079 -360.477803)
			(xy 31.733888 -360.442112) (xy 31.698197 -360.400921) (xy 31.668731 -360.355071) (xy 31.646089 -360.305494)
			(xy 31.630734 -360.253199) (xy 31.622978 -360.199251) (xy 31.622492 -360.172) (xy 31.622932 -360.145427)
			(xy 31.63031 -360.092795) (xy 31.644924 -360.041697) (xy 31.66649 -359.993122) (xy 31.68015 -359.970324)
			(xy 31.685738 -359.961434) (xy 31.688786 -359.940606) (xy 31.667196 -359.858818) (xy 31.665576 -359.853311)
			(xy 31.660179 -359.843182) (xy 31.656528 -359.838752) (xy 31.650432 -359.83164) (xy 31.64205 -359.827068)
			(xy 31.609453 -359.80892) (xy 31.547551 -359.76727) (xy 31.490014 -359.719772) (xy 31.437393 -359.666879)
			(xy 31.390191 -359.609099) (xy 31.34886 -359.546984) (xy 31.313795 -359.481127) (xy 31.285332 -359.41216)
			(xy 31.263743 -359.340743) (xy 31.249234 -359.267557) (xy 31.241945 -359.193305) (xy 31.241492 -359.156)
			(xy 28.58135 -359.156) (xy 28.58135 -359.5878) (xy 29.259782 -359.5878) (xy 29.263853 -359.532178)
			(xy 29.275979 -359.477741) (xy 29.295902 -359.42565) (xy 29.323198 -359.377015) (xy 29.357284 -359.332872)
			(xy 29.397433 -359.294163) (xy 29.442791 -359.261712) (xy 29.492391 -359.236211) (xy 29.545175 -359.218204)
			(xy 29.600018 -359.208074) (xy 29.655752 -359.206037) (xy 29.711189 -359.212137) (xy 29.765146 -359.226243)
			(xy 29.816475 -359.248055) (xy 29.864081 -359.277109) (xy 29.906949 -359.312784) (xy 29.944166 -359.354321)
			(xy 29.974939 -359.400834) (xy 29.998611 -359.451331) (xy 30.014679 -359.504738) (xy 30.022799 -359.559914)
			(xy 30.023308 -359.5878) (xy 30.022799 -359.615686) (xy 30.014679 -359.670862) (xy 29.998611 -359.724269)
			(xy 29.974939 -359.774766) (xy 29.944166 -359.821279) (xy 29.906949 -359.862816) (xy 29.864081 -359.898491)
			(xy 29.816475 -359.927545) (xy 29.765146 -359.949357) (xy 29.711189 -359.963463) (xy 29.655752 -359.969563)
			(xy 29.600018 -359.967526) (xy 29.545175 -359.957396) (xy 29.492391 -359.939389) (xy 29.442791 -359.913888)
			(xy 29.397433 -359.881437) (xy 29.357284 -359.842728) (xy 29.323198 -359.798585) (xy 29.295902 -359.74995)
			(xy 29.275979 -359.697859) (xy 29.263853 -359.643422) (xy 29.259782 -359.5878) (xy 28.58135 -359.5878)
			(xy 28.58135 -360.449368) (xy 28.581818 -360.459242) (xy 28.589268 -360.477532) (xy 28.595828 -360.484928)
			(xy 28.596082 -360.485182) (xy 29.690314 -361.579414) (xy 29.690822 -361.579922) (xy 29.6982 -361.586512)
			(xy 29.716499 -361.593979) (xy 29.726382 -361.5944) (xy 32.871918 -361.5944) (xy 32.881987 -361.594827)
			(xy 32.900586 -361.602546) (xy 32.907986 -361.609386) (xy 33.030414 -361.731814) (xy 33.037268 -361.739209)
			(xy 33.04501 -361.757808) (xy 33.0454 -361.767882) (xy 33.0454 -363.728) (xy 33.674304 -363.728)
			(xy 33.678364 -363.644062) (xy 33.690506 -363.560908) (xy 33.710617 -363.479314) (xy 33.73851 -363.400042)
			(xy 33.773922 -363.323832) (xy 33.816525 -363.251396) (xy 33.86592 -363.183409) (xy 33.921646 -363.120507)
			(xy 33.983183 -363.063278) (xy 34.049956 -363.012254) (xy 34.121342 -362.967913) (xy 34.196674 -362.930669)
			(xy 34.275249 -362.90087) (xy 34.356333 -362.878793) (xy 34.43917 -362.864645) (xy 34.522985 -362.858558)
			(xy 34.606996 -362.860589) (xy 34.690419 -362.870718) (xy 34.772476 -362.888852) (xy 34.852398 -362.91482)
			(xy 34.929442 -362.948381) (xy 35.002887 -362.989221) (xy 35.072047 -363.036959) (xy 35.136277 -363.091149)
			(xy 35.138084 -363.093) (xy 35.558728 -363.093) (xy 35.562801 -363.037341) (xy 35.574936 -362.982868)
			(xy 35.594872 -362.930742) (xy 35.622186 -362.882074) (xy 35.656294 -362.837902) (xy 35.696471 -362.799167)
			(xy 35.741859 -362.766695) (xy 35.791491 -362.741177) (xy 35.844311 -362.723158) (xy 35.89919 -362.713021)
			(xy 35.954961 -362.710983) (xy 36.010435 -362.717086) (xy 36.064428 -362.731202) (xy 36.115791 -362.753029)
			(xy 36.163429 -362.782102) (xy 36.206325 -362.817801) (xy 36.243567 -362.859365) (xy 36.274361 -362.905909)
			(xy 36.298049 -362.95644) (xy 36.314127 -363.009882) (xy 36.322253 -363.065096) (xy 36.322762 -363.093)
			(xy 36.322253 -363.120904) (xy 36.314127 -363.176118) (xy 36.298049 -363.22956) (xy 36.274361 -363.280091)
			(xy 36.243567 -363.326635) (xy 36.206325 -363.368199) (xy 36.163429 -363.403898) (xy 36.115791 -363.432971)
			(xy 36.064428 -363.454798) (xy 36.010435 -363.468914) (xy 35.954961 -363.475017) (xy 35.89919 -363.472979)
			(xy 35.844311 -363.462842) (xy 35.791491 -363.444823) (xy 35.741859 -363.419305) (xy 35.696471 -363.386833)
			(xy 35.656294 -363.348098) (xy 35.622186 -363.303926) (xy 35.594872 -363.255258) (xy 35.574936 -363.203132)
			(xy 35.562801 -363.148659) (xy 35.558728 -363.093) (xy 35.138084 -363.093) (xy 35.194977 -363.151285)
			(xy 35.247599 -363.216806) (xy 35.293652 -363.287099) (xy 35.332705 -363.361509) (xy 35.364395 -363.439341)
			(xy 35.388424 -363.519868) (xy 35.40457 -363.602338) (xy 35.41268 -363.685982) (xy 35.413188 -363.728)
			(xy 35.41268 -363.770018) (xy 35.40457 -363.853662) (xy 35.388424 -363.936132) (xy 35.364395 -364.016659)
			(xy 35.332705 -364.094491) (xy 35.32509 -364.109) (xy 35.559238 -364.109) (xy 35.559724 -364.081731)
			(xy 35.567486 -364.027747) (xy 35.582851 -363.975417) (xy 35.605508 -363.925807) (xy 35.634994 -363.879926)
			(xy 35.670709 -363.838709) (xy 35.711926 -363.802994) (xy 35.757807 -363.773508) (xy 35.807417 -363.750851)
			(xy 35.859747 -363.735486) (xy 35.913731 -363.727724) (xy 35.968269 -363.727724) (xy 36.022253 -363.735486)
			(xy 36.074583 -363.750851) (xy 36.124193 -363.773508) (xy 36.170074 -363.802994) (xy 36.211291 -363.838709)
			(xy 36.247006 -363.879926) (xy 36.276492 -363.925807) (xy 36.299149 -363.975417) (xy 36.314514 -364.027747)
			(xy 36.322276 -364.081731) (xy 36.322762 -364.109) (xy 36.322216 -364.137766) (xy 36.313577 -364.194645)
			(xy 36.296509 -364.249586) (xy 36.271398 -364.301348) (xy 36.238812 -364.348762) (xy 36.199486 -364.390754)
			(xy 36.17722 -364.408974) (xy 36.165738 -364.418665) (xy 36.148598 -364.443328) (xy 36.139366 -364.471908)
			(xy 36.138838 -364.501938) (xy 36.14706 -364.530825) (xy 36.163323 -364.556075) (xy 36.174426 -364.5662)
			(xy 36.176458 -364.567724) (xy 36.199333 -364.585913) (xy 36.239799 -364.628074) (xy 36.273367 -364.675909)
			(xy 36.299255 -364.7283) (xy 36.316857 -364.784025) (xy 36.325762 -364.841781) (xy 36.326318 -364.871)
			(xy 36.325832 -364.898269) (xy 36.31807 -364.952253) (xy 36.302705 -365.004583) (xy 36.280048 -365.054193)
			(xy 36.250562 -365.100074) (xy 36.214847 -365.141291) (xy 36.17363 -365.177006) (xy 36.127749 -365.206492)
			(xy 36.078139 -365.229149) (xy 36.025809 -365.244514) (xy 35.971825 -365.252276) (xy 35.917287 -365.252276)
			(xy 35.863303 -365.244514) (xy 35.810973 -365.229149) (xy 35.761363 -365.206492) (xy 35.715482 -365.177006)
			(xy 35.674265 -365.141291) (xy 35.63855 -365.100074) (xy 35.609064 -365.054193) (xy 35.586407 -365.004583)
			(xy 35.571042 -364.952253) (xy 35.56328 -364.898269) (xy 35.562794 -364.871) (xy 35.563357 -364.842235)
			(xy 35.571995 -364.785358) (xy 35.589061 -364.730417) (xy 35.614168 -364.678655) (xy 35.646751 -364.631242)
			(xy 35.686072 -364.589247) (xy 35.708336 -364.571026) (xy 35.720064 -364.561048) (xy 35.737432 -364.53564)
			(xy 35.746453 -364.506216) (xy 35.746309 -364.475439) (xy 35.737013 -364.4461) (xy 35.719408 -364.420856)
			(xy 35.707574 -364.411006) (xy 35.684902 -364.392831) (xy 35.644838 -364.350747) (xy 35.611615 -364.303077)
			(xy 35.586001 -364.250922) (xy 35.56859 -364.195487) (xy 35.559782 -364.138053) (xy 35.559238 -364.109)
			(xy 35.32509 -364.109) (xy 35.293652 -364.168901) (xy 35.247599 -364.239194) (xy 35.194977 -364.304715)
			(xy 35.136277 -364.364851) (xy 35.072047 -364.419041) (xy 35.002887 -364.466779) (xy 34.929442 -364.507619)
			(xy 34.852398 -364.54118) (xy 34.772476 -364.567148) (xy 34.690419 -364.585282) (xy 34.606996 -364.595411)
			(xy 34.522985 -364.597442) (xy 34.43917 -364.591355) (xy 34.356333 -364.577207) (xy 34.275249 -364.55513)
			(xy 34.196674 -364.525331) (xy 34.121342 -364.488087) (xy 34.049956 -364.443746) (xy 33.983183 -364.392722)
			(xy 33.921646 -364.335493) (xy 33.86592 -364.272591) (xy 33.816525 -364.204604) (xy 33.773922 -364.132168)
			(xy 33.73851 -364.055958) (xy 33.710617 -363.976686) (xy 33.690506 -363.895092) (xy 33.678364 -363.811938)
			(xy 33.674304 -363.728) (xy 33.0454 -363.728) (xy 33.0454 -365.883698) (xy 34.67303 -365.883698)
			(xy 34.677103 -365.828039) (xy 34.689238 -365.773566) (xy 34.709174 -365.72144) (xy 34.736488 -365.672772)
			(xy 34.770596 -365.6286) (xy 34.810773 -365.589865) (xy 34.856161 -365.557393) (xy 34.905793 -365.531875)
			(xy 34.958613 -365.513856) (xy 35.013492 -365.503719) (xy 35.069263 -365.501681) (xy 35.124737 -365.507784)
			(xy 35.17873 -365.5219) (xy 35.230093 -365.543727) (xy 35.277731 -365.5728) (xy 35.320627 -365.608499)
			(xy 35.357869 -365.650063) (xy 35.388663 -365.696607) (xy 35.412351 -365.747138) (xy 35.428429 -365.80058)
			(xy 35.436555 -365.855794) (xy 35.437064 -365.883698) (xy 35.436555 -365.911602) (xy 35.428429 -365.966816)
			(xy 35.412351 -366.020258) (xy 35.388663 -366.070789) (xy 35.357869 -366.117333) (xy 35.320627 -366.158897)
			(xy 35.277731 -366.194596) (xy 35.230093 -366.223669) (xy 35.17873 -366.245496) (xy 35.124737 -366.259612)
			(xy 35.069263 -366.265715) (xy 35.013492 -366.263677) (xy 34.958613 -366.25354) (xy 34.905793 -366.235521)
			(xy 34.856161 -366.210003) (xy 34.810773 -366.177531) (xy 34.770596 -366.138796) (xy 34.736488 -366.094624)
			(xy 34.709174 -366.045956) (xy 34.689238 -365.99383) (xy 34.677103 -365.939357) (xy 34.67303 -365.883698)
			(xy 33.0454 -365.883698) (xy 33.0454 -367.346992) (xy 33.045873 -367.356863) (xy 33.053335 -367.375143)
			(xy 33.059878 -367.382552) (xy 33.060132 -367.382806) (xy 33.272222 -367.594896) (xy 33.27273 -367.595404)
			(xy 33.280108 -367.601995) (xy 33.298407 -367.609461) (xy 33.30829 -367.609882)
		)
		(stroke
			(width 0)
			(type solid)
		)
		(fill yes)
		(layer "In13.Cu")
		(net "PVDDCR_CPU1_P1_VCCS")
	)
	(gr_poly
		(pts
			(xy 133.25602 -81.31302) (xy 133.266027 -81.312529) (xy 133.284515 -81.304867) (xy 133.298667 -81.290715)
			(xy 133.306329 -81.272227) (xy 133.30682 -81.26222) (xy 133.30682 -70.567042) (xy 133.306387 -70.556976)
			(xy 133.29866 -70.538385) (xy 133.291834 -70.530974) (xy 132.613908 -69.853048) (xy 132.606796 -69.845682)
			(xy 132.588 -69.838062) (xy 114.682778 -69.838062) (xy 114.672711 -69.838491) (xy 114.654118 -69.846218)
			(xy 114.64671 -69.853048) (xy 113.884202 -70.615556) (xy 113.883948 -70.615556) (xy 113.848134 -70.65137)
			(xy 113.840768 -70.658482) (xy 113.833148 -70.677278) (xy 113.833148 -71.348648) (xy 115.0666 -71.348648)
			(xy 115.0666 -71.294152) (xy 115.074355 -71.24021) (xy 115.089708 -71.18792) (xy 115.112346 -71.138348)
			(xy 115.141808 -71.092501) (xy 115.177494 -71.051314) (xy 115.218679 -71.015625) (xy 115.264523 -70.986159)
			(xy 115.314094 -70.963518) (xy 115.366382 -70.948161) (xy 115.420324 -70.940402) (xy 115.447572 -70.939914)
			(xy 115.476004 -70.940456) (xy 115.53224 -70.948887) (xy 115.586599 -70.965582) (xy 115.637873 -70.990169)
			(xy 115.661694 -71.0057) (xy 115.670838 -71.011796) (xy 115.691412 -71.015606) (xy 115.785646 -70.993254)
			(xy 115.802156 -70.980554) (xy 115.80749 -70.970902) (xy 115.822018 -70.945803) (xy 115.857558 -70.899975)
			(xy 115.899623 -70.860052) (xy 115.947244 -70.826955) (xy 115.999325 -70.801445) (xy 116.054667 -70.784109)
			(xy 116.111995 -70.775347) (xy 116.140992 -70.774814) (xy 116.168246 -70.775263) (xy 116.222198 -70.783019)
			(xy 116.274498 -70.798375) (xy 116.324079 -70.821019) (xy 116.369933 -70.850488) (xy 116.411127 -70.886183)
			(xy 116.446821 -70.927378) (xy 116.476288 -70.973233) (xy 116.498929 -71.022815) (xy 116.514284 -71.075115)
			(xy 116.522038 -71.129068) (xy 116.5225 -71.156322) (xy 116.522047 -71.183693) (xy 116.514226 -71.237872)
			(xy 116.498734 -71.290376) (xy 116.480376 -71.330352) (xy 130.866589 -71.330352) (xy 130.866589 -71.275848)
			(xy 130.874347 -71.221898) (xy 130.889704 -71.169601) (xy 130.912347 -71.120023) (xy 130.941816 -71.074172)
			(xy 130.977511 -71.032982) (xy 131.018705 -70.997291) (xy 131.06456 -70.967827) (xy 131.114141 -70.945189)
			(xy 131.166439 -70.929838) (xy 131.22039 -70.922086) (xy 131.247642 -70.921626) (xy 131.275352 -70.922112)
			(xy 131.330187 -70.930142) (xy 131.383282 -70.946025) (xy 131.433518 -70.969427) (xy 131.479837 -70.999856)
			(xy 131.50088 -71.017892) (xy 131.507992 -71.023988) (xy 131.525264 -71.030592) (xy 131.61137 -71.030592)
			(xy 131.628642 -71.023988) (xy 131.635754 -71.017892) (xy 131.656797 -70.999858) (xy 131.703117 -70.969432)
			(xy 131.753353 -70.946034) (xy 131.806448 -70.930156) (xy 131.861283 -70.922132) (xy 131.916701 -70.922132)
			(xy 131.971536 -70.930156) (xy 132.024631 -70.946034) (xy 132.074867 -70.969432) (xy 132.121187 -70.999858)
			(xy 132.14223 -71.017892) (xy 132.149342 -71.023988) (xy 132.166614 -71.030592) (xy 132.25272 -71.030592)
			(xy 132.269992 -71.023988) (xy 132.277104 -71.017892) (xy 132.298136 -70.999844) (xy 132.344457 -70.969416)
			(xy 132.394696 -70.946017) (xy 132.447794 -70.93014) (xy 132.502632 -70.92212) (xy 132.530342 -70.921626)
			(xy 132.557594 -70.922047) (xy 132.611542 -70.929809) (xy 132.663836 -70.945169) (xy 132.713412 -70.967814)
			(xy 132.759262 -70.997285) (xy 132.800451 -71.032979) (xy 132.836141 -71.074172) (xy 132.865606 -71.120024)
			(xy 132.888246 -71.169603) (xy 132.9036 -71.221899) (xy 132.911356 -71.275848) (xy 132.911356 -71.330352)
			(xy 132.9036 -71.384301) (xy 132.888246 -71.436597) (xy 132.865606 -71.486176) (xy 132.836141 -71.532028)
			(xy 132.800451 -71.573221) (xy 132.759262 -71.608915) (xy 132.713412 -71.638386) (xy 132.663836 -71.661031)
			(xy 132.611542 -71.676391) (xy 132.557594 -71.684153) (xy 132.530342 -71.684642) (xy 132.502633 -71.684148)
			(xy 132.447799 -71.676118) (xy 132.394704 -71.660236) (xy 132.344468 -71.636835) (xy 132.298148 -71.60641)
			(xy 132.277104 -71.588376) (xy 132.269992 -71.58228) (xy 132.25272 -71.575676) (xy 132.166614 -71.575676)
			(xy 132.149342 -71.58228) (xy 132.14223 -71.588376) (xy 132.121187 -71.60641) (xy 132.074867 -71.636836)
			(xy 132.024631 -71.660234) (xy 131.971536 -71.676112) (xy 131.916701 -71.684136) (xy 131.861283 -71.684136)
			(xy 131.806448 -71.676112) (xy 131.753353 -71.660234) (xy 131.703117 -71.636836) (xy 131.656797 -71.60641)
			(xy 131.635754 -71.588376) (xy 131.628642 -71.58228) (xy 131.61137 -71.575676) (xy 131.525264 -71.575676)
			(xy 131.507992 -71.58228) (xy 131.50088 -71.588376) (xy 131.479849 -71.606427) (xy 131.433529 -71.636855)
			(xy 131.383289 -71.660254) (xy 131.330191 -71.67613) (xy 131.275353 -71.684148) (xy 131.247642 -71.684642)
			(xy 131.22039 -71.684114) (xy 131.166439 -71.676362) (xy 131.114141 -71.661011) (xy 131.06456 -71.638373)
			(xy 131.018705 -71.608909) (xy 130.977511 -71.573218) (xy 130.941816 -71.532028) (xy 130.912347 -71.486177)
			(xy 130.889704 -71.436599) (xy 130.874347 -71.384302) (xy 130.866589 -71.330352) (xy 116.480376 -71.330352)
			(xy 116.475889 -71.340122) (xy 116.446162 -71.386089) (xy 116.42852 -71.40702) (xy 116.422424 -71.414132)
			(xy 116.416074 -71.43115) (xy 116.416074 -71.516494) (xy 116.422424 -71.533512) (xy 116.42852 -71.540624)
			(xy 116.44614 -71.561571) (xy 116.475854 -71.60754) (xy 116.498693 -71.657284) (xy 116.514189 -71.709781)
			(xy 116.522023 -71.763954) (xy 116.5225 -71.791322) (xy 116.522094 -71.817196) (xy 116.515108 -71.86847)
			(xy 116.501254 -71.918328) (xy 116.480786 -71.965856) (xy 116.454081 -72.01018) (xy 116.421628 -72.050487)
			(xy 116.384023 -72.086036) (xy 116.363242 -72.101456) (xy 116.355622 -72.107044) (xy 116.345208 -72.122792)
			(xy 116.327174 -72.208644) (xy 116.330222 -72.22744) (xy 116.335048 -72.235568) (xy 116.347727 -72.257734)
			(xy 116.367675 -72.304741) (xy 116.381173 -72.35399) (xy 116.387981 -72.404599) (xy 116.388388 -72.430132)
			(xy 116.387902 -72.457383) (xy 116.380146 -72.511331) (xy 116.364791 -72.563626) (xy 116.363697 -72.566022)
			(xy 119.059704 -72.566022) (xy 119.063775 -72.5104) (xy 119.075901 -72.455963) (xy 119.095824 -72.403872)
			(xy 119.12312 -72.355237) (xy 119.157206 -72.311094) (xy 119.197355 -72.272385) (xy 119.242713 -72.239934)
			(xy 119.292313 -72.214433) (xy 119.345097 -72.196426) (xy 119.39994 -72.186296) (xy 119.455674 -72.184259)
			(xy 119.511111 -72.190359) (xy 119.565068 -72.204465) (xy 119.616397 -72.226277) (xy 119.664003 -72.255331)
			(xy 119.706871 -72.291006) (xy 119.744088 -72.332543) (xy 119.774861 -72.379056) (xy 119.798533 -72.429553)
			(xy 119.814601 -72.48296) (xy 119.822721 -72.538136) (xy 119.82323 -72.566022) (xy 119.822721 -72.593908)
			(xy 119.819349 -72.616822) (xy 122.509024 -72.616822) (xy 122.513095 -72.5612) (xy 122.525221 -72.506763)
			(xy 122.545144 -72.454672) (xy 122.57244 -72.406037) (xy 122.606526 -72.361894) (xy 122.646675 -72.323185)
			(xy 122.692033 -72.290734) (xy 122.741633 -72.265233) (xy 122.794417 -72.247226) (xy 122.84926 -72.237096)
			(xy 122.904994 -72.235059) (xy 122.960431 -72.241159) (xy 123.014388 -72.255265) (xy 123.065717 -72.277077)
			(xy 123.113323 -72.306131) (xy 123.156191 -72.341806) (xy 123.193408 -72.383343) (xy 123.224181 -72.429856)
			(xy 123.247853 -72.480353) (xy 123.263921 -72.53376) (xy 123.272041 -72.588936) (xy 123.27255 -72.616822)
			(xy 123.272041 -72.644708) (xy 123.263921 -72.699884) (xy 123.247853 -72.753291) (xy 123.224181 -72.803788)
			(xy 123.193408 -72.850301) (xy 123.156191 -72.891838) (xy 123.113323 -72.927513) (xy 123.065717 -72.956567)
			(xy 123.014388 -72.978379) (xy 122.960431 -72.992485) (xy 122.904994 -72.998585) (xy 122.84926 -72.996548)
			(xy 122.794417 -72.986418) (xy 122.741633 -72.968411) (xy 122.692033 -72.94291) (xy 122.646675 -72.910459)
			(xy 122.606526 -72.87175) (xy 122.57244 -72.827607) (xy 122.545144 -72.778972) (xy 122.525221 -72.726881)
			(xy 122.513095 -72.672444) (xy 122.509024 -72.616822) (xy 119.819349 -72.616822) (xy 119.814601 -72.649084)
			(xy 119.798533 -72.702491) (xy 119.774861 -72.752988) (xy 119.744088 -72.799501) (xy 119.706871 -72.841038)
			(xy 119.664003 -72.876713) (xy 119.616397 -72.905767) (xy 119.565068 -72.927579) (xy 119.511111 -72.941685)
			(xy 119.455674 -72.947785) (xy 119.39994 -72.945748) (xy 119.345097 -72.935618) (xy 119.292313 -72.917611)
			(xy 119.242713 -72.89211) (xy 119.197355 -72.859659) (xy 119.157206 -72.82095) (xy 119.12312 -72.776807)
			(xy 119.095824 -72.728172) (xy 119.075901 -72.676081) (xy 119.063775 -72.621644) (xy 119.059704 -72.566022)
			(xy 116.363697 -72.566022) (xy 116.342149 -72.613203) (xy 116.312683 -72.659053) (xy 116.276992 -72.700244)
			(xy 116.235801 -72.735935) (xy 116.189951 -72.765401) (xy 116.140374 -72.788043) (xy 116.088079 -72.803398)
			(xy 116.034131 -72.811154) (xy 115.979629 -72.811154) (xy 115.925681 -72.803398) (xy 115.873386 -72.788043)
			(xy 115.823809 -72.765401) (xy 115.777959 -72.735935) (xy 115.736768 -72.700244) (xy 115.701077 -72.659053)
			(xy 115.671611 -72.613203) (xy 115.648969 -72.563626) (xy 115.633614 -72.511331) (xy 115.625858 -72.457383)
			(xy 115.625372 -72.430132) (xy 115.625788 -72.404258) (xy 115.632769 -72.352983) (xy 115.646618 -72.303124)
			(xy 115.667084 -72.255595) (xy 115.693788 -72.21127) (xy 115.726242 -72.170964) (xy 115.763848 -72.135417)
			(xy 115.78463 -72.119998) (xy 115.79225 -72.11441) (xy 115.802664 -72.098662) (xy 115.820698 -72.01281)
			(xy 115.81765 -71.994014) (xy 115.812824 -71.985886) (xy 115.800164 -71.96371) (xy 115.780212 -71.916706)
			(xy 115.766708 -71.86746) (xy 115.759894 -71.816854) (xy 115.759484 -71.791322) (xy 115.7605 -71.763128)
			(xy 115.761516 -71.749666) (xy 115.749578 -71.725028) (xy 115.654074 -71.660258) (xy 115.626896 -71.65848)
			(xy 115.614704 -71.664322) (xy 115.588549 -71.676514) (xy 115.533469 -71.693715) (xy 115.476424 -71.702406)
			(xy 115.447572 -71.70293) (xy 115.420324 -71.702398) (xy 115.366382 -71.694639) (xy 115.314094 -71.679282)
			(xy 115.264523 -71.656641) (xy 115.218679 -71.627175) (xy 115.177494 -71.591486) (xy 115.141808 -71.550299)
			(xy 115.112346 -71.504452) (xy 115.089708 -71.45488) (xy 115.074355 -71.40259) (xy 115.0666 -71.348648)
			(xy 113.833148 -71.348648) (xy 113.833148 -73.442156) (xy 130.485545 -73.442156) (xy 130.485545 -73.387644)
			(xy 130.493303 -73.333688) (xy 130.508662 -73.281386) (xy 130.531308 -73.231801) (xy 130.560781 -73.185945)
			(xy 130.59648 -73.14475) (xy 130.637679 -73.109056) (xy 130.683538 -73.079588) (xy 130.733125 -73.056947)
			(xy 130.785429 -73.041594) (xy 130.839386 -73.033842) (xy 130.866642 -73.033382) (xy 130.894351 -73.033879)
			(xy 130.949186 -73.041908) (xy 131.00228 -73.057789) (xy 131.052516 -73.081189) (xy 131.098836 -73.111614)
			(xy 131.11988 -73.129648) (xy 131.126992 -73.135744) (xy 131.144264 -73.142348) (xy 131.23037 -73.142348)
			(xy 131.247642 -73.135744) (xy 131.254754 -73.129648) (xy 131.275797 -73.111614) (xy 131.322117 -73.081188)
			(xy 131.372353 -73.05779) (xy 131.425448 -73.041912) (xy 131.480283 -73.033888) (xy 131.535701 -73.033888)
			(xy 131.590536 -73.041912) (xy 131.643631 -73.05779) (xy 131.693867 -73.081188) (xy 131.740187 -73.111614)
			(xy 131.76123 -73.129648) (xy 131.768342 -73.135744) (xy 131.785614 -73.142348) (xy 131.87172 -73.142348)
			(xy 131.888992 -73.135744) (xy 131.896104 -73.129648) (xy 131.917147 -73.111614) (xy 131.963467 -73.081188)
			(xy 132.013703 -73.05779) (xy 132.066798 -73.041912) (xy 132.121633 -73.033888) (xy 132.177051 -73.033888)
			(xy 132.231886 -73.041912) (xy 132.284981 -73.05779) (xy 132.335217 -73.081188) (xy 132.381537 -73.111614)
			(xy 132.40258 -73.129648) (xy 132.409692 -73.135744) (xy 132.426964 -73.142348) (xy 132.51307 -73.142348)
			(xy 132.530342 -73.135744) (xy 132.537454 -73.129648) (xy 132.5585 -73.111616) (xy 132.604817 -73.081187)
			(xy 132.655053 -73.057786) (xy 132.708148 -73.041905) (xy 132.762983 -73.03388) (xy 132.790692 -73.033382)
			(xy 132.817945 -73.033865) (xy 132.871895 -73.041621) (xy 132.924192 -73.056976) (xy 132.973772 -73.079617)
			(xy 133.019625 -73.109084) (xy 133.060818 -73.144777) (xy 133.096511 -73.185969) (xy 133.125979 -73.231821)
			(xy 133.148622 -73.2814) (xy 133.163978 -73.333697) (xy 133.171735 -73.387647) (xy 133.171735 -73.442153)
			(xy 133.163978 -73.496103) (xy 133.148622 -73.5484) (xy 133.125979 -73.597979) (xy 133.096511 -73.643831)
			(xy 133.060818 -73.685023) (xy 133.019625 -73.720716) (xy 132.973772 -73.750183) (xy 132.924192 -73.772824)
			(xy 132.871895 -73.788179) (xy 132.817945 -73.795935) (xy 132.790692 -73.796398) (xy 132.762983 -73.795886)
			(xy 132.708149 -73.787862) (xy 132.655055 -73.771984) (xy 132.604818 -73.748588) (xy 132.558498 -73.718165)
			(xy 132.537454 -73.700132) (xy 132.530342 -73.694036) (xy 132.51307 -73.687432) (xy 132.426964 -73.687432)
			(xy 132.409692 -73.694036) (xy 132.40258 -73.700132) (xy 132.381537 -73.718166) (xy 132.335217 -73.748592)
			(xy 132.284981 -73.77199) (xy 132.231886 -73.787868) (xy 132.177051 -73.795892) (xy 132.121633 -73.795892)
			(xy 132.066798 -73.787868) (xy 132.013703 -73.77199) (xy 131.963467 -73.748592) (xy 131.917147 -73.718166)
			(xy 131.896104 -73.700132) (xy 131.888992 -73.694036) (xy 131.87172 -73.687432) (xy 131.785614 -73.687432)
			(xy 131.768342 -73.694036) (xy 131.76123 -73.700132) (xy 131.740187 -73.718166) (xy 131.693867 -73.748592)
			(xy 131.643631 -73.77199) (xy 131.590536 -73.787868) (xy 131.535701 -73.795892) (xy 131.480283 -73.795892)
			(xy 131.425448 -73.787868) (xy 131.372353 -73.77199) (xy 131.322117 -73.748592) (xy 131.275797 -73.718166)
			(xy 131.254754 -73.700132) (xy 131.247642 -73.694036) (xy 131.23037 -73.687432) (xy 131.144264 -73.687432)
			(xy 131.126992 -73.694036) (xy 131.11988 -73.700132) (xy 131.098857 -73.718192) (xy 131.052533 -73.748617)
			(xy 131.002292 -73.772013) (xy 130.949192 -73.787888) (xy 130.894353 -73.795905) (xy 130.866642 -73.796398)
			(xy 130.839386 -73.795958) (xy 130.785429 -73.788206) (xy 130.733125 -73.772853) (xy 130.683538 -73.750212)
			(xy 130.637679 -73.720744) (xy 130.59648 -73.68505) (xy 130.560781 -73.643855) (xy 130.531308 -73.597999)
			(xy 130.508662 -73.548414) (xy 130.493303 -73.496112) (xy 130.485545 -73.442156) (xy 113.833148 -73.442156)
			(xy 113.833148 -74.038968) (xy 120.219214 -74.038968) (xy 120.223285 -73.983346) (xy 120.235411 -73.928909)
			(xy 120.255334 -73.876818) (xy 120.28263 -73.828183) (xy 120.316716 -73.78404) (xy 120.356865 -73.745331)
			(xy 120.402223 -73.71288) (xy 120.451823 -73.687379) (xy 120.504607 -73.669372) (xy 120.55945 -73.659242)
			(xy 120.615184 -73.657205) (xy 120.670621 -73.663305) (xy 120.724578 -73.677411) (xy 120.775907 -73.699223)
			(xy 120.823513 -73.728277) (xy 120.866381 -73.763952) (xy 120.903598 -73.805489) (xy 120.934371 -73.852002)
			(xy 120.958043 -73.902499) (xy 120.974111 -73.955906) (xy 120.982231 -74.011082) (xy 120.982314 -74.015652)
			(xy 122.273777 -74.015652) (xy 122.273777 -73.961148) (xy 122.281534 -73.907198) (xy 122.296891 -73.854901)
			(xy 122.319533 -73.805323) (xy 122.349002 -73.759471) (xy 122.384696 -73.71828) (xy 122.425889 -73.682589)
			(xy 122.471742 -73.653123) (xy 122.521322 -73.630483) (xy 122.57362 -73.61513) (xy 122.62757 -73.607376)
			(xy 122.654822 -73.606914) (xy 122.684157 -73.607438) (xy 122.742138 -73.616412) (xy 122.79806 -73.634158)
			(xy 122.850605 -73.660259) (xy 122.898533 -73.694099) (xy 122.919998 -73.714102) (xy 122.930403 -73.723572)
			(xy 122.955184 -73.736877) (xy 122.982652 -73.742927) (xy 123.010729 -73.741263) (xy 123.037291 -73.732012)
			(xy 123.060327 -73.715873) (xy 123.078093 -73.694068) (xy 123.084082 -73.681336) (xy 123.095504 -73.656036)
			(xy 123.124646 -73.60879) (xy 123.160328 -73.566267) (xy 123.201797 -73.529366) (xy 123.248177 -73.498865)
			(xy 123.298488 -73.475409) (xy 123.351668 -73.459494) (xy 123.406593 -73.451454) (xy 123.434348 -73.450958)
			(xy 123.461595 -73.451515) (xy 123.515532 -73.459277) (xy 123.567816 -73.474635) (xy 123.617383 -73.497277)
			(xy 123.663223 -73.526741) (xy 123.704404 -73.56243) (xy 123.740087 -73.603615) (xy 123.769546 -73.649459)
			(xy 123.792182 -73.699029) (xy 123.807533 -73.751315) (xy 123.815288 -73.805253) (xy 123.815288 -73.859747)
			(xy 123.807533 -73.913685) (xy 123.792182 -73.965971) (xy 123.769546 -74.015541) (xy 123.740087 -74.061385)
			(xy 123.704404 -74.10257) (xy 123.663223 -74.138259) (xy 123.617383 -74.167723) (xy 123.567816 -74.190365)
			(xy 123.515532 -74.205723) (xy 123.461595 -74.213485) (xy 123.434348 -74.213974) (xy 123.405014 -74.21341)
			(xy 123.347035 -74.204447) (xy 123.291113 -74.18671) (xy 123.238567 -74.160618) (xy 123.190638 -74.126786)
			(xy 123.169172 -74.106786) (xy 123.158793 -74.097285) (xy 123.134005 -74.083984) (xy 123.106531 -74.077939)
			(xy 123.078449 -74.079608) (xy 123.051884 -74.088865) (xy 123.028846 -74.105008) (xy 123.011077 -74.126817)
			(xy 123.005088 -74.139552) (xy 122.993604 -74.164823) (xy 122.964471 -74.212067) (xy 122.928797 -74.254589)
			(xy 122.887337 -74.291493) (xy 122.840967 -74.321997) (xy 122.790664 -74.345458) (xy 122.737492 -74.361381)
			(xy 122.682574 -74.369429) (xy 122.654822 -74.36993) (xy 122.62757 -74.369424) (xy 122.573619 -74.36167)
			(xy 122.521322 -74.346317) (xy 122.471742 -74.323677) (xy 122.425889 -74.294211) (xy 122.384696 -74.25852)
			(xy 122.349002 -74.217329) (xy 122.319533 -74.171477) (xy 122.296891 -74.121899) (xy 122.281534 -74.069602)
			(xy 122.273777 -74.015652) (xy 120.982314 -74.015652) (xy 120.98274 -74.038968) (xy 120.982231 -74.066854)
			(xy 120.974111 -74.12203) (xy 120.958043 -74.175437) (xy 120.934371 -74.225934) (xy 120.903598 -74.272447)
			(xy 120.866381 -74.313984) (xy 120.823513 -74.349659) (xy 120.775907 -74.378713) (xy 120.724578 -74.400525)
			(xy 120.670621 -74.414631) (xy 120.615184 -74.420731) (xy 120.55945 -74.418694) (xy 120.504607 -74.408564)
			(xy 120.451823 -74.390557) (xy 120.402223 -74.365056) (xy 120.356865 -74.332605) (xy 120.316716 -74.293896)
			(xy 120.28263 -74.249753) (xy 120.255334 -74.201118) (xy 120.235411 -74.149027) (xy 120.223285 -74.09459)
			(xy 120.219214 -74.038968) (xy 113.833148 -74.038968) (xy 113.833148 -78.016862) (xy 121.734324 -78.016862)
			(xy 121.738395 -77.96124) (xy 121.750521 -77.906803) (xy 121.770444 -77.854712) (xy 121.79774 -77.806077)
			(xy 121.831826 -77.761934) (xy 121.871975 -77.723225) (xy 121.917333 -77.690774) (xy 121.966933 -77.665273)
			(xy 122.019717 -77.647266) (xy 122.07456 -77.637136) (xy 122.130294 -77.635099) (xy 122.174162 -77.639926)
			(xy 122.569984 -77.639926) (xy 122.574055 -77.584304) (xy 122.586181 -77.529867) (xy 122.606104 -77.477776)
			(xy 122.6334 -77.429141) (xy 122.667486 -77.384998) (xy 122.707635 -77.346289) (xy 122.752993 -77.313838)
			(xy 122.802593 -77.288337) (xy 122.855377 -77.27033) (xy 122.91022 -77.2602) (xy 122.965954 -77.258163)
			(xy 123.021391 -77.264263) (xy 123.075348 -77.278369) (xy 123.126677 -77.300181) (xy 123.174283 -77.329235)
			(xy 123.217151 -77.36491) (xy 123.254368 -77.406447) (xy 123.285141 -77.45296) (xy 123.308813 -77.503457)
			(xy 123.318018 -77.534053) (xy 130.485585 -77.534053) (xy 130.485585 -77.479547) (xy 130.493343 -77.425597)
			(xy 130.5087 -77.3733) (xy 130.531344 -77.323721) (xy 130.560813 -77.277869) (xy 130.596509 -77.236679)
			(xy 130.637703 -77.200988) (xy 130.683558 -77.171523) (xy 130.733139 -77.148885) (xy 130.785438 -77.133534)
			(xy 130.839389 -77.125782) (xy 130.866642 -77.125322) (xy 130.894352 -77.125809) (xy 130.949187 -77.133838)
			(xy 131.002282 -77.149722) (xy 131.052518 -77.173124) (xy 131.098837 -77.203553) (xy 131.11988 -77.221588)
			(xy 131.126992 -77.227684) (xy 131.144264 -77.234288) (xy 131.23037 -77.234288) (xy 131.247642 -77.227684)
			(xy 131.254754 -77.221588) (xy 131.275797 -77.203554) (xy 131.322117 -77.173128) (xy 131.372353 -77.14973)
			(xy 131.425448 -77.133852) (xy 131.480283 -77.125828) (xy 131.535701 -77.125828) (xy 131.590536 -77.133852)
			(xy 131.643631 -77.14973) (xy 131.693867 -77.173128) (xy 131.740187 -77.203554) (xy 131.76123 -77.221588)
			(xy 131.768342 -77.227684) (xy 131.785614 -77.234288) (xy 131.87172 -77.234288) (xy 131.888992 -77.227684)
			(xy 131.896104 -77.221588) (xy 131.917136 -77.203539) (xy 131.963457 -77.173111) (xy 132.013696 -77.149713)
			(xy 132.066794 -77.133836) (xy 132.121631 -77.125816) (xy 132.149342 -77.125322) (xy 132.176593 -77.125751)
			(xy 132.230541 -77.133513) (xy 132.282835 -77.148873) (xy 132.332411 -77.171518) (xy 132.378259 -77.200988)
			(xy 132.419448 -77.236682) (xy 132.455137 -77.277874) (xy 132.484602 -77.323726) (xy 132.507242 -77.373305)
			(xy 132.522596 -77.4256) (xy 132.530352 -77.479549) (xy 132.530352 -77.534051) (xy 132.522596 -77.588)
			(xy 132.507242 -77.640295) (xy 132.484602 -77.689874) (xy 132.455137 -77.735726) (xy 132.419448 -77.776918)
			(xy 132.378259 -77.812612) (xy 132.33241 -77.842082) (xy 132.282835 -77.864727) (xy 132.230541 -77.880087)
			(xy 132.176593 -77.887849) (xy 132.149342 -77.888338) (xy 132.121633 -77.887845) (xy 132.066798 -77.879815)
			(xy 132.013704 -77.863932) (xy 131.963468 -77.840532) (xy 131.917148 -77.810106) (xy 131.896104 -77.792072)
			(xy 131.888992 -77.785976) (xy 131.87172 -77.779372) (xy 131.785614 -77.779372) (xy 131.768342 -77.785976)
			(xy 131.76123 -77.792072) (xy 131.740187 -77.810106) (xy 131.693867 -77.840532) (xy 131.643631 -77.86393)
			(xy 131.590536 -77.879808) (xy 131.535701 -77.887832) (xy 131.480283 -77.887832) (xy 131.425448 -77.879808)
			(xy 131.372353 -77.86393) (xy 131.322117 -77.840532) (xy 131.275797 -77.810106) (xy 131.254754 -77.792072)
			(xy 131.247642 -77.785976) (xy 131.23037 -77.779372) (xy 131.144264 -77.779372) (xy 131.126992 -77.785976)
			(xy 131.11988 -77.792072) (xy 131.098849 -77.810122) (xy 131.052528 -77.840551) (xy 131.002289 -77.86395)
			(xy 130.949191 -77.879826) (xy 130.894353 -77.887844) (xy 130.866642 -77.888338) (xy 130.839389 -77.887818)
			(xy 130.785438 -77.880066) (xy 130.733139 -77.864715) (xy 130.683558 -77.842077) (xy 130.637703 -77.812612)
			(xy 130.596509 -77.776921) (xy 130.560813 -77.735731) (xy 130.531344 -77.689879) (xy 130.5087 -77.6403)
			(xy 130.493343 -77.588003) (xy 130.485585 -77.534053) (xy 123.318018 -77.534053) (xy 123.324881 -77.556864)
			(xy 123.333001 -77.61204) (xy 123.33351 -77.639926) (xy 123.333001 -77.667812) (xy 123.324881 -77.722988)
			(xy 123.308813 -77.776395) (xy 123.285141 -77.826892) (xy 123.254368 -77.873405) (xy 123.217151 -77.914942)
			(xy 123.174283 -77.950617) (xy 123.126677 -77.979671) (xy 123.075348 -78.001483) (xy 123.021391 -78.015589)
			(xy 122.965954 -78.021689) (xy 122.91022 -78.019652) (xy 122.855377 -78.009522) (xy 122.802593 -77.991515)
			(xy 122.752993 -77.966014) (xy 122.707635 -77.933563) (xy 122.667486 -77.894854) (xy 122.6334 -77.850711)
			(xy 122.606104 -77.802076) (xy 122.586181 -77.749985) (xy 122.574055 -77.695548) (xy 122.569984 -77.639926)
			(xy 122.174162 -77.639926) (xy 122.185731 -77.641199) (xy 122.239688 -77.655305) (xy 122.291017 -77.677117)
			(xy 122.338623 -77.706171) (xy 122.381491 -77.741846) (xy 122.418708 -77.783383) (xy 122.449481 -77.829896)
			(xy 122.473153 -77.880393) (xy 122.489221 -77.9338) (xy 122.497341 -77.988976) (xy 122.49785 -78.016862)
			(xy 122.497341 -78.044748) (xy 122.489221 -78.099924) (xy 122.473153 -78.153331) (xy 122.449481 -78.203828)
			(xy 122.418708 -78.250341) (xy 122.381491 -78.291878) (xy 122.338623 -78.327553) (xy 122.291017 -78.356607)
			(xy 122.239688 -78.378419) (xy 122.185731 -78.392525) (xy 122.130294 -78.398625) (xy 122.07456 -78.396588)
			(xy 122.019717 -78.386458) (xy 121.966933 -78.368451) (xy 121.917333 -78.34295) (xy 121.871975 -78.310499)
			(xy 121.831826 -78.27179) (xy 121.79774 -78.227647) (xy 121.770444 -78.179012) (xy 121.750521 -78.126921)
			(xy 121.738395 -78.072484) (xy 121.734324 -78.016862) (xy 113.833148 -78.016862) (xy 113.833148 -79.580055)
			(xy 130.485555 -79.580055) (xy 130.485555 -79.525545) (xy 130.493314 -79.471591) (xy 130.508672 -79.419289)
			(xy 130.531317 -79.369707) (xy 130.560789 -79.323851) (xy 130.596487 -79.282658) (xy 130.637685 -79.246964)
			(xy 130.683543 -79.217497) (xy 130.733129 -79.194857) (xy 130.785432 -79.179505) (xy 130.839387 -79.171752)
			(xy 130.866642 -79.171292) (xy 130.894351 -79.171787) (xy 130.949186 -79.179815) (xy 131.00228 -79.195697)
			(xy 131.052517 -79.219098) (xy 131.098836 -79.249524) (xy 131.11988 -79.267558) (xy 131.126992 -79.273654)
			(xy 131.144264 -79.280258) (xy 131.23037 -79.280258) (xy 131.247642 -79.273654) (xy 131.254754 -79.267558)
			(xy 131.275797 -79.249524) (xy 131.322117 -79.219098) (xy 131.372353 -79.1957) (xy 131.425448 -79.179822)
			(xy 131.480283 -79.171798) (xy 131.535701 -79.171798) (xy 131.590536 -79.179822) (xy 131.643631 -79.1957)
			(xy 131.693867 -79.219098) (xy 131.740187 -79.249524) (xy 131.76123 -79.267558) (xy 131.768342 -79.273654)
			(xy 131.785614 -79.280258) (xy 131.87172 -79.280258) (xy 131.888992 -79.273654) (xy 131.896104 -79.267558)
			(xy 131.917132 -79.249504) (xy 131.963454 -79.219078) (xy 132.013695 -79.195681) (xy 132.066793 -79.179805)
			(xy 132.121631 -79.171786) (xy 132.149342 -79.171292) (xy 132.176591 -79.171781) (xy 132.230534 -79.179542)
			(xy 132.282824 -79.194901) (xy 132.332396 -79.217544) (xy 132.378241 -79.247012) (xy 132.419426 -79.282703)
			(xy 132.455113 -79.323892) (xy 132.484576 -79.369741) (xy 132.507214 -79.419315) (xy 132.522567 -79.471607)
			(xy 132.530322 -79.525551) (xy 132.530322 -79.580049) (xy 132.522567 -79.633993) (xy 132.507214 -79.686285)
			(xy 132.484576 -79.735859) (xy 132.455113 -79.781708) (xy 132.419426 -79.822897) (xy 132.378241 -79.858588)
			(xy 132.332396 -79.888056) (xy 132.282824 -79.910699) (xy 132.230534 -79.926058) (xy 132.176591 -79.933819)
			(xy 132.149342 -79.934308) (xy 132.121632 -79.933823) (xy 132.066797 -79.925792) (xy 132.013703 -79.909908)
			(xy 131.963467 -79.886505) (xy 131.917147 -79.856077) (xy 131.896104 -79.838042) (xy 131.888992 -79.831946)
			(xy 131.87172 -79.825342) (xy 131.785614 -79.825342) (xy 131.768342 -79.831946) (xy 131.76123 -79.838042)
			(xy 131.740187 -79.856076) (xy 131.693867 -79.886502) (xy 131.643631 -79.9099) (xy 131.590536 -79.925778)
			(xy 131.535701 -79.933802) (xy 131.480283 -79.933802) (xy 131.425448 -79.925778) (xy 131.372353 -79.9099)
			(xy 131.322117 -79.886502) (xy 131.275797 -79.856076) (xy 131.254754 -79.838042) (xy 131.247642 -79.831946)
			(xy 131.23037 -79.825342) (xy 131.144264 -79.825342) (xy 131.126992 -79.831946) (xy 131.11988 -79.838042)
			(xy 131.098859 -79.856103) (xy 131.052534 -79.886528) (xy 131.002292 -79.909924) (xy 130.949192 -79.925798)
			(xy 130.894353 -79.933815) (xy 130.866642 -79.934308) (xy 130.839387 -79.933848) (xy 130.785432 -79.926095)
			(xy 130.733129 -79.910743) (xy 130.683543 -79.888103) (xy 130.637685 -79.858636) (xy 130.596487 -79.822942)
			(xy 130.560789 -79.781749) (xy 130.531317 -79.735893) (xy 130.508672 -79.686311) (xy 130.493314 -79.634009)
			(xy 130.485555 -79.580055) (xy 113.833148 -79.580055) (xy 113.833148 -80.137508) (xy 121.321574 -80.137508)
			(xy 121.325645 -80.081886) (xy 121.337771 -80.027449) (xy 121.357694 -79.975358) (xy 121.38499 -79.926723)
			(xy 121.419076 -79.88258) (xy 121.459225 -79.843871) (xy 121.504583 -79.81142) (xy 121.554183 -79.785919)
			(xy 121.606967 -79.767912) (xy 121.66181 -79.757782) (xy 121.717544 -79.755745) (xy 121.772981 -79.761845)
			(xy 121.826938 -79.775951) (xy 121.878267 -79.797763) (xy 121.925873 -79.826817) (xy 121.968741 -79.862492)
			(xy 122.005958 -79.904029) (xy 122.036731 -79.950542) (xy 122.060403 -80.001039) (xy 122.076471 -80.054446)
			(xy 122.084591 -80.109622) (xy 122.0851 -80.137508) (xy 122.084591 -80.165394) (xy 122.076471 -80.22057)
			(xy 122.060403 -80.273977) (xy 122.036731 -80.324474) (xy 122.005958 -80.370987) (xy 121.968741 -80.412524)
			(xy 121.925873 -80.448199) (xy 121.878267 -80.477253) (xy 121.826938 -80.499065) (xy 121.772981 -80.513171)
			(xy 121.717544 -80.519271) (xy 121.66181 -80.517234) (xy 121.606967 -80.507104) (xy 121.554183 -80.489097)
			(xy 121.504583 -80.463596) (xy 121.459225 -80.431145) (xy 121.419076 -80.392436) (xy 121.38499 -80.348293)
			(xy 121.357694 -80.299658) (xy 121.337771 -80.247567) (xy 121.325645 -80.19313) (xy 121.321574 -80.137508)
			(xy 113.833148 -80.137508) (xy 113.833148 -81.241138) (xy 113.83361 -81.251015) (xy 113.841053 -81.269313)
			(xy 113.847626 -81.276698) (xy 113.84788 -81.276952) (xy 113.868962 -81.298034) (xy 113.86947 -81.298542)
			(xy 113.876851 -81.305123) (xy 113.895151 -81.312569) (xy 113.90503 -81.31302)
		)
		(stroke
			(width 0)
			(type solid)
		)
		(fill yes)
		(layer "In13.Cu")
		(net "GND")
	)
	(gr_poly
		(pts
			(xy 251.944886 -52.876958) (xy 251.954759 -52.876487) (xy 251.973045 -52.869033) (xy 251.980446 -52.86248)
			(xy 251.9807 -52.862226) (xy 252.546358 -52.296568) (xy 252.546866 -52.29606) (xy 252.553449 -52.288679)
			(xy 252.560902 -52.27038) (xy 252.561344 -52.2605) (xy 252.561344 -47.194978) (xy 252.560874 -47.18467)
			(xy 252.55276 -47.165721) (xy 252.53782 -47.151518) (xy 252.528324 -47.14748) (xy 252.424438 -47.108364)
			(xy 252.393958 -47.115984) (xy 252.38329 -47.127922) (xy 252.3651 -47.147961) (xy 252.324036 -47.183211)
			(xy 252.278401 -47.212301) (xy 252.229111 -47.234646) (xy 252.177157 -47.249799) (xy 252.123583 -47.257454)
			(xy 252.096524 -47.25797) (xy 252.069273 -47.257508) (xy 252.015325 -47.249755) (xy 251.963029 -47.234403)
			(xy 251.913451 -47.211764) (xy 251.867599 -47.182299) (xy 251.826408 -47.146609) (xy 251.790715 -47.10542)
			(xy 251.761248 -47.05957) (xy 251.738606 -47.009993) (xy 251.72325 -46.957699) (xy 251.715493 -46.903751)
			(xy 251.715493 -46.849249) (xy 251.72325 -46.795301) (xy 251.738606 -46.743007) (xy 251.761248 -46.69343)
			(xy 251.790715 -46.64758) (xy 251.826408 -46.606391) (xy 251.867599 -46.570701) (xy 251.913451 -46.541236)
			(xy 251.963029 -46.518597) (xy 252.015325 -46.503245) (xy 252.069273 -46.495492) (xy 252.096524 -46.494954)
			(xy 252.123584 -46.495429) (xy 252.17716 -46.503088) (xy 252.229114 -46.518249) (xy 252.278401 -46.540607)
			(xy 252.324029 -46.569711) (xy 252.365082 -46.604977) (xy 252.38329 -46.625002) (xy 252.393958 -46.63694)
			(xy 252.424438 -46.64456) (xy 252.528324 -46.605444) (xy 252.537793 -46.601378) (xy 252.55268 -46.587157)
			(xy 252.560803 -46.568239) (xy 252.561344 -46.557946) (xy 252.561344 -45.671486) (xy 252.560697 -45.658934)
			(xy 252.548832 -45.636812) (xy 252.538738 -45.629322) (xy 252.457712 -45.57522) (xy 252.43282 -45.57268)
			(xy 252.420882 -45.57776) (xy 252.397568 -45.587007) (xy 252.349127 -45.60001) (xy 252.299402 -45.606569)
			(xy 252.274324 -45.60697) (xy 252.269752 -45.60697) (xy 252.242582 -45.606159) (xy 252.188875 -45.597793)
			(xy 252.136897 -45.581893) (xy 252.087701 -45.558781) (xy 252.042281 -45.528922) (xy 252.001556 -45.492923)
			(xy 251.96635 -45.45151) (xy 251.937375 -45.405522) (xy 251.925836 -45.38091) (xy 251.921518 -45.371004)
			(xy 251.906024 -45.357034) (xy 251.814838 -45.326046) (xy 251.79401 -45.327824) (xy 251.784612 -45.333158)
			(xy 251.745416 -45.353829) (xy 251.663729 -45.388187) (xy 251.57903 -45.414255) (xy 251.492161 -45.431773)
			(xy 251.403979 -45.44057) (xy 251.35967 -45.441108) (xy 251.317834 -45.440631) (xy 251.234532 -45.432779)
			(xy 251.152336 -45.417136) (xy 251.071972 -45.393843) (xy 250.994152 -45.363103) (xy 250.919563 -45.325191)
			(xy 250.848865 -45.280439) (xy 250.782683 -45.229245) (xy 250.721602 -45.172061) (xy 250.666162 -45.109393)
			(xy 250.616854 -45.041794) (xy 250.574113 -44.969863) (xy 250.538318 -44.894235) (xy 250.509785 -44.815579)
			(xy 250.488765 -44.734591) (xy 250.475446 -44.651986) (xy 250.472194 -44.610274) (xy 250.471221 -44.600884)
			(xy 250.463272 -44.583776) (xy 250.4567 -44.577) (xy 250.434856 -44.556172) (xy 250.427792 -44.549953)
			(xy 250.41046 -44.542658) (xy 250.401074 -44.541948) (xy 250.358152 -44.540314) (xy 250.272897 -44.529813)
			(xy 250.189052 -44.511141) (xy 250.107397 -44.484473) (xy 250.028694 -44.450057) (xy 249.953675 -44.408214)
			(xy 249.883039 -44.359333) (xy 249.817445 -44.30387) (xy 249.757504 -44.242342) (xy 249.703773 -44.175322)
			(xy 249.656754 -44.103434) (xy 249.616884 -44.027348) (xy 249.584536 -43.947772) (xy 249.56001 -43.865448)
			(xy 249.543534 -43.781144) (xy 249.535263 -43.695644) (xy 249.53468 -43.652694) (xy 249.535183 -43.610457)
			(xy 249.543203 -43.526364) (xy 249.55916 -43.44341) (xy 249.58291 -43.362343) (xy 249.61424 -43.283893)
			(xy 249.652867 -43.208767) (xy 249.698443 -43.137642) (xy 249.750558 -43.071159) (xy 249.808741 -43.009917)
			(xy 249.872469 -42.954467) (xy 249.941168 -42.905309) (xy 250.014218 -42.862887) (xy 250.090961 -42.827582)
			(xy 250.170706 -42.799713) (xy 250.21159 -42.789094) (xy 250.220743 -42.78637) (xy 250.236274 -42.775281)
			(xy 250.241816 -42.767504) (xy 250.25858 -42.742104) (xy 250.26334 -42.733862) (xy 250.267126 -42.715226)
			(xy 250.265946 -42.705782) (xy 250.259966 -42.668479) (xy 250.253609 -42.593192) (xy 250.253246 -42.555414)
			(xy 250.25375 -42.513066) (xy 250.261801 -42.428752) (xy 250.27783 -42.345586) (xy 250.301691 -42.264319)
			(xy 250.33317 -42.185689) (xy 250.371981 -42.110408) (xy 250.417771 -42.039156) (xy 250.470127 -41.97258)
			(xy 250.528575 -41.911282) (xy 250.592585 -41.855817) (xy 250.661577 -41.806688) (xy 250.734927 -41.764339)
			(xy 250.81197 -41.729155) (xy 250.892009 -41.701453) (xy 250.974318 -41.681485) (xy 251.058153 -41.669432)
			(xy 251.142754 -41.665402) (xy 251.227355 -41.669432) (xy 251.31119 -41.681485) (xy 251.393499 -41.701453)
			(xy 251.473538 -41.729155) (xy 251.550581 -41.764339) (xy 251.623931 -41.806688) (xy 251.692923 -41.855817)
			(xy 251.756933 -41.911282) (xy 251.815381 -41.97258) (xy 251.867737 -42.039156) (xy 251.913527 -42.110408)
			(xy 251.952338 -42.185689) (xy 251.983817 -42.264319) (xy 252.007678 -42.345586) (xy 252.023707 -42.428752)
			(xy 252.031758 -42.513066) (xy 252.032262 -42.555414) (xy 252.031763 -42.597654) (xy 252.023751 -42.681754)
			(xy 252.007801 -42.764715) (xy 251.984057 -42.845791) (xy 251.952733 -42.924249) (xy 251.91411 -42.999384)
			(xy 251.868537 -43.070518) (xy 251.816424 -43.137011) (xy 251.758242 -43.198262) (xy 251.694513 -43.253721)
			(xy 251.625814 -43.302888) (xy 251.552762 -43.345319) (xy 251.476016 -43.380632) (xy 251.396267 -43.408509)
			(xy 251.355352 -43.419014) (xy 251.346195 -43.421732) (xy 251.330655 -43.432816) (xy 251.325126 -43.440604)
			(xy 251.308362 -43.466004) (xy 251.303608 -43.474248) (xy 251.299829 -43.492881) (xy 251.300996 -43.502326)
			(xy 251.304708 -43.525116) (xy 251.310044 -43.570987) (xy 251.311664 -43.59402) (xy 251.312655 -43.603401)
			(xy 251.320632 -43.62048) (xy 251.327158 -43.627294) (xy 251.349002 -43.648122) (xy 251.356064 -43.654348)
			(xy 251.373395 -43.661658) (xy 251.382784 -43.662346) (xy 251.425576 -43.663968) (xy 251.510576 -43.674407)
			(xy 251.594179 -43.692967) (xy 251.675612 -43.719476) (xy 251.75412 -43.753688) (xy 251.828976 -43.795286)
			(xy 251.899489 -43.843886) (xy 251.965005 -43.899038) (xy 252.024916 -43.96023) (xy 252.07867 -44.026898)
			(xy 252.10262 -44.062396) (xy 252.109407 -44.071715) (xy 252.129182 -44.083522) (xy 252.152123 -44.085557)
			(xy 252.163072 -44.081954) (xy 252.184948 -44.073917) (xy 252.230165 -44.062618) (xy 252.276421 -44.056915)
			(xy 252.299724 -44.056554) (xy 252.331977 -44.05723) (xy 252.395564 -44.068084) (xy 252.426216 -44.078144)
			(xy 252.4379 -44.082208) (xy 252.46203 -44.078906) (xy 252.539754 -44.023788) (xy 252.545264 -44.019693)
			(xy 252.554031 -44.009136) (xy 252.557026 -44.00296) (xy 252.561344 -43.9928) (xy 252.561344 -42.283634)
			(xy 252.561781 -42.27357) (xy 252.569517 -42.254987) (xy 252.57633 -42.247566) (xy 253.49581 -41.328086)
			(xy 253.503205 -41.321232) (xy 253.521804 -41.313487) (xy 253.531878 -41.3131) (xy 253.96444 -41.3131)
			(xy 253.975685 -41.312527) (xy 253.996011 -41.302912) (xy 254.003556 -41.294558) (xy 254.031663 -41.261131)
			(xy 254.093426 -41.199377) (xy 254.160945 -41.143975) (xy 254.23357 -41.095458) (xy 254.310602 -41.054294)
			(xy 254.391297 -41.020879) (xy 254.474879 -40.995536) (xy 254.560543 -40.978508) (xy 254.647464 -40.969959)
			(xy 254.691134 -40.969438) (xy 254.734931 -40.969956) (xy 254.8221 -40.978559) (xy 254.908 -40.995697)
			(xy 254.991797 -41.021204) (xy 255.072677 -41.054833) (xy 255.111504 -41.075102) (xy 255.12297 -41.08052)
			(xy 255.148298 -41.08052) (xy 255.159764 -41.075102) (xy 255.193705 -41.057353) (xy 255.264074 -41.02709)
			(xy 255.336785 -41.002995) (xy 255.411301 -40.985246) (xy 255.487067 -40.973976) (xy 255.52527 -40.971216)
			(xy 255.534668 -40.970454) (xy 255.551686 -40.962834) (xy 255.648714 -40.865806) (xy 255.649222 -40.865298)
			(xy 255.6558 -40.857916) (xy 255.663238 -40.839616) (xy 255.6637 -40.829738) (xy 255.6637 -39.251382)
			(xy 255.663273 -39.241313) (xy 255.655554 -39.222714) (xy 255.648714 -39.215314) (xy 255.295146 -38.861746)
			(xy 255.288034 -38.85438) (xy 255.269238 -38.84676) (xy 254.802386 -38.84676) (xy 254.793947 -38.847022)
			(xy 254.77796 -38.852425) (xy 254.764603 -38.862737) (xy 254.759714 -38.86962) (xy 254.70612 -38.951662)
			(xy 254.704088 -38.977062) (xy 254.709168 -38.988746) (xy 254.726802 -39.0308) (xy 254.754387 -39.117725)
			(xy 254.772942 -39.207014) (xy 254.782271 -39.297732) (xy 254.782828 -39.34333) (xy 254.782203 -39.390758)
			(xy 254.772074 -39.485073) (xy 254.751958 -39.577772) (xy 254.737616 -39.622984) (xy 254.734314 -39.63289)
			(xy 254.736092 -39.652956) (xy 254.779272 -39.736268) (xy 254.794766 -39.749222) (xy 254.804926 -39.75227)
			(xy 254.83074 -39.760541) (xy 254.879907 -39.78336) (xy 254.92535 -39.812909) (xy 254.966153 -39.848592)
			(xy 255.001496 -39.88969) (xy 255.030666 -39.935377) (xy 255.053076 -39.984732) (xy 255.068275 -40.036762)
			(xy 255.075958 -40.09042) (xy 255.076452 -40.117522) (xy 255.075965 -40.144773) (xy 255.068206 -40.198721)
			(xy 255.052849 -40.251016) (xy 255.030208 -40.300593) (xy 255.000741 -40.346444) (xy 254.965051 -40.387635)
			(xy 254.923861 -40.423328) (xy 254.878012 -40.452797) (xy 254.828436 -40.475442) (xy 254.776143 -40.490801)
			(xy 254.722195 -40.498563) (xy 254.694944 -40.49903) (xy 254.66603 -40.498492) (xy 254.608865 -40.489756)
			(xy 254.553673 -40.472494) (xy 254.501719 -40.4471) (xy 254.454191 -40.414157) (xy 254.41218 -40.374418)
			(xy 254.393954 -40.351964) (xy 254.386414 -40.343174) (xy 254.365642 -40.332988) (xy 254.354076 -40.332406)
			(xy 254.273812 -40.332406) (xy 254.262251 -40.333013) (xy 254.241479 -40.343185) (xy 254.233934 -40.351964)
			(xy 254.215744 -40.374449) (xy 254.173728 -40.41419) (xy 254.126194 -40.447133) (xy 254.074232 -40.472522)
			(xy 254.019032 -40.489775) (xy 253.961861 -40.498498) (xy 253.932944 -40.49903) (xy 253.903619 -40.498495)
			(xy 253.845659 -40.489519) (xy 253.789757 -40.471772) (xy 253.737233 -40.445673) (xy 253.71298 -40.42918)
			(xy 253.703836 -40.42283) (xy 253.6825 -40.418766) (xy 253.586488 -40.44188) (xy 253.56947 -40.455342)
			(xy 253.56439 -40.464994) (xy 253.543515 -40.503793) (xy 253.495196 -40.577472) (xy 253.439828 -40.646012)
			(xy 253.377953 -40.70874) (xy 253.310178 -40.765043) (xy 253.237169 -40.814368) (xy 253.159639 -40.856231)
			(xy 253.07835 -40.890222) (xy 252.994097 -40.916008) (xy 252.907708 -40.933336) (xy 252.820029 -40.942037)
			(xy 252.775974 -40.942514) (xy 252.733356 -40.942012) (xy 252.64851 -40.933855) (xy 252.564833 -40.917618)
			(xy 252.483094 -40.89345) (xy 252.404042 -40.861574) (xy 252.328402 -40.822281) (xy 252.256868 -40.775931)
			(xy 252.190097 -40.722951) (xy 252.1287 -40.663826) (xy 252.073242 -40.599098) (xy 252.02423 -40.529361)
			(xy 251.982115 -40.455255) (xy 251.947282 -40.37746) (xy 251.933202 -40.337232) (xy 251.929714 -40.328191)
			(xy 251.917175 -40.313436) (xy 251.908818 -40.30853) (xy 251.881894 -40.294306) (xy 251.873171 -40.290148)
			(xy 251.853974 -40.288072) (xy 251.844556 -40.290242) (xy 251.805819 -40.300519) (xy 251.726967 -40.31488)
			(xy 251.647141 -40.322075) (xy 251.607066 -40.3225) (xy 251.581866 -40.322352) (xy 251.531544 -40.319555)
			(xy 251.506482 -40.316912) (xy 251.497134 -40.316192) (xy 251.478995 -40.320884) (xy 251.471176 -40.326056)
			(xy 251.446792 -40.343582) (xy 251.439356 -40.349308) (xy 251.429033 -40.364966) (xy 251.426726 -40.374062)
			(xy 251.417072 -40.41608) (xy 251.39069 -40.498164) (xy 251.356491 -40.577311) (xy 251.314794 -40.652777)
			(xy 251.26599 -40.723855) (xy 251.210539 -40.789877) (xy 251.14896 -40.850224) (xy 251.081831 -40.90433)
			(xy 251.009782 -40.951688) (xy 250.933488 -40.991851) (xy 250.853667 -41.024445) (xy 250.771067 -41.049163)
			(xy 250.686462 -41.065772) (xy 250.600648 -41.074118) (xy 250.557538 -41.074594) (xy 250.515188 -41.074108)
			(xy 250.430872 -41.06606) (xy 250.347703 -41.050034) (xy 250.266433 -41.026174) (xy 250.1878 -40.994697)
			(xy 250.112515 -40.955887) (xy 250.04126 -40.910097) (xy 249.97468 -40.857741) (xy 249.913379 -40.799293)
			(xy 249.857912 -40.735283) (xy 249.80878 -40.66629) (xy 249.766429 -40.592938) (xy 249.731243 -40.515893)
			(xy 249.70354 -40.435853) (xy 249.683571 -40.353541) (xy 249.671516 -40.269704) (xy 249.667486 -40.1851)
			(xy 249.671516 -40.100496) (xy 249.683571 -40.016659) (xy 249.70354 -39.934347) (xy 249.731243 -39.854307)
			(xy 249.766429 -39.777262) (xy 249.80878 -39.70391) (xy 249.857912 -39.634917) (xy 249.913379 -39.570907)
			(xy 249.97468 -39.512459) (xy 250.04126 -39.460103) (xy 250.112515 -39.414313) (xy 250.1878 -39.375503)
			(xy 250.266433 -39.344026) (xy 250.347703 -39.320166) (xy 250.430872 -39.30414) (xy 250.515188 -39.296092)
			(xy 250.557538 -39.295578) (xy 250.582738 -39.295726) (xy 250.63306 -39.298523) (xy 250.658122 -39.301166)
			(xy 250.667466 -39.301829) (xy 250.685588 -39.297147) (xy 250.693428 -39.292022) (xy 250.717812 -39.274496)
			(xy 250.725245 -39.268768) (xy 250.73556 -39.253109) (xy 250.737878 -39.244016) (xy 250.74775 -39.20114)
			(xy 250.774846 -39.117425) (xy 250.810069 -39.036793) (xy 250.831096 -38.998144) (xy 250.8377 -38.986206)
			(xy 250.837446 -38.959282) (xy 250.786392 -38.871906) (xy 250.781642 -38.864409) (xy 250.768013 -38.853057)
			(xy 250.75132 -38.847061) (xy 250.74245 -38.84676) (xy 248.28246 -38.84676) (xy 248.270387 -38.847426)
			(xy 248.248894 -38.858425) (xy 248.241312 -38.867842) (xy 248.18594 -38.944804) (xy 248.182384 -38.968934)
			(xy 248.186448 -38.980872) (xy 248.195796 -39.010417) (xy 248.205876 -39.071556) (xy 248.206514 -39.102538)
			(xy 248.206514 -39.1033) (xy 248.20598 -39.132217) (xy 248.197253 -39.189388) (xy 248.18 -39.244588)
			(xy 248.154614 -39.296553) (xy 248.121678 -39.344092) (xy 248.081946 -39.386117) (xy 248.059448 -39.40429)
			(xy 248.052056 -39.41057) (xy 248.042243 -39.427281) (xy 248.040398 -39.436802) (xy 248.03989 -39.444422)
			(xy 248.03989 -39.524178) (xy 248.040398 -39.531798) (xy 248.042268 -39.541311) (xy 248.052067 -39.558022)
			(xy 248.059448 -39.56431) (xy 248.081937 -39.582498) (xy 248.121686 -39.624511) (xy 248.154637 -39.672044)
			(xy 248.180035 -39.724006) (xy 248.197297 -39.779207) (xy 248.206028 -39.836381) (xy 248.206514 -39.8653)
			(xy 248.206028 -39.892551) (xy 248.198272 -39.946499) (xy 248.182917 -39.998794) (xy 248.160275 -40.048371)
			(xy 248.130809 -40.094221) (xy 248.095118 -40.135412) (xy 248.053927 -40.171103) (xy 248.008077 -40.200569)
			(xy 247.9585 -40.223211) (xy 247.906205 -40.238566) (xy 247.852257 -40.246322) (xy 247.797755 -40.246322)
			(xy 247.743807 -40.238566) (xy 247.691512 -40.223211) (xy 247.641935 -40.200569) (xy 247.596085 -40.171103)
			(xy 247.554894 -40.135412) (xy 247.519203 -40.094221) (xy 247.489737 -40.048371) (xy 247.467095 -39.998794)
			(xy 247.45174 -39.946499) (xy 247.443984 -39.892551) (xy 247.443498 -39.8653) (xy 247.444032 -39.836383)
			(xy 247.452759 -39.779212) (xy 247.470013 -39.724012) (xy 247.495399 -39.672048) (xy 247.528335 -39.62451)
			(xy 247.568068 -39.582486) (xy 247.590564 -39.56431) (xy 247.597954 -39.558029) (xy 247.607766 -39.541317)
			(xy 247.609614 -39.531798) (xy 247.610122 -39.524178) (xy 247.610122 -39.444422) (xy 247.609614 -39.436802)
			(xy 247.608077 -39.428709) (xy 247.60057 -39.414058) (xy 247.594882 -39.4081) (xy 247.581674 -39.397178)
			(xy 247.561672 -39.380043) (xy 247.526112 -39.341193) (xy 247.496238 -39.297817) (xy 247.472619 -39.250743)
			(xy 247.455703 -39.200865) (xy 247.445815 -39.149134) (xy 247.444006 -39.122858) (xy 247.443244 -39.107618)
			(xy 247.425718 -39.083488) (xy 247.32488 -39.044626) (xy 247.315593 -39.041515) (xy 247.296028 -39.041822)
			(xy 247.278008 -39.049449) (xy 247.270778 -39.056056) (xy 244.735096 -41.591738) (xy 244.729192 -41.598195)
			(xy 244.721769 -41.614025) (xy 244.720113 -41.631429) (xy 244.721888 -41.639998) (xy 244.746272 -41.737534)
			(xy 244.76456 -41.756838) (xy 244.777514 -41.760648) (xy 244.819134 -41.77385) (xy 244.899796 -41.807295)
			(xy 244.976793 -41.848484) (xy 245.049382 -41.89702) (xy 245.116866 -41.952435) (xy 245.178594 -42.014198)
			(xy 245.233973 -42.081712) (xy 245.282469 -42.154328) (xy 245.323615 -42.231348) (xy 245.357016 -42.312028)
			(xy 245.382349 -42.395594) (xy 245.399371 -42.48124) (xy 245.407919 -42.568141) (xy 245.40845 -42.611802)
			(xy 245.408039 -42.650091) (xy 245.40143 -42.726385) (xy 245.388279 -42.801826) (xy 245.368684 -42.875856)
			(xy 245.356126 -42.91203) (xy 245.353483 -42.920468) (xy 245.353484 -42.938136) (xy 245.356126 -42.946574)
			(xy 245.368669 -42.982752) (xy 245.388243 -43.056784) (xy 245.401388 -43.132224) (xy 245.408006 -43.208514)
			(xy 245.40845 -43.246802) (xy 245.407946 -43.28915) (xy 245.399895 -43.373464) (xy 245.383866 -43.45663)
			(xy 245.360005 -43.537897) (xy 245.328526 -43.616527) (xy 245.289715 -43.691808) (xy 245.243925 -43.76306)
			(xy 245.191569 -43.829636) (xy 245.133121 -43.890934) (xy 245.069111 -43.946399) (xy 245.000119 -43.995528)
			(xy 244.926769 -44.037877) (xy 244.849726 -44.073061) (xy 244.769687 -44.100763) (xy 244.687378 -44.120731)
			(xy 244.603543 -44.132784) (xy 244.518942 -44.136815) (xy 244.434341 -44.132784) (xy 244.350506 -44.120731)
			(xy 244.268197 -44.100763) (xy 244.188158 -44.073061) (xy 244.111115 -44.037877) (xy 244.037765 -43.995528)
			(xy 243.968773 -43.946399) (xy 243.904763 -43.890934) (xy 243.846315 -43.829636) (xy 243.793959 -43.76306)
			(xy 243.748169 -43.691808) (xy 243.709358 -43.616527) (xy 243.677879 -43.537897) (xy 243.654018 -43.45663)
			(xy 243.637989 -43.373464) (xy 243.629938 -43.28915) (xy 243.629434 -43.246802) (xy 243.629845 -43.208512)
			(xy 243.636453 -43.132219) (xy 243.649603 -43.056777) (xy 243.669198 -42.982747) (xy 243.681758 -42.946574)
			(xy 243.684401 -42.938136) (xy 243.684402 -42.920468) (xy 243.681758 -42.91203) (xy 243.667788 -42.870374)
			(xy 243.663978 -42.85742) (xy 243.644674 -42.839132) (xy 243.547138 -42.814748) (xy 243.538574 -42.812957)
			(xy 243.521171 -42.81463) (xy 243.505346 -42.822062) (xy 243.498878 -42.827956) (xy 242.39855 -43.928284)
			(xy 242.391711 -43.935684) (xy 242.383999 -43.954283) (xy 242.383564 -43.964352) (xy 242.383564 -45.726153)
			(xy 244.028673 -45.726153) (xy 244.028673 -45.671647) (xy 244.036431 -45.617697) (xy 244.051787 -45.5654)
			(xy 244.07443 -45.515821) (xy 244.103899 -45.469969) (xy 244.139593 -45.428777) (xy 244.180786 -45.393085)
			(xy 244.22664 -45.363619) (xy 244.276221 -45.340979) (xy 244.328519 -45.325626) (xy 244.382469 -45.317872)
			(xy 244.409722 -45.31741) (xy 244.41912 -45.31741) (xy 244.432582 -45.317918) (xy 244.45595 -45.305218)
			(xy 244.51691 -45.208444) (xy 244.51818 -45.182028) (xy 244.512084 -45.169836) (xy 244.499055 -45.142926)
			(xy 244.480598 -45.086061) (xy 244.471261 -45.027009) (xy 244.470682 -44.997116) (xy 244.471168 -44.969865)
			(xy 244.478924 -44.915917) (xy 244.494279 -44.863622) (xy 244.516921 -44.814045) (xy 244.546387 -44.768195)
			(xy 244.582078 -44.727004) (xy 244.623269 -44.691313) (xy 244.669119 -44.661847) (xy 244.718696 -44.639205)
			(xy 244.770991 -44.62385) (xy 244.824939 -44.616094) (xy 244.879441 -44.616094) (xy 244.933389 -44.62385)
			(xy 244.985684 -44.639205) (xy 245.035261 -44.661847) (xy 245.081111 -44.691313) (xy 245.122302 -44.727004)
			(xy 245.157993 -44.768195) (xy 245.187459 -44.814045) (xy 245.210101 -44.863622) (xy 245.225456 -44.915917)
			(xy 245.233212 -44.969865) (xy 245.233698 -44.997116) (xy 245.233189 -45.025048) (xy 245.225048 -45.080314)
			(xy 245.208941 -45.133805) (xy 245.185214 -45.184379) (xy 245.170198 -45.207936) (xy 245.164102 -45.21708)
			(xy 245.160546 -45.23867) (xy 245.186708 -45.33392) (xy 245.200678 -45.350684) (xy 245.210838 -45.35551)
			(xy 245.234703 -45.367543) (xy 245.279101 -45.397298) (xy 245.31891 -45.43296) (xy 245.353352 -45.47383)
			(xy 245.38175 -45.519108) (xy 245.40355 -45.567907) (xy 245.418323 -45.619271) (xy 245.425782 -45.672195)
			(xy 245.42623 -45.698918) (xy 245.425739 -45.726169) (xy 245.417981 -45.780115) (xy 245.402624 -45.832408)
			(xy 245.379983 -45.881984) (xy 245.350517 -45.927833) (xy 245.314826 -45.969023) (xy 245.273637 -46.004714)
			(xy 245.227788 -46.034181) (xy 245.178212 -46.056823) (xy 245.125919 -46.07218) (xy 245.071973 -46.079939)
			(xy 245.044722 -46.080426) (xy 245.017351 -46.079965) (xy 244.963171 -46.072149) (xy 244.910667 -46.056659)
			(xy 244.860921 -46.033816) (xy 244.814955 -46.004089) (xy 244.794024 -45.986446) (xy 244.786912 -45.98035)
			(xy 244.769894 -45.974) (xy 244.68455 -45.974) (xy 244.667532 -45.98035) (xy 244.66042 -45.986446)
			(xy 244.639484 -46.004081) (xy 244.593513 -46.033795) (xy 244.543767 -46.056633) (xy 244.491267 -46.072125)
			(xy 244.437091 -46.079953) (xy 244.409722 -46.080426) (xy 244.382469 -46.079928) (xy 244.328519 -46.072174)
			(xy 244.276221 -46.056821) (xy 244.22664 -46.034181) (xy 244.180786 -46.004715) (xy 244.139593 -45.969023)
			(xy 244.103899 -45.927831) (xy 244.07443 -45.881979) (xy 244.051787 -45.8324) (xy 244.036431 -45.780103)
			(xy 244.028673 -45.726153) (xy 242.383564 -45.726153) (xy 242.383564 -47.116054) (xy 248.905961 -47.116054)
			(xy 248.905961 -47.061546) (xy 248.913719 -47.007594) (xy 248.929076 -46.955294) (xy 248.951721 -46.905713)
			(xy 248.981191 -46.859859) (xy 249.016887 -46.818666) (xy 249.058083 -46.782973) (xy 249.103939 -46.753506)
			(xy 249.153522 -46.730866) (xy 249.205823 -46.715513) (xy 249.259776 -46.707759) (xy 249.28703 -46.707298)
			(xy 249.319753 -46.707953) (xy 249.384248 -46.719055) (xy 249.4153 -46.729396) (xy 249.423986 -46.732171)
			(xy 249.442209 -46.732028) (xy 249.45086 -46.729142) (xy 249.479308 -46.717966) (xy 249.487869 -46.714156)
			(xy 249.501684 -46.701521) (xy 249.506232 -46.693328) (xy 249.524985 -46.656696) (xy 249.568231 -46.586674)
			(xy 249.61776 -46.520945) (xy 249.673148 -46.460073) (xy 249.733922 -46.404576) (xy 249.799562 -46.35493)
			(xy 249.869507 -46.311559) (xy 249.943158 -46.274833) (xy 250.019887 -46.245067) (xy 250.099037 -46.222516)
			(xy 250.179932 -46.207371) (xy 250.26188 -46.199763) (xy 250.30303 -46.199298) (xy 250.344133 -46.199738)
			(xy 250.425989 -46.207326) (xy 250.506795 -46.222434) (xy 250.585862 -46.244933) (xy 250.662517 -46.274631)
			(xy 250.736104 -46.311276) (xy 250.805996 -46.354553) (xy 250.871597 -46.404095) (xy 250.932347 -46.459479)
			(xy 250.987728 -46.520231) (xy 251.037267 -46.585834) (xy 251.080542 -46.655728) (xy 251.117183 -46.729316)
			(xy 251.146879 -46.805972) (xy 251.169375 -46.88504) (xy 251.184479 -46.965847) (xy 251.192064 -47.047703)
			(xy 251.192538 -47.088806) (xy 251.192049 -47.13012) (xy 251.184383 -47.212393) (xy 251.16912 -47.293599)
			(xy 251.146389 -47.37304) (xy 251.116387 -47.450029) (xy 251.079373 -47.523904) (xy 251.057918 -47.559214)
			(xy 251.050806 -47.570644) (xy 251.04979 -47.596552) (xy 251.10059 -47.698152) (xy 251.12218 -47.712884)
			(xy 251.135388 -47.714154) (xy 251.163573 -47.717102) (xy 251.218695 -47.730247) (xy 251.271265 -47.751405)
			(xy 251.320124 -47.780109) (xy 251.364198 -47.815727) (xy 251.402516 -47.857476) (xy 251.434233 -47.904436)
			(xy 251.458652 -47.955573) (xy 251.475234 -48.00976) (xy 251.483615 -48.065804) (xy 251.48413 -48.094138)
			(xy 251.483644 -48.121389) (xy 251.475888 -48.175337) (xy 251.460533 -48.227632) (xy 251.437891 -48.277209)
			(xy 251.408425 -48.323059) (xy 251.372734 -48.36425) (xy 251.331543 -48.399941) (xy 251.285693 -48.429407)
			(xy 251.236116 -48.452049) (xy 251.183821 -48.467404) (xy 251.129873 -48.47516) (xy 251.075371 -48.47516)
			(xy 251.021423 -48.467404) (xy 250.969128 -48.452049) (xy 250.919551 -48.429407) (xy 250.873701 -48.399941)
			(xy 250.83251 -48.36425) (xy 250.796819 -48.323059) (xy 250.767353 -48.277209) (xy 250.744711 -48.227632)
			(xy 250.729356 -48.175337) (xy 250.7216 -48.121389) (xy 250.721114 -48.094138) (xy 250.721234 -48.080693)
			(xy 250.72314 -48.053871) (xy 250.724924 -48.040544) (xy 250.726702 -48.027336) (xy 250.717304 -48.002952)
			(xy 250.629928 -47.930562) (xy 250.60402 -47.92599) (xy 250.59132 -47.930308) (xy 250.544796 -47.945523)
			(xy 250.449269 -47.966891) (xy 250.351974 -47.977642) (xy 250.30303 -47.978314) (xy 250.261878 -47.97783)
			(xy 250.179925 -47.970238) (xy 250.099025 -47.955107) (xy 250.019868 -47.932566) (xy 249.943132 -47.902808)
			(xy 249.869474 -47.866088) (xy 249.799524 -47.82272) (xy 249.733879 -47.773075) (xy 249.673102 -47.717576)
			(xy 249.617713 -47.656701) (xy 249.568184 -47.590968) (xy 249.524941 -47.52094) (xy 249.506232 -47.484284)
			(xy 249.501673 -47.476099) (xy 249.487865 -47.46346) (xy 249.479308 -47.459646) (xy 249.45086 -47.44847)
			(xy 249.442209 -47.445577) (xy 249.423985 -47.445432) (xy 249.4153 -47.448216) (xy 249.384244 -47.458544)
			(xy 249.319752 -47.469658) (xy 249.28703 -47.470314) (xy 249.259776 -47.469841) (xy 249.205823 -47.462087)
			(xy 249.153522 -47.446734) (xy 249.103939 -47.424094) (xy 249.058083 -47.394627) (xy 249.016887 -47.358934)
			(xy 248.981191 -47.317741) (xy 248.951721 -47.271887) (xy 248.929076 -47.222306) (xy 248.913719 -47.170006)
			(xy 248.905961 -47.116054) (xy 242.383564 -47.116054) (xy 242.383564 -47.23765) (xy 242.387374 -47.250858)
			(xy 242.39093 -47.256954) (xy 242.394436 -47.263059) (xy 242.398309 -47.276589) (xy 242.39855 -47.283624)
			(xy 242.39855 -52.086764) (xy 242.398986 -52.096828) (xy 242.406723 -52.115411) (xy 242.413536 -52.122832)
			(xy 242.419651 -52.128947) (xy 243.816428 -52.128947) (xy 243.816428 -52.074453) (xy 243.824183 -52.020515)
			(xy 243.839535 -51.968229) (xy 243.862172 -51.918659) (xy 243.891632 -51.872816) (xy 243.927316 -51.831632)
			(xy 243.968498 -51.795945) (xy 244.01434 -51.766482) (xy 244.063908 -51.743843) (xy 244.116193 -51.728488)
			(xy 244.170131 -51.72073) (xy 244.197378 -51.720242) (xy 244.223757 -51.720681) (xy 244.276014 -51.727943)
			(xy 244.326772 -51.742331) (xy 244.375066 -51.763572) (xy 244.419975 -51.79126) (xy 244.460644 -51.824869)
			(xy 244.496297 -51.863757) (xy 244.526255 -51.907184) (xy 244.5385 -51.930554) (xy 244.545202 -51.942913)
			(xy 244.564177 -51.963641) (xy 244.588091 -51.978403) (xy 244.615127 -51.986075) (xy 244.643229 -51.986075)
			(xy 244.670265 -51.978403) (xy 244.694179 -51.963641) (xy 244.713154 -51.942913) (xy 244.719856 -51.930554)
			(xy 244.732095 -51.907182) (xy 244.762059 -51.86376) (xy 244.797716 -51.824876) (xy 244.838386 -51.791271)
			(xy 244.883295 -51.763585) (xy 244.931588 -51.742344) (xy 244.982345 -51.727954) (xy 245.034599 -51.720689)
			(xy 245.060978 -51.720242) (xy 245.088235 -51.720603) (xy 245.142196 -51.728359) (xy 245.194503 -51.743715)
			(xy 245.244093 -51.766359) (xy 245.289955 -51.795831) (xy 245.331155 -51.831529) (xy 245.366856 -51.872728)
			(xy 245.39633 -51.918588) (xy 245.418977 -51.968176) (xy 245.434336 -52.020483) (xy 245.442095 -52.074443)
			(xy 245.442095 -52.128957) (xy 245.434336 -52.182917) (xy 245.418977 -52.235224) (xy 245.39633 -52.284812)
			(xy 245.366856 -52.330672) (xy 245.331155 -52.371871) (xy 245.289955 -52.407569) (xy 245.244093 -52.437041)
			(xy 245.194503 -52.459685) (xy 245.142196 -52.475041) (xy 245.088235 -52.482797) (xy 245.060978 -52.483258)
			(xy 245.0346 -52.482773) (xy 244.982346 -52.475519) (xy 244.931588 -52.461138) (xy 244.883295 -52.439904)
			(xy 244.838386 -52.412222) (xy 244.797716 -52.378619) (xy 244.762062 -52.339736) (xy 244.732101 -52.296313)
			(xy 244.719856 -52.272946) (xy 244.713154 -52.260587) (xy 244.694179 -52.239859) (xy 244.670265 -52.225097)
			(xy 244.643229 -52.217425) (xy 244.615127 -52.217425) (xy 244.588091 -52.225097) (xy 244.564177 -52.239859)
			(xy 244.545202 -52.260587) (xy 244.5385 -52.272946) (xy 244.526294 -52.296336) (xy 244.496326 -52.339759)
			(xy 244.460664 -52.378643) (xy 244.41999 -52.412247) (xy 244.375076 -52.439931) (xy 244.326778 -52.461168)
			(xy 244.276017 -52.475554) (xy 244.223758 -52.482814) (xy 244.197378 -52.483258) (xy 244.170131 -52.48267)
			(xy 244.116193 -52.474912) (xy 244.063908 -52.459557) (xy 244.01434 -52.436918) (xy 243.968498 -52.407455)
			(xy 243.927316 -52.371768) (xy 243.891632 -52.330584) (xy 243.862172 -52.284741) (xy 243.839535 -52.235171)
			(xy 243.824183 -52.182885) (xy 243.816428 -52.128947) (xy 242.419651 -52.128947) (xy 243.152676 -52.861972)
			(xy 243.160077 -52.86881) (xy 243.178676 -52.876521) (xy 243.188744 -52.876958)
		)
		(stroke
			(width 0)
			(type solid)
		)
		(fill yes)
		(layer "In13.Cu")
		(net "P12V_E1S_0")
	)
	(gr_poly
		(pts
			(xy 223.426528 -409.329128) (xy 223.436597 -409.328701) (xy 223.455196 -409.320982) (xy 223.462596 -409.314142)
			(xy 223.901 -408.875738) (xy 223.907784 -408.868316) (xy 223.915391 -408.849719) (xy 223.915732 -408.83967)
			(xy 223.915732 -402.928074) (xy 223.916185 -402.908055) (xy 223.923991 -402.868786) (xy 223.939316 -402.831798)
			(xy 223.961571 -402.798516) (xy 223.975422 -402.784056) (xy 224.381314 -402.378164) (xy 224.395796 -402.364357)
			(xy 224.429088 -402.342169) (xy 224.466074 -402.326914) (xy 224.505327 -402.31918) (xy 224.525332 -402.318728)
			(xy 225.76409 -402.318728) (xy 225.774162 -402.318307) (xy 225.792771 -402.310599) (xy 225.800158 -402.303742)
			(xy 226.332796 -401.771104) (xy 226.339487 -401.763659) (xy 226.347082 -401.745162) (xy 226.347068 -401.725165)
			(xy 226.343718 -401.715732) (xy 226.337876 -401.701254) (xy 226.312476 -401.684236) (xy 224.728532 -401.684236)
			(xy 224.700084 -401.70862) (xy 224.69729 -401.727416) (xy 224.692761 -401.754147) (xy 224.677137 -401.806061)
			(xy 224.65432 -401.855241) (xy 224.624771 -401.900695) (xy 224.589084 -401.941508) (xy 224.547979 -401.976857)
			(xy 224.502283 -402.006031) (xy 224.452917 -402.028442) (xy 224.400876 -402.043638) (xy 224.347207 -402.051314)
			(xy 224.3201 -402.051774) (xy 224.289193 -402.051172) (xy 224.228185 -402.041212) (xy 224.198688 -402.031962)
			(xy 224.186496 -402.027898) (xy 224.16135 -402.032216) (xy 224.074228 -402.100796) (xy 224.064068 -402.124164)
			(xy 224.065084 -402.137118) (xy 224.066608 -402.170138) (xy 224.06612 -402.197389) (xy 224.058358 -402.251334)
			(xy 224.042998 -402.303627) (xy 224.020353 -402.353201) (xy 223.990883 -402.399048) (xy 223.955189 -402.440234)
			(xy 223.913997 -402.475921) (xy 223.868145 -402.505384) (xy 223.818567 -402.52802) (xy 223.766273 -402.543371)
			(xy 223.712325 -402.551124) (xy 223.657824 -402.55112) (xy 223.603878 -402.543361) (xy 223.551585 -402.528003)
			(xy 223.50201 -402.505359) (xy 223.456162 -402.475891) (xy 223.414975 -402.440198) (xy 223.379286 -402.399007)
			(xy 223.349823 -402.353156) (xy 223.327184 -402.303579) (xy 223.311831 -402.251285) (xy 223.304077 -402.197338)
			(xy 223.304079 -402.142837) (xy 223.311837 -402.08889) (xy 223.327193 -402.036597) (xy 223.349835 -401.987021)
			(xy 223.379301 -401.941173) (xy 223.414993 -401.899984) (xy 223.456183 -401.864294) (xy 223.502033 -401.834829)
			(xy 223.551609 -401.812188) (xy 223.603903 -401.796834) (xy 223.657849 -401.789078) (xy 223.6851 -401.78863)
			(xy 223.716007 -401.789232) (xy 223.777015 -401.799192) (xy 223.806512 -401.808442) (xy 223.818704 -401.812506)
			(xy 223.84385 -401.808188) (xy 223.930972 -401.739608) (xy 223.941132 -401.71624) (xy 223.940116 -401.703286)
			(xy 223.938592 -401.670266) (xy 223.938717 -401.655346) (xy 223.941007 -401.625594) (xy 223.943164 -401.61083)
			(xy 223.945196 -401.598638) (xy 223.93783 -401.575778) (xy 222.664274 -400.302222) (xy 222.656875 -400.295377)
			(xy 222.638277 -400.287649) (xy 222.628206 -400.287236) (xy 222.599758 -400.287236) (xy 222.589759 -400.287732)
			(xy 222.571287 -400.2954) (xy 222.557156 -400.309553) (xy 222.549516 -400.328036) (xy 222.548958 -400.338036)
			(xy 222.548958 -400.347434) (xy 222.555054 -400.363944) (xy 222.560896 -400.371056) (xy 222.577844 -400.391785)
			(xy 222.606371 -400.437096) (xy 222.628278 -400.485954) (xy 222.643131 -400.537396) (xy 222.65064 -400.59041)
			(xy 222.651066 -400.617182) (xy 222.65058 -400.644433) (xy 222.642824 -400.698381) (xy 222.627469 -400.750676)
			(xy 222.604827 -400.800253) (xy 222.575361 -400.846103) (xy 222.53967 -400.887294) (xy 222.498479 -400.922985)
			(xy 222.452629 -400.952451) (xy 222.403052 -400.975093) (xy 222.350757 -400.990448) (xy 222.296809 -400.998204)
			(xy 222.242307 -400.998204) (xy 222.188359 -400.990448) (xy 222.136064 -400.975093) (xy 222.086487 -400.952451)
			(xy 222.040637 -400.922985) (xy 221.999446 -400.887294) (xy 221.963755 -400.846103) (xy 221.934289 -400.800253)
			(xy 221.911647 -400.750676) (xy 221.896292 -400.698381) (xy 221.888536 -400.644433) (xy 221.88805 -400.617182)
			(xy 221.888661 -400.585861) (xy 221.898861 -400.524056) (xy 221.919032 -400.464751) (xy 221.933262 -400.436842)
			(xy 221.939612 -400.424904) (xy 221.939104 -400.398488) (xy 221.887288 -400.312128) (xy 221.88251 -400.304795)
			(xy 221.869036 -400.293646) (xy 221.852596 -400.287679) (xy 221.843854 -400.287236) (xy 221.298262 -400.287236)
			(xy 221.289514 -400.287639) (xy 221.273067 -400.293614) (xy 221.259596 -400.304783) (xy 221.254828 -400.312128)
			(xy 221.203012 -400.398488) (xy 221.202504 -400.424904) (xy 221.208854 -400.436842) (xy 221.22308 -400.464752)
			(xy 221.243234 -400.52406) (xy 221.253441 -400.585862) (xy 221.254066 -400.617182) (xy 221.25358 -400.644433)
			(xy 221.245824 -400.698381) (xy 221.230469 -400.750676) (xy 221.207827 -400.800253) (xy 221.178361 -400.846103)
			(xy 221.14267 -400.887294) (xy 221.101479 -400.922985) (xy 221.055629 -400.952451) (xy 221.006052 -400.975093)
			(xy 220.953757 -400.990448) (xy 220.899809 -400.998204) (xy 220.845307 -400.998204) (xy 220.791359 -400.990448)
			(xy 220.739064 -400.975093) (xy 220.689487 -400.952451) (xy 220.643637 -400.922985) (xy 220.602446 -400.887294)
			(xy 220.566755 -400.846103) (xy 220.537289 -400.800253) (xy 220.514647 -400.750676) (xy 220.499292 -400.698381)
			(xy 220.491536 -400.644433) (xy 220.49105 -400.617182) (xy 220.491661 -400.585861) (xy 220.501861 -400.524056)
			(xy 220.522032 -400.464751) (xy 220.536262 -400.436842) (xy 220.542612 -400.424904) (xy 220.542104 -400.398488)
			(xy 220.490288 -400.312128) (xy 220.48551 -400.304795) (xy 220.472036 -400.293646) (xy 220.455596 -400.287679)
			(xy 220.446854 -400.287236) (xy 219.875862 -400.287236) (xy 219.867114 -400.287639) (xy 219.850667 -400.293614)
			(xy 219.837196 -400.304783) (xy 219.832428 -400.312128) (xy 219.780612 -400.398488) (xy 219.780104 -400.424904)
			(xy 219.786454 -400.436842) (xy 219.80068 -400.464752) (xy 219.820834 -400.52406) (xy 219.831041 -400.585862)
			(xy 219.831666 -400.617182) (xy 219.83118 -400.644433) (xy 219.823424 -400.698381) (xy 219.808069 -400.750676)
			(xy 219.785427 -400.800253) (xy 219.755961 -400.846103) (xy 219.72027 -400.887294) (xy 219.679079 -400.922985)
			(xy 219.633229 -400.952451) (xy 219.583652 -400.975093) (xy 219.531357 -400.990448) (xy 219.477409 -400.998204)
			(xy 219.422907 -400.998204) (xy 219.368959 -400.990448) (xy 219.316664 -400.975093) (xy 219.267087 -400.952451)
			(xy 219.221237 -400.922985) (xy 219.180046 -400.887294) (xy 219.144355 -400.846103) (xy 219.114889 -400.800253)
			(xy 219.092247 -400.750676) (xy 219.076892 -400.698381) (xy 219.069136 -400.644433) (xy 219.06865 -400.617182)
			(xy 219.069261 -400.585861) (xy 219.079461 -400.524056) (xy 219.099632 -400.464751) (xy 219.113862 -400.436842)
			(xy 219.120212 -400.424904) (xy 219.119704 -400.398488) (xy 219.067888 -400.312128) (xy 219.06311 -400.304795)
			(xy 219.049636 -400.293646) (xy 219.033196 -400.287679) (xy 219.024454 -400.287236) (xy 217.203782 -400.287236)
			(xy 217.193714 -400.287663) (xy 217.175118 -400.295386) (xy 217.167714 -400.302222) (xy 216.299796 -401.17014)
			(xy 216.826082 -401.17014) (xy 216.830153 -401.114518) (xy 216.842279 -401.060081) (xy 216.862202 -401.00799)
			(xy 216.889498 -400.959355) (xy 216.923584 -400.915212) (xy 216.963733 -400.876503) (xy 217.009091 -400.844052)
			(xy 217.058691 -400.818551) (xy 217.111475 -400.800544) (xy 217.166318 -400.790414) (xy 217.222052 -400.788377)
			(xy 217.277489 -400.794477) (xy 217.331446 -400.808583) (xy 217.382775 -400.830395) (xy 217.430381 -400.859449)
			(xy 217.473249 -400.895124) (xy 217.510466 -400.936661) (xy 217.541239 -400.983174) (xy 217.564911 -401.033671)
			(xy 217.580979 -401.087078) (xy 217.589099 -401.142254) (xy 217.589608 -401.17014) (xy 217.589099 -401.198026)
			(xy 217.580979 -401.253202) (xy 217.564911 -401.306609) (xy 217.541239 -401.357106) (xy 217.510466 -401.403619)
			(xy 217.473249 -401.445156) (xy 217.430381 -401.480831) (xy 217.382775 -401.509885) (xy 217.331446 -401.531697)
			(xy 217.277489 -401.545803) (xy 217.222052 -401.551903) (xy 217.166318 -401.549866) (xy 217.111475 -401.539736)
			(xy 217.058691 -401.521729) (xy 217.009091 -401.496228) (xy 216.963733 -401.463777) (xy 216.923584 -401.425068)
			(xy 216.889498 -401.380925) (xy 216.862202 -401.33229) (xy 216.842279 -401.280199) (xy 216.830153 -401.225762)
			(xy 216.826082 -401.17014) (xy 216.299796 -401.17014) (xy 216.000076 -401.46986) (xy 215.993371 -401.477301)
			(xy 215.985751 -401.495803) (xy 215.985754 -401.515812) (xy 215.989154 -401.525232) (xy 215.994996 -401.53971)
			(xy 216.020396 -401.556728) (xy 216.718134 -401.556728) (xy 216.738133 -401.557201) (xy 216.777369 -401.564967)
			(xy 216.814337 -401.580233) (xy 216.84762 -401.602415) (xy 216.862152 -401.616164) (xy 217.16619 -401.920202)
			(xy 219.06814 -401.920202) (xy 219.072211 -401.86458) (xy 219.084337 -401.810143) (xy 219.10426 -401.758052)
			(xy 219.131556 -401.709417) (xy 219.165642 -401.665274) (xy 219.205791 -401.626565) (xy 219.251149 -401.594114)
			(xy 219.300749 -401.568613) (xy 219.353533 -401.550606) (xy 219.408376 -401.540476) (xy 219.46411 -401.538439)
			(xy 219.519547 -401.544539) (xy 219.573504 -401.558645) (xy 219.624833 -401.580457) (xy 219.672439 -401.609511)
			(xy 219.715307 -401.645186) (xy 219.752524 -401.686723) (xy 219.783297 -401.733236) (xy 219.806969 -401.783733)
			(xy 219.823037 -401.83714) (xy 219.831157 -401.892316) (xy 219.831666 -401.920202) (xy 221.88754 -401.920202)
			(xy 221.891611 -401.86458) (xy 221.903737 -401.810143) (xy 221.92366 -401.758052) (xy 221.950956 -401.709417)
			(xy 221.985042 -401.665274) (xy 222.025191 -401.626565) (xy 222.070549 -401.594114) (xy 222.120149 -401.568613)
			(xy 222.172933 -401.550606) (xy 222.227776 -401.540476) (xy 222.28351 -401.538439) (xy 222.338947 -401.544539)
			(xy 222.392904 -401.558645) (xy 222.444233 -401.580457) (xy 222.491839 -401.609511) (xy 222.534707 -401.645186)
			(xy 222.571924 -401.686723) (xy 222.602697 -401.733236) (xy 222.626369 -401.783733) (xy 222.642437 -401.83714)
			(xy 222.650557 -401.892316) (xy 222.651066 -401.920202) (xy 222.650557 -401.948088) (xy 222.642437 -402.003264)
			(xy 222.626369 -402.056671) (xy 222.602697 -402.107168) (xy 222.571924 -402.153681) (xy 222.534707 -402.195218)
			(xy 222.491839 -402.230893) (xy 222.444233 -402.259947) (xy 222.392904 -402.281759) (xy 222.338947 -402.295865)
			(xy 222.28351 -402.301965) (xy 222.227776 -402.299928) (xy 222.172933 -402.289798) (xy 222.120149 -402.271791)
			(xy 222.070549 -402.24629) (xy 222.025191 -402.213839) (xy 221.985042 -402.17513) (xy 221.950956 -402.130987)
			(xy 221.92366 -402.082352) (xy 221.903737 -402.030261) (xy 221.891611 -401.975824) (xy 221.88754 -401.920202)
			(xy 219.831666 -401.920202) (xy 219.831157 -401.948088) (xy 219.823037 -402.003264) (xy 219.806969 -402.056671)
			(xy 219.783297 -402.107168) (xy 219.752524 -402.153681) (xy 219.715307 -402.195218) (xy 219.672439 -402.230893)
			(xy 219.624833 -402.259947) (xy 219.573504 -402.281759) (xy 219.519547 -402.295865) (xy 219.46411 -402.301965)
			(xy 219.408376 -402.299928) (xy 219.353533 -402.289798) (xy 219.300749 -402.271791) (xy 219.251149 -402.24629)
			(xy 219.205791 -402.213839) (xy 219.165642 -402.17513) (xy 219.131556 -402.130987) (xy 219.10426 -402.082352)
			(xy 219.084337 -402.030261) (xy 219.072211 -401.975824) (xy 219.06814 -401.920202) (xy 217.16619 -401.920202)
			(xy 218.035632 -402.789644) (xy 218.048078 -402.796502) (xy 218.05519 -402.79828) (xy 218.082884 -402.805169)
			(xy 218.135993 -402.826054) (xy 218.185398 -402.854615) (xy 218.229999 -402.890216) (xy 218.268799 -402.932063)
			(xy 218.300935 -402.979222) (xy 218.325688 -403.030641) (xy 218.342506 -403.085173) (xy 218.351015 -403.141603)
			(xy 218.351608 -403.170136) (xy 218.351188 -403.195799) (xy 218.347474 -403.223222) (xy 219.06814 -403.223222)
			(xy 219.072211 -403.1676) (xy 219.084337 -403.113163) (xy 219.10426 -403.061072) (xy 219.131556 -403.012437)
			(xy 219.165642 -402.968294) (xy 219.205791 -402.929585) (xy 219.251149 -402.897134) (xy 219.300749 -402.871633)
			(xy 219.353533 -402.853626) (xy 219.408376 -402.843496) (xy 219.46411 -402.841459) (xy 219.519547 -402.847559)
			(xy 219.573504 -402.861665) (xy 219.624833 -402.883477) (xy 219.672439 -402.912531) (xy 219.715307 -402.948206)
			(xy 219.752524 -402.989743) (xy 219.783297 -403.036256) (xy 219.806969 -403.086753) (xy 219.823037 -403.14016)
			(xy 219.831157 -403.195336) (xy 219.831666 -403.223222) (xy 220.49054 -403.223222) (xy 220.494611 -403.1676)
			(xy 220.506737 -403.113163) (xy 220.52666 -403.061072) (xy 220.553956 -403.012437) (xy 220.588042 -402.968294)
			(xy 220.628191 -402.929585) (xy 220.673549 -402.897134) (xy 220.723149 -402.871633) (xy 220.775933 -402.853626)
			(xy 220.830776 -402.843496) (xy 220.88651 -402.841459) (xy 220.941947 -402.847559) (xy 220.995904 -402.861665)
			(xy 221.047233 -402.883477) (xy 221.094839 -402.912531) (xy 221.137707 -402.948206) (xy 221.174924 -402.989743)
			(xy 221.205697 -403.036256) (xy 221.229369 -403.086753) (xy 221.245437 -403.14016) (xy 221.253557 -403.195336)
			(xy 221.254066 -403.223222) (xy 221.88754 -403.223222) (xy 221.891611 -403.1676) (xy 221.903737 -403.113163)
			(xy 221.92366 -403.061072) (xy 221.950956 -403.012437) (xy 221.985042 -402.968294) (xy 222.025191 -402.929585)
			(xy 222.070549 -402.897134) (xy 222.120149 -402.871633) (xy 222.172933 -402.853626) (xy 222.227776 -402.843496)
			(xy 222.28351 -402.841459) (xy 222.338947 -402.847559) (xy 222.392904 -402.861665) (xy 222.444233 -402.883477)
			(xy 222.491839 -402.912531) (xy 222.534707 -402.948206) (xy 222.571924 -402.989743) (xy 222.602697 -403.036256)
			(xy 222.626369 -403.086753) (xy 222.642437 -403.14016) (xy 222.650557 -403.195336) (xy 222.651066 -403.223222)
			(xy 222.650557 -403.251108) (xy 222.642437 -403.306284) (xy 222.626369 -403.359691) (xy 222.602697 -403.410188)
			(xy 222.571924 -403.456701) (xy 222.534707 -403.498238) (xy 222.491839 -403.533913) (xy 222.444233 -403.562967)
			(xy 222.392904 -403.584779) (xy 222.338947 -403.598885) (xy 222.28351 -403.604985) (xy 222.227776 -403.602948)
			(xy 222.172933 -403.592818) (xy 222.120149 -403.574811) (xy 222.070549 -403.54931) (xy 222.025191 -403.516859)
			(xy 221.985042 -403.47815) (xy 221.950956 -403.434007) (xy 221.92366 -403.385372) (xy 221.903737 -403.333281)
			(xy 221.891611 -403.278844) (xy 221.88754 -403.223222) (xy 221.254066 -403.223222) (xy 221.253557 -403.251108)
			(xy 221.245437 -403.306284) (xy 221.229369 -403.359691) (xy 221.205697 -403.410188) (xy 221.174924 -403.456701)
			(xy 221.137707 -403.498238) (xy 221.094839 -403.533913) (xy 221.047233 -403.562967) (xy 220.995904 -403.584779)
			(xy 220.941947 -403.598885) (xy 220.88651 -403.604985) (xy 220.830776 -403.602948) (xy 220.775933 -403.592818)
			(xy 220.723149 -403.574811) (xy 220.673549 -403.54931) (xy 220.628191 -403.516859) (xy 220.588042 -403.47815)
			(xy 220.553956 -403.434007) (xy 220.52666 -403.385372) (xy 220.506737 -403.333281) (xy 220.494611 -403.278844)
			(xy 220.49054 -403.223222) (xy 219.831666 -403.223222) (xy 219.831157 -403.251108) (xy 219.823037 -403.306284)
			(xy 219.806969 -403.359691) (xy 219.783297 -403.410188) (xy 219.752524 -403.456701) (xy 219.715307 -403.498238)
			(xy 219.672439 -403.533913) (xy 219.624833 -403.562967) (xy 219.573504 -403.584779) (xy 219.519547 -403.598885)
			(xy 219.46411 -403.604985) (xy 219.408376 -403.602948) (xy 219.353533 -403.592818) (xy 219.300749 -403.574811)
			(xy 219.251149 -403.54931) (xy 219.205791 -403.516859) (xy 219.165642 -403.47815) (xy 219.131556 -403.434007)
			(xy 219.10426 -403.385372) (xy 219.084337 -403.333281) (xy 219.072211 -403.278844) (xy 219.06814 -403.223222)
			(xy 218.347474 -403.223222) (xy 218.3443 -403.24666) (xy 218.330653 -403.296137) (xy 218.310495 -403.343338)
			(xy 218.284189 -403.387409) (xy 218.25221 -403.427554) (xy 218.215136 -403.463048) (xy 218.194636 -403.478492)
			(xy 218.185335 -403.486147) (xy 218.174473 -403.507612) (xy 218.173808 -403.51964) (xy 218.173808 -406.27046)
			(xy 218.173353 -406.290478) (xy 218.165542 -406.329744) (xy 218.150215 -406.36673) (xy 218.12796 -406.40001)
			(xy 218.114118 -406.414478) (xy 217.07094 -407.457402) (xy 217.064169 -407.46483) (xy 217.056585 -407.483426)
			(xy 217.056208 -407.49347) (xy 217.056208 -408.086653) (xy 217.43666 -408.086653) (xy 217.43666 -408.032147)
			(xy 217.444417 -407.978197) (xy 217.459773 -407.9259) (xy 217.482415 -407.87632) (xy 217.511882 -407.830468)
			(xy 217.547576 -407.789276) (xy 217.588768 -407.753582) (xy 217.63462 -407.724115) (xy 217.6842 -407.701473)
			(xy 217.736497 -407.686117) (xy 217.790447 -407.67836) (xy 217.8177 -407.677874) (xy 217.846618 -407.678364)
			(xy 217.903792 -407.687095) (xy 217.958993 -407.704357) (xy 218.010955 -407.729754) (xy 218.058488 -407.762703)
			(xy 218.100502 -407.802451) (xy 218.11869 -407.82494) (xy 218.126254 -407.8337) (xy 218.147011 -407.843883)
			(xy 218.158568 -407.844498) (xy 218.238832 -407.844498) (xy 218.250395 -407.843889) (xy 218.271166 -407.833722)
			(xy 218.27871 -407.82494) (xy 218.293486 -407.806539) (xy 218.326858 -407.77317) (xy 218.345258 -407.758392)
			(xy 218.354029 -407.750839) (xy 218.364205 -407.730073) (xy 218.364816 -407.718514) (xy 218.364816 -407.63825)
			(xy 218.364211 -407.626687) (xy 218.35404 -407.605916) (xy 218.345258 -407.598372) (xy 218.322752 -407.580207)
			(xy 218.28302 -407.538181) (xy 218.250085 -407.49064) (xy 218.224701 -407.438674) (xy 218.207449 -407.383472)
			(xy 218.198725 -407.326299) (xy 218.198192 -407.297382) (xy 218.198661 -407.27013) (xy 218.20642 -407.216182)
			(xy 218.221777 -407.163887) (xy 218.244421 -407.11431) (xy 218.273889 -407.068459) (xy 218.309582 -407.027269)
			(xy 218.350774 -406.991578) (xy 218.396625 -406.962112) (xy 218.446204 -406.939471) (xy 218.4985 -406.924116)
			(xy 218.552448 -406.91636) (xy 218.5797 -406.915874) (xy 218.608618 -406.916364) (xy 218.665792 -406.925095)
			(xy 218.720993 -406.942357) (xy 218.772955 -406.967754) (xy 218.820488 -407.000703) (xy 218.862502 -407.040451)
			(xy 218.88069 -407.06294) (xy 218.888254 -407.0717) (xy 218.909011 -407.081883) (xy 218.920568 -407.082498)
			(xy 219.000832 -407.082498) (xy 219.012395 -407.081889) (xy 219.033166 -407.071722) (xy 219.04071 -407.06294)
			(xy 219.055486 -407.044539) (xy 219.088858 -407.01117) (xy 219.107258 -406.996392) (xy 219.116029 -406.988839)
			(xy 219.126205 -406.968073) (xy 219.126816 -406.956514) (xy 219.126816 -406.87625) (xy 219.126211 -406.864687)
			(xy 219.11604 -406.843916) (xy 219.107258 -406.836372) (xy 219.086457 -406.81964) (xy 219.049327 -406.781284)
			(xy 219.017905 -406.738127) (xy 218.992807 -406.691011) (xy 218.974521 -406.640856) (xy 218.963406 -406.588642)
			(xy 218.959678 -406.535389) (xy 218.963409 -406.482136) (xy 218.974528 -406.429922) (xy 218.992816 -406.379769)
			(xy 219.017917 -406.332654) (xy 219.049341 -406.289499) (xy 219.086474 -406.251145) (xy 219.107258 -406.234392)
			(xy 219.116029 -406.226839) (xy 219.126205 -406.206073) (xy 219.126816 -406.194514) (xy 219.126816 -406.11425)
			(xy 219.126211 -406.102687) (xy 219.11604 -406.081916) (xy 219.107258 -406.074372) (xy 219.086457 -406.05764)
			(xy 219.049327 -406.019284) (xy 219.017905 -405.976127) (xy 218.992807 -405.929011) (xy 218.974521 -405.878856)
			(xy 218.963406 -405.826642) (xy 218.959678 -405.773389) (xy 218.963409 -405.720136) (xy 218.974528 -405.667922)
			(xy 218.992816 -405.617769) (xy 219.017917 -405.570654) (xy 219.049341 -405.527499) (xy 219.086474 -405.489145)
			(xy 219.107258 -405.472392) (xy 219.116029 -405.464839) (xy 219.126205 -405.444073) (xy 219.126816 -405.432514)
			(xy 219.126816 -405.35225) (xy 219.126211 -405.340687) (xy 219.11604 -405.319916) (xy 219.107258 -405.312372)
			(xy 219.084752 -405.294207) (xy 219.04502 -405.252181) (xy 219.012085 -405.20464) (xy 218.986701 -405.152674)
			(xy 218.969449 -405.097472) (xy 218.960725 -405.040299) (xy 218.960192 -405.011382) (xy 218.960661 -404.98413)
			(xy 218.96842 -404.930182) (xy 218.983777 -404.877887) (xy 219.006421 -404.82831) (xy 219.035889 -404.782459)
			(xy 219.071582 -404.741269) (xy 219.112774 -404.705578) (xy 219.158625 -404.676112) (xy 219.208204 -404.653471)
			(xy 219.2605 -404.638116) (xy 219.314448 -404.63036) (xy 219.3417 -404.629874) (xy 219.370618 -404.630364)
			(xy 219.427792 -404.639095) (xy 219.482993 -404.656357) (xy 219.534955 -404.681754) (xy 219.582488 -404.714703)
			(xy 219.624502 -404.754451) (xy 219.64269 -404.77694) (xy 219.650254 -404.7857) (xy 219.671011 -404.795883)
			(xy 219.682568 -404.796498) (xy 219.762832 -404.796498) (xy 219.774395 -404.795889) (xy 219.795166 -404.785722)
			(xy 219.80271 -404.77694) (xy 219.819463 -404.756157) (xy 219.857817 -404.719027) (xy 219.900971 -404.687605)
			(xy 219.948085 -404.662506) (xy 219.998237 -404.64422) (xy 220.050448 -404.633103) (xy 220.1037 -404.629373)
			(xy 220.156952 -404.633103) (xy 220.209163 -404.64422) (xy 220.259315 -404.662506) (xy 220.306429 -404.687605)
			(xy 220.349583 -404.719027) (xy 220.387937 -404.756157) (xy 220.40469 -404.77694) (xy 220.412254 -404.7857)
			(xy 220.433011 -404.795883) (xy 220.444568 -404.796498) (xy 220.524832 -404.796498) (xy 220.536395 -404.795889)
			(xy 220.557166 -404.785722) (xy 220.56471 -404.77694) (xy 220.581463 -404.756157) (xy 220.619817 -404.719027)
			(xy 220.662971 -404.687605) (xy 220.710085 -404.662506) (xy 220.760237 -404.64422) (xy 220.812448 -404.633103)
			(xy 220.8657 -404.629373) (xy 220.918952 -404.633103) (xy 220.971163 -404.64422) (xy 221.021315 -404.662506)
			(xy 221.068429 -404.687605) (xy 221.111583 -404.719027) (xy 221.149937 -404.756157) (xy 221.16669 -404.77694)
			(xy 221.174254 -404.7857) (xy 221.195011 -404.795883) (xy 221.206568 -404.796498) (xy 221.286832 -404.796498)
			(xy 221.298395 -404.795889) (xy 221.319166 -404.785722) (xy 221.32671 -404.77694) (xy 221.343463 -404.756157)
			(xy 221.381817 -404.719027) (xy 221.424971 -404.687605) (xy 221.472085 -404.662506) (xy 221.522237 -404.64422)
			(xy 221.574448 -404.633103) (xy 221.6277 -404.629373) (xy 221.680952 -404.633103) (xy 221.733163 -404.64422)
			(xy 221.783315 -404.662506) (xy 221.830429 -404.687605) (xy 221.873583 -404.719027) (xy 221.911937 -404.756157)
			(xy 221.92869 -404.77694) (xy 221.936254 -404.7857) (xy 221.957011 -404.795883) (xy 221.968568 -404.796498)
			(xy 222.048832 -404.796498) (xy 222.060395 -404.795889) (xy 222.081166 -404.785722) (xy 222.08871 -404.77694)
			(xy 222.106905 -404.75446) (xy 222.148923 -404.714723) (xy 222.196457 -404.681782) (xy 222.248417 -404.656393)
			(xy 222.303615 -404.639136) (xy 222.360784 -404.630408) (xy 222.3897 -404.629874) (xy 222.41695 -404.630378)
			(xy 222.470897 -404.638134) (xy 222.52319 -404.653488) (xy 222.572766 -404.676128) (xy 222.618615 -404.705592)
			(xy 222.659805 -404.741282) (xy 222.695497 -404.78247) (xy 222.724964 -404.828318) (xy 222.747606 -404.877893)
			(xy 222.762962 -404.930186) (xy 222.770721 -404.984132) (xy 222.771208 -405.011382) (xy 222.770712 -405.0403)
			(xy 222.761983 -405.097474) (xy 222.744723 -405.152675) (xy 222.719327 -405.204637) (xy 222.686378 -405.25217)
			(xy 222.646631 -405.294184) (xy 222.624142 -405.312372) (xy 222.615387 -405.31994) (xy 222.605202 -405.340695)
			(xy 222.604584 -405.35225) (xy 222.604584 -405.432514) (xy 222.605152 -405.444082) (xy 222.615349 -405.464852)
			(xy 222.624142 -405.472392) (xy 222.644907 -405.489167) (xy 222.682037 -405.527517) (xy 222.713459 -405.570669)
			(xy 222.738558 -405.61778) (xy 222.756845 -405.66793) (xy 222.767963 -405.72014) (xy 222.771694 -405.773389)
			(xy 222.767966 -405.826639) (xy 222.756851 -405.878849) (xy 222.738567 -405.928999) (xy 222.71347 -405.976112)
			(xy 222.682052 -406.019266) (xy 222.644924 -406.057619) (xy 222.624142 -406.074372) (xy 222.615387 -406.08194)
			(xy 222.605202 -406.102695) (xy 222.604584 -406.11425) (xy 222.604584 -406.194514) (xy 222.605152 -406.206082)
			(xy 222.615349 -406.226852) (xy 222.624142 -406.234392) (xy 222.644907 -406.251167) (xy 222.682037 -406.289517)
			(xy 222.713459 -406.332669) (xy 222.738558 -406.37978) (xy 222.756845 -406.42993) (xy 222.767963 -406.48214)
			(xy 222.771694 -406.535389) (xy 222.767966 -406.588639) (xy 222.756851 -406.640849) (xy 222.738567 -406.690999)
			(xy 222.71347 -406.738112) (xy 222.682052 -406.781266) (xy 222.644924 -406.819619) (xy 222.624142 -406.836372)
			(xy 222.615387 -406.84394) (xy 222.605202 -406.864695) (xy 222.604584 -406.87625) (xy 222.604584 -406.956514)
			(xy 222.605152 -406.968082) (xy 222.615349 -406.988852) (xy 222.624142 -406.996392) (xy 222.64254 -407.011172)
			(xy 222.675911 -407.044541) (xy 222.69069 -407.06294) (xy 222.698254 -407.0717) (xy 222.719011 -407.081883)
			(xy 222.730568 -407.082498) (xy 222.810832 -407.082498) (xy 222.822395 -407.081889) (xy 222.843166 -407.071722)
			(xy 222.85071 -407.06294) (xy 222.868905 -407.04046) (xy 222.910923 -407.000723) (xy 222.958457 -406.967782)
			(xy 223.010417 -406.942393) (xy 223.065615 -406.925136) (xy 223.122784 -406.916408) (xy 223.1517 -406.915874)
			(xy 223.17895 -406.916378) (xy 223.232897 -406.924134) (xy 223.28519 -406.939488) (xy 223.334766 -406.962128)
			(xy 223.380615 -406.991592) (xy 223.421805 -407.027282) (xy 223.457497 -407.06847) (xy 223.486964 -407.114318)
			(xy 223.509606 -407.163893) (xy 223.524962 -407.216186) (xy 223.532721 -407.270132) (xy 223.533208 -407.297382)
			(xy 223.532712 -407.3263) (xy 223.523983 -407.383474) (xy 223.506723 -407.438675) (xy 223.481327 -407.490637)
			(xy 223.448378 -407.53817) (xy 223.408631 -407.580184) (xy 223.386142 -407.598372) (xy 223.377387 -407.60594)
			(xy 223.367202 -407.626695) (xy 223.366584 -407.63825) (xy 223.366584 -407.718514) (xy 223.367152 -407.730082)
			(xy 223.377349 -407.750852) (xy 223.386142 -407.758392) (xy 223.40863 -407.776577) (xy 223.448363 -407.818599)
			(xy 223.481301 -407.866136) (xy 223.506688 -407.918098) (xy 223.523943 -407.973296) (xy 223.532673 -408.030466)
			(xy 223.533208 -408.059382) (xy 223.532728 -408.086634) (xy 223.524973 -408.140585) (xy 223.50962 -408.192882)
			(xy 223.486979 -408.242462) (xy 223.457513 -408.288316) (xy 223.421821 -408.329508) (xy 223.38063 -408.365202)
			(xy 223.334778 -408.394671) (xy 223.285199 -408.417313) (xy 223.232902 -408.43267) (xy 223.178952 -408.440427)
			(xy 223.1517 -408.44089) (xy 223.122783 -408.440375) (xy 223.065611 -408.431646) (xy 223.010412 -408.414388)
			(xy 222.958451 -408.388995) (xy 222.910917 -408.356051) (xy 222.8689 -408.31631) (xy 222.85071 -408.293824)
			(xy 222.843152 -408.285058) (xy 222.82239 -408.27488) (xy 222.810832 -408.274266) (xy 222.730568 -408.274266)
			(xy 222.719002 -408.274852) (xy 222.698229 -408.285033) (xy 222.69069 -408.293824) (xy 222.673937 -408.314607)
			(xy 222.635583 -408.351737) (xy 222.592429 -408.383159) (xy 222.545315 -408.408258) (xy 222.495163 -408.426544)
			(xy 222.442952 -408.437661) (xy 222.3897 -408.441391) (xy 222.336448 -408.437661) (xy 222.284237 -408.426544)
			(xy 222.234085 -408.408258) (xy 222.186971 -408.383159) (xy 222.143817 -408.351737) (xy 222.105463 -408.314607)
			(xy 222.08871 -408.293824) (xy 222.081152 -408.285058) (xy 222.06039 -408.27488) (xy 222.048832 -408.274266)
			(xy 221.968568 -408.274266) (xy 221.957002 -408.274852) (xy 221.936229 -408.285033) (xy 221.92869 -408.293824)
			(xy 221.911937 -408.314607) (xy 221.873583 -408.351737) (xy 221.830429 -408.383159) (xy 221.783315 -408.408258)
			(xy 221.733163 -408.426544) (xy 221.680952 -408.437661) (xy 221.6277 -408.441391) (xy 221.574448 -408.437661)
			(xy 221.522237 -408.426544) (xy 221.472085 -408.408258) (xy 221.424971 -408.383159) (xy 221.381817 -408.351737)
			(xy 221.343463 -408.314607) (xy 221.32671 -408.293824) (xy 221.319152 -408.285058) (xy 221.29839 -408.27488)
			(xy 221.286832 -408.274266) (xy 221.206568 -408.274266) (xy 221.195002 -408.274852) (xy 221.174229 -408.285033)
			(xy 221.16669 -408.293824) (xy 221.149937 -408.314607) (xy 221.111583 -408.351737) (xy 221.068429 -408.383159)
			(xy 221.021315 -408.408258) (xy 220.971163 -408.426544) (xy 220.918952 -408.437661) (xy 220.8657 -408.441391)
			(xy 220.812448 -408.437661) (xy 220.760237 -408.426544) (xy 220.710085 -408.408258) (xy 220.662971 -408.383159)
			(xy 220.619817 -408.351737) (xy 220.581463 -408.314607) (xy 220.56471 -408.293824) (xy 220.557152 -408.285058)
			(xy 220.53639 -408.27488) (xy 220.524832 -408.274266) (xy 220.444568 -408.274266) (xy 220.433002 -408.274852)
			(xy 220.412229 -408.285033) (xy 220.40469 -408.293824) (xy 220.387937 -408.314607) (xy 220.349583 -408.351737)
			(xy 220.306429 -408.383159) (xy 220.259315 -408.408258) (xy 220.209163 -408.426544) (xy 220.156952 -408.437661)
			(xy 220.1037 -408.441391) (xy 220.050448 -408.437661) (xy 219.998237 -408.426544) (xy 219.948085 -408.408258)
			(xy 219.900971 -408.383159) (xy 219.857817 -408.351737) (xy 219.819463 -408.314607) (xy 219.80271 -408.293824)
			(xy 219.795152 -408.285058) (xy 219.77439 -408.27488) (xy 219.762832 -408.274266) (xy 219.682568 -408.274266)
			(xy 219.671002 -408.274852) (xy 219.650229 -408.285033) (xy 219.64269 -408.293824) (xy 219.625937 -408.314607)
			(xy 219.587583 -408.351737) (xy 219.544429 -408.383159) (xy 219.497315 -408.408258) (xy 219.447163 -408.426544)
			(xy 219.394952 -408.437661) (xy 219.3417 -408.441391) (xy 219.288448 -408.437661) (xy 219.236237 -408.426544)
			(xy 219.186085 -408.408258) (xy 219.138971 -408.383159) (xy 219.095817 -408.351737) (xy 219.057463 -408.314607)
			(xy 219.04071 -408.293824) (xy 219.033152 -408.285058) (xy 219.01239 -408.27488) (xy 219.000832 -408.274266)
			(xy 218.920568 -408.274266) (xy 218.909002 -408.274852) (xy 218.888229 -408.285033) (xy 218.88069 -408.293824)
			(xy 218.863937 -408.314607) (xy 218.825583 -408.351737) (xy 218.782429 -408.383159) (xy 218.735315 -408.408258)
			(xy 218.685163 -408.426544) (xy 218.632952 -408.437661) (xy 218.5797 -408.441391) (xy 218.526448 -408.437661)
			(xy 218.474237 -408.426544) (xy 218.424085 -408.408258) (xy 218.376971 -408.383159) (xy 218.333817 -408.351737)
			(xy 218.295463 -408.314607) (xy 218.27871 -408.293824) (xy 218.271152 -408.285058) (xy 218.25039 -408.27488)
			(xy 218.238832 -408.274266) (xy 218.158568 -408.274266) (xy 218.147002 -408.274852) (xy 218.126229 -408.285033)
			(xy 218.11869 -408.293824) (xy 218.100511 -408.316317) (xy 218.058488 -408.356051) (xy 218.01095 -408.388988)
			(xy 217.958987 -408.414374) (xy 217.903787 -408.431629) (xy 217.846617 -408.440356) (xy 217.8177 -408.44089)
			(xy 217.790447 -408.44044) (xy 217.736497 -408.432683) (xy 217.6842 -408.417327) (xy 217.63462 -408.394685)
			(xy 217.588768 -408.365218) (xy 217.547576 -408.329524) (xy 217.511882 -408.288332) (xy 217.482415 -408.24248)
			(xy 217.459773 -408.1929) (xy 217.444417 -408.140603) (xy 217.43666 -408.086653) (xy 217.056208 -408.086653)
			(xy 217.056208 -408.78887) (xy 217.056649 -408.798901) (xy 217.064229 -408.817471) (xy 217.07094 -408.824938)
			(xy 217.560144 -409.314142) (xy 217.567542 -409.320988) (xy 217.586141 -409.328715) (xy 217.596212 -409.329128)
		)
		(stroke
			(width 0)
			(type solid)
		)
		(fill yes)
		(layer "In13.Cu")
		(net "AGND_HSC")
	)
	(gr_poly
		(pts
			(xy 212.758528 -409.329128) (xy 212.768597 -409.328701) (xy 212.787196 -409.320982) (xy 212.794596 -409.314142)
			(xy 213.233 -408.875738) (xy 213.239784 -408.868316) (xy 213.247391 -408.849719) (xy 213.247732 -408.83967)
			(xy 213.247732 -402.928074) (xy 213.248185 -402.908055) (xy 213.255991 -402.868786) (xy 213.271316 -402.831798)
			(xy 213.293571 -402.798516) (xy 213.307422 -402.784056) (xy 213.713314 -402.378164) (xy 213.727768 -402.364423)
			(xy 213.760935 -402.342288) (xy 213.797778 -402.327037) (xy 213.836887 -402.319256) (xy 213.856824 -402.318728)
			(xy 215.09609 -402.318728) (xy 215.106162 -402.318307) (xy 215.124771 -402.310599) (xy 215.132158 -402.303742)
			(xy 215.690196 -401.745704) (xy 215.696887 -401.738259) (xy 215.704482 -401.719762) (xy 215.704468 -401.699765)
			(xy 215.701118 -401.690332) (xy 215.695276 -401.675854) (xy 215.669876 -401.658836) (xy 214.062564 -401.658836)
			(xy 214.033862 -401.685252) (xy 214.032084 -401.705064) (xy 214.029003 -401.733139) (xy 214.015619 -401.788008)
			(xy 213.994293 -401.840304) (xy 213.965488 -401.888885) (xy 213.929836 -401.932687) (xy 213.888115 -401.970754)
			(xy 213.841238 -402.002254) (xy 213.790228 -402.026498) (xy 213.736202 -402.042956) (xy 213.680339 -402.051269)
			(xy 213.6521 -402.051774) (xy 213.651846 -402.051774) (xy 213.621003 -402.051156) (xy 213.560124 -402.041194)
			(xy 213.530688 -402.031962) (xy 213.518496 -402.027898) (xy 213.49335 -402.032216) (xy 213.406228 -402.100796)
			(xy 213.396068 -402.124164) (xy 213.397084 -402.137118) (xy 213.398608 -402.170138) (xy 213.39812 -402.197389)
			(xy 213.390358 -402.251334) (xy 213.374998 -402.303627) (xy 213.352353 -402.353201) (xy 213.322883 -402.399048)
			(xy 213.287189 -402.440234) (xy 213.245997 -402.475921) (xy 213.200145 -402.505384) (xy 213.150567 -402.52802)
			(xy 213.098273 -402.543371) (xy 213.044325 -402.551124) (xy 212.989824 -402.55112) (xy 212.935878 -402.543361)
			(xy 212.883585 -402.528003) (xy 212.83401 -402.505359) (xy 212.788162 -402.475891) (xy 212.746975 -402.440198)
			(xy 212.711286 -402.399007) (xy 212.681823 -402.353156) (xy 212.659184 -402.303579) (xy 212.643831 -402.251285)
			(xy 212.636077 -402.197338) (xy 212.636079 -402.142837) (xy 212.643837 -402.08889) (xy 212.659193 -402.036597)
			(xy 212.681835 -401.987021) (xy 212.711301 -401.941173) (xy 212.746993 -401.899984) (xy 212.788183 -401.864294)
			(xy 212.834033 -401.834829) (xy 212.883609 -401.812188) (xy 212.935903 -401.796834) (xy 212.989849 -401.789078)
			(xy 213.0171 -401.78863) (xy 213.017354 -401.78863) (xy 213.048197 -401.789248) (xy 213.109076 -401.79921)
			(xy 213.138512 -401.808442) (xy 213.150704 -401.812506) (xy 213.17585 -401.808188) (xy 213.262972 -401.739608)
			(xy 213.273132 -401.71624) (xy 213.272116 -401.703286) (xy 213.270592 -401.670266) (xy 213.270717 -401.655346)
			(xy 213.273007 -401.625594) (xy 213.275164 -401.61083) (xy 213.277196 -401.598638) (xy 213.26983 -401.575778)
			(xy 211.901532 -400.20748) (xy 211.894108 -400.200699) (xy 211.875512 -400.193097) (xy 211.865464 -400.192748)
			(xy 211.818728 -400.192748) (xy 211.808707 -400.193163) (xy 211.790188 -400.20083) (xy 211.776019 -400.215005)
			(xy 211.768359 -400.233526) (xy 211.767928 -400.243548) (xy 211.767928 -400.257264) (xy 211.78139 -400.280378)
			(xy 211.793328 -400.287236) (xy 211.817674 -400.302013) (xy 211.862093 -400.337652) (xy 211.900726 -400.379494)
			(xy 211.932715 -400.42661) (xy 211.957349 -400.477955) (xy 211.974083 -400.53239) (xy 211.982546 -400.588707)
			(xy 211.983066 -400.617182) (xy 211.98258 -400.644433) (xy 211.974824 -400.698381) (xy 211.959469 -400.750676)
			(xy 211.936827 -400.800253) (xy 211.907361 -400.846103) (xy 211.87167 -400.887294) (xy 211.830479 -400.922985)
			(xy 211.784629 -400.952451) (xy 211.735052 -400.975093) (xy 211.682757 -400.990448) (xy 211.628809 -400.998204)
			(xy 211.574307 -400.998204) (xy 211.520359 -400.990448) (xy 211.468064 -400.975093) (xy 211.418487 -400.952451)
			(xy 211.372637 -400.922985) (xy 211.331446 -400.887294) (xy 211.295755 -400.846103) (xy 211.266289 -400.800253)
			(xy 211.243647 -400.750676) (xy 211.228292 -400.698381) (xy 211.220536 -400.644433) (xy 211.22005 -400.617182)
			(xy 211.220534 -400.589234) (xy 211.228681 -400.533934) (xy 211.244814 -400.480417) (xy 211.268587 -400.429828)
			(xy 211.299489 -400.38325) (xy 211.31784 -400.362166) (xy 211.328 -400.350736) (xy 211.332572 -400.321272)
			(xy 211.28863 -400.22272) (xy 211.284218 -400.214037) (xy 211.270171 -400.200569) (xy 211.25213 -400.193276)
			(xy 211.242402 -400.192748) (xy 210.563714 -400.192748) (xy 210.553965 -400.193173) (xy 210.535881 -400.200455)
			(xy 210.521856 -400.213995) (xy 210.517486 -400.22272) (xy 210.473544 -400.321272) (xy 210.478116 -400.350736)
			(xy 210.488276 -400.362166) (xy 210.506594 -400.383277) (xy 210.537493 -400.429852) (xy 210.561269 -400.480435)
			(xy 210.577414 -400.533944) (xy 210.585582 -400.589236) (xy 210.586066 -400.617182) (xy 210.58558 -400.644433)
			(xy 210.577824 -400.698381) (xy 210.562469 -400.750676) (xy 210.539827 -400.800253) (xy 210.510361 -400.846103)
			(xy 210.47467 -400.887294) (xy 210.433479 -400.922985) (xy 210.387629 -400.952451) (xy 210.338052 -400.975093)
			(xy 210.285757 -400.990448) (xy 210.231809 -400.998204) (xy 210.177307 -400.998204) (xy 210.123359 -400.990448)
			(xy 210.071064 -400.975093) (xy 210.021487 -400.952451) (xy 209.975637 -400.922985) (xy 209.934446 -400.887294)
			(xy 209.898755 -400.846103) (xy 209.869289 -400.800253) (xy 209.846647 -400.750676) (xy 209.831292 -400.698381)
			(xy 209.823536 -400.644433) (xy 209.82305 -400.617182) (xy 209.823534 -400.589234) (xy 209.831681 -400.533934)
			(xy 209.847814 -400.480417) (xy 209.871587 -400.429828) (xy 209.902489 -400.38325) (xy 209.92084 -400.362166)
			(xy 209.931 -400.350736) (xy 209.935572 -400.321272) (xy 209.89163 -400.22272) (xy 209.887218 -400.214037)
			(xy 209.873171 -400.200569) (xy 209.85513 -400.193276) (xy 209.845402 -400.192748) (xy 209.141314 -400.192748)
			(xy 209.131565 -400.193173) (xy 209.113481 -400.200455) (xy 209.099456 -400.213995) (xy 209.095086 -400.22272)
			(xy 209.051144 -400.321272) (xy 209.055716 -400.350736) (xy 209.065876 -400.362166) (xy 209.084194 -400.383277)
			(xy 209.115093 -400.429852) (xy 209.138869 -400.480435) (xy 209.155014 -400.533944) (xy 209.163182 -400.589236)
			(xy 209.163666 -400.617182) (xy 209.16318 -400.644433) (xy 209.155424 -400.698381) (xy 209.140069 -400.750676)
			(xy 209.117427 -400.800253) (xy 209.087961 -400.846103) (xy 209.05227 -400.887294) (xy 209.011079 -400.922985)
			(xy 208.965229 -400.952451) (xy 208.915652 -400.975093) (xy 208.863357 -400.990448) (xy 208.809409 -400.998204)
			(xy 208.754907 -400.998204) (xy 208.700959 -400.990448) (xy 208.648664 -400.975093) (xy 208.599087 -400.952451)
			(xy 208.553237 -400.922985) (xy 208.512046 -400.887294) (xy 208.476355 -400.846103) (xy 208.446889 -400.800253)
			(xy 208.424247 -400.750676) (xy 208.408892 -400.698381) (xy 208.401136 -400.644433) (xy 208.40065 -400.617182)
			(xy 208.401134 -400.589234) (xy 208.409281 -400.533934) (xy 208.425414 -400.480417) (xy 208.449187 -400.429828)
			(xy 208.480089 -400.38325) (xy 208.49844 -400.362166) (xy 208.5086 -400.350736) (xy 208.513172 -400.321272)
			(xy 208.46923 -400.22272) (xy 208.464818 -400.214037) (xy 208.450771 -400.200569) (xy 208.43273 -400.193276)
			(xy 208.423002 -400.192748) (xy 206.627476 -400.192748) (xy 206.617451 -400.1932) (xy 206.598898 -400.200798)
			(xy 206.591408 -400.20748) (xy 205.628748 -401.17014) (xy 206.158082 -401.17014) (xy 206.162153 -401.114518)
			(xy 206.174279 -401.060081) (xy 206.194202 -401.00799) (xy 206.221498 -400.959355) (xy 206.255584 -400.915212)
			(xy 206.295733 -400.876503) (xy 206.341091 -400.844052) (xy 206.390691 -400.818551) (xy 206.443475 -400.800544)
			(xy 206.498318 -400.790414) (xy 206.554052 -400.788377) (xy 206.609489 -400.794477) (xy 206.663446 -400.808583)
			(xy 206.714775 -400.830395) (xy 206.762381 -400.859449) (xy 206.805249 -400.895124) (xy 206.842466 -400.936661)
			(xy 206.873239 -400.983174) (xy 206.896911 -401.033671) (xy 206.912979 -401.087078) (xy 206.921099 -401.142254)
			(xy 206.921608 -401.17014) (xy 206.921099 -401.198026) (xy 206.912979 -401.253202) (xy 206.896911 -401.306609)
			(xy 206.873239 -401.357106) (xy 206.842466 -401.403619) (xy 206.805249 -401.445156) (xy 206.762381 -401.480831)
			(xy 206.714775 -401.509885) (xy 206.663446 -401.531697) (xy 206.609489 -401.545803) (xy 206.554052 -401.551903)
			(xy 206.498318 -401.549866) (xy 206.443475 -401.539736) (xy 206.390691 -401.521729) (xy 206.341091 -401.496228)
			(xy 206.295733 -401.463777) (xy 206.255584 -401.425068) (xy 206.221498 -401.380925) (xy 206.194202 -401.33229)
			(xy 206.174279 -401.280199) (xy 206.162153 -401.225762) (xy 206.158082 -401.17014) (xy 205.628748 -401.17014)
			(xy 205.329028 -401.46986) (xy 205.322328 -401.477303) (xy 205.314716 -401.495804) (xy 205.314719 -401.515809)
			(xy 205.318106 -401.525232) (xy 205.323948 -401.53971) (xy 205.349348 -401.556728) (xy 206.050642 -401.556728)
			(xy 206.070576 -401.557245) (xy 206.109673 -401.565059) (xy 206.146506 -401.580323) (xy 206.17967 -401.602455)
			(xy 206.194152 -401.616164) (xy 206.49819 -401.920202) (xy 208.40014 -401.920202) (xy 208.404211 -401.86458)
			(xy 208.416337 -401.810143) (xy 208.43626 -401.758052) (xy 208.463556 -401.709417) (xy 208.497642 -401.665274)
			(xy 208.537791 -401.626565) (xy 208.583149 -401.594114) (xy 208.632749 -401.568613) (xy 208.685533 -401.550606)
			(xy 208.740376 -401.540476) (xy 208.79611 -401.538439) (xy 208.851547 -401.544539) (xy 208.905504 -401.558645)
			(xy 208.956833 -401.580457) (xy 209.004439 -401.609511) (xy 209.047307 -401.645186) (xy 209.084524 -401.686723)
			(xy 209.115297 -401.733236) (xy 209.138969 -401.783733) (xy 209.155037 -401.83714) (xy 209.163157 -401.892316)
			(xy 209.163666 -401.920202) (xy 211.21954 -401.920202) (xy 211.223611 -401.86458) (xy 211.235737 -401.810143)
			(xy 211.25566 -401.758052) (xy 211.282956 -401.709417) (xy 211.317042 -401.665274) (xy 211.357191 -401.626565)
			(xy 211.402549 -401.594114) (xy 211.452149 -401.568613) (xy 211.504933 -401.550606) (xy 211.559776 -401.540476)
			(xy 211.61551 -401.538439) (xy 211.670947 -401.544539) (xy 211.724904 -401.558645) (xy 211.776233 -401.580457)
			(xy 211.823839 -401.609511) (xy 211.866707 -401.645186) (xy 211.903924 -401.686723) (xy 211.934697 -401.733236)
			(xy 211.958369 -401.783733) (xy 211.974437 -401.83714) (xy 211.982557 -401.892316) (xy 211.983066 -401.920202)
			(xy 211.982557 -401.948088) (xy 211.974437 -402.003264) (xy 211.958369 -402.056671) (xy 211.934697 -402.107168)
			(xy 211.903924 -402.153681) (xy 211.866707 -402.195218) (xy 211.823839 -402.230893) (xy 211.776233 -402.259947)
			(xy 211.724904 -402.281759) (xy 211.670947 -402.295865) (xy 211.61551 -402.301965) (xy 211.559776 -402.299928)
			(xy 211.504933 -402.289798) (xy 211.452149 -402.271791) (xy 211.402549 -402.24629) (xy 211.357191 -402.213839)
			(xy 211.317042 -402.17513) (xy 211.282956 -402.130987) (xy 211.25566 -402.082352) (xy 211.235737 -402.030261)
			(xy 211.223611 -401.975824) (xy 211.21954 -401.920202) (xy 209.163666 -401.920202) (xy 209.163157 -401.948088)
			(xy 209.155037 -402.003264) (xy 209.138969 -402.056671) (xy 209.115297 -402.107168) (xy 209.084524 -402.153681)
			(xy 209.047307 -402.195218) (xy 209.004439 -402.230893) (xy 208.956833 -402.259947) (xy 208.905504 -402.281759)
			(xy 208.851547 -402.295865) (xy 208.79611 -402.301965) (xy 208.740376 -402.299928) (xy 208.685533 -402.289798)
			(xy 208.632749 -402.271791) (xy 208.583149 -402.24629) (xy 208.537791 -402.213839) (xy 208.497642 -402.17513)
			(xy 208.463556 -402.130987) (xy 208.43626 -402.082352) (xy 208.416337 -402.030261) (xy 208.404211 -401.975824)
			(xy 208.40014 -401.920202) (xy 206.49819 -401.920202) (xy 207.367632 -402.789644) (xy 207.380078 -402.796502)
			(xy 207.38719 -402.79828) (xy 207.414884 -402.805169) (xy 207.467993 -402.826054) (xy 207.517398 -402.854615)
			(xy 207.561999 -402.890216) (xy 207.600799 -402.932063) (xy 207.632935 -402.979222) (xy 207.657688 -403.030641)
			(xy 207.674506 -403.085173) (xy 207.683015 -403.141603) (xy 207.683608 -403.170136) (xy 207.683188 -403.195799)
			(xy 207.679474 -403.223222) (xy 208.40014 -403.223222) (xy 208.404211 -403.1676) (xy 208.416337 -403.113163)
			(xy 208.43626 -403.061072) (xy 208.463556 -403.012437) (xy 208.497642 -402.968294) (xy 208.537791 -402.929585)
			(xy 208.583149 -402.897134) (xy 208.632749 -402.871633) (xy 208.685533 -402.853626) (xy 208.740376 -402.843496)
			(xy 208.79611 -402.841459) (xy 208.851547 -402.847559) (xy 208.905504 -402.861665) (xy 208.956833 -402.883477)
			(xy 209.004439 -402.912531) (xy 209.047307 -402.948206) (xy 209.084524 -402.989743) (xy 209.115297 -403.036256)
			(xy 209.138969 -403.086753) (xy 209.155037 -403.14016) (xy 209.163157 -403.195336) (xy 209.163666 -403.223222)
			(xy 209.82254 -403.223222) (xy 209.826611 -403.1676) (xy 209.838737 -403.113163) (xy 209.85866 -403.061072)
			(xy 209.885956 -403.012437) (xy 209.920042 -402.968294) (xy 209.960191 -402.929585) (xy 210.005549 -402.897134)
			(xy 210.055149 -402.871633) (xy 210.107933 -402.853626) (xy 210.162776 -402.843496) (xy 210.21851 -402.841459)
			(xy 210.273947 -402.847559) (xy 210.327904 -402.861665) (xy 210.379233 -402.883477) (xy 210.426839 -402.912531)
			(xy 210.469707 -402.948206) (xy 210.506924 -402.989743) (xy 210.537697 -403.036256) (xy 210.561369 -403.086753)
			(xy 210.577437 -403.14016) (xy 210.585557 -403.195336) (xy 210.586066 -403.223222) (xy 211.21954 -403.223222)
			(xy 211.223611 -403.1676) (xy 211.235737 -403.113163) (xy 211.25566 -403.061072) (xy 211.282956 -403.012437)
			(xy 211.317042 -402.968294) (xy 211.357191 -402.929585) (xy 211.402549 -402.897134) (xy 211.452149 -402.871633)
			(xy 211.504933 -402.853626) (xy 211.559776 -402.843496) (xy 211.61551 -402.841459) (xy 211.670947 -402.847559)
			(xy 211.724904 -402.861665) (xy 211.776233 -402.883477) (xy 211.823839 -402.912531) (xy 211.866707 -402.948206)
			(xy 211.903924 -402.989743) (xy 211.934697 -403.036256) (xy 211.958369 -403.086753) (xy 211.974437 -403.14016)
			(xy 211.982557 -403.195336) (xy 211.983066 -403.223222) (xy 211.982557 -403.251108) (xy 211.974437 -403.306284)
			(xy 211.958369 -403.359691) (xy 211.934697 -403.410188) (xy 211.903924 -403.456701) (xy 211.866707 -403.498238)
			(xy 211.823839 -403.533913) (xy 211.776233 -403.562967) (xy 211.724904 -403.584779) (xy 211.670947 -403.598885)
			(xy 211.61551 -403.604985) (xy 211.559776 -403.602948) (xy 211.504933 -403.592818) (xy 211.452149 -403.574811)
			(xy 211.402549 -403.54931) (xy 211.357191 -403.516859) (xy 211.317042 -403.47815) (xy 211.282956 -403.434007)
			(xy 211.25566 -403.385372) (xy 211.235737 -403.333281) (xy 211.223611 -403.278844) (xy 211.21954 -403.223222)
			(xy 210.586066 -403.223222) (xy 210.585557 -403.251108) (xy 210.577437 -403.306284) (xy 210.561369 -403.359691)
			(xy 210.537697 -403.410188) (xy 210.506924 -403.456701) (xy 210.469707 -403.498238) (xy 210.426839 -403.533913)
			(xy 210.379233 -403.562967) (xy 210.327904 -403.584779) (xy 210.273947 -403.598885) (xy 210.21851 -403.604985)
			(xy 210.162776 -403.602948) (xy 210.107933 -403.592818) (xy 210.055149 -403.574811) (xy 210.005549 -403.54931)
			(xy 209.960191 -403.516859) (xy 209.920042 -403.47815) (xy 209.885956 -403.434007) (xy 209.85866 -403.385372)
			(xy 209.838737 -403.333281) (xy 209.826611 -403.278844) (xy 209.82254 -403.223222) (xy 209.163666 -403.223222)
			(xy 209.163157 -403.251108) (xy 209.155037 -403.306284) (xy 209.138969 -403.359691) (xy 209.115297 -403.410188)
			(xy 209.084524 -403.456701) (xy 209.047307 -403.498238) (xy 209.004439 -403.533913) (xy 208.956833 -403.562967)
			(xy 208.905504 -403.584779) (xy 208.851547 -403.598885) (xy 208.79611 -403.604985) (xy 208.740376 -403.602948)
			(xy 208.685533 -403.592818) (xy 208.632749 -403.574811) (xy 208.583149 -403.54931) (xy 208.537791 -403.516859)
			(xy 208.497642 -403.47815) (xy 208.463556 -403.434007) (xy 208.43626 -403.385372) (xy 208.416337 -403.333281)
			(xy 208.404211 -403.278844) (xy 208.40014 -403.223222) (xy 207.679474 -403.223222) (xy 207.6763 -403.24666)
			(xy 207.662653 -403.296137) (xy 207.642495 -403.343338) (xy 207.616189 -403.387409) (xy 207.58421 -403.427554)
			(xy 207.547136 -403.463048) (xy 207.526636 -403.478492) (xy 207.517377 -403.486098) (xy 207.506518 -403.507424)
			(xy 207.505808 -403.519386) (xy 207.505808 -406.27046) (xy 207.505353 -406.290478) (xy 207.497542 -406.329744)
			(xy 207.482215 -406.36673) (xy 207.45996 -406.40001) (xy 207.446118 -406.414478) (xy 206.40294 -407.457402)
			(xy 206.401162 -407.459434) (xy 206.21498 -407.645362) (xy 206.208198 -407.652786) (xy 206.200594 -407.671382)
			(xy 206.200248 -407.68143) (xy 206.200248 -408.086653) (xy 206.76866 -408.086653) (xy 206.76866 -408.032147)
			(xy 206.776417 -407.978197) (xy 206.791773 -407.9259) (xy 206.814415 -407.87632) (xy 206.843882 -407.830468)
			(xy 206.879576 -407.789276) (xy 206.920768 -407.753582) (xy 206.96662 -407.724115) (xy 207.0162 -407.701473)
			(xy 207.068497 -407.686117) (xy 207.122447 -407.67836) (xy 207.1497 -407.677874) (xy 207.178618 -407.678364)
			(xy 207.235792 -407.687095) (xy 207.290993 -407.704357) (xy 207.342955 -407.729754) (xy 207.390488 -407.762703)
			(xy 207.432502 -407.802451) (xy 207.45069 -407.82494) (xy 207.458254 -407.8337) (xy 207.479011 -407.843883)
			(xy 207.490568 -407.844498) (xy 207.570832 -407.844498) (xy 207.582395 -407.843889) (xy 207.603166 -407.833722)
			(xy 207.61071 -407.82494) (xy 207.625486 -407.806539) (xy 207.658858 -407.77317) (xy 207.677258 -407.758392)
			(xy 207.686029 -407.750839) (xy 207.696205 -407.730073) (xy 207.696816 -407.718514) (xy 207.696816 -407.63825)
			(xy 207.696211 -407.626687) (xy 207.68604 -407.605916) (xy 207.677258 -407.598372) (xy 207.654752 -407.580207)
			(xy 207.61502 -407.538181) (xy 207.582085 -407.49064) (xy 207.556701 -407.438674) (xy 207.539449 -407.383472)
			(xy 207.530725 -407.326299) (xy 207.530192 -407.297382) (xy 207.530661 -407.27013) (xy 207.53842 -407.216182)
			(xy 207.553777 -407.163887) (xy 207.576421 -407.11431) (xy 207.605889 -407.068459) (xy 207.641582 -407.027269)
			(xy 207.682774 -406.991578) (xy 207.728625 -406.962112) (xy 207.778204 -406.939471) (xy 207.8305 -406.924116)
			(xy 207.884448 -406.91636) (xy 207.9117 -406.915874) (xy 207.940618 -406.916364) (xy 207.997792 -406.925095)
			(xy 208.052993 -406.942357) (xy 208.104955 -406.967754) (xy 208.152488 -407.000703) (xy 208.194502 -407.040451)
			(xy 208.21269 -407.06294) (xy 208.220254 -407.0717) (xy 208.241011 -407.081883) (xy 208.252568 -407.082498)
			(xy 208.332832 -407.082498) (xy 208.344395 -407.081889) (xy 208.365166 -407.071722) (xy 208.37271 -407.06294)
			(xy 208.387486 -407.044539) (xy 208.420858 -407.01117) (xy 208.439258 -406.996392) (xy 208.448029 -406.988839)
			(xy 208.458205 -406.968073) (xy 208.458816 -406.956514) (xy 208.458816 -406.87625) (xy 208.458211 -406.864687)
			(xy 208.44804 -406.843916) (xy 208.439258 -406.836372) (xy 208.418457 -406.81964) (xy 208.381327 -406.781284)
			(xy 208.349905 -406.738127) (xy 208.324807 -406.691011) (xy 208.306521 -406.640856) (xy 208.295406 -406.588642)
			(xy 208.291678 -406.535389) (xy 208.295409 -406.482136) (xy 208.306528 -406.429922) (xy 208.324816 -406.379769)
			(xy 208.349917 -406.332654) (xy 208.381341 -406.289499) (xy 208.418474 -406.251145) (xy 208.439258 -406.234392)
			(xy 208.448029 -406.226839) (xy 208.458205 -406.206073) (xy 208.458816 -406.194514) (xy 208.458816 -406.11425)
			(xy 208.458211 -406.102687) (xy 208.44804 -406.081916) (xy 208.439258 -406.074372) (xy 208.418457 -406.05764)
			(xy 208.381327 -406.019284) (xy 208.349905 -405.976127) (xy 208.324807 -405.929011) (xy 208.306521 -405.878856)
			(xy 208.295406 -405.826642) (xy 208.291678 -405.773389) (xy 208.295409 -405.720136) (xy 208.306528 -405.667922)
			(xy 208.324816 -405.617769) (xy 208.349917 -405.570654) (xy 208.381341 -405.527499) (xy 208.418474 -405.489145)
			(xy 208.439258 -405.472392) (xy 208.448029 -405.464839) (xy 208.458205 -405.444073) (xy 208.458816 -405.432514)
			(xy 208.458816 -405.35225) (xy 208.458211 -405.340687) (xy 208.44804 -405.319916) (xy 208.439258 -405.312372)
			(xy 208.416752 -405.294207) (xy 208.37702 -405.252181) (xy 208.344085 -405.20464) (xy 208.318701 -405.152674)
			(xy 208.301449 -405.097472) (xy 208.292725 -405.040299) (xy 208.292192 -405.011382) (xy 208.292661 -404.98413)
			(xy 208.30042 -404.930182) (xy 208.315777 -404.877887) (xy 208.338421 -404.82831) (xy 208.367889 -404.782459)
			(xy 208.403582 -404.741269) (xy 208.444774 -404.705578) (xy 208.490625 -404.676112) (xy 208.540204 -404.653471)
			(xy 208.5925 -404.638116) (xy 208.646448 -404.63036) (xy 208.6737 -404.629874) (xy 208.702618 -404.630364)
			(xy 208.759792 -404.639095) (xy 208.814993 -404.656357) (xy 208.866955 -404.681754) (xy 208.914488 -404.714703)
			(xy 208.956502 -404.754451) (xy 208.97469 -404.77694) (xy 208.982254 -404.7857) (xy 209.003011 -404.795883)
			(xy 209.014568 -404.796498) (xy 209.094832 -404.796498) (xy 209.106395 -404.795889) (xy 209.127166 -404.785722)
			(xy 209.13471 -404.77694) (xy 209.151463 -404.756157) (xy 209.189817 -404.719027) (xy 209.232971 -404.687605)
			(xy 209.280085 -404.662506) (xy 209.330237 -404.64422) (xy 209.382448 -404.633103) (xy 209.4357 -404.629373)
			(xy 209.488952 -404.633103) (xy 209.541163 -404.64422) (xy 209.591315 -404.662506) (xy 209.638429 -404.687605)
			(xy 209.681583 -404.719027) (xy 209.719937 -404.756157) (xy 209.73669 -404.77694) (xy 209.744254 -404.7857)
			(xy 209.765011 -404.795883) (xy 209.776568 -404.796498) (xy 209.856832 -404.796498) (xy 209.868395 -404.795889)
			(xy 209.889166 -404.785722) (xy 209.89671 -404.77694) (xy 209.913463 -404.756157) (xy 209.951817 -404.719027)
			(xy 209.994971 -404.687605) (xy 210.042085 -404.662506) (xy 210.092237 -404.64422) (xy 210.144448 -404.633103)
			(xy 210.1977 -404.629373) (xy 210.250952 -404.633103) (xy 210.303163 -404.64422) (xy 210.353315 -404.662506)
			(xy 210.400429 -404.687605) (xy 210.443583 -404.719027) (xy 210.481937 -404.756157) (xy 210.49869 -404.77694)
			(xy 210.506254 -404.7857) (xy 210.527011 -404.795883) (xy 210.538568 -404.796498) (xy 210.618832 -404.796498)
			(xy 210.630395 -404.795889) (xy 210.651166 -404.785722) (xy 210.65871 -404.77694) (xy 210.675463 -404.756157)
			(xy 210.713817 -404.719027) (xy 210.756971 -404.687605) (xy 210.804085 -404.662506) (xy 210.854237 -404.64422)
			(xy 210.906448 -404.633103) (xy 210.9597 -404.629373) (xy 211.012952 -404.633103) (xy 211.065163 -404.64422)
			(xy 211.115315 -404.662506) (xy 211.162429 -404.687605) (xy 211.205583 -404.719027) (xy 211.243937 -404.756157)
			(xy 211.26069 -404.77694) (xy 211.268254 -404.7857) (xy 211.289011 -404.795883) (xy 211.300568 -404.796498)
			(xy 211.380832 -404.796498) (xy 211.392395 -404.795889) (xy 211.413166 -404.785722) (xy 211.42071 -404.77694)
			(xy 211.438905 -404.75446) (xy 211.480923 -404.714723) (xy 211.528457 -404.681782) (xy 211.580417 -404.656393)
			(xy 211.635615 -404.639136) (xy 211.692784 -404.630408) (xy 211.7217 -404.629874) (xy 211.74895 -404.630378)
			(xy 211.802897 -404.638134) (xy 211.85519 -404.653488) (xy 211.904766 -404.676128) (xy 211.950615 -404.705592)
			(xy 211.991805 -404.741282) (xy 212.027497 -404.78247) (xy 212.056964 -404.828318) (xy 212.079606 -404.877893)
			(xy 212.094962 -404.930186) (xy 212.102721 -404.984132) (xy 212.103208 -405.011382) (xy 212.102712 -405.0403)
			(xy 212.093983 -405.097474) (xy 212.076723 -405.152675) (xy 212.051327 -405.204637) (xy 212.018378 -405.25217)
			(xy 211.978631 -405.294184) (xy 211.956142 -405.312372) (xy 211.947387 -405.31994) (xy 211.937202 -405.340695)
			(xy 211.936584 -405.35225) (xy 211.936584 -405.432514) (xy 211.937152 -405.444082) (xy 211.947349 -405.464852)
			(xy 211.956142 -405.472392) (xy 211.976907 -405.489167) (xy 212.014037 -405.527517) (xy 212.045459 -405.570669)
			(xy 212.070558 -405.61778) (xy 212.088845 -405.66793) (xy 212.099963 -405.72014) (xy 212.103694 -405.773389)
			(xy 212.099966 -405.826639) (xy 212.088851 -405.878849) (xy 212.070567 -405.928999) (xy 212.04547 -405.976112)
			(xy 212.014052 -406.019266) (xy 211.976924 -406.057619) (xy 211.956142 -406.074372) (xy 211.947387 -406.08194)
			(xy 211.937202 -406.102695) (xy 211.936584 -406.11425) (xy 211.936584 -406.194514) (xy 211.937152 -406.206082)
			(xy 211.947349 -406.226852) (xy 211.956142 -406.234392) (xy 211.976907 -406.251167) (xy 212.014037 -406.289517)
			(xy 212.045459 -406.332669) (xy 212.070558 -406.37978) (xy 212.088845 -406.42993) (xy 212.099963 -406.48214)
			(xy 212.103694 -406.535389) (xy 212.099966 -406.588639) (xy 212.088851 -406.640849) (xy 212.070567 -406.690999)
			(xy 212.04547 -406.738112) (xy 212.014052 -406.781266) (xy 211.976924 -406.819619) (xy 211.956142 -406.836372)
			(xy 211.947387 -406.84394) (xy 211.937202 -406.864695) (xy 211.936584 -406.87625) (xy 211.936584 -406.956514)
			(xy 211.937152 -406.968082) (xy 211.947349 -406.988852) (xy 211.956142 -406.996392) (xy 211.97454 -407.011172)
			(xy 212.007911 -407.044541) (xy 212.02269 -407.06294) (xy 212.030254 -407.0717) (xy 212.051011 -407.081883)
			(xy 212.062568 -407.082498) (xy 212.142832 -407.082498) (xy 212.154395 -407.081889) (xy 212.175166 -407.071722)
			(xy 212.18271 -407.06294) (xy 212.200905 -407.04046) (xy 212.242923 -407.000723) (xy 212.290457 -406.967782)
			(xy 212.342417 -406.942393) (xy 212.397615 -406.925136) (xy 212.454784 -406.916408) (xy 212.4837 -406.915874)
			(xy 212.51095 -406.916378) (xy 212.564897 -406.924134) (xy 212.61719 -406.939488) (xy 212.666766 -406.962128)
			(xy 212.712615 -406.991592) (xy 212.753805 -407.027282) (xy 212.789497 -407.06847) (xy 212.818964 -407.114318)
			(xy 212.841606 -407.163893) (xy 212.856962 -407.216186) (xy 212.864721 -407.270132) (xy 212.865208 -407.297382)
			(xy 212.864712 -407.3263) (xy 212.855983 -407.383474) (xy 212.838723 -407.438675) (xy 212.813327 -407.490637)
			(xy 212.780378 -407.53817) (xy 212.740631 -407.580184) (xy 212.718142 -407.598372) (xy 212.709387 -407.60594)
			(xy 212.699202 -407.626695) (xy 212.698584 -407.63825) (xy 212.698584 -407.718514) (xy 212.699152 -407.730082)
			(xy 212.709349 -407.750852) (xy 212.718142 -407.758392) (xy 212.74063 -407.776577) (xy 212.780363 -407.818599)
			(xy 212.813301 -407.866136) (xy 212.838688 -407.918098) (xy 212.855943 -407.973296) (xy 212.864673 -408.030466)
			(xy 212.865208 -408.059382) (xy 212.864728 -408.086634) (xy 212.856973 -408.140585) (xy 212.84162 -408.192882)
			(xy 212.818979 -408.242462) (xy 212.789513 -408.288316) (xy 212.753821 -408.329508) (xy 212.71263 -408.365202)
			(xy 212.666778 -408.394671) (xy 212.617199 -408.417313) (xy 212.564902 -408.43267) (xy 212.510952 -408.440427)
			(xy 212.4837 -408.44089) (xy 212.454783 -408.440375) (xy 212.397611 -408.431646) (xy 212.342412 -408.414388)
			(xy 212.290451 -408.388995) (xy 212.242917 -408.356051) (xy 212.2009 -408.31631) (xy 212.18271 -408.293824)
			(xy 212.175152 -408.285058) (xy 212.15439 -408.27488) (xy 212.142832 -408.274266) (xy 212.062568 -408.274266)
			(xy 212.051002 -408.274852) (xy 212.030229 -408.285033) (xy 212.02269 -408.293824) (xy 212.005937 -408.314607)
			(xy 211.967583 -408.351737) (xy 211.924429 -408.383159) (xy 211.877315 -408.408258) (xy 211.827163 -408.426544)
			(xy 211.774952 -408.437661) (xy 211.7217 -408.441391) (xy 211.668448 -408.437661) (xy 211.616237 -408.426544)
			(xy 211.566085 -408.408258) (xy 211.518971 -408.383159) (xy 211.475817 -408.351737) (xy 211.437463 -408.314607)
			(xy 211.42071 -408.293824) (xy 211.413152 -408.285058) (xy 211.39239 -408.27488) (xy 211.380832 -408.274266)
			(xy 211.300568 -408.274266) (xy 211.289002 -408.274852) (xy 211.268229 -408.285033) (xy 211.26069 -408.293824)
			(xy 211.243937 -408.314607) (xy 211.205583 -408.351737) (xy 211.162429 -408.383159) (xy 211.115315 -408.408258)
			(xy 211.065163 -408.426544) (xy 211.012952 -408.437661) (xy 210.9597 -408.441391) (xy 210.906448 -408.437661)
			(xy 210.854237 -408.426544) (xy 210.804085 -408.408258) (xy 210.756971 -408.383159) (xy 210.713817 -408.351737)
			(xy 210.675463 -408.314607) (xy 210.65871 -408.293824) (xy 210.651152 -408.285058) (xy 210.63039 -408.27488)
			(xy 210.618832 -408.274266) (xy 210.538568 -408.274266) (xy 210.527002 -408.274852) (xy 210.506229 -408.285033)
			(xy 210.49869 -408.293824) (xy 210.481937 -408.314607) (xy 210.443583 -408.351737) (xy 210.400429 -408.383159)
			(xy 210.353315 -408.408258) (xy 210.303163 -408.426544) (xy 210.250952 -408.437661) (xy 210.1977 -408.441391)
			(xy 210.144448 -408.437661) (xy 210.092237 -408.426544) (xy 210.042085 -408.408258) (xy 209.994971 -408.383159)
			(xy 209.951817 -408.351737) (xy 209.913463 -408.314607) (xy 209.89671 -408.293824) (xy 209.889152 -408.285058)
			(xy 209.86839 -408.27488) (xy 209.856832 -408.274266) (xy 209.776568 -408.274266) (xy 209.765002 -408.274852)
			(xy 209.744229 -408.285033) (xy 209.73669 -408.293824) (xy 209.719937 -408.314607) (xy 209.681583 -408.351737)
			(xy 209.638429 -408.383159) (xy 209.591315 -408.408258) (xy 209.541163 -408.426544) (xy 209.488952 -408.437661)
			(xy 209.4357 -408.441391) (xy 209.382448 -408.437661) (xy 209.330237 -408.426544) (xy 209.280085 -408.408258)
			(xy 209.232971 -408.383159) (xy 209.189817 -408.351737) (xy 209.151463 -408.314607) (xy 209.13471 -408.293824)
			(xy 209.127152 -408.285058) (xy 209.10639 -408.27488) (xy 209.094832 -408.274266) (xy 209.014568 -408.274266)
			(xy 209.003002 -408.274852) (xy 208.982229 -408.285033) (xy 208.97469 -408.293824) (xy 208.957937 -408.314607)
			(xy 208.919583 -408.351737) (xy 208.876429 -408.383159) (xy 208.829315 -408.408258) (xy 208.779163 -408.426544)
			(xy 208.726952 -408.437661) (xy 208.6737 -408.441391) (xy 208.620448 -408.437661) (xy 208.568237 -408.426544)
			(xy 208.518085 -408.408258) (xy 208.470971 -408.383159) (xy 208.427817 -408.351737) (xy 208.389463 -408.314607)
			(xy 208.37271 -408.293824) (xy 208.365152 -408.285058) (xy 208.34439 -408.27488) (xy 208.332832 -408.274266)
			(xy 208.252568 -408.274266) (xy 208.241002 -408.274852) (xy 208.220229 -408.285033) (xy 208.21269 -408.293824)
			(xy 208.195937 -408.314607) (xy 208.157583 -408.351737) (xy 208.114429 -408.383159) (xy 208.067315 -408.408258)
			(xy 208.017163 -408.426544) (xy 207.964952 -408.437661) (xy 207.9117 -408.441391) (xy 207.858448 -408.437661)
			(xy 207.806237 -408.426544) (xy 207.756085 -408.408258) (xy 207.708971 -408.383159) (xy 207.665817 -408.351737)
			(xy 207.627463 -408.314607) (xy 207.61071 -408.293824) (xy 207.603152 -408.285058) (xy 207.58239 -408.27488)
			(xy 207.570832 -408.274266) (xy 207.490568 -408.274266) (xy 207.479002 -408.274852) (xy 207.458229 -408.285033)
			(xy 207.45069 -408.293824) (xy 207.432511 -408.316317) (xy 207.390488 -408.356051) (xy 207.34295 -408.388988)
			(xy 207.290987 -408.414374) (xy 207.235787 -408.431629) (xy 207.178617 -408.440356) (xy 207.1497 -408.44089)
			(xy 207.122447 -408.44044) (xy 207.068497 -408.432683) (xy 207.0162 -408.417327) (xy 206.96662 -408.394685)
			(xy 206.920768 -408.365218) (xy 206.879576 -408.329524) (xy 206.843882 -408.288332) (xy 206.814415 -408.24248)
			(xy 206.791773 -408.1929) (xy 206.776417 -408.140603) (xy 206.76866 -408.086653) (xy 206.200248 -408.086653)
			(xy 206.200248 -408.60091) (xy 206.200698 -408.610937) (xy 206.208292 -408.629492) (xy 206.21498 -408.636978)
			(xy 206.401416 -408.82316) (xy 206.40294 -408.824938) (xy 206.892144 -409.314142) (xy 206.899542 -409.320988)
			(xy 206.918141 -409.328715) (xy 206.928212 -409.329128)
		)
		(stroke
			(width 0)
			(type solid)
		)
		(fill yes)
		(layer "In13.Cu")
		(net "AGND_HSC")
	)
	(gr_poly
		(pts
			(xy 212.484462 -399.318988) (xy 212.494527 -399.318553) (xy 212.513114 -399.310822) (xy 212.52053 -399.304002)
			(xy 213.827868 -397.996664) (xy 213.835267 -397.989821) (xy 213.853866 -397.982101) (xy 213.863936 -397.981678)
			(xy 217.608912 -397.981678) (xy 217.618982 -397.982103) (xy 217.637585 -397.989818) (xy 217.64498 -397.996664)
			(xy 218.952318 -399.304002) (xy 218.959718 -399.310845) (xy 218.978316 -399.318573) (xy 218.988386 -399.318988)
			(xy 223.134936 -399.318988) (xy 223.145003 -399.318558) (xy 223.163597 -399.310833) (xy 223.171004 -399.304002)
			(xy 224.45599 -398.019016) (xy 224.463387 -398.012166) (xy 224.481985 -398.004425) (xy 224.492058 -398.00403)
			(xy 228.370892 -398.00403) (xy 228.380962 -398.004452) (xy 228.399566 -398.012168) (xy 228.40696 -398.019016)
			(xy 229.691946 -399.304002) (xy 229.699347 -399.310841) (xy 229.717945 -399.318558) (xy 229.728014 -399.318988)
			(xy 234.185968 -399.318988) (xy 234.196032 -399.318552) (xy 234.214618 -399.310819) (xy 234.222036 -399.304002)
			(xy 238.249206 -395.276832) (xy 238.256041 -395.26943) (xy 238.26375 -395.250831) (xy 238.264192 -395.240764)
			(xy 238.264192 -385.38785) (xy 238.261398 -385.385056) (xy 238.261398 -383.07137) (xy 238.261827 -383.061302)
			(xy 238.269549 -383.042706) (xy 238.276384 -383.035302) (xy 238.395256 -382.91643) (xy 238.402656 -382.909589)
			(xy 238.421255 -382.901871) (xy 238.431324 -382.901444) (xy 278.041608 -382.901444) (xy 278.051676 -382.901018)
			(xy 278.070273 -382.893295) (xy 278.077676 -382.886458) (xy 278.196294 -382.76784) (xy 278.203132 -382.760439)
			(xy 278.210845 -382.74184) (xy 278.21128 -382.731772) (xy 278.21128 -382.71704) (xy 278.211373 -382.712021)
			(xy 278.213294 -382.70217) (xy 278.21509 -382.697482) (xy 278.222456 -382.68021) (xy 278.224257 -382.675524)
			(xy 278.226178 -382.665671) (xy 278.226266 -382.660652) (xy 278.226266 -374.886474) (xy 278.225837 -374.876407)
			(xy 278.218113 -374.857812) (xy 278.21128 -374.850406) (xy 275.2979 -371.937026) (xy 275.290503 -371.930177)
			(xy 275.271904 -371.922438) (xy 275.261832 -371.92204) (xy 232.034842 -371.92204) (xy 232.024777 -371.922475)
			(xy 232.006192 -371.930209) (xy 231.998774 -371.937026) (xy 222.63 -381.3058) (xy 242.544088 -381.3058)
			(xy 242.548118 -381.221198) (xy 242.560172 -381.137363) (xy 242.58014 -381.055053) (xy 242.607842 -380.975014)
			(xy 242.643027 -380.897971) (xy 242.685376 -380.824621) (xy 242.734505 -380.755628) (xy 242.789971 -380.691619)
			(xy 242.851269 -380.633171) (xy 242.917846 -380.580815) (xy 242.989099 -380.535024) (xy 243.064381 -380.496214)
			(xy 243.143012 -380.464736) (xy 243.224278 -380.440874) (xy 243.307445 -380.424846) (xy 243.391759 -380.416796)
			(xy 243.434108 -380.416308) (xy 243.474162 -380.41672) (xy 243.553944 -380.423932) (xy 243.632755 -380.438288)
			(xy 243.709956 -380.459672) (xy 243.784921 -380.48791) (xy 243.857045 -380.522773) (xy 243.925741 -380.56398)
			(xy 243.990455 -380.611197) (xy 244.020848 -380.637288) (xy 244.027964 -380.642979) (xy 244.045018 -380.649358)
			(xy 244.054122 -380.649734) (xy 244.084094 -380.649734) (xy 244.093196 -380.64935) (xy 244.110247 -380.64297)
			(xy 244.117368 -380.637288) (xy 244.147764 -380.611201) (xy 244.212475 -380.563983) (xy 244.281171 -380.522776)
			(xy 244.353294 -380.487914) (xy 244.42826 -380.459679) (xy 244.505461 -380.4383) (xy 244.584272 -380.423951)
			(xy 244.664055 -380.416748) (xy 244.704108 -380.416308) (xy 244.746457 -380.41678) (xy 244.830771 -380.424832)
			(xy 244.913939 -380.440862) (xy 244.995206 -380.464724) (xy 245.073836 -380.496204) (xy 245.149119 -380.535015)
			(xy 245.220371 -380.580807) (xy 245.286948 -380.633164) (xy 245.348247 -380.691613) (xy 245.403712 -380.755624)
			(xy 245.452841 -380.824617) (xy 245.49519 -380.897967) (xy 245.530375 -380.975012) (xy 245.558077 -381.055051)
			(xy 245.578045 -381.137362) (xy 245.590098 -381.221198) (xy 245.594129 -381.3058) (xy 248.479103 -381.3058)
			(xy 248.483133 -381.221202) (xy 248.495186 -381.13737) (xy 248.515153 -381.055064) (xy 248.542853 -380.975028)
			(xy 248.578036 -380.897988) (xy 248.620382 -380.82464) (xy 248.669508 -380.75565) (xy 248.72497 -380.691642)
			(xy 248.786265 -380.633196) (xy 248.852838 -380.58084) (xy 248.924086 -380.53505) (xy 248.999364 -380.496239)
			(xy 249.07799 -380.46476) (xy 249.159252 -380.440897) (xy 249.242415 -380.424866) (xy 249.326725 -380.416813)
			(xy 249.369072 -380.416308) (xy 249.409125 -380.416742) (xy 249.488907 -380.423951) (xy 249.567717 -380.438304)
			(xy 249.644918 -380.459684) (xy 249.719884 -380.487919) (xy 249.792007 -380.52278) (xy 249.860704 -380.563984)
			(xy 249.925418 -380.611198) (xy 249.955812 -380.637288) (xy 249.962939 -380.642963) (xy 249.979984 -380.649352)
			(xy 249.989086 -380.649734) (xy 250.019058 -380.649734) (xy 250.028158 -380.649333) (xy 250.045209 -380.642965)
			(xy 250.052332 -380.637288) (xy 250.082702 -380.61117) (xy 250.147418 -380.563954) (xy 250.216118 -380.522751)
			(xy 250.288245 -380.487892) (xy 250.363214 -380.459661) (xy 250.440419 -380.438287) (xy 250.519233 -380.423943)
			(xy 250.599018 -380.416745) (xy 250.639072 -380.416308) (xy 250.681423 -380.416763) (xy 250.765741 -380.424812)
			(xy 250.848913 -380.440839) (xy 250.930184 -380.4647) (xy 251.008819 -380.496179) (xy 251.084106 -380.53499)
			(xy 251.155362 -380.580782) (xy 251.221943 -380.63314) (xy 251.283246 -380.691589) (xy 251.338714 -380.755602)
			(xy 251.387847 -380.824597) (xy 251.430199 -380.897951) (xy 251.465386 -380.974998) (xy 251.49309 -381.055041)
			(xy 251.513059 -381.137355) (xy 251.525114 -381.221194) (xy 251.529144 -381.3058) (xy 254.413988 -381.3058)
			(xy 254.418018 -381.221197) (xy 254.430073 -381.13736) (xy 254.450042 -381.055048) (xy 254.477745 -380.975008)
			(xy 254.512931 -380.897963) (xy 254.555281 -380.824612) (xy 254.604413 -380.755619) (xy 254.65988 -380.691609)
			(xy 254.721181 -380.633161) (xy 254.78776 -380.580805) (xy 254.859015 -380.535015) (xy 254.934299 -380.496206)
			(xy 255.012932 -380.464729) (xy 255.094201 -380.440869) (xy 255.17737 -380.424842) (xy 255.261686 -380.416794)
			(xy 255.304036 -380.416308) (xy 255.344089 -380.416764) (xy 255.42387 -380.42397) (xy 255.502679 -380.43832)
			(xy 255.57988 -380.459697) (xy 255.654846 -380.487929) (xy 255.726969 -380.522787) (xy 255.795667 -380.563988)
			(xy 255.860382 -380.6112) (xy 255.890776 -380.637288) (xy 255.897884 -380.64299) (xy 255.914944 -380.649363)
			(xy 255.92405 -380.649734) (xy 255.954022 -380.649734) (xy 255.963125 -380.649364) (xy 255.980176 -380.642974)
			(xy 255.987296 -380.637288) (xy 256.017681 -380.611187) (xy 256.082394 -380.56397) (xy 256.151091 -380.522765)
			(xy 256.223216 -380.487904) (xy 256.298184 -380.459671) (xy 256.375386 -380.438295) (xy 256.454199 -380.423948)
			(xy 256.533982 -380.416747) (xy 256.574036 -380.416308) (xy 256.616384 -380.416781) (xy 256.700697 -380.424835)
			(xy 256.783862 -380.440867) (xy 256.865127 -380.464732) (xy 256.943755 -380.496212) (xy 257.019035 -380.535025)
			(xy 257.090285 -380.580817) (xy 257.15686 -380.633174) (xy 257.218156 -380.691623) (xy 257.273619 -380.755633)
			(xy 257.322747 -380.824625) (xy 257.365094 -380.897975) (xy 257.400277 -380.975018) (xy 257.427978 -381.055056)
			(xy 257.447945 -381.137365) (xy 257.459999 -381.2212) (xy 257.464029 -381.3058) (xy 260.349004 -381.3058)
			(xy 260.353033 -381.2212) (xy 260.365087 -381.137367) (xy 260.385055 -381.055059) (xy 260.412756 -380.975022)
			(xy 260.44794 -380.89798) (xy 260.490287 -380.824632) (xy 260.539415 -380.755641) (xy 260.594879 -380.691632)
			(xy 260.656176 -380.633186) (xy 260.722751 -380.58083) (xy 260.794002 -380.53504) (xy 260.869282 -380.496231)
			(xy 260.947911 -380.464753) (xy 261.029175 -380.440891) (xy 261.11234 -380.424862) (xy 261.196652 -380.416812)
			(xy 261.239 -380.416308) (xy 261.279054 -380.416725) (xy 261.358836 -380.423936) (xy 261.437646 -380.438292)
			(xy 261.514847 -380.459674) (xy 261.589813 -380.487912) (xy 261.661936 -380.522775) (xy 261.730633 -380.563981)
			(xy 261.795346 -380.611197) (xy 261.82574 -380.637288) (xy 261.832859 -380.642975) (xy 261.84991 -380.649357)
			(xy 261.859014 -380.649734) (xy 261.888986 -380.649734) (xy 261.898088 -380.649346) (xy 261.915138 -380.642969)
			(xy 261.92226 -380.637288) (xy 261.952659 -380.611204) (xy 262.01737 -380.563986) (xy 262.086065 -380.522779)
			(xy 262.158188 -380.487916) (xy 262.233153 -380.459681) (xy 262.310354 -380.438302) (xy 262.389165 -380.423952)
			(xy 262.468947 -380.416748) (xy 262.509 -380.416308) (xy 262.551349 -380.41678) (xy 262.635664 -380.424831)
			(xy 262.718832 -380.44086) (xy 262.8001 -380.464722) (xy 262.878731 -380.496202) (xy 262.954014 -380.535013)
			(xy 263.025267 -380.580804) (xy 263.091845 -380.633161) (xy 263.153144 -380.69161) (xy 263.20861 -380.755621)
			(xy 263.25774 -380.824614) (xy 263.300089 -380.897965) (xy 263.335274 -380.97501) (xy 263.362976 -381.05505)
			(xy 263.382945 -381.137361) (xy 263.394998 -381.221197) (xy 263.399029 -381.3058) (xy 266.284003 -381.3058)
			(xy 266.288033 -381.221203) (xy 266.300086 -381.137371) (xy 266.320053 -381.055065) (xy 266.347753 -380.97503)
			(xy 266.382935 -380.89799) (xy 266.42528 -380.824643) (xy 266.474406 -380.755653) (xy 266.529867 -380.691645)
			(xy 266.591161 -380.633198) (xy 266.657734 -380.580843) (xy 266.728981 -380.535052) (xy 266.804258 -380.496242)
			(xy 266.882884 -380.464762) (xy 266.964146 -380.440898) (xy 267.047308 -380.424867) (xy 267.131617 -380.416813)
			(xy 267.173964 -380.416308) (xy 267.214017 -380.416747) (xy 267.293799 -380.423955) (xy 267.372609 -380.438307)
			(xy 267.449809 -380.459687) (xy 267.524775 -380.487921) (xy 267.596899 -380.522782) (xy 267.665596 -380.563985)
			(xy 267.73031 -380.611199) (xy 267.760704 -380.637288) (xy 267.767804 -380.643002) (xy 267.78487 -380.649368)
			(xy 267.793978 -380.649734) (xy 267.82395 -380.649734) (xy 267.83305 -380.649329) (xy 267.850101 -380.642964)
			(xy 267.857224 -380.637288) (xy 267.887598 -380.611174) (xy 267.952313 -380.563958) (xy 268.021012 -380.522754)
			(xy 268.093138 -380.487895) (xy 268.168107 -380.459664) (xy 268.245312 -380.438289) (xy 268.324125 -380.423944)
			(xy 268.40391 -380.416746) (xy 268.443964 -380.416308) (xy 268.486315 -380.416762) (xy 268.570634 -380.424811)
			(xy 268.653806 -380.440838) (xy 268.735078 -380.464698) (xy 268.813714 -380.496177) (xy 268.889001 -380.534987)
			(xy 268.960258 -380.580779) (xy 269.02684 -380.633137) (xy 269.088143 -380.691587) (xy 269.143612 -380.755599)
			(xy 269.192746 -380.824595) (xy 269.235098 -380.897949) (xy 269.270285 -380.974996) (xy 269.297989 -381.055039)
			(xy 269.317959 -381.137354) (xy 269.330014 -381.221194) (xy 269.334044 -381.3058) (xy 272.218888 -381.3058)
			(xy 272.222918 -381.221197) (xy 272.234972 -381.137361) (xy 272.254941 -381.05505) (xy 272.282644 -380.97501)
			(xy 272.31783 -380.897965) (xy 272.36018 -380.824615) (xy 272.409311 -380.755622) (xy 272.464777 -380.691612)
			(xy 272.526078 -380.633164) (xy 272.592656 -380.580808) (xy 272.66391 -380.535018) (xy 272.739194 -380.496208)
			(xy 272.817826 -380.464731) (xy 272.899095 -380.44087) (xy 272.982263 -380.424843) (xy 273.066579 -380.416795)
			(xy 273.108928 -380.416308) (xy 273.148981 -380.416769) (xy 273.228761 -380.423974) (xy 273.307571 -380.438323)
			(xy 273.384772 -380.4597) (xy 273.459737 -380.487931) (xy 273.531861 -380.522788) (xy 273.600559 -380.563989)
			(xy 273.665274 -380.6112) (xy 273.695668 -380.637288) (xy 273.702779 -380.642987) (xy 273.719837 -380.649362)
			(xy 273.728942 -380.649734) (xy 273.758914 -380.649734) (xy 273.768017 -380.64936) (xy 273.785068 -380.642973)
			(xy 273.792188 -380.637288) (xy 273.822576 -380.611191) (xy 273.887289 -380.563974) (xy 273.955986 -380.522768)
			(xy 274.02811 -380.487907) (xy 274.103077 -380.459673) (xy 274.180279 -380.438296) (xy 274.259091 -380.423949)
			(xy 274.338874 -380.416747) (xy 274.378928 -380.416308) (xy 274.421276 -380.416781) (xy 274.505589 -380.424834)
			(xy 274.588755 -380.440866) (xy 274.670021 -380.46473) (xy 274.74865 -380.49621) (xy 274.82393 -380.535022)
			(xy 274.895181 -380.580814) (xy 274.961756 -380.633171) (xy 275.023053 -380.69162) (xy 275.078517 -380.75563)
			(xy 275.127645 -380.824623) (xy 275.169993 -380.897973) (xy 275.205176 -380.975016) (xy 275.232878 -381.055055)
			(xy 275.252845 -381.137364) (xy 275.264899 -381.221199) (xy 275.268929 -381.3058) (xy 275.264899 -381.390401)
			(xy 275.252845 -381.474236) (xy 275.232878 -381.556545) (xy 275.205176 -381.636584) (xy 275.169993 -381.713627)
			(xy 275.127645 -381.786977) (xy 275.078517 -381.85597) (xy 275.023053 -381.91998) (xy 274.961756 -381.978429)
			(xy 274.895181 -382.030786) (xy 274.82393 -382.076578) (xy 274.74865 -382.11539) (xy 274.670021 -382.14687)
			(xy 274.588755 -382.170734) (xy 274.505589 -382.186766) (xy 274.421276 -382.194819) (xy 274.378928 -382.195324)
			(xy 274.338875 -382.194882) (xy 274.259094 -382.187673) (xy 274.180284 -382.173321) (xy 274.103083 -382.151941)
			(xy 274.028118 -382.123707) (xy 273.955994 -382.088848) (xy 273.887297 -382.047645) (xy 273.822582 -382.000433)
			(xy 273.792188 -381.974344) (xy 273.785058 -381.968672) (xy 273.768015 -381.96228) (xy 273.758914 -381.961898)
			(xy 273.728942 -381.961898) (xy 273.719844 -381.962314) (xy 273.702793 -381.968673) (xy 273.695668 -381.974344)
			(xy 273.665302 -382.000468) (xy 273.600585 -382.047682) (xy 273.531885 -382.088884) (xy 273.459757 -382.123742)
			(xy 273.384787 -382.151972) (xy 273.307582 -382.173345) (xy 273.228767 -382.187689) (xy 273.148983 -382.194887)
			(xy 273.108928 -382.195324) (xy 273.066579 -382.194805) (xy 272.982263 -382.186757) (xy 272.899095 -382.17073)
			(xy 272.817826 -382.146869) (xy 272.739194 -382.115392) (xy 272.66391 -382.076582) (xy 272.592656 -382.030792)
			(xy 272.526078 -381.978436) (xy 272.464777 -381.919988) (xy 272.409311 -381.855978) (xy 272.36018 -381.786985)
			(xy 272.31783 -381.713635) (xy 272.282644 -381.63659) (xy 272.254941 -381.55655) (xy 272.234972 -381.474239)
			(xy 272.222918 -381.390403) (xy 272.218888 -381.3058) (xy 269.334044 -381.3058) (xy 269.330014 -381.390406)
			(xy 269.317959 -381.474246) (xy 269.297989 -381.556561) (xy 269.270285 -381.636604) (xy 269.235098 -381.713651)
			(xy 269.192746 -381.787005) (xy 269.143612 -381.856001) (xy 269.088143 -381.920013) (xy 269.02684 -381.978463)
			(xy 268.960258 -382.030821) (xy 268.889001 -382.076613) (xy 268.813714 -382.115423) (xy 268.735078 -382.146902)
			(xy 268.653806 -382.170762) (xy 268.570634 -382.186789) (xy 268.486315 -382.194838) (xy 268.443964 -382.195324)
			(xy 268.403911 -382.19486) (xy 268.324131 -382.187654) (xy 268.245322 -382.173305) (xy 268.168121 -382.151929)
			(xy 268.093156 -382.123698) (xy 268.021032 -382.088841) (xy 267.952334 -382.047641) (xy 267.887619 -382.000432)
			(xy 267.857224 -381.974344) (xy 267.850113 -381.968645) (xy 267.833056 -381.962269) (xy 267.82395 -381.961898)
			(xy 267.793978 -381.961898) (xy 267.784876 -381.962283) (xy 267.767826 -381.968664) (xy 267.760704 -381.974344)
			(xy 267.730324 -382.00045) (xy 267.665609 -382.047666) (xy 267.596911 -382.08887) (xy 267.524786 -382.12373)
			(xy 267.449817 -382.151962) (xy 267.372614 -382.173338) (xy 267.293802 -382.187684) (xy 267.214018 -382.194885)
			(xy 267.173964 -382.195324) (xy 267.131617 -382.194787) (xy 267.047308 -382.186733) (xy 266.964146 -382.170702)
			(xy 266.882884 -382.146838) (xy 266.804258 -382.115358) (xy 266.728981 -382.076548) (xy 266.657734 -382.030757)
			(xy 266.591161 -381.978402) (xy 266.529867 -381.919955) (xy 266.474406 -381.855947) (xy 266.42528 -381.786957)
			(xy 266.382935 -381.71361) (xy 266.347753 -381.63657) (xy 266.320053 -381.556535) (xy 266.300086 -381.474229)
			(xy 266.288033 -381.390397) (xy 266.284003 -381.3058) (xy 263.399029 -381.3058) (xy 263.394998 -381.390403)
			(xy 263.382945 -381.474239) (xy 263.362976 -381.55655) (xy 263.335274 -381.63659) (xy 263.300089 -381.713635)
			(xy 263.25774 -381.786986) (xy 263.20861 -381.855979) (xy 263.153144 -381.91999) (xy 263.091845 -381.978439)
			(xy 263.025267 -382.030796) (xy 262.954014 -382.076587) (xy 262.878731 -382.115398) (xy 262.8001 -382.146878)
			(xy 262.718832 -382.17074) (xy 262.635664 -382.186769) (xy 262.551349 -382.19482) (xy 262.509 -382.195324)
			(xy 262.468947 -382.194899) (xy 262.389165 -382.187688) (xy 262.310355 -382.173333) (xy 262.233154 -382.151951)
			(xy 262.158188 -382.123715) (xy 262.086065 -382.088853) (xy 262.017368 -382.047648) (xy 261.952654 -382.000434)
			(xy 261.92226 -381.974344) (xy 261.915138 -381.96866) (xy 261.898089 -381.962275) (xy 261.888986 -381.961898)
			(xy 261.859014 -381.961898) (xy 261.849914 -381.962301) (xy 261.832864 -381.968669) (xy 261.82574 -381.974344)
			(xy 261.795345 -382.000433) (xy 261.730633 -382.04765) (xy 261.661937 -382.088856) (xy 261.589814 -382.123718)
			(xy 261.514848 -382.151952) (xy 261.437647 -382.173331) (xy 261.358836 -382.18768) (xy 261.279053 -382.194884)
			(xy 261.239 -382.195324) (xy 261.196652 -382.194788) (xy 261.11234 -382.186738) (xy 261.029175 -382.170709)
			(xy 260.947911 -382.146847) (xy 260.869282 -382.115369) (xy 260.794002 -382.07656) (xy 260.722751 -382.03077)
			(xy 260.656176 -381.978414) (xy 260.594879 -381.919968) (xy 260.539415 -381.855959) (xy 260.490287 -381.786968)
			(xy 260.44794 -381.71362) (xy 260.412756 -381.636578) (xy 260.385055 -381.556541) (xy 260.365087 -381.474233)
			(xy 260.353033 -381.3904) (xy 260.349004 -381.3058) (xy 257.464029 -381.3058) (xy 257.459999 -381.3904)
			(xy 257.447945 -381.474235) (xy 257.427978 -381.556544) (xy 257.400277 -381.636582) (xy 257.365094 -381.713625)
			(xy 257.322747 -381.786975) (xy 257.273619 -381.855967) (xy 257.218156 -381.919977) (xy 257.15686 -381.978426)
			(xy 257.090285 -382.030783) (xy 257.019035 -382.076575) (xy 256.943755 -382.115388) (xy 256.865127 -382.146868)
			(xy 256.783862 -382.170733) (xy 256.700697 -382.186765) (xy 256.616384 -382.194819) (xy 256.574036 -382.195324)
			(xy 256.533983 -382.194877) (xy 256.454202 -382.187669) (xy 256.375392 -382.173318) (xy 256.298192 -382.151939)
			(xy 256.223226 -382.123705) (xy 256.151103 -382.088846) (xy 256.082405 -382.047644) (xy 256.01769 -382.000433)
			(xy 255.987296 -381.974344) (xy 255.980193 -381.968633) (xy 255.963129 -381.962264) (xy 255.954022 -381.961898)
			(xy 255.92405 -381.961898) (xy 255.914952 -381.962318) (xy 255.897902 -381.968675) (xy 255.890776 -381.974344)
			(xy 255.860407 -382.000464) (xy 255.795691 -382.047678) (xy 255.726991 -382.088881) (xy 255.654863 -382.123739)
			(xy 255.579894 -382.15197) (xy 255.502689 -382.173344) (xy 255.423875 -382.187688) (xy 255.34409 -382.194886)
			(xy 255.304036 -382.195324) (xy 255.261686 -382.194806) (xy 255.17737 -382.186758) (xy 255.094201 -382.170731)
			(xy 255.012932 -382.146871) (xy 254.934299 -382.115394) (xy 254.859015 -382.076585) (xy 254.78776 -382.030795)
			(xy 254.721181 -381.978439) (xy 254.65988 -381.919991) (xy 254.604413 -381.855981) (xy 254.555281 -381.786988)
			(xy 254.512931 -381.713637) (xy 254.477745 -381.636592) (xy 254.450042 -381.556552) (xy 254.430073 -381.47424)
			(xy 254.418018 -381.390403) (xy 254.413988 -381.3058) (xy 251.529144 -381.3058) (xy 251.525114 -381.390406)
			(xy 251.513059 -381.474245) (xy 251.49309 -381.556559) (xy 251.465386 -381.636602) (xy 251.430199 -381.713649)
			(xy 251.387847 -381.787003) (xy 251.338714 -381.855998) (xy 251.283246 -381.920011) (xy 251.221943 -381.97846)
			(xy 251.155362 -382.030818) (xy 251.084106 -382.07661) (xy 251.008819 -382.115421) (xy 250.930184 -382.1469)
			(xy 250.848913 -382.170761) (xy 250.765741 -382.186788) (xy 250.681423 -382.194837) (xy 250.639072 -382.195324)
			(xy 250.59902 -382.194855) (xy 250.519239 -382.18765) (xy 250.44043 -382.173302) (xy 250.36323 -382.151926)
			(xy 250.288264 -382.123696) (xy 250.21614 -382.08884) (xy 250.147442 -382.04764) (xy 250.082727 -382.000431)
			(xy 250.052332 -381.974344) (xy 250.045219 -381.968649) (xy 250.028163 -381.962271) (xy 250.019058 -381.961898)
			(xy 249.989086 -381.961898) (xy 249.979985 -381.962287) (xy 249.962935 -381.968665) (xy 249.955812 -381.974344)
			(xy 249.925429 -382.000446) (xy 249.860715 -382.047662) (xy 249.792017 -382.088867) (xy 249.719892 -382.123727)
			(xy 249.644924 -382.15196) (xy 249.567721 -382.173336) (xy 249.488909 -382.187683) (xy 249.409126 -382.194885)
			(xy 249.369072 -382.195324) (xy 249.326725 -382.194787) (xy 249.242415 -382.186734) (xy 249.159252 -382.170703)
			(xy 249.07799 -382.14684) (xy 248.999364 -382.115361) (xy 248.924086 -382.07655) (xy 248.852838 -382.03076)
			(xy 248.786265 -381.978404) (xy 248.72497 -381.919958) (xy 248.669508 -381.85595) (xy 248.620382 -381.78696)
			(xy 248.578036 -381.713612) (xy 248.542853 -381.636572) (xy 248.515153 -381.556536) (xy 248.495186 -381.47423)
			(xy 248.483133 -381.390398) (xy 248.479103 -381.3058) (xy 245.594129 -381.3058) (xy 245.590098 -381.390402)
			(xy 245.578045 -381.474238) (xy 245.558077 -381.556549) (xy 245.530375 -381.636588) (xy 245.49519 -381.713633)
			(xy 245.452841 -381.786983) (xy 245.403712 -381.855976) (xy 245.348247 -381.919987) (xy 245.286948 -381.978436)
			(xy 245.220371 -382.030793) (xy 245.149119 -382.076585) (xy 245.073836 -382.115396) (xy 244.995206 -382.146876)
			(xy 244.913939 -382.170738) (xy 244.830771 -382.186768) (xy 244.746457 -382.19482) (xy 244.704108 -382.195324)
			(xy 244.664055 -382.194894) (xy 244.584273 -382.187684) (xy 244.505463 -382.17333) (xy 244.428262 -382.151948)
			(xy 244.353297 -382.123713) (xy 244.281173 -382.088852) (xy 244.212476 -382.047647) (xy 244.147762 -382.000434)
			(xy 244.117368 -381.974344) (xy 244.110244 -381.968664) (xy 244.093196 -381.962277) (xy 244.084094 -381.961898)
			(xy 244.054122 -381.961898) (xy 244.045023 -381.962304) (xy 244.027972 -381.968671) (xy 244.020848 -381.974344)
			(xy 243.99045 -382.000429) (xy 243.925739 -382.047646) (xy 243.857043 -382.088853) (xy 243.78492 -382.123715)
			(xy 243.709955 -382.15195) (xy 243.632754 -382.173329) (xy 243.553943 -382.187679) (xy 243.474161 -382.194883)
			(xy 243.434108 -382.195324) (xy 243.391759 -382.194804) (xy 243.307445 -382.186754) (xy 243.224278 -382.170726)
			(xy 243.143012 -382.146864) (xy 243.064381 -382.115386) (xy 242.989099 -382.076576) (xy 242.917846 -382.030785)
			(xy 242.851269 -381.978429) (xy 242.789971 -381.919981) (xy 242.734505 -381.855972) (xy 242.685376 -381.786979)
			(xy 242.643027 -381.713629) (xy 242.607842 -381.636586) (xy 242.58014 -381.556547) (xy 242.560172 -381.474237)
			(xy 242.548118 -381.390402) (xy 242.544088 -381.3058) (xy 222.63 -381.3058) (xy 218.425014 -385.510786)
			(xy 218.419426 -385.542028) (xy 218.42603 -385.55676) (xy 218.437094 -385.581881) (xy 218.452705 -385.634507)
			(xy 218.460609 -385.688826) (xy 218.461082 -385.716272) (xy 218.46061 -385.743334) (xy 218.452958 -385.796915)
			(xy 218.437804 -385.848874) (xy 218.415453 -385.898167) (xy 218.386353 -385.943803) (xy 218.351091 -385.984864)
			(xy 218.331034 -386.003038) (xy 218.322906 -386.010404) (xy 218.313762 -386.030216) (xy 218.313254 -386.128006)
			(xy 218.322144 -386.148072) (xy 218.330272 -386.155184) (xy 218.349928 -386.173356) (xy 218.384461 -386.214256)
			(xy 218.412935 -386.259585) (xy 218.434789 -386.30845) (xy 218.449593 -386.359892) (xy 218.457057 -386.412899)
			(xy 218.457526 -386.439664) (xy 218.457066 -386.466919) (xy 218.449313 -386.520875) (xy 218.43396 -386.573178)
			(xy 218.41132 -386.622764) (xy 218.381853 -386.668623) (xy 218.34616 -386.709821) (xy 218.304966 -386.745521)
			(xy 218.259111 -386.774994) (xy 218.209529 -386.797641) (xy 218.157228 -386.813001) (xy 218.103273 -386.820762)
			(xy 218.076018 -386.821172) (xy 218.049467 -386.820714) (xy 217.996879 -386.813346) (xy 217.945822 -386.798749)
			(xy 217.897286 -386.777207) (xy 217.85221 -386.749136) (xy 217.811466 -386.71508) (xy 217.793316 -386.695696)
			(xy 217.786204 -386.688076) (xy 217.767916 -386.67944) (xy 217.674698 -386.67563) (xy 217.655902 -386.682742)
			(xy 217.648282 -386.689854) (xy 217.626935 -386.709263) (xy 217.579481 -386.742076) (xy 217.527623 -386.76736)
			(xy 217.472546 -386.784536) (xy 217.415509 -386.793213) (xy 217.386662 -386.79374) (xy 217.358849 -386.79326)
			(xy 217.303809 -386.785218) (xy 217.250524 -386.769253) (xy 217.225118 -386.757926) (xy 217.21064 -386.751068)
			(xy 217.179144 -386.756656) (xy 215.775286 -388.160514) (xy 221.30132 -388.160514) (xy 221.305305 -387.979173)
			(xy 221.317251 -387.798181) (xy 221.337135 -387.617889) (xy 221.364919 -387.438645) (xy 221.40055 -387.260793)
			(xy 221.443958 -387.084679) (xy 221.49506 -386.910641) (xy 221.553758 -386.739016) (xy 221.619937 -386.570135)
			(xy 221.69347 -386.404323) (xy 221.774215 -386.241902) (xy 221.862017 -386.083183) (xy 221.956706 -385.928475)
			(xy 222.058098 -385.778075) (xy 222.165999 -385.632274) (xy 222.2802 -385.491353) (xy 222.400481 -385.355584)
			(xy 222.526609 -385.22523) (xy 222.658341 -385.100541) (xy 222.795423 -384.981759) (xy 222.93759 -384.869113)
			(xy 223.084567 -384.76282) (xy 223.236072 -384.663086) (xy 223.391811 -384.570102) (xy 223.551484 -384.484049)
			(xy 223.714783 -384.405093) (xy 223.881392 -384.333385) (xy 224.05099 -384.269065) (xy 224.22325 -384.212257)
			(xy 224.397838 -384.163069) (xy 224.574419 -384.121598) (xy 224.752651 -384.087923) (xy 224.93219 -384.062109)
			(xy 225.112689 -384.044207) (xy 225.293801 -384.034249) (xy 225.475175 -384.032257) (xy 225.656462 -384.038233)
			(xy 225.837311 -384.052167) (xy 226.017374 -384.07403) (xy 226.196302 -384.103782) (xy 226.373751 -384.141364)
			(xy 226.549378 -384.186704) (xy 226.722844 -384.239715) (xy 226.893814 -384.300294) (xy 227.061959 -384.368324)
			(xy 227.226952 -384.443674) (xy 227.388477 -384.526199) (xy 227.546221 -384.615739) (xy 227.69988 -384.712121)
			(xy 227.849157 -384.815159) (xy 227.993764 -384.924655) (xy 228.133422 -385.040397) (xy 228.267862 -385.162162)
			(xy 228.396823 -385.289714) (xy 228.520057 -385.422808) (xy 228.637326 -385.561186) (xy 228.748404 -385.704582)
			(xy 228.853076 -385.852718) (xy 228.95114 -386.005309) (xy 229.042407 -386.16206) (xy 229.126701 -386.322669)
			(xy 229.203859 -386.486825) (xy 229.273732 -386.654212) (xy 229.336186 -386.824506) (xy 229.391098 -386.997379)
			(xy 229.438365 -387.172498) (xy 229.477894 -387.349523) (xy 229.509609 -387.528114) (xy 229.53345 -387.707926)
			(xy 229.549369 -387.888611) (xy 229.557336 -388.069821) (xy 229.557834 -388.160514) (xy 229.557336 -388.251207)
			(xy 229.549369 -388.432417) (xy 229.53345 -388.613102) (xy 229.509609 -388.792914) (xy 229.477894 -388.971505)
			(xy 229.438365 -389.14853) (xy 229.391098 -389.323649) (xy 229.336186 -389.496522) (xy 229.273732 -389.666816)
			(xy 229.203859 -389.834203) (xy 229.126701 -389.998359) (xy 229.042407 -390.158968) (xy 228.95114 -390.315719)
			(xy 228.853076 -390.46831) (xy 228.748404 -390.616446) (xy 228.637326 -390.759842) (xy 228.520057 -390.89822)
			(xy 228.396823 -391.031314) (xy 228.267862 -391.158866) (xy 228.133422 -391.280631) (xy 227.993764 -391.396373)
			(xy 227.849157 -391.505869) (xy 227.69988 -391.608907) (xy 227.546221 -391.705289) (xy 227.388477 -391.794829)
			(xy 227.226952 -391.877354) (xy 227.061959 -391.952704) (xy 226.893814 -392.020734) (xy 226.722844 -392.081313)
			(xy 226.549378 -392.134324) (xy 226.373751 -392.179664) (xy 226.196302 -392.217246) (xy 226.017374 -392.246998)
			(xy 225.837311 -392.268861) (xy 225.656462 -392.282795) (xy 225.475175 -392.288771) (xy 225.293801 -392.286779)
			(xy 225.112689 -392.276821) (xy 224.93219 -392.258919) (xy 224.752651 -392.233105) (xy 224.574419 -392.19943)
			(xy 224.397838 -392.157959) (xy 224.22325 -392.108771) (xy 224.05099 -392.051963) (xy 223.881392 -391.987643)
			(xy 223.714783 -391.915935) (xy 223.551484 -391.836979) (xy 223.391811 -391.750926) (xy 223.236072 -391.657942)
			(xy 223.084567 -391.558208) (xy 222.93759 -391.451915) (xy 222.795423 -391.339269) (xy 222.658341 -391.220487)
			(xy 222.526609 -391.095798) (xy 222.400481 -390.965444) (xy 222.2802 -390.829675) (xy 222.165999 -390.688754)
			(xy 222.058098 -390.542953) (xy 221.956706 -390.392553) (xy 221.862017 -390.237845) (xy 221.774215 -390.079126)
			(xy 221.69347 -389.916705) (xy 221.619937 -389.750893) (xy 221.553758 -389.582012) (xy 221.49506 -389.410387)
			(xy 221.443958 -389.236349) (xy 221.40055 -389.060235) (xy 221.364919 -388.882383) (xy 221.337135 -388.703139)
			(xy 221.317251 -388.522847) (xy 221.305305 -388.341855) (xy 221.30132 -388.160514) (xy 215.775286 -388.160514)
			(xy 213.945978 -389.989822) (xy 213.938582 -389.996673) (xy 213.919983 -390.004412) (xy 213.90991 -390.004808)
			(xy 199.582278 -390.004808) (xy 199.557386 -390.021064) (xy 199.551036 -390.035034) (xy 199.539463 -390.060015)
			(xy 199.510192 -390.106643) (xy 199.47452 -390.148576) (xy 199.433187 -390.184944) (xy 199.387054 -390.214989)
			(xy 199.33708 -390.238087) (xy 199.284303 -390.253758) (xy 199.229821 -390.261675) (xy 199.174767 -390.261675)
			(xy 199.120285 -390.253758) (xy 199.067508 -390.238087) (xy 199.017534 -390.214989) (xy 198.971401 -390.184944)
			(xy 198.930068 -390.148576) (xy 198.894396 -390.106643) (xy 198.865125 -390.060015) (xy 198.853552 -390.035034)
			(xy 198.847202 -390.021064) (xy 198.82231 -390.004808) (xy 192.95745 -390.004808) (xy 192.932558 -390.021064)
			(xy 192.926208 -390.035034) (xy 192.914635 -390.060015) (xy 192.885364 -390.106643) (xy 192.849692 -390.148576)
			(xy 192.808359 -390.184944) (xy 192.762226 -390.214989) (xy 192.712252 -390.238087) (xy 192.659475 -390.253758)
			(xy 192.604993 -390.261675) (xy 192.549939 -390.261675) (xy 192.495457 -390.253758) (xy 192.44268 -390.238087)
			(xy 192.392706 -390.214989) (xy 192.346573 -390.184944) (xy 192.30524 -390.148576) (xy 192.269568 -390.106643)
			(xy 192.240297 -390.060015) (xy 192.228724 -390.035034) (xy 192.222374 -390.021064) (xy 192.197482 -390.004808)
			(xy 189.13094 -390.004808) (xy 189.120875 -390.005242) (xy 189.102287 -390.012973) (xy 189.094872 -390.019794)
			(xy 184.53481 -394.579856) (xy 184.527971 -394.587257) (xy 184.520255 -394.605855) (xy 184.519824 -394.615924)
			(xy 184.519824 -395.95552) (xy 184.520251 -395.965588) (xy 184.527974 -395.984185) (xy 184.53481 -395.991588)
			(xy 184.616344 -396.073122) (xy 184.623741 -396.07997) (xy 184.64234 -396.087701) (xy 184.652412 -396.088108)
			(xy 185.033412 -396.088108) (xy 185.043481 -396.088534) (xy 185.062082 -396.096252) (xy 185.06948 -396.103094)
			(xy 185.345832 -396.379446) (xy 185.352679 -396.386844) (xy 185.360407 -396.405443) (xy 185.360818 -396.415514)
			(xy 185.360818 -399.052288) (xy 185.361239 -399.062359) (xy 185.368953 -399.080965) (xy 185.375804 -399.088356)
			(xy 185.429398 -399.14195) (xy 185.436794 -399.148802) (xy 185.455392 -399.156545) (xy 185.465466 -399.156936)
			(xy 189.027562 -399.156936) (xy 189.037626 -399.1565) (xy 189.056208 -399.148762) (xy 189.06363 -399.14195)
			(xy 190.454026 -397.751554) (xy 190.461423 -397.744706) (xy 190.480022 -397.736972) (xy 190.490094 -397.736568)
			(xy 193.891408 -397.736568) (xy 193.902695 -397.735961) (xy 193.923117 -397.726338) (xy 193.930778 -397.718026)
			(xy 193.95739 -397.6864) (xy 194.015584 -397.627696) (xy 194.078973 -397.574644) (xy 194.147011 -397.527703)
			(xy 194.219111 -397.487276) (xy 194.294651 -397.453713) (xy 194.372978 -397.427304) (xy 194.453418 -397.408275)
			(xy 194.535277 -397.396792) (xy 194.617848 -397.392954) (xy 194.700419 -397.396792) (xy 194.782278 -397.408275)
			(xy 194.862718 -397.427304) (xy 194.941045 -397.453713) (xy 195.016585 -397.487276) (xy 195.088685 -397.527703)
			(xy 195.156723 -397.574644) (xy 195.220112 -397.627696) (xy 195.278306 -397.6864) (xy 195.304918 -397.718026)
			(xy 195.312536 -397.7264) (xy 195.332981 -397.736046) (xy 195.344288 -397.736568) (xy 196.068188 -397.736568)
			(xy 196.07826 -397.736988) (xy 196.09687 -397.744696) (xy 196.104256 -397.751554) (xy 197.292722 -398.94002)
			(xy 197.306184 -398.947132) (xy 197.313804 -398.948656) (xy 197.348825 -398.95559) (xy 197.417371 -398.975563)
			(xy 197.483572 -399.002301) (xy 197.546762 -399.035535) (xy 197.606305 -399.074932) (xy 197.661603 -399.120094)
			(xy 197.687184 -399.144998) (xy 197.754494 -399.212308) (xy 197.761904 -399.218992) (xy 197.78034 -399.226575)
			(xy 197.790308 -399.22704) (xy 201.843386 -399.22704) (xy 201.85761 -399.227294) (xy 201.868024 -399.227548)
			(xy 201.887074 -399.219928) (xy 203.3778 -397.729202) (xy 203.385198 -397.722355) (xy 203.403796 -397.71462)
			(xy 203.413868 -397.714216) (xy 206.779876 -397.714216) (xy 206.78994 -397.714653) (xy 206.808523 -397.722389)
			(xy 206.815944 -397.729202) (xy 208.349342 -399.2626) (xy 208.356754 -399.269278) (xy 208.37519 -399.276844)
			(xy 208.385156 -399.277332) (xy 211.970874 -399.277332) (xy 212.010213 -399.27787) (xy 212.088407 -399.286576)
			(xy 212.165163 -399.303861) (xy 212.202522 -399.316194) (xy 212.21065 -399.318988)
		)
		(stroke
			(width 0)
			(type solid)
		)
		(fill yes)
		(layer "In13.Cu")
		(net "P12V_AUX")
	)
	(gr_poly
		(pts
			(xy 180.366924 -28.493974) (xy 180.376992 -28.493546) (xy 180.395587 -28.485822) (xy 180.402992 -28.478988)
			(xy 180.434276 -28.448192) (xy 180.501933 -28.392248) (xy 180.574773 -28.343242) (xy 180.652087 -28.301652)
			(xy 180.733124 -28.267882) (xy 180.817093 -28.242262) (xy 180.903178 -28.225039) (xy 180.990541 -28.216383)
			(xy 181.034436 -28.215844) (xy 181.03469 -28.215844) (xy 181.074436 -28.2163) (xy 181.15361 -28.223421)
			(xy 181.231833 -28.237573) (xy 181.308483 -28.258641) (xy 181.38295 -28.286458) (xy 181.418992 -28.30322)
			(xy 181.440836 -28.308046) (xy 181.46268 -28.30322) (xy 181.498711 -28.28643) (xy 181.573174 -28.258593)
			(xy 181.649827 -28.237518) (xy 181.728055 -28.223373) (xy 181.807234 -28.216272) (xy 181.846982 -28.215844)
			(xy 181.847236 -28.215844) (xy 181.891133 -28.216371) (xy 181.9785 -28.225017) (xy 182.06459 -28.242232)
			(xy 182.148564 -28.267848) (xy 182.229605 -28.301616) (xy 182.306923 -28.343206) (xy 182.379765 -28.392214)
			(xy 182.447423 -28.448163) (xy 182.47868 -28.478988) (xy 182.486082 -28.485823) (xy 182.504681 -28.49353)
			(xy 182.514748 -28.493974) (xy 185.057542 -28.493974) (xy 185.068487 -28.49344) (xy 185.088388 -28.484318)
			(xy 185.102692 -28.467745) (xy 185.10631 -28.457398) (xy 185.138314 -28.347162) (xy 185.126376 -28.315666)
			(xy 185.111898 -28.306522) (xy 185.077752 -28.284367) (xy 185.013239 -28.234725) (xy 184.95353 -28.179397)
			(xy 184.899126 -28.118846) (xy 184.850482 -28.053577) (xy 184.808005 -27.984136) (xy 184.772049 -27.911105)
			(xy 184.742916 -27.835095) (xy 184.72085 -27.756741) (xy 184.706035 -27.676698) (xy 184.698594 -27.595637)
			(xy 184.698132 -27.554936) (xy 184.698655 -27.512091) (xy 184.706916 -27.426799) (xy 184.723336 -27.342696)
			(xy 184.747762 -27.260561) (xy 184.76341 -27.220672) (xy 184.766669 -27.211705) (xy 184.766926 -27.192643)
			(xy 184.763918 -27.183588) (xy 184.752996 -27.154886) (xy 184.749376 -27.146444) (xy 184.737279 -27.132638)
			(xy 184.729374 -27.127962) (xy 184.703586 -27.113623) (xy 184.656379 -27.078229) (xy 184.615181 -27.035993)
			(xy 184.580974 -26.987919) (xy 184.554572 -26.935154) (xy 184.536605 -26.878954) (xy 184.527501 -26.820659)
			(xy 184.526936 -26.791158) (xy 184.527402 -26.763908) (xy 184.535164 -26.709964) (xy 184.550524 -26.657674)
			(xy 184.57317 -26.608102) (xy 184.60264 -26.562257) (xy 184.638334 -26.521073) (xy 184.679526 -26.485388)
			(xy 184.725377 -26.455929) (xy 184.774955 -26.433294) (xy 184.827248 -26.417946) (xy 184.881194 -26.410196)
			(xy 184.908444 -26.40965) (xy 184.93705 -26.410165) (xy 184.993619 -26.418721) (xy 185.048274 -26.435633)
			(xy 185.099789 -26.460521) (xy 185.147006 -26.492828) (xy 185.188866 -26.531828) (xy 185.224429 -26.576644)
			(xy 185.252896 -26.626272) (xy 185.26379 -26.652728) (xy 185.267537 -26.66111) (xy 185.27991 -26.674656)
			(xy 185.28792 -26.679144) (xy 185.315098 -26.693368) (xy 185.320583 -26.69598) (xy 185.332393 -26.698816)
			(xy 185.338466 -26.698956) (xy 185.351928 -26.697178) (xy 185.390351 -26.687087) (xy 185.468533 -26.672971)
			(xy 185.547663 -26.665876) (xy 185.587386 -26.665428) (xy 185.58764 -26.665428) (xy 185.628741 -26.665904)
			(xy 185.710591 -26.673493) (xy 185.791392 -26.688601) (xy 185.870455 -26.7111) (xy 185.947104 -26.740798)
			(xy 186.020686 -26.777441) (xy 186.090573 -26.820718) (xy 186.156169 -26.870258) (xy 186.216914 -26.925639)
			(xy 186.272291 -26.986389) (xy 186.321825 -27.05199) (xy 186.365096 -27.12188) (xy 186.401733 -27.195466)
			(xy 186.431424 -27.272117) (xy 186.453917 -27.351182) (xy 186.469018 -27.431984) (xy 186.476599 -27.513835)
			(xy 186.477148 -27.554936) (xy 186.47669 -27.595636) (xy 186.469249 -27.676696) (xy 186.454432 -27.756737)
			(xy 186.432364 -27.835089) (xy 186.403228 -27.911097) (xy 186.36727 -27.984125) (xy 186.324789 -28.053561)
			(xy 186.276141 -28.118826) (xy 186.221733 -28.179372) (xy 186.16202 -28.234694) (xy 186.097502 -28.284328)
			(xy 186.063382 -28.306522) (xy 186.048904 -28.315666) (xy 186.036966 -28.347162) (xy 186.06897 -28.457398)
			(xy 186.07254 -28.467765) (xy 186.086864 -28.484334) (xy 186.106786 -28.493437) (xy 186.117738 -28.493974)
			(xy 186.46521 -28.493974) (xy 186.494928 -28.46451) (xy 186.494928 -28.443428) (xy 186.495517 -28.416248)
			(xy 186.50345 -28.362465) (xy 186.518936 -28.310353) (xy 186.541664 -28.260967) (xy 186.571172 -28.215308)
			(xy 186.606862 -28.174299) (xy 186.648013 -28.138773) (xy 186.69379 -28.109447) (xy 186.743266 -28.086918)
			(xy 186.79544 -28.071639) (xy 186.849254 -28.063922) (xy 186.903618 -28.063922) (xy 186.957432 -28.071639)
			(xy 187.009606 -28.086918) (xy 187.059082 -28.109447) (xy 187.104859 -28.138773) (xy 187.14601 -28.174299)
			(xy 187.1817 -28.215308) (xy 187.211208 -28.260967) (xy 187.233936 -28.310353) (xy 187.249422 -28.362465)
			(xy 187.257355 -28.416248) (xy 187.257944 -28.443428) (xy 187.257944 -28.46451) (xy 187.287662 -28.493974)
			(xy 187.670948 -28.493974) (xy 187.681382 -28.493471) (xy 187.700512 -28.48514) (xy 187.71471 -28.469849)
			(xy 187.7187 -28.460192) (xy 187.756038 -28.354274) (xy 187.747402 -28.32354) (xy 187.734448 -28.31338)
			(xy 187.700431 -28.285279) (xy 187.637536 -28.223388) (xy 187.581077 -28.155575) (xy 187.53161 -28.082506)
			(xy 187.489619 -28.004898) (xy 187.455518 -27.923514) (xy 187.429642 -27.839154) (xy 187.412244 -27.752646)
			(xy 187.403496 -27.664842) (xy 187.402978 -27.620722) (xy 187.402978 -27.620468) (xy 187.403482 -27.57812)
			(xy 187.411533 -27.493806) (xy 187.427562 -27.41064) (xy 187.451423 -27.329373) (xy 187.482902 -27.250743)
			(xy 187.521713 -27.175462) (xy 187.567503 -27.10421) (xy 187.619859 -27.037634) (xy 187.678307 -26.976336)
			(xy 187.742317 -26.920871) (xy 187.811309 -26.871742) (xy 187.884659 -26.829393) (xy 187.961702 -26.794209)
			(xy 188.041741 -26.766507) (xy 188.12405 -26.746539) (xy 188.207885 -26.734486) (xy 188.292486 -26.730456)
			(xy 188.377087 -26.734486) (xy 188.460922 -26.746539) (xy 188.543231 -26.766507) (xy 188.62327 -26.794209)
			(xy 188.700313 -26.829393) (xy 188.773663 -26.871742) (xy 188.842655 -26.920871) (xy 188.906665 -26.976336)
			(xy 188.965113 -27.037634) (xy 189.017469 -27.10421) (xy 189.063259 -27.175462) (xy 189.10207 -27.250743)
			(xy 189.133549 -27.329373) (xy 189.15741 -27.41064) (xy 189.173439 -27.493806) (xy 189.18149 -27.57812)
			(xy 189.181994 -27.620468) (xy 189.181994 -27.620722) (xy 189.181457 -27.664843) (xy 189.172726 -27.752652)
			(xy 189.155342 -27.839165) (xy 189.129476 -27.923531) (xy 189.095382 -28.00492) (xy 189.053395 -28.082533)
			(xy 189.003929 -28.155607) (xy 188.947469 -28.223422) (xy 188.88457 -28.285313) (xy 188.850524 -28.31338)
			(xy 188.83757 -28.32354) (xy 188.828934 -28.354274) (xy 188.866272 -28.460192) (xy 188.870254 -28.469845)
			(xy 188.884487 -28.485094) (xy 188.903597 -28.49346) (xy 188.914024 -28.493974) (xy 189.148212 -28.493974)
			(xy 189.176406 -28.46959) (xy 189.179454 -28.451048) (xy 189.186228 -28.410654) (xy 189.206239 -28.331225)
			(xy 189.233469 -28.253972) (xy 189.267687 -28.179551) (xy 189.308604 -28.108592) (xy 189.355872 -28.041695)
			(xy 189.409091 -27.979429) (xy 189.467811 -27.92232) (xy 189.531533 -27.870852) (xy 189.599717 -27.825462)
			(xy 189.671787 -27.786534) (xy 189.747131 -27.754398) (xy 189.82511 -27.729326) (xy 189.865 -27.720036)
			(xy 189.877192 -27.717242) (xy 189.896242 -27.70124) (xy 189.93739 -27.601164) (xy 189.935358 -27.576526)
			(xy 189.9285 -27.566112) (xy 189.906215 -27.530316) (xy 189.86774 -27.455279) (xy 189.836538 -27.376938)
			(xy 189.812889 -27.295996) (xy 189.797005 -27.213179) (xy 189.789029 -27.129231) (xy 189.788546 -27.087068)
			(xy 189.789022 -27.045966) (xy 189.796609 -26.964112) (xy 189.811717 -26.883307) (xy 189.834215 -26.804241)
			(xy 189.863912 -26.727588) (xy 189.900554 -26.654002) (xy 189.94383 -26.58411) (xy 189.993369 -26.51851)
			(xy 190.04875 -26.457759) (xy 190.109499 -26.402378) (xy 190.175099 -26.352837) (xy 190.24499 -26.309561)
			(xy 190.318575 -26.272917) (xy 190.395228 -26.243219) (xy 190.474294 -26.22072) (xy 190.555098 -26.205611)
			(xy 190.636952 -26.198023) (xy 190.678054 -26.19756) (xy 190.720717 -26.198061) (xy 190.805651 -26.206227)
			(xy 190.889413 -26.222488) (xy 190.971233 -26.246695) (xy 191.050359 -26.278626) (xy 191.126064 -26.317987)
			(xy 191.197652 -26.364415) (xy 191.264465 -26.417486) (xy 191.295528 -26.446734) (xy 191.302386 -26.453338)
			(xy 191.319404 -26.46045) (xy 191.406526 -26.463498) (xy 191.424052 -26.457402) (xy 191.431418 -26.451306)
			(xy 191.453127 -26.433651) (xy 191.500717 -26.404222) (xy 191.552093 -26.382053) (xy 191.578992 -26.374344)
			(xy 191.59601 -26.370026) (xy 191.616838 -26.342848) (xy 191.616838 -25.865836) (xy 191.614044 -25.857708)
			(xy 191.602216 -25.822463) (xy 191.583774 -25.750437) (xy 191.571399 -25.677125) (xy 191.56518 -25.603037)
			(xy 191.564768 -25.565862) (xy 191.564909 -25.541876) (xy 191.567453 -25.493971) (xy 191.569848 -25.470104)
			(xy 191.570473 -25.46091) (xy 191.565926 -25.443066) (xy 191.560958 -25.435306) (xy 191.543686 -25.410922)
			(xy 191.537996 -25.403625) (xy 191.522628 -25.393342) (xy 191.513714 -25.390856) (xy 191.472275 -25.380714)
			(xy 191.391399 -25.353543) (xy 191.313496 -25.318753) (xy 191.239281 -25.276665) (xy 191.169437 -25.227665)
			(xy 191.104605 -25.172203) (xy 191.04538 -25.11079) (xy 190.992307 -25.043988) (xy 190.945873 -24.972412)
			(xy 190.906505 -24.89672) (xy 190.874564 -24.817606) (xy 190.850344 -24.735797) (xy 190.834068 -24.652046)
			(xy 190.825884 -24.567121) (xy 190.825374 -24.524462) (xy 190.825862 -24.482795) (xy 190.83366 -24.399827)
			(xy 190.849183 -24.317952) (xy 190.872297 -24.237887) (xy 190.902797 -24.160335) (xy 190.940417 -24.085976)
			(xy 190.984826 -24.015462) (xy 191.035637 -23.94941) (xy 191.092402 -23.8884) (xy 191.154625 -23.832966)
			(xy 191.221759 -23.783595) (xy 191.293217 -23.74072) (xy 191.368372 -23.704716) (xy 191.407288 -23.689818)
			(xy 191.416432 -23.686516) (xy 191.430656 -23.673816) (xy 191.470788 -23.595076) (xy 191.472566 -23.57628)
			(xy 191.469772 -23.566882) (xy 191.459133 -23.527512) (xy 191.44424 -23.447322) (xy 191.436738 -23.366108)
			(xy 191.436244 -23.325328) (xy 191.436244 -23.324566) (xy 191.436682 -23.284511) (xy 191.443881 -23.204726)
			(xy 191.458229 -23.125911) (xy 191.479607 -23.048707) (xy 191.507843 -22.973738) (xy 191.542708 -22.901613)
			(xy 191.583919 -22.832917) (xy 191.607186 -22.80031) (xy 191.611589 -22.793678) (xy 191.616497 -22.778545)
			(xy 191.616838 -22.770592) (xy 191.616838 -20.392898) (xy 191.616413 -20.382829) (xy 191.608691 -20.364231)
			(xy 191.601852 -20.35683) (xy 191.168528 -19.923506) (xy 191.161126 -19.91667) (xy 191.142528 -19.908961)
			(xy 191.13246 -19.90852) (xy 187.334144 -19.90852) (xy 187.329318 -19.909536) (xy 187.325 -19.910298)
			(xy 187.301632 -19.962622) (xy 187.299578 -19.96758) (xy 187.297394 -19.978084) (xy 187.297314 -19.98345)
			(xy 187.303664 -20.007834) (xy 187.322609 -20.041605) (xy 187.355248 -20.111831) (xy 187.381666 -20.184626)
			(xy 187.401664 -20.259439) (xy 187.41509 -20.335707) (xy 187.421843 -20.412852) (xy 187.422282 -20.451572)
			(xy 187.421791 -20.493391) (xy 187.413916 -20.576657) (xy 187.398261 -20.658816) (xy 187.374965 -20.739144)
			(xy 187.360052 -20.778216) (xy 187.384546 -20.790029) (xy 187.430209 -20.819559) (xy 187.471221 -20.85527)
			(xy 187.50675 -20.896438) (xy 187.536079 -20.94223) (xy 187.558614 -20.991721) (xy 187.573899 -21.043908)
			(xy 187.581625 -21.097736) (xy 187.582048 -21.124926) (xy 187.58156 -21.152194) (xy 187.573795 -21.206174)
			(xy 187.558427 -21.258499) (xy 187.535769 -21.308105) (xy 187.506283 -21.353982) (xy 187.470567 -21.395195)
			(xy 187.42935 -21.430907) (xy 187.38347 -21.460389) (xy 187.333862 -21.483041) (xy 187.281535 -21.498404)
			(xy 187.227554 -21.506163) (xy 187.200286 -21.506688) (xy 187.172906 -21.506216) (xy 187.118709 -21.498388)
			(xy 187.066186 -21.482896) (xy 187.016417 -21.460056) (xy 186.970422 -21.430339) (xy 186.929146 -21.394354)
			(xy 186.893437 -21.352839) (xy 186.864027 -21.306648) (xy 186.852306 -21.281898) (xy 186.833949 -21.288841)
			(xy 186.796724 -21.30129) (xy 186.777884 -21.30679) (xy 186.741308 -21.355304) (xy 186.740879 -21.38258)
			(xy 186.733179 -21.436585) (xy 186.717866 -21.488942) (xy 186.695252 -21.538585) (xy 186.665797 -21.5845)
			(xy 186.630103 -21.625752) (xy 186.588898 -21.6615) (xy 186.543021 -21.691014) (xy 186.493407 -21.713692)
			(xy 186.44107 -21.729074) (xy 186.387075 -21.736843) (xy 186.3598 -21.73732) (xy 186.332726 -21.736846)
			(xy 186.279121 -21.729188) (xy 186.227138 -21.714026) (xy 186.177823 -21.691664) (xy 186.132165 -21.662552)
			(xy 186.091084 -21.627276) (xy 186.055405 -21.586544) (xy 186.040268 -21.564092) (xy 186.015597 -21.581421)
			(xy 185.961945 -21.608916) (xy 185.904644 -21.627653) (xy 185.845113 -21.637169) (xy 185.81497 -21.637752)
			(xy 185.788361 -21.637289) (xy 185.73566 -21.629893) (xy 185.684497 -21.615249) (xy 185.635864 -21.59364)
			(xy 185.590703 -21.565486) (xy 185.549891 -21.531332) (xy 185.514218 -21.491841) (xy 185.484376 -21.447778)
			(xy 185.460944 -21.399997) (xy 185.444375 -21.349424) (xy 185.439304 -21.3233) (xy 185.395583 -21.331627)
			(xy 185.307023 -21.340534) (xy 185.26252 -21.34108) (xy 185.221417 -21.340621) (xy 185.139561 -21.333037)
			(xy 185.058754 -21.317933) (xy 184.979685 -21.295437) (xy 184.903029 -21.265742) (xy 184.829441 -21.229099)
			(xy 184.759547 -21.185824) (xy 184.693945 -21.136283) (xy 184.633194 -21.080901) (xy 184.577812 -21.020149)
			(xy 184.528272 -20.954546) (xy 184.484997 -20.884652) (xy 184.448355 -20.811063) (xy 184.41866 -20.734407)
			(xy 184.396165 -20.655339) (xy 184.381062 -20.574531) (xy 184.373479 -20.492675) (xy 184.373012 -20.451572)
			(xy 184.373499 -20.410496) (xy 184.381099 -20.328695) (xy 184.396203 -20.247943) (xy 184.418684 -20.168925)
			(xy 184.44835 -20.092316) (xy 184.46623 -20.055332) (xy 184.472072 -20.043394) (xy 184.470802 -20.017232)
			(xy 184.418478 -19.93265) (xy 184.413614 -19.925464) (xy 184.400086 -19.914613) (xy 184.383716 -19.908888)
			(xy 184.375044 -19.90852) (xy 176.150016 -19.90852) (xy 176.139953 -19.908959) (xy 176.121373 -19.916697)
			(xy 176.113948 -19.923506) (xy 175.607472 -20.429982) (xy 175.600631 -20.437381) (xy 175.592915 -20.455981)
			(xy 175.592486 -20.46605) (xy 175.592486 -21.517356) (xy 180.142642 -21.517356) (xy 180.143125 -21.476254)
			(xy 180.150713 -21.394402) (xy 180.165821 -21.313598) (xy 180.188319 -21.234534) (xy 180.218016 -21.157882)
			(xy 180.254659 -21.084297) (xy 180.297935 -21.014407) (xy 180.347474 -20.948807) (xy 180.402854 -20.888058)
			(xy 180.463603 -20.832677) (xy 180.529202 -20.783138) (xy 180.599092 -20.739862) (xy 180.672676 -20.703219)
			(xy 180.749328 -20.673521) (xy 180.828393 -20.651022) (xy 180.909196 -20.635914) (xy 180.991048 -20.628325)
			(xy 181.03215 -20.627848) (xy 181.074964 -20.628318) (xy 181.160196 -20.63654) (xy 181.244244 -20.652913)
			(xy 181.32633 -20.677285) (xy 181.405694 -20.709431) (xy 181.481603 -20.749053) (xy 181.553354 -20.795786)
			(xy 181.620284 -20.849195) (xy 181.681772 -20.908788) (xy 181.73725 -20.974013) (xy 181.762146 -21.008848)
			(xy 181.769671 -21.018519) (xy 181.791316 -21.029929) (xy 181.803548 -21.030692) (xy 181.846338 -21.031435)
			(xy 181.931487 -21.040087) (xy 182.015412 -21.056875) (xy 182.097337 -21.081642) (xy 182.176506 -21.114161)
			(xy 182.252188 -21.15413) (xy 182.323682 -21.201181) (xy 182.390328 -21.254878) (xy 182.421276 -21.284438)
			(xy 182.429235 -21.291462) (xy 182.449096 -21.298886) (xy 182.470265 -21.297673) (xy 182.47995 -21.293328)
			(xy 182.517531 -21.274729) (xy 182.595501 -21.243857) (xy 182.676027 -21.220452) (xy 182.758397 -21.20472)
			(xy 182.841881 -21.1968) (xy 182.88381 -21.1963) (xy 182.884064 -21.1963) (xy 182.924117 -21.196741)
			(xy 183.003898 -21.203949) (xy 183.082709 -21.218301) (xy 183.159909 -21.239681) (xy 183.234875 -21.267915)
			(xy 183.306998 -21.302775) (xy 183.375696 -21.343978) (xy 183.44041 -21.391191) (xy 183.470804 -21.41728)
			(xy 183.477905 -21.422993) (xy 183.49497 -21.42936) (xy 183.504078 -21.429726) (xy 183.53405 -21.429726)
			(xy 183.54315 -21.429323) (xy 183.560201 -21.422956) (xy 183.567324 -21.41728) (xy 183.597696 -21.391164)
			(xy 183.662412 -21.343949) (xy 183.731111 -21.302745) (xy 183.803238 -21.267886) (xy 183.878207 -21.239655)
			(xy 183.955411 -21.218281) (xy 184.034225 -21.203936) (xy 184.11401 -21.196738) (xy 184.154064 -21.1963)
			(xy 184.195167 -21.196787) (xy 184.277022 -21.204368) (xy 184.357828 -21.219471) (xy 184.436897 -21.241965)
			(xy 184.513552 -21.271659) (xy 184.58714 -21.308299) (xy 184.657034 -21.351573) (xy 184.722636 -21.401112)
			(xy 184.783388 -21.456492) (xy 184.83877 -21.517242) (xy 184.888311 -21.582843) (xy 184.931587 -21.652735)
			(xy 184.96823 -21.726323) (xy 184.997926 -21.802977) (xy 185.020423 -21.882044) (xy 185.035528 -21.96285)
			(xy 185.043112 -22.044705) (xy 185.043572 -22.085808) (xy 185.043496 -22.101634) (xy 185.042351 -22.133264)
			(xy 185.041286 -22.149054) (xy 185.040524 -22.1615) (xy 185.049922 -22.183852) (xy 185.13298 -22.252432)
			(xy 185.156856 -22.257512) (xy 185.169048 -22.25421) (xy 185.206557 -22.244609) (xy 185.282813 -22.23117)
			(xy 185.359949 -22.224414) (xy 185.398664 -22.223984) (xy 185.399172 -22.223984) (xy 185.440274 -22.224479)
			(xy 185.522129 -22.232061) (xy 185.602935 -22.247164) (xy 185.682002 -22.269658) (xy 185.758657 -22.299352)
			(xy 185.832244 -22.335992) (xy 185.902137 -22.379266) (xy 185.967739 -22.428804) (xy 186.028491 -22.484184)
			(xy 186.083873 -22.544933) (xy 186.133414 -22.610533) (xy 186.17669 -22.680424) (xy 186.213333 -22.75401)
			(xy 186.24303 -22.830664) (xy 186.265528 -22.90973) (xy 186.280634 -22.990535) (xy 186.288219 -23.07239)
			(xy 186.28868 -23.113492) (xy 186.288296 -23.150242) (xy 186.282191 -23.223489) (xy 186.276488 -23.259796)
			(xy 186.274202 -23.274528) (xy 186.285632 -23.301706) (xy 186.38647 -23.37054) (xy 186.416188 -23.371556)
			(xy 186.428888 -23.363682) (xy 186.463409 -23.34352) (xy 186.535417 -23.308779) (xy 186.610254 -23.280645)
			(xy 186.687314 -23.259345) (xy 186.765977 -23.245051) (xy 186.845605 -23.237878) (xy 186.88558 -23.237444)
			(xy 186.885834 -23.237444) (xy 186.920378 -23.238206) (xy 186.930792 -23.23846) (xy 186.950096 -23.231094)
			(xy 187.017914 -23.165054) (xy 187.026042 -23.146258) (xy 187.025788 -23.13559) (xy 187.025788 -23.127208)
			(xy 187.026267 -23.085282) (xy 187.034158 -23.001803) (xy 187.049869 -22.919436) (xy 187.073262 -22.838914)
			(xy 187.10413 -22.76095) (xy 187.142197 -22.686237) (xy 187.187126 -22.615439) (xy 187.238519 -22.549183)
			(xy 187.295919 -22.488057) (xy 187.358817 -22.432605) (xy 187.426654 -22.383317) (xy 187.498828 -22.340633)
			(xy 187.574699 -22.30493) (xy 187.653594 -22.276526) (xy 187.734811 -22.255673) (xy 187.81763 -22.242555)
			(xy 187.901316 -22.237289) (xy 187.985126 -22.239923) (xy 188.068317 -22.250432) (xy 188.150149 -22.268723)
			(xy 188.229897 -22.294635) (xy 188.306852 -22.327936) (xy 188.380332 -22.368331) (xy 188.449684 -22.415463)
			(xy 188.514293 -22.468912) (xy 188.573586 -22.528204) (xy 188.627035 -22.592812) (xy 188.674166 -22.662164)
			(xy 188.714562 -22.735644) (xy 188.747864 -22.812599) (xy 188.773776 -22.892347) (xy 188.792067 -22.974179)
			(xy 188.802577 -23.05737) (xy 188.805211 -23.14118) (xy 188.799946 -23.224866) (xy 188.786828 -23.307685)
			(xy 188.765975 -23.388903) (xy 188.737571 -23.467797) (xy 188.701869 -23.543668) (xy 188.659185 -23.615843)
			(xy 188.609898 -23.68368) (xy 188.554446 -23.746578) (xy 188.49332 -23.803978) (xy 188.427064 -23.855371)
			(xy 188.356266 -23.900301) (xy 188.281554 -23.938369) (xy 188.20359 -23.969236) (xy 188.123068 -23.99263)
			(xy 188.040701 -24.008342) (xy 187.957222 -24.016233) (xy 187.915296 -24.016716) (xy 187.880752 -24.015954)
			(xy 187.870338 -24.0157) (xy 187.851034 -24.023066) (xy 187.783216 -24.089106) (xy 187.775088 -24.107902)
			(xy 187.775342 -24.11857) (xy 187.775342 -24.126952) (xy 187.774838 -24.169236) (xy 187.766815 -24.253422)
			(xy 187.750838 -24.336467) (xy 187.727051 -24.41762) (xy 187.695668 -24.496149) (xy 187.656972 -24.571344)
			(xy 187.611314 -24.642527) (xy 187.585604 -24.6761) (xy 187.579508 -24.68372) (xy 187.574174 -24.70277)
			(xy 187.583572 -24.79294) (xy 187.59297 -24.810466) (xy 187.60059 -24.816816) (xy 187.621673 -24.835055)
			(xy 187.658873 -24.876571) (xy 187.689634 -24.92306) (xy 187.7133 -24.973532) (xy 187.729366 -25.026911)
			(xy 187.737491 -25.08206) (xy 187.738004 -25.109932) (xy 187.73745 -25.139352) (xy 187.728408 -25.197492)
			(xy 187.710528 -25.253548) (xy 187.697872 -25.280112) (xy 187.693458 -25.290213) (xy 187.692716 -25.312215)
			(xy 187.701275 -25.332497) (xy 187.709048 -25.34031) (xy 187.739037 -25.368336) (xy 187.794291 -25.429044)
			(xy 187.843714 -25.494587) (xy 187.886886 -25.564405) (xy 187.923439 -25.637906) (xy 187.953062 -25.714463)
			(xy 187.975502 -25.793424) (xy 187.99057 -25.874117) (xy 187.998136 -25.955856) (xy 187.998608 -25.9969)
			(xy 187.998104 -26.039248) (xy 187.990053 -26.123562) (xy 187.974024 -26.206728) (xy 187.950163 -26.287995)
			(xy 187.918684 -26.366625) (xy 187.879873 -26.441906) (xy 187.834083 -26.513158) (xy 187.781727 -26.579734)
			(xy 187.723279 -26.641032) (xy 187.659269 -26.696497) (xy 187.590277 -26.745626) (xy 187.516927 -26.787975)
			(xy 187.439884 -26.823159) (xy 187.359845 -26.850861) (xy 187.277536 -26.870829) (xy 187.193701 -26.882882)
			(xy 187.1091 -26.886913) (xy 187.024499 -26.882882) (xy 186.940664 -26.870829) (xy 186.858355 -26.850861)
			(xy 186.778316 -26.823159) (xy 186.701273 -26.787975) (xy 186.627923 -26.745626) (xy 186.558931 -26.696497)
			(xy 186.494921 -26.641032) (xy 186.436473 -26.579734) (xy 186.384117 -26.513158) (xy 186.338327 -26.441906)
			(xy 186.299516 -26.366625) (xy 186.268037 -26.287995) (xy 186.244176 -26.206728) (xy 186.228147 -26.123562)
			(xy 186.220096 -26.039248) (xy 186.219592 -25.9969) (xy 186.219592 -25.996646) (xy 186.220074 -25.954732)
			(xy 186.227973 -25.871276) (xy 186.243686 -25.788933) (xy 186.267073 -25.708433) (xy 186.297928 -25.63049)
			(xy 186.335977 -25.555794) (xy 186.358022 -25.520142) (xy 186.363356 -25.512014) (xy 186.366912 -25.49398)
			(xy 186.351926 -25.407366) (xy 186.342528 -25.391618) (xy 186.334654 -25.385522) (xy 186.312171 -25.36733)
			(xy 186.272438 -25.325309) (xy 186.239501 -25.277774) (xy 186.214112 -25.225813) (xy 186.196855 -25.170616)
			(xy 186.188124 -25.113448) (xy 186.187588 -25.084532) (xy 186.1882 -25.053635) (xy 186.198154 -24.992649)
			(xy 186.217807 -24.934064) (xy 186.246646 -24.879413) (xy 186.264804 -24.854408) (xy 186.269945 -24.847041)
			(xy 186.275155 -24.829861) (xy 186.274964 -24.82088) (xy 186.273186 -24.790654) (xy 186.272273 -24.78136)
			(xy 186.264728 -24.764296) (xy 186.258454 -24.75738) (xy 186.227759 -24.726121) (xy 186.172017 -24.658528)
			(xy 186.123193 -24.585779) (xy 186.081763 -24.508581) (xy 186.048126 -24.427682) (xy 186.02261 -24.343866)
			(xy 186.005463 -24.257947) (xy 185.996849 -24.170759) (xy 185.996326 -24.126952) (xy 185.996716 -24.090202)
			(xy 186.002817 -24.016955) (xy 186.008518 -23.980648) (xy 186.010804 -23.965916) (xy 185.999374 -23.938738)
			(xy 185.898536 -23.869904) (xy 185.868818 -23.868888) (xy 185.856118 -23.876762) (xy 185.821592 -23.896916)
			(xy 185.749586 -23.931659) (xy 185.67475 -23.959795) (xy 185.59769 -23.981097) (xy 185.519029 -23.995392)
			(xy 185.439401 -24.002565) (xy 185.399426 -24.003) (xy 185.399172 -24.003) (xy 185.358069 -24.00256)
			(xy 185.276213 -23.994973) (xy 185.195407 -23.979865) (xy 185.116339 -23.957366) (xy 185.039685 -23.927667)
			(xy 184.966098 -23.891023) (xy 184.896206 -23.847745) (xy 184.830605 -23.798203) (xy 184.769854 -23.74282)
			(xy 184.714474 -23.682068) (xy 184.664934 -23.616465) (xy 184.621659 -23.546571) (xy 184.585018 -23.472982)
			(xy 184.555323 -23.396326) (xy 184.532827 -23.317258) (xy 184.517722 -23.236451) (xy 184.510138 -23.154595)
			(xy 184.509664 -23.113492) (xy 184.50974 -23.097666) (xy 184.510885 -23.066036) (xy 184.51195 -23.050246)
			(xy 184.512712 -23.0378) (xy 184.503314 -23.015448) (xy 184.420256 -22.946868) (xy 184.39638 -22.941788)
			(xy 184.384188 -22.94509) (xy 184.346683 -22.954704) (xy 184.270425 -22.968139) (xy 184.193288 -22.974889)
			(xy 184.154572 -22.975316) (xy 184.154064 -22.975316) (xy 184.114011 -22.974854) (xy 184.034231 -22.967648)
			(xy 183.955421 -22.953299) (xy 183.878221 -22.931922) (xy 183.803255 -22.903691) (xy 183.731132 -22.868834)
			(xy 183.662434 -22.827634) (xy 183.597719 -22.780424) (xy 183.567324 -22.754336) (xy 183.560214 -22.748636)
			(xy 183.543156 -22.742261) (xy 183.53405 -22.74189) (xy 183.504078 -22.74189) (xy 183.494977 -22.742277)
			(xy 183.477927 -22.748657) (xy 183.470804 -22.754336) (xy 183.440423 -22.780441) (xy 183.375708 -22.827657)
			(xy 183.30701 -22.868862) (xy 183.234885 -22.903721) (xy 183.159917 -22.931954) (xy 183.082714 -22.95333)
			(xy 183.003901 -22.967676) (xy 182.924118 -22.974877) (xy 182.884064 -22.975316) (xy 182.840997 -22.974829)
			(xy 182.755267 -22.966506) (xy 182.670744 -22.949931) (xy 182.588219 -22.925261) (xy 182.508467 -22.892726)
			(xy 182.432234 -22.852632) (xy 182.360236 -22.805354) (xy 182.293148 -22.751334) (xy 182.262018 -22.72157)
			(xy 182.254062 -22.714542) (xy 182.234199 -22.707118) (xy 182.213029 -22.708333) (xy 182.203344 -22.71268)
			(xy 182.165764 -22.731282) (xy 182.087794 -22.762153) (xy 182.007267 -22.785558) (xy 181.924897 -22.801289)
			(xy 181.841413 -22.809208) (xy 181.799484 -22.809708) (xy 181.79923 -22.809708) (xy 181.756417 -22.809195)
			(xy 181.671186 -22.80098) (xy 181.587138 -22.784614) (xy 181.505053 -22.760248) (xy 181.425688 -22.728107)
			(xy 181.349778 -22.688489) (xy 181.278027 -22.641761) (xy 181.211097 -22.588355) (xy 181.149608 -22.528764)
			(xy 181.09413 -22.463542) (xy 181.069234 -22.428708) (xy 181.061727 -22.41902) (xy 181.040068 -22.407621)
			(xy 181.027832 -22.406864) (xy 180.98686 -22.406177) (xy 180.905296 -22.398239) (xy 180.824808 -22.382833)
			(xy 180.746078 -22.360089) (xy 180.669773 -22.330199) (xy 180.596541 -22.293419) (xy 180.527003 -22.250058)
			(xy 180.461748 -22.200486) (xy 180.401328 -22.145121) (xy 180.346257 -22.084434) (xy 180.297001 -22.018939)
			(xy 180.253979 -21.949191) (xy 180.217553 -21.875782) (xy 180.188034 -21.799334) (xy 180.165672 -21.720494)
			(xy 180.150656 -21.639932) (xy 180.143113 -21.558331) (xy 180.142642 -21.517356) (xy 175.592486 -21.517356)
			(xy 175.592486 -24.7548) (xy 183.389512 -24.7548) (xy 183.393542 -24.670199) (xy 183.405596 -24.586364)
			(xy 183.425565 -24.504054) (xy 183.453267 -24.424016) (xy 183.488453 -24.346973) (xy 183.530802 -24.273624)
			(xy 183.579933 -24.204633) (xy 183.635399 -24.140624) (xy 183.696698 -24.082178) (xy 183.763276 -24.029823)
			(xy 183.834529 -23.984034) (xy 183.909812 -23.945226) (xy 183.988443 -23.91375) (xy 184.06971 -23.889891)
			(xy 184.152878 -23.873866) (xy 184.237191 -23.865818) (xy 184.27954 -23.865332) (xy 184.323025 -23.865878)
			(xy 184.40958 -23.874377) (xy 184.494893 -23.891279) (xy 184.57815 -23.916424) (xy 184.658556 -23.949572)
			(xy 184.735345 -23.990405) (xy 184.807784 -24.038536) (xy 184.875181 -24.093504) (xy 184.936895 -24.154786)
			(xy 184.992335 -24.221796) (xy 185.040973 -24.293895) (xy 185.082346 -24.370395) (xy 185.116057 -24.450567)
			(xy 185.129424 -24.49195) (xy 185.132472 -24.50211) (xy 185.145934 -24.517858) (xy 185.231278 -24.560022)
			(xy 185.251852 -24.561038) (xy 185.261758 -24.557228) (xy 185.293836 -24.546102) (xy 185.360655 -24.534091)
			(xy 185.3946 -24.533352) (xy 185.421848 -24.533918) (xy 185.47579 -24.541674) (xy 185.52808 -24.557027)
			(xy 185.577652 -24.579666) (xy 185.623497 -24.609129) (xy 185.664683 -24.644817) (xy 185.700371 -24.686003)
			(xy 185.729834 -24.731848) (xy 185.752473 -24.78142) (xy 185.767826 -24.83371) (xy 185.775582 -24.887652)
			(xy 185.775582 -24.942148) (xy 185.767826 -24.99609) (xy 185.752473 -25.04838) (xy 185.729834 -25.097952)
			(xy 185.700371 -25.143797) (xy 185.664683 -25.184983) (xy 185.623497 -25.220671) (xy 185.577652 -25.250134)
			(xy 185.52808 -25.272773) (xy 185.47579 -25.288126) (xy 185.421848 -25.295882) (xy 185.3946 -25.296368)
			(xy 185.364022 -25.295772) (xy 185.303649 -25.286015) (xy 185.245606 -25.266752) (xy 185.19138 -25.238474)
			(xy 185.166508 -25.220676) (xy 185.157872 -25.214326) (xy 185.13806 -25.2095) (xy 185.044334 -25.22601)
			(xy 185.027062 -25.237186) (xy 185.02122 -25.246076) (xy 185.000822 -25.27623) (xy 184.955809 -25.333453)
			(xy 184.931304 -25.360376) (xy 184.921652 -25.370536) (xy 184.91581 -25.396952) (xy 184.95137 -25.50795)
			(xy 184.971436 -25.526238) (xy 184.985152 -25.529032) (xy 185.013472 -25.535368) (xy 185.0679 -25.555496)
			(xy 185.11865 -25.583638) (xy 185.164551 -25.619145) (xy 185.204542 -25.661196) (xy 185.2377 -25.70882)
			(xy 185.26326 -25.760919) (xy 185.280632 -25.816288) (xy 185.289414 -25.873651) (xy 185.289952 -25.902666)
			(xy 185.289466 -25.929917) (xy 185.28171 -25.983865) (xy 185.266355 -26.03616) (xy 185.243713 -26.085737)
			(xy 185.214247 -26.131587) (xy 185.178556 -26.172778) (xy 185.137365 -26.208469) (xy 185.091515 -26.237935)
			(xy 185.041938 -26.260577) (xy 184.989643 -26.275932) (xy 184.935695 -26.283688) (xy 184.881193 -26.283688)
			(xy 184.827245 -26.275932) (xy 184.77495 -26.260577) (xy 184.725373 -26.237935) (xy 184.679523 -26.208469)
			(xy 184.638332 -26.172778) (xy 184.602641 -26.131587) (xy 184.573175 -26.085737) (xy 184.550533 -26.03616)
			(xy 184.535178 -25.983865) (xy 184.527422 -25.929917) (xy 184.526936 -25.902666) (xy 184.526936 -25.902412)
			(xy 184.527297 -25.879202) (xy 184.532941 -25.833127) (xy 184.544123 -25.788074) (xy 184.552082 -25.766268)
			(xy 184.557162 -25.75306) (xy 184.552844 -25.72639) (xy 184.478422 -25.636728) (xy 184.452768 -25.62733)
			(xy 184.439052 -25.62987) (xy 184.399523 -25.63665) (xy 184.319644 -25.643897) (xy 184.27954 -25.644348)
			(xy 184.237191 -25.643782) (xy 184.152878 -25.635734) (xy 184.06971 -25.619709) (xy 183.988443 -25.59585)
			(xy 183.909812 -25.564374) (xy 183.834529 -25.525566) (xy 183.763276 -25.479777) (xy 183.696698 -25.427422)
			(xy 183.635399 -25.368976) (xy 183.579933 -25.304967) (xy 183.530802 -25.235976) (xy 183.488453 -25.162627)
			(xy 183.453267 -25.085584) (xy 183.425565 -25.005546) (xy 183.405596 -24.923236) (xy 183.393542 -24.839401)
			(xy 183.389512 -24.7548) (xy 175.592486 -24.7548) (xy 175.592486 -25.92324) (xy 180.826662 -25.92324)
			(xy 180.830733 -25.867618) (xy 180.842859 -25.813181) (xy 180.862782 -25.76109) (xy 180.890078 -25.712455)
			(xy 180.924164 -25.668312) (xy 180.964313 -25.629603) (xy 181.009671 -25.597152) (xy 181.059271 -25.571651)
			(xy 181.112055 -25.553644) (xy 181.166898 -25.543514) (xy 181.222632 -25.541477) (xy 181.278069 -25.547577)
			(xy 181.332026 -25.561683) (xy 181.383355 -25.583495) (xy 181.430961 -25.612549) (xy 181.473829 -25.648224)
			(xy 181.511046 -25.689761) (xy 181.541819 -25.736274) (xy 181.565491 -25.786771) (xy 181.581559 -25.840178)
			(xy 181.589679 -25.895354) (xy 181.590188 -25.92324) (xy 181.589679 -25.951126) (xy 181.581559 -26.006302)
			(xy 181.565491 -26.059709) (xy 181.541819 -26.110206) (xy 181.511046 -26.156719) (xy 181.473829 -26.198256)
			(xy 181.430961 -26.233931) (xy 181.383355 -26.262985) (xy 181.332026 -26.284797) (xy 181.278069 -26.298903)
			(xy 181.222632 -26.305003) (xy 181.166898 -26.302966) (xy 181.112055 -26.292836) (xy 181.059271 -26.274829)
			(xy 181.009671 -26.249328) (xy 180.964313 -26.216877) (xy 180.924164 -26.178168) (xy 180.890078 -26.134025)
			(xy 180.862782 -26.08539) (xy 180.842859 -26.033299) (xy 180.830733 -25.978862) (xy 180.826662 -25.92324)
			(xy 175.592486 -25.92324) (xy 175.592486 -27.667966) (xy 175.592921 -27.678031) (xy 175.60065 -27.69662)
			(xy 175.607472 -27.704034) (xy 175.902112 -27.998674) (xy 175.942752 -27.999436) (xy 175.957992 -27.985466)
			(xy 175.987891 -27.958472) (xy 176.051891 -27.909549) (xy 176.120168 -27.866797) (xy 176.192129 -27.830588)
			(xy 176.267149 -27.801236) (xy 176.344576 -27.778997) (xy 176.423737 -27.764064) (xy 176.503945 -27.756565)
			(xy 176.544224 -27.756104) (xy 176.588662 -27.75667) (xy 176.677069 -27.765789) (xy 176.764073 -27.78394)
			(xy 176.848752 -27.81093) (xy 176.930211 -27.846473) (xy 176.969166 -27.867864) (xy 176.976945 -27.871888)
			(xy 176.994185 -27.874906) (xy 177.011425 -27.871888) (xy 177.019204 -27.867864) (xy 177.054605 -27.848401)
			(xy 177.128349 -27.8154) (xy 177.204851 -27.789428) (xy 177.283445 -27.770713) (xy 177.363443 -27.759418)
			(xy 177.444146 -27.755642) (xy 177.524849 -27.759418) (xy 177.604847 -27.770713) (xy 177.683441 -27.789428)
			(xy 177.759943 -27.8154) (xy 177.833687 -27.848401) (xy 177.869088 -27.867864) (xy 177.876867 -27.871888)
			(xy 177.894107 -27.874906) (xy 177.911347 -27.871888) (xy 177.919126 -27.867864) (xy 177.958095 -27.846502)
			(xy 178.039553 -27.810962) (xy 178.124229 -27.783972) (xy 178.211228 -27.765818) (xy 178.299631 -27.756691)
			(xy 178.344068 -27.756104) (xy 178.344322 -27.756104) (xy 178.38876 -27.756671) (xy 178.477165 -27.765793)
			(xy 178.564166 -27.783949) (xy 178.648841 -27.810947) (xy 178.730294 -27.846501) (xy 178.769264 -27.867864)
			(xy 178.794156 -27.874468) (xy 178.819048 -27.867864) (xy 178.85802 -27.846508) (xy 178.93948 -27.810974)
			(xy 179.024156 -27.783982) (xy 179.111152 -27.765817) (xy 179.199554 -27.75667) (xy 179.24399 -27.756104)
			(xy 179.244244 -27.756104) (xy 179.286723 -27.756612) (xy 179.371271 -27.764953) (xy 179.454593 -27.781551)
			(xy 179.535883 -27.806245) (xy 179.614358 -27.838796) (xy 179.68926 -27.878892) (xy 179.759866 -27.926143)
			(xy 179.825495 -27.980096) (xy 179.885512 -28.040228) (xy 179.939339 -28.105959) (xy 179.986456 -28.176655)
			(xy 180.026408 -28.251633) (xy 180.05881 -28.33017) (xy 180.083349 -28.411508) (xy 180.092096 -28.45308)
			(xy 180.095652 -28.471114) (xy 180.123592 -28.493974)
		)
		(stroke
			(width 0)
			(type solid)
		)
		(fill yes)
		(layer "In13.Cu")
		(net "P12V_SCM_R")
	)
	(gr_poly
		(pts
			(xy 356.319582 -269.355062) (xy 356.319582 -269.041626) (xy 356.536244 -268.824964) (xy 358.876346 -268.824964)
			(xy 359.57637 -269.524988) (xy 360.913172 -269.524988) (xy 361.119674 -269.318486) (xy 361.12704 -269.294864)
			(xy 361.124754 -269.282164) (xy 361.122279 -269.268262) (xy 361.11961 -269.240149) (xy 361.11942 -269.22603)
			(xy 361.119864 -269.202036) (xy 361.127367 -269.154639) (xy 361.142193 -269.108999) (xy 361.163978 -269.066241)
			(xy 361.192183 -269.027417) (xy 361.226115 -268.993484) (xy 361.264939 -268.965279) (xy 361.307697 -268.943494)
			(xy 361.353337 -268.928668) (xy 361.400734 -268.921164) (xy 361.424728 -268.920722) (xy 361.438847 -268.920921)
			(xy 361.466959 -268.923591) (xy 361.480862 -268.926056) (xy 361.493562 -268.928342) (xy 361.517184 -268.920976)
			(xy 361.670854 -268.767306) (xy 361.677541 -268.760031) (xy 361.685266 -268.741864) (xy 361.68584 -268.732)
			(xy 361.686856 -268.651228) (xy 361.679744 -268.63294) (xy 361.672886 -268.625574) (xy 361.657336 -268.608475)
			(xy 361.631043 -268.570467) (xy 361.610775 -268.528932) (xy 361.596994 -268.484818) (xy 361.590014 -268.439132)
			(xy 361.589574 -268.416024) (xy 361.590096 -268.390769) (xy 361.598409 -268.340947) (xy 361.61481 -268.293173)
			(xy 361.638851 -268.24875) (xy 361.669875 -268.20889) (xy 361.707037 -268.17468) (xy 361.749323 -268.147054)
			(xy 361.795579 -268.126764) (xy 361.844544 -268.114364) (xy 361.894882 -268.110193) (xy 361.94522 -268.114364)
			(xy 361.994185 -268.126764) (xy 362.040441 -268.147054) (xy 362.082727 -268.17468) (xy 362.119889 -268.20889)
			(xy 362.150913 -268.24875) (xy 362.174954 -268.293173) (xy 362.191355 -268.340947) (xy 362.199668 -268.390769)
			(xy 362.20019 -268.416024) (xy 362.199568 -268.443864) (xy 362.189481 -268.498623) (xy 362.169661 -268.550656)
			(xy 362.15574 -268.574774) (xy 362.15155 -268.582297) (xy 362.147972 -268.599129) (xy 362.150177 -268.616195)
			(xy 362.153708 -268.62405) (xy 362.16717 -268.65072) (xy 362.171737 -268.658896) (xy 362.185577 -268.671487)
			(xy 362.203027 -268.67824) (xy 362.212382 -268.67866) (xy 362.222542 -268.67866) (xy 362.228384 -268.677136)
			(xy 362.26194 -268.669312) (xy 362.33033 -268.660912) (xy 362.364782 -268.660372) (xy 362.662724 -268.660372)
			(xy 362.697176 -268.660899) (xy 362.765567 -268.669306) (xy 362.799122 -268.677136) (xy 362.804964 -268.67866)
			(xy 362.864654 -268.67866) (xy 362.870496 -268.677136) (xy 362.904051 -268.669307) (xy 362.972442 -268.660896)
			(xy 363.006894 -268.660372) (xy 363.304836 -268.660372) (xy 363.339288 -268.6609) (xy 363.407679 -268.669308)
			(xy 363.441234 -268.677136) (xy 363.447076 -268.67866) (xy 363.457236 -268.67866) (xy 363.466576 -268.678186)
			(xy 363.483988 -268.671404) (xy 363.497834 -268.658856) (xy 363.502448 -268.65072) (xy 363.51591 -268.62405)
			(xy 363.519502 -268.616212) (xy 363.521725 -268.599127) (xy 363.518118 -268.58228) (xy 363.513878 -268.574774)
			(xy 363.499921 -268.550672) (xy 363.480069 -268.498641) (xy 363.470001 -268.443869) (xy 363.469428 -268.416024)
			(xy 363.46995 -268.390769) (xy 363.478263 -268.340947) (xy 363.494664 -268.293173) (xy 363.518705 -268.24875)
			(xy 363.549729 -268.20889) (xy 363.586891 -268.17468) (xy 363.629177 -268.147054) (xy 363.675433 -268.126764)
			(xy 363.724398 -268.114364) (xy 363.774736 -268.110193) (xy 363.825074 -268.114364) (xy 363.874039 -268.126764)
			(xy 363.920295 -268.147054) (xy 363.962581 -268.17468) (xy 363.999743 -268.20889) (xy 364.030767 -268.24875)
			(xy 364.054808 -268.293173) (xy 364.071209 -268.340947) (xy 364.079522 -268.390769) (xy 364.080044 -268.416024)
			(xy 365.34904 -268.416024) (xy 365.353 -268.36697) (xy 365.364777 -268.319186) (xy 365.384068 -268.27391)
			(xy 365.410371 -268.232314) (xy 365.443006 -268.195477) (xy 365.481127 -268.164352) (xy 365.523748 -268.139745)
			(xy 365.569764 -268.122293) (xy 365.617983 -268.112449) (xy 365.667158 -268.110468) (xy 365.716013 -268.1164)
			(xy 365.763284 -268.130092) (xy 365.807746 -268.15119) (xy 365.848249 -268.179146) (xy 365.883742 -268.213238)
			(xy 365.913307 -268.252582) (xy 365.936178 -268.296159) (xy 365.951762 -268.34284) (xy 365.959657 -268.391417)
			(xy 365.960152 -268.416024) (xy 367.228894 -268.416024) (xy 367.232854 -268.36697) (xy 367.244631 -268.319186)
			(xy 367.263922 -268.27391) (xy 367.290225 -268.232314) (xy 367.32286 -268.195477) (xy 367.360981 -268.164352)
			(xy 367.403602 -268.139745) (xy 367.449618 -268.122293) (xy 367.497837 -268.112449) (xy 367.547012 -268.110468)
			(xy 367.595867 -268.1164) (xy 367.643138 -268.130092) (xy 367.6876 -268.15119) (xy 367.728103 -268.179146)
			(xy 367.763596 -268.213238) (xy 367.793161 -268.252582) (xy 367.816032 -268.296159) (xy 367.831616 -268.34284)
			(xy 367.839511 -268.391417) (xy 367.840006 -268.416024) (xy 369.109002 -268.416024) (xy 369.112962 -268.36697)
			(xy 369.124739 -268.319186) (xy 369.14403 -268.27391) (xy 369.170333 -268.232314) (xy 369.202968 -268.195477)
			(xy 369.241089 -268.164352) (xy 369.28371 -268.139745) (xy 369.329726 -268.122293) (xy 369.377945 -268.112449)
			(xy 369.42712 -268.110468) (xy 369.475975 -268.1164) (xy 369.523246 -268.130092) (xy 369.567708 -268.15119)
			(xy 369.608211 -268.179146) (xy 369.643704 -268.213238) (xy 369.673269 -268.252582) (xy 369.69614 -268.296159)
			(xy 369.711724 -268.34284) (xy 369.719619 -268.391417) (xy 369.720114 -268.416024) (xy 370.98911 -268.416024)
			(xy 370.99307 -268.36697) (xy 371.004847 -268.319186) (xy 371.024138 -268.27391) (xy 371.050441 -268.232314)
			(xy 371.083076 -268.195477) (xy 371.121197 -268.164352) (xy 371.163818 -268.139745) (xy 371.209834 -268.122293)
			(xy 371.258053 -268.112449) (xy 371.307228 -268.110468) (xy 371.356083 -268.1164) (xy 371.403354 -268.130092)
			(xy 371.447816 -268.15119) (xy 371.488319 -268.179146) (xy 371.523812 -268.213238) (xy 371.553377 -268.252582)
			(xy 371.576248 -268.296159) (xy 371.591832 -268.34284) (xy 371.599727 -268.391417) (xy 371.600222 -268.416024)
			(xy 372.868964 -268.416024) (xy 372.872924 -268.36697) (xy 372.884701 -268.319186) (xy 372.903992 -268.27391)
			(xy 372.930295 -268.232314) (xy 372.96293 -268.195477) (xy 373.001051 -268.164352) (xy 373.043672 -268.139745)
			(xy 373.089688 -268.122293) (xy 373.137907 -268.112449) (xy 373.187082 -268.110468) (xy 373.235937 -268.1164)
			(xy 373.283208 -268.130092) (xy 373.32767 -268.15119) (xy 373.368173 -268.179146) (xy 373.403666 -268.213238)
			(xy 373.433231 -268.252582) (xy 373.456102 -268.296159) (xy 373.471686 -268.34284) (xy 373.479581 -268.391417)
			(xy 373.480076 -268.416024) (xy 373.479581 -268.440631) (xy 373.471686 -268.489208) (xy 373.456102 -268.535889)
			(xy 373.433231 -268.579466) (xy 373.403666 -268.61881) (xy 373.368173 -268.652902) (xy 373.32767 -268.680858)
			(xy 373.283208 -268.701956) (xy 373.235937 -268.715648) (xy 373.187082 -268.72158) (xy 373.137907 -268.719599)
			(xy 373.089688 -268.709755) (xy 373.043672 -268.692303) (xy 373.001051 -268.667696) (xy 372.96293 -268.636571)
			(xy 372.930295 -268.599734) (xy 372.903992 -268.558138) (xy 372.884701 -268.512862) (xy 372.872924 -268.465078)
			(xy 372.868964 -268.416024) (xy 371.600222 -268.416024) (xy 371.599727 -268.440631) (xy 371.591832 -268.489208)
			(xy 371.576248 -268.535889) (xy 371.553377 -268.579466) (xy 371.523812 -268.61881) (xy 371.488319 -268.652902)
			(xy 371.447816 -268.680858) (xy 371.403354 -268.701956) (xy 371.356083 -268.715648) (xy 371.307228 -268.72158)
			(xy 371.258053 -268.719599) (xy 371.209834 -268.709755) (xy 371.163818 -268.692303) (xy 371.121197 -268.667696)
			(xy 371.083076 -268.636571) (xy 371.050441 -268.599734) (xy 371.024138 -268.558138) (xy 371.004847 -268.512862)
			(xy 370.99307 -268.465078) (xy 370.98911 -268.416024) (xy 369.720114 -268.416024) (xy 369.719619 -268.440631)
			(xy 369.711724 -268.489208) (xy 369.69614 -268.535889) (xy 369.673269 -268.579466) (xy 369.643704 -268.61881)
			(xy 369.608211 -268.652902) (xy 369.567708 -268.680858) (xy 369.523246 -268.701956) (xy 369.475975 -268.715648)
			(xy 369.42712 -268.72158) (xy 369.377945 -268.719599) (xy 369.329726 -268.709755) (xy 369.28371 -268.692303)
			(xy 369.241089 -268.667696) (xy 369.202968 -268.636571) (xy 369.170333 -268.599734) (xy 369.14403 -268.558138)
			(xy 369.124739 -268.512862) (xy 369.112962 -268.465078) (xy 369.109002 -268.416024) (xy 367.840006 -268.416024)
			(xy 367.839511 -268.440631) (xy 367.831616 -268.489208) (xy 367.816032 -268.535889) (xy 367.793161 -268.579466)
			(xy 367.763596 -268.61881) (xy 367.728103 -268.652902) (xy 367.6876 -268.680858) (xy 367.643138 -268.701956)
			(xy 367.595867 -268.715648) (xy 367.547012 -268.72158) (xy 367.497837 -268.719599) (xy 367.449618 -268.709755)
			(xy 367.403602 -268.692303) (xy 367.360981 -268.667696) (xy 367.32286 -268.636571) (xy 367.290225 -268.599734)
			(xy 367.263922 -268.558138) (xy 367.244631 -268.512862) (xy 367.232854 -268.465078) (xy 367.228894 -268.416024)
			(xy 365.960152 -268.416024) (xy 365.959657 -268.440631) (xy 365.951762 -268.489208) (xy 365.936178 -268.535889)
			(xy 365.913307 -268.579466) (xy 365.883742 -268.61881) (xy 365.848249 -268.652902) (xy 365.807746 -268.680858)
			(xy 365.763284 -268.701956) (xy 365.716013 -268.715648) (xy 365.667158 -268.72158) (xy 365.617983 -268.719599)
			(xy 365.569764 -268.709755) (xy 365.523748 -268.692303) (xy 365.481127 -268.667696) (xy 365.443006 -268.636571)
			(xy 365.410371 -268.599734) (xy 365.384068 -268.558138) (xy 365.364777 -268.512862) (xy 365.353 -268.465078)
			(xy 365.34904 -268.416024) (xy 364.080044 -268.416024) (xy 364.079719 -268.43675) (xy 364.074144 -268.477824)
			(xy 364.063046 -268.517762) (xy 364.055152 -268.536928) (xy 364.050072 -268.548612) (xy 364.052358 -268.574012)
			(xy 364.105952 -268.6558) (xy 364.113472 -268.665983) (xy 364.13573 -268.677973) (xy 364.14837 -268.67866)
			(xy 364.298738 -268.67866) (xy 364.308804 -268.679092) (xy 364.327393 -268.686822) (xy 364.334806 -268.693646)
			(xy 365.092234 -269.451074) (xy 365.099633 -269.457918) (xy 365.118231 -269.465644) (xy 365.128302 -269.46606)
			(xy 366.682274 -269.46606) (xy 366.694455 -269.465286) (xy 366.71606 -269.454009) (xy 366.723676 -269.44447)
			(xy 366.77854 -269.366238) (xy 366.781842 -269.3416) (xy 366.777778 -269.329916) (xy 366.769268 -269.304791)
			(xy 366.760079 -269.252551) (xy 366.75949 -269.22603) (xy 366.760012 -269.200775) (xy 366.768325 -269.150953)
			(xy 366.784726 -269.103179) (xy 366.808767 -269.058756) (xy 366.839791 -269.018896) (xy 366.876953 -268.984686)
			(xy 366.919239 -268.95706) (xy 366.965495 -268.93677) (xy 367.01446 -268.92437) (xy 367.064798 -268.920199)
			(xy 367.115136 -268.92437) (xy 367.164101 -268.93677) (xy 367.210357 -268.95706) (xy 367.252643 -268.984686)
			(xy 367.289805 -269.018896) (xy 367.320829 -269.058756) (xy 367.34487 -269.103179) (xy 367.361271 -269.150953)
			(xy 367.369584 -269.200775) (xy 367.370106 -269.22603) (xy 367.369513 -269.25255) (xy 367.360315 -269.304787)
			(xy 367.351818 -269.329916) (xy 367.347754 -269.3416) (xy 367.351056 -269.366238) (xy 367.40592 -269.44447)
			(xy 367.413498 -269.454048) (xy 367.435129 -269.465304) (xy 367.447322 -269.46606) (xy 369.502182 -269.46606)
			(xy 369.514362 -269.465285) (xy 369.535964 -269.454005) (xy 369.543584 -269.44447) (xy 369.598448 -269.366238)
			(xy 369.60175 -269.3416) (xy 369.597686 -269.329916) (xy 369.589177 -269.304791) (xy 369.579987 -269.252551)
			(xy 369.579398 -269.22603) (xy 369.57992 -269.200775) (xy 369.588233 -269.150953) (xy 369.604634 -269.103179)
			(xy 369.628675 -269.058756) (xy 369.659699 -269.018896) (xy 369.696861 -268.984686) (xy 369.739147 -268.95706)
			(xy 369.785403 -268.93677) (xy 369.834368 -268.92437) (xy 369.884706 -268.920199) (xy 369.935044 -268.92437)
			(xy 369.984009 -268.93677) (xy 370.030265 -268.95706) (xy 370.072551 -268.984686) (xy 370.109713 -269.018896)
			(xy 370.140737 -269.058756) (xy 370.164778 -269.103179) (xy 370.181179 -269.150953) (xy 370.189492 -269.200775)
			(xy 370.190014 -269.22603) (xy 370.189421 -269.25255) (xy 370.180223 -269.304787) (xy 370.171726 -269.329916)
			(xy 370.167662 -269.3416) (xy 370.170964 -269.366238) (xy 370.225828 -269.44447) (xy 370.2334 -269.454063)
			(xy 370.25503 -269.465358) (xy 370.26723 -269.46606) (xy 372.322344 -269.46606) (xy 372.334528 -269.465293)
			(xy 372.356144 -269.454022) (xy 372.363746 -269.44447) (xy 372.41861 -269.366238) (xy 372.421912 -269.3416)
			(xy 372.417848 -269.329916) (xy 372.409339 -269.304791) (xy 372.400151 -269.252551) (xy 372.39956 -269.22603)
			(xy 372.400082 -269.200775) (xy 372.408395 -269.150953) (xy 372.424796 -269.103179) (xy 372.448837 -269.058756)
			(xy 372.479861 -269.018896) (xy 372.517023 -268.984686) (xy 372.559309 -268.95706) (xy 372.605565 -268.93677)
			(xy 372.65453 -268.92437) (xy 372.704868 -268.920199) (xy 372.755206 -268.92437) (xy 372.804171 -268.93677)
			(xy 372.850427 -268.95706) (xy 372.892713 -268.984686) (xy 372.929875 -269.018896) (xy 372.960899 -269.058756)
			(xy 372.98494 -269.103179) (xy 373.001341 -269.150953) (xy 373.009654 -269.200775) (xy 373.010176 -269.22603)
			(xy 373.009583 -269.25255) (xy 373.000384 -269.304787) (xy 372.991888 -269.329916) (xy 372.987824 -269.3416)
			(xy 372.991126 -269.366238) (xy 373.04599 -269.44447) (xy 373.053566 -269.454053) (xy 373.075197 -269.465321)
			(xy 373.087392 -269.46606) (xy 374.631458 -269.46606) (xy 374.641523 -269.465625) (xy 374.660108 -269.457891)
			(xy 374.667526 -269.451074) (xy 374.878854 -269.239746) (xy 374.885697 -269.232347) (xy 374.893419 -269.213748)
			(xy 374.89384 -269.203678) (xy 374.89384 -268.702282) (xy 374.893205 -268.690341) (xy 374.882484 -268.669001)
			(xy 374.873266 -268.661388) (xy 374.854435 -268.646886) (xy 374.821077 -268.613032) (xy 374.793369 -268.574417)
			(xy 374.771979 -268.531975) (xy 374.757424 -268.486731) (xy 374.750057 -268.439778) (xy 374.750055 -268.392251)
			(xy 374.757418 -268.345297) (xy 374.771968 -268.300052) (xy 374.793354 -268.257607) (xy 374.821059 -268.21899)
			(xy 374.854413 -268.185133) (xy 374.873266 -268.17066) (xy 374.882493 -268.163048) (xy 374.893232 -268.141711)
			(xy 374.89384 -268.129766) (xy 374.89384 -267.894562) (xy 374.893408 -267.884496) (xy 374.885678 -267.865907)
			(xy 374.878854 -267.858494) (xy 374.842532 -267.822172) (xy 374.8024 -267.821156) (xy 374.78716 -267.834364)
			(xy 374.766048 -267.8523) (xy 374.718671 -267.880997) (xy 374.666895 -267.900676) (xy 374.612417 -267.910691)
			(xy 374.584722 -267.911326) (xy 374.560727 -267.910881) (xy 374.513328 -267.903378) (xy 374.467686 -267.888551)
			(xy 374.424926 -267.866767) (xy 374.3861 -267.838562) (xy 374.352164 -267.804631) (xy 374.323954 -267.765808)
			(xy 374.302164 -267.723051) (xy 374.287332 -267.677411) (xy 374.279822 -267.630013) (xy 374.279414 -267.606018)
			(xy 374.279929 -267.581451) (xy 374.287849 -267.532958) (xy 374.295162 -267.509498) (xy 374.298972 -267.497814)
			(xy 374.295416 -267.473684) (xy 374.240044 -267.396722) (xy 374.232381 -267.387303) (xy 374.210768 -267.376313)
			(xy 374.198642 -267.37564) (xy 373.090948 -267.37564) (xy 373.078808 -267.376255) (xy 373.057175 -267.38726)
			(xy 373.049546 -267.396722) (xy 372.994174 -267.473684) (xy 372.990618 -267.497814) (xy 372.994428 -267.509498)
			(xy 373.001748 -267.532955) (xy 373.009658 -267.58145) (xy 373.010176 -267.606018) (xy 373.009654 -267.631273)
			(xy 373.001341 -267.681095) (xy 372.98494 -267.728869) (xy 372.960899 -267.773292) (xy 372.929875 -267.813152)
			(xy 372.892713 -267.847362) (xy 372.850427 -267.874988) (xy 372.804171 -267.895278) (xy 372.755206 -267.907678)
			(xy 372.704868 -267.911849) (xy 372.65453 -267.907678) (xy 372.605565 -267.895278) (xy 372.559309 -267.874988)
			(xy 372.517023 -267.847362) (xy 372.479861 -267.813152) (xy 372.448837 -267.773292) (xy 372.424796 -267.728869)
			(xy 372.408395 -267.681095) (xy 372.400082 -267.631273) (xy 372.39956 -267.606018) (xy 372.400075 -267.581451)
			(xy 372.407994 -267.532957) (xy 372.415308 -267.509498) (xy 372.419118 -267.497814) (xy 372.415562 -267.473684)
			(xy 372.36019 -267.396722) (xy 372.35253 -267.387295) (xy 372.330917 -267.376286) (xy 372.318788 -267.37564)
			(xy 371.21084 -267.37564) (xy 371.198701 -267.376257) (xy 371.177071 -267.387264) (xy 371.169438 -267.396722)
			(xy 371.114066 -267.473684) (xy 371.11051 -267.497814) (xy 371.11432 -267.509498) (xy 371.121638 -267.532956)
			(xy 371.129545 -267.581451) (xy 371.130068 -267.606018) (xy 371.129546 -267.631273) (xy 371.121233 -267.681095)
			(xy 371.104832 -267.728869) (xy 371.080791 -267.773292) (xy 371.049767 -267.813152) (xy 371.012605 -267.847362)
			(xy 370.970319 -267.874988) (xy 370.924063 -267.895278) (xy 370.875098 -267.907678) (xy 370.82476 -267.911849)
			(xy 370.774422 -267.907678) (xy 370.725457 -267.895278) (xy 370.679201 -267.874988) (xy 370.636915 -267.847362)
			(xy 370.599753 -267.813152) (xy 370.568729 -267.773292) (xy 370.544688 -267.728869) (xy 370.528287 -267.681095)
			(xy 370.519974 -267.631273) (xy 370.519452 -267.606018) (xy 370.519967 -267.581451) (xy 370.527886 -267.532957)
			(xy 370.5352 -267.509498) (xy 370.53901 -267.497814) (xy 370.535454 -267.473684) (xy 370.480082 -267.396722)
			(xy 370.472422 -267.387296) (xy 370.450808 -267.376291) (xy 370.43868 -267.37564) (xy 369.330986 -267.37564)
			(xy 369.318853 -267.376269) (xy 369.297243 -267.387289) (xy 369.289584 -267.396722) (xy 369.234212 -267.473684)
			(xy 369.230656 -267.497814) (xy 369.234466 -267.509498) (xy 369.241785 -267.532956) (xy 369.249694 -267.581451)
			(xy 369.250214 -267.606018) (xy 369.249692 -267.631273) (xy 369.241379 -267.681095) (xy 369.224978 -267.728869)
			(xy 369.200937 -267.773292) (xy 369.169913 -267.813152) (xy 369.132751 -267.847362) (xy 369.090465 -267.874988)
			(xy 369.044209 -267.895278) (xy 368.995244 -267.907678) (xy 368.944906 -267.911849) (xy 368.894568 -267.907678)
			(xy 368.845603 -267.895278) (xy 368.799347 -267.874988) (xy 368.757061 -267.847362) (xy 368.719899 -267.813152)
			(xy 368.688875 -267.773292) (xy 368.664834 -267.728869) (xy 368.648433 -267.681095) (xy 368.64012 -267.631273)
			(xy 368.639598 -267.606018) (xy 368.640113 -267.581451) (xy 368.648033 -267.532958) (xy 368.655346 -267.509498)
			(xy 368.659156 -267.497814) (xy 368.6556 -267.473684) (xy 368.600228 -267.396722) (xy 368.592571 -267.387289)
			(xy 368.570958 -267.376264) (xy 368.558826 -267.37564) (xy 367.450878 -267.37564) (xy 367.438746 -267.376271)
			(xy 367.417139 -267.387292) (xy 367.409476 -267.396722) (xy 367.354104 -267.473684) (xy 367.350548 -267.497814)
			(xy 367.354358 -267.509498) (xy 367.361677 -267.532955) (xy 367.369586 -267.581451) (xy 367.370106 -267.606018)
			(xy 367.369584 -267.631273) (xy 367.361271 -267.681095) (xy 367.34487 -267.728869) (xy 367.320829 -267.773292)
			(xy 367.289805 -267.813152) (xy 367.252643 -267.847362) (xy 367.210357 -267.874988) (xy 367.164101 -267.895278)
			(xy 367.115136 -267.907678) (xy 367.064798 -267.911849) (xy 367.01446 -267.907678) (xy 366.965495 -267.895278)
			(xy 366.919239 -267.874988) (xy 366.876953 -267.847362) (xy 366.839791 -267.813152) (xy 366.808767 -267.773292)
			(xy 366.784726 -267.728869) (xy 366.768325 -267.681095) (xy 366.760012 -267.631273) (xy 366.75949 -267.606018)
			(xy 366.760005 -267.581451) (xy 366.767925 -267.532957) (xy 366.775238 -267.509498) (xy 366.779048 -267.497814)
			(xy 366.775492 -267.473684) (xy 366.72012 -267.396722) (xy 366.712462 -267.38729) (xy 366.690849 -267.376269)
			(xy 366.678718 -267.37564) (xy 365.57077 -267.37564) (xy 365.558639 -267.376272) (xy 365.537034 -267.387296)
			(xy 365.529368 -267.396722) (xy 365.473996 -267.473684) (xy 365.47044 -267.497814) (xy 365.47425 -267.509498)
			(xy 365.481569 -267.532955) (xy 365.489479 -267.581451) (xy 365.489998 -267.606018) (xy 365.489476 -267.631273)
			(xy 365.481163 -267.681095) (xy 365.464762 -267.728869) (xy 365.440721 -267.773292) (xy 365.409697 -267.813152)
			(xy 365.372535 -267.847362) (xy 365.330249 -267.874988) (xy 365.283993 -267.895278) (xy 365.235028 -267.907678)
			(xy 365.18469 -267.911849) (xy 365.134352 -267.907678) (xy 365.085387 -267.895278) (xy 365.039131 -267.874988)
			(xy 364.996845 -267.847362) (xy 364.959683 -267.813152) (xy 364.928659 -267.773292) (xy 364.904618 -267.728869)
			(xy 364.888217 -267.681095) (xy 364.879904 -267.631273) (xy 364.879382 -267.606018) (xy 364.879897 -267.581451)
			(xy 364.887816 -267.532957) (xy 364.89513 -267.509498) (xy 364.89894 -267.497814) (xy 364.895384 -267.473684)
			(xy 364.840012 -267.396722) (xy 364.832354 -267.387291) (xy 364.810741 -267.376273) (xy 364.79861 -267.37564)
			(xy 363.690916 -267.37564) (xy 363.67878 -267.376262) (xy 363.657159 -267.387275) (xy 363.649514 -267.396722)
			(xy 363.594142 -267.473684) (xy 363.590586 -267.497814) (xy 363.594396 -267.509498) (xy 363.601714 -267.532956)
			(xy 363.609623 -267.581451) (xy 363.610144 -267.606018) (xy 363.609622 -267.631273) (xy 363.601309 -267.681095)
			(xy 363.584908 -267.728869) (xy 363.560867 -267.773292) (xy 363.529843 -267.813152) (xy 363.492681 -267.847362)
			(xy 363.450395 -267.874988) (xy 363.404139 -267.895278) (xy 363.355174 -267.907678) (xy 363.304836 -267.911849)
			(xy 363.254498 -267.907678) (xy 363.205533 -267.895278) (xy 363.159277 -267.874988) (xy 363.116991 -267.847362)
			(xy 363.079829 -267.813152) (xy 363.048805 -267.773292) (xy 363.024764 -267.728869) (xy 363.008363 -267.681095)
			(xy 363.00005 -267.631273) (xy 362.999528 -267.606018) (xy 363.000043 -267.581451) (xy 363.007961 -267.532957)
			(xy 363.015276 -267.509498) (xy 363.019086 -267.497814) (xy 363.01553 -267.473684) (xy 362.960158 -267.396722)
			(xy 362.952496 -267.3873) (xy 362.930883 -267.376305) (xy 362.918756 -267.37564) (xy 361.810808 -267.37564)
			(xy 361.798673 -267.376264) (xy 361.777054 -267.387279) (xy 361.769406 -267.396722) (xy 361.714034 -267.473684)
			(xy 361.710478 -267.497814) (xy 361.714288 -267.509498) (xy 361.721606 -267.532956) (xy 361.729515 -267.581451)
			(xy 361.730036 -267.606018) (xy 361.729514 -267.631273) (xy 361.721201 -267.681095) (xy 361.7048 -267.728869)
			(xy 361.680759 -267.773292) (xy 361.649735 -267.813152) (xy 361.612573 -267.847362) (xy 361.570287 -267.874988)
			(xy 361.524031 -267.895278) (xy 361.475066 -267.907678) (xy 361.424728 -267.911849) (xy 361.37439 -267.907678)
			(xy 361.325425 -267.895278) (xy 361.279169 -267.874988) (xy 361.236883 -267.847362) (xy 361.199721 -267.813152)
			(xy 361.168697 -267.773292) (xy 361.144656 -267.728869) (xy 361.128255 -267.681095) (xy 361.119942 -267.631273)
			(xy 361.11942 -267.606018) (xy 361.119935 -267.581451) (xy 361.127853 -267.532957) (xy 361.135168 -267.509498)
			(xy 361.138978 -267.497814) (xy 361.135422 -267.473684) (xy 361.08005 -267.396722) (xy 361.072387 -267.387302)
			(xy 361.050774 -267.37631) (xy 361.038648 -267.37564) (xy 360.246676 -267.37564) (xy 360.238484 -267.375954)
			(xy 360.222945 -267.381145) (xy 360.216196 -267.3858) (xy 360.194795 -267.401349) (xy 360.148426 -267.426808)
			(xy 360.098894 -267.445375) (xy 360.047216 -267.456671) (xy 359.994454 -267.460462) (xy 359.941692 -267.456671)
			(xy 359.890014 -267.445375) (xy 359.840482 -267.426808) (xy 359.794113 -267.401349) (xy 359.772712 -267.3858)
			(xy 359.765974 -267.381124) (xy 359.750428 -267.375928) (xy 359.742232 -267.37564) (xy 358.057196 -267.37564)
			(xy 358.045062 -267.376267) (xy 358.023448 -267.387284) (xy 358.015794 -267.396722) (xy 357.960422 -267.473684)
			(xy 357.956866 -267.497814) (xy 357.960676 -267.509498) (xy 357.967995 -267.532956) (xy 357.975904 -267.581451)
			(xy 357.976424 -267.606018) (xy 357.975902 -267.631273) (xy 357.967589 -267.681095) (xy 357.951188 -267.728869)
			(xy 357.927147 -267.773292) (xy 357.896123 -267.813152) (xy 357.858961 -267.847362) (xy 357.816675 -267.874988)
			(xy 357.770419 -267.895278) (xy 357.721454 -267.907678) (xy 357.671116 -267.911849) (xy 357.620778 -267.907678)
			(xy 357.571813 -267.895278) (xy 357.525557 -267.874988) (xy 357.483271 -267.847362) (xy 357.446109 -267.813152)
			(xy 357.415085 -267.773292) (xy 357.391044 -267.728869) (xy 357.374643 -267.681095) (xy 357.36633 -267.631273)
			(xy 357.365808 -267.606018) (xy 357.366323 -267.581451) (xy 357.374243 -267.532958) (xy 357.381556 -267.509498)
			(xy 357.385366 -267.497814) (xy 357.38181 -267.473684) (xy 357.326438 -267.396722) (xy 357.318775 -267.387304)
			(xy 357.297161 -267.376317) (xy 357.285036 -267.37564) (xy 356.177088 -267.37564) (xy 356.164955 -267.376268)
			(xy 356.143344 -267.387288) (xy 356.135686 -267.396722) (xy 356.080314 -267.473684) (xy 356.076758 -267.497814)
			(xy 356.080568 -267.509498) (xy 356.087887 -267.532956) (xy 356.095796 -267.581451) (xy 356.096316 -267.606018)
			(xy 356.095794 -267.631273) (xy 356.087481 -267.681095) (xy 356.07108 -267.728869) (xy 356.047039 -267.773292)
			(xy 356.016015 -267.813152) (xy 355.978853 -267.847362) (xy 355.936567 -267.874988) (xy 355.890311 -267.895278)
			(xy 355.841346 -267.907678) (xy 355.791008 -267.911849) (xy 355.74067 -267.907678) (xy 355.691705 -267.895278)
			(xy 355.645449 -267.874988) (xy 355.603163 -267.847362) (xy 355.566001 -267.813152) (xy 355.534977 -267.773292)
			(xy 355.510936 -267.728869) (xy 355.494535 -267.681095) (xy 355.486222 -267.631273) (xy 355.4857 -267.606018)
			(xy 355.486215 -267.581451) (xy 355.494135 -267.532958) (xy 355.501448 -267.509498) (xy 355.505258 -267.497814)
			(xy 355.501702 -267.473684) (xy 355.44633 -267.396722) (xy 355.438673 -267.387288) (xy 355.41706 -267.376263)
			(xy 355.404928 -267.37564) (xy 354.297234 -267.37564) (xy 354.285096 -267.376258) (xy 354.263468 -267.387267)
			(xy 354.255832 -267.396722) (xy 354.20046 -267.473684) (xy 354.196904 -267.497814) (xy 354.200714 -267.509498)
			(xy 354.208032 -267.532956) (xy 354.21594 -267.581451) (xy 354.216462 -267.606018) (xy 354.21594 -267.631273)
			(xy 354.207627 -267.681095) (xy 354.191226 -267.728869) (xy 354.167185 -267.773292) (xy 354.136161 -267.813152)
			(xy 354.098999 -267.847362) (xy 354.056713 -267.874988) (xy 354.010457 -267.895278) (xy 353.961492 -267.907678)
			(xy 353.911154 -267.911849) (xy 353.860816 -267.907678) (xy 353.811851 -267.895278) (xy 353.765595 -267.874988)
			(xy 353.723309 -267.847362) (xy 353.686147 -267.813152) (xy 353.655123 -267.773292) (xy 353.631082 -267.728869)
			(xy 353.614681 -267.681095) (xy 353.606368 -267.631273) (xy 353.605846 -267.606018) (xy 353.606361 -267.581451)
			(xy 353.614279 -267.532957) (xy 353.621594 -267.509498) (xy 353.625404 -267.497814) (xy 353.621848 -267.473684)
			(xy 353.566476 -267.396722) (xy 353.558815 -267.387297) (xy 353.537202 -267.376295) (xy 353.525074 -267.37564)
			(xy 352.417126 -267.37564) (xy 352.404989 -267.37626) (xy 352.383364 -267.38727) (xy 352.375724 -267.396722)
			(xy 352.320352 -267.473684) (xy 352.316796 -267.497814) (xy 352.320606 -267.509498) (xy 352.327924 -267.532956)
			(xy 352.335832 -267.581451) (xy 352.336354 -267.606018) (xy 352.335832 -267.631273) (xy 352.327519 -267.681095)
			(xy 352.311118 -267.728869) (xy 352.287077 -267.773292) (xy 352.256053 -267.813152) (xy 352.218891 -267.847362)
			(xy 352.176605 -267.874988) (xy 352.130349 -267.895278) (xy 352.081384 -267.907678) (xy 352.031046 -267.911849)
			(xy 351.980708 -267.907678) (xy 351.931743 -267.895278) (xy 351.885487 -267.874988) (xy 351.843201 -267.847362)
			(xy 351.806039 -267.813152) (xy 351.775015 -267.773292) (xy 351.750974 -267.728869) (xy 351.734573 -267.681095)
			(xy 351.72626 -267.631273) (xy 351.725738 -267.606018) (xy 351.726253 -267.581451) (xy 351.734171 -267.532957)
			(xy 351.741486 -267.509498) (xy 351.745296 -267.497814) (xy 351.74174 -267.473684) (xy 351.686368 -267.396722)
			(xy 351.678707 -267.387299) (xy 351.657093 -267.376299) (xy 351.644966 -267.37564) (xy 350.537272 -267.37564)
			(xy 350.525141 -267.376272) (xy 350.503535 -267.387295) (xy 350.49587 -267.396722) (xy 350.440498 -267.473684)
			(xy 350.436942 -267.497814) (xy 350.440752 -267.509498) (xy 350.448071 -267.532955) (xy 350.455981 -267.581451)
			(xy 350.4565 -267.606018) (xy 350.455978 -267.631273) (xy 350.447665 -267.681095) (xy 350.431264 -267.728869)
			(xy 350.407223 -267.773292) (xy 350.376199 -267.813152) (xy 350.339037 -267.847362) (xy 350.296751 -267.874988)
			(xy 350.250495 -267.895278) (xy 350.20153 -267.907678) (xy 350.151192 -267.911849) (xy 350.100854 -267.907678)
			(xy 350.051889 -267.895278) (xy 350.005633 -267.874988) (xy 349.963347 -267.847362) (xy 349.926185 -267.813152)
			(xy 349.895161 -267.773292) (xy 349.87112 -267.728869) (xy 349.854719 -267.681095) (xy 349.846406 -267.631273)
			(xy 349.845884 -267.606018) (xy 349.846399 -267.581451) (xy 349.854318 -267.532957) (xy 349.861632 -267.509498)
			(xy 349.865442 -267.497814) (xy 349.861886 -267.473684) (xy 349.806514 -267.396722) (xy 349.798856 -267.387291)
			(xy 349.777243 -267.376272) (xy 349.765112 -267.37564) (xy 348.791022 -267.37564) (xy 348.780959 -267.376079)
			(xy 348.762379 -267.383817) (xy 348.754954 -267.390626) (xy 348.58325 -267.56233) (xy 348.57563 -267.581888)
			(xy 348.576138 -267.59281) (xy 348.576392 -267.606018) (xy 348.57592 -267.630008) (xy 348.568412 -267.677396)
			(xy 348.553582 -267.723027) (xy 348.531798 -267.765776) (xy 348.503594 -267.804591) (xy 348.469665 -267.838516)
			(xy 348.430847 -267.866715) (xy 348.388096 -267.888495) (xy 348.342463 -267.90332) (xy 348.295074 -267.910823)
			(xy 348.271084 -267.911326) (xy 348.257876 -267.911072) (xy 348.246954 -267.910564) (xy 348.227396 -267.918184)
			(xy 348.14002 -268.00556) (xy 359.650541 -268.00556) (xy 359.654571 -267.953062) (xy 359.666568 -267.901794)
			(xy 359.686251 -267.852959) (xy 359.713157 -267.8077) (xy 359.746657 -267.767079) (xy 359.785965 -267.732048)
			(xy 359.83016 -267.703428) (xy 359.878205 -267.681889) (xy 359.928976 -267.667937) (xy 359.981281 -267.661899)
			(xy 360.033895 -267.663916) (xy 360.085585 -267.67394) (xy 360.135138 -267.691738) (xy 360.181394 -267.716891)
			(xy 360.223268 -267.74881) (xy 360.25978 -267.786748) (xy 360.290072 -267.829814) (xy 360.313435 -267.876999)
			(xy 360.329321 -267.927198) (xy 360.337358 -267.979234) (xy 360.337862 -268.00556) (xy 360.337358 -268.031886)
			(xy 360.329321 -268.083922) (xy 360.313435 -268.134121) (xy 360.290072 -268.181306) (xy 360.25978 -268.224372)
			(xy 360.223268 -268.26231) (xy 360.181394 -268.294229) (xy 360.135138 -268.319382) (xy 360.085585 -268.33718)
			(xy 360.033895 -268.347204) (xy 359.981281 -268.349221) (xy 359.928976 -268.343183) (xy 359.878205 -268.329231)
			(xy 359.83016 -268.307692) (xy 359.785965 -268.279072) (xy 359.746657 -268.244041) (xy 359.713157 -268.20342)
			(xy 359.686251 -268.158161) (xy 359.666568 -268.109326) (xy 359.654571 -268.058058) (xy 359.650541 -268.00556)
			(xy 348.14002 -268.00556) (xy 348.03207 -268.11351) (xy 348.025254 -268.120853) (xy 348.017514 -268.139316)
			(xy 348.017084 -268.149324) (xy 348.017084 -268.180058) (xy 348.017434 -268.189317) (xy 348.023944 -268.206648)
			(xy 348.029784 -268.21384) (xy 348.047673 -268.234936) (xy 348.07629 -268.282263) (xy 348.095909 -268.333973)
			(xy 348.105889 -268.388371) (xy 348.106492 -268.416024) (xy 349.375234 -268.416024) (xy 349.379194 -268.36697)
			(xy 349.390971 -268.319186) (xy 349.410262 -268.27391) (xy 349.436565 -268.232314) (xy 349.4692 -268.195477)
			(xy 349.507321 -268.164352) (xy 349.549942 -268.139745) (xy 349.595958 -268.122293) (xy 349.644177 -268.112449)
			(xy 349.693352 -268.110468) (xy 349.742207 -268.1164) (xy 349.789478 -268.130092) (xy 349.83394 -268.15119)
			(xy 349.874443 -268.179146) (xy 349.909936 -268.213238) (xy 349.939501 -268.252582) (xy 349.962372 -268.296159)
			(xy 349.977956 -268.34284) (xy 349.985851 -268.391417) (xy 349.986346 -268.416024) (xy 351.255342 -268.416024)
			(xy 351.259302 -268.36697) (xy 351.271079 -268.319186) (xy 351.29037 -268.27391) (xy 351.316673 -268.232314)
			(xy 351.349308 -268.195477) (xy 351.387429 -268.164352) (xy 351.43005 -268.139745) (xy 351.476066 -268.122293)
			(xy 351.524285 -268.112449) (xy 351.57346 -268.110468) (xy 351.622315 -268.1164) (xy 351.669586 -268.130092)
			(xy 351.714048 -268.15119) (xy 351.754551 -268.179146) (xy 351.790044 -268.213238) (xy 351.819609 -268.252582)
			(xy 351.84248 -268.296159) (xy 351.858064 -268.34284) (xy 351.865959 -268.391417) (xy 351.866454 -268.416024)
			(xy 353.135196 -268.416024) (xy 353.139156 -268.36697) (xy 353.150933 -268.319186) (xy 353.170224 -268.27391)
			(xy 353.196527 -268.232314) (xy 353.229162 -268.195477) (xy 353.267283 -268.164352) (xy 353.309904 -268.139745)
			(xy 353.35592 -268.122293) (xy 353.404139 -268.112449) (xy 353.453314 -268.110468) (xy 353.502169 -268.1164)
			(xy 353.54944 -268.130092) (xy 353.593902 -268.15119) (xy 353.634405 -268.179146) (xy 353.669898 -268.213238)
			(xy 353.699463 -268.252582) (xy 353.722334 -268.296159) (xy 353.737918 -268.34284) (xy 353.745813 -268.391417)
			(xy 353.746308 -268.416024) (xy 355.015304 -268.416024) (xy 355.019264 -268.36697) (xy 355.031041 -268.319186)
			(xy 355.050332 -268.27391) (xy 355.076635 -268.232314) (xy 355.10927 -268.195477) (xy 355.147391 -268.164352)
			(xy 355.190012 -268.139745) (xy 355.236028 -268.122293) (xy 355.284247 -268.112449) (xy 355.333422 -268.110468)
			(xy 355.382277 -268.1164) (xy 355.429548 -268.130092) (xy 355.47401 -268.15119) (xy 355.514513 -268.179146)
			(xy 355.550006 -268.213238) (xy 355.579571 -268.252582) (xy 355.602442 -268.296159) (xy 355.618026 -268.34284)
			(xy 355.625921 -268.391417) (xy 355.626416 -268.416024) (xy 356.895412 -268.416024) (xy 356.899372 -268.36697)
			(xy 356.911149 -268.319186) (xy 356.93044 -268.27391) (xy 356.956743 -268.232314) (xy 356.989378 -268.195477)
			(xy 357.027499 -268.164352) (xy 357.07012 -268.139745) (xy 357.116136 -268.122293) (xy 357.164355 -268.112449)
			(xy 357.21353 -268.110468) (xy 357.262385 -268.1164) (xy 357.309656 -268.130092) (xy 357.354118 -268.15119)
			(xy 357.394621 -268.179146) (xy 357.430114 -268.213238) (xy 357.459679 -268.252582) (xy 357.48255 -268.296159)
			(xy 357.498134 -268.34284) (xy 357.506029 -268.391417) (xy 357.506524 -268.416024) (xy 357.506029 -268.440631)
			(xy 357.498134 -268.489208) (xy 357.48255 -268.535889) (xy 357.459679 -268.579466) (xy 357.430114 -268.61881)
			(xy 357.394621 -268.652902) (xy 357.354118 -268.680858) (xy 357.309656 -268.701956) (xy 357.262385 -268.715648)
			(xy 357.21353 -268.72158) (xy 357.164355 -268.719599) (xy 357.116136 -268.709755) (xy 357.07012 -268.692303)
			(xy 357.027499 -268.667696) (xy 356.989378 -268.636571) (xy 356.956743 -268.599734) (xy 356.93044 -268.558138)
			(xy 356.911149 -268.512862) (xy 356.899372 -268.465078) (xy 356.895412 -268.416024) (xy 355.626416 -268.416024)
			(xy 355.625921 -268.440631) (xy 355.618026 -268.489208) (xy 355.602442 -268.535889) (xy 355.579571 -268.579466)
			(xy 355.550006 -268.61881) (xy 355.514513 -268.652902) (xy 355.47401 -268.680858) (xy 355.429548 -268.701956)
			(xy 355.382277 -268.715648) (xy 355.333422 -268.72158) (xy 355.284247 -268.719599) (xy 355.236028 -268.709755)
			(xy 355.190012 -268.692303) (xy 355.147391 -268.667696) (xy 355.10927 -268.636571) (xy 355.076635 -268.599734)
			(xy 355.050332 -268.558138) (xy 355.031041 -268.512862) (xy 355.019264 -268.465078) (xy 355.015304 -268.416024)
			(xy 353.746308 -268.416024) (xy 353.745813 -268.440631) (xy 353.737918 -268.489208) (xy 353.722334 -268.535889)
			(xy 353.699463 -268.579466) (xy 353.669898 -268.61881) (xy 353.634405 -268.652902) (xy 353.593902 -268.680858)
			(xy 353.54944 -268.701956) (xy 353.502169 -268.715648) (xy 353.453314 -268.72158) (xy 353.404139 -268.719599)
			(xy 353.35592 -268.709755) (xy 353.309904 -268.692303) (xy 353.267283 -268.667696) (xy 353.229162 -268.636571)
			(xy 353.196527 -268.599734) (xy 353.170224 -268.558138) (xy 353.150933 -268.512862) (xy 353.139156 -268.465078)
			(xy 353.135196 -268.416024) (xy 351.866454 -268.416024) (xy 351.865959 -268.440631) (xy 351.858064 -268.489208)
			(xy 351.84248 -268.535889) (xy 351.819609 -268.579466) (xy 351.790044 -268.61881) (xy 351.754551 -268.652902)
			(xy 351.714048 -268.680858) (xy 351.669586 -268.701956) (xy 351.622315 -268.715648) (xy 351.57346 -268.72158)
			(xy 351.524285 -268.719599) (xy 351.476066 -268.709755) (xy 351.43005 -268.692303) (xy 351.387429 -268.667696)
			(xy 351.349308 -268.636571) (xy 351.316673 -268.599734) (xy 351.29037 -268.558138) (xy 351.271079 -268.512862)
			(xy 351.259302 -268.465078) (xy 351.255342 -268.416024) (xy 349.986346 -268.416024) (xy 349.985851 -268.440631)
			(xy 349.977956 -268.489208) (xy 349.962372 -268.535889) (xy 349.939501 -268.579466) (xy 349.909936 -268.61881)
			(xy 349.874443 -268.652902) (xy 349.83394 -268.680858) (xy 349.789478 -268.701956) (xy 349.742207 -268.715648)
			(xy 349.693352 -268.72158) (xy 349.644177 -268.719599) (xy 349.595958 -268.709755) (xy 349.549942 -268.692303)
			(xy 349.507321 -268.667696) (xy 349.4692 -268.636571) (xy 349.436565 -268.599734) (xy 349.410262 -268.558138)
			(xy 349.390971 -268.512862) (xy 349.379194 -268.465078) (xy 349.375234 -268.416024) (xy 348.106492 -268.416024)
			(xy 348.10597 -268.441279) (xy 348.097657 -268.491101) (xy 348.081256 -268.538875) (xy 348.057215 -268.583298)
			(xy 348.026191 -268.623158) (xy 347.989029 -268.657368) (xy 347.946743 -268.684994) (xy 347.900487 -268.705284)
			(xy 347.851522 -268.717684) (xy 347.801184 -268.721855) (xy 347.750846 -268.717684) (xy 347.701881 -268.705284)
			(xy 347.655625 -268.684994) (xy 347.613339 -268.657368) (xy 347.576177 -268.623158) (xy 347.545153 -268.583298)
			(xy 347.521112 -268.538875) (xy 347.504711 -268.491101) (xy 347.496398 -268.441279) (xy 347.495876 -268.416024)
			(xy 347.496142 -268.3984) (xy 347.500216 -268.363388) (xy 347.504004 -268.346174) (xy 347.506544 -268.334744)
			(xy 347.501718 -268.312392) (xy 347.444822 -268.240764) (xy 347.437244 -268.232051) (xy 347.416479 -268.222002)
			(xy 347.404944 -268.22146) (xy 346.317316 -268.22146) (xy 346.305781 -268.222001) (xy 346.285013 -268.232048)
			(xy 346.277438 -268.240764) (xy 346.220542 -268.312392) (xy 346.215716 -268.334744) (xy 346.218256 -268.346174)
			(xy 346.222061 -268.363385) (xy 346.226135 -268.398399) (xy 346.226384 -268.416024) (xy 346.225912 -268.440013)
			(xy 346.218402 -268.487401) (xy 346.203573 -268.53303) (xy 346.181787 -268.575778) (xy 346.153583 -268.614591)
			(xy 346.119654 -268.648514) (xy 346.080837 -268.676712) (xy 346.038086 -268.698491) (xy 345.992454 -268.713314)
			(xy 345.945065 -268.720815) (xy 345.921076 -268.721332) (xy 345.897235 -268.720879) (xy 345.850132 -268.713473)
			(xy 345.804754 -268.698832) (xy 345.762206 -268.67731) (xy 345.723523 -268.649431) (xy 345.689648 -268.615875)
			(xy 345.661405 -268.577458) (xy 345.650058 -268.556486) (xy 345.64447 -268.545564) (xy 345.624912 -268.531594)
			(xy 345.531694 -268.51737) (xy 345.519746 -268.516153) (xy 345.496939 -268.523569) (xy 345.488006 -268.531594)
			(xy 345.002866 -269.016734) (xy 344.996018 -269.024131) (xy 344.988285 -269.04273) (xy 344.98788 -269.052802)
			(xy 344.98788 -269.252954) (xy 345.092782 -269.357856) (xy 345.092782 -269.367) (xy 345.13393 -269.408148)
			(xy 346.911422 -269.408148) (xy 346.911422 -269.405354) (xy 346.993718 -269.323058) (xy 346.993718 -269.07236)
			(xy 347.158564 -268.907514) (xy 347.48851 -268.907514) (xy 347.961204 -269.380208) (xy 349.52813 -269.380208)
			(xy 350.022922 -268.885416) (xy 350.081596 -268.885416) (xy 350.105218 -268.885416) (xy 350.337628 -268.885416)
			(xy 350.678242 -269.22603) (xy 352.665296 -269.22603) (xy 352.669256 -269.176976) (xy 352.681033 -269.129192)
			(xy 352.700324 -269.083916) (xy 352.726627 -269.04232) (xy 352.759262 -269.005483) (xy 352.797383 -268.974358)
			(xy 352.840004 -268.949751) (xy 352.88602 -268.932299) (xy 352.934239 -268.922455) (xy 352.983414 -268.920474)
			(xy 353.032269 -268.926406) (xy 353.07954 -268.940098) (xy 353.124002 -268.961196) (xy 353.164505 -268.989152)
			(xy 353.199998 -269.023244) (xy 353.229563 -269.062588) (xy 353.252434 -269.106165) (xy 353.268018 -269.152846)
			(xy 353.275913 -269.201423) (xy 353.276408 -269.22603) (xy 355.485204 -269.22603) (xy 355.489164 -269.176976)
			(xy 355.500941 -269.129192) (xy 355.520232 -269.083916) (xy 355.546535 -269.04232) (xy 355.57917 -269.005483)
			(xy 355.617291 -268.974358) (xy 355.659912 -268.949751) (xy 355.705928 -268.932299) (xy 355.754147 -268.922455)
			(xy 355.803322 -268.920474) (xy 355.852177 -268.926406) (xy 355.899448 -268.940098) (xy 355.94391 -268.961196)
			(xy 355.984413 -268.989152) (xy 356.019906 -269.023244) (xy 356.049471 -269.062588) (xy 356.072342 -269.106165)
			(xy 356.087926 -269.152846) (xy 356.095821 -269.201423) (xy 356.096316 -269.22603) (xy 356.095821 -269.250637)
			(xy 356.087926 -269.299214) (xy 356.072342 -269.345895) (xy 356.049471 -269.389472) (xy 356.019906 -269.428816)
			(xy 355.984413 -269.462908) (xy 355.94391 -269.490864) (xy 355.899448 -269.511962) (xy 355.852177 -269.525654)
			(xy 355.803322 -269.531586) (xy 355.754147 -269.529605) (xy 355.705928 -269.519761) (xy 355.659912 -269.502309)
			(xy 355.617291 -269.477702) (xy 355.57917 -269.446577) (xy 355.546535 -269.40974) (xy 355.520232 -269.368144)
			(xy 355.500941 -269.322868) (xy 355.489164 -269.275084) (xy 355.485204 -269.22603) (xy 353.276408 -269.22603)
			(xy 353.275913 -269.250637) (xy 353.268018 -269.299214) (xy 353.252434 -269.345895) (xy 353.229563 -269.389472)
			(xy 353.199998 -269.428816) (xy 353.164505 -269.462908) (xy 353.124002 -269.490864) (xy 353.07954 -269.511962)
			(xy 353.032269 -269.525654) (xy 352.983414 -269.531586) (xy 352.934239 -269.529605) (xy 352.88602 -269.519761)
			(xy 352.840004 -269.502309) (xy 352.797383 -269.477702) (xy 352.759262 -269.446577) (xy 352.726627 -269.40974)
			(xy 352.700324 -269.368144) (xy 352.681033 -269.322868) (xy 352.669256 -269.275084) (xy 352.665296 -269.22603)
			(xy 350.678242 -269.22603) (xy 351.085404 -269.633192) (xy 356.041452 -269.633192)
		)
		(stroke
			(width 0)
			(type solid)
		)
		(fill yes)
		(layer "In13.Cu")
		(net "PVDDCR_CPU1_P0")
	)
	(gr_poly
		(pts
			(xy 12.861036 -331.919072) (xy 12.870911 -331.918608) (xy 12.889203 -331.911157) (xy 12.896596 -331.904594)
			(xy 12.89685 -331.90434) (xy 13.296646 -331.504544) (xy 13.297154 -331.504036) (xy 13.303735 -331.496654)
			(xy 13.311181 -331.478355) (xy 13.311632 -331.468476) (xy 13.311632 -187.3885) (xy 13.312056 -187.37843)
			(xy 13.319774 -187.359829) (xy 13.326618 -187.352432) (xy 25.22474 -175.45431) (xy 25.23214 -175.447469)
			(xy 25.250738 -175.439747) (xy 25.260808 -175.439324) (xy 40.583104 -175.439324) (xy 40.593174 -175.438901)
			(xy 40.61178 -175.431188) (xy 40.619172 -175.424338) (xy 40.633142 -175.410114) (xy 40.640542 -175.403273)
			(xy 40.65914 -175.395551) (xy 40.66921 -175.395128) (xy 40.669464 -175.395128) (xy 43.375834 -172.688758)
			(xy 43.382692 -172.663358) (xy 43.37939 -172.65015) (xy 43.372026 -172.61924) (xy 43.364129 -172.556191)
			(xy 43.363642 -172.52442) (xy 43.364104 -172.493687) (xy 43.371511 -172.432669) (xy 43.386217 -172.372989)
			(xy 43.40801 -172.315516) (xy 43.436572 -172.261089) (xy 43.471485 -172.210502) (xy 43.512242 -172.164491)
			(xy 43.558247 -172.123729) (xy 43.608829 -172.088808) (xy 43.663252 -172.060239) (xy 43.720722 -172.038438)
			(xy 43.7804 -172.023723) (xy 43.841417 -172.016309) (xy 43.87215 -172.015912) (xy 43.903922 -172.016385)
			(xy 43.966973 -172.024282) (xy 43.99788 -172.03166) (xy 44.011088 -172.034962) (xy 44.036488 -172.028104)
			(xy 53.144674 -162.919918) (xy 53.152076 -162.913081) (xy 53.170674 -162.905371) (xy 53.180742 -162.904932)
			(xy 57.946036 -162.904932) (xy 57.955912 -162.90447) (xy 57.974209 -162.897025) (xy 57.981596 -162.890454)
			(xy 57.98185 -162.8902) (xy 58.3311 -162.54095) (xy 58.331608 -162.540442) (xy 58.338194 -162.533063)
			(xy 58.34565 -162.514763) (xy 58.346086 -162.504882) (xy 58.346086 -160.25114) (xy 58.3438 -160.2486)
			(xy 58.3438 -147.346924) (xy 58.346848 -147.343876) (xy 58.346848 -144.655286) (xy 58.346421 -144.645218)
			(xy 58.338697 -144.626622) (xy 58.331862 -144.619218) (xy 58.08726 -144.374616) (xy 58.07986 -144.367774)
			(xy 58.061262 -144.360052) (xy 58.051192 -144.35963) (xy 37.59581 -144.35963) (xy 37.58574 -144.360052)
			(xy 37.567135 -144.367767) (xy 37.559742 -144.374616) (xy 36.72967 -145.204688) (xy 36.722814 -145.212082)
			(xy 36.715064 -145.230681) (xy 36.714684 -145.240756) (xy 36.714684 -148.08835) (xy 36.715116 -148.098417)
			(xy 36.722841 -148.117009) (xy 36.72967 -148.124418) (xy 36.733226 -148.127974) (xy 36.726368 -148.134578)
			(xy 36.71824 -148.153628) (xy 36.71824 -151.201454) (xy 50.610451 -151.201454) (xy 50.610451 -151.146946)
			(xy 50.618209 -151.092993) (xy 50.633566 -151.040694) (xy 50.65621 -150.991112) (xy 50.68568 -150.945258)
			(xy 50.721375 -150.904064) (xy 50.76257 -150.86837) (xy 50.808426 -150.838902) (xy 50.858009 -150.81626)
			(xy 50.910309 -150.800905) (xy 50.964262 -150.79315) (xy 50.991516 -150.792688) (xy 51.020432 -150.793233)
			(xy 51.077604 -150.801952) (xy 51.132803 -150.819202) (xy 51.184766 -150.844589) (xy 51.2323 -150.877529)
			(xy 51.274316 -150.917269) (xy 51.292506 -150.939754) (xy 51.30006 -150.948523) (xy 51.320825 -150.958701)
			(xy 51.332384 -150.959312) (xy 51.412648 -150.959312) (xy 51.424211 -150.958708) (xy 51.444983 -150.948537)
			(xy 51.452526 -150.939754) (xy 51.470691 -150.917248) (xy 51.512717 -150.877517) (xy 51.560258 -150.844582)
			(xy 51.612224 -150.819198) (xy 51.667426 -150.801946) (xy 51.724599 -150.793221) (xy 51.753516 -150.792688)
			(xy 51.780766 -150.793183) (xy 51.834712 -150.800941) (xy 51.887004 -150.816297) (xy 51.936579 -150.838939)
			(xy 51.982427 -150.868406) (xy 52.023614 -150.904097) (xy 52.059304 -150.945286) (xy 52.088768 -150.991135)
			(xy 52.111408 -151.040711) (xy 52.126762 -151.093004) (xy 52.134518 -151.14695) (xy 52.134518 -151.20145)
			(xy 52.126762 -151.255396) (xy 52.111408 -151.307689) (xy 52.088768 -151.357265) (xy 52.059304 -151.403114)
			(xy 52.023614 -151.444303) (xy 51.982427 -151.479994) (xy 51.936579 -151.509461) (xy 51.887004 -151.532103)
			(xy 51.834712 -151.547459) (xy 51.780766 -151.555217) (xy 51.753516 -151.555704) (xy 51.724598 -151.555211)
			(xy 51.667424 -151.546482) (xy 51.612223 -151.529221) (xy 51.56026 -151.503825) (xy 51.512727 -151.470875)
			(xy 51.470714 -151.431127) (xy 51.452526 -151.408638) (xy 51.444959 -151.399882) (xy 51.424204 -151.389698)
			(xy 51.412648 -151.38908) (xy 51.332384 -151.38908) (xy 51.320816 -151.389648) (xy 51.300046 -151.399845)
			(xy 51.292506 -151.408638) (xy 51.274321 -151.431127) (xy 51.232299 -151.47086) (xy 51.184762 -151.503797)
			(xy 51.1328 -151.529184) (xy 51.077602 -151.54644) (xy 51.020432 -151.555169) (xy 50.991516 -151.555704)
			(xy 50.964262 -151.55525) (xy 50.910309 -151.547495) (xy 50.858009 -151.53214) (xy 50.808426 -151.509498)
			(xy 50.76257 -151.48003) (xy 50.721375 -151.444336) (xy 50.68568 -151.403142) (xy 50.65621 -151.357288)
			(xy 50.633566 -151.307706) (xy 50.618209 -151.255407) (xy 50.610451 -151.201454) (xy 36.71824 -151.201454)
			(xy 36.71824 -153.258854) (xy 50.610451 -153.258854) (xy 50.610451 -153.204346) (xy 50.618209 -153.150393)
			(xy 50.633566 -153.098094) (xy 50.65621 -153.048512) (xy 50.68568 -153.002658) (xy 50.721375 -152.961464)
			(xy 50.76257 -152.92577) (xy 50.808426 -152.896302) (xy 50.858009 -152.87366) (xy 50.910309 -152.858305)
			(xy 50.964262 -152.85055) (xy 50.991516 -152.850088) (xy 51.020432 -152.850633) (xy 51.077604 -152.859352)
			(xy 51.132803 -152.876602) (xy 51.184766 -152.901989) (xy 51.2323 -152.934929) (xy 51.274316 -152.974669)
			(xy 51.292506 -152.997154) (xy 51.30006 -153.005923) (xy 51.320825 -153.016101) (xy 51.332384 -153.016712)
			(xy 51.412648 -153.016712) (xy 51.424211 -153.016108) (xy 51.444983 -153.005937) (xy 51.452526 -152.997154)
			(xy 51.470691 -152.974648) (xy 51.512717 -152.934917) (xy 51.560258 -152.901982) (xy 51.612224 -152.876598)
			(xy 51.667426 -152.859346) (xy 51.724599 -152.850621) (xy 51.753516 -152.850088) (xy 51.780766 -152.850583)
			(xy 51.834712 -152.858341) (xy 51.887004 -152.873697) (xy 51.936579 -152.896339) (xy 51.982427 -152.925806)
			(xy 52.023614 -152.961497) (xy 52.059304 -153.002686) (xy 52.088768 -153.048535) (xy 52.111408 -153.098111)
			(xy 52.126762 -153.150404) (xy 52.134518 -153.20435) (xy 52.134518 -153.25885) (xy 52.126762 -153.312796)
			(xy 52.111408 -153.365089) (xy 52.088768 -153.414665) (xy 52.059304 -153.460514) (xy 52.023614 -153.501703)
			(xy 51.982427 -153.537394) (xy 51.936579 -153.566861) (xy 51.887004 -153.589503) (xy 51.834712 -153.604859)
			(xy 51.780766 -153.612617) (xy 51.753516 -153.613104) (xy 51.724598 -153.612611) (xy 51.667424 -153.603882)
			(xy 51.612223 -153.586621) (xy 51.56026 -153.561225) (xy 51.512727 -153.528275) (xy 51.470714 -153.488527)
			(xy 51.452526 -153.466038) (xy 51.444959 -153.457282) (xy 51.424204 -153.447098) (xy 51.412648 -153.44648)
			(xy 51.332384 -153.44648) (xy 51.320816 -153.447048) (xy 51.300046 -153.457245) (xy 51.292506 -153.466038)
			(xy 51.274321 -153.488527) (xy 51.232299 -153.52826) (xy 51.184762 -153.561197) (xy 51.1328 -153.586584)
			(xy 51.077602 -153.60384) (xy 51.020432 -153.612569) (xy 50.991516 -153.613104) (xy 50.964262 -153.61265)
			(xy 50.910309 -153.604895) (xy 50.858009 -153.58954) (xy 50.808426 -153.566898) (xy 50.76257 -153.53743)
			(xy 50.721375 -153.501736) (xy 50.68568 -153.460542) (xy 50.65621 -153.414688) (xy 50.633566 -153.365106)
			(xy 50.618209 -153.312807) (xy 50.610451 -153.258854) (xy 36.71824 -153.258854) (xy 36.71824 -156.788358)
			(xy 36.717805 -156.798422) (xy 36.710069 -156.817006) (xy 36.703254 -156.824426) (xy 35.414649 -158.113051)
			(xy 50.521868 -158.113051) (xy 50.521868 -158.058549) (xy 50.529624 -158.004603) (xy 50.544978 -157.952309)
			(xy 50.567617 -157.902733) (xy 50.597081 -157.856882) (xy 50.632771 -157.815692) (xy 50.673958 -157.779999)
			(xy 50.719806 -157.750532) (xy 50.769381 -157.727888) (xy 50.821674 -157.71253) (xy 50.875619 -157.70477)
			(xy 50.90287 -157.704282) (xy 50.930128 -157.704768) (xy 50.984087 -157.712532) (xy 51.036394 -157.727892)
			(xy 51.085985 -157.750535) (xy 51.13185 -157.780001) (xy 51.173059 -157.815691) (xy 51.208772 -157.85688)
			(xy 51.223926 -157.879542) (xy 51.228744 -157.886536) (xy 51.242068 -157.897053) (xy 51.25811 -157.902603)
			(xy 51.266598 -157.90291) (xy 51.351942 -157.90291) (xy 51.360422 -157.902595) (xy 51.376436 -157.897002)
			(xy 51.38976 -157.886504) (xy 51.394614 -157.879542) (xy 51.409767 -157.85688) (xy 51.44548 -157.815693)
			(xy 51.486688 -157.780005) (xy 51.532555 -157.750542) (xy 51.582146 -157.727905) (xy 51.634454 -157.712552)
			(xy 51.688413 -157.704797) (xy 51.742927 -157.704797) (xy 51.796886 -157.712552) (xy 51.849194 -157.727905)
			(xy 51.898785 -157.750542) (xy 51.944652 -157.780005) (xy 51.98586 -157.815693) (xy 52.021573 -157.85688)
			(xy 52.036726 -157.879542) (xy 52.041544 -157.886536) (xy 52.054868 -157.897053) (xy 52.07091 -157.902603)
			(xy 52.079398 -157.90291) (xy 52.164742 -157.90291) (xy 52.173222 -157.902595) (xy 52.189236 -157.897002)
			(xy 52.20256 -157.886504) (xy 52.207414 -157.879542) (xy 52.222528 -157.856849) (xy 52.258239 -157.81565)
			(xy 52.299451 -157.779952) (xy 52.345323 -157.750482) (xy 52.394923 -157.727841) (xy 52.447239 -157.71249)
			(xy 52.501209 -157.70474) (xy 52.52847 -157.704282) (xy 52.555724 -157.704763) (xy 52.609676 -157.712517)
			(xy 52.661976 -157.72787) (xy 52.711559 -157.75051) (xy 52.757415 -157.779976) (xy 52.79861 -157.815669)
			(xy 52.834306 -157.856861) (xy 52.863776 -157.902715) (xy 52.88642 -157.952295) (xy 52.901777 -158.004594)
			(xy 52.909535 -158.058547) (xy 52.909535 -158.113054) (xy 52.901777 -158.167006) (xy 52.88642 -158.219305)
			(xy 52.863776 -158.268885) (xy 52.834306 -158.314739) (xy 52.79861 -158.355931) (xy 52.757415 -158.391624)
			(xy 52.711559 -158.42109) (xy 52.661976 -158.44373) (xy 52.609676 -158.459083) (xy 52.555724 -158.466837)
			(xy 52.52847 -158.467298) (xy 52.501213 -158.466822) (xy 52.447254 -158.459052) (xy 52.394948 -158.443688)
			(xy 52.345359 -158.421042) (xy 52.299494 -158.391575) (xy 52.258285 -158.355886) (xy 52.22257 -158.314699)
			(xy 52.207414 -158.292038) (xy 52.202578 -158.285058) (xy 52.189261 -158.27454) (xy 52.173227 -158.268982)
			(xy 52.164742 -158.26867) (xy 52.079398 -158.26867) (xy 52.070921 -158.269021) (xy 52.05491 -158.274599)
			(xy 52.041583 -158.285082) (xy 52.036726 -158.292038) (xy 52.021573 -158.3147) (xy 51.98586 -158.355887)
			(xy 51.944652 -158.391575) (xy 51.898785 -158.421038) (xy 51.849194 -158.443675) (xy 51.796886 -158.459028)
			(xy 51.742927 -158.466783) (xy 51.688413 -158.466783) (xy 51.634454 -158.459028) (xy 51.582146 -158.443675)
			(xy 51.532555 -158.421038) (xy 51.486688 -158.391575) (xy 51.44548 -158.355887) (xy 51.409767 -158.3147)
			(xy 51.394614 -158.292038) (xy 51.389778 -158.285058) (xy 51.376461 -158.27454) (xy 51.360427 -158.268982)
			(xy 51.351942 -158.26867) (xy 51.266598 -158.26867) (xy 51.258121 -158.269021) (xy 51.24211 -158.274599)
			(xy 51.228783 -158.285082) (xy 51.223926 -158.292038) (xy 51.20878 -158.314708) (xy 51.173074 -158.355909)
			(xy 51.131869 -158.391609) (xy 51.086002 -158.421081) (xy 51.036407 -158.443726) (xy 50.984095 -158.459082)
			(xy 50.93013 -158.466837) (xy 50.90287 -158.467298) (xy 50.875619 -158.46683) (xy 50.821674 -158.45907)
			(xy 50.769381 -158.443712) (xy 50.719806 -158.421068) (xy 50.673958 -158.391601) (xy 50.632771 -158.355908)
			(xy 50.597081 -158.314718) (xy 50.567617 -158.268867) (xy 50.544978 -158.219291) (xy 50.529624 -158.166997)
			(xy 50.521868 -158.113051) (xy 35.414649 -158.113051) (xy 32.874687 -160.653051) (xy 50.521868 -160.653051)
			(xy 50.521868 -160.598549) (xy 50.529624 -160.544603) (xy 50.544978 -160.492309) (xy 50.567617 -160.442733)
			(xy 50.597081 -160.396882) (xy 50.632771 -160.355692) (xy 50.673958 -160.319999) (xy 50.719806 -160.290532)
			(xy 50.769381 -160.267888) (xy 50.821674 -160.25253) (xy 50.875619 -160.24477) (xy 50.90287 -160.244282)
			(xy 50.930128 -160.244768) (xy 50.984087 -160.252532) (xy 51.036394 -160.267892) (xy 51.085985 -160.290535)
			(xy 51.13185 -160.320001) (xy 51.173059 -160.355691) (xy 51.208772 -160.39688) (xy 51.223926 -160.419542)
			(xy 51.228744 -160.426536) (xy 51.242068 -160.437053) (xy 51.25811 -160.442603) (xy 51.266598 -160.44291)
			(xy 51.351942 -160.44291) (xy 51.360422 -160.442595) (xy 51.376436 -160.437002) (xy 51.38976 -160.426504)
			(xy 51.394614 -160.419542) (xy 51.409767 -160.39688) (xy 51.44548 -160.355693) (xy 51.486688 -160.320005)
			(xy 51.532555 -160.290542) (xy 51.582146 -160.267905) (xy 51.634454 -160.252552) (xy 51.688413 -160.244797)
			(xy 51.742927 -160.244797) (xy 51.796886 -160.252552) (xy 51.849194 -160.267905) (xy 51.898785 -160.290542)
			(xy 51.944652 -160.320005) (xy 51.98586 -160.355693) (xy 52.021573 -160.39688) (xy 52.036726 -160.419542)
			(xy 52.041544 -160.426536) (xy 52.054868 -160.437053) (xy 52.07091 -160.442603) (xy 52.079398 -160.44291)
			(xy 52.164742 -160.44291) (xy 52.173222 -160.442595) (xy 52.189236 -160.437002) (xy 52.20256 -160.426504)
			(xy 52.207414 -160.419542) (xy 52.222528 -160.396849) (xy 52.258239 -160.35565) (xy 52.299451 -160.319952)
			(xy 52.345323 -160.290482) (xy 52.394923 -160.267841) (xy 52.447239 -160.25249) (xy 52.501209 -160.24474)
			(xy 52.52847 -160.244282) (xy 52.555724 -160.244763) (xy 52.609676 -160.252517) (xy 52.661976 -160.26787)
			(xy 52.711559 -160.29051) (xy 52.757415 -160.319976) (xy 52.79861 -160.355669) (xy 52.834306 -160.396861)
			(xy 52.863776 -160.442715) (xy 52.88642 -160.492295) (xy 52.901777 -160.544594) (xy 52.909535 -160.598547)
			(xy 52.909535 -160.653054) (xy 52.901777 -160.707006) (xy 52.88642 -160.759305) (xy 52.863776 -160.808885)
			(xy 52.834306 -160.854739) (xy 52.79861 -160.895931) (xy 52.757415 -160.931624) (xy 52.711559 -160.96109)
			(xy 52.661976 -160.98373) (xy 52.609676 -160.999083) (xy 52.555724 -161.006837) (xy 52.52847 -161.007298)
			(xy 52.501213 -161.006822) (xy 52.447254 -160.999052) (xy 52.394948 -160.983688) (xy 52.345359 -160.961042)
			(xy 52.299494 -160.931575) (xy 52.258285 -160.895886) (xy 52.22257 -160.854699) (xy 52.207414 -160.832038)
			(xy 52.202578 -160.825058) (xy 52.189261 -160.81454) (xy 52.173227 -160.808982) (xy 52.164742 -160.80867)
			(xy 52.079398 -160.80867) (xy 52.070921 -160.809021) (xy 52.05491 -160.814599) (xy 52.041583 -160.825082)
			(xy 52.036726 -160.832038) (xy 52.021573 -160.8547) (xy 51.98586 -160.895887) (xy 51.944652 -160.931575)
			(xy 51.898785 -160.961038) (xy 51.849194 -160.983675) (xy 51.796886 -160.999028) (xy 51.742927 -161.006783)
			(xy 51.688413 -161.006783) (xy 51.634454 -160.999028) (xy 51.582146 -160.983675) (xy 51.532555 -160.961038)
			(xy 51.486688 -160.931575) (xy 51.44548 -160.895887) (xy 51.409767 -160.8547) (xy 51.394614 -160.832038)
			(xy 51.389778 -160.825058) (xy 51.376461 -160.81454) (xy 51.360427 -160.808982) (xy 51.351942 -160.80867)
			(xy 51.266598 -160.80867) (xy 51.258121 -160.809021) (xy 51.24211 -160.814599) (xy 51.228783 -160.825082)
			(xy 51.223926 -160.832038) (xy 51.20878 -160.854708) (xy 51.173074 -160.895909) (xy 51.131869 -160.931609)
			(xy 51.086002 -160.961081) (xy 51.036407 -160.983726) (xy 50.984095 -160.999082) (xy 50.93013 -161.006837)
			(xy 50.90287 -161.007298) (xy 50.875619 -161.00683) (xy 50.821674 -160.99907) (xy 50.769381 -160.983712)
			(xy 50.719806 -160.961068) (xy 50.673958 -160.931601) (xy 50.632771 -160.895908) (xy 50.597081 -160.854718)
			(xy 50.567617 -160.808867) (xy 50.544978 -160.759291) (xy 50.529624 -160.706997) (xy 50.521868 -160.653051)
			(xy 32.874687 -160.653051) (xy 23.727353 -169.800524) (xy 32.9565 -169.800524) (xy 32.956954 -169.770117)
			(xy 32.964183 -169.709735) (xy 32.978566 -169.650648) (xy 32.999897 -169.593698) (xy 33.027871 -169.539701)
			(xy 33.062087 -169.489428) (xy 33.102059 -169.443596) (xy 33.147213 -169.402861) (xy 33.196905 -169.367806)
			(xy 33.223454 -169.352976) (xy 33.23463 -169.34688) (xy 33.2486 -169.32656) (xy 33.260538 -169.218356)
			(xy 33.251648 -169.195242) (xy 33.241996 -169.18686) (xy 33.221827 -169.168673) (xy 33.186361 -169.127546)
			(xy 33.157088 -169.081803) (xy 33.134602 -169.032369) (xy 33.119357 -168.980245) (xy 33.111661 -168.926486)
			(xy 33.111186 -168.899332) (xy 33.111672 -168.872081) (xy 33.119428 -168.818133) (xy 33.134783 -168.765838)
			(xy 33.157425 -168.716261) (xy 33.186891 -168.670411) (xy 33.222582 -168.62922) (xy 33.263773 -168.593529)
			(xy 33.309623 -168.564063) (xy 33.3592 -168.541421) (xy 33.411495 -168.526066) (xy 33.465443 -168.51831)
			(xy 33.519945 -168.51831) (xy 33.573893 -168.526066) (xy 33.626188 -168.541421) (xy 33.675765 -168.564063)
			(xy 33.721615 -168.593529) (xy 33.762806 -168.62922) (xy 33.798497 -168.670411) (xy 33.827963 -168.716261)
			(xy 33.850605 -168.765838) (xy 33.86596 -168.818133) (xy 33.873716 -168.872081) (xy 33.874202 -168.899332)
			(xy 33.873613 -168.928456) (xy 33.864755 -168.986027) (xy 33.84725 -169.041583) (xy 33.83608 -169.064251)
			(xy 37.635678 -169.064251) (xy 37.635678 -169.009749) (xy 37.643434 -168.955803) (xy 37.658788 -168.903509)
			(xy 37.681429 -168.853932) (xy 37.710894 -168.808083) (xy 37.746584 -168.766893) (xy 37.787773 -168.731201)
			(xy 37.833622 -168.701735) (xy 37.883198 -168.679093) (xy 37.935491 -168.663737) (xy 37.989437 -168.655979)
			(xy 38.016688 -168.655492) (xy 38.043623 -168.655932) (xy 38.096956 -168.663526) (xy 38.148689 -168.67855)
			(xy 38.197793 -168.700705) (xy 38.24329 -168.72955) (xy 38.264084 -168.746678) (xy 38.272212 -168.753536)
			(xy 38.29177 -168.759632) (xy 38.386766 -168.749218) (xy 38.404546 -168.739058) (xy 38.41115 -168.730422)
			(xy 38.43178 -168.703946) (xy 38.478936 -168.65618) (xy 38.53197 -168.615037) (xy 38.589957 -168.581231)
			(xy 38.651889 -168.555351) (xy 38.716688 -168.537848) (xy 38.783227 -168.529025) (xy 38.816788 -168.528492)
			(xy 38.848751 -168.528972) (xy 38.912173 -168.536983) (xy 38.97409 -168.552879) (xy 39.033527 -168.576411)
			(xy 39.089546 -168.607206) (xy 39.141264 -168.64478) (xy 39.187864 -168.68854) (xy 39.228612 -168.737795)
			(xy 39.262866 -168.791769) (xy 39.290084 -168.84961) (xy 39.309839 -168.910407) (xy 39.321818 -168.9732)
			(xy 39.325832 -169.037) (xy 39.321818 -169.1008) (xy 39.309839 -169.163593) (xy 39.290084 -169.22439)
			(xy 39.262866 -169.282231) (xy 39.228612 -169.336205) (xy 39.187864 -169.38546) (xy 39.141264 -169.42922)
			(xy 39.089546 -169.466794) (xy 39.033527 -169.497589) (xy 38.97409 -169.521121) (xy 38.912173 -169.537017)
			(xy 38.848751 -169.545028) (xy 38.816788 -169.545508) (xy 38.783232 -169.544925) (xy 38.716704 -169.536085)
			(xy 38.651916 -169.518573) (xy 38.589994 -169.492693) (xy 38.532013 -169.458896) (xy 38.47898 -169.417766)
			(xy 38.431817 -169.37002) (xy 38.41115 -169.343578) (xy 38.404546 -169.334942) (xy 38.386766 -169.324782)
			(xy 38.29177 -169.314368) (xy 38.272212 -169.320464) (xy 38.264084 -169.327322) (xy 38.243284 -169.344441)
			(xy 38.19779 -169.373288) (xy 38.148688 -169.395441) (xy 38.096955 -169.41046) (xy 38.043622 -169.418044)
			(xy 38.016688 -169.418508) (xy 37.989437 -169.418021) (xy 37.935491 -169.410263) (xy 37.883198 -169.394907)
			(xy 37.833622 -169.372265) (xy 37.787773 -169.342799) (xy 37.746584 -169.307107) (xy 37.710894 -169.265917)
			(xy 37.681429 -169.220068) (xy 37.658788 -169.170491) (xy 37.643434 -169.118197) (xy 37.635678 -169.064251)
			(xy 33.83608 -169.064251) (xy 33.821504 -169.093833) (xy 33.788116 -169.141563) (xy 33.747862 -169.183663)
			(xy 33.725104 -169.201846) (xy 33.715198 -169.209466) (xy 33.704784 -169.232072) (xy 33.710118 -169.34053)
			(xy 33.722818 -169.361866) (xy 33.733486 -169.368724) (xy 33.750551 -169.379521) (xy 33.7831 -169.403426)
			(xy 33.79851 -169.416476) (xy 33.805368 -169.422826) (xy 33.822386 -169.428922) (xy 33.90773 -169.428922)
			(xy 33.924748 -169.422826) (xy 33.931606 -169.416476) (xy 33.954779 -169.396924) (xy 34.00497 -169.362906)
			(xy 34.058852 -169.335101) (xy 34.115659 -169.313903) (xy 34.174584 -169.299614) (xy 34.234791 -169.292437)
			(xy 34.265108 -169.292016) (xy 34.29707 -169.29247) (xy 34.36049 -169.300483) (xy 34.422406 -169.316381)
			(xy 34.481842 -169.339914) (xy 34.537859 -169.370711) (xy 34.589574 -169.408285) (xy 34.636173 -169.452045)
			(xy 34.676919 -169.5013) (xy 34.711172 -169.555273) (xy 34.738389 -169.613114) (xy 34.749104 -169.646092)
			(xy 43.363642 -169.646092) (xy 43.364131 -169.61568) (xy 43.371398 -169.555291) (xy 43.385815 -169.4962)
			(xy 43.407177 -169.43925) (xy 43.435179 -169.385255) (xy 43.46942 -169.334984) (xy 43.509413 -169.289156)
			(xy 43.554586 -169.248425) (xy 43.604294 -169.213372) (xy 43.63085 -169.198544) (xy 43.63974 -169.193718)
			(xy 43.652186 -169.178986) (xy 43.679872 -169.093134) (xy 43.678602 -169.07383) (xy 43.674284 -169.06494)
			(xy 43.662344 -169.038982) (xy 43.64548 -168.984393) (xy 43.63695 -168.927899) (xy 43.636438 -168.899332)
			(xy 43.636924 -168.872081) (xy 43.64468 -168.818133) (xy 43.660035 -168.765838) (xy 43.682677 -168.716261)
			(xy 43.712143 -168.670411) (xy 43.747834 -168.62922) (xy 43.789025 -168.593529) (xy 43.834875 -168.564063)
			(xy 43.884452 -168.541421) (xy 43.936747 -168.526066) (xy 43.990695 -168.51831) (xy 44.045197 -168.51831)
			(xy 44.099145 -168.526066) (xy 44.15144 -168.541421) (xy 44.201017 -168.564063) (xy 44.246867 -168.593529)
			(xy 44.288058 -168.62922) (xy 44.323749 -168.670411) (xy 44.353215 -168.716261) (xy 44.375857 -168.765838)
			(xy 44.391212 -168.818133) (xy 44.398968 -168.872081) (xy 44.399454 -168.899332) (xy 44.398977 -168.92587)
			(xy 44.391622 -168.978434) (xy 44.377057 -169.029473) (xy 44.355564 -169.078003) (xy 44.327557 -169.123088)
			(xy 44.293576 -169.16386) (xy 44.274232 -169.182034) (xy 44.266866 -169.188638) (xy 44.25823 -169.206164)
			(xy 44.25188 -169.29608) (xy 44.257722 -169.314368) (xy 44.264072 -169.321988) (xy 44.282419 -169.344824)
			(xy 44.314299 -169.393969) (xy 44.340325 -169.446451) (xy 44.360152 -169.501574) (xy 44.373518 -169.558609)
			(xy 44.380246 -169.616802) (xy 44.380658 -169.646092) (xy 44.380156 -169.678053) (xy 44.372145 -169.741471)
			(xy 44.356248 -169.803385) (xy 44.332716 -169.862818) (xy 44.301922 -169.918833) (xy 44.264349 -169.970548)
			(xy 44.220592 -170.017145) (xy 44.171339 -170.05789) (xy 44.117368 -170.092141) (xy 44.059529 -170.119358)
			(xy 43.998736 -170.139111) (xy 43.935946 -170.151089) (xy 43.87215 -170.155103) (xy 43.808354 -170.151089)
			(xy 43.745564 -170.139111) (xy 43.684771 -170.119358) (xy 43.626932 -170.092141) (xy 43.572961 -170.05789)
			(xy 43.523708 -170.017145) (xy 43.479951 -169.970548) (xy 43.442378 -169.918833) (xy 43.411584 -169.862818)
			(xy 43.388052 -169.803385) (xy 43.372155 -169.741471) (xy 43.364144 -169.678053) (xy 43.363642 -169.646092)
			(xy 34.749104 -169.646092) (xy 34.758143 -169.67391) (xy 34.770121 -169.736702) (xy 34.774135 -169.8005)
			(xy 34.770121 -169.864298) (xy 34.758143 -169.92709) (xy 34.738389 -169.987886) (xy 34.711172 -170.045727)
			(xy 34.676919 -170.0997) (xy 34.636173 -170.148955) (xy 34.589574 -170.192715) (xy 34.537859 -170.230289)
			(xy 34.481842 -170.261086) (xy 34.422406 -170.284619) (xy 34.36049 -170.300517) (xy 34.29707 -170.30853)
			(xy 34.265108 -170.309032) (xy 34.234793 -170.308608) (xy 34.174591 -170.301415) (xy 34.11567 -170.287117)
			(xy 34.058867 -170.265917) (xy 34.004986 -170.238116) (xy 33.954791 -170.204108) (xy 33.931606 -170.184572)
			(xy 33.924748 -170.178222) (xy 33.90773 -170.172126) (xy 33.822386 -170.172126) (xy 33.805368 -170.178222)
			(xy 33.79851 -170.184572) (xy 33.775324 -170.204108) (xy 33.725136 -170.23813) (xy 33.671258 -170.265938)
			(xy 33.614453 -170.287139) (xy 33.55553 -170.30143) (xy 33.495324 -170.30861) (xy 33.465008 -170.309032)
			(xy 33.434278 -170.308536) (xy 33.373266 -170.301129) (xy 33.313592 -170.286422) (xy 33.256126 -170.26463)
			(xy 33.201705 -170.236069) (xy 33.151124 -170.201158) (xy 33.105119 -170.160404) (xy 33.064362 -170.114402)
			(xy 33.029447 -170.063822) (xy 33.000883 -170.009404) (xy 32.979087 -169.951938) (xy 32.964376 -169.892265)
			(xy 32.956965 -169.831254) (xy 32.9565 -169.800524) (xy 23.727353 -169.800524) (xy 23.202894 -170.324991)
			(xy 35.171628 -170.324991) (xy 35.171628 -170.261069) (xy 35.179639 -170.197651) (xy 35.195536 -170.135737)
			(xy 35.219068 -170.076304) (xy 35.249862 -170.020289) (xy 35.287435 -169.968574) (xy 35.331192 -169.921977)
			(xy 35.380445 -169.881232) (xy 35.434416 -169.846981) (xy 35.492255 -169.819764) (xy 35.553048 -169.800011)
			(xy 35.615838 -169.788033) (xy 35.679634 -169.78402) (xy 35.74343 -169.788033) (xy 35.80622 -169.800011)
			(xy 35.867013 -169.819764) (xy 35.924852 -169.846981) (xy 35.978823 -169.881232) (xy 36.028076 -169.921977)
			(xy 36.071833 -169.968574) (xy 36.109406 -170.020289) (xy 36.1402 -170.076304) (xy 36.163732 -170.135737)
			(xy 36.179629 -170.197651) (xy 36.18764 -170.261069) (xy 36.188142 -170.29303) (xy 36.18764 -170.324991)
			(xy 36.179629 -170.388409) (xy 36.168652 -170.431163) (xy 40.988482 -170.431163) (xy 40.988482 -170.367241)
			(xy 40.996493 -170.303823) (xy 41.01239 -170.241909) (xy 41.035922 -170.182476) (xy 41.066716 -170.126461)
			(xy 41.104289 -170.074746) (xy 41.148046 -170.028149) (xy 41.197299 -169.987404) (xy 41.25127 -169.953153)
			(xy 41.309109 -169.925936) (xy 41.369902 -169.906183) (xy 41.432692 -169.894205) (xy 41.496488 -169.890192)
			(xy 41.560284 -169.894205) (xy 41.623074 -169.906183) (xy 41.683867 -169.925936) (xy 41.741706 -169.953153)
			(xy 41.795677 -169.987404) (xy 41.84493 -170.028149) (xy 41.888687 -170.074746) (xy 41.92626 -170.126461)
			(xy 41.957054 -170.182476) (xy 41.980586 -170.241909) (xy 41.996483 -170.303823) (xy 42.004494 -170.367241)
			(xy 42.004996 -170.399202) (xy 42.004494 -170.431163) (xy 41.996483 -170.494581) (xy 41.980586 -170.556495)
			(xy 41.957054 -170.615928) (xy 41.92626 -170.671943) (xy 41.888687 -170.723658) (xy 41.84493 -170.770255)
			(xy 41.795677 -170.811) (xy 41.741706 -170.845251) (xy 41.683867 -170.872468) (xy 41.623074 -170.892221)
			(xy 41.560284 -170.904199) (xy 41.496488 -170.908213) (xy 41.432692 -170.904199) (xy 41.369902 -170.892221)
			(xy 41.309109 -170.872468) (xy 41.25127 -170.845251) (xy 41.197299 -170.811) (xy 41.148046 -170.770255)
			(xy 41.104289 -170.723658) (xy 41.066716 -170.671943) (xy 41.035922 -170.615928) (xy 41.01239 -170.556495)
			(xy 40.996493 -170.494581) (xy 40.988482 -170.431163) (xy 36.168652 -170.431163) (xy 36.163732 -170.450323)
			(xy 36.1402 -170.509756) (xy 36.109406 -170.565771) (xy 36.071833 -170.617486) (xy 36.028076 -170.664083)
			(xy 35.978823 -170.704828) (xy 35.924852 -170.739079) (xy 35.867013 -170.766296) (xy 35.80622 -170.786049)
			(xy 35.74343 -170.798027) (xy 35.679634 -170.802041) (xy 35.615838 -170.798027) (xy 35.553048 -170.786049)
			(xy 35.492255 -170.766296) (xy 35.434416 -170.739079) (xy 35.380445 -170.704828) (xy 35.331192 -170.664083)
			(xy 35.287435 -170.617486) (xy 35.249862 -170.565771) (xy 35.219068 -170.509756) (xy 35.195536 -170.450323)
			(xy 35.179639 -170.388409) (xy 35.171628 -170.324991) (xy 23.202894 -170.324991) (xy 22.082771 -171.445131)
			(xy 40.008296 -171.445131) (xy 40.008296 -171.381209) (xy 40.016307 -171.317791) (xy 40.032204 -171.255877)
			(xy 40.055736 -171.196444) (xy 40.08653 -171.140429) (xy 40.124103 -171.088714) (xy 40.16786 -171.042117)
			(xy 40.217113 -171.001372) (xy 40.271084 -170.967121) (xy 40.328923 -170.939904) (xy 40.389716 -170.920151)
			(xy 40.452506 -170.908173) (xy 40.516302 -170.90416) (xy 40.580098 -170.908173) (xy 40.642888 -170.920151)
			(xy 40.703681 -170.939904) (xy 40.76152 -170.967121) (xy 40.815491 -171.001372) (xy 40.864744 -171.042117)
			(xy 40.908501 -171.088714) (xy 40.946074 -171.140429) (xy 40.976868 -171.196444) (xy 41.0004 -171.255877)
			(xy 41.016297 -171.317791) (xy 41.024308 -171.381209) (xy 41.02481 -171.41317) (xy 41.024308 -171.445131)
			(xy 41.016297 -171.508549) (xy 41.0004 -171.570463) (xy 40.976868 -171.629896) (xy 40.946074 -171.685911)
			(xy 40.908501 -171.737626) (xy 40.864744 -171.784223) (xy 40.815491 -171.824968) (xy 40.76152 -171.859219)
			(xy 40.703681 -171.886436) (xy 40.642888 -171.906189) (xy 40.580098 -171.918167) (xy 40.516302 -171.922181)
			(xy 40.452506 -171.918167) (xy 40.389716 -171.906189) (xy 40.328923 -171.886436) (xy 40.271084 -171.859219)
			(xy 40.217113 -171.824968) (xy 40.16786 -171.784223) (xy 40.124103 -171.737626) (xy 40.08653 -171.685911)
			(xy 40.055736 -171.629896) (xy 40.032204 -171.570463) (xy 40.016307 -171.508549) (xy 40.008296 -171.445131)
			(xy 22.082771 -171.445131) (xy 20.956298 -172.571621) (xy 33.009834 -172.571621) (xy 33.009834 -172.507699)
			(xy 33.017845 -172.444281) (xy 33.033742 -172.382367) (xy 33.057274 -172.322934) (xy 33.088068 -172.266919)
			(xy 33.125641 -172.215204) (xy 33.169398 -172.168607) (xy 33.218651 -172.127862) (xy 33.272622 -172.093611)
			(xy 33.330461 -172.066394) (xy 33.391254 -172.046641) (xy 33.454044 -172.034663) (xy 33.51784 -172.03065)
			(xy 33.581636 -172.034663) (xy 33.644426 -172.046641) (xy 33.705219 -172.066394) (xy 33.763058 -172.093611)
			(xy 33.817029 -172.127862) (xy 33.866282 -172.168607) (xy 33.910039 -172.215204) (xy 33.947612 -172.266919)
			(xy 33.978406 -172.322934) (xy 34.001938 -172.382367) (xy 34.017835 -172.444281) (xy 34.025846 -172.507699)
			(xy 34.026348 -172.53966) (xy 34.025846 -172.571621) (xy 34.024916 -172.578987) (xy 40.762422 -172.578987)
			(xy 40.762422 -172.515065) (xy 40.770433 -172.451647) (xy 40.78633 -172.389733) (xy 40.809862 -172.3303)
			(xy 40.840656 -172.274285) (xy 40.878229 -172.22257) (xy 40.921986 -172.175973) (xy 40.971239 -172.135228)
			(xy 41.02521 -172.100977) (xy 41.083049 -172.07376) (xy 41.143842 -172.054007) (xy 41.206632 -172.042029)
			(xy 41.270428 -172.038016) (xy 41.334224 -172.042029) (xy 41.397014 -172.054007) (xy 41.457807 -172.07376)
			(xy 41.515646 -172.100977) (xy 41.569617 -172.135228) (xy 41.61887 -172.175973) (xy 41.662627 -172.22257)
			(xy 41.7002 -172.274285) (xy 41.730994 -172.3303) (xy 41.754526 -172.389733) (xy 41.770423 -172.451647)
			(xy 41.778434 -172.515065) (xy 41.778936 -172.547026) (xy 41.778434 -172.578987) (xy 41.770423 -172.642405)
			(xy 41.754526 -172.704319) (xy 41.730994 -172.763752) (xy 41.7002 -172.819767) (xy 41.662627 -172.871482)
			(xy 41.61887 -172.918079) (xy 41.569617 -172.958824) (xy 41.515646 -172.993075) (xy 41.457807 -173.020292)
			(xy 41.397014 -173.040045) (xy 41.334224 -173.052023) (xy 41.270428 -173.056037) (xy 41.206632 -173.052023)
			(xy 41.143842 -173.040045) (xy 41.083049 -173.020292) (xy 41.02521 -172.993075) (xy 40.971239 -172.958824)
			(xy 40.921986 -172.918079) (xy 40.878229 -172.871482) (xy 40.840656 -172.819767) (xy 40.809862 -172.763752)
			(xy 40.78633 -172.704319) (xy 40.770433 -172.642405) (xy 40.762422 -172.578987) (xy 34.024916 -172.578987)
			(xy 34.017835 -172.635039) (xy 34.001938 -172.696953) (xy 33.978406 -172.756386) (xy 33.947612 -172.812401)
			(xy 33.910039 -172.864116) (xy 33.866282 -172.910713) (xy 33.817029 -172.951458) (xy 33.763058 -172.985709)
			(xy 33.705219 -173.012926) (xy 33.644426 -173.032679) (xy 33.581636 -173.044657) (xy 33.51784 -173.048671)
			(xy 33.454044 -173.044657) (xy 33.391254 -173.032679) (xy 33.330461 -173.012926) (xy 33.272622 -172.985709)
			(xy 33.218651 -172.951458) (xy 33.169398 -172.910713) (xy 33.125641 -172.864116) (xy 33.088068 -172.812401)
			(xy 33.057274 -172.756386) (xy 33.033742 -172.696953) (xy 33.017845 -172.635039) (xy 33.009834 -172.571621)
			(xy 20.956298 -172.571621) (xy 19.95805 -173.569884) (xy 19.951247 -173.577231) (xy 19.943537 -173.595695)
			(xy 19.943064 -173.605698) (xy 19.943064 -174.348351) (xy 28.204662 -174.348351) (xy 28.204662 -174.284429)
			(xy 28.212673 -174.221011) (xy 28.22857 -174.159097) (xy 28.252102 -174.099664) (xy 28.282896 -174.043649)
			(xy 28.320469 -173.991934) (xy 28.364226 -173.945337) (xy 28.413479 -173.904592) (xy 28.46745 -173.870341)
			(xy 28.525289 -173.843124) (xy 28.586082 -173.823371) (xy 28.648872 -173.811393) (xy 28.712668 -173.80738)
			(xy 28.776464 -173.811393) (xy 28.839254 -173.823371) (xy 28.900047 -173.843124) (xy 28.957886 -173.870341)
			(xy 29.011857 -173.904592) (xy 29.06111 -173.945337) (xy 29.104867 -173.991934) (xy 29.14244 -174.043649)
			(xy 29.173234 -174.099664) (xy 29.196766 -174.159097) (xy 29.212663 -174.221011) (xy 29.217942 -174.2628)
			(xy 32.955964 -174.2628) (xy 32.959978 -174.199) (xy 32.971957 -174.136207) (xy 32.991711 -174.07541)
			(xy 33.01893 -174.017568) (xy 33.053184 -173.963594) (xy 33.093932 -173.914338) (xy 33.140532 -173.870579)
			(xy 33.192249 -173.833004) (xy 33.248268 -173.802208) (xy 33.307705 -173.778676) (xy 33.369623 -173.76278)
			(xy 33.433045 -173.754768) (xy 33.465008 -173.754288) (xy 33.495324 -173.754697) (xy 33.555527 -173.761893)
			(xy 33.614447 -173.776194) (xy 33.671251 -173.797396) (xy 33.725131 -173.8252) (xy 33.775325 -173.859211)
			(xy 33.79851 -173.878748) (xy 33.805368 -173.885098) (xy 33.822386 -173.891194) (xy 33.90773 -173.891194)
			(xy 33.924748 -173.885098) (xy 33.931606 -173.878748) (xy 33.954789 -173.859207) (xy 34.004977 -173.825186)
			(xy 34.058856 -173.797378) (xy 34.115661 -173.776178) (xy 34.174586 -173.761887) (xy 34.234792 -173.754709)
			(xy 34.265108 -173.754288) (xy 34.297068 -173.754798) (xy 34.360485 -173.762811) (xy 34.422398 -173.778708)
			(xy 34.48183 -173.80224) (xy 34.537844 -173.833034) (xy 34.589556 -173.870607) (xy 34.636152 -173.914364)
			(xy 34.676897 -173.963616) (xy 34.711147 -174.017586) (xy 34.738363 -174.075424) (xy 34.758115 -174.136216)
			(xy 34.770093 -174.199005) (xy 34.774107 -174.2628) (xy 34.770093 -174.326595) (xy 34.758115 -174.389384)
			(xy 34.757321 -174.391828) (xy 35.145218 -174.391828) (xy 35.145681 -174.364962) (xy 35.153217 -174.311762)
			(xy 35.168144 -174.260145) (xy 35.190166 -174.211134) (xy 35.218848 -174.165698) (xy 35.253621 -174.124736)
			(xy 35.293799 -174.089059) (xy 35.338585 -174.059372) (xy 35.362642 -174.047404) (xy 35.375561 -174.040748)
			(xy 35.397232 -174.0214) (xy 35.412575 -173.996731) (xy 35.420348 -173.96874) (xy 35.419921 -173.939692)
			(xy 35.411329 -173.91194) (xy 35.395268 -173.887733) (xy 35.384486 -173.877986) (xy 35.360625 -173.857251)
			(xy 35.317732 -173.810813) (xy 35.280928 -173.759415) (xy 35.25078 -173.703851) (xy 35.227753 -173.644977)
			(xy 35.212203 -173.583703) (xy 35.20437 -173.520974) (xy 35.203892 -173.489366) (xy 35.204394 -173.457405)
			(xy 35.212405 -173.393987) (xy 35.228302 -173.332073) (xy 35.251834 -173.27264) (xy 35.282628 -173.216625)
			(xy 35.320201 -173.16491) (xy 35.363958 -173.118313) (xy 35.413211 -173.077568) (xy 35.467182 -173.043317)
			(xy 35.525021 -173.0161) (xy 35.585814 -172.996347) (xy 35.648604 -172.984369) (xy 35.7124 -172.980356)
			(xy 35.776196 -172.984369) (xy 35.838986 -172.996347) (xy 35.899779 -173.0161) (xy 35.957618 -173.043317)
			(xy 36.011589 -173.077568) (xy 36.060842 -173.118313) (xy 36.104599 -173.16491) (xy 36.142172 -173.216625)
			(xy 36.172966 -173.27264) (xy 36.196498 -173.332073) (xy 36.212395 -173.393987) (xy 36.220406 -173.457405)
			(xy 36.220908 -173.489366) (xy 36.220375 -173.521817) (xy 36.218376 -173.537372) (xy 38.405052 -173.537372)
			(xy 38.409123 -173.48175) (xy 38.421249 -173.427313) (xy 38.441172 -173.375222) (xy 38.468468 -173.326587)
			(xy 38.502554 -173.282444) (xy 38.542703 -173.243735) (xy 38.588061 -173.211284) (xy 38.637661 -173.185783)
			(xy 38.690445 -173.167776) (xy 38.745288 -173.157646) (xy 38.801022 -173.155609) (xy 38.856459 -173.161709)
			(xy 38.910416 -173.175815) (xy 38.961745 -173.197627) (xy 39.009351 -173.226681) (xy 39.052219 -173.262356)
			(xy 39.089436 -173.303893) (xy 39.120209 -173.350406) (xy 39.143881 -173.400903) (xy 39.159949 -173.45431)
			(xy 39.168069 -173.509486) (xy 39.168578 -173.537372) (xy 39.168069 -173.565258) (xy 39.159949 -173.620434)
			(xy 39.143881 -173.673841) (xy 39.120209 -173.724338) (xy 39.089436 -173.770851) (xy 39.052219 -173.812388)
			(xy 39.009351 -173.848063) (xy 38.961745 -173.877117) (xy 38.946054 -173.883785) (xy 40.572684 -173.883785)
			(xy 40.572684 -173.819863) (xy 40.580695 -173.756445) (xy 40.596592 -173.694531) (xy 40.620124 -173.635098)
			(xy 40.650918 -173.579083) (xy 40.688491 -173.527368) (xy 40.732248 -173.480771) (xy 40.781501 -173.440026)
			(xy 40.835472 -173.405775) (xy 40.893311 -173.378558) (xy 40.954104 -173.358805) (xy 41.016894 -173.346827)
			(xy 41.08069 -173.342814) (xy 41.144486 -173.346827) (xy 41.207276 -173.358805) (xy 41.268069 -173.378558)
			(xy 41.325908 -173.405775) (xy 41.379879 -173.440026) (xy 41.429132 -173.480771) (xy 41.472889 -173.527368)
			(xy 41.510462 -173.579083) (xy 41.541256 -173.635098) (xy 41.564788 -173.694531) (xy 41.580685 -173.756445)
			(xy 41.588696 -173.819863) (xy 41.589198 -173.851824) (xy 41.588696 -173.883785) (xy 41.580685 -173.947203)
			(xy 41.564788 -174.009117) (xy 41.541256 -174.06855) (xy 41.510462 -174.124565) (xy 41.472889 -174.17628)
			(xy 41.429132 -174.222877) (xy 41.379879 -174.263622) (xy 41.325908 -174.297873) (xy 41.268069 -174.32509)
			(xy 41.207276 -174.344843) (xy 41.144486 -174.356821) (xy 41.08069 -174.360835) (xy 41.016894 -174.356821)
			(xy 40.954104 -174.344843) (xy 40.893311 -174.32509) (xy 40.835472 -174.297873) (xy 40.781501 -174.263622)
			(xy 40.732248 -174.222877) (xy 40.688491 -174.17628) (xy 40.650918 -174.124565) (xy 40.620124 -174.06855)
			(xy 40.596592 -174.009117) (xy 40.580695 -173.947203) (xy 40.572684 -173.883785) (xy 38.946054 -173.883785)
			(xy 38.910416 -173.898929) (xy 38.856459 -173.913035) (xy 38.801022 -173.919135) (xy 38.745288 -173.917098)
			(xy 38.690445 -173.906968) (xy 38.637661 -173.888961) (xy 38.588061 -173.86346) (xy 38.542703 -173.831009)
			(xy 38.502554 -173.7923) (xy 38.468468 -173.748157) (xy 38.441172 -173.699522) (xy 38.421249 -173.647431)
			(xy 38.409123 -173.592994) (xy 38.405052 -173.537372) (xy 36.218376 -173.537372) (xy 36.212101 -173.58619)
			(xy 36.195711 -173.648989) (xy 36.171468 -173.709194) (xy 36.139768 -173.765828) (xy 36.101124 -173.817972)
			(xy 36.056164 -173.864779) (xy 36.005617 -173.90549) (xy 35.950304 -173.939444) (xy 35.891123 -173.966089)
			(xy 35.860228 -173.97603) (xy 35.846489 -173.980701) (xy 35.822228 -173.996599) (xy 35.803423 -174.018684)
			(xy 35.791595 -174.045169) (xy 35.7877 -174.073912) (xy 35.792052 -174.10259) (xy 35.804301 -174.128883)
			(xy 35.813492 -174.140114) (xy 35.831273 -174.161096) (xy 35.861226 -174.207221) (xy 35.88425 -174.257167)
			(xy 35.899868 -174.309901) (xy 35.907756 -174.364329) (xy 35.908234 -174.391828) (xy 35.907748 -174.419079)
			(xy 35.899992 -174.473027) (xy 35.884637 -174.525322) (xy 35.861995 -174.574899) (xy 35.832529 -174.620749)
			(xy 35.796838 -174.66194) (xy 35.755647 -174.697631) (xy 35.709797 -174.727097) (xy 35.66022 -174.749739)
			(xy 35.607925 -174.765094) (xy 35.553977 -174.77285) (xy 35.499475 -174.77285) (xy 35.445527 -174.765094)
			(xy 35.393232 -174.749739) (xy 35.343655 -174.727097) (xy 35.297805 -174.697631) (xy 35.256614 -174.66194)
			(xy 35.220923 -174.620749) (xy 35.191457 -174.574899) (xy 35.168815 -174.525322) (xy 35.15346 -174.473027)
			(xy 35.145704 -174.419079) (xy 35.145218 -174.391828) (xy 34.757321 -174.391828) (xy 34.738363 -174.450176)
			(xy 34.711147 -174.508014) (xy 34.676897 -174.561984) (xy 34.636152 -174.611236) (xy 34.589556 -174.654993)
			(xy 34.537844 -174.692566) (xy 34.48183 -174.72336) (xy 34.422398 -174.746892) (xy 34.360485 -174.762789)
			(xy 34.297068 -174.770802) (xy 34.265108 -174.771304) (xy 34.234792 -174.770887) (xy 34.17459 -174.763693)
			(xy 34.115669 -174.749394) (xy 34.058866 -174.728193) (xy 34.004985 -174.70039) (xy 33.954791 -174.666381)
			(xy 33.931606 -174.646844) (xy 33.924748 -174.640494) (xy 33.90773 -174.634398) (xy 33.822386 -174.634398)
			(xy 33.805368 -174.640494) (xy 33.79851 -174.646844) (xy 33.77532 -174.666376) (xy 33.725134 -174.700399)
			(xy 33.671256 -174.728208) (xy 33.614452 -174.74941) (xy 33.555529 -174.763702) (xy 33.495324 -174.770882)
			(xy 33.465008 -174.771304) (xy 33.433045 -174.770832) (xy 33.369623 -174.76282) (xy 33.307705 -174.746924)
			(xy 33.248268 -174.723392) (xy 33.192249 -174.692596) (xy 33.140532 -174.655021) (xy 33.093932 -174.611262)
			(xy 33.053184 -174.562006) (xy 33.01893 -174.508032) (xy 32.991711 -174.45019) (xy 32.971957 -174.389393)
			(xy 32.959978 -174.3266) (xy 32.955964 -174.2628) (xy 29.217942 -174.2628) (xy 29.220674 -174.284429)
			(xy 29.221176 -174.31639) (xy 29.220674 -174.348351) (xy 29.212663 -174.411769) (xy 29.196766 -174.473683)
			(xy 29.173234 -174.533116) (xy 29.14244 -174.589131) (xy 29.104867 -174.640846) (xy 29.06111 -174.687443)
			(xy 29.011857 -174.728188) (xy 28.957886 -174.762439) (xy 28.900047 -174.789656) (xy 28.839254 -174.809409)
			(xy 28.776464 -174.821387) (xy 28.712668 -174.825401) (xy 28.648872 -174.821387) (xy 28.586082 -174.809409)
			(xy 28.525289 -174.789656) (xy 28.46745 -174.762439) (xy 28.413479 -174.728188) (xy 28.364226 -174.687443)
			(xy 28.320469 -174.640846) (xy 28.282896 -174.589131) (xy 28.252102 -174.533116) (xy 28.22857 -174.473683)
			(xy 28.212673 -174.411769) (xy 28.204662 -174.348351) (xy 19.943064 -174.348351) (xy 19.943064 -174.741332)
			(xy 19.942516 -174.769465) (xy 19.933034 -174.824926) (xy 19.914315 -174.877986) (xy 19.886897 -174.927119)
			(xy 19.869658 -174.949358) (xy 19.86446 -174.956322) (xy 19.858627 -174.97268) (xy 19.858228 -174.981362)
			(xy 19.858228 -175.34128) (xy 19.857798 -175.373092) (xy 19.850672 -175.436316) (xy 19.836508 -175.498343)
			(xy 19.815483 -175.558393) (xy 19.787863 -175.615709) (xy 19.753995 -175.66957) (xy 19.714307 -175.719297)
			(xy 19.692112 -175.742092) (xy 8.943594 -186.49061) (xy 8.93675 -186.498009) (xy 8.92902 -186.516607)
			(xy 8.928608 -186.526678) (xy 8.928608 -323.541898) (xy 8.928186 -323.551969) (xy 8.920473 -323.570574)
			(xy 8.913622 -323.577966) (xy 8.505952 -323.985636) (xy 8.499106 -323.993034) (xy 8.491376 -324.011633)
			(xy 8.490966 -324.021704) (xy 8.490966 -331.43952) (xy 8.491394 -331.449587) (xy 8.499121 -331.46818)
			(xy 8.505952 -331.475588) (xy 8.6868 -331.656436) (xy 8.708898 -331.664056) (xy 8.720582 -331.662532)
			(xy 8.736452 -331.660632) (xy 8.768353 -331.658596) (xy 8.784336 -331.658468) (xy 8.816373 -331.65895)
			(xy 8.87994 -331.66699) (xy 8.941994 -331.682953) (xy 9.001551 -331.706584) (xy 9.057667 -331.737509)
			(xy 9.109455 -331.775239) (xy 9.156092 -331.819175) (xy 9.196841 -331.868622) (xy 9.214358 -331.89545)
			(xy 9.219203 -331.902502) (xy 9.232591 -331.913139) (xy 9.248734 -331.918775) (xy 9.257284 -331.919072)
		)
		(stroke
			(width 0)
			(type solid)
		)
		(fill yes)
		(layer "In13.Cu")
		(net "PVDD18_S5_P1")
	)
	(gr_poly
		(pts
			(xy 71.619618 -26.34234) (xy 71.629428 -26.341891) (xy 71.647619 -26.334538) (xy 71.661733 -26.320909)
			(xy 71.6661 -26.312114) (xy 71.683855 -26.273159) (xy 71.7258 -26.198523) (xy 71.774724 -26.128265)
			(xy 71.830176 -26.063035) (xy 71.89164 -26.003436) (xy 71.958549 -25.950022) (xy 72.030282 -25.903287)
			(xy 72.106176 -25.863663) (xy 72.185526 -25.831517) (xy 72.267599 -25.807148) (xy 72.351635 -25.790781)
			(xy 72.436855 -25.782567) (xy 72.479662 -25.782016) (xy 72.518874 -25.78246) (xy 72.596992 -25.78939)
			(xy 72.674197 -25.803166) (xy 72.74989 -25.823681) (xy 72.823486 -25.850774) (xy 72.859138 -25.867106)
			(xy 72.864218 -25.869392) (xy 72.874886 -25.871678) (xy 72.880422 -25.87277) (xy 72.891702 -25.87277)
			(xy 72.897238 -25.871678) (xy 72.907906 -25.869392) (xy 72.912986 -25.867106) (xy 72.948629 -25.850752)
			(xy 73.022223 -25.823645) (xy 73.097918 -25.803128) (xy 73.175127 -25.78936) (xy 73.253249 -25.782447)
			(xy 73.292462 -25.782016) (xy 73.335268 -25.782529) (xy 73.420483 -25.790762) (xy 73.504513 -25.807145)
			(xy 73.58658 -25.831527) (xy 73.665924 -25.863682) (xy 73.741811 -25.903312) (xy 73.813539 -25.950052)
			(xy 73.880443 -26.003467) (xy 73.941905 -26.063065) (xy 73.997356 -26.128292) (xy 74.046282 -26.198547)
			(xy 74.088231 -26.273177) (xy 74.106024 -26.312114) (xy 74.110405 -26.320901) (xy 74.124504 -26.334541)
			(xy 74.142697 -26.341879) (xy 74.152506 -26.34234) (xy 76.281788 -26.34234) (xy 76.287884 -26.340816)
			(xy 76.330796 -26.3309) (xy 76.41801 -26.318582) (xy 76.506014 -26.314939) (xy 76.550012 -26.31694)
			(xy 76.59056 -26.319678) (xy 76.670951 -26.331631) (xy 76.71054 -26.340816) (xy 76.716636 -26.34234)
			(xy 78.783942 -26.34234) (xy 78.796388 -26.340816) (xy 78.835415 -26.331726) (xy 78.914658 -26.31977)
			(xy 78.95463 -26.31694) (xy 78.964028 -26.316432) (xy 78.980792 -26.308812) (xy 80.426052 -24.863552)
			(xy 80.432739 -24.856143) (xy 80.440331 -24.837707) (xy 80.440784 -24.827738) (xy 80.440784 -23.519892)
			(xy 80.415638 -23.49119) (xy 80.396842 -23.48865) (xy 80.390238 -23.487634) (xy 80.345013 -23.48072)
			(xy 80.256181 -23.458817) (xy 80.170066 -23.42791) (xy 80.087579 -23.388327) (xy 80.009591 -23.340485)
			(xy 79.972916 -23.313136) (xy 79.963565 -23.306701) (xy 79.941401 -23.301947) (xy 79.919353 -23.307218)
			(xy 79.910178 -23.313898) (xy 79.876298 -23.340539) (xy 79.80426 -23.387868) (xy 79.727983 -23.428008)
			(xy 79.648182 -23.460584) (xy 79.565605 -23.485291) (xy 79.481026 -23.501896) (xy 79.395237 -23.510245)
			(xy 79.35214 -23.510748) (xy 79.309788 -23.510262) (xy 79.225466 -23.502214) (xy 79.142292 -23.486186)
			(xy 79.061017 -23.462325) (xy 78.982379 -23.430846) (xy 78.907089 -23.392035) (xy 78.83583 -23.346242)
			(xy 78.769246 -23.293883) (xy 78.707941 -23.235431) (xy 78.65247 -23.171417) (xy 78.603335 -23.102419)
			(xy 78.560982 -23.029064) (xy 78.525793 -22.952014) (xy 78.498088 -22.871968) (xy 78.478118 -22.789651)
			(xy 78.466063 -22.705809) (xy 78.462032 -22.6212) (xy 78.466063 -22.536591) (xy 78.478118 -22.452749)
			(xy 78.498088 -22.370432) (xy 78.525793 -22.290386) (xy 78.560982 -22.213336) (xy 78.603335 -22.139981)
			(xy 78.65247 -22.070983) (xy 78.707941 -22.006969) (xy 78.769246 -21.948517) (xy 78.83583 -21.896158)
			(xy 78.907089 -21.850365) (xy 78.982379 -21.811554) (xy 79.061017 -21.780075) (xy 79.142292 -21.756214)
			(xy 79.225466 -21.740186) (xy 79.309788 -21.732138) (xy 79.35214 -21.731732) (xy 79.393647 -21.732209)
			(xy 79.476299 -21.739941) (xy 79.55787 -21.755343) (xy 79.637651 -21.778281) (xy 79.714947 -21.808555)
			(xy 79.789084 -21.845902) (xy 79.859418 -21.889997) (xy 79.892652 -21.914866) (xy 79.902002 -21.921285)
			(xy 79.924153 -21.926011) (xy 79.946176 -21.920722) (xy 79.95539 -21.914104) (xy 79.986694 -21.889434)
			(xy 80.052973 -21.845156) (xy 80.122949 -21.806987) (xy 80.19606 -21.775234) (xy 80.271719 -21.750151)
			(xy 80.349319 -21.73194) (xy 80.388714 -21.72589) (xy 80.396842 -21.724874) (xy 80.41259 -21.717254)
			(xy 80.420949 -21.712734) (xy 80.433791 -21.698745) (xy 80.440636 -21.681031) (xy 80.441038 -21.671534)
			(xy 80.441038 -21.338286) (xy 80.440784 -21.32584) (xy 80.440784 -20.31365) (xy 80.441038 -20.301204)
			(xy 80.441038 -19.784568) (xy 80.439994 -19.769095) (xy 80.438851 -19.7381) (xy 80.438752 -19.722592)
			(xy 80.438851 -19.707084) (xy 80.439994 -19.676089) (xy 80.441038 -19.660616) (xy 80.441038 -19.14398)
			(xy 80.440784 -19.131534) (xy 80.440784 -16.027654) (xy 80.440301 -16.017691) (xy 80.432717 -15.999262)
			(xy 80.426052 -15.99184) (xy 79.972662 -15.53845) (xy 79.96555 -15.531084) (xy 79.946754 -15.523464)
			(xy 73.3933 -15.523464) (xy 73.388982 -15.523718) (xy 73.380607 -15.524699) (xy 73.365165 -15.531447)
			(xy 73.358756 -15.536926) (xy 73.337503 -15.555811) (xy 73.290449 -15.58772) (xy 73.239181 -15.612292)
			(xy 73.184833 -15.628982) (xy 73.12861 -15.637421) (xy 73.071758 -15.637421) (xy 73.015535 -15.628982)
			(xy 72.961187 -15.612292) (xy 72.909919 -15.58772) (xy 72.862865 -15.555811) (xy 72.841612 -15.536926)
			(xy 72.835177 -15.531485) (xy 72.819751 -15.524733) (xy 72.811386 -15.523718) (xy 72.807068 -15.523464)
			(xy 72.103234 -15.523464) (xy 72.09317 -15.523028) (xy 72.074586 -15.515293) (xy 72.067166 -15.508478)
			(xy 69.914008 -13.355574) (xy 69.906896 -13.348208) (xy 69.8881 -13.340588) (xy 67.809618 -13.340588)
			(xy 67.783202 -13.359638) (xy 67.778122 -13.375386) (xy 67.764241 -13.415962) (xy 67.729736 -13.494479)
			(xy 67.687834 -13.56931) (xy 67.638924 -13.63976) (xy 67.583458 -13.705175) (xy 67.521954 -13.764947)
			(xy 67.454982 -13.818521) (xy 67.383164 -13.8654) (xy 67.307166 -13.905147) (xy 67.227696 -13.937395)
			(xy 67.14549 -13.961843) (xy 67.061313 -13.978265) (xy 66.975946 -13.986507) (xy 66.933064 -13.987018)
			(xy 66.894774 -13.98661) (xy 66.818479 -13.980007) (xy 66.743036 -13.96686) (xy 66.669004 -13.947269)
			(xy 66.632836 -13.934694) (xy 66.624398 -13.932052) (xy 66.60673 -13.932052) (xy 66.598292 -13.934694)
			(xy 66.562114 -13.947239) (xy 66.488082 -13.966817) (xy 66.412643 -13.979967) (xy 66.336352 -13.98659)
			(xy 66.298064 -13.987018) (xy 66.254268 -13.9865) (xy 66.167098 -13.977897) (xy 66.081199 -13.960757)
			(xy 65.997403 -13.935249) (xy 65.916523 -13.901618) (xy 65.877694 -13.881354) (xy 65.866228 -13.875936)
			(xy 65.8409 -13.875936) (xy 65.829434 -13.881354) (xy 65.79059 -13.901586) (xy 65.709706 -13.935193)
			(xy 65.625912 -13.960696) (xy 65.54002 -13.977848) (xy 65.452858 -13.986484) (xy 65.409064 -13.987018)
			(xy 65.365268 -13.9865) (xy 65.278098 -13.977897) (xy 65.192199 -13.960757) (xy 65.108403 -13.935249)
			(xy 65.027523 -13.901618) (xy 64.988694 -13.881354) (xy 64.977228 -13.875936) (xy 64.9519 -13.875936)
			(xy 64.940434 -13.881354) (xy 64.90159 -13.901586) (xy 64.820706 -13.935193) (xy 64.736912 -13.960696)
			(xy 64.65102 -13.977848) (xy 64.563858 -13.986484) (xy 64.520064 -13.987018) (xy 64.476268 -13.9865)
			(xy 64.389098 -13.977897) (xy 64.303199 -13.960757) (xy 64.219403 -13.935249) (xy 64.138523 -13.901618)
			(xy 64.099694 -13.881354) (xy 64.088228 -13.875936) (xy 64.0629 -13.875936) (xy 64.051434 -13.881354)
			(xy 64.01259 -13.901586) (xy 63.931706 -13.935193) (xy 63.847912 -13.960696) (xy 63.76202 -13.977848)
			(xy 63.674858 -13.986484) (xy 63.631064 -13.987018) (xy 63.588183 -13.986503) (xy 63.502819 -13.978247)
			(xy 63.418646 -13.961815) (xy 63.336444 -13.93736) (xy 63.256977 -13.905109) (xy 63.180982 -13.865361)
			(xy 63.109164 -13.818484) (xy 63.042191 -13.764915) (xy 62.980682 -13.705149) (xy 62.925211 -13.639743)
			(xy 62.87629 -13.569302) (xy 62.834374 -13.49448) (xy 62.799853 -13.415973) (xy 62.786006 -13.375386)
			(xy 62.780926 -13.359638) (xy 62.75451 -13.340588) (xy 61.834014 -13.340588) (xy 61.821507 -13.341234)
			(xy 61.799403 -13.35295) (xy 61.79185 -13.36294) (xy 61.737748 -13.442696) (xy 61.734954 -13.467588)
			(xy 61.73978 -13.479272) (xy 61.75482 -13.518351) (xy 61.778337 -13.598721) (xy 61.794183 -13.680947)
			(xy 61.802219 -13.764301) (xy 61.802772 -13.80617) (xy 61.802772 -13.80871) (xy 61.802278 -13.850853)
			(xy 61.794307 -13.934762) (xy 61.778438 -14.01754) (xy 61.754812 -14.098448) (xy 61.723642 -14.176759)
			(xy 61.685207 -14.251771) (xy 61.639851 -14.322813) (xy 61.614304 -14.356334) (xy 61.609224 -14.362938)
			(xy 61.600842 -14.386306) (xy 61.599546 -14.390375) (xy 61.598146 -14.3988) (xy 61.598048 -14.40307)
			(xy 61.598048 -14.84884) (xy 61.598495 -14.858982) (xy 61.606339 -14.877688) (xy 61.620796 -14.891916)
			(xy 61.630052 -14.896084) (xy 61.732414 -14.936978) (xy 61.76264 -14.93012) (xy 61.773562 -14.91869)
			(xy 61.791658 -14.900126) (xy 61.831996 -14.867564) (xy 61.87637 -14.84076) (xy 61.923964 -14.82021)
			(xy 61.973902 -14.80629) (xy 62.025264 -14.799258) (xy 62.051184 -14.798802) (xy 62.078437 -14.799264)
			(xy 62.132388 -14.807019) (xy 62.184687 -14.822373) (xy 62.234267 -14.845014) (xy 62.280121 -14.874481)
			(xy 62.321315 -14.910174) (xy 62.357009 -14.951366) (xy 62.386478 -14.997219) (xy 62.409121 -15.046798)
			(xy 62.424477 -15.099096) (xy 62.432235 -15.153047) (xy 62.432235 -15.207553) (xy 62.424477 -15.261504)
			(xy 62.409121 -15.313802) (xy 62.386478 -15.363381) (xy 62.357009 -15.409234) (xy 62.321315 -15.450426)
			(xy 62.280121 -15.486119) (xy 62.234267 -15.515586) (xy 62.184687 -15.538227) (xy 62.132388 -15.553581)
			(xy 62.078437 -15.561336) (xy 62.051184 -15.561818) (xy 62.02526 -15.561388) (xy 61.973889 -15.554374)
			(xy 61.923942 -15.540464) (xy 61.87634 -15.519915) (xy 61.831962 -15.493105) (xy 61.791625 -15.460529)
			(xy 61.773562 -15.44193) (xy 61.76264 -15.4305) (xy 61.732414 -15.423642) (xy 61.630052 -15.464536)
			(xy 61.620789 -15.468698) (xy 61.606311 -15.482916) (xy 61.598476 -15.501634) (xy 61.598048 -15.51178)
			(xy 61.598048 -16.259302) (xy 61.598473 -16.269371) (xy 61.606193 -16.28797) (xy 61.613034 -16.29537)
			(xy 61.670946 -16.353282) (xy 61.689742 -16.360902) (xy 61.699902 -16.360902) (xy 61.70168 -16.360902)
			(xy 61.748481 -16.361501) (xy 61.841567 -16.371328) (xy 61.933106 -16.390876) (xy 61.977778 -16.404844)
			(xy 61.984474 -16.406764) (xy 61.99839 -16.407278) (xy 62.00521 -16.40586) (xy 62.056261 -16.394427)
			(xy 62.160164 -16.382205) (xy 62.212474 -16.381476) (xy 62.212728 -16.381476) (xy 62.257831 -16.382068)
			(xy 62.347571 -16.391235) (xy 62.435924 -16.40943) (xy 62.521984 -16.436467) (xy 62.604868 -16.47207)
			(xy 62.683727 -16.515873) (xy 62.757751 -16.567426) (xy 62.792356 -16.59636) (xy 62.802008 -16.602964)
			(xy 62.806272 -16.605019) (xy 62.815346 -16.607706) (xy 62.820042 -16.608298) (xy 62.837059 -16.602421)
			(xy 62.871487 -16.591878) (xy 62.888876 -16.587216) (xy 62.894691 -16.585499) (xy 62.905348 -16.579724)
			(xy 62.909958 -16.575786) (xy 62.940526 -16.548954) (xy 63.005764 -16.500367) (xy 63.075164 -16.457939)
			(xy 63.148149 -16.422024) (xy 63.224108 -16.392923) (xy 63.302407 -16.370879) (xy 63.382391 -16.356076)
			(xy 63.463393 -16.348637) (xy 63.504064 -16.348202) (xy 63.545168 -16.348661) (xy 63.627026 -16.356243)
			(xy 63.707835 -16.371346) (xy 63.786905 -16.39384) (xy 63.863563 -16.423535) (xy 63.937153 -16.460177)
			(xy 64.007049 -16.503452) (xy 64.072654 -16.552992) (xy 64.133407 -16.608375) (xy 64.188791 -16.669126)
			(xy 64.238333 -16.734729) (xy 64.281611 -16.804624) (xy 64.318254 -16.878213) (xy 64.347951 -16.95487)
			(xy 64.370448 -17.03394) (xy 64.385554 -17.114748) (xy 64.393138 -17.196606) (xy 64.393572 -17.23771)
			(xy 64.393102 -17.279429) (xy 64.385295 -17.3625) (xy 64.369743 -17.444475) (xy 64.346581 -17.524632)
			(xy 64.316014 -17.602269) (xy 64.278309 -17.676701) (xy 64.233799 -17.747274) (xy 64.182875 -17.813369)
			(xy 64.125985 -17.874403) (xy 64.063627 -17.929841) (xy 63.996352 -17.979194) (xy 63.92475 -18.02203)
			(xy 63.849451 -18.057971) (xy 63.771116 -18.086702) (xy 63.730886 -18.097754) (xy 63.725152 -18.099526)
			(xy 63.714641 -18.105309) (xy 63.710058 -18.109184) (xy 63.677124 -18.13804) (xy 63.606523 -18.189847)
			(xy 63.531175 -18.234467) (xy 63.451807 -18.271468) (xy 63.369187 -18.300492) (xy 63.326772 -18.311368)
			(xy 63.317919 -18.31393) (xy 63.302708 -18.324313) (xy 63.292119 -18.339381) (xy 63.289434 -18.348198)
			(xy 63.282016 -18.375198) (xy 63.260355 -18.42683) (xy 63.231381 -18.474743) (xy 63.195715 -18.517906)
			(xy 63.194987 -18.518562) (xy 67.655436 -18.518562) (xy 67.655436 -18.433866) (xy 67.663487 -18.349552)
			(xy 67.679516 -18.266386) (xy 67.703377 -18.185119) (xy 67.734856 -18.106489) (xy 67.773667 -18.031208)
			(xy 67.819457 -17.959956) (xy 67.871813 -17.89338) (xy 67.930261 -17.832082) (xy 67.994271 -17.776617)
			(xy 68.063263 -17.727488) (xy 68.136613 -17.685139) (xy 68.213656 -17.649955) (xy 68.293695 -17.622253)
			(xy 68.376004 -17.602285) (xy 68.459839 -17.590232) (xy 68.54444 -17.586202) (xy 68.629041 -17.590232)
			(xy 68.712876 -17.602285) (xy 68.795185 -17.622253) (xy 68.875224 -17.649955) (xy 68.952267 -17.685139)
			(xy 69.025617 -17.727488) (xy 69.094609 -17.776617) (xy 69.158619 -17.832082) (xy 69.217067 -17.89338)
			(xy 69.269423 -17.959956) (xy 69.315213 -18.031208) (xy 69.354024 -18.106489) (xy 69.385503 -18.185119)
			(xy 69.409364 -18.266386) (xy 69.425393 -18.349552) (xy 69.433444 -18.433866) (xy 69.433948 -18.476214)
			(xy 69.43377 -18.4912) (xy 74.232262 -18.4912) (xy 74.232808 -18.448529) (xy 74.240982 -18.363579)
			(xy 74.257255 -18.279803) (xy 74.281476 -18.19797) (xy 74.313425 -18.118833) (xy 74.352806 -18.043121)
			(xy 74.399257 -17.971528) (xy 74.452352 -17.904713) (xy 74.511602 -17.843291) (xy 74.576463 -17.787826)
			(xy 74.646338 -17.738828) (xy 74.720585 -17.696748) (xy 74.79852 -17.661973) (xy 74.838814 -17.64792)
			(xy 74.849466 -17.643697) (xy 74.865885 -17.627756) (xy 74.873802 -17.606285) (xy 74.873358 -17.594834)
			(xy 74.87158 -17.558512) (xy 74.872066 -17.531261) (xy 74.879822 -17.477313) (xy 74.895177 -17.425018)
			(xy 74.917819 -17.375441) (xy 74.947285 -17.329591) (xy 74.982976 -17.2884) (xy 75.024167 -17.252709)
			(xy 75.070017 -17.223243) (xy 75.119594 -17.200601) (xy 75.171889 -17.185246) (xy 75.225837 -17.17749)
			(xy 75.280339 -17.17749) (xy 75.334287 -17.185246) (xy 75.386582 -17.200601) (xy 75.436159 -17.223243)
			(xy 75.482009 -17.252709) (xy 75.5232 -17.2884) (xy 75.558891 -17.329591) (xy 75.588357 -17.375441)
			(xy 75.610999 -17.425018) (xy 75.626354 -17.477313) (xy 75.63411 -17.531261) (xy 75.634596 -17.558512)
			(xy 75.634245 -17.582355) (xy 75.628321 -17.629672) (xy 75.616553 -17.675884) (xy 75.60818 -17.698212)
			(xy 75.604528 -17.709037) (xy 75.606167 -17.731801) (xy 75.617456 -17.751637) (xy 75.626468 -17.758664)
			(xy 75.661973 -17.783798) (xy 75.728437 -17.83993) (xy 75.789106 -17.90228) (xy 75.843402 -17.970251)
			(xy 75.890807 -18.043196) (xy 75.930868 -18.120419) (xy 75.963203 -18.201182) (xy 75.987504 -18.284714)
			(xy 75.996038 -18.32737) (xy 75.99807 -18.3388) (xy 76.011786 -18.357088) (xy 76.101702 -18.405602)
			(xy 76.124816 -18.406618) (xy 76.135484 -18.402046) (xy 76.176588 -18.385277) (xy 76.261424 -18.359109)
			(xy 76.348446 -18.341529) (xy 76.436788 -18.332715) (xy 76.481178 -18.332196) (xy 76.519228 -18.332603)
			(xy 76.59505 -18.339103) (xy 76.67004 -18.352057) (xy 76.743648 -18.371371) (xy 76.779628 -18.383758)
			(xy 76.788671 -18.386584) (xy 76.807592 -18.386078) (xy 76.816458 -18.382742) (xy 76.844144 -18.371058)
			(xy 76.852714 -18.367033) (xy 76.866288 -18.353853) (xy 76.87056 -18.345404) (xy 76.888685 -18.307284)
			(xy 76.931153 -18.234331) (xy 76.980341 -18.165729) (xy 77.035806 -18.102094) (xy 77.09705 -18.044001)
			(xy 77.163522 -17.99197) (xy 77.234624 -17.94647) (xy 77.309716 -17.907911) (xy 77.388123 -17.876638)
			(xy 77.469141 -17.852933) (xy 77.552039 -17.83701) (xy 77.636073 -17.829012) (xy 77.67828 -17.828514)
			(xy 77.718904 -17.829005) (xy 77.799814 -17.836411) (xy 77.879712 -17.851162) (xy 77.957932 -17.873137)
			(xy 78.033822 -17.902151) (xy 78.106752 -17.937964) (xy 78.176112 -17.980277) (xy 78.241326 -18.028738)
			(xy 78.30185 -18.082942) (xy 78.35718 -18.142438) (xy 78.406855 -18.206732) (xy 78.450461 -18.275286)
			(xy 78.487636 -18.347531) (xy 78.503272 -18.385028) (xy 78.507191 -18.393638) (xy 78.5201 -18.407444)
			(xy 78.528418 -18.411952) (xy 78.555596 -18.424906) (xy 78.564331 -18.428603) (xy 78.58323 -18.430026)
			(xy 78.592426 -18.4277) (xy 78.635129 -18.415046) (xy 78.722415 -18.39731) (xy 78.811035 -18.388381)
			(xy 78.85557 -18.387822) (xy 78.897922 -18.388249) (xy 78.982241 -18.396298) (xy 79.065414 -18.412325)
			(xy 79.146687 -18.436187) (xy 79.225324 -18.467666) (xy 79.300612 -18.506477) (xy 79.371869 -18.55227)
			(xy 79.438452 -18.604628) (xy 79.499755 -18.663079) (xy 79.555225 -18.727093) (xy 79.604359 -18.796089)
			(xy 79.646711 -18.869444) (xy 79.681899 -18.946492) (xy 79.709603 -19.026536) (xy 79.729573 -19.108852)
			(xy 79.741628 -19.192693) (xy 79.745658 -19.2773) (xy 79.741628 -19.361907) (xy 79.729573 -19.445748)
			(xy 79.709603 -19.528064) (xy 79.681899 -19.608108) (xy 79.646711 -19.685156) (xy 79.604359 -19.758511)
			(xy 79.555225 -19.827507) (xy 79.499755 -19.891521) (xy 79.438452 -19.949972) (xy 79.371869 -20.00233)
			(xy 79.300612 -20.048123) (xy 79.225324 -20.086934) (xy 79.146687 -20.118413) (xy 79.065414 -20.142275)
			(xy 78.982241 -20.158302) (xy 78.897922 -20.166351) (xy 78.85557 -20.166838) (xy 78.814944 -20.166421)
			(xy 78.734031 -20.15901) (xy 78.654131 -20.144254) (xy 78.575909 -20.122273) (xy 78.500016 -20.093253)
			(xy 78.427086 -20.057434) (xy 78.357725 -20.015115) (xy 78.292512 -19.966648) (xy 78.231988 -19.912437)
			(xy 78.17666 -19.852935) (xy 78.126987 -19.788635) (xy 78.083383 -19.720074) (xy 78.046212 -19.647824)
			(xy 78.030578 -19.610324) (xy 78.026625 -19.601733) (xy 78.01374 -19.587916) (xy 78.005432 -19.5834)
			(xy 77.978254 -19.570446) (xy 77.96951 -19.566775) (xy 77.950619 -19.565336) (xy 77.941424 -19.567652)
			(xy 77.898725 -19.58032) (xy 77.811437 -19.59805) (xy 77.722815 -19.606974) (xy 77.67828 -19.60753)
			(xy 77.64023 -19.607134) (xy 77.564407 -19.60063) (xy 77.489418 -19.587673) (xy 77.415809 -19.568357)
			(xy 77.37983 -19.555968) (xy 77.370793 -19.553118) (xy 77.351866 -19.553639) (xy 77.343 -19.556984)
			(xy 77.315314 -19.568668) (xy 77.306749 -19.572702) (xy 77.293171 -19.585874) (xy 77.288898 -19.594322)
			(xy 77.27115 -19.631643) (xy 77.229678 -19.703133) (xy 77.206094 -19.73707) (xy 77.200506 -19.744944)
			(xy 77.195934 -19.763232) (xy 77.206348 -19.8501) (xy 77.215238 -19.86661) (xy 77.22235 -19.87296)
			(xy 77.242703 -19.891142) (xy 77.278503 -19.932337) (xy 77.308061 -19.978215) (xy 77.330776 -20.02784)
			(xy 77.346182 -20.080197) (xy 77.353964 -20.134216) (xy 77.35443 -20.161504) (xy 77.353892 -20.19005)
			(xy 77.345374 -20.246504) (xy 77.328542 -20.301059) (xy 77.303773 -20.352499) (xy 77.288136 -20.376388)
			(xy 77.282126 -20.386323) (xy 77.27881 -20.409277) (xy 77.285868 -20.431368) (xy 77.29347 -20.440142)
			(xy 77.322601 -20.471192) (xy 77.375459 -20.537945) (xy 77.421699 -20.609442) (xy 77.460897 -20.685029)
			(xy 77.492695 -20.764015) (xy 77.516801 -20.845678) (xy 77.532995 -20.92927) (xy 77.541129 -21.014027)
			(xy 77.541628 -21.0566) (xy 77.54111 -21.09857) (xy 77.53322 -21.182138) (xy 77.517492 -21.26459)
			(xy 77.494064 -21.345194) (xy 77.463146 -21.423232) (xy 77.425013 -21.49801) (xy 77.380004 -21.568862)
			(xy 77.32852 -21.635158) (xy 77.271018 -21.696309) (xy 77.20801 -21.751769) (xy 77.140057 -21.801046)
			(xy 77.067763 -21.843701) (xy 76.991772 -21.879355) (xy 76.91276 -21.907691) (xy 76.831429 -21.928455)
			(xy 76.790042 -21.93544) (xy 76.777342 -21.937218) (xy 76.75753 -21.952204) (xy 76.710286 -22.050502)
			(xy 76.711302 -22.075394) (xy 76.717652 -22.086316) (xy 76.740279 -22.12687) (xy 76.777909 -22.211777)
			(xy 76.806498 -22.30014) (xy 76.825735 -22.390997) (xy 76.835411 -22.483364) (xy 76.836016 -22.5298)
			(xy 76.835585 -22.571119) (xy 76.827906 -22.6534) (xy 76.812632 -22.734614) (xy 76.789894 -22.814063)
			(xy 76.75989 -22.891061) (xy 76.722876 -22.964947) (xy 76.679172 -23.035083) (xy 76.629155 -23.100865)
			(xy 76.573254 -23.161728) (xy 76.511952 -23.217146) (xy 76.479146 -23.24227) (xy 76.472222 -23.247833)
			(xy 76.46247 -23.262667) (xy 76.460096 -23.271226) (xy 76.453238 -23.300182) (xy 76.451608 -23.308584)
			(xy 76.453418 -23.325592) (xy 76.456794 -23.333456) (xy 76.468356 -23.359066) (xy 76.484643 -23.412845)
			(xy 76.492874 -23.468429) (xy 76.49337 -23.496524) (xy 76.492884 -23.523775) (xy 76.485128 -23.577723)
			(xy 76.469773 -23.630018) (xy 76.447131 -23.679595) (xy 76.417665 -23.725445) (xy 76.381974 -23.766636)
			(xy 76.340783 -23.802327) (xy 76.294933 -23.831793) (xy 76.245356 -23.854435) (xy 76.193061 -23.86979)
			(xy 76.139113 -23.877546) (xy 76.084611 -23.877546) (xy 76.030663 -23.86979) (xy 75.978368 -23.854435)
			(xy 75.928791 -23.831793) (xy 75.882941 -23.802327) (xy 75.84175 -23.766636) (xy 75.806059 -23.725445)
			(xy 75.776593 -23.679595) (xy 75.753951 -23.630018) (xy 75.738596 -23.577723) (xy 75.73084 -23.523775)
			(xy 75.730354 -23.496524) (xy 75.730421 -23.486727) (xy 75.731436 -23.467159) (xy 75.732386 -23.457408)
			(xy 75.732877 -23.448872) (xy 75.728853 -23.432263) (xy 75.724512 -23.424896) (xy 75.70851 -23.39975)
			(xy 75.703416 -23.392507) (xy 75.68939 -23.381721) (xy 75.681078 -23.378668) (xy 75.63985 -23.365172)
			(xy 75.559959 -23.331355) (xy 75.483741 -23.289919) (xy 75.411919 -23.241259) (xy 75.345176 -23.185838)
			(xy 75.284147 -23.124181) (xy 75.229411 -23.056875) (xy 75.181488 -22.984559) (xy 75.140834 -22.90792)
			(xy 75.107836 -22.827688) (xy 75.082806 -22.744624) (xy 75.065983 -22.659517) (xy 75.057526 -22.573177)
			(xy 75.057 -22.5298) (xy 75.057494 -22.487829) (xy 75.065384 -22.40426) (xy 75.081114 -22.321806)
			(xy 75.104542 -22.241201) (xy 75.135461 -22.163162) (xy 75.173596 -22.088383) (xy 75.218606 -22.017531)
			(xy 75.270093 -21.951234) (xy 75.327597 -21.890084) (xy 75.390607 -21.834624) (xy 75.458562 -21.785347)
			(xy 75.530858 -21.742693) (xy 75.606851 -21.70704) (xy 75.685865 -21.678706) (xy 75.767198 -21.657943)
			(xy 75.808586 -21.65096) (xy 75.821286 -21.649182) (xy 75.841098 -21.634196) (xy 75.888342 -21.535898)
			(xy 75.887326 -21.511006) (xy 75.880976 -21.500084) (xy 75.858351 -21.459528) (xy 75.82072 -21.374622)
			(xy 75.792131 -21.28626) (xy 75.772893 -21.195402) (xy 75.763217 -21.103036) (xy 75.762612 -21.0566)
			(xy 75.763054 -21.015482) (xy 75.770647 -20.933596) (xy 75.785769 -20.852761) (xy 75.80829 -20.773668)
			(xy 75.838018 -20.696992) (xy 75.874698 -20.623388) (xy 75.918018 -20.553486) (xy 75.942444 -20.520406)
			(xy 75.947966 -20.51244) (xy 75.953053 -20.493752) (xy 75.95235 -20.484084) (xy 75.948794 -20.453604)
			(xy 75.947355 -20.444381) (xy 75.938741 -20.427836) (xy 75.93203 -20.421346) (xy 75.912273 -20.40315)
			(xy 75.877544 -20.362178) (xy 75.8489 -20.316742) (xy 75.826908 -20.26774) (xy 75.812 -20.21614)
			(xy 75.804471 -20.162959) (xy 75.804014 -20.136104) (xy 75.8045 -20.108014) (xy 75.812745 -20.052443)
			(xy 75.829057 -19.998683) (xy 75.853083 -19.9479) (xy 75.868276 -19.924268) (xy 75.874278 -19.914104)
			(xy 75.877174 -19.890704) (xy 75.869411 -19.868439) (xy 75.861418 -19.859752) (xy 75.829118 -19.827595)
			(xy 75.770579 -19.757729) (xy 75.719492 -19.682242) (xy 75.676392 -19.601927) (xy 75.64173 -19.517626)
			(xy 75.61587 -19.430223) (xy 75.60691 -19.385534) (xy 75.604878 -19.374104) (xy 75.591162 -19.355816)
			(xy 75.501246 -19.307302) (xy 75.478132 -19.306286) (xy 75.467464 -19.310858) (xy 75.426354 -19.327612)
			(xy 75.34152 -19.353784) (xy 75.2545 -19.371368) (xy 75.16616 -19.380187) (xy 75.12177 -19.380708)
			(xy 75.080667 -19.380262) (xy 74.998812 -19.372674) (xy 74.918006 -19.357567) (xy 74.838939 -19.335068)
			(xy 74.762285 -19.30537) (xy 74.688698 -19.268725) (xy 74.618806 -19.225448) (xy 74.553205 -19.175907)
			(xy 74.492455 -19.120524) (xy 74.437074 -19.059772) (xy 74.387535 -18.994169) (xy 74.34426 -18.924276)
			(xy 74.307618 -18.850688) (xy 74.277923 -18.774033) (xy 74.255426 -18.694965) (xy 74.240321 -18.614158)
			(xy 74.232737 -18.532303) (xy 74.232262 -18.4912) (xy 69.43377 -18.4912) (xy 69.433444 -18.518562)
			(xy 69.425393 -18.602876) (xy 69.409364 -18.686042) (xy 69.385503 -18.767309) (xy 69.354024 -18.845939)
			(xy 69.315213 -18.92122) (xy 69.269423 -18.992472) (xy 69.217067 -19.059048) (xy 69.158619 -19.120346)
			(xy 69.094609 -19.175811) (xy 69.025617 -19.22494) (xy 68.952267 -19.267289) (xy 68.875224 -19.302473)
			(xy 68.795185 -19.330175) (xy 68.712876 -19.350143) (xy 68.629041 -19.362196) (xy 68.54444 -19.366227)
			(xy 68.459839 -19.362196) (xy 68.376004 -19.350143) (xy 68.293695 -19.330175) (xy 68.213656 -19.302473)
			(xy 68.136613 -19.267289) (xy 68.063263 -19.22494) (xy 67.994271 -19.175811) (xy 67.930261 -19.120346)
			(xy 67.871813 -19.059048) (xy 67.819457 -18.992472) (xy 67.773667 -18.92122) (xy 67.734856 -18.845939)
			(xy 67.703377 -18.767309) (xy 67.679516 -18.686042) (xy 67.663487 -18.602876) (xy 67.655436 -18.518562)
			(xy 63.194987 -18.518562) (xy 63.154124 -18.555393) (xy 63.107501 -18.586399) (xy 63.056847 -18.610258)
			(xy 63.003249 -18.626458) (xy 62.94786 -18.63465) (xy 62.919864 -18.635218) (xy 62.892614 -18.63473)
			(xy 62.83867 -18.626969) (xy 62.786379 -18.611611) (xy 62.736805 -18.588968) (xy 62.690959 -18.559501)
			(xy 62.649772 -18.523809) (xy 62.614084 -18.48262) (xy 62.58462 -18.436772) (xy 62.56198 -18.387197)
			(xy 62.546625 -18.334905) (xy 62.538868 -18.28096) (xy 62.538356 -18.25371) (xy 62.53861 -18.23974)
			(xy 62.539118 -18.228056) (xy 62.529212 -18.206466) (xy 62.448948 -18.140172) (xy 62.425834 -18.134584)
			(xy 62.41415 -18.137378) (xy 62.364558 -18.148168) (xy 62.263728 -18.159756) (xy 62.212982 -18.160492)
			(xy 62.212474 -18.160492) (xy 62.165672 -18.159895) (xy 62.072586 -18.15007) (xy 61.981047 -18.130521)
			(xy 61.936376 -18.11655) (xy 61.929676 -18.114645) (xy 61.915763 -18.114118) (xy 61.908944 -18.115534)
			(xy 61.85916 -18.125948) (xy 61.847476 -18.12798) (xy 61.786516 -18.173192) (xy 61.775848 -18.195798)
			(xy 61.776356 -18.208752) (xy 61.777372 -18.25371) (xy 61.776913 -18.293606) (xy 61.769745 -18.373076)
			(xy 61.755495 -18.451586) (xy 61.734277 -18.528506) (xy 61.706261 -18.603219) (xy 61.671672 -18.675125)
			(xy 61.630787 -18.743647) (xy 61.6077 -18.776188) (xy 61.60262 -18.7833) (xy 61.598048 -18.798794)
			(xy 61.598048 -19.26971) (xy 62.537846 -19.26971) (xy 62.541917 -19.214088) (xy 62.554043 -19.159651)
			(xy 62.573966 -19.10756) (xy 62.601262 -19.058925) (xy 62.635348 -19.014782) (xy 62.675497 -18.976073)
			(xy 62.720855 -18.943622) (xy 62.770455 -18.918121) (xy 62.823239 -18.900114) (xy 62.878082 -18.889984)
			(xy 62.933816 -18.887947) (xy 62.989253 -18.894047) (xy 63.04321 -18.908153) (xy 63.094539 -18.929965)
			(xy 63.142145 -18.959019) (xy 63.185013 -18.994694) (xy 63.22223 -19.036231) (xy 63.253003 -19.082744)
			(xy 63.276675 -19.133241) (xy 63.292743 -19.186648) (xy 63.300863 -19.241824) (xy 63.301372 -19.26971)
			(xy 63.300863 -19.297596) (xy 63.292743 -19.352772) (xy 63.276675 -19.406179) (xy 63.253003 -19.456676)
			(xy 63.22223 -19.503189) (xy 63.185013 -19.544726) (xy 63.142145 -19.580401) (xy 63.094539 -19.609455)
			(xy 63.04321 -19.631267) (xy 62.989253 -19.645373) (xy 62.933816 -19.651473) (xy 62.878082 -19.649436)
			(xy 62.823239 -19.639306) (xy 62.770455 -19.621299) (xy 62.720855 -19.595798) (xy 62.675497 -19.563347)
			(xy 62.635348 -19.524638) (xy 62.601262 -19.480495) (xy 62.573966 -19.43186) (xy 62.554043 -19.379769)
			(xy 62.541917 -19.325332) (xy 62.537846 -19.26971) (xy 61.598048 -19.26971) (xy 61.598048 -19.958304)
			(xy 74.152504 -19.958304) (xy 74.156575 -19.902682) (xy 74.168701 -19.848245) (xy 74.188624 -19.796154)
			(xy 74.21592 -19.747519) (xy 74.250006 -19.703376) (xy 74.290155 -19.664667) (xy 74.335513 -19.632216)
			(xy 74.385113 -19.606715) (xy 74.437897 -19.588708) (xy 74.49274 -19.578578) (xy 74.548474 -19.576541)
			(xy 74.603911 -19.582641) (xy 74.657868 -19.596747) (xy 74.709197 -19.618559) (xy 74.756803 -19.647613)
			(xy 74.799671 -19.683288) (xy 74.836888 -19.724825) (xy 74.867661 -19.771338) (xy 74.891333 -19.821835)
			(xy 74.907401 -19.875242) (xy 74.915521 -19.930418) (xy 74.91603 -19.958304) (xy 74.915521 -19.98619)
			(xy 74.907401 -20.041366) (xy 74.891333 -20.094773) (xy 74.867661 -20.14527) (xy 74.836888 -20.191783)
			(xy 74.799671 -20.23332) (xy 74.756803 -20.268995) (xy 74.709197 -20.298049) (xy 74.657868 -20.319861)
			(xy 74.603911 -20.333967) (xy 74.548474 -20.340067) (xy 74.49274 -20.33803) (xy 74.437897 -20.3279)
			(xy 74.385113 -20.309893) (xy 74.335513 -20.284392) (xy 74.290155 -20.251941) (xy 74.250006 -20.213232)
			(xy 74.21592 -20.169089) (xy 74.188624 -20.120454) (xy 74.168701 -20.068363) (xy 74.156575 -20.013926)
			(xy 74.152504 -19.958304) (xy 61.598048 -19.958304) (xy 61.598048 -21.0881) (xy 69.020483 -21.0881)
			(xy 69.024513 -21.003501) (xy 69.036566 -20.919669) (xy 69.056533 -20.837362) (xy 69.084233 -20.757325)
			(xy 69.119415 -20.680284) (xy 69.161761 -20.606935) (xy 69.210887 -20.537944) (xy 69.266349 -20.473935)
			(xy 69.327643 -20.415488) (xy 69.394216 -20.363131) (xy 69.465464 -20.317339) (xy 69.540742 -20.278527)
			(xy 69.619368 -20.247046) (xy 69.700631 -20.223181) (xy 69.783794 -20.207149) (xy 69.868105 -20.199094)
			(xy 69.910452 -20.198588) (xy 69.952896 -20.19906) (xy 70.037397 -20.207152) (xy 70.120743 -20.223257)
			(xy 70.202175 -20.247229) (xy 70.280954 -20.278849) (xy 70.318884 -20.297902) (xy 70.330048 -20.302883)
			(xy 70.354456 -20.302883) (xy 70.36562 -20.297902) (xy 70.403559 -20.278868) (xy 70.482336 -20.247249)
			(xy 70.563766 -20.223278) (xy 70.64711 -20.207174) (xy 70.731609 -20.199083) (xy 70.774052 -20.198588)
			(xy 70.816403 -20.199082) (xy 70.90072 -20.207129) (xy 70.983892 -20.223155) (xy 71.065163 -20.247014)
			(xy 71.143798 -20.278491) (xy 71.219084 -20.317301) (xy 71.290341 -20.363091) (xy 71.356922 -20.415448)
			(xy 71.418225 -20.473896) (xy 71.473694 -20.537908) (xy 71.522826 -20.606902) (xy 71.565178 -20.680254)
			(xy 71.600365 -20.757301) (xy 71.628069 -20.837343) (xy 71.648039 -20.919656) (xy 71.65261 -20.951444)
			(xy 74.153774 -20.951444) (xy 74.157845 -20.895822) (xy 74.169971 -20.841385) (xy 74.189894 -20.789294)
			(xy 74.21719 -20.740659) (xy 74.251276 -20.696516) (xy 74.291425 -20.657807) (xy 74.336783 -20.625356)
			(xy 74.386383 -20.599855) (xy 74.439167 -20.581848) (xy 74.49401 -20.571718) (xy 74.549744 -20.569681)
			(xy 74.605181 -20.575781) (xy 74.659138 -20.589887) (xy 74.710467 -20.611699) (xy 74.758073 -20.640753)
			(xy 74.800941 -20.676428) (xy 74.838158 -20.717965) (xy 74.868931 -20.764478) (xy 74.892603 -20.814975)
			(xy 74.908671 -20.868382) (xy 74.916791 -20.923558) (xy 74.9173 -20.951444) (xy 74.916791 -20.97933)
			(xy 74.908671 -21.034506) (xy 74.892603 -21.087913) (xy 74.868931 -21.13841) (xy 74.838158 -21.184923)
			(xy 74.800941 -21.22646) (xy 74.758073 -21.262135) (xy 74.710467 -21.291189) (xy 74.659138 -21.313001)
			(xy 74.605181 -21.327107) (xy 74.549744 -21.333207) (xy 74.49401 -21.33117) (xy 74.439167 -21.32104)
			(xy 74.386383 -21.303033) (xy 74.336783 -21.277532) (xy 74.291425 -21.245081) (xy 74.251276 -21.206372)
			(xy 74.21719 -21.162229) (xy 74.189894 -21.113594) (xy 74.169971 -21.061503) (xy 74.157845 -21.007066)
			(xy 74.153774 -20.951444) (xy 71.65261 -20.951444) (xy 71.660094 -21.003495) (xy 71.664124 -21.0881)
			(xy 71.660094 -21.172705) (xy 71.648039 -21.256544) (xy 71.628069 -21.338857) (xy 71.600365 -21.418899)
			(xy 71.565178 -21.495946) (xy 71.522826 -21.569298) (xy 71.473694 -21.638292) (xy 71.418225 -21.702304)
			(xy 71.356922 -21.760752) (xy 71.290341 -21.813109) (xy 71.247803 -21.840444) (xy 74.153774 -21.840444)
			(xy 74.157845 -21.784822) (xy 74.169971 -21.730385) (xy 74.189894 -21.678294) (xy 74.21719 -21.629659)
			(xy 74.251276 -21.585516) (xy 74.291425 -21.546807) (xy 74.336783 -21.514356) (xy 74.386383 -21.488855)
			(xy 74.439167 -21.470848) (xy 74.49401 -21.460718) (xy 74.549744 -21.458681) (xy 74.605181 -21.464781)
			(xy 74.659138 -21.478887) (xy 74.710467 -21.500699) (xy 74.758073 -21.529753) (xy 74.800941 -21.565428)
			(xy 74.838158 -21.606965) (xy 74.868931 -21.653478) (xy 74.892603 -21.703975) (xy 74.908671 -21.757382)
			(xy 74.916791 -21.812558) (xy 74.9173 -21.840444) (xy 74.916791 -21.86833) (xy 74.908671 -21.923506)
			(xy 74.892603 -21.976913) (xy 74.868931 -22.02741) (xy 74.838158 -22.073923) (xy 74.800941 -22.11546)
			(xy 74.758073 -22.151135) (xy 74.710467 -22.180189) (xy 74.659138 -22.202001) (xy 74.605181 -22.216107)
			(xy 74.549744 -22.222207) (xy 74.49401 -22.22017) (xy 74.439167 -22.21004) (xy 74.386383 -22.192033)
			(xy 74.336783 -22.166532) (xy 74.291425 -22.134081) (xy 74.251276 -22.095372) (xy 74.21719 -22.051229)
			(xy 74.189894 -22.002594) (xy 74.169971 -21.950503) (xy 74.157845 -21.896066) (xy 74.153774 -21.840444)
			(xy 71.247803 -21.840444) (xy 71.219084 -21.858899) (xy 71.143798 -21.897709) (xy 71.065163 -21.929186)
			(xy 70.983892 -21.953045) (xy 70.90072 -21.969071) (xy 70.816403 -21.977118) (xy 70.774052 -21.977604)
			(xy 70.731608 -21.977131) (xy 70.647107 -21.969039) (xy 70.563761 -21.952935) (xy 70.482329 -21.928963)
			(xy 70.40355 -21.897343) (xy 70.36562 -21.87829) (xy 70.354456 -21.873309) (xy 70.330048 -21.873309)
			(xy 70.318884 -21.87829) (xy 70.280962 -21.897359) (xy 70.20218 -21.928972) (xy 70.120745 -21.952935)
			(xy 70.037398 -21.969031) (xy 69.952896 -21.977114) (xy 69.910452 -21.977604) (xy 69.868105 -21.977106)
			(xy 69.783794 -21.969051) (xy 69.700631 -21.953019) (xy 69.619368 -21.929154) (xy 69.540742 -21.897673)
			(xy 69.465464 -21.858861) (xy 69.394216 -21.813069) (xy 69.327643 -21.760712) (xy 69.266349 -21.702265)
			(xy 69.210887 -21.638256) (xy 69.161761 -21.569265) (xy 69.119415 -21.495916) (xy 69.084233 -21.418875)
			(xy 69.056533 -21.338838) (xy 69.036566 -21.256531) (xy 69.024513 -21.172699) (xy 69.020483 -21.0881)
			(xy 61.598048 -21.0881) (xy 61.598048 -23.447432) (xy 62.126618 -23.447432) (xy 62.126618 -23.362736)
			(xy 62.134669 -23.278422) (xy 62.150698 -23.195256) (xy 62.174559 -23.113989) (xy 62.206038 -23.035359)
			(xy 62.244849 -22.960078) (xy 62.290639 -22.888826) (xy 62.342995 -22.82225) (xy 62.401443 -22.760952)
			(xy 62.465453 -22.705487) (xy 62.534445 -22.656358) (xy 62.607795 -22.614009) (xy 62.684838 -22.578825)
			(xy 62.764877 -22.551123) (xy 62.847186 -22.531155) (xy 62.931021 -22.519102) (xy 63.015622 -22.515072)
			(xy 63.100223 -22.519102) (xy 63.184058 -22.531155) (xy 63.266367 -22.551123) (xy 63.346406 -22.578825)
			(xy 63.423449 -22.614009) (xy 63.496799 -22.656358) (xy 63.565791 -22.705487) (xy 63.629801 -22.760952)
			(xy 63.688249 -22.82225) (xy 63.740605 -22.888826) (xy 63.786395 -22.960078) (xy 63.825206 -23.035359)
			(xy 63.856685 -23.113989) (xy 63.880546 -23.195256) (xy 63.896575 -23.278422) (xy 63.904626 -23.362736)
			(xy 63.90513 -23.405084) (xy 63.904626 -23.447432) (xy 63.896575 -23.531746) (xy 63.880546 -23.614912)
			(xy 63.856685 -23.696179) (xy 63.825206 -23.774809) (xy 63.786395 -23.85009) (xy 63.740605 -23.921342)
			(xy 63.688249 -23.987918) (xy 63.629801 -24.049216) (xy 63.565791 -24.104681) (xy 63.496799 -24.15381)
			(xy 63.423449 -24.196159) (xy 63.346406 -24.231343) (xy 63.266367 -24.259045) (xy 63.184058 -24.279013)
			(xy 63.100223 -24.291066) (xy 63.015622 -24.295097) (xy 62.931021 -24.291066) (xy 62.847186 -24.279013)
			(xy 62.764877 -24.259045) (xy 62.684838 -24.231343) (xy 62.607795 -24.196159) (xy 62.534445 -24.15381)
			(xy 62.465453 -24.104681) (xy 62.401443 -24.049216) (xy 62.342995 -23.987918) (xy 62.290639 -23.921342)
			(xy 62.244849 -23.85009) (xy 62.206038 -23.774809) (xy 62.174559 -23.696179) (xy 62.150698 -23.614912)
			(xy 62.134669 -23.531746) (xy 62.126618 -23.447432) (xy 61.598048 -23.447432) (xy 61.598048 -24.12111)
			(xy 61.598505 -24.130989) (xy 61.605941 -24.149294) (xy 61.612526 -24.15667) (xy 61.61278 -24.156924)
			(xy 61.812862 -24.357006) (xy 77.29626 -24.357006) (xy 77.29626 -24.27231) (xy 77.304311 -24.187996)
			(xy 77.32034 -24.10483) (xy 77.344201 -24.023563) (xy 77.37568 -23.944933) (xy 77.414491 -23.869652)
			(xy 77.460281 -23.7984) (xy 77.512637 -23.731824) (xy 77.571085 -23.670526) (xy 77.635095 -23.615061)
			(xy 77.704087 -23.565932) (xy 77.777437 -23.523583) (xy 77.85448 -23.488399) (xy 77.934519 -23.460697)
			(xy 78.016828 -23.440729) (xy 78.100663 -23.428676) (xy 78.185264 -23.424646) (xy 78.269865 -23.428676)
			(xy 78.3537 -23.440729) (xy 78.436009 -23.460697) (xy 78.516048 -23.488399) (xy 78.593091 -23.523583)
			(xy 78.666441 -23.565932) (xy 78.735433 -23.615061) (xy 78.799443 -23.670526) (xy 78.857891 -23.731824)
			(xy 78.910247 -23.7984) (xy 78.956037 -23.869652) (xy 78.994848 -23.944933) (xy 79.026327 -24.023563)
			(xy 79.050188 -24.10483) (xy 79.066217 -24.187996) (xy 79.074268 -24.27231) (xy 79.074772 -24.314658)
			(xy 79.074268 -24.357006) (xy 79.066217 -24.44132) (xy 79.050188 -24.524486) (xy 79.026327 -24.605753)
			(xy 78.994848 -24.684383) (xy 78.956037 -24.759664) (xy 78.910247 -24.830916) (xy 78.857891 -24.897492)
			(xy 78.799443 -24.95879) (xy 78.735433 -25.014255) (xy 78.666441 -25.063384) (xy 78.593091 -25.105733)
			(xy 78.516048 -25.140917) (xy 78.436009 -25.168619) (xy 78.3537 -25.188587) (xy 78.269865 -25.20064)
			(xy 78.185264 -25.204671) (xy 78.100663 -25.20064) (xy 78.016828 -25.188587) (xy 77.934519 -25.168619)
			(xy 77.85448 -25.140917) (xy 77.777437 -25.105733) (xy 77.704087 -25.063384) (xy 77.635095 -25.014255)
			(xy 77.571085 -24.95879) (xy 77.512637 -24.897492) (xy 77.460281 -24.830916) (xy 77.414491 -24.759664)
			(xy 77.37568 -24.684383) (xy 77.344201 -24.605753) (xy 77.32034 -24.524486) (xy 77.304311 -24.44132)
			(xy 77.29626 -24.357006) (xy 61.812862 -24.357006) (xy 62.314328 -24.858472) (xy 62.321508 -24.864976)
			(xy 62.339322 -24.872551) (xy 62.358673 -24.873047) (xy 62.367922 -24.870156) (xy 62.385448 -24.863552)
			(xy 62.392306 -24.857964) (xy 62.426657 -24.829767) (xy 62.500035 -24.77962) (xy 62.57805 -24.737044)
			(xy 62.659924 -24.702465) (xy 62.74484 -24.676227) (xy 62.831949 -24.658592) (xy 62.920384 -24.649737)
			(xy 62.964822 -24.649176) (xy 63.008168 -24.649696) (xy 63.094449 -24.65813) (xy 63.1795 -24.674916)
			(xy 63.262516 -24.699895) (xy 63.342708 -24.73283) (xy 63.419317 -24.773408) (xy 63.491616 -24.821245)
			(xy 63.55892 -24.875887) (xy 63.620589 -24.936817) (xy 63.67604 -25.003455) (xy 63.724747 -25.075171)
			(xy 63.766247 -25.151285) (xy 63.783718 -25.190958) (xy 63.784647 -25.193244) (xy 70.553324 -25.193244)
			(xy 70.557395 -25.137622) (xy 70.569521 -25.083185) (xy 70.589444 -25.031094) (xy 70.61674 -24.982459)
			(xy 70.650826 -24.938316) (xy 70.690975 -24.899607) (xy 70.736333 -24.867156) (xy 70.785933 -24.841655)
			(xy 70.838717 -24.823648) (xy 70.89356 -24.813518) (xy 70.949294 -24.811481) (xy 71.004731 -24.817581)
			(xy 71.058688 -24.831687) (xy 71.110017 -24.853499) (xy 71.157623 -24.882553) (xy 71.200491 -24.918228)
			(xy 71.237708 -24.959765) (xy 71.268481 -25.006278) (xy 71.292153 -25.056775) (xy 71.308221 -25.110182)
			(xy 71.316341 -25.165358) (xy 71.31685 -25.193244) (xy 71.316341 -25.22113) (xy 71.308221 -25.276306)
			(xy 71.292153 -25.329713) (xy 71.268481 -25.38021) (xy 71.237708 -25.426723) (xy 71.200491 -25.46826)
			(xy 71.157623 -25.503935) (xy 71.110017 -25.532989) (xy 71.058688 -25.554801) (xy 71.004731 -25.568907)
			(xy 70.949294 -25.575007) (xy 70.89356 -25.57297) (xy 70.838717 -25.56284) (xy 70.785933 -25.544833)
			(xy 70.736333 -25.519332) (xy 70.690975 -25.486881) (xy 70.650826 -25.448172) (xy 70.61674 -25.404029)
			(xy 70.589444 -25.355394) (xy 70.569521 -25.303303) (xy 70.557395 -25.248866) (xy 70.553324 -25.193244)
			(xy 63.784647 -25.193244) (xy 63.78702 -25.199086) (xy 63.805054 -25.21839) (xy 63.808171 -25.221597)
			(xy 63.815327 -25.226962) (xy 63.819278 -25.229058) (xy 63.837058 -25.237948) (xy 63.843715 -25.24108)
			(xy 63.858168 -25.243801) (xy 63.865506 -25.243282) (xy 63.871602 -25.24252) (xy 63.874142 -25.242012)
			(xy 63.894025 -25.237967) (xy 63.934371 -25.233634) (xy 63.95466 -25.233376) (xy 63.955422 -25.233376)
			(xy 63.982673 -25.233863) (xy 64.036621 -25.241623) (xy 64.088915 -25.25698) (xy 64.138492 -25.279624)
			(xy 64.184341 -25.309092) (xy 64.225531 -25.344785) (xy 64.261221 -25.385976) (xy 64.290687 -25.431828)
			(xy 64.313327 -25.481405) (xy 64.328682 -25.533701) (xy 64.336438 -25.587649) (xy 64.336438 -25.642151)
			(xy 64.328682 -25.696099) (xy 64.313327 -25.748395) (xy 64.290687 -25.797972) (xy 64.261221 -25.843824)
			(xy 64.225531 -25.885015) (xy 64.184341 -25.920708) (xy 64.138492 -25.950176) (xy 64.088915 -25.97282)
			(xy 64.036621 -25.988177) (xy 63.982673 -25.995937) (xy 63.955422 -25.996392) (xy 63.932348 -25.996023)
			(xy 63.88654 -25.990425) (xy 63.841739 -25.979356) (xy 63.82004 -25.9715) (xy 63.815722 -25.969976)
			(xy 63.8048 -25.967944) (xy 63.79863 -25.96697) (xy 63.786167 -25.967748) (xy 63.780162 -25.969468)
			(xy 63.761874 -25.97531) (xy 63.757483 -25.976788) (xy 63.749303 -25.981137) (xy 63.745618 -25.983946)
			(xy 63.725552 -25.999948) (xy 63.720726 -26.007314) (xy 63.702423 -26.036271) (xy 63.66199 -26.091576)
			(xy 63.639954 -26.117804) (xy 63.627 -26.133044) (xy 63.628524 -26.172668) (xy 63.78321 -26.327354)
			(xy 63.783718 -26.327862) (xy 63.791098 -26.334449) (xy 63.809397 -26.341911) (xy 63.819278 -26.34234)
		)
		(stroke
			(width 0)
			(type solid)
		)
		(fill yes)
		(layer "In13.Cu")
		(net "P12V_OCP_V3_2")
	)
	(gr_poly
		(pts
			(xy 242.087654 -324.994016) (xy 242.098009 -324.993467) (xy 242.117006 -324.985199) (xy 242.124484 -324.978014)
			(xy 242.18265 -324.9168) (xy 242.189762 -324.897496) (xy 242.189 -324.886828) (xy 242.188492 -324.866)
			(xy 242.188978 -324.838749) (xy 242.196734 -324.784801) (xy 242.212089 -324.732506) (xy 242.234731 -324.682929)
			(xy 242.264197 -324.637079) (xy 242.299888 -324.595888) (xy 242.341079 -324.560197) (xy 242.386929 -324.530731)
			(xy 242.436506 -324.508089) (xy 242.488801 -324.492734) (xy 242.542749 -324.484978) (xy 242.597251 -324.484978)
			(xy 242.651199 -324.492734) (xy 242.703494 -324.508089) (xy 242.753071 -324.530731) (xy 242.798921 -324.560197)
			(xy 242.840112 -324.595888) (xy 242.875803 -324.637079) (xy 242.905269 -324.682929) (xy 242.927911 -324.732506)
			(xy 242.943266 -324.784801) (xy 242.951022 -324.838749) (xy 242.951508 -324.866) (xy 242.951 -324.886828)
			(xy 242.950238 -324.897496) (xy 242.95735 -324.9168) (xy 243.015516 -324.978014) (xy 243.022964 -324.985242)
			(xy 243.04198 -324.993504) (xy 243.052346 -324.994016) (xy 244.916706 -324.994016) (xy 244.92935 -324.993341)
			(xy 244.951613 -324.981348) (xy 244.959124 -324.971156) (xy 245.012718 -324.889114) (xy 245.015004 -324.863714)
			(xy 245.00967 -324.851776) (xy 244.996319 -324.819628) (xy 244.977533 -324.752599) (xy 244.968056 -324.683636)
			(xy 244.967506 -324.64883) (xy 244.967949 -324.618364) (xy 244.975229 -324.55787) (xy 244.9897 -324.498682)
			(xy 245.000018 -324.470014) (xy 245.005098 -324.456298) (xy 244.99951 -324.42785) (xy 244.917468 -324.34022)
			(xy 244.889528 -324.3326) (xy 244.875558 -324.336918) (xy 244.839764 -324.34702) (xy 244.766186 -324.357857)
			(xy 244.729 -324.358508) (xy 244.698269 -324.358044) (xy 244.637255 -324.350635) (xy 244.577579 -324.335927)
			(xy 244.520111 -324.314132) (xy 244.465689 -324.285569) (xy 244.415107 -324.250655) (xy 244.369102 -324.209898)
			(xy 244.328345 -324.163893) (xy 244.293431 -324.113311) (xy 244.264868 -324.058889) (xy 244.243073 -324.001421)
			(xy 244.228365 -323.941745) (xy 244.220956 -323.880731) (xy 244.220492 -323.85) (xy 244.220939 -323.819148)
			(xy 244.228396 -323.757898) (xy 244.243213 -323.698) (xy 244.265172 -323.640336) (xy 244.293949 -323.585755)
			(xy 244.329122 -323.535058) (xy 244.370173 -323.488992) (xy 244.416498 -323.448234) (xy 244.467417 -323.413383)
			(xy 244.522179 -323.384952) (xy 244.579981 -323.36336) (xy 244.609874 -323.355716) (xy 244.623336 -323.352414)
			(xy 244.642894 -323.333618) (xy 244.675406 -323.222874) (xy 244.668802 -323.196204) (xy 244.659404 -323.186552)
			(xy 244.637272 -323.162787) (xy 244.598591 -323.110621) (xy 244.566861 -323.053959) (xy 244.542598 -322.99372)
			(xy 244.526196 -322.930883) (xy 244.517921 -322.866471) (xy 244.517418 -322.834) (xy 244.517868 -322.8035)
			(xy 244.525168 -322.742939) (xy 244.539662 -322.683686) (xy 244.561142 -322.626594) (xy 244.589299 -322.572482)
			(xy 244.62373 -322.522128) (xy 244.663938 -322.476256) (xy 244.686328 -322.45554) (xy 244.69598 -322.44665)
			(xy 244.704616 -322.422266) (xy 244.686074 -322.311776) (xy 244.670072 -322.291456) (xy 244.65788 -322.286376)
			(xy 244.627614 -322.273001) (xy 244.570526 -322.239539) (xy 244.518262 -322.198954) (xy 244.471705 -322.151931)
			(xy 244.431642 -322.099266) (xy 244.39875 -322.041848) (xy 244.373585 -321.980648) (xy 244.356573 -321.9167)
			(xy 244.348001 -321.851086) (xy 244.347492 -321.818) (xy 244.347994 -321.786039) (xy 244.356005 -321.722621)
			(xy 244.371902 -321.660707) (xy 244.395434 -321.601274) (xy 244.426228 -321.545259) (xy 244.463801 -321.493544)
			(xy 244.507558 -321.446947) (xy 244.556811 -321.406202) (xy 244.610782 -321.371951) (xy 244.668621 -321.344734)
			(xy 244.729414 -321.324981) (xy 244.792204 -321.313003) (xy 244.856 -321.30899) (xy 244.919796 -321.313003)
			(xy 244.982586 -321.324981) (xy 245.043379 -321.344734) (xy 245.101218 -321.371951) (xy 245.155189 -321.406202)
			(xy 245.197166 -321.440928) (xy 249.087988 -321.440928) (xy 249.090594 -321.377898) (xy 249.100977 -321.315675)
			(xy 249.118976 -321.255214) (xy 249.144315 -321.197443) (xy 249.176606 -321.143251) (xy 249.215352 -321.093468)
			(xy 249.259958 -321.048861) (xy 249.309739 -321.010114) (xy 249.363931 -320.977822) (xy 249.421701 -320.95248)
			(xy 249.482161 -320.93448) (xy 249.544384 -320.924096) (xy 249.607414 -320.921488) (xy 249.670282 -320.926697)
			(xy 249.732023 -320.939642) (xy 249.791689 -320.960124) (xy 249.848363 -320.98783) (xy 249.901174 -321.022333)
			(xy 249.949313 -321.063103) (xy 249.992038 -321.109514) (xy 250.028695 -321.160855) (xy 250.05872 -321.216335)
			(xy 250.081652 -321.275102) (xy 250.097139 -321.336255) (xy 250.104942 -321.398854) (xy 250.105418 -321.430396)
			(xy 250.105302 -321.446506) (xy 250.103268 -321.478662) (xy 250.101354 -321.494658) (xy 250.09983 -321.506596)
			(xy 250.107704 -321.528948) (xy 250.18238 -321.602354) (xy 250.204986 -321.60972) (xy 250.216924 -321.607942)
			(xy 250.235236 -321.605437) (xy 250.272102 -321.602766) (xy 250.290584 -321.602608) (xy 250.322126 -321.603051)
			(xy 250.384726 -321.610852) (xy 250.44588 -321.626336) (xy 250.504649 -321.649266) (xy 250.560131 -321.679289)
			(xy 250.611473 -321.715944) (xy 250.657887 -321.758668) (xy 250.69866 -321.806805) (xy 250.733165 -321.859616)
			(xy 250.760873 -321.916289) (xy 250.781358 -321.975955) (xy 250.794306 -322.037696) (xy 250.799517 -322.100564)
			(xy 250.796912 -322.163594) (xy 250.786531 -322.225818) (xy 250.768533 -322.28628) (xy 250.743194 -322.344052)
			(xy 250.710904 -322.398245) (xy 250.672159 -322.448029) (xy 250.627553 -322.492637) (xy 250.577772 -322.531386)
			(xy 250.52358 -322.563679) (xy 250.46581 -322.589022) (xy 250.405349 -322.607024) (xy 250.343126 -322.617409)
			(xy 250.280096 -322.620018) (xy 250.217227 -322.614811) (xy 250.155485 -322.601867) (xy 250.095819 -322.581385)
			(xy 250.039144 -322.553681) (xy 249.986331 -322.519179) (xy 249.938191 -322.478409) (xy 249.895464 -322.431998)
			(xy 249.858806 -322.380658) (xy 249.828779 -322.325178) (xy 249.805846 -322.266411) (xy 249.790358 -322.205257)
			(xy 249.782553 -322.142658) (xy 249.782076 -322.111116) (xy 249.782193 -322.095006) (xy 249.784226 -322.06285)
			(xy 249.78614 -322.046854) (xy 249.787664 -322.034916) (xy 249.77979 -322.012564) (xy 249.705114 -321.939158)
			(xy 249.682508 -321.931792) (xy 249.67057 -321.93357) (xy 249.652258 -321.936076) (xy 249.615392 -321.938747)
			(xy 249.59691 -321.938904) (xy 249.565368 -321.938443) (xy 249.502769 -321.930641) (xy 249.441616 -321.915156)
			(xy 249.382847 -321.892226) (xy 249.327366 -321.862203) (xy 249.276025 -321.825547) (xy 249.229613 -321.782823)
			(xy 249.188841 -321.734685) (xy 249.154337 -321.681875) (xy 249.12663 -321.625202) (xy 249.106145 -321.565536)
			(xy 249.093199 -321.503796) (xy 249.087988 -321.440928) (xy 245.197166 -321.440928) (xy 245.204442 -321.446947)
			(xy 245.248199 -321.493544) (xy 245.285772 -321.545259) (xy 245.316566 -321.601274) (xy 245.340098 -321.660707)
			(xy 245.355995 -321.722621) (xy 245.364006 -321.786039) (xy 245.364508 -321.818) (xy 245.364058 -321.8485)
			(xy 245.356759 -321.909062) (xy 245.342265 -321.968315) (xy 245.320786 -322.025408) (xy 245.292629 -322.079521)
			(xy 245.2582 -322.129876) (xy 245.217993 -322.175749) (xy 245.195598 -322.19646) (xy 245.185946 -322.20535)
			(xy 245.17731 -322.229734) (xy 245.195852 -322.340224) (xy 245.211854 -322.360544) (xy 245.224046 -322.365624)
			(xy 245.254311 -322.379) (xy 245.311396 -322.412464) (xy 245.363658 -322.45305) (xy 245.410213 -322.500073)
			(xy 245.450273 -322.552739) (xy 245.483163 -322.610156) (xy 245.508327 -322.671355) (xy 245.525338 -322.735302)
			(xy 245.533909 -322.800915) (xy 245.534434 -322.834) (xy 245.533987 -322.864852) (xy 245.52653 -322.926104)
			(xy 245.511713 -322.986002) (xy 245.489755 -323.043667) (xy 245.460979 -323.09825) (xy 245.425807 -323.148948)
			(xy 245.384756 -323.195016) (xy 245.338432 -323.235776) (xy 245.287513 -323.270629) (xy 245.232751 -323.299062)
			(xy 245.17495 -323.320658) (xy 245.145052 -323.328284) (xy 245.13159 -323.331586) (xy 245.112032 -323.350382)
			(xy 245.090718 -323.422983) (xy 250.505462 -323.422983) (xy 250.505462 -323.359061) (xy 250.513473 -323.295643)
			(xy 250.52937 -323.233729) (xy 250.552902 -323.174296) (xy 250.583696 -323.118281) (xy 250.621269 -323.066566)
			(xy 250.665026 -323.019969) (xy 250.714279 -322.979224) (xy 250.76825 -322.944973) (xy 250.826089 -322.917756)
			(xy 250.886882 -322.898003) (xy 250.949672 -322.886025) (xy 251.013468 -322.882012) (xy 251.077264 -322.886025)
			(xy 251.140054 -322.898003) (xy 251.200847 -322.917756) (xy 251.258686 -322.944973) (xy 251.312657 -322.979224)
			(xy 251.36191 -323.019969) (xy 251.405667 -323.066566) (xy 251.44324 -323.118281) (xy 251.474034 -323.174296)
			(xy 251.497566 -323.233729) (xy 251.513463 -323.295643) (xy 251.521474 -323.359061) (xy 251.521976 -323.391022)
			(xy 251.521474 -323.422983) (xy 251.513463 -323.486401) (xy 251.497566 -323.548315) (xy 251.474034 -323.607748)
			(xy 251.44324 -323.663763) (xy 251.405667 -323.715478) (xy 251.36191 -323.762075) (xy 251.312657 -323.80282)
			(xy 251.258686 -323.837071) (xy 251.200847 -323.864288) (xy 251.140054 -323.884041) (xy 251.077264 -323.896019)
			(xy 251.013468 -323.900033) (xy 250.949672 -323.896019) (xy 250.886882 -323.884041) (xy 250.826089 -323.864288)
			(xy 250.76825 -323.837071) (xy 250.714279 -323.80282) (xy 250.665026 -323.762075) (xy 250.621269 -323.715478)
			(xy 250.583696 -323.663763) (xy 250.552902 -323.607748) (xy 250.52937 -323.548315) (xy 250.513473 -323.486401)
			(xy 250.505462 -323.422983) (xy 245.090718 -323.422983) (xy 245.07952 -323.461126) (xy 245.086124 -323.487796)
			(xy 245.095522 -323.497448) (xy 245.117653 -323.521214) (xy 245.156332 -323.57338) (xy 245.18806 -323.630043)
			(xy 245.212322 -323.690282) (xy 245.228723 -323.753118) (xy 245.236997 -323.81753) (xy 245.237508 -323.85)
			(xy 245.237064 -323.880465) (xy 245.22978 -323.940959) (xy 245.215306 -324.000145) (xy 245.204996 -324.028816)
			(xy 245.199916 -324.042532) (xy 245.205504 -324.07098) (xy 245.287546 -324.15861) (xy 245.315486 -324.16623)
			(xy 245.329456 -324.161912) (xy 245.36525 -324.151811) (xy 245.438828 -324.140975) (xy 245.476014 -324.140322)
			(xy 245.506745 -324.140768) (xy 245.567758 -324.148179) (xy 245.627434 -324.162889) (xy 245.684901 -324.184686)
			(xy 245.739322 -324.213251) (xy 245.789902 -324.248167) (xy 245.835905 -324.288926) (xy 245.87666 -324.334932)
			(xy 245.911572 -324.385516) (xy 245.940132 -324.439939) (xy 245.961924 -324.497408) (xy 245.976629 -324.557085)
			(xy 245.984034 -324.618099) (xy 245.984522 -324.64883) (xy 245.983969 -324.683636) (xy 245.974501 -324.7526)
			(xy 245.955706 -324.819626) (xy 245.942358 -324.851776) (xy 245.937024 -324.863714) (xy 245.93931 -324.889114)
			(xy 245.992904 -324.971156) (xy 246.000424 -324.981336) (xy 246.022683 -324.993315) (xy 246.035322 -324.994016)
			(xy 251.554996 -324.994016) (xy 251.565067 -324.993594) (xy 251.583674 -324.985883) (xy 251.591064 -324.97903)
			(xy 253.097792 -323.472302) (xy 253.10464 -323.464904) (xy 253.112376 -323.446306) (xy 253.112778 -323.436234)
			(xy 253.112778 -308.354222) (xy 253.11234 -308.344159) (xy 253.104603 -308.325577) (xy 253.097792 -308.318154)
			(xy 252.29947 -307.519832) (xy 252.292071 -307.512987) (xy 252.273473 -307.505258) (xy 252.263402 -307.504846)
			(xy 238.09325 -307.504846) (xy 238.083185 -307.50528) (xy 238.064598 -307.513012) (xy 238.057182 -307.519832)
			(xy 237.403386 -308.173628) (xy 237.39657 -308.180971) (xy 237.388835 -308.199434) (xy 237.3884 -308.209442)
			(xy 237.3884 -316.897766) (xy 237.388888 -316.908211) (xy 237.3972 -316.927372) (xy 237.412488 -316.941603)
			(xy 237.422182 -316.945518) (xy 237.527084 -316.983618) (xy 237.558072 -316.975236) (xy 237.568232 -316.96279)
			(xy 237.586444 -316.941599) (xy 237.628009 -316.904258) (xy 237.674574 -316.873377) (xy 237.725146 -316.849618)
			(xy 237.778642 -316.833488) (xy 237.833919 -316.825333) (xy 237.861856 -316.824868) (xy 237.889113 -316.825328)
			(xy 237.943072 -316.83308) (xy 237.995378 -316.848433) (xy 238.044967 -316.871075) (xy 238.090829 -316.900544)
			(xy 238.132029 -316.93624) (xy 238.16773 -316.977436) (xy 238.197204 -317.023294) (xy 238.219851 -317.07288)
			(xy 238.23521 -317.125185) (xy 238.242969 -317.179143) (xy 238.242969 -317.22568) (xy 238.579406 -317.22568)
			(xy 238.579979 -317.196765) (xy 238.588697 -317.139596) (xy 238.605943 -317.084398) (xy 238.631325 -317.032436)
			(xy 238.664259 -316.984901) (xy 238.703991 -316.942882) (xy 238.726472 -316.92469) (xy 238.735246 -316.91714)
			(xy 238.74542 -316.896372) (xy 238.74603 -316.884812) (xy 238.74603 -316.804548) (xy 238.745456 -316.79298)
			(xy 238.735266 -316.772207) (xy 238.726472 -316.76467) (xy 238.703968 -316.746503) (xy 238.664236 -316.704477)
			(xy 238.6313 -316.656937) (xy 238.605915 -316.604971) (xy 238.588663 -316.54977) (xy 238.579939 -316.492597)
			(xy 238.579406 -316.46368) (xy 238.579892 -316.436429) (xy 238.587648 -316.382481) (xy 238.603003 -316.330186)
			(xy 238.625645 -316.280609) (xy 238.655111 -316.234759) (xy 238.690802 -316.193568) (xy 238.731993 -316.157877)
			(xy 238.777843 -316.128411) (xy 238.82742 -316.105769) (xy 238.879715 -316.090414) (xy 238.933663 -316.082658)
			(xy 238.988165 -316.082658) (xy 239.042113 -316.090414) (xy 239.094408 -316.105769) (xy 239.143985 -316.128411)
			(xy 239.189835 -316.157877) (xy 239.231026 -316.193568) (xy 239.266717 -316.234759) (xy 239.296183 -316.280609)
			(xy 239.318825 -316.330186) (xy 239.33418 -316.382481) (xy 239.341936 -316.436429) (xy 239.342422 -316.46368)
			(xy 239.341919 -316.492598) (xy 239.333191 -316.549771) (xy 239.315932 -316.604972) (xy 239.290538 -316.656934)
			(xy 239.25759 -316.704467) (xy 239.217844 -316.746482) (xy 239.195356 -316.76467) (xy 239.186605 -316.772242)
			(xy 239.176417 -316.792993) (xy 239.175798 -316.804548) (xy 239.175798 -316.884812) (xy 239.176362 -316.896381)
			(xy 239.186561 -316.917151) (xy 239.195356 -316.92469) (xy 239.217826 -316.942898) (xy 239.257564 -316.984913)
			(xy 239.290506 -317.032444) (xy 239.315897 -317.084402) (xy 239.333155 -317.139597) (xy 239.341886 -317.196765)
			(xy 239.342422 -317.22568) (xy 239.342021 -317.252375) (xy 239.334597 -317.305247) (xy 239.319876 -317.356567)
			(xy 239.298146 -317.405336) (xy 239.269832 -317.450599) (xy 239.235486 -317.491475) (xy 239.21593 -317.509652)
			(xy 239.207294 -317.517272) (xy 239.198404 -317.5381) (xy 239.202976 -317.6397) (xy 239.21339 -317.659512)
			(xy 239.222788 -317.66637) (xy 239.246075 -317.684499) (xy 239.287267 -317.726759) (xy 239.321465 -317.774855)
			(xy 239.347854 -317.827641) (xy 239.365805 -317.88386) (xy 239.37489 -317.942171) (xy 239.375442 -317.971678)
			(xy 239.374956 -317.998929) (xy 239.3672 -318.052877) (xy 239.351845 -318.105172) (xy 239.329203 -318.154749)
			(xy 239.299737 -318.200599) (xy 239.264046 -318.24179) (xy 239.222855 -318.277481) (xy 239.177005 -318.306947)
			(xy 239.127428 -318.329589) (xy 239.075133 -318.344944) (xy 239.021185 -318.3527) (xy 238.966683 -318.3527)
			(xy 238.912735 -318.344944) (xy 238.86044 -318.329589) (xy 238.810863 -318.306947) (xy 238.765013 -318.277481)
			(xy 238.723822 -318.24179) (xy 238.688131 -318.200599) (xy 238.658665 -318.154749) (xy 238.636023 -318.105172)
			(xy 238.620668 -318.052877) (xy 238.612912 -317.998929) (xy 238.612426 -317.971678) (xy 238.612883 -317.944985)
			(xy 238.620299 -317.892117) (xy 238.635009 -317.840798) (xy 238.656728 -317.79203) (xy 238.685032 -317.746764)
			(xy 238.719367 -317.705885) (xy 238.738918 -317.687706) (xy 238.747554 -317.680086) (xy 238.756444 -317.659258)
			(xy 238.751872 -317.557658) (xy 238.741458 -317.537846) (xy 238.73206 -317.530988) (xy 238.708805 -317.512817)
			(xy 238.6676 -317.470574) (xy 238.633391 -317.422489) (xy 238.606994 -317.369709) (xy 238.589039 -317.313495)
			(xy 238.579955 -317.255186) (xy 238.579406 -317.22568) (xy 238.242969 -317.22568) (xy 238.242969 -317.233657)
			(xy 238.23521 -317.287615) (xy 238.219851 -317.33992) (xy 238.197204 -317.389506) (xy 238.16773 -317.435364)
			(xy 238.132029 -317.47656) (xy 238.090829 -317.512256) (xy 238.044967 -317.541725) (xy 237.995378 -317.564367)
			(xy 237.943072 -317.57972) (xy 237.889113 -317.587472) (xy 237.861856 -317.587884) (xy 237.833921 -317.587393)
			(xy 237.778649 -317.579238) (xy 237.725158 -317.563107) (xy 237.674592 -317.539348) (xy 237.628032 -317.508467)
			(xy 237.586474 -317.471125) (xy 237.568232 -317.449962) (xy 237.558072 -317.437516) (xy 237.527084 -317.429134)
			(xy 237.422182 -317.467234) (xy 237.41254 -317.471222) (xy 237.397315 -317.485461) (xy 237.388977 -317.504566)
			(xy 237.3884 -317.514986) (xy 237.3884 -318.70448) (xy 239.823475 -318.70448) (xy 239.827208 -318.651225)
			(xy 239.838329 -318.59901) (xy 239.856619 -318.548855) (xy 239.881723 -318.50174) (xy 239.91315 -318.458584)
			(xy 239.950286 -318.420231) (xy 239.971072 -318.403478) (xy 239.979851 -318.395934) (xy 239.990022 -318.375161)
			(xy 239.99063 -318.3636) (xy 239.99063 -318.283336) (xy 239.990063 -318.271767) (xy 239.979869 -318.250994)
			(xy 239.971072 -318.243458) (xy 239.948563 -318.225298) (xy 239.90883 -318.183271) (xy 239.875895 -318.135729)
			(xy 239.850511 -318.083762) (xy 239.833261 -318.028559) (xy 239.824538 -317.971386) (xy 239.824006 -317.942468)
			(xy 239.824492 -317.915217) (xy 239.832248 -317.861269) (xy 239.847603 -317.808974) (xy 239.870245 -317.759397)
			(xy 239.899711 -317.713547) (xy 239.935402 -317.672356) (xy 239.976593 -317.636665) (xy 240.022443 -317.607199)
			(xy 240.07202 -317.584557) (xy 240.124315 -317.569202) (xy 240.178263 -317.561446) (xy 240.232765 -317.561446)
			(xy 240.286713 -317.569202) (xy 240.339008 -317.584557) (xy 240.388585 -317.607199) (xy 240.434435 -317.636665)
			(xy 240.475626 -317.672356) (xy 240.511317 -317.713547) (xy 240.540783 -317.759397) (xy 240.563425 -317.808974)
			(xy 240.57878 -317.861269) (xy 240.586536 -317.915217) (xy 240.587022 -317.942468) (xy 240.58651 -317.971386)
			(xy 240.577784 -318.028558) (xy 240.560527 -318.083759) (xy 240.535134 -318.135721) (xy 240.502188 -318.183255)
			(xy 240.462443 -318.225269) (xy 240.439956 -318.243458) (xy 240.43121 -318.251035) (xy 240.42102 -318.271783)
			(xy 240.420398 -318.283336) (xy 240.420398 -318.3636) (xy 240.420969 -318.375168) (xy 240.431163 -318.395939)
			(xy 240.439956 -318.403478) (xy 240.460707 -318.420269) (xy 240.497835 -318.458619) (xy 240.529256 -318.501769)
			(xy 240.554354 -318.548878) (xy 240.572641 -318.599026) (xy 240.583759 -318.651233) (xy 240.587492 -318.70448)
			(xy 242.211075 -318.70448) (xy 242.214808 -318.651225) (xy 242.225929 -318.59901) (xy 242.244219 -318.548855)
			(xy 242.269323 -318.50174) (xy 242.30075 -318.458584) (xy 242.337886 -318.420231) (xy 242.358672 -318.403478)
			(xy 242.367451 -318.395934) (xy 242.377622 -318.375161) (xy 242.37823 -318.3636) (xy 242.37823 -318.283336)
			(xy 242.377663 -318.271767) (xy 242.367469 -318.250994) (xy 242.358672 -318.243458) (xy 242.336163 -318.225298)
			(xy 242.29643 -318.183271) (xy 242.263495 -318.135729) (xy 242.238111 -318.083762) (xy 242.220861 -318.028559)
			(xy 242.212138 -317.971386) (xy 242.211606 -317.942468) (xy 242.212081 -317.914872) (xy 242.220051 -317.860258)
			(xy 242.235805 -317.807362) (xy 242.259015 -317.757287) (xy 242.289197 -317.711078) (xy 242.32572 -317.669699)
			(xy 242.367824 -317.634013) (xy 242.414629 -317.604764) (xy 242.439698 -317.593218) (xy 242.450112 -317.588646)
			(xy 242.464844 -317.571628) (xy 242.49253 -317.474092) (xy 242.488974 -317.451994) (xy 242.48237 -317.442342)
			(xy 242.466424 -317.418329) (xy 242.441172 -317.366513) (xy 242.424011 -317.311485) (xy 242.415334 -317.254501)
			(xy 242.414806 -317.22568) (xy 242.415379 -317.196765) (xy 242.424097 -317.139596) (xy 242.441343 -317.084398)
			(xy 242.466725 -317.032436) (xy 242.499659 -316.984901) (xy 242.539391 -316.942882) (xy 242.561872 -316.92469)
			(xy 242.570646 -316.91714) (xy 242.58082 -316.896372) (xy 242.58143 -316.884812) (xy 242.58143 -316.804548)
			(xy 242.580856 -316.79298) (xy 242.570666 -316.772207) (xy 242.561872 -316.76467) (xy 242.539368 -316.746503)
			(xy 242.499636 -316.704477) (xy 242.4667 -316.656937) (xy 242.441315 -316.604971) (xy 242.424063 -316.54977)
			(xy 242.415339 -316.492597) (xy 242.414806 -316.46368) (xy 242.415292 -316.436429) (xy 242.423048 -316.382481)
			(xy 242.438403 -316.330186) (xy 242.461045 -316.280609) (xy 242.490511 -316.234759) (xy 242.526202 -316.193568)
			(xy 242.567393 -316.157877) (xy 242.613243 -316.128411) (xy 242.66282 -316.105769) (xy 242.715115 -316.090414)
			(xy 242.769063 -316.082658) (xy 242.823565 -316.082658) (xy 242.877513 -316.090414) (xy 242.929808 -316.105769)
			(xy 242.979385 -316.128411) (xy 243.025235 -316.157877) (xy 243.066426 -316.193568) (xy 243.102117 -316.234759)
			(xy 243.131583 -316.280609) (xy 243.154225 -316.330186) (xy 243.16958 -316.382481) (xy 243.177336 -316.436429)
			(xy 243.177822 -316.46368) (xy 243.177319 -316.492598) (xy 243.168591 -316.549771) (xy 243.151332 -316.604972)
			(xy 243.125938 -316.656934) (xy 243.09299 -316.704467) (xy 243.053244 -316.746482) (xy 243.030756 -316.76467)
			(xy 243.022005 -316.772242) (xy 243.011817 -316.792993) (xy 243.011198 -316.804548) (xy 243.011198 -316.884812)
			(xy 243.011762 -316.896381) (xy 243.021961 -316.917151) (xy 243.030756 -316.92469) (xy 243.053226 -316.942898)
			(xy 243.092964 -316.984913) (xy 243.125906 -317.032444) (xy 243.151297 -317.084402) (xy 243.168555 -317.139597)
			(xy 243.177286 -317.196765) (xy 243.177822 -317.22568) (xy 244.472206 -317.22568) (xy 244.472779 -317.196765)
			(xy 244.481497 -317.139596) (xy 244.498743 -317.084398) (xy 244.524125 -317.032436) (xy 244.557059 -316.984901)
			(xy 244.596791 -316.942882) (xy 244.619272 -316.92469) (xy 244.628046 -316.91714) (xy 244.63822 -316.896372)
			(xy 244.63883 -316.884812) (xy 244.63883 -316.804548) (xy 244.638256 -316.79298) (xy 244.628066 -316.772207)
			(xy 244.619272 -316.76467) (xy 244.596768 -316.746503) (xy 244.557036 -316.704477) (xy 244.5241 -316.656937)
			(xy 244.498715 -316.604971) (xy 244.481463 -316.54977) (xy 244.472739 -316.492597) (xy 244.472206 -316.46368)
			(xy 244.472692 -316.436429) (xy 244.480448 -316.382481) (xy 244.495803 -316.330186) (xy 244.518445 -316.280609)
			(xy 244.547911 -316.234759) (xy 244.583602 -316.193568) (xy 244.624793 -316.157877) (xy 244.670643 -316.128411)
			(xy 244.72022 -316.105769) (xy 244.772515 -316.090414) (xy 244.826463 -316.082658) (xy 244.880965 -316.082658)
			(xy 244.934913 -316.090414) (xy 244.987208 -316.105769) (xy 245.036785 -316.128411) (xy 245.082635 -316.157877)
			(xy 245.123826 -316.193568) (xy 245.159517 -316.234759) (xy 245.188983 -316.280609) (xy 245.211625 -316.330186)
			(xy 245.22698 -316.382481) (xy 245.234736 -316.436429) (xy 245.235222 -316.46368) (xy 245.234719 -316.492598)
			(xy 245.225991 -316.549771) (xy 245.208732 -316.604972) (xy 245.183338 -316.656934) (xy 245.15039 -316.704467)
			(xy 245.110644 -316.746482) (xy 245.088156 -316.76467) (xy 245.079405 -316.772242) (xy 245.069217 -316.792993)
			(xy 245.068598 -316.804548) (xy 245.068598 -316.884812) (xy 245.069162 -316.896381) (xy 245.079361 -316.917151)
			(xy 245.088156 -316.92469) (xy 245.110626 -316.942898) (xy 245.150364 -316.984913) (xy 245.183306 -317.032444)
			(xy 245.208697 -317.084402) (xy 245.225955 -317.139597) (xy 245.234686 -317.196765) (xy 245.235222 -317.22568)
			(xy 245.23473 -317.253149) (xy 245.226852 -317.307519) (xy 245.211258 -317.360196) (xy 245.188269 -317.410093)
			(xy 245.158361 -317.456175) (xy 245.122152 -317.497492) (xy 245.080391 -317.533187) (xy 245.057422 -317.54826)
			(xy 245.045992 -317.555372) (xy 245.033546 -317.57874) (xy 245.035832 -317.692786) (xy 245.049294 -317.715646)
			(xy 245.060978 -317.72225) (xy 245.08549 -317.736983) (xy 245.130248 -317.772578) (xy 245.169193 -317.814455)
			(xy 245.201451 -317.861676) (xy 245.226301 -317.913181) (xy 245.243186 -317.967819) (xy 245.251727 -318.024365)
			(xy 245.25224 -318.052958) (xy 245.251754 -318.080209) (xy 245.243998 -318.134157) (xy 245.228643 -318.186452)
			(xy 245.206001 -318.236029) (xy 245.176535 -318.281879) (xy 245.140844 -318.32307) (xy 245.099653 -318.358761)
			(xy 245.053803 -318.388227) (xy 245.004226 -318.410869) (xy 244.951931 -318.426224) (xy 244.897983 -318.43398)
			(xy 244.843481 -318.43398) (xy 244.789533 -318.426224) (xy 244.737238 -318.410869) (xy 244.687661 -318.388227)
			(xy 244.641811 -318.358761) (xy 244.60062 -318.32307) (xy 244.564929 -318.281879) (xy 244.535463 -318.236029)
			(xy 244.512821 -318.186452) (xy 244.497466 -318.134157) (xy 244.48971 -318.080209) (xy 244.489224 -318.052958)
			(xy 244.489724 -318.025489) (xy 244.497597 -317.971119) (xy 244.513189 -317.91844) (xy 244.536176 -317.868543)
			(xy 244.566084 -317.82246) (xy 244.602293 -317.781144) (xy 244.644055 -317.74545) (xy 244.667024 -317.730378)
			(xy 244.678454 -317.723266) (xy 244.6909 -317.699898) (xy 244.688614 -317.585852) (xy 244.675152 -317.562992)
			(xy 244.663468 -317.556388) (xy 244.638916 -317.541719) (xy 244.59416 -317.506111) (xy 244.55522 -317.464222)
			(xy 244.522967 -317.416991) (xy 244.498124 -317.365475) (xy 244.481247 -317.310829) (xy 244.472714 -317.254276)
			(xy 244.472206 -317.22568) (xy 243.177822 -317.22568) (xy 243.177287 -317.253274) (xy 243.169325 -317.307884)
			(xy 243.153579 -317.360778) (xy 243.130377 -317.410852) (xy 243.100204 -317.457061) (xy 243.063689 -317.498441)
			(xy 243.021593 -317.53413) (xy 242.974796 -317.563381) (xy 242.94973 -317.57493) (xy 242.939316 -317.579502)
			(xy 242.924584 -317.59652) (xy 242.896898 -317.694056) (xy 242.900454 -317.716154) (xy 242.907058 -317.725806)
			(xy 242.923028 -317.749804) (xy 242.948274 -317.801626) (xy 242.965428 -317.856658) (xy 242.974098 -317.913646)
			(xy 242.974622 -317.942468) (xy 242.97411 -317.971386) (xy 242.965384 -318.028558) (xy 242.948127 -318.083759)
			(xy 242.922734 -318.135721) (xy 242.889788 -318.183255) (xy 242.850043 -318.225269) (xy 242.827556 -318.243458)
			(xy 242.81881 -318.251035) (xy 242.80862 -318.271783) (xy 242.807998 -318.283336) (xy 242.807998 -318.3636)
			(xy 242.808569 -318.375168) (xy 242.818763 -318.395939) (xy 242.827556 -318.403478) (xy 242.848307 -318.420269)
			(xy 242.885435 -318.458619) (xy 242.916856 -318.501769) (xy 242.941954 -318.548878) (xy 242.960241 -318.599026)
			(xy 242.971359 -318.651233) (xy 242.975092 -318.70448) (xy 245.919475 -318.70448) (xy 245.923208 -318.651225)
			(xy 245.934329 -318.59901) (xy 245.952619 -318.548855) (xy 245.977723 -318.50174) (xy 246.00915 -318.458584)
			(xy 246.046286 -318.420231) (xy 246.067072 -318.403478) (xy 246.075851 -318.395934) (xy 246.086022 -318.375161)
			(xy 246.08663 -318.3636) (xy 246.08663 -318.283336) (xy 246.086063 -318.271767) (xy 246.075869 -318.250994)
			(xy 246.067072 -318.243458) (xy 246.044563 -318.225298) (xy 246.00483 -318.183271) (xy 245.971895 -318.135729)
			(xy 245.946511 -318.083762) (xy 245.929261 -318.028559) (xy 245.920538 -317.971386) (xy 245.920006 -317.942468)
			(xy 245.920492 -317.915217) (xy 245.928248 -317.861269) (xy 245.943603 -317.808974) (xy 245.966245 -317.759397)
			(xy 245.995711 -317.713547) (xy 246.031402 -317.672356) (xy 246.072593 -317.636665) (xy 246.118443 -317.607199)
			(xy 246.16802 -317.584557) (xy 246.220315 -317.569202) (xy 246.274263 -317.561446) (xy 246.328765 -317.561446)
			(xy 246.382713 -317.569202) (xy 246.435008 -317.584557) (xy 246.484585 -317.607199) (xy 246.530435 -317.636665)
			(xy 246.571626 -317.672356) (xy 246.607317 -317.713547) (xy 246.636783 -317.759397) (xy 246.659425 -317.808974)
			(xy 246.67478 -317.861269) (xy 246.682536 -317.915217) (xy 246.683022 -317.942468) (xy 246.68251 -317.971386)
			(xy 246.673784 -318.028558) (xy 246.656527 -318.083759) (xy 246.631134 -318.135721) (xy 246.598188 -318.183255)
			(xy 246.558443 -318.225269) (xy 246.535956 -318.243458) (xy 246.52721 -318.251035) (xy 246.51702 -318.271783)
			(xy 246.516398 -318.283336) (xy 246.516398 -318.3636) (xy 246.516969 -318.375168) (xy 246.527163 -318.395939)
			(xy 246.535956 -318.403478) (xy 246.556707 -318.420269) (xy 246.593835 -318.458619) (xy 246.625256 -318.501769)
			(xy 246.650354 -318.548878) (xy 246.668641 -318.599026) (xy 246.679759 -318.651233) (xy 246.683492 -318.70448)
			(xy 248.307075 -318.70448) (xy 248.310808 -318.651225) (xy 248.321929 -318.59901) (xy 248.340219 -318.548855)
			(xy 248.365323 -318.50174) (xy 248.39675 -318.458584) (xy 248.433886 -318.420231) (xy 248.454672 -318.403478)
			(xy 248.463451 -318.395934) (xy 248.473622 -318.375161) (xy 248.47423 -318.3636) (xy 248.47423 -318.283336)
			(xy 248.473663 -318.271767) (xy 248.463469 -318.250994) (xy 248.454672 -318.243458) (xy 248.432163 -318.225298)
			(xy 248.39243 -318.183271) (xy 248.359495 -318.135729) (xy 248.334111 -318.083762) (xy 248.316861 -318.028559)
			(xy 248.308138 -317.971386) (xy 248.307606 -317.942468) (xy 248.308023 -317.915885) (xy 248.315415 -317.863236)
			(xy 248.33005 -317.812124) (xy 248.351646 -317.763541) (xy 248.379782 -317.718431) (xy 248.413913 -317.677667)
			(xy 248.433336 -317.659512) (xy 248.440859 -317.651897) (xy 248.449528 -317.632354) (xy 248.4501 -317.621666)
			(xy 248.4501 -317.546482) (xy 248.449667 -317.535759) (xy 248.440993 -317.516154) (xy 248.433336 -317.508636)
			(xy 248.413902 -317.490495) (xy 248.379783 -317.449724) (xy 248.351658 -317.404608) (xy 248.330074 -317.356023)
			(xy 248.315449 -317.304911) (xy 248.308066 -317.252262) (xy 248.307606 -317.22568) (xy 248.308179 -317.196765)
			(xy 248.316897 -317.139596) (xy 248.334143 -317.084398) (xy 248.359525 -317.032436) (xy 248.392459 -316.984901)
			(xy 248.432191 -316.942882) (xy 248.454672 -316.92469) (xy 248.463446 -316.91714) (xy 248.47362 -316.896372)
			(xy 248.47423 -316.884812) (xy 248.47423 -316.804548) (xy 248.473656 -316.79298) (xy 248.463466 -316.772207)
			(xy 248.454672 -316.76467) (xy 248.432168 -316.746503) (xy 248.392436 -316.704477) (xy 248.3595 -316.656937)
			(xy 248.334115 -316.604971) (xy 248.316863 -316.54977) (xy 248.308139 -316.492597) (xy 248.307606 -316.46368)
			(xy 248.308092 -316.436429) (xy 248.315848 -316.382481) (xy 248.331203 -316.330186) (xy 248.353845 -316.280609)
			(xy 248.383311 -316.234759) (xy 248.419002 -316.193568) (xy 248.460193 -316.157877) (xy 248.506043 -316.128411)
			(xy 248.55562 -316.105769) (xy 248.607915 -316.090414) (xy 248.661863 -316.082658) (xy 248.716365 -316.082658)
			(xy 248.770313 -316.090414) (xy 248.822608 -316.105769) (xy 248.872185 -316.128411) (xy 248.918035 -316.157877)
			(xy 248.959226 -316.193568) (xy 248.994917 -316.234759) (xy 249.024383 -316.280609) (xy 249.047025 -316.330186)
			(xy 249.06238 -316.382481) (xy 249.070136 -316.436429) (xy 249.070622 -316.46368) (xy 249.070119 -316.492598)
			(xy 249.061391 -316.549771) (xy 249.044132 -316.604972) (xy 249.018738 -316.656934) (xy 248.98579 -316.704467)
			(xy 248.946044 -316.746482) (xy 248.923556 -316.76467) (xy 248.914805 -316.772242) (xy 248.904617 -316.792993)
			(xy 248.903998 -316.804548) (xy 248.903998 -316.884812) (xy 248.904562 -316.896381) (xy 248.914761 -316.917151)
			(xy 248.923556 -316.92469) (xy 248.946026 -316.942898) (xy 248.985764 -316.984913) (xy 249.018706 -317.032444)
			(xy 249.044097 -317.084402) (xy 249.061355 -317.139597) (xy 249.070086 -317.196765) (xy 249.070622 -317.22568)
			(xy 249.070161 -317.252261) (xy 249.062777 -317.304908) (xy 249.048149 -317.356019) (xy 249.026562 -317.404601)
			(xy 248.998434 -317.449713) (xy 248.964311 -317.490479) (xy 248.944892 -317.508636) (xy 248.937352 -317.516237)
			(xy 248.928691 -317.53579) (xy 248.928128 -317.546482) (xy 248.928128 -317.621666) (xy 248.928556 -317.632389)
			(xy 248.937236 -317.651993) (xy 248.944892 -317.659512) (xy 248.964287 -317.677694) (xy 248.998413 -317.718454)
			(xy 249.026544 -317.763561) (xy 249.048135 -317.812138) (xy 249.062768 -317.863244) (xy 249.070159 -317.915888)
			(xy 249.070622 -317.942468) (xy 249.07011 -317.971386) (xy 249.061384 -318.028558) (xy 249.044127 -318.083759)
			(xy 249.018734 -318.135721) (xy 248.985788 -318.183255) (xy 248.946043 -318.225269) (xy 248.923556 -318.243458)
			(xy 248.91481 -318.251035) (xy 248.90462 -318.271783) (xy 248.903998 -318.283336) (xy 248.903998 -318.3636)
			(xy 248.904569 -318.375168) (xy 248.914763 -318.395939) (xy 248.923556 -318.403478) (xy 248.944307 -318.420269)
			(xy 248.981435 -318.458619) (xy 249.012856 -318.501769) (xy 249.037954 -318.548878) (xy 249.056241 -318.599026)
			(xy 249.067359 -318.651233) (xy 249.071092 -318.70448) (xy 249.067365 -318.757728) (xy 249.056252 -318.809936)
			(xy 249.03797 -318.860086) (xy 249.012877 -318.907197) (xy 248.981461 -318.950351) (xy 248.944336 -318.988704)
			(xy 248.923556 -319.005458) (xy 248.91481 -319.013035) (xy 248.90462 -319.033783) (xy 248.903998 -319.045336)
			(xy 248.903998 -319.1256) (xy 248.904569 -319.137168) (xy 248.914763 -319.157939) (xy 248.923556 -319.165478)
			(xy 248.94602 -319.183693) (xy 248.985758 -319.225706) (xy 249.018701 -319.273236) (xy 249.044093 -319.325193)
			(xy 249.061353 -319.380387) (xy 249.070085 -319.437553) (xy 249.070622 -319.466468) (xy 249.070136 -319.493719)
			(xy 249.06238 -319.547667) (xy 249.047025 -319.599962) (xy 249.024383 -319.649539) (xy 248.994917 -319.695389)
			(xy 248.959226 -319.73658) (xy 248.918035 -319.772271) (xy 248.872185 -319.801737) (xy 248.822608 -319.824379)
			(xy 248.770313 -319.839734) (xy 248.716365 -319.84749) (xy 248.661863 -319.84749) (xy 248.607915 -319.839734)
			(xy 248.55562 -319.824379) (xy 248.506043 -319.801737) (xy 248.460193 -319.772271) (xy 248.419002 -319.73658)
			(xy 248.383311 -319.695389) (xy 248.353845 -319.649539) (xy 248.331203 -319.599962) (xy 248.315848 -319.547667)
			(xy 248.308092 -319.493719) (xy 248.307606 -319.466468) (xy 248.308171 -319.437553) (xy 248.31689 -319.380384)
			(xy 248.334138 -319.325186) (xy 248.359521 -319.273224) (xy 248.392457 -319.225689) (xy 248.43219 -319.18367)
			(xy 248.454672 -319.165478) (xy 248.463451 -319.157934) (xy 248.473622 -319.137161) (xy 248.47423 -319.1256)
			(xy 248.47423 -319.045336) (xy 248.473663 -319.033767) (xy 248.463469 -319.012994) (xy 248.454672 -319.005458)
			(xy 248.433857 -318.988743) (xy 248.396725 -318.950386) (xy 248.365302 -318.907227) (xy 248.340203 -318.860109)
			(xy 248.321918 -318.809952) (xy 248.310803 -318.757736) (xy 248.307075 -318.70448) (xy 246.683492 -318.70448)
			(xy 246.679765 -318.757728) (xy 246.668652 -318.809936) (xy 246.65037 -318.860086) (xy 246.625277 -318.907197)
			(xy 246.593861 -318.950351) (xy 246.556736 -318.988704) (xy 246.535956 -319.005458) (xy 246.52721 -319.013035)
			(xy 246.51702 -319.033783) (xy 246.516398 -319.045336) (xy 246.516398 -319.1256) (xy 246.516969 -319.137168)
			(xy 246.527163 -319.157939) (xy 246.535956 -319.165478) (xy 246.55842 -319.183693) (xy 246.598158 -319.225706)
			(xy 246.631101 -319.273236) (xy 246.656493 -319.325193) (xy 246.673753 -319.380387) (xy 246.682485 -319.437553)
			(xy 246.683022 -319.466468) (xy 246.682536 -319.493719) (xy 246.67478 -319.547667) (xy 246.659425 -319.599962)
			(xy 246.636783 -319.649539) (xy 246.607317 -319.695389) (xy 246.571626 -319.73658) (xy 246.530435 -319.772271)
			(xy 246.484585 -319.801737) (xy 246.435008 -319.824379) (xy 246.382713 -319.839734) (xy 246.328765 -319.84749)
			(xy 246.274263 -319.84749) (xy 246.220315 -319.839734) (xy 246.16802 -319.824379) (xy 246.118443 -319.801737)
			(xy 246.072593 -319.772271) (xy 246.031402 -319.73658) (xy 245.995711 -319.695389) (xy 245.966245 -319.649539)
			(xy 245.943603 -319.599962) (xy 245.928248 -319.547667) (xy 245.920492 -319.493719) (xy 245.920006 -319.466468)
			(xy 245.920571 -319.437553) (xy 245.92929 -319.380384) (xy 245.946538 -319.325186) (xy 245.971921 -319.273224)
			(xy 246.004857 -319.225689) (xy 246.04459 -319.18367) (xy 246.067072 -319.165478) (xy 246.075851 -319.157934)
			(xy 246.086022 -319.137161) (xy 246.08663 -319.1256) (xy 246.08663 -319.045336) (xy 246.086063 -319.033767)
			(xy 246.075869 -319.012994) (xy 246.067072 -319.005458) (xy 246.046257 -318.988743) (xy 246.009125 -318.950386)
			(xy 245.977702 -318.907227) (xy 245.952603 -318.860109) (xy 245.934318 -318.809952) (xy 245.923203 -318.757736)
			(xy 245.919475 -318.70448) (xy 242.975092 -318.70448) (xy 242.971365 -318.757728) (xy 242.960252 -318.809936)
			(xy 242.94197 -318.860086) (xy 242.916877 -318.907197) (xy 242.885461 -318.950351) (xy 242.848336 -318.988704)
			(xy 242.827556 -319.005458) (xy 242.81881 -319.013035) (xy 242.80862 -319.033783) (xy 242.807998 -319.045336)
			(xy 242.807998 -319.1256) (xy 242.808569 -319.137168) (xy 242.818763 -319.157939) (xy 242.827556 -319.165478)
			(xy 242.85002 -319.183693) (xy 242.889758 -319.225706) (xy 242.922701 -319.273236) (xy 242.948093 -319.325193)
			(xy 242.965353 -319.380387) (xy 242.974085 -319.437553) (xy 242.974622 -319.466468) (xy 242.974136 -319.493719)
			(xy 242.96638 -319.547667) (xy 242.951025 -319.599962) (xy 242.928383 -319.649539) (xy 242.898917 -319.695389)
			(xy 242.863226 -319.73658) (xy 242.822035 -319.772271) (xy 242.776185 -319.801737) (xy 242.726608 -319.824379)
			(xy 242.674313 -319.839734) (xy 242.620365 -319.84749) (xy 242.565863 -319.84749) (xy 242.511915 -319.839734)
			(xy 242.45962 -319.824379) (xy 242.410043 -319.801737) (xy 242.364193 -319.772271) (xy 242.323002 -319.73658)
			(xy 242.287311 -319.695389) (xy 242.257845 -319.649539) (xy 242.235203 -319.599962) (xy 242.219848 -319.547667)
			(xy 242.212092 -319.493719) (xy 242.211606 -319.466468) (xy 242.212171 -319.437553) (xy 242.22089 -319.380384)
			(xy 242.238138 -319.325186) (xy 242.263521 -319.273224) (xy 242.296457 -319.225689) (xy 242.33619 -319.18367)
			(xy 242.358672 -319.165478) (xy 242.367451 -319.157934) (xy 242.377622 -319.137161) (xy 242.37823 -319.1256)
			(xy 242.37823 -319.045336) (xy 242.377663 -319.033767) (xy 242.367469 -319.012994) (xy 242.358672 -319.005458)
			(xy 242.337857 -318.988743) (xy 242.300725 -318.950386) (xy 242.269302 -318.907227) (xy 242.244203 -318.860109)
			(xy 242.225918 -318.809952) (xy 242.214803 -318.757736) (xy 242.211075 -318.70448) (xy 240.587492 -318.70448)
			(xy 240.583765 -318.757728) (xy 240.572652 -318.809936) (xy 240.55437 -318.860086) (xy 240.529277 -318.907197)
			(xy 240.497861 -318.950351) (xy 240.460736 -318.988704) (xy 240.439956 -319.005458) (xy 240.43121 -319.013035)
			(xy 240.42102 -319.033783) (xy 240.420398 -319.045336) (xy 240.420398 -319.1256) (xy 240.420969 -319.137168)
			(xy 240.431163 -319.157939) (xy 240.439956 -319.165478) (xy 240.46242 -319.183693) (xy 240.502158 -319.225706)
			(xy 240.535101 -319.273236) (xy 240.560493 -319.325193) (xy 240.577753 -319.380387) (xy 240.586485 -319.437553)
			(xy 240.587022 -319.466468) (xy 240.586536 -319.493719) (xy 240.57878 -319.547667) (xy 240.563425 -319.599962)
			(xy 240.540783 -319.649539) (xy 240.511317 -319.695389) (xy 240.475626 -319.73658) (xy 240.434435 -319.772271)
			(xy 240.388585 -319.801737) (xy 240.339008 -319.824379) (xy 240.286713 -319.839734) (xy 240.232765 -319.84749)
			(xy 240.178263 -319.84749) (xy 240.124315 -319.839734) (xy 240.07202 -319.824379) (xy 240.022443 -319.801737)
			(xy 239.976593 -319.772271) (xy 239.935402 -319.73658) (xy 239.899711 -319.695389) (xy 239.870245 -319.649539)
			(xy 239.847603 -319.599962) (xy 239.832248 -319.547667) (xy 239.824492 -319.493719) (xy 239.824006 -319.466468)
			(xy 239.824571 -319.437553) (xy 239.83329 -319.380384) (xy 239.850538 -319.325186) (xy 239.875921 -319.273224)
			(xy 239.908857 -319.225689) (xy 239.94859 -319.18367) (xy 239.971072 -319.165478) (xy 239.979851 -319.157934)
			(xy 239.990022 -319.137161) (xy 239.99063 -319.1256) (xy 239.99063 -319.045336) (xy 239.990063 -319.033767)
			(xy 239.979869 -319.012994) (xy 239.971072 -319.005458) (xy 239.950257 -318.988743) (xy 239.913125 -318.950386)
			(xy 239.881702 -318.907227) (xy 239.856603 -318.860109) (xy 239.838318 -318.809952) (xy 239.827203 -318.757736)
			(xy 239.823475 -318.70448) (xy 237.3884 -318.70448) (xy 237.3884 -320.866473) (xy 247.984766 -320.866473)
			(xy 247.984766 -320.802551) (xy 247.992777 -320.739133) (xy 248.008674 -320.677219) (xy 248.032206 -320.617786)
			(xy 248.063 -320.561771) (xy 248.100573 -320.510056) (xy 248.14433 -320.463459) (xy 248.193583 -320.422714)
			(xy 248.247554 -320.388463) (xy 248.305393 -320.361246) (xy 248.366186 -320.341493) (xy 248.428976 -320.329515)
			(xy 248.492772 -320.325502) (xy 248.556568 -320.329515) (xy 248.619358 -320.341493) (xy 248.680151 -320.361246)
			(xy 248.73799 -320.388463) (xy 248.791961 -320.422714) (xy 248.841214 -320.463459) (xy 248.884971 -320.510056)
			(xy 248.922544 -320.561771) (xy 248.953338 -320.617786) (xy 248.97687 -320.677219) (xy 248.992767 -320.739133)
			(xy 249.000778 -320.802551) (xy 249.00128 -320.834512) (xy 249.000778 -320.866473) (xy 248.992767 -320.929891)
			(xy 248.97687 -320.991805) (xy 248.953338 -321.051238) (xy 248.922544 -321.107253) (xy 248.884971 -321.158968)
			(xy 248.841214 -321.205565) (xy 248.791961 -321.24631) (xy 248.73799 -321.280561) (xy 248.680151 -321.307778)
			(xy 248.619358 -321.327531) (xy 248.556568 -321.339509) (xy 248.492772 -321.343523) (xy 248.428976 -321.339509)
			(xy 248.366186 -321.327531) (xy 248.305393 -321.307778) (xy 248.247554 -321.280561) (xy 248.193583 -321.24631)
			(xy 248.14433 -321.205565) (xy 248.100573 -321.158968) (xy 248.063 -321.107253) (xy 248.032206 -321.051238)
			(xy 248.008674 -320.991805) (xy 247.992777 -320.929891) (xy 247.984766 -320.866473) (xy 237.3884 -320.866473)
			(xy 237.3884 -321.471544) (xy 238.503968 -321.471544) (xy 238.50447 -321.439583) (xy 238.512481 -321.376165)
			(xy 238.528378 -321.314251) (xy 238.55191 -321.254818) (xy 238.582704 -321.198803) (xy 238.620277 -321.147088)
			(xy 238.664034 -321.100491) (xy 238.713287 -321.059746) (xy 238.767258 -321.025495) (xy 238.825097 -320.998278)
			(xy 238.88589 -320.978525) (xy 238.94868 -320.966547) (xy 239.012476 -320.962534) (xy 239.076272 -320.966547)
			(xy 239.139062 -320.978525) (xy 239.199855 -320.998278) (xy 239.257694 -321.025495) (xy 239.311665 -321.059746)
			(xy 239.360918 -321.100491) (xy 239.404675 -321.147088) (xy 239.442248 -321.198803) (xy 239.473042 -321.254818)
			(xy 239.496574 -321.314251) (xy 239.512471 -321.376165) (xy 239.520482 -321.439583) (xy 239.520984 -321.471544)
			(xy 239.520399 -321.505335) (xy 239.511436 -321.572319) (xy 239.493687 -321.637529) (xy 239.467464 -321.699815)
			(xy 239.433228 -321.758084) (xy 239.391583 -321.811309) (xy 239.384739 -321.818) (xy 242.187982 -321.818)
			(xy 242.192053 -321.762378) (xy 242.204179 -321.707941) (xy 242.224102 -321.65585) (xy 242.251398 -321.607215)
			(xy 242.285484 -321.563072) (xy 242.325633 -321.524363) (xy 242.370991 -321.491912) (xy 242.420591 -321.466411)
			(xy 242.473375 -321.448404) (xy 242.528218 -321.438274) (xy 242.583952 -321.436237) (xy 242.639389 -321.442337)
			(xy 242.693346 -321.456443) (xy 242.744675 -321.478255) (xy 242.792281 -321.507309) (xy 242.835149 -321.542984)
			(xy 242.872366 -321.584521) (xy 242.903139 -321.631034) (xy 242.926811 -321.681531) (xy 242.942879 -321.734938)
			(xy 242.950999 -321.790114) (xy 242.951508 -321.818) (xy 242.950999 -321.845886) (xy 242.942879 -321.901062)
			(xy 242.926811 -321.954469) (xy 242.903139 -322.004966) (xy 242.872366 -322.051479) (xy 242.835149 -322.093016)
			(xy 242.792281 -322.128691) (xy 242.744675 -322.157745) (xy 242.693346 -322.179557) (xy 242.639389 -322.193663)
			(xy 242.583952 -322.199763) (xy 242.528218 -322.197726) (xy 242.473375 -322.187596) (xy 242.420591 -322.169589)
			(xy 242.370991 -322.144088) (xy 242.325633 -322.111637) (xy 242.285484 -322.072928) (xy 242.251398 -322.028785)
			(xy 242.224102 -321.98015) (xy 242.204179 -321.928059) (xy 242.192053 -321.873622) (xy 242.187982 -321.818)
			(xy 239.384739 -321.818) (xy 239.343259 -321.858554) (xy 239.316514 -321.879214) (xy 239.306862 -321.886326)
			(xy 239.296194 -321.907916) (xy 239.296448 -322.013834) (xy 239.30737 -322.035424) (xy 239.317276 -322.042536)
			(xy 239.344475 -322.063121) (xy 239.393624 -322.11042) (xy 239.436008 -322.163865) (xy 239.470865 -322.222498)
			(xy 239.497569 -322.285266) (xy 239.515641 -322.35104) (xy 239.524755 -322.41864) (xy 239.525302 -322.452746)
			(xy 239.5248 -322.484707) (xy 239.516789 -322.548125) (xy 239.500892 -322.610039) (xy 239.47736 -322.669472)
			(xy 239.446566 -322.725487) (xy 239.408993 -322.777202) (xy 239.365236 -322.823799) (xy 239.352905 -322.834)
			(xy 242.187982 -322.834) (xy 242.192053 -322.778378) (xy 242.204179 -322.723941) (xy 242.224102 -322.67185)
			(xy 242.251398 -322.623215) (xy 242.285484 -322.579072) (xy 242.325633 -322.540363) (xy 242.370991 -322.507912)
			(xy 242.420591 -322.482411) (xy 242.473375 -322.464404) (xy 242.528218 -322.454274) (xy 242.583952 -322.452237)
			(xy 242.639389 -322.458337) (xy 242.693346 -322.472443) (xy 242.744675 -322.494255) (xy 242.792281 -322.523309)
			(xy 242.835149 -322.558984) (xy 242.872366 -322.600521) (xy 242.903139 -322.647034) (xy 242.926811 -322.697531)
			(xy 242.942879 -322.750938) (xy 242.950999 -322.806114) (xy 242.951508 -322.834) (xy 242.950999 -322.861886)
			(xy 242.942879 -322.917062) (xy 242.926811 -322.970469) (xy 242.903139 -323.020966) (xy 242.872366 -323.067479)
			(xy 242.835149 -323.109016) (xy 242.792281 -323.144691) (xy 242.744675 -323.173745) (xy 242.693346 -323.195557)
			(xy 242.639389 -323.209663) (xy 242.583952 -323.215763) (xy 242.528218 -323.213726) (xy 242.473375 -323.203596)
			(xy 242.420591 -323.185589) (xy 242.370991 -323.160088) (xy 242.325633 -323.127637) (xy 242.285484 -323.088928)
			(xy 242.251398 -323.044785) (xy 242.224102 -322.99615) (xy 242.204179 -322.944059) (xy 242.192053 -322.889622)
			(xy 242.187982 -322.834) (xy 239.352905 -322.834) (xy 239.315983 -322.864544) (xy 239.262012 -322.898795)
			(xy 239.204173 -322.926012) (xy 239.14338 -322.945765) (xy 239.08059 -322.957743) (xy 239.016794 -322.961757)
			(xy 238.952998 -322.957743) (xy 238.890208 -322.945765) (xy 238.829415 -322.926012) (xy 238.771576 -322.898795)
			(xy 238.717605 -322.864544) (xy 238.668352 -322.823799) (xy 238.624595 -322.777202) (xy 238.587022 -322.725487)
			(xy 238.556228 -322.669472) (xy 238.532696 -322.610039) (xy 238.516799 -322.548125) (xy 238.508788 -322.484707)
			(xy 238.508286 -322.452746) (xy 238.508836 -322.418954) (xy 238.517801 -322.351967) (xy 238.535554 -322.286755)
			(xy 238.561782 -322.224467) (xy 238.596024 -322.166199) (xy 238.637677 -322.112976) (xy 238.686007 -322.065733)
			(xy 238.712756 -322.045076) (xy 238.722408 -322.037964) (xy 238.733076 -322.016374) (xy 238.732822 -321.910456)
			(xy 238.7219 -321.888866) (xy 238.711994 -321.881754) (xy 238.684784 -321.861184) (xy 238.635636 -321.813881)
			(xy 238.593254 -321.760433) (xy 238.558399 -321.701797) (xy 238.531697 -321.639028) (xy 238.513627 -321.573252)
			(xy 238.504514 -321.505651) (xy 238.503968 -321.471544) (xy 237.3884 -321.471544) (xy 237.3884 -323.276468)
			(xy 237.388932 -323.286458) (xy 237.396637 -323.304898) (xy 237.403386 -323.312282) (xy 237.941104 -323.85)
			(xy 242.187982 -323.85) (xy 242.192053 -323.794378) (xy 242.204179 -323.739941) (xy 242.224102 -323.68785)
			(xy 242.251398 -323.639215) (xy 242.285484 -323.595072) (xy 242.325633 -323.556363) (xy 242.370991 -323.523912)
			(xy 242.420591 -323.498411) (xy 242.473375 -323.480404) (xy 242.528218 -323.470274) (xy 242.583952 -323.468237)
			(xy 242.639389 -323.474337) (xy 242.693346 -323.488443) (xy 242.744675 -323.510255) (xy 242.792281 -323.539309)
			(xy 242.835149 -323.574984) (xy 242.872366 -323.616521) (xy 242.903139 -323.663034) (xy 242.926811 -323.713531)
			(xy 242.942879 -323.766938) (xy 242.950999 -323.822114) (xy 242.951508 -323.85) (xy 242.950999 -323.877886)
			(xy 242.942879 -323.933062) (xy 242.926811 -323.986469) (xy 242.903139 -324.036966) (xy 242.872366 -324.083479)
			(xy 242.835149 -324.125016) (xy 242.792281 -324.160691) (xy 242.744675 -324.189745) (xy 242.693346 -324.211557)
			(xy 242.639389 -324.225663) (xy 242.583952 -324.231763) (xy 242.528218 -324.229726) (xy 242.473375 -324.219596)
			(xy 242.420591 -324.201589) (xy 242.370991 -324.176088) (xy 242.325633 -324.143637) (xy 242.285484 -324.104928)
			(xy 242.251398 -324.060785) (xy 242.224102 -324.01215) (xy 242.204179 -323.960059) (xy 242.192053 -323.905622)
			(xy 242.187982 -323.85) (xy 237.941104 -323.85) (xy 239.070134 -324.97903) (xy 239.077531 -324.985879)
			(xy 239.09613 -324.993612) (xy 239.106202 -324.994016)
		)
		(stroke
			(width 0)
			(type solid)
		)
		(fill yes)
		(layer "In13.Cu")
		(net "P1V8_CPU0_RT_1D")
	)
	(gr_poly
		(pts
			(xy 112.12322 -270.574262) (xy 112.123651 -270.564195) (xy 112.131377 -270.545603) (xy 112.138206 -270.538194)
			(xy 113.221262 -269.455138) (xy 113.229099 -269.446582) (xy 113.236721 -269.424692) (xy 113.233933 -269.401682)
			(xy 113.22812 -269.391638) (xy 113.216574 -269.373073) (xy 113.198339 -269.33334) (xy 113.185967 -269.29141)
			(xy 113.179711 -269.248143) (xy 113.179352 -269.226284) (xy 113.179824 -269.202292) (xy 113.187332 -269.1549)
			(xy 113.20216 -269.109266) (xy 113.223944 -269.066513) (xy 113.252147 -269.027693) (xy 113.286075 -268.993762)
			(xy 113.324892 -268.965556) (xy 113.367644 -268.943769) (xy 113.413277 -268.928937) (xy 113.460668 -268.921426)
			(xy 113.48466 -268.920976) (xy 113.506515 -268.921374) (xy 113.549773 -268.927648) (xy 113.591698 -268.940017)
			(xy 113.631434 -268.958229) (xy 113.650014 -268.969744) (xy 113.660061 -268.975523) (xy 113.683054 -268.978251)
			(xy 113.704935 -268.970679) (xy 113.713514 -268.962886) (xy 113.83137 -268.84503) (xy 113.839285 -268.836184)
			(xy 113.846709 -268.813667) (xy 113.845594 -268.80185) (xy 113.832386 -268.709394) (xy 113.818924 -268.69009)
			(xy 113.808256 -268.683994) (xy 113.787988 -268.67241) (xy 113.750915 -268.644041) (xy 113.718599 -268.610354)
			(xy 113.691794 -268.572135) (xy 113.671128 -268.530277) (xy 113.657083 -268.485758) (xy 113.649986 -268.439619)
			(xy 113.649506 -268.416278) (xy 113.650028 -268.391023) (xy 113.658341 -268.341201) (xy 113.674742 -268.293427)
			(xy 113.698783 -268.249004) (xy 113.729807 -268.209144) (xy 113.766969 -268.174934) (xy 113.809255 -268.147308)
			(xy 113.855511 -268.127018) (xy 113.904476 -268.114618) (xy 113.954814 -268.110447) (xy 114.005152 -268.114618)
			(xy 114.054117 -268.127018) (xy 114.100373 -268.147308) (xy 114.142659 -268.174934) (xy 114.179821 -268.209144)
			(xy 114.210845 -268.249004) (xy 114.234886 -268.293427) (xy 114.251287 -268.341201) (xy 114.2596 -268.391023)
			(xy 114.260122 -268.416278) (xy 114.259471 -268.444978) (xy 114.248733 -268.501363) (xy 114.238786 -268.528292)
			(xy 114.23396 -268.540992) (xy 114.23777 -268.567408) (xy 114.30889 -268.657832) (xy 114.333782 -268.667992)
			(xy 114.347244 -268.66596) (xy 114.366518 -268.663522) (xy 114.405287 -268.660979) (xy 114.424714 -268.66088)
			(xy 114.722656 -268.66088) (xy 114.762698 -268.66154) (xy 114.841991 -268.672758) (xy 114.880644 -268.683232)
			(xy 114.887579 -268.685033) (xy 114.901903 -268.685033) (xy 114.908838 -268.683232) (xy 114.947489 -268.672747)
			(xy 115.026783 -268.661529) (xy 115.066826 -268.66088) (xy 115.364768 -268.66088) (xy 115.384195 -268.660985)
			(xy 115.422964 -268.663527) (xy 115.442238 -268.66596) (xy 115.4557 -268.667992) (xy 115.480592 -268.657832)
			(xy 115.551712 -268.567408) (xy 115.555522 -268.540992) (xy 115.550696 -268.528292) (xy 115.540773 -268.501356)
			(xy 115.530025 -268.444975) (xy 115.52936 -268.416278) (xy 115.529882 -268.391023) (xy 115.538195 -268.341201)
			(xy 115.554596 -268.293427) (xy 115.578637 -268.249004) (xy 115.609661 -268.209144) (xy 115.646823 -268.174934)
			(xy 115.689109 -268.147308) (xy 115.735365 -268.127018) (xy 115.78433 -268.114618) (xy 115.834668 -268.110447)
			(xy 115.885006 -268.114618) (xy 115.933971 -268.127018) (xy 115.980227 -268.147308) (xy 116.022513 -268.174934)
			(xy 116.059675 -268.209144) (xy 116.090699 -268.249004) (xy 116.11474 -268.293427) (xy 116.131141 -268.341201)
			(xy 116.139454 -268.391023) (xy 116.139976 -268.416278) (xy 117.408972 -268.416278) (xy 117.412932 -268.367224)
			(xy 117.424709 -268.31944) (xy 117.444 -268.274164) (xy 117.470303 -268.232568) (xy 117.502938 -268.195731)
			(xy 117.541059 -268.164606) (xy 117.58368 -268.139999) (xy 117.629696 -268.122547) (xy 117.677915 -268.112703)
			(xy 117.72709 -268.110722) (xy 117.775945 -268.116654) (xy 117.823216 -268.130346) (xy 117.867678 -268.151444)
			(xy 117.908181 -268.1794) (xy 117.943674 -268.213492) (xy 117.973239 -268.252836) (xy 117.99611 -268.296413)
			(xy 118.011694 -268.343094) (xy 118.019589 -268.391671) (xy 118.020084 -268.416278) (xy 119.288826 -268.416278)
			(xy 119.292786 -268.367224) (xy 119.304563 -268.31944) (xy 119.323854 -268.274164) (xy 119.350157 -268.232568)
			(xy 119.382792 -268.195731) (xy 119.420913 -268.164606) (xy 119.463534 -268.139999) (xy 119.50955 -268.122547)
			(xy 119.557769 -268.112703) (xy 119.606944 -268.110722) (xy 119.655799 -268.116654) (xy 119.70307 -268.130346)
			(xy 119.747532 -268.151444) (xy 119.788035 -268.1794) (xy 119.823528 -268.213492) (xy 119.853093 -268.252836)
			(xy 119.875964 -268.296413) (xy 119.891548 -268.343094) (xy 119.899443 -268.391671) (xy 119.899938 -268.416278)
			(xy 121.168934 -268.416278) (xy 121.172894 -268.367224) (xy 121.184671 -268.31944) (xy 121.203962 -268.274164)
			(xy 121.230265 -268.232568) (xy 121.2629 -268.195731) (xy 121.301021 -268.164606) (xy 121.343642 -268.139999)
			(xy 121.389658 -268.122547) (xy 121.437877 -268.112703) (xy 121.487052 -268.110722) (xy 121.535907 -268.116654)
			(xy 121.583178 -268.130346) (xy 121.62764 -268.151444) (xy 121.668143 -268.1794) (xy 121.703636 -268.213492)
			(xy 121.733201 -268.252836) (xy 121.756072 -268.296413) (xy 121.771656 -268.343094) (xy 121.779551 -268.391671)
			(xy 121.780046 -268.416278) (xy 123.049042 -268.416278) (xy 123.053002 -268.367224) (xy 123.064779 -268.31944)
			(xy 123.08407 -268.274164) (xy 123.110373 -268.232568) (xy 123.143008 -268.195731) (xy 123.181129 -268.164606)
			(xy 123.22375 -268.139999) (xy 123.269766 -268.122547) (xy 123.317985 -268.112703) (xy 123.36716 -268.110722)
			(xy 123.416015 -268.116654) (xy 123.463286 -268.130346) (xy 123.507748 -268.151444) (xy 123.548251 -268.1794)
			(xy 123.583744 -268.213492) (xy 123.613309 -268.252836) (xy 123.63618 -268.296413) (xy 123.651764 -268.343094)
			(xy 123.659659 -268.391671) (xy 123.660154 -268.416278) (xy 124.928896 -268.416278) (xy 124.932856 -268.367224)
			(xy 124.944633 -268.31944) (xy 124.963924 -268.274164) (xy 124.990227 -268.232568) (xy 125.022862 -268.195731)
			(xy 125.060983 -268.164606) (xy 125.103604 -268.139999) (xy 125.14962 -268.122547) (xy 125.197839 -268.112703)
			(xy 125.247014 -268.110722) (xy 125.295869 -268.116654) (xy 125.34314 -268.130346) (xy 125.387602 -268.151444)
			(xy 125.428105 -268.1794) (xy 125.463598 -268.213492) (xy 125.493163 -268.252836) (xy 125.516034 -268.296413)
			(xy 125.531618 -268.343094) (xy 125.539513 -268.391671) (xy 125.540008 -268.416278) (xy 125.539513 -268.440885)
			(xy 125.531618 -268.489462) (xy 125.516034 -268.536143) (xy 125.493163 -268.57972) (xy 125.463598 -268.619064)
			(xy 125.428105 -268.653156) (xy 125.387602 -268.681112) (xy 125.34314 -268.70221) (xy 125.295869 -268.715902)
			(xy 125.247014 -268.721834) (xy 125.197839 -268.719853) (xy 125.14962 -268.710009) (xy 125.103604 -268.692557)
			(xy 125.060983 -268.66795) (xy 125.022862 -268.636825) (xy 124.990227 -268.599988) (xy 124.963924 -268.558392)
			(xy 124.944633 -268.513116) (xy 124.932856 -268.465332) (xy 124.928896 -268.416278) (xy 123.660154 -268.416278)
			(xy 123.659659 -268.440885) (xy 123.651764 -268.489462) (xy 123.63618 -268.536143) (xy 123.613309 -268.57972)
			(xy 123.583744 -268.619064) (xy 123.548251 -268.653156) (xy 123.507748 -268.681112) (xy 123.463286 -268.70221)
			(xy 123.416015 -268.715902) (xy 123.36716 -268.721834) (xy 123.317985 -268.719853) (xy 123.269766 -268.710009)
			(xy 123.22375 -268.692557) (xy 123.181129 -268.66795) (xy 123.143008 -268.636825) (xy 123.110373 -268.599988)
			(xy 123.08407 -268.558392) (xy 123.064779 -268.513116) (xy 123.053002 -268.465332) (xy 123.049042 -268.416278)
			(xy 121.780046 -268.416278) (xy 121.779551 -268.440885) (xy 121.771656 -268.489462) (xy 121.756072 -268.536143)
			(xy 121.733201 -268.57972) (xy 121.703636 -268.619064) (xy 121.668143 -268.653156) (xy 121.62764 -268.681112)
			(xy 121.583178 -268.70221) (xy 121.535907 -268.715902) (xy 121.487052 -268.721834) (xy 121.437877 -268.719853)
			(xy 121.389658 -268.710009) (xy 121.343642 -268.692557) (xy 121.301021 -268.66795) (xy 121.2629 -268.636825)
			(xy 121.230265 -268.599988) (xy 121.203962 -268.558392) (xy 121.184671 -268.513116) (xy 121.172894 -268.465332)
			(xy 121.168934 -268.416278) (xy 119.899938 -268.416278) (xy 119.899443 -268.440885) (xy 119.891548 -268.489462)
			(xy 119.875964 -268.536143) (xy 119.853093 -268.57972) (xy 119.823528 -268.619064) (xy 119.788035 -268.653156)
			(xy 119.747532 -268.681112) (xy 119.70307 -268.70221) (xy 119.655799 -268.715902) (xy 119.606944 -268.721834)
			(xy 119.557769 -268.719853) (xy 119.50955 -268.710009) (xy 119.463534 -268.692557) (xy 119.420913 -268.66795)
			(xy 119.382792 -268.636825) (xy 119.350157 -268.599988) (xy 119.323854 -268.558392) (xy 119.304563 -268.513116)
			(xy 119.292786 -268.465332) (xy 119.288826 -268.416278) (xy 118.020084 -268.416278) (xy 118.019589 -268.440885)
			(xy 118.011694 -268.489462) (xy 117.99611 -268.536143) (xy 117.973239 -268.57972) (xy 117.943674 -268.619064)
			(xy 117.908181 -268.653156) (xy 117.867678 -268.681112) (xy 117.823216 -268.70221) (xy 117.775945 -268.715902)
			(xy 117.72709 -268.721834) (xy 117.677915 -268.719853) (xy 117.629696 -268.710009) (xy 117.58368 -268.692557)
			(xy 117.541059 -268.66795) (xy 117.502938 -268.636825) (xy 117.470303 -268.599988) (xy 117.444 -268.558392)
			(xy 117.424709 -268.513116) (xy 117.412932 -268.465332) (xy 117.408972 -268.416278) (xy 116.139976 -268.416278)
			(xy 116.13952 -268.439741) (xy 116.132293 -268.486109) (xy 116.118066 -268.530828) (xy 116.097174 -268.572849)
			(xy 116.070108 -268.611185) (xy 116.054124 -268.628368) (xy 116.04371 -268.639544) (xy 116.038122 -268.669516)
			(xy 116.08054 -268.769592) (xy 116.084855 -268.778553) (xy 116.098975 -268.792532) (xy 116.117342 -268.800112)
			(xy 116.127276 -268.80058) (xy 116.242338 -268.80058) (xy 116.252406 -268.801009) (xy 116.271002 -268.808731)
			(xy 116.278406 -268.815566) (xy 116.398294 -268.935454) (xy 116.408962 -268.939264) (xy 116.433896 -268.9489)
			(xy 116.480202 -268.9756) (xy 116.521155 -269.00995) (xy 116.555505 -269.050904) (xy 116.582203 -269.097211)
			(xy 116.591842 -269.122144) (xy 116.595652 -269.132812) (xy 116.91874 -269.4559) (xy 116.926152 -269.462578)
			(xy 116.944588 -269.470145) (xy 116.954554 -269.470632) (xy 117.072664 -269.470632) (xy 117.104569 -269.471114)
			(xy 117.167967 -269.478372) (xy 117.199156 -269.48511) (xy 117.204744 -269.48638) (xy 117.284754 -269.48638)
			(xy 117.290342 -269.48511) (xy 117.321529 -269.47836) (xy 117.384928 -269.471107) (xy 117.416834 -269.470632)
			(xy 117.714776 -269.470632) (xy 117.746681 -269.471115) (xy 117.810078 -269.478374) (xy 117.841268 -269.48511)
			(xy 117.846856 -269.48638) (xy 118.75008 -269.48638) (xy 118.762654 -269.485652) (xy 118.784763 -269.473653)
			(xy 118.792244 -269.46352) (xy 118.846092 -269.382494) (xy 118.848632 -269.357094) (xy 118.843552 -269.345156)
			(xy 118.832338 -269.316724) (xy 118.820178 -269.256838) (xy 118.819422 -269.226284) (xy 118.819944 -269.201029)
			(xy 118.828257 -269.151207) (xy 118.844658 -269.103433) (xy 118.868699 -269.05901) (xy 118.899723 -269.01915)
			(xy 118.936885 -268.98494) (xy 118.979171 -268.957314) (xy 119.025427 -268.937024) (xy 119.074392 -268.924624)
			(xy 119.12473 -268.920453) (xy 119.175068 -268.924624) (xy 119.224033 -268.937024) (xy 119.270289 -268.957314)
			(xy 119.312575 -268.98494) (xy 119.349737 -269.01915) (xy 119.380761 -269.05901) (xy 119.404802 -269.103433)
			(xy 119.421203 -269.151207) (xy 119.429516 -269.201029) (xy 119.430038 -269.226284) (xy 119.429484 -269.253731)
			(xy 119.419716 -269.307748) (xy 119.40044 -269.359144) (xy 119.386858 -269.383002) (xy 119.382722 -269.390505)
			(xy 119.379236 -269.407267) (xy 119.381506 -269.424237) (xy 119.38508 -269.432024) (xy 119.398796 -269.458694)
			(xy 119.403413 -269.466805) (xy 119.417279 -269.479274) (xy 119.434685 -269.485966) (xy 119.444008 -269.48638)
			(xy 119.46255 -269.48638) (xy 119.468138 -269.48511) (xy 119.499325 -269.47836) (xy 119.562724 -269.471106)
			(xy 119.59463 -269.470632) (xy 119.892572 -269.470632) (xy 119.924477 -269.471115) (xy 119.987874 -269.478373)
			(xy 120.019064 -269.48511) (xy 120.024652 -269.48638) (xy 120.104662 -269.48638) (xy 120.11025 -269.48511)
			(xy 120.141437 -269.47836) (xy 120.204836 -269.471108) (xy 120.236742 -269.470632) (xy 120.534684 -269.470632)
			(xy 120.566589 -269.471115) (xy 120.629986 -269.478375) (xy 120.661176 -269.48511) (xy 120.666764 -269.48638)
			(xy 121.569988 -269.48638) (xy 121.582561 -269.48565) (xy 121.604667 -269.47365) (xy 121.612152 -269.46352)
			(xy 121.666 -269.382494) (xy 121.66854 -269.357094) (xy 121.66346 -269.345156) (xy 121.652246 -269.316724)
			(xy 121.640086 -269.256838) (xy 121.63933 -269.226284) (xy 121.639852 -269.201029) (xy 121.648165 -269.151207)
			(xy 121.664566 -269.103433) (xy 121.688607 -269.05901) (xy 121.719631 -269.01915) (xy 121.756793 -268.98494)
			(xy 121.799079 -268.957314) (xy 121.845335 -268.937024) (xy 121.8943 -268.924624) (xy 121.944638 -268.920453)
			(xy 121.994976 -268.924624) (xy 122.043941 -268.937024) (xy 122.090197 -268.957314) (xy 122.132483 -268.98494)
			(xy 122.169645 -269.01915) (xy 122.200669 -269.05901) (xy 122.22471 -269.103433) (xy 122.241111 -269.151207)
			(xy 122.249424 -269.201029) (xy 122.249946 -269.226284) (xy 122.249392 -269.253731) (xy 122.239625 -269.307748)
			(xy 122.220348 -269.359145) (xy 122.206766 -269.383002) (xy 122.202629 -269.390504) (xy 122.199143 -269.407267)
			(xy 122.201414 -269.424237) (xy 122.204988 -269.432024) (xy 122.218704 -269.458694) (xy 122.223321 -269.466804)
			(xy 122.237188 -269.47927) (xy 122.254593 -269.48596) (xy 122.263916 -269.48638) (xy 122.282712 -269.48638)
			(xy 122.2883 -269.48511) (xy 122.319487 -269.478357) (xy 122.382886 -269.4711) (xy 122.414792 -269.470632)
			(xy 122.712734 -269.470632) (xy 122.744639 -269.471113) (xy 122.808038 -269.478367) (xy 122.839226 -269.48511)
			(xy 122.844814 -269.48638) (xy 122.924824 -269.48638) (xy 122.930412 -269.48511) (xy 122.961599 -269.478358)
			(xy 123.024998 -269.471102) (xy 123.056904 -269.470632) (xy 123.354846 -269.470632) (xy 123.386751 -269.471113)
			(xy 123.450149 -269.478369) (xy 123.481338 -269.48511) (xy 123.486926 -269.48638) (xy 124.39015 -269.48638)
			(xy 124.402727 -269.485659) (xy 124.424848 -269.473667) (xy 124.432314 -269.46352) (xy 124.486162 -269.382494)
			(xy 124.488702 -269.357094) (xy 124.483622 -269.345156) (xy 124.472406 -269.316725) (xy 124.460243 -269.256838)
			(xy 124.459492 -269.226284) (xy 124.460014 -269.201029) (xy 124.468327 -269.151207) (xy 124.484728 -269.103433)
			(xy 124.508769 -269.05901) (xy 124.539793 -269.01915) (xy 124.576955 -268.98494) (xy 124.619241 -268.957314)
			(xy 124.665497 -268.937024) (xy 124.714462 -268.924624) (xy 124.7648 -268.920453) (xy 124.815138 -268.924624)
			(xy 124.864103 -268.937024) (xy 124.910359 -268.957314) (xy 124.952645 -268.98494) (xy 124.989807 -269.01915)
			(xy 125.020831 -269.05901) (xy 125.044872 -269.103433) (xy 125.061273 -269.151207) (xy 125.069586 -269.201029)
			(xy 125.070108 -269.226284) (xy 125.069554 -269.253731) (xy 125.059785 -269.307747) (xy 125.040507 -269.359143)
			(xy 125.026928 -269.383002) (xy 125.022794 -269.390505) (xy 125.01931 -269.407267) (xy 125.021579 -269.424237)
			(xy 125.02515 -269.432024) (xy 125.038866 -269.458694) (xy 125.043486 -269.466798) (xy 125.057356 -269.479247)
			(xy 125.074759 -269.485916) (xy 125.084078 -269.48638) (xy 125.10262 -269.48638) (xy 125.108208 -269.48511)
			(xy 125.139395 -269.478358) (xy 125.202794 -269.471101) (xy 125.2347 -269.470632) (xy 125.532642 -269.470632)
			(xy 125.564547 -269.471113) (xy 125.627945 -269.478368) (xy 125.659134 -269.48511) (xy 125.664722 -269.48638)
			(xy 125.744732 -269.48638) (xy 125.75032 -269.48511) (xy 125.781507 -269.478359) (xy 125.844906 -269.471103)
			(xy 125.876812 -269.470632) (xy 126.174754 -269.470632) (xy 126.206659 -269.471114) (xy 126.270057 -269.47837)
			(xy 126.301246 -269.48511) (xy 126.306834 -269.48638) (xy 126.656338 -269.48638) (xy 126.666405 -269.485949)
			(xy 126.684997 -269.478223) (xy 126.692406 -269.471394) (xy 126.954534 -269.209266) (xy 126.961382 -269.201869)
			(xy 126.969115 -269.18327) (xy 126.96952 -269.173198) (xy 126.96952 -268.713458) (xy 126.968838 -268.700819)
			(xy 126.956837 -268.678569) (xy 126.94666 -268.67104) (xy 126.92595 -268.656783) (xy 126.889071 -268.622613)
			(xy 126.858296 -268.582857) (xy 126.83446 -268.538591) (xy 126.818208 -268.491014) (xy 126.80998 -268.441416)
			(xy 126.8095 -268.416278) (xy 126.810206 -268.385798) (xy 126.822227 -268.326036) (xy 126.833376 -268.29766)
			(xy 126.839472 -268.283436) (xy 126.83363 -268.25321) (xy 125.917706 -267.337286) (xy 125.910312 -267.330429)
			(xy 125.891713 -267.322679) (xy 125.881638 -267.3223) (xy 125.128528 -267.3223) (xy 125.119892 -267.322641)
			(xy 125.103607 -267.328399) (xy 125.090179 -267.339262) (xy 125.085348 -267.34643) (xy 125.03277 -267.431266)
			(xy 125.031754 -267.457428) (xy 125.037596 -267.469366) (xy 125.047833 -267.490721) (xy 125.062309 -267.53581)
			(xy 125.069638 -267.582594) (xy 125.070108 -267.606272) (xy 125.069586 -267.631527) (xy 125.061273 -267.681349)
			(xy 125.044872 -267.729123) (xy 125.020831 -267.773546) (xy 124.989807 -267.813406) (xy 124.952645 -267.847616)
			(xy 124.910359 -267.875242) (xy 124.864103 -267.895532) (xy 124.815138 -267.907932) (xy 124.7648 -267.912103)
			(xy 124.714462 -267.907932) (xy 124.665497 -267.895532) (xy 124.619241 -267.875242) (xy 124.576955 -267.847616)
			(xy 124.539793 -267.813406) (xy 124.508769 -267.773546) (xy 124.484728 -267.729123) (xy 124.468327 -267.681349)
			(xy 124.460014 -267.631527) (xy 124.459492 -267.606272) (xy 124.459961 -267.582596) (xy 124.46731 -267.535816)
			(xy 124.481783 -267.490728) (xy 124.492004 -267.469366) (xy 124.497846 -267.457428) (xy 124.49683 -267.431266)
			(xy 124.444252 -267.34643) (xy 124.439425 -267.339258) (xy 124.425987 -267.328402) (xy 124.409709 -267.322617)
			(xy 124.401072 -267.3223) (xy 123.589542 -267.3223) (xy 123.579477 -267.321866) (xy 123.560887 -267.314137)
			(xy 123.553474 -267.307314) (xy 123.354846 -267.108686) (xy 123.338844 -267.10132) (xy 123.3297 -267.100558)
			(xy 123.305957 -267.098137) (xy 123.259585 -267.086861) (xy 123.215533 -267.068506) (xy 123.174874 -267.04352)
			(xy 123.138597 -267.012512) (xy 123.107587 -266.976237) (xy 123.0826 -266.935578) (xy 123.064243 -266.891527)
			(xy 123.052965 -266.845156) (xy 123.050554 -266.821412) (xy 123.049792 -266.812268) (xy 123.042426 -266.796266)
			(xy 122.844306 -266.598146) (xy 122.83691 -266.591294) (xy 122.818312 -266.58355) (xy 122.808238 -266.58316)
			(xy 121.887742 -266.58316) (xy 121.877678 -266.583595) (xy 121.859094 -266.591331) (xy 121.851674 -266.598146)
			(xy 121.772934 -266.676886) (xy 121.765822 -266.703302) (xy 121.769378 -266.71651) (xy 121.774353 -266.736073)
			(xy 121.779704 -266.776083) (xy 121.780046 -266.796266) (xy 121.779578 -266.82026) (xy 121.772076 -266.867658)
			(xy 121.757252 -266.913299) (xy 121.735471 -266.956059) (xy 121.707269 -266.994886) (xy 121.67334 -267.028822)
			(xy 121.634521 -267.057034) (xy 121.591766 -267.078825) (xy 121.546128 -267.093659) (xy 121.498732 -267.101172)
			(xy 121.474738 -267.101574) (xy 121.454555 -267.101232) (xy 121.414545 -267.095881) (xy 121.394982 -267.090906)
			(xy 121.381774 -267.08735) (xy 121.355358 -267.094462) (xy 121.211848 -267.237972) (xy 121.204885 -267.245527)
			(xy 121.19713 -267.264533) (xy 121.196862 -267.274802) (xy 121.198132 -267.35786) (xy 121.206514 -267.37691)
			(xy 121.214134 -267.383768) (xy 121.231945 -267.401224) (xy 121.262207 -267.440859) (xy 121.285629 -267.484884)
			(xy 121.301588 -267.532129) (xy 121.309661 -267.581338) (xy 121.310146 -267.606272) (xy 122.578888 -267.606272)
			(xy 122.582848 -267.557218) (xy 122.594625 -267.509434) (xy 122.613916 -267.464158) (xy 122.640219 -267.422562)
			(xy 122.672854 -267.385725) (xy 122.710975 -267.3546) (xy 122.753596 -267.329993) (xy 122.799612 -267.312541)
			(xy 122.847831 -267.302697) (xy 122.897006 -267.300716) (xy 122.945861 -267.306648) (xy 122.993132 -267.32034)
			(xy 123.037594 -267.341438) (xy 123.078097 -267.369394) (xy 123.11359 -267.403486) (xy 123.143155 -267.44283)
			(xy 123.166026 -267.486407) (xy 123.18161 -267.533088) (xy 123.189505 -267.581665) (xy 123.19 -267.606272)
			(xy 123.189505 -267.630879) (xy 123.18161 -267.679456) (xy 123.166026 -267.726137) (xy 123.143155 -267.769714)
			(xy 123.11359 -267.809058) (xy 123.078097 -267.84315) (xy 123.037594 -267.871106) (xy 122.993132 -267.892204)
			(xy 122.945861 -267.905896) (xy 122.897006 -267.911828) (xy 122.847831 -267.909847) (xy 122.799612 -267.900003)
			(xy 122.753596 -267.882551) (xy 122.710975 -267.857944) (xy 122.672854 -267.826819) (xy 122.640219 -267.789982)
			(xy 122.613916 -267.748386) (xy 122.594625 -267.70311) (xy 122.582848 -267.655326) (xy 122.578888 -267.606272)
			(xy 121.310146 -267.606272) (xy 121.309624 -267.631527) (xy 121.301311 -267.681349) (xy 121.28491 -267.729123)
			(xy 121.260869 -267.773546) (xy 121.229845 -267.813406) (xy 121.192683 -267.847616) (xy 121.150397 -267.875242)
			(xy 121.104141 -267.895532) (xy 121.055176 -267.907932) (xy 121.004838 -267.912103) (xy 120.9545 -267.907932)
			(xy 120.905535 -267.895532) (xy 120.859279 -267.875242) (xy 120.816993 -267.847616) (xy 120.779831 -267.813406)
			(xy 120.748807 -267.773546) (xy 120.724766 -267.729123) (xy 120.708365 -267.681349) (xy 120.700052 -267.631527)
			(xy 120.69953 -267.606272) (xy 120.699999 -267.582595) (xy 120.707347 -267.535815) (xy 120.721817 -267.490726)
			(xy 120.732042 -267.469366) (xy 120.737884 -267.457428) (xy 120.736868 -267.431266) (xy 120.68429 -267.34643)
			(xy 120.67946 -267.339265) (xy 120.66602 -267.328425) (xy 120.649743 -267.32266) (xy 120.64111 -267.3223)
			(xy 119.962422 -267.3223) (xy 119.952358 -267.321862) (xy 119.933774 -267.314128) (xy 119.926354 -267.307314)
			(xy 119.713502 -267.094462) (xy 119.687594 -267.08735) (xy 119.674132 -267.09116) (xy 119.654623 -267.096056)
			(xy 119.614742 -267.101286) (xy 119.59463 -267.101574) (xy 119.570636 -267.10113) (xy 119.523239 -267.093627)
			(xy 119.4776 -267.0788) (xy 119.434842 -267.057016) (xy 119.396019 -267.02881) (xy 119.362087 -266.994878)
			(xy 119.333882 -266.956055) (xy 119.312098 -266.913297) (xy 119.297272 -266.867657) (xy 119.28977 -266.82026)
			(xy 119.289322 -266.796266) (xy 119.289609 -266.776154) (xy 119.294834 -266.736272) (xy 119.299736 -266.716764)
			(xy 119.303546 -266.703302) (xy 119.296434 -266.677394) (xy 119.148606 -266.529566) (xy 119.141211 -266.522711)
			(xy 119.122612 -266.514964) (xy 119.112538 -266.51458) (xy 118.245382 -266.51458) (xy 118.235313 -266.515006)
			(xy 118.216711 -266.522723) (xy 118.209314 -266.529566) (xy 118.02237 -266.71651) (xy 118.015004 -266.739116)
			(xy 118.016782 -266.751308) (xy 118.018328 -266.762483) (xy 118.019977 -266.784985) (xy 118.020084 -266.796266)
			(xy 118.01964 -266.82026) (xy 118.012138 -266.867658) (xy 117.997312 -266.913299) (xy 117.975528 -266.956058)
			(xy 117.947322 -266.994883) (xy 117.91339 -267.028816) (xy 117.874567 -267.057023) (xy 117.831808 -267.078808)
			(xy 117.786168 -267.093635) (xy 117.73877 -267.10114) (xy 117.714776 -267.101574) (xy 117.703494 -267.101484)
			(xy 117.680991 -267.099834) (xy 117.669818 -267.098272) (xy 117.657626 -267.096494) (xy 117.63502 -267.10386)
			(xy 117.476016 -267.262864) (xy 117.469447 -267.269985) (xy 117.461746 -267.287746) (xy 117.46103 -267.297408)
			(xy 117.458744 -267.377164) (xy 117.465602 -267.395198) (xy 117.471952 -267.402564) (xy 117.486568 -267.419435)
			(xy 117.511219 -267.456647) (xy 117.530185 -267.497054) (xy 117.543059 -267.539794) (xy 117.549568 -267.583954)
			(xy 117.54993 -267.606272) (xy 118.818926 -267.606272) (xy 118.822886 -267.557218) (xy 118.834663 -267.509434)
			(xy 118.853954 -267.464158) (xy 118.880257 -267.422562) (xy 118.912892 -267.385725) (xy 118.951013 -267.3546)
			(xy 118.993634 -267.329993) (xy 119.03965 -267.312541) (xy 119.087869 -267.302697) (xy 119.137044 -267.300716)
			(xy 119.185899 -267.306648) (xy 119.23317 -267.32034) (xy 119.277632 -267.341438) (xy 119.318135 -267.369394)
			(xy 119.353628 -267.403486) (xy 119.383193 -267.44283) (xy 119.406064 -267.486407) (xy 119.421648 -267.533088)
			(xy 119.429543 -267.581665) (xy 119.430038 -267.606272) (xy 119.429543 -267.630879) (xy 119.421648 -267.679456)
			(xy 119.406064 -267.726137) (xy 119.383193 -267.769714) (xy 119.353628 -267.809058) (xy 119.318135 -267.84315)
			(xy 119.277632 -267.871106) (xy 119.23317 -267.892204) (xy 119.185899 -267.905896) (xy 119.137044 -267.911828)
			(xy 119.087869 -267.909847) (xy 119.03965 -267.900003) (xy 118.993634 -267.882551) (xy 118.951013 -267.857944)
			(xy 118.912892 -267.826819) (xy 118.880257 -267.789982) (xy 118.853954 -267.748386) (xy 118.834663 -267.70311)
			(xy 118.822886 -267.655326) (xy 118.818926 -267.606272) (xy 117.54993 -267.606272) (xy 117.549408 -267.631527)
			(xy 117.541095 -267.681349) (xy 117.524694 -267.729123) (xy 117.500653 -267.773546) (xy 117.469629 -267.813406)
			(xy 117.432467 -267.847616) (xy 117.390181 -267.875242) (xy 117.343925 -267.895532) (xy 117.29496 -267.907932)
			(xy 117.244622 -267.912103) (xy 117.194284 -267.907932) (xy 117.145319 -267.895532) (xy 117.099063 -267.875242)
			(xy 117.056777 -267.847616) (xy 117.019615 -267.813406) (xy 116.988591 -267.773546) (xy 116.96455 -267.729123)
			(xy 116.948149 -267.681349) (xy 116.939836 -267.631527) (xy 116.939314 -267.606272) (xy 116.939783 -267.582595)
			(xy 116.947131 -267.535815) (xy 116.9616 -267.490725) (xy 116.971826 -267.469366) (xy 116.977668 -267.457428)
			(xy 116.976652 -267.431266) (xy 116.924074 -267.34643) (xy 116.919244 -267.339267) (xy 116.905802 -267.328431)
			(xy 116.889526 -267.322671) (xy 116.880894 -267.3223) (xy 116.106702 -267.3223) (xy 116.096632 -267.321877)
			(xy 116.078027 -267.314163) (xy 116.070634 -267.307314) (xy 115.87226 -267.10894) (xy 115.852956 -267.10132)
			(xy 115.842542 -267.101574) (xy 115.834668 -267.101574) (xy 115.810677 -267.101125) (xy 115.763288 -267.093614)
			(xy 115.717657 -267.078783) (xy 115.674907 -267.056995) (xy 115.636093 -267.028788) (xy 115.602169 -266.994857)
			(xy 115.57397 -266.956036) (xy 115.552192 -266.913282) (xy 115.53737 -266.867648) (xy 115.529869 -266.820257)
			(xy 115.52936 -266.796266) (xy 115.52936 -266.788392) (xy 115.529614 -266.777978) (xy 115.521994 -266.758674)
			(xy 115.341146 -266.577826) (xy 115.333746 -266.570985) (xy 115.315147 -266.563267) (xy 115.305078 -266.56284)
			(xy 114.339878 -266.56284) (xy 114.327719 -266.563537) (xy 114.306103 -266.574681) (xy 114.298476 -266.584176)
			(xy 114.243104 -266.661392) (xy 114.239548 -266.685522) (xy 114.243612 -266.69746) (xy 114.251295 -266.721437)
			(xy 114.259598 -266.771094) (xy 114.260122 -266.796266) (xy 114.2596 -266.821521) (xy 114.251287 -266.871343)
			(xy 114.234886 -266.919117) (xy 114.210845 -266.96354) (xy 114.179821 -267.0034) (xy 114.142659 -267.03761)
			(xy 114.100373 -267.065236) (xy 114.054117 -267.085526) (xy 114.005152 -267.097926) (xy 113.954814 -267.102097)
			(xy 113.904476 -267.097926) (xy 113.855511 -267.085526) (xy 113.809255 -267.065236) (xy 113.766969 -267.03761)
			(xy 113.729807 -267.0034) (xy 113.698783 -266.96354) (xy 113.674742 -266.919117) (xy 113.658341 -266.871343)
			(xy 113.650028 -266.821521) (xy 113.649506 -266.796266) (xy 113.650039 -266.771094) (xy 113.658331 -266.721436)
			(xy 113.666016 -266.69746) (xy 113.67008 -266.685522) (xy 113.666524 -266.661392) (xy 113.611152 -266.584176)
			(xy 113.603534 -266.574671) (xy 113.581912 -266.563533) (xy 113.56975 -266.56284) (xy 111.712502 -266.56284)
			(xy 111.702433 -266.563264) (xy 111.683831 -266.570982) (xy 111.676434 -266.577826) (xy 110.946946 -267.307314)
			(xy 110.939549 -267.314161) (xy 110.920949 -267.321889) (xy 110.910878 -267.3223) (xy 110.094776 -267.3223)
			(xy 110.086136 -267.322634) (xy 110.069839 -267.328381) (xy 110.056398 -267.33924) (xy 110.051596 -267.34643)
			(xy 109.999018 -267.431266) (xy 109.998002 -267.457428) (xy 110.003844 -267.469366) (xy 110.014083 -267.490721)
			(xy 110.028561 -267.535809) (xy 110.035891 -267.582594) (xy 110.036356 -267.606272) (xy 113.178856 -267.606272)
			(xy 113.182816 -267.557218) (xy 113.194593 -267.509434) (xy 113.213884 -267.464158) (xy 113.240187 -267.422562)
			(xy 113.272822 -267.385725) (xy 113.310943 -267.3546) (xy 113.353564 -267.329993) (xy 113.39958 -267.312541)
			(xy 113.447799 -267.302697) (xy 113.496974 -267.300716) (xy 113.545829 -267.306648) (xy 113.5931 -267.32034)
			(xy 113.637562 -267.341438) (xy 113.678065 -267.369394) (xy 113.713558 -267.403486) (xy 113.743123 -267.44283)
			(xy 113.765994 -267.486407) (xy 113.781578 -267.533088) (xy 113.789473 -267.581665) (xy 113.789968 -267.606272)
			(xy 115.058964 -267.606272) (xy 115.062924 -267.557218) (xy 115.074701 -267.509434) (xy 115.093992 -267.464158)
			(xy 115.120295 -267.422562) (xy 115.15293 -267.385725) (xy 115.191051 -267.3546) (xy 115.233672 -267.329993)
			(xy 115.279688 -267.312541) (xy 115.327907 -267.302697) (xy 115.377082 -267.300716) (xy 115.425937 -267.306648)
			(xy 115.473208 -267.32034) (xy 115.51767 -267.341438) (xy 115.558173 -267.369394) (xy 115.593666 -267.403486)
			(xy 115.623231 -267.44283) (xy 115.646102 -267.486407) (xy 115.661686 -267.533088) (xy 115.669581 -267.581665)
			(xy 115.670076 -267.606272) (xy 115.669581 -267.630879) (xy 115.661686 -267.679456) (xy 115.646102 -267.726137)
			(xy 115.623231 -267.769714) (xy 115.593666 -267.809058) (xy 115.558173 -267.84315) (xy 115.51767 -267.871106)
			(xy 115.473208 -267.892204) (xy 115.425937 -267.905896) (xy 115.377082 -267.911828) (xy 115.327907 -267.909847)
			(xy 115.279688 -267.900003) (xy 115.233672 -267.882551) (xy 115.191051 -267.857944) (xy 115.15293 -267.826819)
			(xy 115.120295 -267.789982) (xy 115.093992 -267.748386) (xy 115.074701 -267.70311) (xy 115.062924 -267.655326)
			(xy 115.058964 -267.606272) (xy 113.789968 -267.606272) (xy 113.789473 -267.630879) (xy 113.781578 -267.679456)
			(xy 113.765994 -267.726137) (xy 113.743123 -267.769714) (xy 113.713558 -267.809058) (xy 113.678065 -267.84315)
			(xy 113.637562 -267.871106) (xy 113.5931 -267.892204) (xy 113.545829 -267.905896) (xy 113.496974 -267.911828)
			(xy 113.447799 -267.909847) (xy 113.39958 -267.900003) (xy 113.353564 -267.882551) (xy 113.310943 -267.857944)
			(xy 113.272822 -267.826819) (xy 113.240187 -267.789982) (xy 113.213884 -267.748386) (xy 113.194593 -267.70311)
			(xy 113.182816 -267.655326) (xy 113.178856 -267.606272) (xy 110.036356 -267.606272) (xy 110.035834 -267.631527)
			(xy 110.027521 -267.681349) (xy 110.01112 -267.729123) (xy 109.987079 -267.773546) (xy 109.956055 -267.813406)
			(xy 109.918893 -267.847616) (xy 109.876607 -267.875242) (xy 109.830351 -267.895532) (xy 109.781386 -267.907932)
			(xy 109.731048 -267.912103) (xy 109.68071 -267.907932) (xy 109.631745 -267.895532) (xy 109.585489 -267.875242)
			(xy 109.543203 -267.847616) (xy 109.506041 -267.813406) (xy 109.475017 -267.773546) (xy 109.450976 -267.729123)
			(xy 109.434575 -267.681349) (xy 109.426262 -267.631527) (xy 109.42574 -267.606272) (xy 109.426133 -267.583623)
			(xy 109.432791 -267.538818) (xy 109.446001 -267.495491) (xy 109.465473 -267.454593) (xy 109.490778 -267.417023)
			(xy 109.50575 -267.400024) (xy 109.512608 -267.392658) (xy 109.519466 -267.374624) (xy 109.517688 -267.29436)
			(xy 109.517017 -267.284629) (xy 109.509323 -267.266723) (xy 109.502702 -267.259562) (xy 109.346238 -267.103098)
			(xy 109.32287 -267.095478) (xy 109.310678 -267.09751) (xy 109.298383 -267.099402) (xy 109.273587 -267.101436)
			(xy 109.261148 -267.101574) (xy 109.237153 -267.101131) (xy 109.189754 -267.09363) (xy 109.144112 -267.078806)
			(xy 109.101352 -267.057022) (xy 109.062526 -267.028817) (xy 109.028592 -266.994884) (xy 109.000385 -266.95606)
			(xy 108.9786 -266.913301) (xy 108.963773 -266.86766) (xy 108.95627 -266.820261) (xy 108.95584 -266.796266)
			(xy 108.955964 -266.783826) (xy 108.958002 -266.75903) (xy 108.959904 -266.746736) (xy 108.961936 -266.734544)
			(xy 108.954316 -266.711176) (xy 108.790486 -266.547346) (xy 108.783089 -266.540497) (xy 108.76449 -266.53276)
			(xy 108.754418 -266.53236) (xy 107.866942 -266.53236) (xy 107.856878 -266.532795) (xy 107.838294 -266.540531)
			(xy 107.830874 -266.547346) (xy 107.684062 -266.694158) (xy 107.676696 -266.71905) (xy 107.67949 -266.73175)
			(xy 107.682702 -266.747685) (xy 107.686142 -266.780012) (xy 107.686348 -266.796266) (xy 107.68588 -266.82026)
			(xy 107.678378 -266.867658) (xy 107.663554 -266.913299) (xy 107.641773 -266.95606) (xy 107.613571 -266.994886)
			(xy 107.579643 -267.028823) (xy 107.540823 -267.057035) (xy 107.498068 -267.078826) (xy 107.45243 -267.093661)
			(xy 107.405034 -267.101174) (xy 107.38104 -267.101574) (xy 107.364785 -267.10138) (xy 107.332457 -267.097943)
			(xy 107.316524 -267.094716) (xy 107.303824 -267.091922) (xy 107.278932 -267.099288) (xy 107.070906 -267.307314)
			(xy 107.063512 -267.314171) (xy 107.044913 -267.321921) (xy 107.034838 -267.3223) (xy 106.334814 -267.3223)
			(xy 106.326179 -267.322644) (xy 106.309898 -267.328404) (xy 106.296473 -267.339268) (xy 106.291634 -267.34643)
			(xy 106.239056 -267.431266) (xy 106.23804 -267.457428) (xy 106.243882 -267.469366) (xy 106.254119 -267.490721)
			(xy 106.268596 -267.535809) (xy 106.275925 -267.582594) (xy 106.276394 -267.606272) (xy 107.545136 -267.606272)
			(xy 107.549096 -267.557218) (xy 107.560873 -267.509434) (xy 107.580164 -267.464158) (xy 107.606467 -267.422562)
			(xy 107.639102 -267.385725) (xy 107.677223 -267.3546) (xy 107.719844 -267.329993) (xy 107.76586 -267.312541)
			(xy 107.814079 -267.302697) (xy 107.863254 -267.300716) (xy 107.912109 -267.306648) (xy 107.95938 -267.32034)
			(xy 108.003842 -267.341438) (xy 108.044345 -267.369394) (xy 108.079838 -267.403486) (xy 108.109403 -267.44283)
			(xy 108.132274 -267.486407) (xy 108.147858 -267.533088) (xy 108.155753 -267.581665) (xy 108.156248 -267.606272)
			(xy 108.155753 -267.630879) (xy 108.147858 -267.679456) (xy 108.132274 -267.726137) (xy 108.109403 -267.769714)
			(xy 108.079838 -267.809058) (xy 108.044345 -267.84315) (xy 108.003842 -267.871106) (xy 107.95938 -267.892204)
			(xy 107.912109 -267.905896) (xy 107.863254 -267.911828) (xy 107.814079 -267.909847) (xy 107.76586 -267.900003)
			(xy 107.719844 -267.882551) (xy 107.677223 -267.857944) (xy 107.639102 -267.826819) (xy 107.606467 -267.789982)
			(xy 107.580164 -267.748386) (xy 107.560873 -267.70311) (xy 107.549096 -267.655326) (xy 107.545136 -267.606272)
			(xy 106.276394 -267.606272) (xy 106.275872 -267.631527) (xy 106.267559 -267.681349) (xy 106.251158 -267.729123)
			(xy 106.227117 -267.773546) (xy 106.196093 -267.813406) (xy 106.158931 -267.847616) (xy 106.116645 -267.875242)
			(xy 106.070389 -267.895532) (xy 106.021424 -267.907932) (xy 105.971086 -267.912103) (xy 105.920748 -267.907932)
			(xy 105.871783 -267.895532) (xy 105.825527 -267.875242) (xy 105.783241 -267.847616) (xy 105.746079 -267.813406)
			(xy 105.715055 -267.773546) (xy 105.691014 -267.729123) (xy 105.674613 -267.681349) (xy 105.6663 -267.631527)
			(xy 105.665778 -267.606272) (xy 105.666194 -267.583305) (xy 105.673077 -267.537889) (xy 105.686683 -267.494016)
			(xy 105.706706 -267.452676) (xy 105.732694 -267.4148) (xy 105.748074 -267.397738) (xy 105.754932 -267.390372)
			(xy 105.76179 -267.372338) (xy 105.76052 -267.291566) (xy 105.759877 -267.281773) (xy 105.752171 -267.263743)
			(xy 105.745534 -267.256514) (xy 105.590848 -267.101828) (xy 105.567226 -267.094462) (xy 105.555034 -267.096748)
			(xy 105.541623 -267.099012) (xy 105.514532 -267.101431) (xy 105.500932 -267.101574) (xy 105.476938 -267.10113)
			(xy 105.429541 -267.093627) (xy 105.383901 -267.078801) (xy 105.341143 -267.057017) (xy 105.30232 -267.028811)
			(xy 105.268387 -266.994879) (xy 105.240182 -266.956055) (xy 105.218398 -266.913297) (xy 105.203572 -266.867657)
			(xy 105.19607 -266.82026) (xy 105.195624 -266.796266) (xy 105.195774 -266.782667) (xy 105.198191 -266.755575)
			(xy 105.20045 -266.742164) (xy 105.202736 -266.729972) (xy 105.19537 -266.70635) (xy 105.087166 -266.598146)
			(xy 105.079768 -266.5913) (xy 105.061169 -266.583571) (xy 105.051098 -266.58316) (xy 104.012492 -266.58316)
			(xy 104.000645 -266.583779) (xy 103.979451 -266.594371) (xy 103.971852 -266.60348) (xy 103.915718 -266.677648)
			(xy 103.9114 -266.701016) (xy 103.914702 -266.7127) (xy 103.920147 -266.733162) (xy 103.926008 -266.775096)
			(xy 103.926386 -266.796266) (xy 103.925942 -266.82026) (xy 103.91844 -266.867659) (xy 103.903614 -266.913299)
			(xy 103.88183 -266.956059) (xy 103.853625 -266.994883) (xy 103.819692 -267.028817) (xy 103.780869 -267.057024)
			(xy 103.73811 -267.078809) (xy 103.69247 -267.093637) (xy 103.645072 -267.101141) (xy 103.621078 -267.101574)
			(xy 103.59476 -267.101021) (xy 103.542902 -267.091995) (xy 103.493359 -267.074214) (xy 103.470202 -267.061696)
			(xy 103.455216 -267.05306) (xy 103.421688 -267.057632) (xy 103.172006 -267.307314) (xy 103.164612 -267.314171)
			(xy 103.146013 -267.321921) (xy 103.135938 -267.3223) (xy 102.574852 -267.3223) (xy 102.566214 -267.322638)
			(xy 102.549923 -267.32839) (xy 102.536488 -267.339251) (xy 102.531672 -267.34643) (xy 102.479094 -267.431266)
			(xy 102.478078 -267.457428) (xy 102.48392 -267.469366) (xy 102.494157 -267.490721) (xy 102.508632 -267.53581)
			(xy 102.51596 -267.582594) (xy 102.516432 -267.606272) (xy 103.785174 -267.606272) (xy 103.789134 -267.557218)
			(xy 103.800911 -267.509434) (xy 103.820202 -267.464158) (xy 103.846505 -267.422562) (xy 103.87914 -267.385725)
			(xy 103.917261 -267.3546) (xy 103.959882 -267.329993) (xy 104.005898 -267.312541) (xy 104.054117 -267.302697)
			(xy 104.103292 -267.300716) (xy 104.152147 -267.306648) (xy 104.199418 -267.32034) (xy 104.24388 -267.341438)
			(xy 104.284383 -267.369394) (xy 104.319876 -267.403486) (xy 104.349441 -267.44283) (xy 104.372312 -267.486407)
			(xy 104.387896 -267.533088) (xy 104.395791 -267.581665) (xy 104.396286 -267.606272) (xy 104.395791 -267.630879)
			(xy 104.387896 -267.679456) (xy 104.372312 -267.726137) (xy 104.349441 -267.769714) (xy 104.319876 -267.809058)
			(xy 104.284383 -267.84315) (xy 104.24388 -267.871106) (xy 104.199418 -267.892204) (xy 104.152147 -267.905896)
			(xy 104.103292 -267.911828) (xy 104.054117 -267.909847) (xy 104.005898 -267.900003) (xy 103.959882 -267.882551)
			(xy 103.917261 -267.857944) (xy 103.87914 -267.826819) (xy 103.846505 -267.789982) (xy 103.820202 -267.748386)
			(xy 103.800911 -267.70311) (xy 103.789134 -267.655326) (xy 103.785174 -267.606272) (xy 102.516432 -267.606272)
			(xy 102.51591 -267.631527) (xy 102.507597 -267.681349) (xy 102.491196 -267.729123) (xy 102.467155 -267.773546)
			(xy 102.436131 -267.813406) (xy 102.398969 -267.847616) (xy 102.356683 -267.875242) (xy 102.310427 -267.895532)
			(xy 102.261462 -267.907932) (xy 102.211124 -267.912103) (xy 102.160786 -267.907932) (xy 102.111821 -267.895532)
			(xy 102.065565 -267.875242) (xy 102.023279 -267.847616) (xy 101.986117 -267.813406) (xy 101.955093 -267.773546)
			(xy 101.931052 -267.729123) (xy 101.914651 -267.681349) (xy 101.906338 -267.631527) (xy 101.905816 -267.606272)
			(xy 101.906285 -267.582595) (xy 101.913633 -267.535815) (xy 101.928102 -267.490726) (xy 101.938328 -267.469366)
			(xy 101.94417 -267.457428) (xy 101.943154 -267.431266) (xy 101.890576 -267.34643) (xy 101.885746 -267.339267)
			(xy 101.872304 -267.32843) (xy 101.856028 -267.322669) (xy 101.847396 -267.3223) (xy 100.694744 -267.3223)
			(xy 100.686106 -267.322639) (xy 100.669818 -267.328393) (xy 100.656385 -267.339255) (xy 100.651564 -267.34643)
			(xy 100.598986 -267.431266) (xy 100.59797 -267.457428) (xy 100.603812 -267.469366) (xy 100.614049 -267.490721)
			(xy 100.628524 -267.53581) (xy 100.635852 -267.582594) (xy 100.636324 -267.606272) (xy 100.635802 -267.631527)
			(xy 100.627489 -267.681349) (xy 100.611088 -267.729123) (xy 100.587047 -267.773546) (xy 100.556023 -267.813406)
			(xy 100.518861 -267.847616) (xy 100.476575 -267.875242) (xy 100.430319 -267.895532) (xy 100.381354 -267.907932)
			(xy 100.331016 -267.912103) (xy 100.280678 -267.907932) (xy 100.231713 -267.895532) (xy 100.185457 -267.875242)
			(xy 100.143171 -267.847616) (xy 100.106009 -267.813406) (xy 100.074985 -267.773546) (xy 100.050944 -267.729123)
			(xy 100.034543 -267.681349) (xy 100.02623 -267.631527) (xy 100.025708 -267.606272) (xy 100.026177 -267.582596)
			(xy 100.033527 -267.535816) (xy 100.048 -267.490728) (xy 100.05822 -267.469366) (xy 100.064062 -267.457428)
			(xy 100.063046 -267.431266) (xy 100.010468 -267.34643) (xy 100.005638 -267.339268) (xy 99.992196 -267.328433)
			(xy 99.97592 -267.322675) (xy 99.967288 -267.3223) (xy 99.75469 -267.3223) (xy 99.746048 -267.322632)
			(xy 99.729749 -267.328375) (xy 99.716304 -267.339234) (xy 99.71151 -267.34643) (xy 99.658932 -267.431266)
			(xy 99.657916 -267.457428) (xy 99.663758 -267.469366) (xy 99.673996 -267.490721) (xy 99.688474 -267.535809)
			(xy 99.695804 -267.582594) (xy 99.69627 -267.606272) (xy 99.695826 -267.630265) (xy 99.688322 -267.677662)
			(xy 99.673496 -267.723301) (xy 99.651711 -267.766058) (xy 99.623506 -267.804881) (xy 99.589573 -267.838812)
			(xy 99.55075 -267.867017) (xy 99.507992 -267.8888) (xy 99.462352 -267.903625) (xy 99.414956 -267.911127)
			(xy 99.390962 -267.91158) (xy 99.366088 -267.911094) (xy 99.316999 -267.903033) (xy 99.269868 -267.887114)
			(xy 99.225943 -267.86376) (xy 99.18639 -267.833588) (xy 99.152257 -267.797399) (xy 99.124446 -267.756152)
			(xy 99.103697 -267.710939) (xy 99.090557 -267.662958) (xy 99.087432 -267.638276) (xy 99.085908 -267.623544)
			(xy 99.06762 -267.600684) (xy 98.96729 -267.565124) (xy 98.958148 -267.562294) (xy 98.939037 -267.562945)
			(xy 98.921508 -267.570588) (xy 98.914458 -267.577062) (xy 98.485706 -268.005814) (xy 111.710473 -268.005814)
			(xy 111.714503 -267.953316) (xy 111.7265 -267.902048) (xy 111.746183 -267.853213) (xy 111.773089 -267.807954)
			(xy 111.806589 -267.767333) (xy 111.845897 -267.732302) (xy 111.890092 -267.703682) (xy 111.938137 -267.682143)
			(xy 111.988908 -267.668191) (xy 112.041213 -267.662153) (xy 112.093827 -267.66417) (xy 112.145517 -267.674194)
			(xy 112.19507 -267.691992) (xy 112.241326 -267.717145) (xy 112.2832 -267.749064) (xy 112.319712 -267.787002)
			(xy 112.350004 -267.830068) (xy 112.373367 -267.877253) (xy 112.389253 -267.927452) (xy 112.39729 -267.979488)
			(xy 112.397794 -268.005814) (xy 112.39729 -268.03214) (xy 112.389253 -268.084176) (xy 112.373367 -268.134375)
			(xy 112.350004 -268.18156) (xy 112.319712 -268.224626) (xy 112.2832 -268.262564) (xy 112.241326 -268.294483)
			(xy 112.19507 -268.319636) (xy 112.145517 -268.337434) (xy 112.093827 -268.347458) (xy 112.041213 -268.349475)
			(xy 111.988908 -268.343437) (xy 111.938137 -268.329485) (xy 111.890092 -268.307946) (xy 111.845897 -268.279326)
			(xy 111.806589 -268.244295) (xy 111.773089 -268.203674) (xy 111.746183 -268.158415) (xy 111.7265 -268.10958)
			(xy 111.714503 -268.058312) (xy 111.710473 -268.005814) (xy 98.485706 -268.005814) (xy 98.254312 -268.237208)
			(xy 98.248978 -268.268958) (xy 98.25609 -268.28369) (xy 98.265617 -268.304482) (xy 98.279086 -268.348188)
			(xy 98.285906 -268.393411) (xy 98.286316 -268.416278) (xy 99.555312 -268.416278) (xy 99.559272 -268.367224)
			(xy 99.571049 -268.31944) (xy 99.59034 -268.274164) (xy 99.616643 -268.232568) (xy 99.649278 -268.195731)
			(xy 99.687399 -268.164606) (xy 99.73002 -268.139999) (xy 99.776036 -268.122547) (xy 99.824255 -268.112703)
			(xy 99.87343 -268.110722) (xy 99.922285 -268.116654) (xy 99.969556 -268.130346) (xy 100.014018 -268.151444)
			(xy 100.054521 -268.1794) (xy 100.090014 -268.213492) (xy 100.119579 -268.252836) (xy 100.14245 -268.296413)
			(xy 100.158034 -268.343094) (xy 100.165929 -268.391671) (xy 100.166424 -268.416278) (xy 101.435166 -268.416278)
			(xy 101.439126 -268.367224) (xy 101.450903 -268.31944) (xy 101.470194 -268.274164) (xy 101.496497 -268.232568)
			(xy 101.529132 -268.195731) (xy 101.567253 -268.164606) (xy 101.609874 -268.139999) (xy 101.65589 -268.122547)
			(xy 101.704109 -268.112703) (xy 101.753284 -268.110722) (xy 101.802139 -268.116654) (xy 101.84941 -268.130346)
			(xy 101.893872 -268.151444) (xy 101.934375 -268.1794) (xy 101.969868 -268.213492) (xy 101.999433 -268.252836)
			(xy 102.022304 -268.296413) (xy 102.037888 -268.343094) (xy 102.045783 -268.391671) (xy 102.046278 -268.416278)
			(xy 103.315274 -268.416278) (xy 103.319234 -268.367224) (xy 103.331011 -268.31944) (xy 103.350302 -268.274164)
			(xy 103.376605 -268.232568) (xy 103.40924 -268.195731) (xy 103.447361 -268.164606) (xy 103.489982 -268.139999)
			(xy 103.535998 -268.122547) (xy 103.584217 -268.112703) (xy 103.633392 -268.110722) (xy 103.682247 -268.116654)
			(xy 103.729518 -268.130346) (xy 103.77398 -268.151444) (xy 103.814483 -268.1794) (xy 103.849976 -268.213492)
			(xy 103.879541 -268.252836) (xy 103.902412 -268.296413) (xy 103.917996 -268.343094) (xy 103.925891 -268.391671)
			(xy 103.926386 -268.416278) (xy 105.195128 -268.416278) (xy 105.199088 -268.367224) (xy 105.210865 -268.31944)
			(xy 105.230156 -268.274164) (xy 105.256459 -268.232568) (xy 105.289094 -268.195731) (xy 105.327215 -268.164606)
			(xy 105.369836 -268.139999) (xy 105.415852 -268.122547) (xy 105.464071 -268.112703) (xy 105.513246 -268.110722)
			(xy 105.562101 -268.116654) (xy 105.609372 -268.130346) (xy 105.653834 -268.151444) (xy 105.694337 -268.1794)
			(xy 105.72983 -268.213492) (xy 105.759395 -268.252836) (xy 105.782266 -268.296413) (xy 105.79785 -268.343094)
			(xy 105.805745 -268.391671) (xy 105.80624 -268.416278) (xy 107.075236 -268.416278) (xy 107.079196 -268.367224)
			(xy 107.090973 -268.31944) (xy 107.110264 -268.274164) (xy 107.136567 -268.232568) (xy 107.169202 -268.195731)
			(xy 107.207323 -268.164606) (xy 107.249944 -268.139999) (xy 107.29596 -268.122547) (xy 107.344179 -268.112703)
			(xy 107.393354 -268.110722) (xy 107.442209 -268.116654) (xy 107.48948 -268.130346) (xy 107.533942 -268.151444)
			(xy 107.574445 -268.1794) (xy 107.609938 -268.213492) (xy 107.639503 -268.252836) (xy 107.662374 -268.296413)
			(xy 107.677958 -268.343094) (xy 107.685853 -268.391671) (xy 107.686348 -268.416278) (xy 108.955344 -268.416278)
			(xy 108.959304 -268.367224) (xy 108.971081 -268.31944) (xy 108.990372 -268.274164) (xy 109.016675 -268.232568)
			(xy 109.04931 -268.195731) (xy 109.087431 -268.164606) (xy 109.130052 -268.139999) (xy 109.176068 -268.122547)
			(xy 109.224287 -268.112703) (xy 109.273462 -268.110722) (xy 109.322317 -268.116654) (xy 109.369588 -268.130346)
			(xy 109.41405 -268.151444) (xy 109.454553 -268.1794) (xy 109.490046 -268.213492) (xy 109.519611 -268.252836)
			(xy 109.542482 -268.296413) (xy 109.558066 -268.343094) (xy 109.565961 -268.391671) (xy 109.566456 -268.416278)
			(xy 109.565961 -268.440885) (xy 109.558066 -268.489462) (xy 109.542482 -268.536143) (xy 109.519611 -268.57972)
			(xy 109.490046 -268.619064) (xy 109.454553 -268.653156) (xy 109.41405 -268.681112) (xy 109.369588 -268.70221)
			(xy 109.322317 -268.715902) (xy 109.273462 -268.721834) (xy 109.224287 -268.719853) (xy 109.176068 -268.710009)
			(xy 109.130052 -268.692557) (xy 109.087431 -268.66795) (xy 109.04931 -268.636825) (xy 109.016675 -268.599988)
			(xy 108.990372 -268.558392) (xy 108.971081 -268.513116) (xy 108.959304 -268.465332) (xy 108.955344 -268.416278)
			(xy 107.686348 -268.416278) (xy 107.685853 -268.440885) (xy 107.677958 -268.489462) (xy 107.662374 -268.536143)
			(xy 107.639503 -268.57972) (xy 107.609938 -268.619064) (xy 107.574445 -268.653156) (xy 107.533942 -268.681112)
			(xy 107.48948 -268.70221) (xy 107.442209 -268.715902) (xy 107.393354 -268.721834) (xy 107.344179 -268.719853)
			(xy 107.29596 -268.710009) (xy 107.249944 -268.692557) (xy 107.207323 -268.66795) (xy 107.169202 -268.636825)
			(xy 107.136567 -268.599988) (xy 107.110264 -268.558392) (xy 107.090973 -268.513116) (xy 107.079196 -268.465332)
			(xy 107.075236 -268.416278) (xy 105.80624 -268.416278) (xy 105.805745 -268.440885) (xy 105.79785 -268.489462)
			(xy 105.782266 -268.536143) (xy 105.759395 -268.57972) (xy 105.72983 -268.619064) (xy 105.694337 -268.653156)
			(xy 105.653834 -268.681112) (xy 105.609372 -268.70221) (xy 105.562101 -268.715902) (xy 105.513246 -268.721834)
			(xy 105.464071 -268.719853) (xy 105.415852 -268.710009) (xy 105.369836 -268.692557) (xy 105.327215 -268.66795)
			(xy 105.289094 -268.636825) (xy 105.256459 -268.599988) (xy 105.230156 -268.558392) (xy 105.210865 -268.513116)
			(xy 105.199088 -268.465332) (xy 105.195128 -268.416278) (xy 103.926386 -268.416278) (xy 103.925891 -268.440885)
			(xy 103.917996 -268.489462) (xy 103.902412 -268.536143) (xy 103.879541 -268.57972) (xy 103.849976 -268.619064)
			(xy 103.814483 -268.653156) (xy 103.77398 -268.681112) (xy 103.729518 -268.70221) (xy 103.682247 -268.715902)
			(xy 103.633392 -268.721834) (xy 103.584217 -268.719853) (xy 103.535998 -268.710009) (xy 103.489982 -268.692557)
			(xy 103.447361 -268.66795) (xy 103.40924 -268.636825) (xy 103.376605 -268.599988) (xy 103.350302 -268.558392)
			(xy 103.331011 -268.513116) (xy 103.319234 -268.465332) (xy 103.315274 -268.416278) (xy 102.046278 -268.416278)
			(xy 102.045783 -268.440885) (xy 102.037888 -268.489462) (xy 102.022304 -268.536143) (xy 101.999433 -268.57972)
			(xy 101.969868 -268.619064) (xy 101.934375 -268.653156) (xy 101.893872 -268.681112) (xy 101.84941 -268.70221)
			(xy 101.802139 -268.715902) (xy 101.753284 -268.721834) (xy 101.704109 -268.719853) (xy 101.65589 -268.710009)
			(xy 101.609874 -268.692557) (xy 101.567253 -268.66795) (xy 101.529132 -268.636825) (xy 101.496497 -268.599988)
			(xy 101.470194 -268.558392) (xy 101.450903 -268.513116) (xy 101.439126 -268.465332) (xy 101.435166 -268.416278)
			(xy 100.166424 -268.416278) (xy 100.165929 -268.440885) (xy 100.158034 -268.489462) (xy 100.14245 -268.536143)
			(xy 100.119579 -268.57972) (xy 100.090014 -268.619064) (xy 100.054521 -268.653156) (xy 100.014018 -268.681112)
			(xy 99.969556 -268.70221) (xy 99.922285 -268.715902) (xy 99.87343 -268.721834) (xy 99.824255 -268.719853)
			(xy 99.776036 -268.710009) (xy 99.73002 -268.692557) (xy 99.687399 -268.66795) (xy 99.649278 -268.636825)
			(xy 99.616643 -268.599988) (xy 99.59034 -268.558392) (xy 99.571049 -268.513116) (xy 99.559272 -268.465332)
			(xy 99.555312 -268.416278) (xy 98.286316 -268.416278) (xy 98.285871 -268.440273) (xy 98.278368 -268.487671)
			(xy 98.263541 -268.533312) (xy 98.241757 -268.576072) (xy 98.213552 -268.614897) (xy 98.17962 -268.648832)
			(xy 98.140798 -268.677041) (xy 98.09804 -268.69883) (xy 98.0524 -268.713661) (xy 98.005002 -268.721169)
			(xy 97.981008 -268.721586) (xy 97.958137 -268.721205) (xy 97.912902 -268.714419) (xy 97.869192 -268.700939)
			(xy 97.84842 -268.69136) (xy 97.833688 -268.684248) (xy 97.801938 -268.689582) (xy 97.654872 -268.836648)
			(xy 109.923326 -268.836648) (xy 110.112556 -269.025878) (xy 110.112556 -269.226284) (xy 110.365298 -269.226284)
			(xy 110.369258 -269.17723) (xy 110.381035 -269.129446) (xy 110.400326 -269.08417) (xy 110.426629 -269.042574)
			(xy 110.459264 -269.005737) (xy 110.497385 -268.974612) (xy 110.540006 -268.950005) (xy 110.586022 -268.932553)
			(xy 110.634241 -268.922709) (xy 110.683416 -268.920728) (xy 110.732271 -268.92666) (xy 110.779542 -268.940352)
			(xy 110.824004 -268.96145) (xy 110.864507 -268.989406) (xy 110.9 -269.023498) (xy 110.929565 -269.062842)
			(xy 110.952436 -269.106419) (xy 110.96802 -269.1531) (xy 110.975915 -269.201677) (xy 110.97641 -269.226284)
			(xy 110.975915 -269.250891) (xy 110.96802 -269.299468) (xy 110.952436 -269.346149) (xy 110.929565 -269.389726)
			(xy 110.9 -269.42907) (xy 110.864507 -269.463162) (xy 110.824004 -269.491118) (xy 110.779542 -269.512216)
			(xy 110.732271 -269.525908) (xy 110.683416 -269.53184) (xy 110.634241 -269.529859) (xy 110.586022 -269.520015)
			(xy 110.540006 -269.502563) (xy 110.497385 -269.477956) (xy 110.459264 -269.446831) (xy 110.426629 -269.409994)
			(xy 110.400326 -269.368398) (xy 110.381035 -269.323122) (xy 110.369258 -269.275338) (xy 110.365298 -269.226284)
			(xy 110.112556 -269.226284) (xy 110.112556 -269.310104) (xy 111.376714 -270.574262)
		)
		(stroke
			(width 0)
			(type solid)
		)
		(fill yes)
		(layer "In13.Cu")
		(net "PVDDCR_CPU1_P1")
	)
	(gr_poly
		(pts
			(xy 260.824218 -294.732202) (xy 260.834287 -294.731775) (xy 260.852887 -294.724057) (xy 260.860286 -294.717216)
			(xy 262.02386 -293.553642) (xy 262.030702 -293.546242) (xy 262.038421 -293.527644) (xy 262.038846 -293.517574)
			(xy 262.038846 -273.641058) (xy 262.038414 -273.630992) (xy 262.030683 -273.612404) (xy 262.02386 -273.60499)
			(xy 254.196342 -265.777472) (xy 254.188944 -265.770627) (xy 254.170345 -265.762902) (xy 254.160274 -265.762486)
			(xy 218.291156 -265.762486) (xy 218.272614 -265.770106) (xy 218.265756 -265.776964) (xy 217.050112 -265.776964)
			(xy 217.040042 -265.777387) (xy 217.021441 -265.785105) (xy 217.014044 -265.79195) (xy 213.035039 -269.770955)
			(xy 221.508737 -269.770955) (xy 221.508737 -269.716445) (xy 221.516495 -269.662489) (xy 221.531853 -269.610186)
			(xy 221.554499 -269.560602) (xy 221.583971 -269.514745) (xy 221.619669 -269.473549) (xy 221.660867 -269.437854)
			(xy 221.706726 -269.408385) (xy 221.756312 -269.385743) (xy 221.808616 -269.370389) (xy 221.862573 -269.362635)
			(xy 221.889828 -269.362174) (xy 221.918744 -269.362716) (xy 221.975916 -269.371436) (xy 222.031115 -269.388688)
			(xy 222.083078 -269.414075) (xy 222.130612 -269.447016) (xy 222.172628 -269.486755) (xy 222.190818 -269.50924)
			(xy 222.19837 -269.518012) (xy 222.219136 -269.528188) (xy 222.230696 -269.528798) (xy 222.31096 -269.528798)
			(xy 222.322525 -269.528205) (xy 222.343296 -269.518027) (xy 222.350838 -269.50924) (xy 222.367591 -269.488457)
			(xy 222.405945 -269.451327) (xy 222.449099 -269.419905) (xy 222.496213 -269.394806) (xy 222.546365 -269.37652)
			(xy 222.598576 -269.365403) (xy 222.651828 -269.361673) (xy 222.70508 -269.365403) (xy 222.757291 -269.37652)
			(xy 222.807443 -269.394806) (xy 222.854557 -269.419905) (xy 222.897711 -269.451327) (xy 222.936065 -269.488457)
			(xy 222.952818 -269.50924) (xy 222.96037 -269.518012) (xy 222.981136 -269.528188) (xy 222.992696 -269.528798)
			(xy 223.07296 -269.528798) (xy 223.084525 -269.528205) (xy 223.105296 -269.518027) (xy 223.112838 -269.50924)
			(xy 223.129591 -269.488457) (xy 223.167945 -269.451327) (xy 223.211099 -269.419905) (xy 223.258213 -269.394806)
			(xy 223.308365 -269.37652) (xy 223.360576 -269.365403) (xy 223.413828 -269.361673) (xy 223.46708 -269.365403)
			(xy 223.519291 -269.37652) (xy 223.569443 -269.394806) (xy 223.616557 -269.419905) (xy 223.659711 -269.451327)
			(xy 223.698065 -269.488457) (xy 223.714818 -269.50924) (xy 223.72237 -269.518012) (xy 223.743136 -269.528188)
			(xy 223.754696 -269.528798) (xy 223.83496 -269.528798) (xy 223.846525 -269.528205) (xy 223.867296 -269.518027)
			(xy 223.874838 -269.50924) (xy 223.893018 -269.486747) (xy 223.935039 -269.44701) (xy 223.982575 -269.414071)
			(xy 224.034539 -269.388684) (xy 224.089739 -269.371431) (xy 224.146911 -269.362706) (xy 224.175828 -269.362174)
			(xy 224.203077 -269.362698) (xy 224.257019 -269.370458) (xy 224.309308 -269.385814) (xy 224.358879 -269.408456)
			(xy 224.404724 -269.437922) (xy 224.445908 -269.473611) (xy 224.481595 -269.514799) (xy 224.511057 -269.560646)
			(xy 224.533695 -269.610219) (xy 224.549048 -269.662509) (xy 224.556804 -269.716451) (xy 224.556804 -269.770949)
			(xy 224.549048 -269.824891) (xy 224.533695 -269.877181) (xy 224.511057 -269.926754) (xy 224.481595 -269.972601)
			(xy 224.445908 -270.013789) (xy 224.404724 -270.049478) (xy 224.358879 -270.078944) (xy 224.309308 -270.101586)
			(xy 224.257019 -270.116942) (xy 224.203077 -270.124702) (xy 224.175828 -270.12519) (xy 224.146912 -270.124655)
			(xy 224.089741 -270.11593) (xy 224.034542 -270.098676) (xy 223.982581 -270.073287) (xy 223.935046 -270.040346)
			(xy 223.893029 -270.000608) (xy 223.874838 -269.978124) (xy 223.867268 -269.969371) (xy 223.846515 -269.959186)
			(xy 223.83496 -269.958566) (xy 223.754696 -269.958566) (xy 223.743124 -269.959111) (xy 223.722352 -269.969321)
			(xy 223.714818 -269.978124) (xy 223.698065 -269.998907) (xy 223.659711 -270.036037) (xy 223.616557 -270.067459)
			(xy 223.569443 -270.092558) (xy 223.519291 -270.110844) (xy 223.46708 -270.121961) (xy 223.413828 -270.125691)
			(xy 223.360576 -270.121961) (xy 223.308365 -270.110844) (xy 223.258213 -270.092558) (xy 223.211099 -270.067459)
			(xy 223.167945 -270.036037) (xy 223.129591 -269.998907) (xy 223.112838 -269.978124) (xy 223.105268 -269.969371)
			(xy 223.084515 -269.959186) (xy 223.07296 -269.958566) (xy 222.992696 -269.958566) (xy 222.981124 -269.959111)
			(xy 222.960352 -269.969321) (xy 222.952818 -269.978124) (xy 222.936065 -269.998907) (xy 222.897711 -270.036037)
			(xy 222.854557 -270.067459) (xy 222.807443 -270.092558) (xy 222.757291 -270.110844) (xy 222.70508 -270.121961)
			(xy 222.651828 -270.125691) (xy 222.598576 -270.121961) (xy 222.546365 -270.110844) (xy 222.496213 -270.092558)
			(xy 222.449099 -270.067459) (xy 222.405945 -270.036037) (xy 222.367591 -269.998907) (xy 222.350838 -269.978124)
			(xy 222.343268 -269.969371) (xy 222.322515 -269.959186) (xy 222.31096 -269.958566) (xy 222.230696 -269.958566)
			(xy 222.219124 -269.959111) (xy 222.198352 -269.969321) (xy 222.190818 -269.978124) (xy 222.172623 -270.000604)
			(xy 222.130603 -270.040338) (xy 222.083069 -270.073277) (xy 222.031109 -270.098666) (xy 221.975912 -270.115923)
			(xy 221.918744 -270.124654) (xy 221.889828 -270.12519) (xy 221.862573 -270.124765) (xy 221.808616 -270.117011)
			(xy 221.756312 -270.101657) (xy 221.706726 -270.079015) (xy 221.660867 -270.049546) (xy 221.619669 -270.013851)
			(xy 221.583971 -269.972655) (xy 221.554499 -269.926798) (xy 221.531853 -269.877214) (xy 221.516495 -269.824911)
			(xy 221.508737 -269.770955) (xy 213.035039 -269.770955) (xy 211.398605 -271.407389) (xy 221.507795 -271.407389)
			(xy 221.511527 -271.354135) (xy 221.522646 -271.301921) (xy 221.540936 -271.251767) (xy 221.566039 -271.204652)
			(xy 221.597465 -271.161497) (xy 221.6346 -271.123145) (xy 221.655386 -271.106392) (xy 221.664145 -271.098827)
			(xy 221.674331 -271.078071) (xy 221.674944 -271.066514) (xy 221.674944 -270.98625) (xy 221.674365 -270.974683)
			(xy 221.664178 -270.95391) (xy 221.655386 -270.946372) (xy 221.632886 -270.9282) (xy 221.593153 -270.886176)
			(xy 221.560216 -270.838637) (xy 221.534831 -270.786672) (xy 221.517578 -270.731471) (xy 221.508853 -270.674299)
			(xy 221.50832 -270.645382) (xy 221.508738 -270.618127) (xy 221.516498 -270.564173) (xy 221.531858 -270.511873)
			(xy 221.554505 -270.462291) (xy 221.583977 -270.416436) (xy 221.619676 -270.375243) (xy 221.660873 -270.33955)
			(xy 221.706731 -270.310083) (xy 221.756316 -270.287442) (xy 221.808618 -270.272089) (xy 221.862573 -270.264335)
			(xy 221.889828 -270.263874) (xy 221.918744 -270.264416) (xy 221.975916 -270.273136) (xy 222.031115 -270.290388)
			(xy 222.083078 -270.315775) (xy 222.130612 -270.348716) (xy 222.172628 -270.388455) (xy 222.190818 -270.41094)
			(xy 222.19837 -270.419712) (xy 222.219136 -270.429888) (xy 222.230696 -270.430498) (xy 222.31096 -270.430498)
			(xy 222.322525 -270.429905) (xy 222.343296 -270.419727) (xy 222.350838 -270.41094) (xy 222.369018 -270.388447)
			(xy 222.411039 -270.34871) (xy 222.458575 -270.315771) (xy 222.510539 -270.290384) (xy 222.565739 -270.273131)
			(xy 222.622911 -270.264406) (xy 222.651828 -270.263874) (xy 222.679079 -270.264352) (xy 222.733026 -270.272112)
			(xy 222.78532 -270.287469) (xy 222.834896 -270.310112) (xy 222.880746 -270.33958) (xy 222.921935 -270.375272)
			(xy 222.957626 -270.416463) (xy 222.987092 -270.462313) (xy 223.009734 -270.511889) (xy 223.025091 -270.564184)
			(xy 223.032849 -270.618131) (xy 223.033336 -270.645382) (xy 223.032829 -270.6743) (xy 223.024101 -270.731472)
			(xy 223.006843 -270.786673) (xy 222.981449 -270.838635) (xy 222.948502 -270.886168) (xy 222.908757 -270.928183)
			(xy 222.88627 -270.946372) (xy 222.87752 -270.953945) (xy 222.867331 -270.974696) (xy 222.866712 -270.98625)
			(xy 222.866712 -271.066514) (xy 222.86727 -271.078084) (xy 222.877473 -271.098855) (xy 222.88627 -271.106392)
			(xy 222.907034 -271.123167) (xy 222.944161 -271.161519) (xy 222.975581 -271.204672) (xy 223.000678 -271.251783)
			(xy 223.018964 -271.301932) (xy 223.03008 -271.354141) (xy 223.033811 -271.407389) (xy 223.030083 -271.460638)
			(xy 223.01897 -271.512847) (xy 223.000687 -271.562997) (xy 222.975592 -271.610109) (xy 222.944176 -271.653264)
			(xy 222.90705 -271.691618) (xy 222.88627 -271.708372) (xy 222.87752 -271.715945) (xy 222.867331 -271.736696)
			(xy 222.866712 -271.74825) (xy 222.866712 -271.828514) (xy 222.86727 -271.840084) (xy 222.877473 -271.860855)
			(xy 222.88627 -271.868392) (xy 222.908743 -271.886595) (xy 222.948481 -271.928611) (xy 222.981422 -271.976144)
			(xy 223.006812 -272.028103) (xy 223.02407 -272.083298) (xy 223.0328 -272.140467) (xy 223.033336 -272.169382)
			(xy 223.032805 -272.196631) (xy 223.025052 -272.250576) (xy 223.0097 -272.302868) (xy 222.987063 -272.352443)
			(xy 222.957602 -272.398293) (xy 222.921915 -272.439482) (xy 222.880729 -272.475174) (xy 222.84236 -272.499836)
			(xy 231.378258 -272.499836) (xy 231.382272 -272.294152) (xy 231.394308 -272.088782) (xy 231.414347 -271.884038)
			(xy 231.44236 -271.680231) (xy 231.478303 -271.477672) (xy 231.522122 -271.27667) (xy 231.573749 -271.077531)
			(xy 231.633107 -270.880558) (xy 231.700105 -270.68605) (xy 231.774641 -270.494305) (xy 231.856601 -270.305614)
			(xy 231.945861 -270.120264) (xy 232.042284 -269.938538) (xy 232.145725 -269.760712) (xy 232.256024 -269.587058)
			(xy 232.373015 -269.417839) (xy 232.496519 -269.253313) (xy 232.626348 -269.093732) (xy 232.762305 -268.939337)
			(xy 232.904182 -268.790365) (xy 233.051763 -268.647041) (xy 233.204824 -268.509585) (xy 233.363131 -268.378205)
			(xy 233.526444 -268.253102) (xy 233.694513 -268.134465) (xy 233.867083 -268.022477) (xy 234.043891 -267.917306)
			(xy 234.224668 -267.819115) (xy 234.409138 -267.728051) (xy 234.59702 -267.644254) (xy 234.78803 -267.567851)
			(xy 234.981874 -267.498958) (xy 235.178259 -267.437681) (xy 235.376885 -267.384113) (xy 235.57745 -267.338336)
			(xy 235.779648 -267.300418) (xy 235.983172 -267.270419) (xy 236.187711 -267.248382) (xy 236.392954 -267.234343)
			(xy 236.598589 -267.228323) (xy 236.804302 -267.23033) (xy 237.00978 -267.240362) (xy 237.21471 -267.258403)
			(xy 237.41878 -267.284426) (xy 237.62168 -267.318391) (xy 237.8231 -267.360246) (xy 238.022733 -267.409928)
			(xy 238.220276 -267.467362) (xy 238.415428 -267.532459) (xy 238.607892 -267.60512) (xy 238.797374 -267.685236)
			(xy 238.983585 -267.772683) (xy 239.166244 -267.867329) (xy 239.34507 -267.969029) (xy 239.519792 -268.077629)
			(xy 239.690145 -268.192964) (xy 239.855867 -268.314857) (xy 240.016708 -268.443123) (xy 240.172421 -268.577566)
			(xy 240.322771 -268.717983) (xy 240.467528 -268.864159) (xy 240.606471 -269.015871) (xy 240.739389 -269.172889)
			(xy 240.86608 -269.334974) (xy 240.98635 -269.501877) (xy 241.072241 -269.631446) (xy 249.332814 -269.631446)
			(xy 249.332814 -269.576954) (xy 249.340569 -269.523015) (xy 249.35592 -269.47073) (xy 249.378555 -269.421161)
			(xy 249.408014 -269.375317) (xy 249.443696 -269.334132) (xy 249.484877 -269.298444) (xy 249.530717 -269.268979)
			(xy 249.580283 -269.246337) (xy 249.632567 -269.230979) (xy 249.686504 -269.223218) (xy 249.71375 -269.222728)
			(xy 249.742666 -269.223272) (xy 249.799837 -269.231994) (xy 249.855035 -269.249246) (xy 249.906997 -269.274633)
			(xy 249.954532 -269.307573) (xy 249.99655 -269.34731) (xy 250.01474 -269.369794) (xy 250.02229 -269.378569)
			(xy 250.043058 -269.388745) (xy 250.054618 -269.389352) (xy 250.134882 -269.389352) (xy 250.146451 -269.388788)
			(xy 250.167223 -269.37859) (xy 250.17476 -269.369794) (xy 250.191513 -269.349011) (xy 250.229867 -269.311881)
			(xy 250.273021 -269.280459) (xy 250.320135 -269.25536) (xy 250.370287 -269.237074) (xy 250.422498 -269.225957)
			(xy 250.47575 -269.222227) (xy 250.529002 -269.225957) (xy 250.581213 -269.237074) (xy 250.631365 -269.25536)
			(xy 250.678479 -269.280459) (xy 250.721633 -269.311881) (xy 250.759987 -269.349011) (xy 250.77674 -269.369794)
			(xy 250.78429 -269.378569) (xy 250.805058 -269.388745) (xy 250.816618 -269.389352) (xy 250.896882 -269.389352)
			(xy 250.908451 -269.388788) (xy 250.929223 -269.37859) (xy 250.93676 -269.369794) (xy 250.953513 -269.349011)
			(xy 250.991867 -269.311881) (xy 251.035021 -269.280459) (xy 251.082135 -269.25536) (xy 251.132287 -269.237074)
			(xy 251.184498 -269.225957) (xy 251.23775 -269.222227) (xy 251.291002 -269.225957) (xy 251.343213 -269.237074)
			(xy 251.393365 -269.25536) (xy 251.440479 -269.280459) (xy 251.483633 -269.311881) (xy 251.521987 -269.349011)
			(xy 251.53874 -269.369794) (xy 251.54629 -269.378569) (xy 251.567058 -269.388745) (xy 251.578618 -269.389352)
			(xy 251.658882 -269.389352) (xy 251.670451 -269.388788) (xy 251.691223 -269.37859) (xy 251.69876 -269.369794)
			(xy 251.716972 -269.347328) (xy 251.758988 -269.307592) (xy 251.806518 -269.274651) (xy 251.858475 -269.24926)
			(xy 251.913669 -269.232) (xy 251.970835 -269.223266) (xy 251.99975 -269.222728) (xy 252.027008 -269.223116)
			(xy 252.080969 -269.230867) (xy 252.133278 -269.246221) (xy 252.182869 -269.268862) (xy 252.228733 -269.298332)
			(xy 252.269936 -269.334029) (xy 252.305638 -269.375227) (xy 252.335114 -269.421087) (xy 252.357762 -269.470675)
			(xy 252.373122 -269.522982) (xy 252.380881 -269.576942) (xy 252.380881 -269.631458) (xy 252.373122 -269.685418)
			(xy 252.357762 -269.737725) (xy 252.335114 -269.787313) (xy 252.305638 -269.833173) (xy 252.269936 -269.874371)
			(xy 252.228733 -269.910068) (xy 252.182869 -269.939538) (xy 252.133278 -269.962179) (xy 252.080969 -269.977533)
			(xy 252.027008 -269.985284) (xy 251.99975 -269.985744) (xy 251.970833 -269.985211) (xy 251.913662 -269.976488)
			(xy 251.858462 -269.959235) (xy 251.8065 -269.933846) (xy 251.758966 -269.900904) (xy 251.71695 -269.861163)
			(xy 251.69876 -269.838678) (xy 251.691215 -269.829899) (xy 251.670443 -269.819726) (xy 251.658882 -269.81912)
			(xy 251.578618 -269.81912) (xy 251.56705 -269.819694) (xy 251.546279 -269.829885) (xy 251.53874 -269.838678)
			(xy 251.521987 -269.859461) (xy 251.483633 -269.896591) (xy 251.440479 -269.928013) (xy 251.393365 -269.953112)
			(xy 251.343213 -269.971398) (xy 251.291002 -269.982515) (xy 251.23775 -269.986245) (xy 251.184498 -269.982515)
			(xy 251.132287 -269.971398) (xy 251.082135 -269.953112) (xy 251.035021 -269.928013) (xy 250.991867 -269.896591)
			(xy 250.953513 -269.859461) (xy 250.93676 -269.838678) (xy 250.929215 -269.829899) (xy 250.908443 -269.819726)
			(xy 250.896882 -269.81912) (xy 250.816618 -269.81912) (xy 250.80505 -269.819694) (xy 250.784279 -269.829885)
			(xy 250.77674 -269.838678) (xy 250.759987 -269.859461) (xy 250.721633 -269.896591) (xy 250.678479 -269.928013)
			(xy 250.631365 -269.953112) (xy 250.581213 -269.971398) (xy 250.529002 -269.982515) (xy 250.47575 -269.986245)
			(xy 250.422498 -269.982515) (xy 250.370287 -269.971398) (xy 250.320135 -269.953112) (xy 250.273021 -269.928013)
			(xy 250.229867 -269.896591) (xy 250.191513 -269.859461) (xy 250.17476 -269.838678) (xy 250.167215 -269.829899)
			(xy 250.146443 -269.819726) (xy 250.134882 -269.81912) (xy 250.054618 -269.81912) (xy 250.04305 -269.819694)
			(xy 250.022279 -269.829885) (xy 250.01474 -269.838678) (xy 249.996521 -269.861138) (xy 249.954508 -269.900875)
			(xy 249.906979 -269.933818) (xy 249.855023 -269.959211) (xy 249.79983 -269.976472) (xy 249.742664 -269.985206)
			(xy 249.71375 -269.985744) (xy 249.686504 -269.985182) (xy 249.632567 -269.977421) (xy 249.580283 -269.962063)
			(xy 249.530717 -269.939421) (xy 249.484877 -269.909956) (xy 249.443697 -269.874268) (xy 249.408014 -269.833083)
			(xy 249.378555 -269.787239) (xy 249.35592 -269.73767) (xy 249.340569 -269.685385) (xy 249.332814 -269.631446)
			(xy 241.072241 -269.631446) (xy 241.100017 -269.673347) (xy 241.206907 -269.84912) (xy 241.306858 -270.02893)
			(xy 241.399717 -270.212503) (xy 241.485344 -270.399559) (xy 241.563606 -270.589814) (xy 241.634387 -270.782977)
			(xy 241.697577 -270.978755) (xy 241.75308 -271.176849) (xy 241.774804 -271.267922) (xy 250.855751 -271.267922)
			(xy 250.859478 -271.214673) (xy 250.870593 -271.162463) (xy 250.888877 -271.112313) (xy 250.913975 -271.065201)
			(xy 250.945396 -271.022049) (xy 250.982526 -270.983698) (xy 251.003308 -270.966946) (xy 251.012046 -270.959361)
			(xy 251.022242 -270.93862) (xy 251.022866 -270.927068) (xy 251.022866 -270.846804) (xy 251.022305 -270.835235)
			(xy 251.012105 -270.814463) (xy 251.003308 -270.806926) (xy 250.980839 -270.788718) (xy 250.941102 -270.746702)
			(xy 250.908161 -270.699171) (xy 250.88277 -270.647213) (xy 250.865511 -270.592018) (xy 250.856779 -270.534851)
			(xy 250.856242 -270.505936) (xy 250.856689 -270.478682) (xy 250.864442 -270.424728) (xy 250.879796 -270.372426)
			(xy 250.902438 -270.322843) (xy 250.931907 -270.276987) (xy 250.967603 -270.235793) (xy 251.008799 -270.200099)
			(xy 251.054655 -270.170632) (xy 251.10424 -270.147991) (xy 251.156541 -270.132639) (xy 251.210496 -270.124888)
			(xy 251.23775 -270.124428) (xy 251.266666 -270.124972) (xy 251.323837 -270.133694) (xy 251.379035 -270.150946)
			(xy 251.430997 -270.176333) (xy 251.478532 -270.209273) (xy 251.52055 -270.24901) (xy 251.53874 -270.271494)
			(xy 251.54629 -270.280269) (xy 251.567058 -270.290445) (xy 251.578618 -270.291052) (xy 251.658882 -270.291052)
			(xy 251.670451 -270.290488) (xy 251.691223 -270.28029) (xy 251.69876 -270.271494) (xy 251.716972 -270.249028)
			(xy 251.758988 -270.209292) (xy 251.806518 -270.176351) (xy 251.858475 -270.15096) (xy 251.913669 -270.1337)
			(xy 251.970835 -270.124966) (xy 251.99975 -270.124428) (xy 252.027003 -270.124902) (xy 252.080956 -270.132653)
			(xy 252.133256 -270.148005) (xy 252.182838 -270.170644) (xy 252.228693 -270.20011) (xy 252.269887 -270.235803)
			(xy 252.305582 -270.276996) (xy 252.335049 -270.32285) (xy 252.357691 -270.372431) (xy 252.373044 -270.424731)
			(xy 252.380797 -270.478683) (xy 252.381258 -270.505936) (xy 252.38071 -270.534852) (xy 252.371989 -270.592023)
			(xy 252.354738 -270.647221) (xy 252.329352 -270.699184) (xy 252.296413 -270.746718) (xy 252.256676 -270.788736)
			(xy 252.234192 -270.806926) (xy 252.225422 -270.81448) (xy 252.215243 -270.835245) (xy 252.214634 -270.846804)
			(xy 252.214634 -270.927068) (xy 252.215211 -270.938635) (xy 252.2254 -270.959407) (xy 252.234192 -270.966946)
			(xy 252.255013 -270.983656) (xy 252.292148 -271.022012) (xy 252.323574 -271.065171) (xy 252.348675 -271.112289)
			(xy 252.366962 -271.162447) (xy 252.378078 -271.214665) (xy 252.381806 -271.267922) (xy 252.378072 -271.321179)
			(xy 252.36695 -271.373395) (xy 252.348657 -271.423551) (xy 252.32355 -271.470667) (xy 252.29212 -271.513822)
			(xy 252.25498 -271.552174) (xy 252.234192 -271.568926) (xy 252.225422 -271.57648) (xy 252.215243 -271.597245)
			(xy 252.214634 -271.608804) (xy 252.214634 -271.689068) (xy 252.215211 -271.700635) (xy 252.2254 -271.721407)
			(xy 252.234192 -271.728946) (xy 252.256648 -271.74717) (xy 252.296385 -271.789182) (xy 252.329328 -271.83671)
			(xy 252.354721 -271.888665) (xy 252.371983 -271.943857) (xy 252.380719 -272.001022) (xy 252.381258 -272.029936)
			(xy 252.380878 -272.057192) (xy 252.373115 -272.111149) (xy 252.357752 -272.163451) (xy 252.335102 -272.213035)
			(xy 252.305625 -272.25889) (xy 252.269923 -272.300084) (xy 252.228721 -272.335777) (xy 252.182859 -272.365243)
			(xy 252.13327 -272.387882) (xy 252.080964 -272.403234) (xy 252.027006 -272.410985) (xy 251.99975 -272.411444)
			(xy 251.970833 -272.410911) (xy 251.913662 -272.402188) (xy 251.858462 -272.384935) (xy 251.8065 -272.359546)
			(xy 251.758966 -272.326604) (xy 251.71695 -272.286863) (xy 251.69876 -272.264378) (xy 251.691215 -272.255599)
			(xy 251.670443 -272.245426) (xy 251.658882 -272.24482) (xy 251.578618 -272.24482) (xy 251.56705 -272.245394)
			(xy 251.546279 -272.255585) (xy 251.53874 -272.264378) (xy 251.520521 -272.286838) (xy 251.478508 -272.326575)
			(xy 251.430979 -272.359518) (xy 251.379023 -272.384911) (xy 251.32383 -272.402172) (xy 251.266664 -272.410906)
			(xy 251.23775 -272.411444) (xy 251.2105 -272.410898) (xy 251.156554 -272.403149) (xy 251.10426 -272.387801)
			(xy 251.054682 -272.365167) (xy 251.008831 -272.335708) (xy 250.967638 -272.300023) (xy 250.931944 -272.258838)
			(xy 250.902474 -272.212993) (xy 250.879829 -272.163421) (xy 250.864469 -272.11113) (xy 250.856708 -272.057186)
			(xy 250.856242 -272.029936) (xy 250.85677 -272.001019) (xy 250.865495 -271.943848) (xy 250.88275 -271.888648)
			(xy 250.90814 -271.836686) (xy 250.941082 -271.789152) (xy 250.980823 -271.747136) (xy 251.003308 -271.728946)
			(xy 251.012046 -271.721361) (xy 251.022242 -271.70062) (xy 251.022866 -271.689068) (xy 251.022866 -271.608804)
			(xy 251.022305 -271.597235) (xy 251.012105 -271.576463) (xy 251.003308 -271.568926) (xy 250.982558 -271.552131)
			(xy 250.945424 -271.513785) (xy 250.913999 -271.470636) (xy 250.888895 -271.423528) (xy 250.870605 -271.37338)
			(xy 250.859485 -271.321171) (xy 250.855751 -271.267922) (xy 241.774804 -271.267922) (xy 241.800812 -271.376958)
			(xy 241.840701 -271.578776) (xy 241.872685 -271.781998) (xy 241.896715 -271.986312) (xy 241.912756 -272.191408)
			(xy 241.920782 -272.396975) (xy 241.921284 -272.499836) (xy 241.920782 -272.602697) (xy 241.912756 -272.808264)
			(xy 241.900979 -272.958846) (xy 249.332814 -272.958846) (xy 249.332814 -272.904354) (xy 249.340569 -272.850415)
			(xy 249.35592 -272.79813) (xy 249.378555 -272.748561) (xy 249.408014 -272.702717) (xy 249.443696 -272.661532)
			(xy 249.484877 -272.625844) (xy 249.530717 -272.596379) (xy 249.580283 -272.573737) (xy 249.632567 -272.558379)
			(xy 249.686504 -272.550618) (xy 249.71375 -272.550128) (xy 249.742666 -272.550672) (xy 249.799837 -272.559394)
			(xy 249.855035 -272.576646) (xy 249.906997 -272.602033) (xy 249.954532 -272.634973) (xy 249.99655 -272.67471)
			(xy 250.01474 -272.697194) (xy 250.02229 -272.705969) (xy 250.043058 -272.716145) (xy 250.054618 -272.716752)
			(xy 250.134882 -272.716752) (xy 250.146451 -272.716188) (xy 250.167223 -272.70599) (xy 250.17476 -272.697194)
			(xy 250.191513 -272.676411) (xy 250.229867 -272.639281) (xy 250.273021 -272.607859) (xy 250.320135 -272.58276)
			(xy 250.370287 -272.564474) (xy 250.422498 -272.553357) (xy 250.47575 -272.549627) (xy 250.529002 -272.553357)
			(xy 250.581213 -272.564474) (xy 250.631365 -272.58276) (xy 250.678479 -272.607859) (xy 250.721633 -272.639281)
			(xy 250.759987 -272.676411) (xy 250.77674 -272.697194) (xy 250.78429 -272.705969) (xy 250.805058 -272.716145)
			(xy 250.816618 -272.716752) (xy 250.896882 -272.716752) (xy 250.908451 -272.716188) (xy 250.929223 -272.70599)
			(xy 250.93676 -272.697194) (xy 250.953513 -272.676411) (xy 250.991867 -272.639281) (xy 251.035021 -272.607859)
			(xy 251.082135 -272.58276) (xy 251.132287 -272.564474) (xy 251.184498 -272.553357) (xy 251.23775 -272.549627)
			(xy 251.291002 -272.553357) (xy 251.343213 -272.564474) (xy 251.393365 -272.58276) (xy 251.440479 -272.607859)
			(xy 251.483633 -272.639281) (xy 251.521987 -272.676411) (xy 251.53874 -272.697194) (xy 251.54629 -272.705969)
			(xy 251.567058 -272.716145) (xy 251.578618 -272.716752) (xy 251.658882 -272.716752) (xy 251.670451 -272.716188)
			(xy 251.691223 -272.70599) (xy 251.69876 -272.697194) (xy 251.716972 -272.674728) (xy 251.758988 -272.634992)
			(xy 251.806518 -272.602051) (xy 251.858475 -272.57666) (xy 251.913669 -272.5594) (xy 251.970835 -272.550666)
			(xy 251.99975 -272.550128) (xy 252.027008 -272.550516) (xy 252.080969 -272.558267) (xy 252.133278 -272.573621)
			(xy 252.182869 -272.596262) (xy 252.228733 -272.625732) (xy 252.269936 -272.661429) (xy 252.305638 -272.702627)
			(xy 252.335114 -272.748487) (xy 252.357762 -272.798075) (xy 252.373122 -272.850382) (xy 252.380881 -272.904342)
			(xy 252.380881 -272.958858) (xy 252.373122 -273.012818) (xy 252.357762 -273.065125) (xy 252.335114 -273.114713)
			(xy 252.305638 -273.160573) (xy 252.269936 -273.201771) (xy 252.228733 -273.237468) (xy 252.182869 -273.266938)
			(xy 252.133278 -273.289579) (xy 252.080969 -273.304933) (xy 252.027008 -273.312684) (xy 251.99975 -273.313144)
			(xy 251.970833 -273.312611) (xy 251.913662 -273.303888) (xy 251.858462 -273.286635) (xy 251.8065 -273.261246)
			(xy 251.758966 -273.228304) (xy 251.71695 -273.188563) (xy 251.69876 -273.166078) (xy 251.691215 -273.157299)
			(xy 251.670443 -273.147126) (xy 251.658882 -273.14652) (xy 251.578618 -273.14652) (xy 251.56705 -273.147094)
			(xy 251.546279 -273.157285) (xy 251.53874 -273.166078) (xy 251.521987 -273.186861) (xy 251.483633 -273.223991)
			(xy 251.440479 -273.255413) (xy 251.393365 -273.280512) (xy 251.343213 -273.298798) (xy 251.291002 -273.309915)
			(xy 251.23775 -273.313645) (xy 251.184498 -273.309915) (xy 251.132287 -273.298798) (xy 251.082135 -273.280512)
			(xy 251.035021 -273.255413) (xy 250.991867 -273.223991) (xy 250.953513 -273.186861) (xy 250.93676 -273.166078)
			(xy 250.929215 -273.157299) (xy 250.908443 -273.147126) (xy 250.896882 -273.14652) (xy 250.816618 -273.14652)
			(xy 250.80505 -273.147094) (xy 250.784279 -273.157285) (xy 250.77674 -273.166078) (xy 250.759987 -273.186861)
			(xy 250.721633 -273.223991) (xy 250.678479 -273.255413) (xy 250.631365 -273.280512) (xy 250.581213 -273.298798)
			(xy 250.529002 -273.309915) (xy 250.47575 -273.313645) (xy 250.422498 -273.309915) (xy 250.370287 -273.298798)
			(xy 250.320135 -273.280512) (xy 250.273021 -273.255413) (xy 250.229867 -273.223991) (xy 250.191513 -273.186861)
			(xy 250.17476 -273.166078) (xy 250.167215 -273.157299) (xy 250.146443 -273.147126) (xy 250.134882 -273.14652)
			(xy 250.054618 -273.14652) (xy 250.04305 -273.147094) (xy 250.022279 -273.157285) (xy 250.01474 -273.166078)
			(xy 249.996521 -273.188538) (xy 249.954508 -273.228275) (xy 249.906979 -273.261218) (xy 249.855023 -273.286611)
			(xy 249.79983 -273.303872) (xy 249.742664 -273.312606) (xy 249.71375 -273.313144) (xy 249.686504 -273.312582)
			(xy 249.632567 -273.304821) (xy 249.580283 -273.289463) (xy 249.530717 -273.266821) (xy 249.484877 -273.237356)
			(xy 249.443697 -273.201668) (xy 249.408014 -273.160483) (xy 249.378555 -273.114639) (xy 249.35592 -273.06507)
			(xy 249.340569 -273.012785) (xy 249.332814 -272.958846) (xy 241.900979 -272.958846) (xy 241.896715 -273.01336)
			(xy 241.872685 -273.217674) (xy 241.840701 -273.420896) (xy 241.800812 -273.622714) (xy 241.75308 -273.822823)
			(xy 241.697577 -274.020917) (xy 241.634387 -274.216695) (xy 241.563606 -274.409858) (xy 241.485344 -274.600113)
			(xy 241.399717 -274.787169) (xy 241.306858 -274.970742) (xy 241.206907 -275.150552) (xy 241.100017 -275.326325)
			(xy 240.98635 -275.497795) (xy 240.86608 -275.664698) (xy 240.739389 -275.826783) (xy 240.606471 -275.983801)
			(xy 240.467528 -276.135513) (xy 240.322771 -276.281689) (xy 240.172421 -276.422106) (xy 240.016708 -276.556549)
			(xy 239.855867 -276.684815) (xy 239.690145 -276.806708) (xy 239.519792 -276.922043) (xy 239.34507 -277.030643)
			(xy 239.166244 -277.132343) (xy 238.983585 -277.226989) (xy 238.797374 -277.314436) (xy 238.607892 -277.394552)
			(xy 238.415428 -277.467213) (xy 238.220276 -277.53231) (xy 238.022733 -277.589744) (xy 237.8231 -277.639426)
			(xy 237.62168 -277.681281) (xy 237.41878 -277.715246) (xy 237.21471 -277.741269) (xy 237.00978 -277.75931)
			(xy 236.804302 -277.769342) (xy 236.598589 -277.771349) (xy 236.392954 -277.765329) (xy 236.187711 -277.75129)
			(xy 235.983172 -277.729253) (xy 235.779648 -277.699254) (xy 235.57745 -277.661336) (xy 235.376885 -277.615559)
			(xy 235.178259 -277.561991) (xy 234.981874 -277.500714) (xy 234.78803 -277.431821) (xy 234.59702 -277.355418)
			(xy 234.409138 -277.271621) (xy 234.224668 -277.180557) (xy 234.043891 -277.082366) (xy 233.867083 -276.977195)
			(xy 233.694513 -276.865207) (xy 233.526444 -276.74657) (xy 233.363131 -276.621467) (xy 233.204824 -276.490087)
			(xy 233.051763 -276.352631) (xy 232.904182 -276.209307) (xy 232.762305 -276.060335) (xy 232.626348 -275.90594)
			(xy 232.496519 -275.746359) (xy 232.373015 -275.581833) (xy 232.256024 -275.412614) (xy 232.145725 -275.23896)
			(xy 232.042284 -275.061134) (xy 231.945861 -274.879408) (xy 231.856601 -274.694058) (xy 231.774641 -274.505367)
			(xy 231.700105 -274.313622) (xy 231.633107 -274.119114) (xy 231.573749 -273.922141) (xy 231.522122 -273.723002)
			(xy 231.478303 -273.522) (xy 231.44236 -273.319441) (xy 231.414347 -273.115634) (xy 231.394308 -272.91089)
			(xy 231.382272 -272.70552) (xy 231.378258 -272.499836) (xy 222.84236 -272.499836) (xy 222.834884 -272.504641)
			(xy 222.785311 -272.527284) (xy 222.733021 -272.542642) (xy 222.679077 -272.550402) (xy 222.651828 -272.55089)
			(xy 222.622912 -272.550355) (xy 222.565741 -272.54163) (xy 222.510542 -272.524376) (xy 222.458581 -272.498987)
			(xy 222.411046 -272.466046) (xy 222.369029 -272.426308) (xy 222.350838 -272.403824) (xy 222.343268 -272.395071)
			(xy 222.322515 -272.384886) (xy 222.31096 -272.384266) (xy 222.230696 -272.384266) (xy 222.219124 -272.384811)
			(xy 222.198352 -272.395021) (xy 222.190818 -272.403824) (xy 222.172623 -272.426304) (xy 222.130603 -272.466038)
			(xy 222.083069 -272.498977) (xy 222.031109 -272.524366) (xy 221.975912 -272.541623) (xy 221.918744 -272.550354)
			(xy 221.889828 -272.55089) (xy 221.862575 -272.550419) (xy 221.808623 -272.542665) (xy 221.756325 -272.527312)
			(xy 221.706743 -272.504671) (xy 221.660889 -272.475204) (xy 221.619696 -272.439511) (xy 221.584002 -272.398319)
			(xy 221.554534 -272.352465) (xy 221.531892 -272.302885) (xy 221.516537 -272.250586) (xy 221.508782 -272.196635)
			(xy 221.50832 -272.169382) (xy 221.508889 -272.140467) (xy 221.517607 -272.083298) (xy 221.534854 -272.0281)
			(xy 221.560236 -271.976137) (xy 221.593171 -271.928602) (xy 221.632904 -271.886583) (xy 221.655386 -271.868392)
			(xy 221.664145 -271.860827) (xy 221.674331 -271.840071) (xy 221.674944 -271.828514) (xy 221.674944 -271.74825)
			(xy 221.674365 -271.736683) (xy 221.664178 -271.71591) (xy 221.655386 -271.708372) (xy 221.634584 -271.691641)
			(xy 221.597451 -271.653286) (xy 221.566027 -271.610129) (xy 221.540927 -271.563013) (xy 221.52264 -271.512858)
			(xy 221.511524 -271.460643) (xy 221.507795 -271.407389) (xy 211.398605 -271.407389) (xy 211.069428 -271.736566)
			(xy 211.062589 -271.743967) (xy 211.054874 -271.762565) (xy 211.054442 -271.772634) (xy 211.054442 -273.098355)
			(xy 221.508737 -273.098355) (xy 221.508737 -273.043845) (xy 221.516495 -272.989889) (xy 221.531853 -272.937586)
			(xy 221.554499 -272.888002) (xy 221.583971 -272.842145) (xy 221.619669 -272.800949) (xy 221.660867 -272.765254)
			(xy 221.706726 -272.735785) (xy 221.756312 -272.713143) (xy 221.808616 -272.697789) (xy 221.862573 -272.690035)
			(xy 221.889828 -272.689574) (xy 221.918744 -272.690116) (xy 221.975916 -272.698836) (xy 222.031115 -272.716088)
			(xy 222.083078 -272.741475) (xy 222.130612 -272.774416) (xy 222.172628 -272.814155) (xy 222.190818 -272.83664)
			(xy 222.19837 -272.845412) (xy 222.219136 -272.855588) (xy 222.230696 -272.856198) (xy 222.31096 -272.856198)
			(xy 222.322525 -272.855605) (xy 222.343296 -272.845427) (xy 222.350838 -272.83664) (xy 222.367591 -272.815857)
			(xy 222.405945 -272.778727) (xy 222.449099 -272.747305) (xy 222.496213 -272.722206) (xy 222.546365 -272.70392)
			(xy 222.598576 -272.692803) (xy 222.651828 -272.689073) (xy 222.70508 -272.692803) (xy 222.757291 -272.70392)
			(xy 222.807443 -272.722206) (xy 222.854557 -272.747305) (xy 222.897711 -272.778727) (xy 222.936065 -272.815857)
			(xy 222.952818 -272.83664) (xy 222.96037 -272.845412) (xy 222.981136 -272.855588) (xy 222.992696 -272.856198)
			(xy 223.07296 -272.856198) (xy 223.084525 -272.855605) (xy 223.105296 -272.845427) (xy 223.112838 -272.83664)
			(xy 223.129591 -272.815857) (xy 223.167945 -272.778727) (xy 223.211099 -272.747305) (xy 223.258213 -272.722206)
			(xy 223.308365 -272.70392) (xy 223.360576 -272.692803) (xy 223.413828 -272.689073) (xy 223.46708 -272.692803)
			(xy 223.519291 -272.70392) (xy 223.569443 -272.722206) (xy 223.616557 -272.747305) (xy 223.659711 -272.778727)
			(xy 223.698065 -272.815857) (xy 223.714818 -272.83664) (xy 223.72237 -272.845412) (xy 223.743136 -272.855588)
			(xy 223.754696 -272.856198) (xy 223.83496 -272.856198) (xy 223.846525 -272.855605) (xy 223.867296 -272.845427)
			(xy 223.874838 -272.83664) (xy 223.893018 -272.814147) (xy 223.935039 -272.77441) (xy 223.982575 -272.741471)
			(xy 224.034539 -272.716084) (xy 224.089739 -272.698831) (xy 224.146911 -272.690106) (xy 224.175828 -272.689574)
			(xy 224.203077 -272.690098) (xy 224.257019 -272.697858) (xy 224.309308 -272.713214) (xy 224.358879 -272.735856)
			(xy 224.404724 -272.765322) (xy 224.445908 -272.801011) (xy 224.481595 -272.842199) (xy 224.511057 -272.888046)
			(xy 224.533695 -272.937619) (xy 224.549048 -272.989909) (xy 224.556804 -273.043851) (xy 224.556804 -273.098349)
			(xy 224.549048 -273.152291) (xy 224.533695 -273.204581) (xy 224.511057 -273.254154) (xy 224.481595 -273.300001)
			(xy 224.445908 -273.341189) (xy 224.404724 -273.376878) (xy 224.358879 -273.406344) (xy 224.309308 -273.428986)
			(xy 224.257019 -273.444342) (xy 224.203077 -273.452102) (xy 224.175828 -273.45259) (xy 224.146912 -273.452055)
			(xy 224.089741 -273.44333) (xy 224.034542 -273.426076) (xy 223.982581 -273.400687) (xy 223.935046 -273.367746)
			(xy 223.893029 -273.328008) (xy 223.874838 -273.305524) (xy 223.867268 -273.296771) (xy 223.846515 -273.286586)
			(xy 223.83496 -273.285966) (xy 223.754696 -273.285966) (xy 223.743124 -273.286511) (xy 223.722352 -273.296721)
			(xy 223.714818 -273.305524) (xy 223.698065 -273.326307) (xy 223.659711 -273.363437) (xy 223.616557 -273.394859)
			(xy 223.569443 -273.419958) (xy 223.519291 -273.438244) (xy 223.46708 -273.449361) (xy 223.413828 -273.453091)
			(xy 223.360576 -273.449361) (xy 223.308365 -273.438244) (xy 223.258213 -273.419958) (xy 223.211099 -273.394859)
			(xy 223.167945 -273.363437) (xy 223.129591 -273.326307) (xy 223.112838 -273.305524) (xy 223.105268 -273.296771)
			(xy 223.084515 -273.286586) (xy 223.07296 -273.285966) (xy 222.992696 -273.285966) (xy 222.981124 -273.286511)
			(xy 222.960352 -273.296721) (xy 222.952818 -273.305524) (xy 222.936065 -273.326307) (xy 222.897711 -273.363437)
			(xy 222.854557 -273.394859) (xy 222.807443 -273.419958) (xy 222.757291 -273.438244) (xy 222.70508 -273.449361)
			(xy 222.651828 -273.453091) (xy 222.598576 -273.449361) (xy 222.546365 -273.438244) (xy 222.496213 -273.419958)
			(xy 222.449099 -273.394859) (xy 222.405945 -273.363437) (xy 222.367591 -273.326307) (xy 222.350838 -273.305524)
			(xy 222.343268 -273.296771) (xy 222.322515 -273.286586) (xy 222.31096 -273.285966) (xy 222.230696 -273.285966)
			(xy 222.219124 -273.286511) (xy 222.198352 -273.296721) (xy 222.190818 -273.305524) (xy 222.172623 -273.328004)
			(xy 222.130603 -273.367738) (xy 222.083069 -273.400677) (xy 222.031109 -273.426066) (xy 221.975912 -273.443323)
			(xy 221.918744 -273.452054) (xy 221.889828 -273.45259) (xy 221.862573 -273.452165) (xy 221.808616 -273.444411)
			(xy 221.756312 -273.429057) (xy 221.706726 -273.406415) (xy 221.660867 -273.376946) (xy 221.619669 -273.341251)
			(xy 221.583971 -273.300055) (xy 221.554499 -273.254198) (xy 221.531853 -273.204614) (xy 221.516495 -273.152311)
			(xy 221.508737 -273.098355) (xy 211.054442 -273.098355) (xy 211.054442 -288.15538) (xy 225.493324 -288.15538)
			(xy 225.497395 -288.099758) (xy 225.509521 -288.045321) (xy 225.529444 -287.99323) (xy 225.55674 -287.944595)
			(xy 225.590826 -287.900452) (xy 225.630975 -287.861743) (xy 225.676333 -287.829292) (xy 225.725933 -287.803791)
			(xy 225.778717 -287.785784) (xy 225.83356 -287.775654) (xy 225.889294 -287.773617) (xy 225.944731 -287.779717)
			(xy 225.998688 -287.793823) (xy 226.050017 -287.815635) (xy 226.097623 -287.844689) (xy 226.140491 -287.880364)
			(xy 226.177708 -287.921901) (xy 226.208481 -287.968414) (xy 226.232153 -288.018911) (xy 226.248221 -288.072318)
			(xy 226.255698 -288.123122) (xy 237.653574 -288.123122) (xy 237.657645 -288.0675) (xy 237.669771 -288.013063)
			(xy 237.689694 -287.960972) (xy 237.71699 -287.912337) (xy 237.751076 -287.868194) (xy 237.791225 -287.829485)
			(xy 237.836583 -287.797034) (xy 237.886183 -287.771533) (xy 237.938967 -287.753526) (xy 237.99381 -287.743396)
			(xy 238.049544 -287.741359) (xy 238.104981 -287.747459) (xy 238.158938 -287.761565) (xy 238.210267 -287.783377)
			(xy 238.257873 -287.812431) (xy 238.300741 -287.848106) (xy 238.337958 -287.889643) (xy 238.368731 -287.936156)
			(xy 238.392403 -287.986653) (xy 238.408471 -288.04006) (xy 238.416591 -288.095236) (xy 238.4171 -288.123122)
			(xy 238.416591 -288.151008) (xy 238.408471 -288.206184) (xy 238.392403 -288.259591) (xy 238.368731 -288.310088)
			(xy 238.337958 -288.356601) (xy 238.300741 -288.398138) (xy 238.257873 -288.433813) (xy 238.210267 -288.462867)
			(xy 238.158938 -288.484679) (xy 238.104981 -288.498785) (xy 238.049544 -288.504885) (xy 237.99381 -288.502848)
			(xy 237.938967 -288.492718) (xy 237.886183 -288.474711) (xy 237.836583 -288.44921) (xy 237.791225 -288.416759)
			(xy 237.751076 -288.37805) (xy 237.71699 -288.333907) (xy 237.689694 -288.285272) (xy 237.669771 -288.233181)
			(xy 237.657645 -288.178744) (xy 237.653574 -288.123122) (xy 226.255698 -288.123122) (xy 226.256341 -288.127494)
			(xy 226.25685 -288.15538) (xy 226.256341 -288.183266) (xy 226.248221 -288.238442) (xy 226.232153 -288.291849)
			(xy 226.208481 -288.342346) (xy 226.177708 -288.388859) (xy 226.140491 -288.430396) (xy 226.097623 -288.466071)
			(xy 226.050017 -288.495125) (xy 225.998688 -288.516937) (xy 225.944731 -288.531043) (xy 225.889294 -288.537143)
			(xy 225.83356 -288.535106) (xy 225.778717 -288.524976) (xy 225.725933 -288.506969) (xy 225.676333 -288.481468)
			(xy 225.630975 -288.449017) (xy 225.590826 -288.410308) (xy 225.55674 -288.366165) (xy 225.529444 -288.31753)
			(xy 225.509521 -288.265439) (xy 225.497395 -288.211002) (xy 225.493324 -288.15538) (xy 211.054442 -288.15538)
			(xy 211.054442 -288.939732) (xy 228.82352 -288.939732) (xy 228.824006 -288.912481) (xy 228.831762 -288.858533)
			(xy 228.847117 -288.806238) (xy 228.869759 -288.756661) (xy 228.899225 -288.710811) (xy 228.934916 -288.66962)
			(xy 228.976107 -288.633929) (xy 229.021957 -288.604463) (xy 229.071534 -288.581821) (xy 229.123829 -288.566466)
			(xy 229.177777 -288.55871) (xy 229.232279 -288.55871) (xy 229.286227 -288.566466) (xy 229.338522 -288.581821)
			(xy 229.388099 -288.604463) (xy 229.433949 -288.633929) (xy 229.47514 -288.66962) (xy 229.510831 -288.710811)
			(xy 229.540297 -288.756661) (xy 229.562939 -288.806238) (xy 229.578294 -288.858533) (xy 229.58605 -288.912481)
			(xy 229.586536 -288.939732) (xy 240.76787 -288.939732) (xy 240.768356 -288.912481) (xy 240.776112 -288.858533)
			(xy 240.791467 -288.806238) (xy 240.814109 -288.756661) (xy 240.843575 -288.710811) (xy 240.879266 -288.66962)
			(xy 240.920457 -288.633929) (xy 240.966307 -288.604463) (xy 241.015884 -288.581821) (xy 241.068179 -288.566466)
			(xy 241.122127 -288.55871) (xy 241.176629 -288.55871) (xy 241.230577 -288.566466) (xy 241.282872 -288.581821)
			(xy 241.332449 -288.604463) (xy 241.378299 -288.633929) (xy 241.41949 -288.66962) (xy 241.455181 -288.710811)
			(xy 241.484647 -288.756661) (xy 241.507289 -288.806238) (xy 241.522644 -288.858533) (xy 241.5304 -288.912481)
			(xy 241.530886 -288.939732) (xy 241.530366 -288.967593) (xy 241.522273 -289.022725) (xy 241.506249 -289.076094)
			(xy 241.482635 -289.126566) (xy 241.451932 -289.173067) (xy 241.414794 -289.214609) (xy 241.393726 -289.232848)
			(xy 241.384582 -289.240468) (xy 241.37493 -289.26155) (xy 241.378486 -289.365436) (xy 241.389408 -289.38601)
			(xy 241.39906 -289.393122) (xy 241.41961 -289.408545) (xy 241.456743 -289.444058) (xy 241.488774 -289.484233)
			(xy 241.515123 -289.528344) (xy 241.535312 -289.575593) (xy 241.548976 -289.625124) (xy 241.555869 -289.676041)
			(xy 241.556286 -289.701732) (xy 241.5558 -289.728983) (xy 241.548044 -289.782931) (xy 241.532689 -289.835226)
			(xy 241.510047 -289.884803) (xy 241.480581 -289.930653) (xy 241.44489 -289.971844) (xy 241.403699 -290.007535)
			(xy 241.357849 -290.037001) (xy 241.308272 -290.059643) (xy 241.255977 -290.074998) (xy 241.202029 -290.082754)
			(xy 241.147527 -290.082754) (xy 241.093579 -290.074998) (xy 241.041284 -290.059643) (xy 240.991707 -290.037001)
			(xy 240.945857 -290.007535) (xy 240.904666 -289.971844) (xy 240.868975 -289.930653) (xy 240.839509 -289.884803)
			(xy 240.816867 -289.835226) (xy 240.801512 -289.782931) (xy 240.793756 -289.728983) (xy 240.79327 -289.701732)
			(xy 240.793781 -289.67387) (xy 240.801878 -289.618739) (xy 240.817905 -289.565371) (xy 240.841521 -289.514899)
			(xy 240.872224 -289.468398) (xy 240.909363 -289.426856) (xy 240.93043 -289.408616) (xy 240.939574 -289.400996)
			(xy 240.949226 -289.379914) (xy 240.94567 -289.276028) (xy 240.934748 -289.255454) (xy 240.925096 -289.248342)
			(xy 240.904589 -289.232864) (xy 240.867451 -289.197363) (xy 240.835415 -289.157198) (xy 240.809061 -289.113096)
			(xy 240.788864 -289.065855) (xy 240.775192 -289.016331) (xy 240.768292 -288.96542) (xy 240.76787 -288.939732)
			(xy 229.586536 -288.939732) (xy 229.585998 -288.967593) (xy 229.577906 -289.022723) (xy 229.561885 -289.076091)
			(xy 229.538274 -289.126562) (xy 229.507575 -289.173063) (xy 229.470441 -289.214608) (xy 229.449376 -289.232848)
			(xy 229.440232 -289.240468) (xy 229.43058 -289.26155) (xy 229.434136 -289.365436) (xy 229.445058 -289.38601)
			(xy 229.45471 -289.393122) (xy 229.475249 -289.408559) (xy 229.512385 -289.444068) (xy 229.544418 -289.48424)
			(xy 229.570769 -289.528349) (xy 229.59096 -289.575596) (xy 229.604625 -289.625126) (xy 229.611519 -289.676042)
			(xy 229.611936 -289.701732) (xy 229.61145 -289.728983) (xy 229.603694 -289.782931) (xy 229.588339 -289.835226)
			(xy 229.565697 -289.884803) (xy 229.536231 -289.930653) (xy 229.50054 -289.971844) (xy 229.459349 -290.007535)
			(xy 229.413499 -290.037001) (xy 229.363922 -290.059643) (xy 229.311627 -290.074998) (xy 229.257679 -290.082754)
			(xy 229.203177 -290.082754) (xy 229.149229 -290.074998) (xy 229.096934 -290.059643) (xy 229.047357 -290.037001)
			(xy 229.001507 -290.007535) (xy 228.960316 -289.971844) (xy 228.924625 -289.930653) (xy 228.895159 -289.884803)
			(xy 228.872517 -289.835226) (xy 228.857162 -289.782931) (xy 228.849406 -289.728983) (xy 228.84892 -289.701732)
			(xy 228.849448 -289.673871) (xy 228.857544 -289.618741) (xy 228.873569 -289.565374) (xy 228.897182 -289.514903)
			(xy 228.927881 -289.468402) (xy 228.965015 -289.426857) (xy 228.98608 -289.408616) (xy 228.995224 -289.400996)
			(xy 229.004876 -289.379914) (xy 229.00132 -289.276028) (xy 228.990398 -289.255454) (xy 228.980746 -289.248342)
			(xy 228.960228 -289.232879) (xy 228.923093 -289.197373) (xy 228.891059 -289.157205) (xy 228.864707 -289.1131)
			(xy 228.844512 -289.065858) (xy 228.830842 -289.016333) (xy 228.823942 -288.965421) (xy 228.82352 -288.939732)
			(xy 211.054442 -288.939732) (xy 211.054442 -290.844732) (xy 236.659418 -290.844732) (xy 236.663489 -290.78911)
			(xy 236.675615 -290.734673) (xy 236.695538 -290.682582) (xy 236.722834 -290.633947) (xy 236.75692 -290.589804)
			(xy 236.797069 -290.551095) (xy 236.842427 -290.518644) (xy 236.892027 -290.493143) (xy 236.944811 -290.475136)
			(xy 236.999654 -290.465006) (xy 237.055388 -290.462969) (xy 237.110825 -290.469069) (xy 237.164782 -290.483175)
			(xy 237.216111 -290.504987) (xy 237.263717 -290.534041) (xy 237.306585 -290.569716) (xy 237.343802 -290.611253)
			(xy 237.374575 -290.657766) (xy 237.398247 -290.708263) (xy 237.414315 -290.76167) (xy 237.422435 -290.816846)
			(xy 237.422944 -290.844732) (xy 237.422435 -290.872618) (xy 237.414315 -290.927794) (xy 237.398247 -290.981201)
			(xy 237.374575 -291.031698) (xy 237.343802 -291.078211) (xy 237.306585 -291.119748) (xy 237.263717 -291.155423)
			(xy 237.216111 -291.184477) (xy 237.164782 -291.206289) (xy 237.110825 -291.220395) (xy 237.055388 -291.226495)
			(xy 236.999654 -291.224458) (xy 236.944811 -291.214328) (xy 236.892027 -291.196321) (xy 236.842427 -291.17082)
			(xy 236.797069 -291.138369) (xy 236.75692 -291.09966) (xy 236.722834 -291.055517) (xy 236.695538 -291.006882)
			(xy 236.675615 -290.954791) (xy 236.663489 -290.900354) (xy 236.659418 -290.844732) (xy 211.054442 -290.844732)
			(xy 211.054442 -291.614098) (xy 237.461804 -291.614098) (xy 237.465875 -291.558476) (xy 237.478001 -291.504039)
			(xy 237.497924 -291.451948) (xy 237.52522 -291.403313) (xy 237.559306 -291.35917) (xy 237.599455 -291.320461)
			(xy 237.644813 -291.28801) (xy 237.694413 -291.262509) (xy 237.747197 -291.244502) (xy 237.80204 -291.234372)
			(xy 237.857774 -291.232335) (xy 237.913211 -291.238435) (xy 237.967168 -291.252541) (xy 238.018497 -291.274353)
			(xy 238.066103 -291.303407) (xy 238.108971 -291.339082) (xy 238.146188 -291.380619) (xy 238.176961 -291.427132)
			(xy 238.200633 -291.477629) (xy 238.216701 -291.531036) (xy 238.224821 -291.586212) (xy 238.22533 -291.614098)
			(xy 238.224821 -291.641984) (xy 238.216701 -291.69716) (xy 238.200633 -291.750567) (xy 238.176961 -291.801064)
			(xy 238.146188 -291.847577) (xy 238.108971 -291.889114) (xy 238.066103 -291.924789) (xy 238.018497 -291.953843)
			(xy 237.967168 -291.975655) (xy 237.913211 -291.989761) (xy 237.857774 -291.995861) (xy 237.80204 -291.993824)
			(xy 237.747197 -291.983694) (xy 237.694413 -291.965687) (xy 237.644813 -291.940186) (xy 237.599455 -291.907735)
			(xy 237.559306 -291.869026) (xy 237.52522 -291.824883) (xy 237.497924 -291.776248) (xy 237.478001 -291.724157)
			(xy 237.465875 -291.66972) (xy 237.461804 -291.614098) (xy 211.054442 -291.614098) (xy 211.054442 -292.025578)
			(xy 226.184966 -292.025578) (xy 226.189037 -291.969956) (xy 226.201163 -291.915519) (xy 226.221086 -291.863428)
			(xy 226.248382 -291.814793) (xy 226.282468 -291.77065) (xy 226.322617 -291.731941) (xy 226.367975 -291.69949)
			(xy 226.417575 -291.673989) (xy 226.470359 -291.655982) (xy 226.525202 -291.645852) (xy 226.580936 -291.643815)
			(xy 226.636373 -291.649915) (xy 226.69033 -291.664021) (xy 226.741659 -291.685833) (xy 226.789265 -291.714887)
			(xy 226.832133 -291.750562) (xy 226.86935 -291.792099) (xy 226.900123 -291.838612) (xy 226.923795 -291.889109)
			(xy 226.939863 -291.942516) (xy 226.947983 -291.997692) (xy 226.948492 -292.025578) (xy 226.947983 -292.053464)
			(xy 226.939863 -292.10864) (xy 226.923795 -292.162047) (xy 226.900123 -292.212544) (xy 226.86935 -292.259057)
			(xy 226.836853 -292.295326) (xy 228.289102 -292.295326) (xy 228.293173 -292.239704) (xy 228.305299 -292.185267)
			(xy 228.325222 -292.133176) (xy 228.352518 -292.084541) (xy 228.386604 -292.040398) (xy 228.426753 -292.001689)
			(xy 228.472111 -291.969238) (xy 228.521711 -291.943737) (xy 228.574495 -291.92573) (xy 228.629338 -291.9156)
			(xy 228.685072 -291.913563) (xy 228.740509 -291.919663) (xy 228.794466 -291.933769) (xy 228.845795 -291.955581)
			(xy 228.893401 -291.984635) (xy 228.936269 -292.02031) (xy 228.973486 -292.061847) (xy 229.004259 -292.10836)
			(xy 229.027931 -292.158857) (xy 229.043999 -292.212264) (xy 229.052119 -292.26744) (xy 229.052628 -292.295326)
			(xy 240.233452 -292.295326) (xy 240.237523 -292.239704) (xy 240.249649 -292.185267) (xy 240.269572 -292.133176)
			(xy 240.296868 -292.084541) (xy 240.330954 -292.040398) (xy 240.371103 -292.001689) (xy 240.416461 -291.969238)
			(xy 240.466061 -291.943737) (xy 240.518845 -291.92573) (xy 240.573688 -291.9156) (xy 240.629422 -291.913563)
			(xy 240.684859 -291.919663) (xy 240.738816 -291.933769) (xy 240.790145 -291.955581) (xy 240.837751 -291.984635)
			(xy 240.880619 -292.02031) (xy 240.917836 -292.061847) (xy 240.948609 -292.10836) (xy 240.972281 -292.158857)
			(xy 240.988349 -292.212264) (xy 240.996469 -292.26744) (xy 240.996978 -292.295326) (xy 240.996469 -292.323212)
			(xy 240.988349 -292.378388) (xy 240.972281 -292.431795) (xy 240.948609 -292.482292) (xy 240.917836 -292.528805)
			(xy 240.880619 -292.570342) (xy 240.837751 -292.606017) (xy 240.790145 -292.635071) (xy 240.738816 -292.656883)
			(xy 240.684859 -292.670989) (xy 240.629422 -292.677089) (xy 240.573688 -292.675052) (xy 240.518845 -292.664922)
			(xy 240.466061 -292.646915) (xy 240.416461 -292.621414) (xy 240.371103 -292.588963) (xy 240.330954 -292.550254)
			(xy 240.296868 -292.506111) (xy 240.269572 -292.457476) (xy 240.249649 -292.405385) (xy 240.237523 -292.350948)
			(xy 240.233452 -292.295326) (xy 229.052628 -292.295326) (xy 229.052119 -292.323212) (xy 229.043999 -292.378388)
			(xy 229.027931 -292.431795) (xy 229.004259 -292.482292) (xy 228.973486 -292.528805) (xy 228.936269 -292.570342)
			(xy 228.893401 -292.606017) (xy 228.845795 -292.635071) (xy 228.794466 -292.656883) (xy 228.740509 -292.670989)
			(xy 228.685072 -292.677089) (xy 228.629338 -292.675052) (xy 228.574495 -292.664922) (xy 228.521711 -292.646915)
			(xy 228.472111 -292.621414) (xy 228.426753 -292.588963) (xy 228.386604 -292.550254) (xy 228.352518 -292.506111)
			(xy 228.325222 -292.457476) (xy 228.305299 -292.405385) (xy 228.293173 -292.350948) (xy 228.289102 -292.295326)
			(xy 226.836853 -292.295326) (xy 226.832133 -292.300594) (xy 226.789265 -292.336269) (xy 226.741659 -292.365323)
			(xy 226.69033 -292.387135) (xy 226.636373 -292.401241) (xy 226.580936 -292.407341) (xy 226.525202 -292.405304)
			(xy 226.470359 -292.395174) (xy 226.417575 -292.377167) (xy 226.367975 -292.351666) (xy 226.322617 -292.319215)
			(xy 226.282468 -292.280506) (xy 226.248382 -292.236363) (xy 226.221086 -292.187728) (xy 226.201163 -292.135637)
			(xy 226.189037 -292.0812) (xy 226.184966 -292.025578) (xy 211.054442 -292.025578) (xy 211.054442 -293.537132)
			(xy 233.241848 -293.537132) (xy 233.245919 -293.48151) (xy 233.258045 -293.427073) (xy 233.277968 -293.374982)
			(xy 233.305264 -293.326347) (xy 233.33935 -293.282204) (xy 233.379499 -293.243495) (xy 233.424857 -293.211044)
			(xy 233.474457 -293.185543) (xy 233.527241 -293.167536) (xy 233.582084 -293.157406) (xy 233.637818 -293.155369)
			(xy 233.693255 -293.161469) (xy 233.747212 -293.175575) (xy 233.798541 -293.197387) (xy 233.846147 -293.226441)
			(xy 233.889015 -293.262116) (xy 233.926232 -293.303653) (xy 233.957005 -293.350166) (xy 233.980677 -293.400663)
			(xy 233.996745 -293.45407) (xy 234.004865 -293.509246) (xy 234.005374 -293.537132) (xy 245.186198 -293.537132)
			(xy 245.190269 -293.48151) (xy 245.202395 -293.427073) (xy 245.222318 -293.374982) (xy 245.249614 -293.326347)
			(xy 245.2837 -293.282204) (xy 245.323849 -293.243495) (xy 245.369207 -293.211044) (xy 245.418807 -293.185543)
			(xy 245.471591 -293.167536) (xy 245.526434 -293.157406) (xy 245.582168 -293.155369) (xy 245.637605 -293.161469)
			(xy 245.691562 -293.175575) (xy 245.742891 -293.197387) (xy 245.790497 -293.226441) (xy 245.833365 -293.262116)
			(xy 245.870582 -293.303653) (xy 245.901355 -293.350166) (xy 245.925027 -293.400663) (xy 245.941095 -293.45407)
			(xy 245.949215 -293.509246) (xy 245.949724 -293.537132) (xy 245.949215 -293.565018) (xy 245.941095 -293.620194)
			(xy 245.925027 -293.673601) (xy 245.901355 -293.724098) (xy 245.870582 -293.770611) (xy 245.833365 -293.812148)
			(xy 245.790497 -293.847823) (xy 245.742891 -293.876877) (xy 245.691562 -293.898689) (xy 245.637605 -293.912795)
			(xy 245.582168 -293.918895) (xy 245.526434 -293.916858) (xy 245.471591 -293.906728) (xy 245.418807 -293.888721)
			(xy 245.369207 -293.86322) (xy 245.323849 -293.830769) (xy 245.2837 -293.79206) (xy 245.249614 -293.747917)
			(xy 245.222318 -293.699282) (xy 245.202395 -293.647191) (xy 245.190269 -293.592754) (xy 245.186198 -293.537132)
			(xy 234.005374 -293.537132) (xy 234.004865 -293.565018) (xy 233.996745 -293.620194) (xy 233.980677 -293.673601)
			(xy 233.957005 -293.724098) (xy 233.926232 -293.770611) (xy 233.889015 -293.812148) (xy 233.846147 -293.847823)
			(xy 233.798541 -293.876877) (xy 233.747212 -293.898689) (xy 233.693255 -293.912795) (xy 233.637818 -293.918895)
			(xy 233.582084 -293.916858) (xy 233.527241 -293.906728) (xy 233.474457 -293.888721) (xy 233.424857 -293.86322)
			(xy 233.379499 -293.830769) (xy 233.33935 -293.79206) (xy 233.305264 -293.747917) (xy 233.277968 -293.699282)
			(xy 233.258045 -293.647191) (xy 233.245919 -293.592754) (xy 233.241848 -293.537132) (xy 211.054442 -293.537132)
			(xy 211.054442 -293.958264) (xy 211.054878 -293.968328) (xy 211.062614 -293.986912) (xy 211.069428 -293.994332)
			(xy 211.792312 -294.717216) (xy 211.799707 -294.72407) (xy 211.818306 -294.731813) (xy 211.82838 -294.732202)
		)
		(stroke
			(width 0)
			(type solid)
		)
		(fill yes)
		(layer "In13.Cu")
		(net "GND")
	)
	(gr_poly
		(pts
			(xy 314.014866 -396.670276) (xy 314.018422 -396.651988) (xy 314.02365 -396.627779) (xy 314.040882 -396.58135)
			(xy 314.065379 -396.538309) (xy 314.0965 -396.499784) (xy 314.133428 -396.466786) (xy 314.175197 -396.440178)
			(xy 314.220712 -396.420658) (xy 314.26878 -396.408738) (xy 314.318142 -396.404729) (xy 314.367504 -396.408738)
			(xy 314.415572 -396.420658) (xy 314.461087 -396.440178) (xy 314.502856 -396.466786) (xy 314.539784 -396.499784)
			(xy 314.570905 -396.538309) (xy 314.595402 -396.58135) (xy 314.612634 -396.627779) (xy 314.617862 -396.651988)
			(xy 314.621418 -396.670276) (xy 314.649104 -396.693136) (xy 315.18733 -396.693136) (xy 315.215016 -396.670276)
			(xy 315.218572 -396.651988) (xy 315.223854 -396.627753) (xy 315.241212 -396.581293) (xy 315.253116 -396.559532)
			(xy 315.257688 -396.551404) (xy 315.260482 -396.534132) (xy 315.245242 -396.451328) (xy 315.236098 -396.436088)
			(xy 315.228986 -396.4305) (xy 315.206795 -396.411816) (xy 315.166841 -396.369757) (xy 315.132521 -396.322988)
			(xy 315.104384 -396.272258) (xy 315.082882 -396.218379) (xy 315.068359 -396.162216) (xy 315.061048 -396.104668)
			(xy 315.060584 -396.075662) (xy 315.061187 -396.042342) (xy 315.070852 -395.976405) (xy 315.089972 -395.912566)
			(xy 315.10351 -395.882114) (xy 315.107779 -395.871644) (xy 315.107714 -395.849064) (xy 315.097959 -395.828698)
			(xy 315.08954 -395.821154) (xy 315.067298 -395.802478) (xy 315.027243 -395.760419) (xy 314.992831 -395.713631)
			(xy 314.964615 -395.662866) (xy 314.943047 -395.608938) (xy 314.928475 -395.552716) (xy 314.921132 -395.495102)
			(xy 314.92063 -395.466062) (xy 314.921075 -395.437137) (xy 314.928369 -395.379747) (xy 314.942835 -395.323734)
			(xy 314.964243 -395.26999) (xy 314.992252 -395.219372) (xy 315.026416 -395.172686) (xy 315.066189 -395.130676)
			(xy 315.08827 -395.111986) (xy 315.095341 -395.105719) (xy 315.104621 -395.089278) (xy 315.106304 -395.079982)
			(xy 315.110622 -395.048994) (xy 315.11157 -395.039756) (xy 315.107537 -395.021644) (xy 315.102748 -395.013688)
			(xy 315.089714 -394.993291) (xy 315.069112 -394.949489) (xy 315.055124 -394.903149) (xy 315.04805 -394.855264)
			(xy 315.04763 -394.831062) (xy 315.047884 -394.81887) (xy 315.048138 -394.809218) (xy 315.042042 -394.791184)
			(xy 314.983368 -394.723874) (xy 314.966604 -394.715238) (xy 314.956698 -394.714222) (xy 314.929783 -394.710874)
			(xy 314.877478 -394.696534) (xy 314.828216 -394.673848) (xy 314.783317 -394.643427) (xy 314.743985 -394.606085)
			(xy 314.711276 -394.562823) (xy 314.686067 -394.514804) (xy 314.669033 -394.463313) (xy 314.664344 -394.4366)
			(xy 314.66282 -394.427202) (xy 314.390024 -393.95527) (xy 314.382658 -393.949428) (xy 314.363878 -393.933625)
			(xy 314.330743 -393.897419) (xy 314.303321 -393.856715) (xy 314.282215 -393.812405) (xy 314.267887 -393.765464)
			(xy 314.260653 -393.71692) (xy 314.26023 -393.69238) (xy 314.260715 -393.666393) (xy 314.268849 -393.615059)
			(xy 314.284913 -393.56563) (xy 314.308513 -393.519322) (xy 314.339066 -393.477276) (xy 314.37582 -393.440528)
			(xy 314.417871 -393.409982) (xy 314.464183 -393.386391) (xy 314.513615 -393.370335) (xy 314.564951 -393.36221)
			(xy 314.590938 -393.361672) (xy 314.616952 -393.362152) (xy 314.668339 -393.370291) (xy 314.717817 -393.386378)
			(xy 314.764165 -393.410015) (xy 314.806239 -393.440619) (xy 314.843 -393.477435) (xy 314.873542 -393.519555)
			(xy 314.89711 -393.565938) (xy 314.913123 -393.61544) (xy 314.917582 -393.641072) (xy 314.919106 -393.65047)
			(xy 315.191902 -394.122402) (xy 315.199268 -394.128244) (xy 315.218048 -394.144047) (xy 315.251184 -394.180253)
			(xy 315.278607 -394.220957) (xy 315.299715 -394.265267) (xy 315.314046 -394.312208) (xy 315.321283 -394.360752)
			(xy 315.321696 -394.385292) (xy 315.321442 -394.397484) (xy 315.321188 -394.407136) (xy 315.327284 -394.42517)
			(xy 315.385958 -394.49248) (xy 315.402722 -394.501116) (xy 315.412628 -394.502132) (xy 315.439395 -394.50546)
			(xy 315.491419 -394.519687) (xy 315.540446 -394.542167) (xy 315.585176 -394.572303) (xy 315.624424 -394.609297)
			(xy 315.65715 -394.652169) (xy 315.682486 -394.699782) (xy 315.699762 -394.750875) (xy 315.708519 -394.804095)
			(xy 315.709046 -394.831062) (xy 315.708579 -394.85526) (xy 315.701484 -394.903133) (xy 315.687498 -394.949464)
			(xy 315.666919 -394.993267) (xy 315.653928 -395.013688) (xy 315.649174 -395.021658) (xy 315.64515 -395.039757)
			(xy 315.646054 -395.048994) (xy 315.650372 -395.079982) (xy 315.652175 -395.089236) (xy 315.661429 -395.105644)
			(xy 315.668406 -395.111986) (xy 315.690502 -395.13066) (xy 315.730278 -395.172669) (xy 315.764442 -395.219357)
			(xy 315.792449 -395.269979) (xy 315.813853 -395.323726) (xy 315.828312 -395.379743) (xy 315.835595 -395.437136)
			(xy 315.836046 -395.466062) (xy 315.835442 -395.499382) (xy 315.825772 -395.565316) (xy 315.806645 -395.629152)
			(xy 315.79312 -395.65961) (xy 315.78886 -395.67008) (xy 315.788936 -395.692654) (xy 315.798684 -395.713016)
			(xy 315.80709 -395.72057) (xy 315.829339 -395.739243) (xy 315.869406 -395.781297) (xy 315.903831 -395.828083)
			(xy 315.93206 -395.878848) (xy 315.95364 -395.932776) (xy 315.968224 -395.989001) (xy 315.975577 -396.046619)
			(xy 315.976 -396.075662) (xy 315.975549 -396.104666) (xy 315.968218 -396.162209) (xy 315.953682 -396.218366)
			(xy 315.932172 -396.272238) (xy 315.904033 -396.322964) (xy 315.869715 -396.369732) (xy 315.829768 -396.411793)
			(xy 315.807598 -396.4305) (xy 315.800486 -396.436088) (xy 315.791342 -396.451328) (xy 315.776102 -396.534132)
			(xy 315.778896 -396.551404) (xy 315.783468 -396.559532) (xy 315.795367 -396.581295) (xy 315.812728 -396.627754)
			(xy 315.818012 -396.651988) (xy 315.821568 -396.670276) (xy 315.849254 -396.693136) (xy 316.387226 -396.693136)
			(xy 316.414912 -396.670276) (xy 316.418468 -396.651988) (xy 316.423636 -396.628174) (xy 316.440509 -396.582461)
			(xy 316.46442 -396.540003) (xy 316.494764 -396.501876) (xy 316.512448 -396.48511) (xy 316.52083 -396.47749)
			(xy 316.529466 -396.457424) (xy 316.526672 -396.35811) (xy 316.517274 -396.338552) (xy 316.508384 -396.33144)
			(xy 316.489824 -396.315637) (xy 316.457098 -396.27951) (xy 316.430027 -396.238973) (xy 316.409195 -396.194903)
			(xy 316.395054 -396.148254) (xy 316.387908 -396.100035) (xy 316.38748 -396.075662) (xy 316.387919 -396.051546)
			(xy 316.394924 -396.003825) (xy 316.408781 -395.957627) (xy 316.429195 -395.913928) (xy 316.44209 -395.893544)
			(xy 316.447932 -395.884654) (xy 316.451488 -395.864588) (xy 316.430406 -395.772386) (xy 316.418214 -395.755622)
			(xy 316.409324 -395.750288) (xy 316.388523 -395.737431) (xy 316.350609 -395.706552) (xy 316.317661 -395.67042)
			(xy 316.2904 -395.629826) (xy 316.26942 -395.585658) (xy 316.255181 -395.538878) (xy 316.247993 -395.490511)
			(xy 316.247526 -395.466062) (xy 316.248087 -395.43878) (xy 316.257049 -395.384956) (xy 316.274722 -395.333333)
			(xy 316.300628 -395.28531) (xy 316.334064 -395.24219) (xy 316.353698 -395.223238) (xy 316.361147 -395.215746)
			(xy 316.36969 -395.196451) (xy 316.370208 -395.1859) (xy 316.370208 -395.111224) (xy 316.369622 -395.100689)
			(xy 316.361095 -395.081411) (xy 316.353698 -395.073886) (xy 316.33404 -395.054955) (xy 316.300592 -395.011836)
			(xy 316.274679 -394.963809) (xy 316.257004 -394.912179) (xy 316.248049 -394.858348) (xy 316.247526 -394.831062)
			(xy 316.24778 -394.81887) (xy 316.248034 -394.809218) (xy 316.241938 -394.791184) (xy 316.183264 -394.723874)
			(xy 316.1665 -394.715238) (xy 316.156848 -394.714222) (xy 316.129935 -394.71087) (xy 316.077637 -394.696524)
			(xy 316.028381 -394.673835) (xy 315.983489 -394.643411) (xy 315.944164 -394.606068) (xy 315.911461 -394.562809)
			(xy 315.886256 -394.514791) (xy 315.869226 -394.463304) (xy 315.864494 -394.4366) (xy 315.86297 -394.427202)
			(xy 315.590174 -393.95527) (xy 315.582808 -393.949428) (xy 315.564031 -393.933624) (xy 315.5309 -393.897416)
			(xy 315.503483 -393.856711) (xy 315.48238 -393.812402) (xy 315.468054 -393.765461) (xy 315.460821 -393.716919)
			(xy 315.46038 -393.69238) (xy 315.460891 -393.666394) (xy 315.469024 -393.615061) (xy 315.485087 -393.565632)
			(xy 315.508683 -393.519325) (xy 315.539233 -393.477278) (xy 315.575984 -393.440528) (xy 315.618031 -393.409979)
			(xy 315.664339 -393.386384) (xy 315.713769 -393.370322) (xy 315.765101 -393.36219) (xy 315.791088 -393.361672)
			(xy 315.817099 -393.362156) (xy 315.86848 -393.370301) (xy 315.917952 -393.386392) (xy 315.964293 -393.410032)
			(xy 316.006361 -393.440638) (xy 316.043116 -393.477454) (xy 316.073652 -393.519571) (xy 316.097216 -393.565951)
			(xy 316.113226 -393.615449) (xy 316.117732 -393.641072) (xy 316.119256 -393.65047) (xy 316.392052 -394.122402)
			(xy 316.399418 -394.128244) (xy 316.418195 -394.144049) (xy 316.451326 -394.180257) (xy 316.478745 -394.220962)
			(xy 316.49985 -394.26527) (xy 316.514178 -394.312211) (xy 316.521415 -394.360753) (xy 316.521846 -394.385292)
			(xy 316.521592 -394.397484) (xy 316.521338 -394.407136) (xy 316.527434 -394.42517) (xy 316.586108 -394.49248)
			(xy 316.602872 -394.501116) (xy 316.612524 -394.502132) (xy 316.639291 -394.50546) (xy 316.691316 -394.519687)
			(xy 316.740343 -394.542166) (xy 316.785074 -394.572302) (xy 316.824323 -394.609296) (xy 316.857049 -394.652168)
			(xy 316.882386 -394.699781) (xy 316.899661 -394.750875) (xy 316.908418 -394.804094) (xy 316.908942 -394.831062)
			(xy 316.908379 -394.858344) (xy 316.899416 -394.912167) (xy 316.881742 -394.96379) (xy 316.855838 -395.011813)
			(xy 316.822405 -395.054935) (xy 316.80277 -395.073886) (xy 316.795329 -395.081381) (xy 316.7868 -395.100676)
			(xy 316.78626 -395.111224) (xy 316.78626 -395.1859) (xy 316.786852 -395.196432) (xy 316.795393 -395.215695)
			(xy 316.80277 -395.223238) (xy 316.822423 -395.242172) (xy 316.855861 -395.285294) (xy 316.881765 -395.333321)
			(xy 316.899432 -395.384949) (xy 316.908382 -395.438778) (xy 316.908942 -395.466062) (xy 316.908509 -395.49018)
			(xy 316.901514 -395.537905) (xy 316.887667 -395.58411) (xy 316.867261 -395.627817) (xy 316.854332 -395.64818)
			(xy 316.84849 -395.65707) (xy 316.844934 -395.677136) (xy 316.866016 -395.769338) (xy 316.878208 -395.786102)
			(xy 316.887098 -395.791436) (xy 316.907902 -395.80429) (xy 316.945822 -395.835166) (xy 316.978775 -395.871296)
			(xy 317.00604 -395.91189) (xy 317.027022 -395.95606) (xy 317.041262 -396.002842) (xy 317.048449 -396.051211)
			(xy 317.048896 -396.075662) (xy 317.048459 -396.100033) (xy 317.041303 -396.148247) (xy 317.027157 -396.194892)
			(xy 317.006324 -396.238958) (xy 316.979257 -396.279493) (xy 316.946538 -396.315623) (xy 316.927992 -396.33144)
			(xy 316.919102 -396.338552) (xy 316.909704 -396.35811) (xy 316.90691 -396.457424) (xy 316.915546 -396.47749)
			(xy 316.923928 -396.48511) (xy 316.941623 -396.501868) (xy 316.971983 -396.539987) (xy 316.9959 -396.582446)
			(xy 317.012768 -396.628166) (xy 317.017908 -396.651988) (xy 317.021464 -396.670276) (xy 317.04915 -396.693136)
			(xy 317.587376 -396.693136) (xy 317.615062 -396.670276) (xy 317.618618 -396.651988) (xy 317.623787 -396.628175)
			(xy 317.640662 -396.582463) (xy 317.664576 -396.540008) (xy 317.694923 -396.501885) (xy 317.712598 -396.48511)
			(xy 317.72098 -396.47749) (xy 317.729616 -396.457424) (xy 317.726822 -396.35811) (xy 317.717424 -396.338552)
			(xy 317.708534 -396.33144) (xy 317.689971 -396.315639) (xy 317.657241 -396.279513) (xy 317.630166 -396.238977)
			(xy 317.609331 -396.194906) (xy 317.595187 -396.148256) (xy 317.58804 -396.100036) (xy 317.58763 -396.075662)
			(xy 317.588069 -396.051546) (xy 317.595075 -396.003826) (xy 317.608933 -395.957628) (xy 317.629351 -395.913931)
			(xy 317.64224 -395.893544) (xy 317.648082 -395.884654) (xy 317.651638 -395.864588) (xy 317.630556 -395.772386)
			(xy 317.618364 -395.755622) (xy 317.609474 -395.750288) (xy 317.588671 -395.737433) (xy 317.550751 -395.706556)
			(xy 317.517799 -395.670426) (xy 317.490533 -395.629833) (xy 317.469549 -395.585663) (xy 317.455308 -395.538882)
			(xy 317.448118 -395.490513) (xy 317.447676 -395.466062) (xy 317.448237 -395.438779) (xy 317.457197 -395.384954)
			(xy 317.474869 -395.333329) (xy 317.500772 -395.285304) (xy 317.534205 -395.242181) (xy 317.553848 -395.223238)
			(xy 317.561303 -395.215749) (xy 317.569855 -395.196453) (xy 317.570358 -395.1859) (xy 317.570358 -395.111224)
			(xy 317.569771 -395.10069) (xy 317.561238 -395.081418) (xy 317.553848 -395.073886) (xy 317.534193 -395.054953)
			(xy 317.500749 -395.011833) (xy 317.47484 -394.963806) (xy 317.457169 -394.912177) (xy 317.448215 -394.858347)
			(xy 317.447676 -394.831062) (xy 317.44793 -394.81887) (xy 317.448184 -394.809218) (xy 317.442088 -394.791184)
			(xy 317.383414 -394.723874) (xy 317.36665 -394.715238) (xy 317.356744 -394.714222) (xy 317.329831 -394.71087)
			(xy 317.277534 -394.696523) (xy 317.228279 -394.673834) (xy 317.183387 -394.64341) (xy 317.144062 -394.606067)
			(xy 317.111359 -394.562807) (xy 317.086155 -394.51479) (xy 317.069125 -394.463304) (xy 317.06439 -394.4366)
			(xy 317.062866 -394.427202) (xy 316.79007 -393.95527) (xy 316.782704 -393.949428) (xy 316.763927 -393.933624)
			(xy 316.730797 -393.897416) (xy 316.70338 -393.85671) (xy 316.682277 -393.812401) (xy 316.667952 -393.765461)
			(xy 316.660719 -393.716919) (xy 316.660276 -393.69238) (xy 316.660787 -393.666393) (xy 316.66892 -393.61506)
			(xy 316.684983 -393.565631) (xy 316.708579 -393.519324) (xy 316.739129 -393.477277) (xy 316.77588 -393.440526)
			(xy 316.817927 -393.409977) (xy 316.864235 -393.386381) (xy 316.913664 -393.370319) (xy 316.964997 -393.362187)
			(xy 316.990984 -393.361672) (xy 317.016996 -393.362156) (xy 317.068377 -393.3703) (xy 317.117849 -393.386391)
			(xy 317.164191 -393.410031) (xy 317.206259 -393.440636) (xy 317.243015 -393.477452) (xy 317.273551 -393.51957)
			(xy 317.297115 -393.56595) (xy 317.313125 -393.615449) (xy 317.317628 -393.641072) (xy 317.319152 -393.65047)
			(xy 317.591948 -394.122402) (xy 317.599314 -394.128244) (xy 317.618091 -394.144048) (xy 317.651223 -394.180256)
			(xy 317.678642 -394.220961) (xy 317.699748 -394.26527) (xy 317.714076 -394.31221) (xy 317.721312 -394.360753)
			(xy 317.721742 -394.385292) (xy 317.721488 -394.397484) (xy 317.721234 -394.407136) (xy 317.72733 -394.42517)
			(xy 317.786004 -394.49248) (xy 317.802768 -394.501116) (xy 317.812674 -394.502132) (xy 317.839444 -394.505456)
			(xy 317.891475 -394.519677) (xy 317.940509 -394.542153) (xy 317.985247 -394.572287) (xy 318.024502 -394.609281)
			(xy 318.057234 -394.652154) (xy 318.082575 -394.699771) (xy 318.099854 -394.750868) (xy 318.108613 -394.804092)
			(xy 318.109092 -394.831062) (xy 318.108529 -394.858344) (xy 318.099565 -394.912166) (xy 318.081889 -394.963787)
			(xy 318.055982 -395.011808) (xy 318.022546 -395.054926) (xy 318.00292 -395.073886) (xy 317.995473 -395.081378)
			(xy 317.986936 -395.100674) (xy 317.98641 -395.111224) (xy 317.98641 -395.1859) (xy 317.987001 -395.196433)
			(xy 317.995536 -395.215702) (xy 318.00292 -395.223238) (xy 318.022575 -395.24217) (xy 318.056019 -395.285291)
			(xy 318.081927 -395.333317) (xy 318.099597 -395.384947) (xy 318.108548 -395.438777) (xy 318.109092 -395.466062)
			(xy 318.108659 -395.49018) (xy 318.101663 -395.537904) (xy 318.087814 -395.584109) (xy 318.067405 -395.627813)
			(xy 318.054482 -395.64818) (xy 318.04864 -395.65707) (xy 318.045084 -395.677136) (xy 318.066166 -395.769338)
			(xy 318.078358 -395.786102) (xy 318.087248 -395.791436) (xy 318.108049 -395.804292) (xy 318.145964 -395.835171)
			(xy 318.178912 -395.871302) (xy 318.206173 -395.911896) (xy 318.227151 -395.956066) (xy 318.241389 -396.002845)
			(xy 318.248574 -396.051213) (xy 318.249046 -396.075662) (xy 318.248608 -396.100033) (xy 318.241452 -396.148246)
			(xy 318.227304 -396.194889) (xy 318.20647 -396.238953) (xy 318.179399 -396.279485) (xy 318.146678 -396.315611)
			(xy 318.128142 -396.33144) (xy 318.119252 -396.338552) (xy 318.109854 -396.35811) (xy 318.10706 -396.457424)
			(xy 318.115696 -396.47749) (xy 318.124078 -396.48511) (xy 318.14177 -396.501869) (xy 318.172125 -396.539991)
			(xy 318.196039 -396.58245) (xy 318.212904 -396.628169) (xy 318.218058 -396.651988) (xy 318.221614 -396.670276)
			(xy 318.2493 -396.693136) (xy 318.787272 -396.693136) (xy 318.814958 -396.670276) (xy 318.818514 -396.651988)
			(xy 318.823683 -396.628175) (xy 318.840558 -396.582463) (xy 318.864471 -396.540008) (xy 318.894818 -396.501885)
			(xy 318.912494 -396.48511) (xy 318.920876 -396.47749) (xy 318.929512 -396.457424) (xy 318.926718 -396.35811)
			(xy 318.91732 -396.338552) (xy 318.90843 -396.33144) (xy 318.889867 -396.315638) (xy 318.857138 -396.279513)
			(xy 318.830063 -396.238976) (xy 318.809228 -396.194906) (xy 318.795084 -396.148256) (xy 318.787938 -396.100036)
			(xy 318.787526 -396.075662) (xy 318.787965 -396.051546) (xy 318.794971 -396.003826) (xy 318.808829 -395.957628)
			(xy 318.829246 -395.913931) (xy 318.842136 -395.893544) (xy 318.847978 -395.884654) (xy 318.851534 -395.864588)
			(xy 318.830452 -395.772386) (xy 318.81826 -395.755622) (xy 318.80937 -395.750288) (xy 318.788567 -395.737433)
			(xy 318.750648 -395.706556) (xy 318.717696 -395.670426) (xy 318.69043 -395.629832) (xy 318.669447 -395.585662)
			(xy 318.655205 -395.538882) (xy 318.648016 -395.490512) (xy 318.647572 -395.466062) (xy 318.648133 -395.438779)
			(xy 318.657093 -395.384954) (xy 318.674764 -395.333329) (xy 318.700667 -395.285304) (xy 318.7341 -395.24218)
			(xy 318.753744 -395.223238) (xy 318.761199 -395.215749) (xy 318.769752 -395.196453) (xy 318.770254 -395.1859)
			(xy 318.770254 -395.111224) (xy 318.769667 -395.10069) (xy 318.761133 -395.081418) (xy 318.753744 -395.073886)
			(xy 318.734089 -395.054953) (xy 318.700646 -395.011832) (xy 318.674737 -394.963806) (xy 318.657066 -394.912177)
			(xy 318.648112 -394.858347) (xy 318.647572 -394.831062) (xy 318.647826 -394.81887) (xy 318.64808 -394.809218)
			(xy 318.641984 -394.791184) (xy 318.58331 -394.723874) (xy 318.566546 -394.715238) (xy 318.55664 -394.714222)
			(xy 318.529689 -394.710859) (xy 318.477318 -394.69648) (xy 318.427996 -394.673744) (xy 318.383048 -394.643262)
			(xy 318.343678 -394.605851) (xy 318.310944 -394.562516) (xy 318.285722 -394.514418) (xy 318.268691 -394.462848)
			(xy 318.264032 -394.436092) (xy 318.262762 -394.426694) (xy 317.99022 -393.95527) (xy 317.982854 -393.949428)
			(xy 317.964075 -393.933625) (xy 317.93094 -393.897419) (xy 317.903518 -393.856715) (xy 317.882412 -393.812405)
			(xy 317.868085 -393.765463) (xy 317.86085 -393.71692) (xy 317.860426 -393.69238) (xy 317.860911 -393.666393)
			(xy 317.869045 -393.615059) (xy 317.885109 -393.565629) (xy 317.908708 -393.519321) (xy 317.939262 -393.477275)
			(xy 317.976016 -393.440526) (xy 318.018067 -393.40998) (xy 318.064379 -393.386388) (xy 318.113811 -393.370332)
			(xy 318.165147 -393.362206) (xy 318.191134 -393.361672) (xy 318.217148 -393.362152) (xy 318.268535 -393.37029)
			(xy 318.318014 -393.386377) (xy 318.364362 -393.410013) (xy 318.406437 -393.440618) (xy 318.443199 -393.477434)
			(xy 318.473741 -393.519553) (xy 318.49731 -393.565937) (xy 318.513323 -393.615439) (xy 318.517778 -393.641072)
			(xy 318.519302 -393.65047) (xy 318.792352 -394.12291) (xy 318.799464 -394.128752) (xy 318.818192 -394.144534)
			(xy 318.851235 -394.180681) (xy 318.878582 -394.221309) (xy 318.899634 -394.265527) (xy 318.913931 -394.312367)
			(xy 318.921159 -394.360805) (xy 318.921638 -394.385292) (xy 318.921384 -394.397484) (xy 318.92113 -394.407136)
			(xy 318.927226 -394.42517) (xy 318.9859 -394.49248) (xy 319.002664 -394.501116) (xy 319.01257 -394.502132)
			(xy 319.03934 -394.505456) (xy 319.091372 -394.519677) (xy 319.140407 -394.542152) (xy 319.185145 -394.572285)
			(xy 319.2244 -394.609279) (xy 319.257133 -394.652153) (xy 319.282475 -394.69977) (xy 319.299754 -394.750868)
			(xy 319.308513 -394.804092) (xy 319.308988 -394.831062) (xy 319.308425 -394.858344) (xy 319.29946 -394.912166)
			(xy 319.281785 -394.963787) (xy 319.255878 -395.011807) (xy 319.222441 -395.054925) (xy 319.202816 -395.073886)
			(xy 319.195369 -395.081379) (xy 319.186833 -395.100674) (xy 319.186306 -395.111224) (xy 319.186306 -395.1859)
			(xy 319.186897 -395.196433) (xy 319.195431 -395.215702) (xy 319.202816 -395.223238) (xy 319.222472 -395.24217)
			(xy 319.255915 -395.28529) (xy 319.281824 -395.333317) (xy 319.299494 -395.384947) (xy 319.308445 -395.438777)
			(xy 319.308988 -395.466062) (xy 319.308555 -395.49018) (xy 319.301559 -395.537904) (xy 319.28771 -395.584108)
			(xy 319.267301 -395.627813) (xy 319.254378 -395.64818) (xy 319.248536 -395.65707) (xy 319.24498 -395.677136)
			(xy 319.266062 -395.769338) (xy 319.278254 -395.786102) (xy 319.287144 -395.791436) (xy 319.307945 -395.804292)
			(xy 319.34586 -395.835171) (xy 319.378809 -395.871302) (xy 319.40607 -395.911896) (xy 319.427049 -395.956065)
			(xy 319.441287 -396.002845) (xy 319.448472 -396.051213) (xy 319.448942 -396.075662) (xy 319.448504 -396.100033)
			(xy 319.441348 -396.148246) (xy 319.4272 -396.194888) (xy 319.406365 -396.238952) (xy 319.379295 -396.279485)
			(xy 319.346573 -396.31561) (xy 319.328038 -396.33144) (xy 319.319148 -396.338552) (xy 319.30975 -396.35811)
			(xy 319.306956 -396.457424) (xy 319.315592 -396.47749) (xy 319.323974 -396.48511) (xy 319.341667 -396.501869)
			(xy 319.372022 -396.53999) (xy 319.395936 -396.58245) (xy 319.412801 -396.628169) (xy 319.417954 -396.651988)
			(xy 319.42151 -396.670276) (xy 319.449196 -396.693136) (xy 319.987422 -396.693136) (xy 320.015108 -396.670276)
			(xy 320.018664 -396.651988) (xy 320.023832 -396.628174) (xy 320.040705 -396.58246) (xy 320.064616 -396.540002)
			(xy 320.094959 -396.501876) (xy 320.112644 -396.48511) (xy 320.121026 -396.47749) (xy 320.129662 -396.457424)
			(xy 320.126868 -396.35811) (xy 320.11747 -396.338552) (xy 320.10858 -396.33144) (xy 320.09002 -396.315637)
			(xy 320.057295 -396.27951) (xy 320.030224 -396.238972) (xy 320.009392 -396.194903) (xy 319.995251 -396.148254)
			(xy 319.988106 -396.100035) (xy 319.987676 -396.075662) (xy 319.988115 -396.051546) (xy 319.99512 -396.003825)
			(xy 320.008976 -395.957627) (xy 320.029391 -395.913928) (xy 320.042286 -395.893544) (xy 320.048128 -395.884654)
			(xy 320.051684 -395.864588) (xy 320.030602 -395.772386) (xy 320.01841 -395.755622) (xy 320.00952 -395.750288)
			(xy 319.988714 -395.737435) (xy 319.95079 -395.706561) (xy 319.917833 -395.670432) (xy 319.890563 -395.629838)
			(xy 319.869576 -395.585667) (xy 319.855332 -395.538885) (xy 319.848142 -395.490514) (xy 319.847722 -395.466062)
			(xy 319.848283 -395.43878) (xy 319.857244 -395.384956) (xy 319.874918 -395.333332) (xy 319.900823 -395.285309)
			(xy 319.934259 -395.242189) (xy 319.953894 -395.223238) (xy 319.961343 -395.215746) (xy 319.969887 -395.196451)
			(xy 319.970404 -395.1859) (xy 319.970404 -395.111224) (xy 319.969818 -395.100689) (xy 319.96129 -395.081412)
			(xy 319.953894 -395.073886) (xy 319.934236 -395.054955) (xy 319.900788 -395.011836) (xy 319.874876 -394.963809)
			(xy 319.857202 -394.912179) (xy 319.848246 -394.858348) (xy 319.847722 -394.831062) (xy 319.847976 -394.81887)
			(xy 319.84823 -394.809218) (xy 319.842134 -394.791184) (xy 319.78346 -394.723874) (xy 319.766696 -394.715238)
			(xy 319.75679 -394.714222) (xy 319.729875 -394.710873) (xy 319.677572 -394.696532) (xy 319.62831 -394.673846)
			(xy 319.583412 -394.643424) (xy 319.544082 -394.606082) (xy 319.511374 -394.562821) (xy 319.486165 -394.514802)
			(xy 319.469132 -394.463312) (xy 319.464436 -394.4366) (xy 319.462912 -394.427202) (xy 319.190116 -393.95527)
			(xy 319.18275 -393.949428) (xy 319.163971 -393.933625) (xy 319.130836 -393.897419) (xy 319.103415 -393.856714)
			(xy 319.082309 -393.812405) (xy 319.067982 -393.765463) (xy 319.060748 -393.71692) (xy 319.060322 -393.69238)
			(xy 319.060807 -393.666393) (xy 319.068941 -393.615058) (xy 319.085005 -393.565628) (xy 319.108604 -393.51932)
			(xy 319.139157 -393.477274) (xy 319.175912 -393.440525) (xy 319.217963 -393.409978) (xy 319.264275 -393.386386)
			(xy 319.313707 -393.370329) (xy 319.365043 -393.362203) (xy 319.39103 -393.361672) (xy 319.417044 -393.362152)
			(xy 319.468432 -393.37029) (xy 319.517911 -393.386375) (xy 319.56426 -393.410012) (xy 319.606335 -393.440616)
			(xy 319.643098 -393.477432) (xy 319.67364 -393.519552) (xy 319.697209 -393.565936) (xy 319.713223 -393.615438)
			(xy 319.717674 -393.641072) (xy 319.719198 -393.65047) (xy 319.991994 -394.122402) (xy 319.99936 -394.128244)
			(xy 320.01814 -394.144047) (xy 320.051277 -394.180253) (xy 320.078701 -394.220957) (xy 320.09981 -394.265266)
			(xy 320.11414 -394.312208) (xy 320.121378 -394.360752) (xy 320.121788 -394.385292) (xy 320.121534 -394.397484)
			(xy 320.12128 -394.407136) (xy 320.127376 -394.42517) (xy 320.18605 -394.49248) (xy 320.202814 -394.501116)
			(xy 320.21272 -394.502132) (xy 320.239487 -394.50546) (xy 320.291513 -394.519686) (xy 320.340541 -394.542165)
			(xy 320.385272 -394.5723) (xy 320.424521 -394.609295) (xy 320.457248 -394.652167) (xy 320.482585 -394.69978)
			(xy 320.499861 -394.750874) (xy 320.508618 -394.804094) (xy 320.509138 -394.831062) (xy 320.508575 -394.858344)
			(xy 320.499612 -394.912167) (xy 320.481938 -394.96379) (xy 320.456034 -395.011813) (xy 320.4226 -395.054935)
			(xy 320.402966 -395.073886) (xy 320.395525 -395.081381) (xy 320.386998 -395.100676) (xy 320.386456 -395.111224)
			(xy 320.386456 -395.1859) (xy 320.387048 -395.196432) (xy 320.395589 -395.215695) (xy 320.402966 -395.223238)
			(xy 320.422619 -395.242172) (xy 320.456058 -395.285293) (xy 320.481962 -395.33332) (xy 320.499629 -395.384949)
			(xy 320.508579 -395.438778) (xy 320.509138 -395.466062) (xy 320.508705 -395.49018) (xy 320.50171 -395.537905)
			(xy 320.487863 -395.58411) (xy 320.467456 -395.627816) (xy 320.454528 -395.64818) (xy 320.448686 -395.65707)
			(xy 320.44513 -395.677136) (xy 320.466212 -395.769338) (xy 320.478404 -395.786102) (xy 320.487294 -395.791436)
			(xy 320.508098 -395.80429) (xy 320.546018 -395.835166) (xy 320.578972 -395.871296) (xy 320.606237 -395.91189)
			(xy 320.62722 -395.95606) (xy 320.64146 -396.002842) (xy 320.648646 -396.051211) (xy 320.649092 -396.075662)
			(xy 320.648655 -396.100033) (xy 320.641499 -396.148247) (xy 320.627353 -396.194891) (xy 320.60652 -396.238957)
			(xy 320.579452 -396.279493) (xy 320.546733 -396.315622) (xy 320.528188 -396.33144) (xy 320.519298 -396.338552)
			(xy 320.5099 -396.35811) (xy 320.507106 -396.457424) (xy 320.515742 -396.47749) (xy 320.524124 -396.48511)
			(xy 320.541814 -396.501871) (xy 320.572165 -396.539994) (xy 320.596075 -396.582454) (xy 320.612937 -396.628173)
			(xy 320.618104 -396.651988) (xy 320.62166 -396.670276) (xy 320.649346 -396.693136) (xy 321.187318 -396.693136)
			(xy 321.215004 -396.670276) (xy 321.21856 -396.651988) (xy 321.223728 -396.628174) (xy 321.240601 -396.58246)
			(xy 321.264511 -396.540002) (xy 321.294855 -396.501875) (xy 321.31254 -396.48511) (xy 321.320922 -396.47749)
			(xy 321.329558 -396.457424) (xy 321.326764 -396.35811) (xy 321.317366 -396.338552) (xy 321.308476 -396.33144)
			(xy 321.289916 -396.315637) (xy 321.257192 -396.279509) (xy 321.230121 -396.238972) (xy 321.209289 -396.194902)
			(xy 321.195148 -396.148253) (xy 321.188003 -396.100035) (xy 321.187572 -396.075662) (xy 321.188011 -396.051546)
			(xy 321.195016 -396.003825) (xy 321.208872 -395.957626) (xy 321.229286 -395.913928) (xy 321.242182 -395.893544)
			(xy 321.248024 -395.884654) (xy 321.25158 -395.864588) (xy 321.230498 -395.772386) (xy 321.218306 -395.755622)
			(xy 321.209416 -395.750288) (xy 321.188611 -395.737435) (xy 321.150687 -395.70656) (xy 321.11773 -395.670431)
			(xy 321.09046 -395.629838) (xy 321.069474 -395.585667) (xy 321.05523 -395.538885) (xy 321.04804 -395.490514)
			(xy 321.047618 -395.466062) (xy 321.048179 -395.43878) (xy 321.05714 -395.384956) (xy 321.074813 -395.333332)
			(xy 321.100719 -395.285309) (xy 321.134155 -395.242188) (xy 321.15379 -395.223238) (xy 321.16124 -395.215747)
			(xy 321.169785 -395.196451) (xy 321.1703 -395.1859) (xy 321.1703 -395.111224) (xy 321.169714 -395.100689)
			(xy 321.161186 -395.081412) (xy 321.15379 -395.073886) (xy 321.134133 -395.054955) (xy 321.100685 -395.011835)
			(xy 321.074773 -394.963809) (xy 321.057099 -394.912179) (xy 321.048143 -394.858348) (xy 321.047618 -394.831062)
			(xy 321.047872 -394.81887) (xy 321.048126 -394.809218) (xy 321.04203 -394.791184) (xy 320.983356 -394.723874)
			(xy 320.966592 -394.715238) (xy 320.956686 -394.714222) (xy 320.929738 -394.710855) (xy 320.877373 -394.69647)
			(xy 320.828059 -394.67373) (xy 320.783118 -394.643245) (xy 320.743755 -394.605834) (xy 320.711027 -394.5625)
			(xy 320.685811 -394.514405) (xy 320.668783 -394.462839) (xy 320.664078 -394.436092) (xy 320.662808 -394.426694)
			(xy 320.390266 -393.95527) (xy 320.3829 -393.949428) (xy 320.364123 -393.933623) (xy 320.330993 -393.897415)
			(xy 320.303576 -393.85671) (xy 320.282474 -393.812401) (xy 320.268149 -393.765461) (xy 320.260916 -393.716919)
			(xy 320.260472 -393.69238) (xy 320.260983 -393.666393) (xy 320.269116 -393.61506) (xy 320.285178 -393.565631)
			(xy 320.308775 -393.519323) (xy 320.339325 -393.477276) (xy 320.376076 -393.440525) (xy 320.418123 -393.409975)
			(xy 320.464431 -393.386378) (xy 320.51386 -393.370316) (xy 320.565193 -393.362183) (xy 320.59118 -393.361672)
			(xy 320.617192 -393.362156) (xy 320.668574 -393.3703) (xy 320.718046 -393.38639) (xy 320.764389 -393.41003)
			(xy 320.806457 -393.440635) (xy 320.843213 -393.477451) (xy 320.873751 -393.519569) (xy 320.897315 -393.565949)
			(xy 320.913325 -393.615448) (xy 320.917824 -393.641072) (xy 320.919348 -393.65047) (xy 320.94357 -393.69238)
			(xy 321.460368 -393.69238) (xy 321.460883 -393.666393) (xy 321.469016 -393.615061) (xy 321.485078 -393.565632)
			(xy 321.508674 -393.519324) (xy 321.539224 -393.477277) (xy 321.575974 -393.440526) (xy 321.61802 -393.409976)
			(xy 321.664328 -393.38638) (xy 321.713757 -393.370317) (xy 321.765089 -393.362183) (xy 321.791076 -393.361672)
			(xy 321.817085 -393.362163) (xy 321.868461 -393.370319) (xy 321.917927 -393.386416) (xy 321.964263 -393.410059)
			(xy 322.006326 -393.440663) (xy 322.04308 -393.477476) (xy 322.073618 -393.519588) (xy 322.079593 -393.531344)
			(xy 323.429122 -393.531344) (xy 323.429544 -393.506448) (xy 323.436996 -393.457216) (xy 323.451738 -393.409655)
			(xy 323.473437 -393.36484) (xy 323.501604 -393.32378) (xy 323.518276 -393.305284) (xy 323.52488 -393.298426)
			(xy 323.531738 -393.281408) (xy 323.534024 -393.195048) (xy 323.527928 -393.177522) (xy 323.521832 -393.17041)
			(xy 323.507068 -393.15242) (xy 323.482239 -393.113058) (xy 323.463177 -393.070602) (xy 323.450259 -393.025892)
			(xy 323.443739 -392.979812) (xy 323.443346 -392.956542) (xy 323.443941 -392.930558) (xy 323.452063 -392.87923)
			(xy 323.468116 -392.829804) (xy 323.491702 -392.783498) (xy 323.522243 -392.741451) (xy 323.558984 -392.7047)
			(xy 323.601022 -392.674149) (xy 323.647322 -392.65055) (xy 323.696744 -392.634484) (xy 323.74807 -392.626348)
			(xy 323.774054 -392.625834) (xy 323.797554 -392.62624) (xy 323.844085 -392.632869) (xy 323.866764 -392.639042)
			(xy 323.880226 -392.643106) (xy 323.906642 -392.636502) (xy 323.9897 -392.555222) (xy 323.997066 -392.52906)
			(xy 323.99351 -392.515598) (xy 323.987575 -392.491652) (xy 323.9812 -392.44273) (xy 323.98081 -392.418062)
			(xy 323.981296 -392.390811) (xy 323.989052 -392.336863) (xy 324.004407 -392.284568) (xy 324.027049 -392.234991)
			(xy 324.056515 -392.189141) (xy 324.092206 -392.14795) (xy 324.133397 -392.112259) (xy 324.179247 -392.082793)
			(xy 324.228824 -392.060151) (xy 324.281119 -392.044796) (xy 324.335067 -392.03704) (xy 324.389569 -392.03704)
			(xy 324.443517 -392.044796) (xy 324.495812 -392.060151) (xy 324.545389 -392.082793) (xy 324.591239 -392.112259)
			(xy 324.63243 -392.14795) (xy 324.668121 -392.189141) (xy 324.697587 -392.234991) (xy 324.720229 -392.284568)
			(xy 324.735584 -392.336863) (xy 324.74334 -392.390811) (xy 324.743826 -392.418062) (xy 324.743356 -392.445432)
			(xy 324.737522 -392.48588) (xy 325.08012 -392.48588) (xy 325.084191 -392.430258) (xy 325.096317 -392.375821)
			(xy 325.11624 -392.32373) (xy 325.143536 -392.275095) (xy 325.177622 -392.230952) (xy 325.217771 -392.192243)
			(xy 325.263129 -392.159792) (xy 325.312729 -392.134291) (xy 325.365513 -392.116284) (xy 325.420356 -392.106154)
			(xy 325.47609 -392.104117) (xy 325.531527 -392.110217) (xy 325.585484 -392.124323) (xy 325.636813 -392.146135)
			(xy 325.684419 -392.175189) (xy 325.727287 -392.210864) (xy 325.764504 -392.252401) (xy 325.795277 -392.298914)
			(xy 325.818949 -392.349411) (xy 325.835017 -392.402818) (xy 325.843137 -392.457994) (xy 325.843646 -392.48588)
			(xy 325.843137 -392.513766) (xy 325.835017 -392.568942) (xy 325.818949 -392.622349) (xy 325.795277 -392.672846)
			(xy 325.764504 -392.719359) (xy 325.727287 -392.760896) (xy 325.684419 -392.796571) (xy 325.636813 -392.825625)
			(xy 325.585484 -392.847437) (xy 325.531527 -392.861543) (xy 325.47609 -392.867643) (xy 325.420356 -392.865606)
			(xy 325.365513 -392.855476) (xy 325.312729 -392.837469) (xy 325.263129 -392.811968) (xy 325.217771 -392.779517)
			(xy 325.177622 -392.740808) (xy 325.143536 -392.696665) (xy 325.11624 -392.64803) (xy 325.096317 -392.595939)
			(xy 325.084191 -392.541502) (xy 325.08012 -392.48588) (xy 324.737522 -392.48588) (xy 324.735542 -392.499612)
			(xy 324.720055 -392.552116) (xy 324.697213 -392.601863) (xy 324.667488 -392.647829) (xy 324.649846 -392.66876)
			(xy 324.64375 -392.675872) (xy 324.6374 -392.69289) (xy 324.6374 -392.778234) (xy 324.64375 -392.795252)
			(xy 324.649846 -392.802364) (xy 324.667451 -392.823326) (xy 324.697179 -392.869288) (xy 324.720028 -392.91903)
			(xy 324.735529 -392.971527) (xy 324.743361 -393.025702) (xy 324.743365 -393.080441) (xy 324.735541 -393.134617)
			(xy 324.720048 -393.187117) (xy 324.697207 -393.236861) (xy 324.667485 -393.282828) (xy 324.649846 -393.30376)
			(xy 324.64375 -393.310872) (xy 324.6374 -393.32789) (xy 324.6374 -393.413234) (xy 324.64375 -393.430252)
			(xy 324.649846 -393.437364) (xy 324.667473 -393.458306) (xy 324.679221 -393.47648) (xy 325.08012 -393.47648)
			(xy 325.084191 -393.420858) (xy 325.096317 -393.366421) (xy 325.11624 -393.31433) (xy 325.143536 -393.265695)
			(xy 325.177622 -393.221552) (xy 325.217771 -393.182843) (xy 325.263129 -393.150392) (xy 325.312729 -393.124891)
			(xy 325.365513 -393.106884) (xy 325.420356 -393.096754) (xy 325.47609 -393.094717) (xy 325.531527 -393.100817)
			(xy 325.585484 -393.114923) (xy 325.636813 -393.136735) (xy 325.684419 -393.165789) (xy 325.727287 -393.201464)
			(xy 325.764504 -393.243001) (xy 325.795277 -393.289514) (xy 325.818949 -393.340011) (xy 325.835017 -393.393418)
			(xy 325.843137 -393.448594) (xy 325.843646 -393.47648) (xy 325.843137 -393.504366) (xy 325.835017 -393.559542)
			(xy 325.818949 -393.612949) (xy 325.795277 -393.663446) (xy 325.764504 -393.709959) (xy 325.727287 -393.751496)
			(xy 325.684419 -393.787171) (xy 325.636813 -393.816225) (xy 325.585484 -393.838037) (xy 325.531527 -393.852143)
			(xy 325.47609 -393.858243) (xy 325.420356 -393.856206) (xy 325.365513 -393.846076) (xy 325.312729 -393.828069)
			(xy 325.263129 -393.802568) (xy 325.217771 -393.770117) (xy 325.177622 -393.731408) (xy 325.143536 -393.687265)
			(xy 325.11624 -393.63863) (xy 325.096317 -393.586539) (xy 325.084191 -393.532102) (xy 325.08012 -393.47648)
			(xy 324.679221 -393.47648) (xy 324.697189 -393.504275) (xy 324.720028 -393.55402) (xy 324.735521 -393.606519)
			(xy 324.743351 -393.660693) (xy 324.743826 -393.688062) (xy 324.743392 -393.714973) (xy 324.735846 -393.768263)
			(xy 324.720883 -393.819962) (xy 324.698802 -393.869046) (xy 324.670041 -393.914538) (xy 324.63517 -393.955535)
			(xy 324.594883 -393.991224) (xy 324.549979 -394.020895) (xy 324.50135 -394.043959) (xy 324.449961 -394.059959)
			(xy 324.396834 -394.068576) (xy 324.369938 -394.06957) (xy 324.358508 -394.069824) (xy 324.338442 -394.07973)
			(xy 324.27545 -394.158978) (xy 324.27037 -394.181076) (xy 324.272656 -394.192252) (xy 324.276578 -394.211829)
			(xy 324.280775 -394.251536) (xy 324.281038 -394.2715) (xy 324.280783 -394.291591) (xy 324.276587 -394.331552)
			(xy 324.272656 -394.351256) (xy 324.269608 -394.364718) (xy 324.278498 -394.39088) (xy 324.366382 -394.467588)
			(xy 324.39356 -394.472668) (xy 324.406514 -394.468096) (xy 324.437903 -394.457455) (xy 324.503172 -394.445965)
			(xy 324.536308 -394.445236) (xy 324.563558 -394.445686) (xy 324.617503 -394.453443) (xy 324.669795 -394.468798)
			(xy 324.719369 -394.491439) (xy 324.765217 -394.520904) (xy 324.806405 -394.556594) (xy 324.842095 -394.597782)
			(xy 324.871561 -394.64363) (xy 324.894201 -394.693204) (xy 324.909556 -394.745496) (xy 324.917314 -394.799441)
			(xy 324.917315 -394.853941) (xy 324.90956 -394.907886) (xy 324.894208 -394.960178) (xy 324.87157 -395.009754)
			(xy 324.842107 -395.055603) (xy 324.806419 -395.096793) (xy 324.765232 -395.132485) (xy 324.719386 -395.161952)
			(xy 324.669812 -395.184595) (xy 324.617521 -395.199953) (xy 324.563577 -395.207712) (xy 324.509077 -395.207716)
			(xy 324.455131 -395.199964) (xy 324.402838 -395.184614) (xy 324.353261 -395.161978) (xy 324.30741 -395.132517)
			(xy 324.266219 -395.096831) (xy 324.230525 -395.055646) (xy 324.201056 -395.009801) (xy 324.178411 -394.960229)
			(xy 324.163051 -394.907938) (xy 324.155289 -394.853994) (xy 324.1548 -394.826744) (xy 324.155046 -394.806653)
			(xy 324.159248 -394.766692) (xy 324.163182 -394.746988) (xy 324.16623 -394.733526) (xy 324.15734 -394.707364)
			(xy 324.069456 -394.630656) (xy 324.042278 -394.625576) (xy 324.029324 -394.630148) (xy 323.997932 -394.640781)
			(xy 323.932665 -394.652276) (xy 323.89953 -394.653008) (xy 323.872278 -394.652517) (xy 323.818328 -394.644764)
			(xy 323.766031 -394.629412) (xy 323.716451 -394.606773) (xy 323.670597 -394.577308) (xy 323.629404 -394.541617)
			(xy 323.59371 -394.500427) (xy 323.564242 -394.454576) (xy 323.541599 -394.404998) (xy 323.526242 -394.352701)
			(xy 323.518485 -394.298752) (xy 323.518022 -394.2715) (xy 323.518433 -394.245517) (xy 323.525498 -394.194033)
			(xy 323.539485 -394.143984) (xy 323.560134 -394.096297) (xy 323.587063 -394.051852) (xy 323.619774 -394.011473)
			(xy 323.638418 -393.99337) (xy 323.647816 -393.984734) (xy 323.65569 -393.961366) (xy 323.639688 -393.85367)
			(xy 323.62521 -393.833604) (xy 323.61378 -393.828016) (xy 323.590388 -393.815954) (xy 323.547442 -393.785533)
			(xy 323.509858 -393.748693) (xy 323.478585 -393.706363) (xy 323.454415 -393.659613) (xy 323.437957 -393.609624)
			(xy 323.429627 -393.557658) (xy 323.429122 -393.531344) (xy 322.079593 -393.531344) (xy 322.097186 -393.565961)
			(xy 322.113205 -393.615453) (xy 322.11772 -393.641072) (xy 322.119244 -393.65047) (xy 322.39204 -394.122402)
			(xy 322.399406 -394.128244) (xy 322.418189 -394.14404) (xy 322.451306 -394.180258) (xy 322.478715 -394.220968)
			(xy 322.499815 -394.265277) (xy 322.514144 -394.312215) (xy 322.521389 -394.360754) (xy 322.521834 -394.385292)
			(xy 322.52158 -394.396976) (xy 322.521326 -394.406882) (xy 322.527676 -394.424916) (xy 322.586858 -394.491972)
			(xy 322.60413 -394.500862) (xy 322.613782 -394.501624) (xy 322.638122 -394.504238) (xy 322.685672 -394.515879)
			(xy 322.730989 -394.534397) (xy 322.773084 -394.559389) (xy 322.811038 -394.59031) (xy 322.844023 -394.626483)
			(xy 322.87132 -394.667121) (xy 322.892333 -394.711337) (xy 322.906603 -394.758165) (xy 322.91382 -394.806585)
			(xy 322.914264 -394.831062) (xy 322.913754 -394.857049) (xy 322.905624 -394.908384) (xy 322.889563 -394.957814)
			(xy 322.865967 -395.004124) (xy 322.835417 -395.046172) (xy 322.798666 -395.082923) (xy 322.756618 -395.113473)
			(xy 322.710308 -395.137069) (xy 322.660878 -395.15313) (xy 322.609543 -395.16126) (xy 322.557569 -395.16126)
			(xy 322.506234 -395.15313) (xy 322.456804 -395.137069) (xy 322.410494 -395.113473) (xy 322.368446 -395.082923)
			(xy 322.331695 -395.046172) (xy 322.301145 -395.004124) (xy 322.277549 -394.957814) (xy 322.261488 -394.908384)
			(xy 322.253358 -394.857049) (xy 322.252848 -394.831062) (xy 322.253102 -394.819378) (xy 322.253356 -394.809472)
			(xy 322.247006 -394.791438) (xy 322.187824 -394.724382) (xy 322.170552 -394.715492) (xy 322.1609 -394.71473)
			(xy 322.136717 -394.712055) (xy 322.089453 -394.700515) (xy 322.044386 -394.682182) (xy 322.002488 -394.657451)
			(xy 321.964661 -394.626853) (xy 321.93172 -394.591049) (xy 321.904374 -394.550808) (xy 321.883212 -394.506998)
			(xy 321.868691 -394.460563) (xy 321.864482 -394.4366) (xy 321.862958 -394.427202) (xy 321.590162 -393.95527)
			(xy 321.582796 -393.949428) (xy 321.564048 -393.933592) (xy 321.530929 -393.897382) (xy 321.503515 -393.856681)
			(xy 321.482409 -393.81238) (xy 321.468072 -393.765449) (xy 321.460818 -393.716916) (xy 321.460368 -393.69238)
			(xy 320.94357 -393.69238) (xy 321.192398 -394.12291) (xy 321.19951 -394.128752) (xy 321.218241 -394.144532)
			(xy 321.251289 -394.180677) (xy 321.27864 -394.221304) (xy 321.299696 -394.265523) (xy 321.313995 -394.312365)
			(xy 321.321225 -394.360804) (xy 321.321684 -394.385292) (xy 321.32143 -394.397484) (xy 321.321176 -394.407136)
			(xy 321.327272 -394.42517) (xy 321.385946 -394.49248) (xy 321.40271 -394.501116) (xy 321.412616 -394.502132)
			(xy 321.439383 -394.505459) (xy 321.491409 -394.519685) (xy 321.540438 -394.542164) (xy 321.58517 -394.572299)
			(xy 321.624419 -394.609293) (xy 321.657146 -394.652165) (xy 321.682484 -394.69978) (xy 321.69976 -394.750874)
			(xy 321.708518 -394.804094) (xy 321.709034 -394.831062) (xy 321.708471 -394.858344) (xy 321.699508 -394.912167)
			(xy 321.681834 -394.96379) (xy 321.655929 -395.011813) (xy 321.622495 -395.054934) (xy 321.602862 -395.073886)
			(xy 321.595422 -395.081382) (xy 321.586895 -395.100676) (xy 321.586352 -395.111224) (xy 321.586352 -395.1859)
			(xy 321.586944 -395.196432) (xy 321.595484 -395.215696) (xy 321.602862 -395.223238) (xy 321.622515 -395.242171)
			(xy 321.655955 -395.285293) (xy 321.681859 -395.33332) (xy 321.699527 -395.384949) (xy 321.708476 -395.438778)
			(xy 321.709034 -395.466062) (xy 321.708601 -395.49018) (xy 321.701606 -395.537905) (xy 321.687758 -395.58411)
			(xy 321.667352 -395.627816) (xy 321.654424 -395.64818) (xy 321.648582 -395.65707) (xy 321.645026 -395.677136)
			(xy 321.666108 -395.769338) (xy 321.6783 -395.786102) (xy 321.68719 -395.791436) (xy 321.707994 -395.80429)
			(xy 321.745915 -395.835165) (xy 321.778869 -395.871295) (xy 321.806135 -395.911889) (xy 321.827117 -395.95606)
			(xy 321.841358 -396.002841) (xy 321.848544 -396.051211) (xy 321.848988 -396.075662) (xy 321.848551 -396.100033)
			(xy 321.841395 -396.148247) (xy 321.827248 -396.194891) (xy 321.806416 -396.238957) (xy 321.779347 -396.279492)
			(xy 321.746629 -396.315621) (xy 321.728084 -396.33144) (xy 321.719194 -396.338552) (xy 321.709796 -396.35811)
			(xy 321.707002 -396.457424) (xy 321.715638 -396.47749) (xy 321.72402 -396.48511) (xy 321.74171 -396.501871)
			(xy 321.772061 -396.539994) (xy 321.795972 -396.582454) (xy 321.812834 -396.628172) (xy 321.818 -396.651988)
			(xy 321.821556 -396.670276) (xy 321.849242 -396.693136) (xy 323.421502 -396.693136) (xy 323.431571 -396.692711)
			(xy 323.450169 -396.684989) (xy 323.45757 -396.67815) (xy 323.491098 -396.644622) (xy 323.498464 -396.630398)
			(xy 323.499734 -396.622016) (xy 323.504091 -396.59625) (xy 323.519865 -396.546434) (xy 323.543285 -396.499723)
			(xy 323.573767 -396.457282) (xy 323.610552 -396.42017) (xy 323.652721 -396.389313) (xy 323.699223 -396.365479)
			(xy 323.748897 -396.349265) (xy 323.800505 -396.341074) (xy 323.826632 -396.340584) (xy 323.854616 -396.341167)
			(xy 323.909785 -396.350587) (xy 323.962577 -396.36917) (xy 324.011482 -396.396384) (xy 324.033642 -396.413482)
			(xy 324.0405 -396.418816) (xy 324.056756 -396.424658) (xy 324.126098 -396.424658) (xy 324.136167 -396.424234)
			(xy 324.154768 -396.416515) (xy 324.162166 -396.409672) (xy 325.595234 -394.976604) (xy 325.602218 -394.969008)
			(xy 325.609945 -394.949896) (xy 325.609488 -394.929286) (xy 325.605648 -394.919708) (xy 325.559928 -394.818616)
			(xy 325.533004 -394.80236) (xy 325.517002 -394.803376) (xy 325.49338 -394.804138) (xy 325.466128 -394.803651)
			(xy 325.412178 -394.795891) (xy 325.359881 -394.780533) (xy 325.310303 -394.757889) (xy 325.264451 -394.72842)
			(xy 325.22326 -394.692726) (xy 325.187568 -394.651533) (xy 325.158101 -394.60568) (xy 325.13546 -394.5561)
			(xy 325.120104 -394.503803) (xy 325.112348 -394.449852) (xy 325.112348 -394.395348) (xy 325.120104 -394.341397)
			(xy 325.13546 -394.2891) (xy 325.158101 -394.23952) (xy 325.187568 -394.193667) (xy 325.22326 -394.152474)
			(xy 325.264451 -394.11678) (xy 325.310303 -394.087311) (xy 325.359881 -394.064667) (xy 325.412178 -394.049309)
			(xy 325.466128 -394.041549) (xy 325.49338 -394.041122) (xy 325.521181 -394.041623) (xy 325.576193 -394.049689)
			(xy 325.629453 -394.065655) (xy 325.679831 -394.089181) (xy 325.726262 -394.11977) (xy 325.767762 -394.156773)
			(xy 325.803452 -394.199408) (xy 325.832576 -394.246771) (xy 325.854518 -394.297859) (xy 325.862188 -394.324586)
			(xy 325.865236 -394.336016) (xy 325.88073 -394.353796) (xy 325.97725 -394.393928) (xy 326.000872 -394.392404)
			(xy 326.011032 -394.386562) (xy 326.036739 -394.372187) (xy 326.090797 -394.348798) (xy 326.147197 -394.33182)
			(xy 326.205183 -394.321478) (xy 326.234552 -394.319252) (xy 326.24395 -394.31849) (xy 326.260714 -394.311124)
			(xy 326.503538 -394.0683) (xy 326.510391 -394.060905) (xy 326.518136 -394.042306) (xy 326.518524 -394.032232)
			(xy 326.518524 -392.21918) (xy 326.518142 -392.209754) (xy 326.511315 -392.192181) (xy 326.498593 -392.178269)
			(xy 326.49033 -392.173714) (xy 326.395588 -392.126724) (xy 326.367394 -392.129518) (xy 326.35571 -392.138408)
			(xy 326.330679 -392.156584) (xy 326.275967 -392.185445) (xy 326.217315 -392.205101) (xy 326.156261 -392.215037)
			(xy 326.125332 -392.215624) (xy 326.098076 -392.215163) (xy 326.04412 -392.20741) (xy 325.991816 -392.192056)
			(xy 325.94223 -392.169414) (xy 325.89637 -392.139946) (xy 325.855172 -392.104251) (xy 325.819473 -392.063055)
			(xy 325.790001 -392.017199) (xy 325.767355 -391.967614) (xy 325.751997 -391.915312) (xy 325.744239 -391.861355)
			(xy 325.744239 -391.806845) (xy 325.751997 -391.752888) (xy 325.767355 -391.700586) (xy 325.790001 -391.651001)
			(xy 325.819473 -391.605145) (xy 325.855172 -391.563949) (xy 325.89637 -391.528254) (xy 325.94223 -391.498786)
			(xy 325.991816 -391.476144) (xy 326.04412 -391.46079) (xy 326.098076 -391.453037) (xy 326.125332 -391.452608)
			(xy 326.154414 -391.453157) (xy 326.211903 -391.461986) (xy 326.267387 -391.479435) (xy 326.319581 -391.5051)
			(xy 326.367277 -391.538387) (xy 326.409371 -391.578524) (xy 326.427592 -391.601198) (xy 326.434958 -391.61085)
			(xy 326.455786 -391.62101) (xy 326.467724 -391.62101) (xy 326.477729 -391.620518) (xy 326.496214 -391.612854)
			(xy 326.510362 -391.598703) (xy 326.518021 -391.580215) (xy 326.518524 -391.57021) (xy 326.518524 -391.479532)
			(xy 326.518089 -391.469467) (xy 326.51036 -391.450878) (xy 326.503538 -391.443464) (xy 326.29475 -391.234676)
			(xy 326.287353 -391.227829) (xy 326.268753 -391.220101) (xy 326.258682 -391.21969) (xy 323.777102 -391.21969)
			(xy 323.747892 -391.247376) (xy 323.746876 -391.267696) (xy 323.745075 -391.292741) (xy 323.734855 -391.341901)
			(xy 323.717323 -391.388951) (xy 323.69288 -391.432811) (xy 323.662088 -391.472472) (xy 323.625656 -391.507023)
			(xy 323.584419 -391.535671) (xy 323.539326 -391.557756) (xy 323.491413 -391.572771) (xy 323.441781 -391.580372)
			(xy 323.416676 -391.580878) (xy 323.392903 -391.580464) (xy 323.345847 -391.573651) (xy 323.300252 -391.560169)
			(xy 323.257058 -391.540295) (xy 323.217156 -391.51444) (xy 323.198998 -391.49909) (xy 323.191877 -391.493406)
			(xy 323.174827 -391.487018) (xy 323.165724 -391.486644) (xy 323.134228 -391.486644) (xy 323.125123 -391.487018)
			(xy 323.108067 -391.493394) (xy 323.100954 -391.49909) (xy 323.082794 -391.514439) (xy 323.042898 -391.540305)
			(xy 322.999705 -391.560183) (xy 322.954108 -391.573662) (xy 322.90705 -391.580463) (xy 322.883276 -391.580878)
			(xy 322.856406 -391.580351) (xy 322.803375 -391.571654) (xy 322.752449 -391.554495) (xy 322.704968 -391.529324)
			(xy 322.662185 -391.496805) (xy 322.625224 -391.457794) (xy 322.609718 -391.435844) (xy 322.603114 -391.426446)
			(xy 322.58381 -391.415016) (xy 322.494402 -391.40638) (xy 322.483186 -391.405961) (xy 322.462113 -391.413612)
			(xy 322.453762 -391.421112) (xy 321.864736 -392.010138) (xy 321.857337 -392.016981) (xy 321.838738 -392.024702)
			(xy 321.828668 -392.025124) (xy 313.64174 -392.025124) (xy 313.631715 -392.025537) (xy 313.613189 -392.033201)
			(xy 313.59901 -392.047375) (xy 313.59134 -392.065899) (xy 313.59094 -392.075924) (xy 313.59094 -393.025709)
			(xy 313.932064 -393.025709) (xy 313.932064 -392.973735) (xy 313.940194 -392.9224) (xy 313.956255 -392.87297)
			(xy 313.979851 -392.82666) (xy 314.010401 -392.784612) (xy 314.047152 -392.747861) (xy 314.0892 -392.717311)
			(xy 314.13551 -392.693715) (xy 314.18494 -392.677654) (xy 314.236275 -392.669524) (xy 314.288249 -392.669524)
			(xy 314.339584 -392.677654) (xy 314.389014 -392.693715) (xy 314.435324 -392.717311) (xy 314.477372 -392.747861)
			(xy 314.514123 -392.784612) (xy 314.544673 -392.82666) (xy 314.568269 -392.87297) (xy 314.58433 -392.9224)
			(xy 314.59246 -392.973735) (xy 314.59297 -392.999722) (xy 314.59246 -393.025709) (xy 315.13196 -393.025709)
			(xy 315.13196 -392.973735) (xy 315.14009 -392.9224) (xy 315.156151 -392.87297) (xy 315.179747 -392.82666)
			(xy 315.210297 -392.784612) (xy 315.247048 -392.747861) (xy 315.289096 -392.717311) (xy 315.335406 -392.693715)
			(xy 315.384836 -392.677654) (xy 315.436171 -392.669524) (xy 315.488145 -392.669524) (xy 315.53948 -392.677654)
			(xy 315.58891 -392.693715) (xy 315.63522 -392.717311) (xy 315.677268 -392.747861) (xy 315.714019 -392.784612)
			(xy 315.744569 -392.82666) (xy 315.768165 -392.87297) (xy 315.784226 -392.9224) (xy 315.792356 -392.973735)
			(xy 315.792866 -392.999722) (xy 315.792356 -393.025709) (xy 316.331856 -393.025709) (xy 316.331856 -392.973735)
			(xy 316.339986 -392.9224) (xy 316.356047 -392.87297) (xy 316.379643 -392.82666) (xy 316.410193 -392.784612)
			(xy 316.446944 -392.747861) (xy 316.488992 -392.717311) (xy 316.535302 -392.693715) (xy 316.584732 -392.677654)
			(xy 316.636067 -392.669524) (xy 316.688041 -392.669524) (xy 316.739376 -392.677654) (xy 316.788806 -392.693715)
			(xy 316.835116 -392.717311) (xy 316.877164 -392.747861) (xy 316.913915 -392.784612) (xy 316.944465 -392.82666)
			(xy 316.968061 -392.87297) (xy 316.984122 -392.9224) (xy 316.992252 -392.973735) (xy 316.992762 -392.999722)
			(xy 316.992252 -393.025709) (xy 317.532006 -393.025709) (xy 317.532006 -392.973735) (xy 317.540136 -392.9224)
			(xy 317.556197 -392.87297) (xy 317.579793 -392.82666) (xy 317.610343 -392.784612) (xy 317.647094 -392.747861)
			(xy 317.689142 -392.717311) (xy 317.735452 -392.693715) (xy 317.784882 -392.677654) (xy 317.836217 -392.669524)
			(xy 317.888191 -392.669524) (xy 317.939526 -392.677654) (xy 317.988956 -392.693715) (xy 318.035266 -392.717311)
			(xy 318.077314 -392.747861) (xy 318.114065 -392.784612) (xy 318.144615 -392.82666) (xy 318.168211 -392.87297)
			(xy 318.184272 -392.9224) (xy 318.192402 -392.973735) (xy 318.192912 -392.999722) (xy 318.192402 -393.025709)
			(xy 318.731902 -393.025709) (xy 318.731902 -392.973735) (xy 318.740032 -392.9224) (xy 318.756093 -392.87297)
			(xy 318.779689 -392.82666) (xy 318.810239 -392.784612) (xy 318.84699 -392.747861) (xy 318.889038 -392.717311)
			(xy 318.935348 -392.693715) (xy 318.984778 -392.677654) (xy 319.036113 -392.669524) (xy 319.088087 -392.669524)
			(xy 319.139422 -392.677654) (xy 319.188852 -392.693715) (xy 319.235162 -392.717311) (xy 319.27721 -392.747861)
			(xy 319.313961 -392.784612) (xy 319.344511 -392.82666) (xy 319.368107 -392.87297) (xy 319.384168 -392.9224)
			(xy 319.392298 -392.973735) (xy 319.392808 -392.999722) (xy 319.392298 -393.025709) (xy 319.932052 -393.025709)
			(xy 319.932052 -392.973735) (xy 319.940182 -392.9224) (xy 319.956243 -392.87297) (xy 319.979839 -392.82666)
			(xy 320.010389 -392.784612) (xy 320.04714 -392.747861) (xy 320.089188 -392.717311) (xy 320.135498 -392.693715)
			(xy 320.184928 -392.677654) (xy 320.236263 -392.669524) (xy 320.288237 -392.669524) (xy 320.339572 -392.677654)
			(xy 320.389002 -392.693715) (xy 320.435312 -392.717311) (xy 320.47736 -392.747861) (xy 320.514111 -392.784612)
			(xy 320.544661 -392.82666) (xy 320.568257 -392.87297) (xy 320.584318 -392.9224) (xy 320.592448 -392.973735)
			(xy 320.592958 -392.999722) (xy 320.592448 -393.025709) (xy 321.131948 -393.025709) (xy 321.131948 -392.973735)
			(xy 321.140078 -392.9224) (xy 321.156139 -392.87297) (xy 321.179735 -392.82666) (xy 321.210285 -392.784612)
			(xy 321.247036 -392.747861) (xy 321.289084 -392.717311) (xy 321.335394 -392.693715) (xy 321.384824 -392.677654)
			(xy 321.436159 -392.669524) (xy 321.488133 -392.669524) (xy 321.539468 -392.677654) (xy 321.588898 -392.693715)
			(xy 321.635208 -392.717311) (xy 321.677256 -392.747861) (xy 321.714007 -392.784612) (xy 321.744557 -392.82666)
			(xy 321.768153 -392.87297) (xy 321.784214 -392.9224) (xy 321.792344 -392.973735) (xy 321.792854 -392.999722)
			(xy 321.792344 -393.025709) (xy 321.784214 -393.077044) (xy 321.768153 -393.126474) (xy 321.744557 -393.172784)
			(xy 321.714007 -393.214832) (xy 321.677256 -393.251583) (xy 321.635208 -393.282133) (xy 321.588898 -393.305729)
			(xy 321.539468 -393.32179) (xy 321.488133 -393.32992) (xy 321.436159 -393.32992) (xy 321.384824 -393.32179)
			(xy 321.335394 -393.305729) (xy 321.289084 -393.282133) (xy 321.247036 -393.251583) (xy 321.210285 -393.214832)
			(xy 321.179735 -393.172784) (xy 321.156139 -393.126474) (xy 321.140078 -393.077044) (xy 321.131948 -393.025709)
			(xy 320.592448 -393.025709) (xy 320.584318 -393.077044) (xy 320.568257 -393.126474) (xy 320.544661 -393.172784)
			(xy 320.514111 -393.214832) (xy 320.47736 -393.251583) (xy 320.435312 -393.282133) (xy 320.389002 -393.305729)
			(xy 320.339572 -393.32179) (xy 320.288237 -393.32992) (xy 320.236263 -393.32992) (xy 320.184928 -393.32179)
			(xy 320.135498 -393.305729) (xy 320.089188 -393.282133) (xy 320.04714 -393.251583) (xy 320.010389 -393.214832)
			(xy 319.979839 -393.172784) (xy 319.956243 -393.126474) (xy 319.940182 -393.077044) (xy 319.932052 -393.025709)
			(xy 319.392298 -393.025709) (xy 319.384168 -393.077044) (xy 319.368107 -393.126474) (xy 319.344511 -393.172784)
			(xy 319.313961 -393.214832) (xy 319.27721 -393.251583) (xy 319.235162 -393.282133) (xy 319.188852 -393.305729)
			(xy 319.139422 -393.32179) (xy 319.088087 -393.32992) (xy 319.036113 -393.32992) (xy 318.984778 -393.32179)
			(xy 318.935348 -393.305729) (xy 318.889038 -393.282133) (xy 318.84699 -393.251583) (xy 318.810239 -393.214832)
			(xy 318.779689 -393.172784) (xy 318.756093 -393.126474) (xy 318.740032 -393.077044) (xy 318.731902 -393.025709)
			(xy 318.192402 -393.025709) (xy 318.184272 -393.077044) (xy 318.168211 -393.126474) (xy 318.144615 -393.172784)
			(xy 318.114065 -393.214832) (xy 318.077314 -393.251583) (xy 318.035266 -393.282133) (xy 317.988956 -393.305729)
			(xy 317.939526 -393.32179) (xy 317.888191 -393.32992) (xy 317.836217 -393.32992) (xy 317.784882 -393.32179)
			(xy 317.735452 -393.305729) (xy 317.689142 -393.282133) (xy 317.647094 -393.251583) (xy 317.610343 -393.214832)
			(xy 317.579793 -393.172784) (xy 317.556197 -393.126474) (xy 317.540136 -393.077044) (xy 317.532006 -393.025709)
			(xy 316.992252 -393.025709) (xy 316.984122 -393.077044) (xy 316.968061 -393.126474) (xy 316.944465 -393.172784)
			(xy 316.913915 -393.214832) (xy 316.877164 -393.251583) (xy 316.835116 -393.282133) (xy 316.788806 -393.305729)
			(xy 316.739376 -393.32179) (xy 316.688041 -393.32992) (xy 316.636067 -393.32992) (xy 316.584732 -393.32179)
			(xy 316.535302 -393.305729) (xy 316.488992 -393.282133) (xy 316.446944 -393.251583) (xy 316.410193 -393.214832)
			(xy 316.379643 -393.172784) (xy 316.356047 -393.126474) (xy 316.339986 -393.077044) (xy 316.331856 -393.025709)
			(xy 315.792356 -393.025709) (xy 315.784226 -393.077044) (xy 315.768165 -393.126474) (xy 315.744569 -393.172784)
			(xy 315.714019 -393.214832) (xy 315.677268 -393.251583) (xy 315.63522 -393.282133) (xy 315.58891 -393.305729)
			(xy 315.53948 -393.32179) (xy 315.488145 -393.32992) (xy 315.436171 -393.32992) (xy 315.384836 -393.32179)
			(xy 315.335406 -393.305729) (xy 315.289096 -393.282133) (xy 315.247048 -393.251583) (xy 315.210297 -393.214832)
			(xy 315.179747 -393.172784) (xy 315.156151 -393.126474) (xy 315.14009 -393.077044) (xy 315.13196 -393.025709)
			(xy 314.59246 -393.025709) (xy 314.58433 -393.077044) (xy 314.568269 -393.126474) (xy 314.544673 -393.172784)
			(xy 314.514123 -393.214832) (xy 314.477372 -393.251583) (xy 314.435324 -393.282133) (xy 314.389014 -393.305729)
			(xy 314.339584 -393.32179) (xy 314.288249 -393.32992) (xy 314.236275 -393.32992) (xy 314.18494 -393.32179)
			(xy 314.13551 -393.305729) (xy 314.0892 -393.282133) (xy 314.047152 -393.251583) (xy 314.010401 -393.214832)
			(xy 313.979851 -393.172784) (xy 313.956255 -393.126474) (xy 313.940194 -393.077044) (xy 313.932064 -393.025709)
			(xy 313.59094 -393.025709) (xy 313.59094 -393.404852) (xy 313.591456 -393.415782) (xy 313.600536 -393.435667)
			(xy 313.608466 -393.443206) (xy 313.629823 -393.462619) (xy 313.666065 -393.50753) (xy 313.693954 -393.558054)
			(xy 313.712641 -393.612655) (xy 313.717686 -393.641072) (xy 313.71921 -393.65047) (xy 313.992006 -394.122402)
			(xy 313.999372 -394.128244) (xy 314.018152 -394.144047) (xy 314.051287 -394.180253) (xy 314.07871 -394.220958)
			(xy 314.099818 -394.265267) (xy 314.114148 -394.312208) (xy 314.121386 -394.360752) (xy 314.1218 -394.385292)
			(xy 314.121546 -394.397484) (xy 314.121292 -394.407136) (xy 314.127388 -394.42517) (xy 314.186062 -394.49248)
			(xy 314.202826 -394.501116) (xy 314.212478 -394.502132) (xy 314.239247 -394.505457) (xy 314.291278 -394.519678)
			(xy 314.340312 -394.542154) (xy 314.385049 -394.572288) (xy 314.424304 -394.609282) (xy 314.457035 -394.652155)
			(xy 314.482376 -394.699771) (xy 314.499655 -394.750869) (xy 314.508413 -394.804092) (xy 314.508896 -394.831062)
			(xy 314.508386 -394.857049) (xy 314.500256 -394.908384) (xy 314.484195 -394.957814) (xy 314.460599 -395.004124)
			(xy 314.430049 -395.046172) (xy 314.393298 -395.082923) (xy 314.35125 -395.113473) (xy 314.30494 -395.137069)
			(xy 314.25551 -395.15313) (xy 314.204175 -395.16126) (xy 314.152201 -395.16126) (xy 314.100866 -395.15313)
			(xy 314.051436 -395.137069) (xy 314.005126 -395.113473) (xy 313.963078 -395.082923) (xy 313.926327 -395.046172)
			(xy 313.895777 -395.004124) (xy 313.872181 -394.957814) (xy 313.85612 -394.908384) (xy 313.84799 -394.857049)
			(xy 313.84748 -394.831062) (xy 313.847734 -394.81887) (xy 313.847988 -394.809218) (xy 313.841892 -394.791184)
			(xy 313.783218 -394.723874) (xy 313.766454 -394.715238) (xy 313.756802 -394.714222) (xy 313.746428 -394.713074)
			(xy 313.725839 -394.709645) (xy 313.715654 -394.707364) (xy 313.704224 -394.70457) (xy 313.681872 -394.70965)
			(xy 313.610244 -394.766292) (xy 313.601536 -394.773872) (xy 313.591497 -394.794637) (xy 313.59094 -394.80617)
			(xy 313.59094 -396.496794) (xy 313.591363 -396.506864) (xy 313.599081 -396.525466) (xy 313.605926 -396.532862)
			(xy 313.751214 -396.67815) (xy 313.758611 -396.685) (xy 313.777209 -396.692737) (xy 313.787282 -396.693136)
			(xy 313.98718 -396.693136)
		)
		(stroke
			(width 0)
			(type solid)
		)
		(fill yes)
		(layer "In13.Cu")
		(net "P1V8_CPU0_RT0_1A_1D")
	)
	(gr_poly
		(pts
			(xy 55.450232 -58.282586) (xy 55.460217 -58.282042) (xy 55.478639 -58.274319) (xy 55.486046 -58.2676)
			(xy 55.530496 -58.223404) (xy 55.537905 -58.216719) (xy 55.556341 -58.209135) (xy 55.56631 -58.208672)
			(xy 70.463918 -58.208672) (xy 70.469939 -58.208436) (xy 70.481615 -58.205472) (xy 70.487032 -58.20283)
			(xy 70.514129 -58.189378) (xy 70.570828 -58.168274) (xy 70.629628 -58.15404) (xy 70.689701 -58.146875)
			(xy 70.71995 -58.146442) (xy 70.750201 -58.146858) (xy 70.810279 -58.154005) (xy 70.869083 -58.168239)
			(xy 70.925779 -58.189359) (xy 70.952868 -58.20283) (xy 70.95828 -58.20548) (xy 70.96996 -58.208434)
			(xy 70.975982 -58.208672) (xy 81.51114 -58.208672) (xy 81.521124 -58.208127) (xy 81.539543 -58.2004)
			(xy 81.546954 -58.193686) (xy 81.765394 -57.975246) (xy 81.772233 -57.967845) (xy 81.779948 -57.949247)
			(xy 81.78038 -57.939178) (xy 81.78038 -56.904382) (xy 81.779953 -56.894314) (xy 81.772232 -56.875716)
			(xy 81.765394 -56.868314) (xy 79.577184 -54.680104) (xy 79.570072 -54.672738) (xy 79.551276 -54.665118)
			(xy 74.84999 -54.665118) (xy 74.841249 -54.665441) (xy 74.824759 -54.671241) (xy 74.811168 -54.682233)
			(xy 74.806302 -54.689502) (xy 74.754486 -54.775354) (xy 74.753724 -54.802024) (xy 74.75982 -54.813962)
			(xy 74.773544 -54.841436) (xy 74.793 -54.899683) (xy 74.802871 -54.960295) (xy 74.803508 -54.991)
			(xy 74.803022 -55.018251) (xy 74.795266 -55.072199) (xy 74.779911 -55.124494) (xy 74.757269 -55.174071)
			(xy 74.727803 -55.219921) (xy 74.692112 -55.261112) (xy 74.650921 -55.296803) (xy 74.605071 -55.326269)
			(xy 74.555494 -55.348911) (xy 74.503199 -55.364266) (xy 74.449251 -55.372022) (xy 74.394749 -55.372022)
			(xy 74.340801 -55.364266) (xy 74.288506 -55.348911) (xy 74.238929 -55.326269) (xy 74.193079 -55.296803)
			(xy 74.151888 -55.261112) (xy 74.116197 -55.219921) (xy 74.086731 -55.174071) (xy 74.064089 -55.124494)
			(xy 74.048734 -55.072199) (xy 74.040978 -55.018251) (xy 74.040492 -54.991) (xy 74.041131 -54.960296)
			(xy 74.051013 -54.899688) (xy 74.070472 -54.841444) (xy 74.08418 -54.813962) (xy 74.090276 -54.802024)
			(xy 74.089514 -54.775354) (xy 74.037698 -54.689502) (xy 74.032849 -54.682218) (xy 74.01926 -54.671213)
			(xy 74.002756 -54.665439) (xy 73.99401 -54.665118) (xy 69.050408 -54.665118) (xy 69.042441 -54.665382)
			(xy 69.027283 -54.670291) (xy 69.02069 -54.67477) (xy 69.020436 -54.67477) (xy 69.014268 -54.679571)
			(xy 69.004951 -54.692112) (xy 69.002148 -54.699408) (xy 69.002148 -54.699662) (xy 68.991945 -54.727925)
			(xy 68.963936 -54.781083) (xy 68.927954 -54.829204) (xy 68.884886 -54.871102) (xy 68.86067 -54.888892)
			(xy 68.85178 -54.894988) (xy 68.840858 -54.913784) (xy 68.829936 -55.011066) (xy 68.83654 -55.031894)
			(xy 68.843906 -55.040022) (xy 68.862359 -55.061158) (xy 68.8935 -55.107828) (xy 68.917467 -55.158556)
			(xy 68.933744 -55.212249) (xy 68.941978 -55.267747) (xy 68.942458 -55.2958) (xy 68.941972 -55.323051)
			(xy 68.934216 -55.376999) (xy 68.918861 -55.429294) (xy 68.896219 -55.478871) (xy 68.866753 -55.524721)
			(xy 68.831062 -55.565912) (xy 68.789871 -55.601603) (xy 68.744021 -55.631069) (xy 68.694444 -55.653711)
			(xy 68.642149 -55.669066) (xy 68.588201 -55.676822) (xy 68.533699 -55.676822) (xy 68.479751 -55.669066)
			(xy 68.427456 -55.653711) (xy 68.377879 -55.631069) (xy 68.332029 -55.601603) (xy 68.290838 -55.565912)
			(xy 68.255147 -55.524721) (xy 68.225681 -55.478871) (xy 68.203039 -55.429294) (xy 68.187684 -55.376999)
			(xy 68.179928 -55.323051) (xy 68.179442 -55.2958) (xy 68.179868 -55.269706) (xy 68.186981 -55.218004)
			(xy 68.201074 -55.167755) (xy 68.221884 -55.119895) (xy 68.249023 -55.075318) (xy 68.281984 -55.034855)
			(xy 68.320152 -54.999263) (xy 68.34124 -54.983888) (xy 68.35013 -54.977792) (xy 68.361052 -54.958996)
			(xy 68.371974 -54.861714) (xy 68.36537 -54.840886) (xy 68.358004 -54.832758) (xy 68.33997 -54.811422)
			(xy 68.333686 -54.804039) (xy 68.316971 -54.794243) (xy 68.307458 -54.792372) (xy 68.299838 -54.791864)
			(xy 68.220082 -54.791864) (xy 68.212462 -54.792372) (xy 68.202952 -54.794248) (xy 68.186248 -54.804051)
			(xy 68.17995 -54.811422) (xy 68.163197 -54.832205) (xy 68.124843 -54.869335) (xy 68.081689 -54.900757)
			(xy 68.034575 -54.925856) (xy 67.984423 -54.944142) (xy 67.932212 -54.955259) (xy 67.87896 -54.958989)
			(xy 67.825708 -54.955259) (xy 67.773497 -54.944142) (xy 67.723345 -54.925856) (xy 67.676231 -54.900757)
			(xy 67.633077 -54.869335) (xy 67.594723 -54.832205) (xy 67.57797 -54.811422) (xy 67.571686 -54.804039)
			(xy 67.554971 -54.794243) (xy 67.545458 -54.792372) (xy 67.537838 -54.791864) (xy 67.458082 -54.791864)
			(xy 67.450462 -54.792372) (xy 67.440952 -54.794248) (xy 67.424248 -54.804051) (xy 67.41795 -54.811422)
			(xy 67.399759 -54.833906) (xy 67.357741 -54.873643) (xy 67.310207 -54.906582) (xy 67.258245 -54.931969)
			(xy 67.203046 -54.949222) (xy 67.145876 -54.957945) (xy 67.11696 -54.958488) (xy 67.090596 -54.958046)
			(xy 67.038368 -54.950791) (xy 66.987639 -54.93641) (xy 66.939374 -54.915178) (xy 66.894494 -54.887499)
			(xy 66.853855 -54.853902) (xy 66.818231 -54.815027) (xy 66.788303 -54.771615) (xy 66.76464 -54.724494)
			(xy 66.755772 -54.699662) (xy 66.755772 -54.699408) (xy 66.752963 -54.692114) (xy 66.743654 -54.679569)
			(xy 66.737484 -54.67477) (xy 66.73723 -54.67477) (xy 66.7306 -54.670361) (xy 66.715467 -54.665441)
			(xy 66.707512 -54.665118) (xy 66.07175 -54.665118) (xy 66.060573 -54.665631) (xy 66.04027 -54.674976)
			(xy 66.032634 -54.683152) (xy 66.011893 -54.707088) (xy 65.965442 -54.750146) (xy 65.914001 -54.787097)
			(xy 65.858367 -54.81737) (xy 65.799402 -54.840496) (xy 65.738021 -54.856114) (xy 65.675175 -54.863985)
			(xy 65.611837 -54.863985) (xy 65.548991 -54.856114) (xy 65.48761 -54.840496) (xy 65.428645 -54.81737)
			(xy 65.373011 -54.787097) (xy 65.32157 -54.750146) (xy 65.275119 -54.707088) (xy 65.254378 -54.683152)
			(xy 65.246737 -54.674976) (xy 65.226441 -54.665614) (xy 65.215262 -54.665118) (xy 53.937408 -54.665118)
			(xy 53.927337 -54.664697) (xy 53.908728 -54.656987) (xy 53.90134 -54.650132) (xy 42.679366 -43.428158)
			(xy 42.672519 -43.42076) (xy 42.664789 -43.402161) (xy 42.66438 -43.39209) (xy 42.66438 -19.618706)
			(xy 42.663872 -19.608284) (xy 42.655611 -19.589143) (xy 42.648378 -19.581622) (xy 42.587164 -19.523964)
			(xy 42.56786 -19.516852) (xy 42.557192 -19.51736) (xy 42.535348 -19.517868) (xy 42.53484 -19.517868)
			(xy 42.514012 -19.51736) (xy 42.501312 -19.516598) (xy 42.478452 -19.527012) (xy 42.419778 -19.60372)
			(xy 42.416168 -19.608783) (xy 42.411283 -19.620216) (xy 42.410126 -19.626326) (xy 42.408094 -19.638772)
			(xy 42.410888 -19.647408) (xy 42.420529 -19.677417) (xy 42.430871 -19.739591) (xy 42.431462 -19.771106)
			(xy 42.430976 -19.798357) (xy 42.42322 -19.852305) (xy 42.407865 -19.9046) (xy 42.385223 -19.954177)
			(xy 42.355757 -20.000027) (xy 42.320066 -20.041218) (xy 42.278875 -20.076909) (xy 42.233025 -20.106375)
			(xy 42.183448 -20.129017) (xy 42.131153 -20.144372) (xy 42.077205 -20.152128) (xy 42.022703 -20.152128)
			(xy 41.968755 -20.144372) (xy 41.91646 -20.129017) (xy 41.866883 -20.106375) (xy 41.821033 -20.076909)
			(xy 41.779842 -20.041218) (xy 41.744151 -20.000027) (xy 41.714685 -19.954177) (xy 41.692043 -19.9046)
			(xy 41.676688 -19.852305) (xy 41.668932 -19.798357) (xy 41.668446 -19.771106) (xy 41.669059 -19.740665)
			(xy 41.678753 -19.680559) (xy 41.68775 -19.651472) (xy 41.69156 -19.639788) (xy 41.68775 -19.615658)
			(xy 41.632378 -19.53895) (xy 41.624769 -19.529563) (xy 41.603294 -19.518556) (xy 41.59123 -19.517868)
			(xy 41.243758 -19.517868) (xy 41.231686 -19.518535) (xy 41.210194 -19.529535) (xy 41.20261 -19.53895)
			(xy 41.147238 -19.615658) (xy 41.143428 -19.639788) (xy 41.147238 -19.651472) (xy 41.156245 -19.680558)
			(xy 41.165951 -19.740664) (xy 41.166542 -19.771106) (xy 41.166056 -19.798357) (xy 41.1583 -19.852305)
			(xy 41.142945 -19.9046) (xy 41.120303 -19.954177) (xy 41.090837 -20.000027) (xy 41.055146 -20.041218)
			(xy 41.013955 -20.076909) (xy 40.968105 -20.106375) (xy 40.918528 -20.129017) (xy 40.866233 -20.144372)
			(xy 40.812285 -20.152128) (xy 40.757783 -20.152128) (xy 40.703835 -20.144372) (xy 40.65154 -20.129017)
			(xy 40.601963 -20.106375) (xy 40.556113 -20.076909) (xy 40.514922 -20.041218) (xy 40.479231 -20.000027)
			(xy 40.449765 -19.954177) (xy 40.427123 -19.9046) (xy 40.411768 -19.852305) (xy 40.404012 -19.798357)
			(xy 40.403526 -19.771106) (xy 40.404179 -19.739862) (xy 40.414398 -19.678213) (xy 40.423846 -19.648424)
			(xy 40.426894 -19.638772) (xy 40.424862 -19.626326) (xy 40.423696 -19.620218) (xy 40.418816 -19.608785)
			(xy 40.41521 -19.60372) (xy 40.356536 -19.527012) (xy 40.333676 -19.516598) (xy 40.320976 -19.51736)
			(xy 40.299894 -19.517868) (xy 40.272646 -19.517381) (xy 40.218705 -19.509625) (xy 40.166416 -19.494271)
			(xy 40.116845 -19.471632) (xy 40.071 -19.442169) (xy 40.029815 -19.406481) (xy 39.994128 -19.365295)
			(xy 39.964665 -19.31945) (xy 39.942027 -19.269878) (xy 39.926674 -19.21759) (xy 39.918918 -19.163648)
			(xy 39.918918 -19.109152) (xy 39.926674 -19.05521) (xy 39.942027 -19.002922) (xy 39.964665 -18.95335)
			(xy 39.994128 -18.907505) (xy 40.029815 -18.866319) (xy 40.071 -18.830631) (xy 40.116845 -18.801168)
			(xy 40.166416 -18.778529) (xy 40.218705 -18.763175) (xy 40.272646 -18.755419) (xy 40.299894 -18.754852)
			(xy 40.320468 -18.75536) (xy 40.332914 -18.756122) (xy 40.355774 -18.745708) (xy 40.422322 -18.659094)
			(xy 40.42664 -18.634202) (xy 40.422576 -18.622264) (xy 40.413624 -18.593107) (xy 40.404059 -18.532872)
			(xy 40.403526 -18.502376) (xy 40.403526 -18.499582) (xy 40.404253 -18.472497) (xy 40.412418 -18.418933)
			(xy 40.428079 -18.367064) (xy 40.45092 -18.317932) (xy 40.480483 -18.272526) (xy 40.516172 -18.231759)
			(xy 40.55727 -18.196451) (xy 40.60295 -18.167313) (xy 40.652293 -18.14493) (xy 40.704306 -18.129753)
			(xy 40.757943 -18.122088) (xy 40.812125 -18.122088) (xy 40.865762 -18.129753) (xy 40.917775 -18.14493)
			(xy 40.967118 -18.167313) (xy 41.012798 -18.196451) (xy 41.053896 -18.231759) (xy 41.089585 -18.272526)
			(xy 41.119148 -18.317932) (xy 41.141989 -18.367064) (xy 41.15765 -18.418933) (xy 41.165815 -18.472497)
			(xy 41.166542 -18.499582) (xy 41.166542 -18.503138) (xy 41.165928 -18.533175) (xy 41.156487 -18.592504)
			(xy 41.147746 -18.621248) (xy 41.147746 -18.621502) (xy 41.147492 -18.62201) (xy 41.14452 -18.633599)
			(xy 41.148348 -18.657186) (xy 41.154858 -18.667222) (xy 41.203118 -18.73377) (xy 41.210729 -18.743155)
			(xy 41.232203 -18.754159) (xy 41.244266 -18.754852) (xy 41.590722 -18.754852) (xy 41.602797 -18.754191)
			(xy 41.624299 -18.743197) (xy 41.63187 -18.73377) (xy 41.68013 -18.667222) (xy 41.686639 -18.657185)
			(xy 41.69046 -18.633603) (xy 41.687496 -18.62201) (xy 41.687242 -18.621502) (xy 41.687242 -18.621248)
			(xy 41.678458 -18.592515) (xy 41.669022 -18.533179) (xy 41.668446 -18.503138) (xy 41.668446 -18.499582)
			(xy 41.669173 -18.472497) (xy 41.677338 -18.418933) (xy 41.692999 -18.367064) (xy 41.71584 -18.317932)
			(xy 41.745403 -18.272526) (xy 41.781092 -18.231759) (xy 41.82219 -18.196451) (xy 41.86787 -18.167313)
			(xy 41.917213 -18.14493) (xy 41.969226 -18.129753) (xy 42.022863 -18.122088) (xy 42.077045 -18.122088)
			(xy 42.130682 -18.129753) (xy 42.182695 -18.14493) (xy 42.232038 -18.167313) (xy 42.277718 -18.196451)
			(xy 42.318816 -18.231759) (xy 42.354505 -18.272526) (xy 42.384068 -18.317932) (xy 42.406909 -18.367064)
			(xy 42.42257 -18.418933) (xy 42.430735 -18.472497) (xy 42.431462 -18.499582) (xy 42.431462 -18.502376)
			(xy 42.430926 -18.532872) (xy 42.421361 -18.593106) (xy 42.412412 -18.622264) (xy 42.408348 -18.634202)
			(xy 42.412666 -18.659094) (xy 42.479214 -18.745708) (xy 42.501566 -18.756122) (xy 42.514266 -18.75536)
			(xy 42.53484 -18.754852) (xy 42.535348 -18.754852) (xy 42.557192 -18.75536) (xy 42.56786 -18.755868)
			(xy 42.587164 -18.748756) (xy 42.648378 -18.691098) (xy 42.652106 -18.687488) (xy 42.65813 -18.67904)
			(xy 42.660316 -18.674334) (xy 42.66438 -18.664682) (xy 42.66438 -15.73403) (xy 42.664815 -15.723965)
			(xy 42.672545 -15.705377) (xy 42.679366 -15.697962) (xy 45.503846 -12.873482) (xy 45.511782 -12.864575)
			(xy 45.519185 -12.841927) (xy 45.51807 -12.830048) (xy 45.5041 -12.737338) (xy 45.49013 -12.717526)
			(xy 45.479462 -12.711938) (xy 45.453634 -12.69761) (xy 45.406348 -12.66222) (xy 45.365083 -12.619963)
			(xy 45.330825 -12.571851) (xy 45.304393 -12.519032) (xy 45.286419 -12.462771) (xy 45.277333 -12.404412)
			(xy 45.27677 -12.37488) (xy 45.277256 -12.347629) (xy 45.285012 -12.293681) (xy 45.300367 -12.241386)
			(xy 45.323009 -12.191809) (xy 45.352475 -12.145959) (xy 45.388166 -12.104768) (xy 45.429357 -12.069077)
			(xy 45.475207 -12.039611) (xy 45.524784 -12.016969) (xy 45.577079 -12.001614) (xy 45.631027 -11.993858)
			(xy 45.685529 -11.993858) (xy 45.739477 -12.001614) (xy 45.791772 -12.016969) (xy 45.841349 -12.039611)
			(xy 45.887199 -12.069077) (xy 45.92839 -12.104768) (xy 45.964081 -12.145959) (xy 45.993547 -12.191809)
			(xy 46.016189 -12.241386) (xy 46.031544 -12.293681) (xy 46.0393 -12.347629) (xy 46.039786 -12.37488)
			(xy 46.03915 -12.406254) (xy 46.02888 -12.468154) (xy 46.008613 -12.527538) (xy 45.99432 -12.555474)
			(xy 45.98797 -12.567412) (xy 45.988478 -12.593828) (xy 46.040294 -12.680442) (xy 46.043846 -12.685948)
			(xy 46.05323 -12.695086) (xy 46.058836 -12.698476) (xy 46.07052 -12.70508) (xy 49.242726 -12.70508)
			(xy 49.249244 -12.704849) (xy 49.261848 -12.701514) (xy 49.267618 -12.698476) (xy 49.273226 -12.695086)
			(xy 49.282617 -12.685955) (xy 49.28616 -12.680442) (xy 49.337976 -12.593828) (xy 49.338484 -12.567412)
			(xy 49.332134 -12.555474) (xy 49.317845 -12.527537) (xy 49.297586 -12.468152) (xy 49.287312 -12.406253)
			(xy 49.286668 -12.37488) (xy 49.287154 -12.347629) (xy 49.29491 -12.293681) (xy 49.310265 -12.241386)
			(xy 49.332907 -12.191809) (xy 49.362373 -12.145959) (xy 49.398064 -12.104768) (xy 49.439255 -12.069077)
			(xy 49.485105 -12.039611) (xy 49.534682 -12.016969) (xy 49.586977 -12.001614) (xy 49.640925 -11.993858)
			(xy 49.695427 -11.993858) (xy 49.749375 -12.001614) (xy 49.80167 -12.016969) (xy 49.851247 -12.039611)
			(xy 49.897097 -12.069077) (xy 49.938288 -12.104768) (xy 49.973979 -12.145959) (xy 50.003445 -12.191809)
			(xy 50.026087 -12.241386) (xy 50.041442 -12.293681) (xy 50.049198 -12.347629) (xy 50.049684 -12.37488)
			(xy 50.049048 -12.406254) (xy 50.038778 -12.468154) (xy 50.018511 -12.527538) (xy 50.004218 -12.555474)
			(xy 49.997868 -12.567412) (xy 49.998376 -12.593828) (xy 50.050192 -12.680442) (xy 50.053744 -12.685948)
			(xy 50.063128 -12.695086) (xy 50.068734 -12.698476) (xy 50.080418 -12.70508) (xy 51.042824 -12.70508)
			(xy 51.049342 -12.70485) (xy 51.061946 -12.701515) (xy 51.067716 -12.698476) (xy 51.073324 -12.695086)
			(xy 51.082716 -12.685955) (xy 51.086258 -12.680442) (xy 51.138074 -12.593828) (xy 51.138582 -12.567412)
			(xy 51.132232 -12.555474) (xy 51.117943 -12.527537) (xy 51.097684 -12.468152) (xy 51.08741 -12.406253)
			(xy 51.086766 -12.37488) (xy 51.087252 -12.347629) (xy 51.095008 -12.293681) (xy 51.110363 -12.241386)
			(xy 51.133005 -12.191809) (xy 51.162471 -12.145959) (xy 51.198162 -12.104768) (xy 51.239353 -12.069077)
			(xy 51.285203 -12.039611) (xy 51.33478 -12.016969) (xy 51.387075 -12.001614) (xy 51.441023 -11.993858)
			(xy 51.495525 -11.993858) (xy 51.549473 -12.001614) (xy 51.601768 -12.016969) (xy 51.651345 -12.039611)
			(xy 51.697195 -12.069077) (xy 51.738386 -12.104768) (xy 51.774077 -12.145959) (xy 51.803543 -12.191809)
			(xy 51.826185 -12.241386) (xy 51.84154 -12.293681) (xy 51.849296 -12.347629) (xy 51.849782 -12.37488)
			(xy 51.849146 -12.406254) (xy 51.838876 -12.468154) (xy 51.818609 -12.527538) (xy 51.804316 -12.555474)
			(xy 51.797966 -12.567412) (xy 51.798474 -12.593828) (xy 51.85029 -12.680442) (xy 51.853842 -12.685948)
			(xy 51.863225 -12.695086) (xy 51.868832 -12.698476) (xy 51.880516 -12.70508) (xy 52.842922 -12.70508)
			(xy 52.84944 -12.70485) (xy 52.862044 -12.701516) (xy 52.867814 -12.698476) (xy 52.873422 -12.695086)
			(xy 52.882814 -12.685955) (xy 52.886356 -12.680442) (xy 52.938172 -12.593828) (xy 52.93868 -12.567412)
			(xy 52.93233 -12.555474) (xy 52.918041 -12.527537) (xy 52.897782 -12.468152) (xy 52.887508 -12.406253)
			(xy 52.886864 -12.37488) (xy 52.88735 -12.347629) (xy 52.895106 -12.293681) (xy 52.910461 -12.241386)
			(xy 52.933103 -12.191809) (xy 52.962569 -12.145959) (xy 52.99826 -12.104768) (xy 53.039451 -12.069077)
			(xy 53.085301 -12.039611) (xy 53.134878 -12.016969) (xy 53.187173 -12.001614) (xy 53.241121 -11.993858)
			(xy 53.295623 -11.993858) (xy 53.349571 -12.001614) (xy 53.401866 -12.016969) (xy 53.451443 -12.039611)
			(xy 53.497293 -12.069077) (xy 53.538484 -12.104768) (xy 53.574175 -12.145959) (xy 53.603641 -12.191809)
			(xy 53.626283 -12.241386) (xy 53.641638 -12.293681) (xy 53.649394 -12.347629) (xy 53.64988 -12.37488)
			(xy 53.649244 -12.406254) (xy 53.638974 -12.468154) (xy 53.618707 -12.527538) (xy 53.604414 -12.555474)
			(xy 53.598064 -12.567412) (xy 53.598572 -12.593828) (xy 53.650388 -12.680442) (xy 53.65394 -12.685948)
			(xy 53.663323 -12.695087) (xy 53.66893 -12.698476) (xy 53.680614 -12.70508) (xy 54.642766 -12.70508)
			(xy 54.649282 -12.704845) (xy 54.661882 -12.701501) (xy 54.667658 -12.698476) (xy 54.673263 -12.695083)
			(xy 54.682648 -12.685948) (xy 54.6862 -12.680442) (xy 54.738016 -12.593828) (xy 54.738524 -12.567412)
			(xy 54.732174 -12.555474) (xy 54.717883 -12.527537) (xy 54.697622 -12.468152) (xy 54.687347 -12.406253)
			(xy 54.686708 -12.37488) (xy 54.687194 -12.347629) (xy 54.69495 -12.293681) (xy 54.710305 -12.241386)
			(xy 54.732947 -12.191809) (xy 54.762413 -12.145959) (xy 54.798104 -12.104768) (xy 54.839295 -12.069077)
			(xy 54.885145 -12.039611) (xy 54.934722 -12.016969) (xy 54.987017 -12.001614) (xy 55.040965 -11.993858)
			(xy 55.095467 -11.993858) (xy 55.149415 -12.001614) (xy 55.20171 -12.016969) (xy 55.251287 -12.039611)
			(xy 55.297137 -12.069077) (xy 55.338328 -12.104768) (xy 55.374019 -12.145959) (xy 55.403485 -12.191809)
			(xy 55.426127 -12.241386) (xy 55.441482 -12.293681) (xy 55.449238 -12.347629) (xy 55.449724 -12.37488)
			(xy 55.449089 -12.406254) (xy 55.438819 -12.468155) (xy 55.418554 -12.52754) (xy 55.404258 -12.555474)
			(xy 55.397908 -12.567412) (xy 55.398416 -12.593828) (xy 55.450232 -12.680442) (xy 55.453786 -12.685946)
			(xy 55.463173 -12.695077) (xy 55.468774 -12.698476) (xy 55.480458 -12.70508) (xy 56.442864 -12.70508)
			(xy 56.44938 -12.704845) (xy 56.46198 -12.701502) (xy 56.467756 -12.698476) (xy 56.473361 -12.695083)
			(xy 56.482746 -12.685948) (xy 56.486298 -12.680442) (xy 56.538114 -12.593828) (xy 56.538622 -12.567412)
			(xy 56.532272 -12.555474) (xy 56.517981 -12.527537) (xy 56.497721 -12.468152) (xy 56.487445 -12.406253)
			(xy 56.486806 -12.37488) (xy 56.487292 -12.347629) (xy 56.495048 -12.293681) (xy 56.510403 -12.241386)
			(xy 56.533045 -12.191809) (xy 56.562511 -12.145959) (xy 56.598202 -12.104768) (xy 56.639393 -12.069077)
			(xy 56.685243 -12.039611) (xy 56.73482 -12.016969) (xy 56.787115 -12.001614) (xy 56.841063 -11.993858)
			(xy 56.895565 -11.993858) (xy 56.949513 -12.001614) (xy 57.001808 -12.016969) (xy 57.051385 -12.039611)
			(xy 57.097235 -12.069077) (xy 57.138426 -12.104768) (xy 57.174117 -12.145959) (xy 57.203583 -12.191809)
			(xy 57.226225 -12.241386) (xy 57.24158 -12.293681) (xy 57.249336 -12.347629) (xy 57.249822 -12.37488)
			(xy 57.248552 -12.405106) (xy 57.24779 -12.416282) (xy 57.254902 -12.436348) (xy 57.284874 -12.46759)
			(xy 57.292509 -12.47486) (xy 57.31193 -12.483002) (xy 57.322466 -12.483338) (xy 57.323228 -12.483338)
			(xy 57.334658 -12.483084) (xy 58.198258 -12.483084) (xy 58.206386 -12.483338) (xy 58.206894 -12.483338)
			(xy 58.21299 -12.483592) (xy 58.223912 -12.483846) (xy 58.243978 -12.475718) (xy 58.28157 -12.436348)
			(xy 58.288682 -12.416282) (xy 58.28792 -12.40536) (xy 58.28665 -12.37488) (xy 58.287136 -12.347629)
			(xy 58.294892 -12.293681) (xy 58.310247 -12.241386) (xy 58.332889 -12.191809) (xy 58.362355 -12.145959)
			(xy 58.398046 -12.104768) (xy 58.439237 -12.069077) (xy 58.485087 -12.039611) (xy 58.534664 -12.016969)
			(xy 58.586959 -12.001614) (xy 58.640907 -11.993858) (xy 58.695409 -11.993858) (xy 58.749357 -12.001614)
			(xy 58.801652 -12.016969) (xy 58.851229 -12.039611) (xy 58.897079 -12.069077) (xy 58.93827 -12.104768)
			(xy 58.973961 -12.145959) (xy 59.003427 -12.191809) (xy 59.026069 -12.241386) (xy 59.041424 -12.293681)
			(xy 59.04918 -12.347629) (xy 59.049666 -12.37488) (xy 59.04903 -12.406253) (xy 59.03876 -12.468154)
			(xy 59.018492 -12.527537) (xy 59.0042 -12.555474) (xy 58.99785 -12.567412) (xy 58.998358 -12.593828)
			(xy 59.050174 -12.680442) (xy 59.05373 -12.685943) (xy 59.063121 -12.695068) (xy 59.068716 -12.698476)
			(xy 59.0804 -12.70508) (xy 62.222126 -12.70508) (xy 62.233236 -12.70452) (xy 62.253393 -12.695173)
			(xy 62.260988 -12.687046) (xy 62.31128 -12.62761) (xy 62.317919 -12.618839) (xy 62.323723 -12.597642)
			(xy 62.322456 -12.586716) (xy 62.322456 -12.586208) (xy 62.316526 -12.549219) (xy 62.310167 -12.474569)
			(xy 62.309756 -12.43711) (xy 62.31023 -12.396007) (xy 62.317814 -12.31415) (xy 62.332918 -12.233343)
			(xy 62.355414 -12.154274) (xy 62.385109 -12.077618) (xy 62.421751 -12.004029) (xy 62.465025 -11.934134)
			(xy 62.514564 -11.868531) (xy 62.569945 -11.807778) (xy 62.630695 -11.752394) (xy 62.696296 -11.702851)
			(xy 62.766189 -11.659573) (xy 62.839776 -11.622928) (xy 62.916431 -11.593229) (xy 62.995498 -11.570729)
			(xy 63.076305 -11.555621) (xy 63.158161 -11.548032) (xy 63.199264 -11.547602) (xy 63.24306 -11.548122)
			(xy 63.330229 -11.556727) (xy 63.416128 -11.573867) (xy 63.499923 -11.599376) (xy 63.580803 -11.633005)
			(xy 63.619634 -11.653266) (xy 63.6311 -11.658684) (xy 63.656428 -11.658684) (xy 63.667894 -11.653266)
			(xy 63.706738 -11.633035) (xy 63.787623 -11.599429) (xy 63.871416 -11.573929) (xy 63.957309 -11.556779)
			(xy 64.04447 -11.548146) (xy 64.088264 -11.547602) (xy 64.13206 -11.548122) (xy 64.219229 -11.556727)
			(xy 64.305128 -11.573867) (xy 64.388923 -11.599376) (xy 64.469803 -11.633005) (xy 64.508634 -11.653266)
			(xy 64.5201 -11.658684) (xy 64.545428 -11.658684) (xy 64.556894 -11.653266) (xy 64.595738 -11.633035)
			(xy 64.676623 -11.599429) (xy 64.760416 -11.573929) (xy 64.846309 -11.556779) (xy 64.93347 -11.548146)
			(xy 64.977264 -11.547602) (xy 65.02106 -11.548122) (xy 65.108229 -11.556727) (xy 65.194128 -11.573867)
			(xy 65.277923 -11.599376) (xy 65.358803 -11.633005) (xy 65.397634 -11.653266) (xy 65.4091 -11.658684)
			(xy 65.434428 -11.658684) (xy 65.445894 -11.653266) (xy 65.484738 -11.633035) (xy 65.565623 -11.599429)
			(xy 65.649416 -11.573929) (xy 65.735309 -11.556779) (xy 65.82247 -11.548146) (xy 65.866264 -11.547602)
			(xy 65.904554 -11.548011) (xy 65.980848 -11.554617) (xy 66.05629 -11.567766) (xy 66.130321 -11.58736)
			(xy 66.166492 -11.599926) (xy 66.17493 -11.602568) (xy 66.192598 -11.602568) (xy 66.201036 -11.599926)
			(xy 66.237214 -11.587382) (xy 66.311246 -11.567806) (xy 66.386686 -11.554658) (xy 66.462976 -11.548037)
			(xy 66.501264 -11.547602) (xy 66.544139 -11.54811) (xy 66.629491 -11.556357) (xy 66.713652 -11.572786)
			(xy 66.79584 -11.597245) (xy 66.875289 -11.629507) (xy 66.913506 -11.648948) (xy 66.922934 -11.653345)
			(xy 66.943655 -11.654921) (xy 66.953638 -11.651996) (xy 67.000299 -11.636605) (xy 67.096159 -11.615022)
			(xy 67.193815 -11.604144) (xy 67.242944 -11.603482) (xy 67.284045 -11.603959) (xy 67.365897 -11.611547)
			(xy 67.4467 -11.626655) (xy 67.525763 -11.649154) (xy 67.602414 -11.678852) (xy 67.675998 -11.715495)
			(xy 67.745887 -11.758771) (xy 67.811485 -11.808311) (xy 67.872232 -11.863692) (xy 67.927611 -11.924441)
			(xy 67.977148 -11.990041) (xy 68.020421 -12.059932) (xy 68.057062 -12.133517) (xy 68.086757 -12.210169)
			(xy 68.109253 -12.289234) (xy 68.124358 -12.370037) (xy 68.131943 -12.451889) (xy 68.132452 -12.49299)
			(xy 68.132267 -12.517809) (xy 68.129474 -12.567368) (xy 68.126864 -12.59205) (xy 68.126167 -12.602809)
			(xy 68.132744 -12.623323) (xy 68.139564 -12.631674) (xy 68.190364 -12.688316) (xy 68.19791 -12.695824)
			(xy 68.217328 -12.704487) (xy 68.227956 -12.70508) (xy 69.646038 -12.70508) (xy 69.66839 -12.692888)
			(xy 69.675502 -12.68222) (xy 69.72935 -12.60094) (xy 69.731636 -12.57554) (xy 69.726556 -12.563856)
			(xy 69.716905 -12.540109) (xy 69.703329 -12.49068) (xy 69.696483 -12.43988) (xy 69.696076 -12.41425)
			(xy 69.696535 -12.386994) (xy 69.704287 -12.333037) (xy 69.719638 -12.280732) (xy 69.742278 -12.231145)
			(xy 69.771744 -12.185284) (xy 69.807437 -12.144084) (xy 69.848631 -12.108384) (xy 69.894487 -12.078909)
			(xy 69.94407 -12.056261) (xy 69.996373 -12.040901) (xy 70.050328 -12.03314) (xy 70.077584 -12.032742)
			(xy 70.106261 -12.033257) (xy 70.162969 -12.041836) (xy 70.217755 -12.058804) (xy 70.269385 -12.083779)
			(xy 70.316697 -12.116198) (xy 70.358626 -12.155332) (xy 70.376796 -12.177522) (xy 70.384416 -12.187174)
			(xy 70.406768 -12.197334) (xy 70.51421 -12.192) (xy 70.535292 -12.179808) (xy 70.541896 -12.16914)
			(xy 70.557009 -12.146402) (xy 70.592705 -12.105089) (xy 70.633927 -12.069289) (xy 70.679832 -12.039732)
			(xy 70.729483 -12.017024) (xy 70.781865 -12.001627) (xy 70.835907 -11.993857) (xy 70.863206 -11.993372)
			(xy 70.890457 -11.993858) (xy 70.944406 -12.001615) (xy 70.996701 -12.016971) (xy 71.046279 -12.039612)
			(xy 71.09213 -12.069078) (xy 71.133321 -12.104769) (xy 71.169014 -12.145959) (xy 71.198481 -12.191809)
			(xy 71.221124 -12.241386) (xy 71.236482 -12.293681) (xy 71.244241 -12.347629) (xy 71.244714 -12.37488)
			(xy 71.243444 -12.405106) (xy 71.242682 -12.416282) (xy 71.249794 -12.436348) (xy 71.279766 -12.46759)
			(xy 71.2874 -12.474861) (xy 71.306821 -12.483006) (xy 71.317358 -12.483338) (xy 71.31812 -12.483338)
			(xy 71.329804 -12.483084) (xy 72.193404 -12.483084) (xy 72.201532 -12.483338) (xy 72.20204 -12.483338)
			(xy 72.208136 -12.483592) (xy 72.219058 -12.483846) (xy 72.239124 -12.475718) (xy 72.276716 -12.436348)
			(xy 72.283828 -12.416282) (xy 72.283066 -12.40536) (xy 72.281796 -12.37488) (xy 72.282282 -12.347629)
			(xy 72.290038 -12.293681) (xy 72.305393 -12.241386) (xy 72.328035 -12.191809) (xy 72.357501 -12.145959)
			(xy 72.393192 -12.104768) (xy 72.434383 -12.069077) (xy 72.480233 -12.039611) (xy 72.52981 -12.016969)
			(xy 72.582105 -12.001614) (xy 72.636053 -11.993858) (xy 72.690555 -11.993858) (xy 72.744503 -12.001614)
			(xy 72.796798 -12.016969) (xy 72.846375 -12.039611) (xy 72.892225 -12.069077) (xy 72.933416 -12.104768)
			(xy 72.969107 -12.145959) (xy 72.998573 -12.191809) (xy 73.021215 -12.241386) (xy 73.03657 -12.293681)
			(xy 73.044326 -12.347629) (xy 73.044812 -12.37488) (xy 73.044176 -12.406254) (xy 73.033907 -12.468155)
			(xy 73.013641 -12.527539) (xy 72.999346 -12.555474) (xy 72.992996 -12.567412) (xy 72.993504 -12.593828)
			(xy 73.04532 -12.680442) (xy 73.048873 -12.685946) (xy 73.05826 -12.69508) (xy 73.063862 -12.698476)
			(xy 73.069627 -12.701529) (xy 73.082233 -12.704869) (xy 73.088754 -12.70508) (xy 74.083672 -12.70508)
			(xy 74.10831 -12.689078) (xy 74.11466 -12.675362) (xy 74.126383 -12.650721) (xy 74.155828 -12.604781)
			(xy 74.191519 -12.563505) (xy 74.232727 -12.527736) (xy 74.27861 -12.498203) (xy 74.328234 -12.47551)
			(xy 74.380585 -12.460118) (xy 74.434595 -12.452343) (xy 74.489161 -12.452343) (xy 74.543171 -12.460118)
			(xy 74.595522 -12.47551) (xy 74.645146 -12.498203) (xy 74.691029 -12.527736) (xy 74.732237 -12.563505)
			(xy 74.767928 -12.604781) (xy 74.797373 -12.650721) (xy 74.809096 -12.675362) (xy 74.815446 -12.689078)
			(xy 74.840084 -12.70508) (xy 75.350878 -12.70508) (xy 75.360941 -12.704642) (xy 75.379523 -12.696906)
			(xy 75.386946 -12.690094) (xy 76.276454 -11.800586) (xy 76.283303 -11.793189) (xy 76.29104 -11.77459)
			(xy 76.29144 -11.764518) (xy 76.29144 -8.398002) (xy 76.291016 -8.387933) (xy 76.283295 -8.369334)
			(xy 76.276454 -8.361934) (xy 75.554586 -7.640066) (xy 75.547474 -7.6327) (xy 75.528678 -7.62508)
			(xy 69.981064 -7.62508) (xy 69.96811 -7.626858) (xy 69.946267 -7.631666) (xy 69.901829 -7.636756)
			(xy 69.879464 -7.637018) (xy 69.856965 -7.636717) (xy 69.812273 -7.631492) (xy 69.79031 -7.626604)
			(xy 69.784468 -7.62508) (xy 43.589194 -7.62508) (xy 43.579124 -7.625504) (xy 43.560519 -7.633217)
			(xy 43.553126 -7.640066) (xy 42.398442 -8.79475) (xy 66.490086 -8.79475) (xy 66.494157 -8.739128)
			(xy 66.506283 -8.684691) (xy 66.526206 -8.6326) (xy 66.553502 -8.583965) (xy 66.587588 -8.539822)
			(xy 66.627737 -8.501113) (xy 66.673095 -8.468662) (xy 66.722695 -8.443161) (xy 66.775479 -8.425154)
			(xy 66.830322 -8.415024) (xy 66.886056 -8.412987) (xy 66.941493 -8.419087) (xy 66.99545 -8.433193)
			(xy 67.046779 -8.455005) (xy 67.094385 -8.484059) (xy 67.137253 -8.519734) (xy 67.17447 -8.561271)
			(xy 67.205243 -8.607784) (xy 67.228915 -8.658281) (xy 67.244983 -8.711688) (xy 67.253103 -8.766864)
			(xy 67.253612 -8.79475) (xy 67.253103 -8.822636) (xy 67.244983 -8.877812) (xy 67.228915 -8.931219)
			(xy 67.205243 -8.981716) (xy 67.17447 -9.028229) (xy 67.137253 -9.069766) (xy 67.094385 -9.105441)
			(xy 67.046779 -9.134495) (xy 66.99545 -9.156307) (xy 66.941493 -9.170413) (xy 66.886056 -9.176513)
			(xy 66.830322 -9.174476) (xy 66.775479 -9.164346) (xy 66.722695 -9.146339) (xy 66.673095 -9.120838)
			(xy 66.627737 -9.088387) (xy 66.587588 -9.049678) (xy 66.553502 -9.005535) (xy 66.526206 -8.9569)
			(xy 66.506283 -8.904809) (xy 66.494157 -8.850372) (xy 66.490086 -8.79475) (xy 42.398442 -8.79475)
			(xy 42.247058 -8.946134) (xy 42.238676 -8.954516) (xy 42.231056 -8.976106) (xy 42.240962 -9.066276)
			(xy 42.242679 -9.07759) (xy 42.254719 -9.097024) (xy 42.264076 -9.103614) (xy 42.286813 -9.118728)
			(xy 42.328122 -9.154425) (xy 42.363919 -9.195648) (xy 42.393472 -9.241554) (xy 42.416177 -9.291204)
			(xy 42.431571 -9.343585) (xy 42.439338 -9.397626) (xy 42.439844 -9.424924) (xy 42.439336 -9.452784)
			(xy 42.431232 -9.507913) (xy 42.415199 -9.561277) (xy 42.391578 -9.611744) (xy 42.360872 -9.65824)
			(xy 42.323732 -9.699779) (xy 42.302684 -9.71804) (xy 42.293794 -9.725406) (xy 42.284396 -9.745218)
			(xy 42.283888 -9.845802) (xy 42.293286 -9.866376) (xy 42.301922 -9.873742) (xy 42.322731 -9.891951)
			(xy 42.359391 -9.933344) (xy 42.389689 -9.979597) (xy 42.412992 -10.02974) (xy 42.428809 -10.082722)
			(xy 42.436811 -10.137434) (xy 42.437304 -10.16508) (xy 43.474132 -10.16508) (xy 43.474615 -10.137204)
			(xy 43.482725 -10.082045) (xy 43.498783 -10.028655) (xy 43.522448 -9.978175) (xy 43.553214 -9.93168)
			(xy 43.590425 -9.890163) (xy 43.611546 -9.871964) (xy 43.620182 -9.864598) (xy 43.62958 -9.844532)
			(xy 43.630088 -9.743694) (xy 43.62069 -9.723628) (xy 43.612054 -9.716262) (xy 43.591211 -9.698089)
			(xy 43.554543 -9.656695) (xy 43.524243 -9.610437) (xy 43.500946 -9.560285) (xy 43.485141 -9.507293)
			(xy 43.47716 -9.452573) (xy 43.476672 -9.424924) (xy 43.477158 -9.397673) (xy 43.484914 -9.343725)
			(xy 43.500269 -9.29143) (xy 43.522911 -9.241853) (xy 43.552377 -9.196003) (xy 43.588068 -9.154812)
			(xy 43.629259 -9.119121) (xy 43.675109 -9.089655) (xy 43.724686 -9.067013) (xy 43.776981 -9.051658)
			(xy 43.830929 -9.043902) (xy 43.885431 -9.043902) (xy 43.939379 -9.051658) (xy 43.991674 -9.067013)
			(xy 44.041251 -9.089655) (xy 44.087101 -9.119121) (xy 44.128292 -9.154812) (xy 44.163983 -9.196003)
			(xy 44.193449 -9.241853) (xy 44.216091 -9.29143) (xy 44.231446 -9.343725) (xy 44.239202 -9.397673)
			(xy 44.239688 -9.424924) (xy 44.239201 -9.4528) (xy 44.231091 -9.507959) (xy 44.215032 -9.561347)
			(xy 44.191368 -9.611828) (xy 44.160604 -9.658323) (xy 44.123394 -9.69984) (xy 44.102274 -9.71804)
			(xy 44.093638 -9.725406) (xy 44.08424 -9.745472) (xy 44.083732 -9.84631) (xy 44.09313 -9.866376)
			(xy 44.101766 -9.873742) (xy 44.122595 -9.891931) (xy 44.159267 -9.933319) (xy 44.189571 -9.979574)
			(xy 44.212872 -10.029722) (xy 44.228679 -10.082713) (xy 44.23666 -10.137431) (xy 44.237148 -10.16508)
			(xy 45.27423 -10.16508) (xy 45.274713 -10.137204) (xy 45.282823 -10.082045) (xy 45.298882 -10.028656)
			(xy 45.322547 -9.978175) (xy 45.353313 -9.93168) (xy 45.390523 -9.890163) (xy 45.411644 -9.871964)
			(xy 45.42028 -9.864598) (xy 45.429678 -9.844532) (xy 45.430186 -9.743694) (xy 45.420788 -9.723628)
			(xy 45.412152 -9.716262) (xy 45.391309 -9.698089) (xy 45.354641 -9.656696) (xy 45.324341 -9.610437)
			(xy 45.301043 -9.560285) (xy 45.285239 -9.507293) (xy 45.277258 -9.452573) (xy 45.27677 -9.424924)
			(xy 45.277256 -9.397673) (xy 45.285012 -9.343725) (xy 45.300367 -9.29143) (xy 45.323009 -9.241853)
			(xy 45.352475 -9.196003) (xy 45.388166 -9.154812) (xy 45.429357 -9.119121) (xy 45.475207 -9.089655)
			(xy 45.524784 -9.067013) (xy 45.577079 -9.051658) (xy 45.631027 -9.043902) (xy 45.685529 -9.043902)
			(xy 45.739477 -9.051658) (xy 45.791772 -9.067013) (xy 45.841349 -9.089655) (xy 45.887199 -9.119121)
			(xy 45.92839 -9.154812) (xy 45.964081 -9.196003) (xy 45.993547 -9.241853) (xy 46.016189 -9.29143)
			(xy 46.031544 -9.343725) (xy 46.0393 -9.397673) (xy 46.039786 -9.424924) (xy 46.0393 -9.4528) (xy 46.031189 -9.507959)
			(xy 46.015131 -9.561348) (xy 45.991467 -9.611828) (xy 45.960702 -9.658323) (xy 45.923492 -9.69984)
			(xy 45.902372 -9.71804) (xy 45.893736 -9.725406) (xy 45.884338 -9.745472) (xy 45.88383 -9.84631)
			(xy 45.893228 -9.866376) (xy 45.901864 -9.873742) (xy 45.922692 -9.891931) (xy 45.959365 -9.93332)
			(xy 45.989669 -9.979574) (xy 46.01297 -10.029723) (xy 46.028777 -10.082713) (xy 46.036758 -10.137431)
			(xy 46.037246 -10.16508) (xy 49.284128 -10.16508) (xy 49.284612 -10.137204) (xy 49.292722 -10.082045)
			(xy 49.308781 -10.028656) (xy 49.332445 -9.978175) (xy 49.363211 -9.931681) (xy 49.400421 -9.890164)
			(xy 49.421542 -9.871964) (xy 49.430178 -9.864598) (xy 49.439576 -9.844532) (xy 49.440084 -9.743694)
			(xy 49.430686 -9.723628) (xy 49.42205 -9.716262) (xy 49.401206 -9.69809) (xy 49.364539 -9.656696)
			(xy 49.334239 -9.610437) (xy 49.310941 -9.560286) (xy 49.295137 -9.507293) (xy 49.287156 -9.452574)
			(xy 49.286668 -9.424924) (xy 49.287154 -9.397673) (xy 49.29491 -9.343725) (xy 49.310265 -9.29143)
			(xy 49.332907 -9.241853) (xy 49.362373 -9.196003) (xy 49.398064 -9.154812) (xy 49.439255 -9.119121)
			(xy 49.485105 -9.089655) (xy 49.534682 -9.067013) (xy 49.586977 -9.051658) (xy 49.640925 -9.043902)
			(xy 49.695427 -9.043902) (xy 49.749375 -9.051658) (xy 49.80167 -9.067013) (xy 49.851247 -9.089655)
			(xy 49.897097 -9.119121) (xy 49.938288 -9.154812) (xy 49.973979 -9.196003) (xy 50.003445 -9.241853)
			(xy 50.026087 -9.29143) (xy 50.041442 -9.343725) (xy 50.049198 -9.397673) (xy 50.049684 -9.424924)
			(xy 50.049198 -9.4528) (xy 50.041088 -9.507959) (xy 50.02503 -9.561348) (xy 50.001365 -9.611828)
			(xy 49.9706 -9.658323) (xy 49.93339 -9.69984) (xy 49.91227 -9.71804) (xy 49.903634 -9.725406) (xy 49.894236 -9.745472)
			(xy 49.893728 -9.84631) (xy 49.903126 -9.866376) (xy 49.911762 -9.873742) (xy 49.93259 -9.891932)
			(xy 49.969262 -9.93332) (xy 49.999567 -9.979574) (xy 50.022868 -10.029723) (xy 50.038675 -10.082713)
			(xy 50.046656 -10.137431) (xy 50.047144 -10.16508) (xy 51.084226 -10.16508) (xy 51.084711 -10.137204)
			(xy 51.092821 -10.082045) (xy 51.108879 -10.028656) (xy 51.132544 -9.978175) (xy 51.163309 -9.931681)
			(xy 51.200519 -9.890164) (xy 51.22164 -9.871964) (xy 51.230276 -9.864598) (xy 51.239674 -9.844532)
			(xy 51.240182 -9.743694) (xy 51.230784 -9.723628) (xy 51.222148 -9.716262) (xy 51.201304 -9.69809)
			(xy 51.164637 -9.656696) (xy 51.134336 -9.610438) (xy 51.111039 -9.560286) (xy 51.095235 -9.507293)
			(xy 51.087254 -9.452574) (xy 51.086766 -9.424924) (xy 51.087252 -9.397673) (xy 51.095008 -9.343725)
			(xy 51.110363 -9.29143) (xy 51.133005 -9.241853) (xy 51.162471 -9.196003) (xy 51.198162 -9.154812)
			(xy 51.239353 -9.119121) (xy 51.285203 -9.089655) (xy 51.33478 -9.067013) (xy 51.387075 -9.051658)
			(xy 51.441023 -9.043902) (xy 51.495525 -9.043902) (xy 51.549473 -9.051658) (xy 51.601768 -9.067013)
			(xy 51.651345 -9.089655) (xy 51.697195 -9.119121) (xy 51.738386 -9.154812) (xy 51.774077 -9.196003)
			(xy 51.803543 -9.241853) (xy 51.826185 -9.29143) (xy 51.84154 -9.343725) (xy 51.849296 -9.397673)
			(xy 51.849782 -9.424924) (xy 51.849297 -9.4528) (xy 51.841187 -9.507959) (xy 51.825128 -9.561348)
			(xy 51.801464 -9.611828) (xy 51.770698 -9.658323) (xy 51.733488 -9.69984) (xy 51.712368 -9.71804)
			(xy 51.703732 -9.725406) (xy 51.694334 -9.745472) (xy 51.693826 -9.84631) (xy 51.703224 -9.866376)
			(xy 51.71186 -9.873742) (xy 51.732688 -9.891932) (xy 51.76936 -9.93332) (xy 51.799665 -9.979574)
			(xy 51.822965 -10.029723) (xy 51.838773 -10.082713) (xy 51.846754 -10.137431) (xy 51.847242 -10.16508)
			(xy 52.884324 -10.16508) (xy 52.88481 -10.137204) (xy 52.892919 -10.082045) (xy 52.908978 -10.028656)
			(xy 52.932642 -9.978176) (xy 52.963407 -9.931681) (xy 53.000618 -9.890164) (xy 53.021738 -9.871964)
			(xy 53.030374 -9.864598) (xy 53.039772 -9.844532) (xy 53.04028 -9.743694) (xy 53.030882 -9.723628)
			(xy 53.022246 -9.716262) (xy 53.001401 -9.698091) (xy 52.964734 -9.656696) (xy 52.934434 -9.610438)
			(xy 52.911137 -9.560286) (xy 52.895332 -9.507294) (xy 52.887352 -9.452574) (xy 52.886864 -9.424924)
			(xy 52.88735 -9.397673) (xy 52.895106 -9.343725) (xy 52.910461 -9.29143) (xy 52.933103 -9.241853)
			(xy 52.962569 -9.196003) (xy 52.99826 -9.154812) (xy 53.039451 -9.119121) (xy 53.085301 -9.089655)
			(xy 53.134878 -9.067013) (xy 53.187173 -9.051658) (xy 53.241121 -9.043902) (xy 53.295623 -9.043902)
			(xy 53.349571 -9.051658) (xy 53.401866 -9.067013) (xy 53.451443 -9.089655) (xy 53.497293 -9.119121)
			(xy 53.538484 -9.154812) (xy 53.574175 -9.196003) (xy 53.603641 -9.241853) (xy 53.626283 -9.29143)
			(xy 53.641638 -9.343725) (xy 53.649394 -9.397673) (xy 53.64988 -9.424924) (xy 53.649396 -9.4528)
			(xy 53.641285 -9.507959) (xy 53.625227 -9.561348) (xy 53.601562 -9.611828) (xy 53.570797 -9.658323)
			(xy 53.533587 -9.69984) (xy 53.512466 -9.71804) (xy 53.50383 -9.725406) (xy 53.494432 -9.745472)
			(xy 53.493924 -9.84631) (xy 53.503322 -9.866376) (xy 53.511958 -9.873742) (xy 53.532805 -9.89191)
			(xy 53.569472 -9.933305) (xy 53.599772 -9.979565) (xy 53.623068 -10.029717) (xy 53.638872 -10.08271)
			(xy 53.646852 -10.13743) (xy 53.64734 -10.16508) (xy 54.684168 -10.16508) (xy 54.684638 -10.137203)
			(xy 54.692749 -10.082043) (xy 54.708809 -10.028653) (xy 54.732476 -9.978172) (xy 54.763245 -9.931678)
			(xy 54.800459 -9.890162) (xy 54.821582 -9.871964) (xy 54.830218 -9.864598) (xy 54.839616 -9.844532)
			(xy 54.840124 -9.743694) (xy 54.830726 -9.723628) (xy 54.82209 -9.716262) (xy 54.801254 -9.698081)
			(xy 54.764585 -9.65669) (xy 54.734282 -9.610433) (xy 54.710983 -9.560283) (xy 54.695177 -9.507292)
			(xy 54.687196 -9.452573) (xy 54.686708 -9.424924) (xy 54.687194 -9.397673) (xy 54.69495 -9.343725)
			(xy 54.710305 -9.29143) (xy 54.732947 -9.241853) (xy 54.762413 -9.196003) (xy 54.798104 -9.154812)
			(xy 54.839295 -9.119121) (xy 54.885145 -9.089655) (xy 54.934722 -9.067013) (xy 54.987017 -9.051658)
			(xy 55.040965 -9.043902) (xy 55.095467 -9.043902) (xy 55.149415 -9.051658) (xy 55.20171 -9.067013)
			(xy 55.251287 -9.089655) (xy 55.297137 -9.119121) (xy 55.338328 -9.154812) (xy 55.374019 -9.196003)
			(xy 55.403485 -9.241853) (xy 55.426127 -9.29143) (xy 55.441482 -9.343725) (xy 55.449238 -9.397673)
			(xy 55.449724 -9.424924) (xy 55.44926 -9.452801) (xy 55.441148 -9.507962) (xy 55.425087 -9.561352)
			(xy 55.401419 -9.611833) (xy 55.370649 -9.658327) (xy 55.333433 -9.699842) (xy 55.31231 -9.71804)
			(xy 55.303674 -9.725406) (xy 55.294276 -9.745472) (xy 55.293768 -9.84631) (xy 55.303166 -9.866376)
			(xy 55.311802 -9.873742) (xy 55.332638 -9.891923) (xy 55.369308 -9.933314) (xy 55.399611 -9.97957)
			(xy 55.42291 -10.02972) (xy 55.438715 -10.082712) (xy 55.446696 -10.137431) (xy 55.447184 -10.16508)
			(xy 56.484266 -10.16508) (xy 56.484737 -10.137203) (xy 56.492847 -10.082043) (xy 56.508908 -10.028653)
			(xy 56.532575 -9.978172) (xy 56.563343 -9.931678) (xy 56.600557 -9.890162) (xy 56.62168 -9.871964)
			(xy 56.630316 -9.864598) (xy 56.639714 -9.844532) (xy 56.640222 -9.743694) (xy 56.630824 -9.723628)
			(xy 56.622188 -9.716262) (xy 56.601352 -9.698081) (xy 56.564682 -9.65669) (xy 56.53438 -9.610434)
			(xy 56.511081 -9.560283) (xy 56.495275 -9.507292) (xy 56.487294 -9.452573) (xy 56.486806 -9.424924)
			(xy 56.487292 -9.397673) (xy 56.495048 -9.343725) (xy 56.510403 -9.29143) (xy 56.533045 -9.241853)
			(xy 56.562511 -9.196003) (xy 56.598202 -9.154812) (xy 56.639393 -9.119121) (xy 56.685243 -9.089655)
			(xy 56.73482 -9.067013) (xy 56.787115 -9.051658) (xy 56.841063 -9.043902) (xy 56.895565 -9.043902)
			(xy 56.949513 -9.051658) (xy 57.001808 -9.067013) (xy 57.051385 -9.089655) (xy 57.097235 -9.119121)
			(xy 57.138426 -9.154812) (xy 57.174117 -9.196003) (xy 57.203583 -9.241853) (xy 57.226225 -9.29143)
			(xy 57.24158 -9.343725) (xy 57.249336 -9.397673) (xy 57.249822 -9.424924) (xy 57.249358 -9.452801)
			(xy 57.241247 -9.507962) (xy 57.225185 -9.561352) (xy 57.201517 -9.611833) (xy 57.170747 -9.658327)
			(xy 57.133531 -9.699842) (xy 57.112408 -9.71804) (xy 57.103772 -9.725406) (xy 57.094374 -9.745472)
			(xy 57.093866 -9.84631) (xy 57.103264 -9.866376) (xy 57.1119 -9.873742) (xy 57.132736 -9.891923)
			(xy 57.169406 -9.933314) (xy 57.199708 -9.97957) (xy 57.223007 -10.02972) (xy 57.238813 -10.082712)
			(xy 57.246794 -10.137431) (xy 57.247282 -10.16508) (xy 58.28411 -10.16508) (xy 58.284565 -10.137202)
			(xy 58.292677 -10.082041) (xy 58.308739 -10.02865) (xy 58.332409 -9.978169) (xy 58.363181 -9.931675)
			(xy 58.400399 -9.890161) (xy 58.421524 -9.871964) (xy 58.43016 -9.864598) (xy 58.439558 -9.844532)
			(xy 58.440066 -9.743694) (xy 58.430668 -9.723628) (xy 58.422032 -9.716262) (xy 58.401205 -9.698071)
			(xy 58.364533 -9.656683) (xy 58.334228 -9.610429) (xy 58.310927 -9.560281) (xy 58.29512 -9.507291)
			(xy 58.287138 -9.452573) (xy 58.28665 -9.424924) (xy 58.287136 -9.397673) (xy 58.294892 -9.343725)
			(xy 58.310247 -9.29143) (xy 58.332889 -9.241853) (xy 58.362355 -9.196003) (xy 58.398046 -9.154812)
			(xy 58.439237 -9.119121) (xy 58.485087 -9.089655) (xy 58.534664 -9.067013) (xy 58.586959 -9.051658)
			(xy 58.640907 -9.043902) (xy 58.695409 -9.043902) (xy 58.749357 -9.051658) (xy 58.801652 -9.067013)
			(xy 58.851229 -9.089655) (xy 58.897079 -9.119121) (xy 58.93827 -9.154812) (xy 58.973961 -9.196003)
			(xy 59.003427 -9.241853) (xy 59.026069 -9.29143) (xy 59.041424 -9.343725) (xy 59.04918 -9.397673)
			(xy 59.049666 -9.424924) (xy 59.049187 -9.4528) (xy 59.041076 -9.50796) (xy 59.025017 -9.561349)
			(xy 59.001351 -9.611829) (xy 58.970585 -9.658324) (xy 58.933373 -9.699841) (xy 58.912252 -9.71804)
			(xy 58.903616 -9.725406) (xy 58.894218 -9.745472) (xy 58.89371 -9.84631) (xy 58.903108 -9.866376)
			(xy 58.911744 -9.873742) (xy 58.932588 -9.891913) (xy 58.969256 -9.933307) (xy 58.999556 -9.979566)
			(xy 59.022854 -10.029718) (xy 59.038658 -10.08271) (xy 59.046638 -10.13743) (xy 59.047126 -10.16508)
			(xy 59.04664 -10.192331) (xy 59.045263 -10.20191) (xy 68.603366 -10.20191) (xy 68.607437 -10.146288)
			(xy 68.619563 -10.091851) (xy 68.639486 -10.03976) (xy 68.666782 -9.991125) (xy 68.700868 -9.946982)
			(xy 68.741017 -9.908273) (xy 68.786375 -9.875822) (xy 68.835975 -9.850321) (xy 68.888759 -9.832314)
			(xy 68.943602 -9.822184) (xy 68.999336 -9.820147) (xy 69.054773 -9.826247) (xy 69.10873 -9.840353)
			(xy 69.160059 -9.862165) (xy 69.207665 -9.891219) (xy 69.250533 -9.926894) (xy 69.28775 -9.968431)
			(xy 69.318523 -10.014944) (xy 69.342195 -10.065441) (xy 69.358263 -10.118848) (xy 69.365067 -10.16508)
			(xy 72.443846 -10.16508) (xy 72.447917 -10.109458) (xy 72.460043 -10.055021) (xy 72.479966 -10.00293)
			(xy 72.507262 -9.954295) (xy 72.541348 -9.910152) (xy 72.581497 -9.871443) (xy 72.626855 -9.838992)
			(xy 72.676455 -9.813491) (xy 72.729239 -9.795484) (xy 72.784082 -9.785354) (xy 72.839816 -9.783317)
			(xy 72.895253 -9.789417) (xy 72.94921 -9.803523) (xy 73.000539 -9.825335) (xy 73.048145 -9.854389)
			(xy 73.091013 -9.890064) (xy 73.12823 -9.931601) (xy 73.159003 -9.978114) (xy 73.182675 -10.028611)
			(xy 73.198743 -10.082018) (xy 73.206863 -10.137194) (xy 73.207372 -10.16508) (xy 73.206863 -10.192966)
			(xy 73.198743 -10.248142) (xy 73.182675 -10.301549) (xy 73.159003 -10.352046) (xy 73.12823 -10.398559)
			(xy 73.091013 -10.440096) (xy 73.048145 -10.475771) (xy 73.000539 -10.504825) (xy 72.94921 -10.526637)
			(xy 72.895253 -10.540743) (xy 72.839816 -10.546843) (xy 72.784082 -10.544806) (xy 72.729239 -10.534676)
			(xy 72.676455 -10.516669) (xy 72.626855 -10.491168) (xy 72.581497 -10.458717) (xy 72.541348 -10.420008)
			(xy 72.507262 -10.375865) (xy 72.479966 -10.32723) (xy 72.460043 -10.275139) (xy 72.447917 -10.220702)
			(xy 72.443846 -10.16508) (xy 69.365067 -10.16508) (xy 69.366383 -10.174024) (xy 69.366892 -10.20191)
			(xy 69.366383 -10.229796) (xy 69.358263 -10.284972) (xy 69.342195 -10.338379) (xy 69.318523 -10.388876)
			(xy 69.28775 -10.435389) (xy 69.250533 -10.476926) (xy 69.207665 -10.512601) (xy 69.160059 -10.541655)
			(xy 69.10873 -10.563467) (xy 69.054773 -10.577573) (xy 68.999336 -10.583673) (xy 68.943602 -10.581636)
			(xy 68.888759 -10.571506) (xy 68.835975 -10.553499) (xy 68.786375 -10.527998) (xy 68.741017 -10.495547)
			(xy 68.700868 -10.456838) (xy 68.666782 -10.412695) (xy 68.639486 -10.36406) (xy 68.619563 -10.311969)
			(xy 68.607437 -10.257532) (xy 68.603366 -10.20191) (xy 59.045263 -10.20191) (xy 59.038884 -10.246279)
			(xy 59.023529 -10.298574) (xy 59.000887 -10.348151) (xy 58.971421 -10.394001) (xy 58.93573 -10.435192)
			(xy 58.894539 -10.470883) (xy 58.848689 -10.500349) (xy 58.799112 -10.522991) (xy 58.746817 -10.538346)
			(xy 58.692869 -10.546102) (xy 58.638367 -10.546102) (xy 58.584419 -10.538346) (xy 58.532124 -10.522991)
			(xy 58.482547 -10.500349) (xy 58.436697 -10.470883) (xy 58.395506 -10.435192) (xy 58.359815 -10.394001)
			(xy 58.330349 -10.348151) (xy 58.307707 -10.298574) (xy 58.292352 -10.246279) (xy 58.284596 -10.192331)
			(xy 58.28411 -10.16508) (xy 57.247282 -10.16508) (xy 57.246796 -10.192331) (xy 57.23904 -10.246279)
			(xy 57.223685 -10.298574) (xy 57.201043 -10.348151) (xy 57.171577 -10.394001) (xy 57.135886 -10.435192)
			(xy 57.094695 -10.470883) (xy 57.048845 -10.500349) (xy 56.999268 -10.522991) (xy 56.946973 -10.538346)
			(xy 56.893025 -10.546102) (xy 56.838523 -10.546102) (xy 56.784575 -10.538346) (xy 56.73228 -10.522991)
			(xy 56.682703 -10.500349) (xy 56.636853 -10.470883) (xy 56.595662 -10.435192) (xy 56.559971 -10.394001)
			(xy 56.530505 -10.348151) (xy 56.507863 -10.298574) (xy 56.492508 -10.246279) (xy 56.484752 -10.192331)
			(xy 56.484266 -10.16508) (xy 55.447184 -10.16508) (xy 55.446698 -10.192331) (xy 55.438942 -10.246279)
			(xy 55.423587 -10.298574) (xy 55.400945 -10.348151) (xy 55.371479 -10.394001) (xy 55.335788 -10.435192)
			(xy 55.294597 -10.470883) (xy 55.248747 -10.500349) (xy 55.19917 -10.522991) (xy 55.146875 -10.538346)
			(xy 55.092927 -10.546102) (xy 55.038425 -10.546102) (xy 54.984477 -10.538346) (xy 54.932182 -10.522991)
			(xy 54.882605 -10.500349) (xy 54.836755 -10.470883) (xy 54.795564 -10.435192) (xy 54.759873 -10.394001)
			(xy 54.730407 -10.348151) (xy 54.707765 -10.298574) (xy 54.69241 -10.246279) (xy 54.684654 -10.192331)
			(xy 54.684168 -10.16508) (xy 53.64734 -10.16508) (xy 53.646854 -10.192331) (xy 53.639098 -10.246279)
			(xy 53.623743 -10.298574) (xy 53.601101 -10.348151) (xy 53.571635 -10.394001) (xy 53.535944 -10.435192)
			(xy 53.494753 -10.470883) (xy 53.448903 -10.500349) (xy 53.399326 -10.522991) (xy 53.347031 -10.538346)
			(xy 53.293083 -10.546102) (xy 53.238581 -10.546102) (xy 53.184633 -10.538346) (xy 53.132338 -10.522991)
			(xy 53.082761 -10.500349) (xy 53.036911 -10.470883) (xy 52.99572 -10.435192) (xy 52.960029 -10.394001)
			(xy 52.930563 -10.348151) (xy 52.907921 -10.298574) (xy 52.892566 -10.246279) (xy 52.88481 -10.192331)
			(xy 52.884324 -10.16508) (xy 51.847242 -10.16508) (xy 51.846756 -10.192331) (xy 51.839 -10.246279)
			(xy 51.823645 -10.298574) (xy 51.801003 -10.348151) (xy 51.771537 -10.394001) (xy 51.735846 -10.435192)
			(xy 51.694655 -10.470883) (xy 51.648805 -10.500349) (xy 51.599228 -10.522991) (xy 51.546933 -10.538346)
			(xy 51.492985 -10.546102) (xy 51.438483 -10.546102) (xy 51.384535 -10.538346) (xy 51.33224 -10.522991)
			(xy 51.282663 -10.500349) (xy 51.236813 -10.470883) (xy 51.195622 -10.435192) (xy 51.159931 -10.394001)
			(xy 51.130465 -10.348151) (xy 51.107823 -10.298574) (xy 51.092468 -10.246279) (xy 51.084712 -10.192331)
			(xy 51.084226 -10.16508) (xy 50.047144 -10.16508) (xy 50.046658 -10.192331) (xy 50.038902 -10.246279)
			(xy 50.023547 -10.298574) (xy 50.000905 -10.348151) (xy 49.971439 -10.394001) (xy 49.935748 -10.435192)
			(xy 49.894557 -10.470883) (xy 49.848707 -10.500349) (xy 49.79913 -10.522991) (xy 49.746835 -10.538346)
			(xy 49.692887 -10.546102) (xy 49.638385 -10.546102) (xy 49.584437 -10.538346) (xy 49.532142 -10.522991)
			(xy 49.482565 -10.500349) (xy 49.436715 -10.470883) (xy 49.395524 -10.435192) (xy 49.359833 -10.394001)
			(xy 49.330367 -10.348151) (xy 49.307725 -10.298574) (xy 49.29237 -10.246279) (xy 49.284614 -10.192331)
			(xy 49.284128 -10.16508) (xy 46.037246 -10.16508) (xy 46.03676 -10.192331) (xy 46.029004 -10.246279)
			(xy 46.013649 -10.298574) (xy 45.991007 -10.348151) (xy 45.961541 -10.394001) (xy 45.92585 -10.435192)
			(xy 45.884659 -10.470883) (xy 45.838809 -10.500349) (xy 45.789232 -10.522991) (xy 45.736937 -10.538346)
			(xy 45.682989 -10.546102) (xy 45.628487 -10.546102) (xy 45.574539 -10.538346) (xy 45.522244 -10.522991)
			(xy 45.472667 -10.500349) (xy 45.426817 -10.470883) (xy 45.385626 -10.435192) (xy 45.349935 -10.394001)
			(xy 45.320469 -10.348151) (xy 45.297827 -10.298574) (xy 45.282472 -10.246279) (xy 45.274716 -10.192331)
			(xy 45.27423 -10.16508) (xy 44.237148 -10.16508) (xy 44.236662 -10.192331) (xy 44.228906 -10.246279)
			(xy 44.213551 -10.298574) (xy 44.190909 -10.348151) (xy 44.161443 -10.394001) (xy 44.125752 -10.435192)
			(xy 44.084561 -10.470883) (xy 44.038711 -10.500349) (xy 43.989134 -10.522991) (xy 43.936839 -10.538346)
			(xy 43.882891 -10.546102) (xy 43.828389 -10.546102) (xy 43.774441 -10.538346) (xy 43.722146 -10.522991)
			(xy 43.672569 -10.500349) (xy 43.626719 -10.470883) (xy 43.585528 -10.435192) (xy 43.549837 -10.394001)
			(xy 43.520371 -10.348151) (xy 43.497729 -10.298574) (xy 43.482374 -10.246279) (xy 43.474618 -10.192331)
			(xy 43.474132 -10.16508) (xy 42.437304 -10.16508) (xy 42.436818 -10.192331) (xy 42.429062 -10.246279)
			(xy 42.413707 -10.298574) (xy 42.391065 -10.348151) (xy 42.361599 -10.394001) (xy 42.325908 -10.435192)
			(xy 42.284717 -10.470883) (xy 42.238867 -10.500349) (xy 42.18929 -10.522991) (xy 42.136995 -10.538346)
			(xy 42.083047 -10.546102) (xy 42.028545 -10.546102) (xy 41.974597 -10.538346) (xy 41.922302 -10.522991)
			(xy 41.872725 -10.500349) (xy 41.826875 -10.470883) (xy 41.785684 -10.435192) (xy 41.749993 -10.394001)
			(xy 41.720527 -10.348151) (xy 41.697885 -10.298574) (xy 41.68253 -10.246279) (xy 41.674774 -10.192331)
			(xy 41.674288 -10.16508) (xy 41.674795 -10.137219) (xy 41.682898 -10.082089) (xy 41.698928 -10.028722)
			(xy 41.722546 -9.978252) (xy 41.753249 -9.931752) (xy 41.790385 -9.890208) (xy 41.811448 -9.871964)
			(xy 41.820338 -9.864598) (xy 41.829736 -9.844786) (xy 41.830244 -9.744202) (xy 41.820846 -9.723628)
			(xy 41.81221 -9.716262) (xy 41.794606 -9.70093) (xy 41.762894 -9.666669) (xy 41.748964 -9.647936)
			(xy 41.74871 -9.647936) (xy 41.737026 -9.630664) (xy 41.730326 -9.621426) (xy 41.710943 -9.609439)
			(xy 41.699688 -9.60755) (xy 41.621202 -9.598914) (xy 41.609711 -9.598183) (xy 41.588026 -9.605857)
			(xy 41.579546 -9.613646) (xy 38.854634 -12.338558) (xy 38.847268 -12.34567) (xy 38.839648 -12.364466)
			(xy 38.839648 -12.37488) (xy 39.87622 -12.37488) (xy 39.880291 -12.319258) (xy 39.892417 -12.264821)
			(xy 39.91234 -12.21273) (xy 39.939636 -12.164095) (xy 39.973722 -12.119952) (xy 40.013871 -12.081243)
			(xy 40.059229 -12.048792) (xy 40.108829 -12.023291) (xy 40.161613 -12.005284) (xy 40.216456 -11.995154)
			(xy 40.27219 -11.993117) (xy 40.327627 -11.999217) (xy 40.381584 -12.013323) (xy 40.432913 -12.035135)
			(xy 40.480519 -12.064189) (xy 40.523387 -12.099864) (xy 40.560604 -12.141401) (xy 40.591377 -12.187914)
			(xy 40.615049 -12.238411) (xy 40.631117 -12.291818) (xy 40.639237 -12.346994) (xy 40.639746 -12.37488)
			(xy 41.676318 -12.37488) (xy 41.680389 -12.319258) (xy 41.692515 -12.264821) (xy 41.712438 -12.21273)
			(xy 41.739734 -12.164095) (xy 41.77382 -12.119952) (xy 41.813969 -12.081243) (xy 41.859327 -12.048792)
			(xy 41.908927 -12.023291) (xy 41.961711 -12.005284) (xy 42.016554 -11.995154) (xy 42.072288 -11.993117)
			(xy 42.127725 -11.999217) (xy 42.181682 -12.013323) (xy 42.233011 -12.035135) (xy 42.280617 -12.064189)
			(xy 42.323485 -12.099864) (xy 42.360702 -12.141401) (xy 42.391475 -12.187914) (xy 42.415147 -12.238411)
			(xy 42.431215 -12.291818) (xy 42.439335 -12.346994) (xy 42.439844 -12.37488) (xy 43.476162 -12.37488)
			(xy 43.480233 -12.319258) (xy 43.492359 -12.264821) (xy 43.512282 -12.21273) (xy 43.539578 -12.164095)
			(xy 43.573664 -12.119952) (xy 43.613813 -12.081243) (xy 43.659171 -12.048792) (xy 43.708771 -12.023291)
			(xy 43.761555 -12.005284) (xy 43.816398 -11.995154) (xy 43.872132 -11.993117) (xy 43.927569 -11.999217)
			(xy 43.981526 -12.013323) (xy 44.032855 -12.035135) (xy 44.080461 -12.064189) (xy 44.123329 -12.099864)
			(xy 44.160546 -12.141401) (xy 44.191319 -12.187914) (xy 44.214991 -12.238411) (xy 44.231059 -12.291818)
			(xy 44.239179 -12.346994) (xy 44.239688 -12.37488) (xy 44.239179 -12.402766) (xy 44.231059 -12.457942)
			(xy 44.214991 -12.511349) (xy 44.191319 -12.561846) (xy 44.160546 -12.608359) (xy 44.123329 -12.649896)
			(xy 44.080461 -12.685571) (xy 44.032855 -12.714625) (xy 43.981526 -12.736437) (xy 43.927569 -12.750543)
			(xy 43.872132 -12.756643) (xy 43.816398 -12.754606) (xy 43.761555 -12.744476) (xy 43.708771 -12.726469)
			(xy 43.659171 -12.700968) (xy 43.613813 -12.668517) (xy 43.573664 -12.629808) (xy 43.539578 -12.585665)
			(xy 43.512282 -12.53703) (xy 43.492359 -12.484939) (xy 43.480233 -12.430502) (xy 43.476162 -12.37488)
			(xy 42.439844 -12.37488) (xy 42.439335 -12.402766) (xy 42.431215 -12.457942) (xy 42.415147 -12.511349)
			(xy 42.391475 -12.561846) (xy 42.360702 -12.608359) (xy 42.323485 -12.649896) (xy 42.280617 -12.685571)
			(xy 42.233011 -12.714625) (xy 42.181682 -12.736437) (xy 42.127725 -12.750543) (xy 42.072288 -12.756643)
			(xy 42.016554 -12.754606) (xy 41.961711 -12.744476) (xy 41.908927 -12.726469) (xy 41.859327 -12.700968)
			(xy 41.813969 -12.668517) (xy 41.77382 -12.629808) (xy 41.739734 -12.585665) (xy 41.712438 -12.53703)
			(xy 41.692515 -12.484939) (xy 41.680389 -12.430502) (xy 41.676318 -12.37488) (xy 40.639746 -12.37488)
			(xy 40.639237 -12.402766) (xy 40.631117 -12.457942) (xy 40.615049 -12.511349) (xy 40.591377 -12.561846)
			(xy 40.560604 -12.608359) (xy 40.523387 -12.649896) (xy 40.480519 -12.685571) (xy 40.432913 -12.714625)
			(xy 40.381584 -12.736437) (xy 40.327627 -12.750543) (xy 40.27219 -12.756643) (xy 40.216456 -12.754606)
			(xy 40.161613 -12.744476) (xy 40.108829 -12.726469) (xy 40.059229 -12.700968) (xy 40.013871 -12.668517)
			(xy 39.973722 -12.629808) (xy 39.939636 -12.585665) (xy 39.91234 -12.53703) (xy 39.892417 -12.484939)
			(xy 39.880291 -12.430502) (xy 39.87622 -12.37488) (xy 38.839648 -12.37488) (xy 38.839164 -12.402133)
			(xy 38.83141 -12.456085) (xy 38.816057 -12.508385) (xy 38.793417 -12.557967) (xy 38.763952 -12.603823)
			(xy 38.728261 -12.645019) (xy 38.687071 -12.680716) (xy 38.64122 -12.710188) (xy 38.591641 -12.732836)
			(xy 38.539344 -12.748197) (xy 38.485393 -12.755959) (xy 38.45814 -12.756388) (xy 38.457886 -12.756388)
			(xy 38.447817 -12.756813) (xy 38.429215 -12.76453) (xy 38.421818 -12.771374) (xy 37.599366 -13.593826)
			(xy 37.592 -13.600938) (xy 37.58438 -13.619734) (xy 37.58438 -16.491966) (xy 37.585396 -16.501618)
			(xy 37.58819 -16.516096) (xy 37.592 -16.525494) (xy 37.649912 -16.583406) (xy 37.653481 -16.586811)
			(xy 37.661665 -16.592316) (xy 37.666168 -16.594328) (xy 37.676074 -16.598392) (xy 37.703591 -16.598209)
			(xy 37.758221 -16.604796) (xy 37.811338 -16.619166) (xy 37.861838 -16.64102) (xy 37.908674 -16.669903)
			(xy 37.950874 -16.705217) (xy 37.987561 -16.746229) (xy 38.017973 -16.792087) (xy 38.041481 -16.841839)
			(xy 38.057594 -16.894453) (xy 38.065981 -16.948836) (xy 38.066726 -16.976344) (xy 38.066726 -16.9799)
			(xy 38.066115 -17.009938) (xy 38.056679 -17.069268) (xy 38.04793 -17.09801) (xy 38.04793 -17.098264)
			(xy 38.047676 -17.098772) (xy 38.044719 -17.110358) (xy 38.048569 -17.133929) (xy 38.055042 -17.143984)
			(xy 38.103302 -17.210278) (xy 38.110864 -17.219622) (xy 38.132198 -17.230627) (xy 38.144196 -17.23136)
			(xy 38.49116 -17.23136) (xy 38.503168 -17.230653) (xy 38.524522 -17.219655) (xy 38.532054 -17.210278)
			(xy 38.580314 -17.143984) (xy 38.586838 -17.133949) (xy 38.590687 -17.110357) (xy 38.58768 -17.098772)
			(xy 38.587426 -17.098264) (xy 38.587426 -17.09801) (xy 38.578638 -17.069277) (xy 38.569192 -17.009941)
			(xy 38.56863 -16.9799) (xy 38.56863 -16.976344) (xy 38.569357 -16.949259) (xy 38.577522 -16.895695)
			(xy 38.593183 -16.843826) (xy 38.616024 -16.794694) (xy 38.645587 -16.749288) (xy 38.681276 -16.708521)
			(xy 38.722374 -16.673213) (xy 38.768054 -16.644075) (xy 38.817397 -16.621692) (xy 38.86941 -16.606515)
			(xy 38.923047 -16.59885) (xy 38.977229 -16.59885) (xy 39.030866 -16.606515) (xy 39.082879 -16.621692)
			(xy 39.132222 -16.644075) (xy 39.177902 -16.673213) (xy 39.219 -16.708521) (xy 39.254689 -16.749288)
			(xy 39.284252 -16.794694) (xy 39.307093 -16.843826) (xy 39.322754 -16.895695) (xy 39.330919 -16.949259)
			(xy 39.331646 -16.976344) (xy 39.331646 -16.979138) (xy 39.331105 -17.009633) (xy 39.32153 -17.069864)
			(xy 39.312596 -17.099026) (xy 39.309281 -17.111075) (xy 39.313429 -17.135689) (xy 39.32047 -17.146016)
			(xy 39.379144 -17.22247) (xy 39.401496 -17.232884) (xy 39.41445 -17.232122) (xy 39.43477 -17.231614)
			(xy 39.461999 -17.232132) (xy 39.515894 -17.239943) (xy 39.568131 -17.255339) (xy 39.617648 -17.278007)
			(xy 39.663438 -17.307487) (xy 39.70457 -17.343178) (xy 39.740208 -17.384357) (xy 39.769629 -17.430184)
			(xy 39.792233 -17.47973) (xy 39.807562 -17.531987) (xy 39.815303 -17.585893) (xy 39.81577 -17.613122)
			(xy 39.815305 -17.640373) (xy 39.807545 -17.694319) (xy 39.792187 -17.746612) (xy 39.769543 -17.796187)
			(xy 39.740074 -17.842035) (xy 39.704379 -17.883222) (xy 39.663187 -17.91891) (xy 39.617335 -17.948372)
			(xy 39.567756 -17.971008) (xy 39.515461 -17.986358) (xy 39.461513 -17.994109) (xy 39.434262 -17.99463)
			(xy 39.413942 -17.994122) (xy 39.401242 -17.99336) (xy 39.37889 -18.003774) (xy 39.312342 -18.090896)
			(xy 39.308278 -18.115534) (xy 39.312088 -18.127726) (xy 39.321188 -18.156926) (xy 39.331019 -18.217289)
			(xy 39.331646 -18.247868) (xy 39.33116 -18.275119) (xy 39.323404 -18.329067) (xy 39.308049 -18.381362)
			(xy 39.285407 -18.430939) (xy 39.255941 -18.476789) (xy 39.22025 -18.51798) (xy 39.179059 -18.553671)
			(xy 39.133209 -18.583137) (xy 39.083632 -18.605779) (xy 39.031337 -18.621134) (xy 38.977389 -18.62889)
			(xy 38.922887 -18.62889) (xy 38.868939 -18.621134) (xy 38.816644 -18.605779) (xy 38.767067 -18.583137)
			(xy 38.721217 -18.553671) (xy 38.680026 -18.51798) (xy 38.644335 -18.476789) (xy 38.614869 -18.430939)
			(xy 38.592227 -18.381362) (xy 38.576872 -18.329067) (xy 38.569116 -18.275119) (xy 38.56863 -18.247868)
			(xy 38.569246 -18.217428) (xy 38.578946 -18.157324) (xy 38.587934 -18.128234) (xy 38.591744 -18.11655)
			(xy 38.587934 -18.09242) (xy 38.532816 -18.015966) (xy 38.52521 -18.00657) (xy 38.503736 -17.995544)
			(xy 38.491668 -17.994884) (xy 38.143688 -17.994884) (xy 38.131613 -17.995545) (xy 38.110113 -18.00654)
			(xy 38.10254 -18.015966) (xy 38.047422 -18.09242) (xy 38.043612 -18.11655) (xy 38.047422 -18.128234)
			(xy 38.056423 -18.15732) (xy 38.066117 -18.217427) (xy 38.066726 -18.247868) (xy 38.066245 -18.275087)
			(xy 38.058512 -18.328972) (xy 38.043198 -18.38121) (xy 38.020615 -18.430742) (xy 37.99122 -18.476561)
			(xy 37.955612 -18.517737) (xy 37.914512 -18.553433) (xy 37.868756 -18.582925) (xy 37.819272 -18.605614)
			(xy 37.767066 -18.621038) (xy 37.713198 -18.628886) (xy 37.68598 -18.629376) (xy 37.680947 -18.629514)
			(xy 37.67109 -18.631556) (xy 37.666422 -18.63344) (xy 37.657024 -18.63725) (xy 37.599366 -18.694908)
			(xy 37.592514 -18.702304) (xy 37.584772 -18.720903) (xy 37.58438 -18.730976) (xy 37.58438 -45.496226)
			(xy 37.584807 -45.506295) (xy 37.592526 -45.524894) (xy 37.599366 -45.532294) (xy 48.059086 -55.992014)
			(xy 67.562982 -55.992014) (xy 67.567053 -55.936392) (xy 67.579179 -55.881955) (xy 67.599102 -55.829864)
			(xy 67.626398 -55.781229) (xy 67.660484 -55.737086) (xy 67.700633 -55.698377) (xy 67.745991 -55.665926)
			(xy 67.795591 -55.640425) (xy 67.848375 -55.622418) (xy 67.903218 -55.612288) (xy 67.958952 -55.610251)
			(xy 68.014389 -55.616351) (xy 68.068346 -55.630457) (xy 68.119675 -55.652269) (xy 68.167281 -55.681323)
			(xy 68.210149 -55.716998) (xy 68.247366 -55.758535) (xy 68.278139 -55.805048) (xy 68.301811 -55.855545)
			(xy 68.317879 -55.908952) (xy 68.325999 -55.964128) (xy 68.326508 -55.992014) (xy 68.325999 -56.0199)
			(xy 68.317879 -56.075076) (xy 68.301811 -56.128483) (xy 68.278139 -56.17898) (xy 68.247366 -56.225493)
			(xy 68.210149 -56.26703) (xy 68.167281 -56.302705) (xy 68.119675 -56.331759) (xy 68.068346 -56.353571)
			(xy 68.014389 -56.367677) (xy 67.958952 -56.373777) (xy 67.903218 -56.37174) (xy 67.848375 -56.36161)
			(xy 67.795591 -56.343603) (xy 67.745991 -56.318102) (xy 67.700633 -56.285651) (xy 67.660484 -56.246942)
			(xy 67.626398 -56.202799) (xy 67.599102 -56.154164) (xy 67.579179 -56.102073) (xy 67.567053 -56.047636)
			(xy 67.562982 -55.992014) (xy 48.059086 -55.992014) (xy 48.633083 -56.566011) (xy 73.151994 -56.566011)
			(xy 73.151994 -56.502089) (xy 73.160005 -56.438671) (xy 73.175902 -56.376757) (xy 73.199434 -56.317324)
			(xy 73.230228 -56.261309) (xy 73.267801 -56.209594) (xy 73.311558 -56.162997) (xy 73.360811 -56.122252)
			(xy 73.414782 -56.088001) (xy 73.472621 -56.060784) (xy 73.533414 -56.041031) (xy 73.596204 -56.029053)
			(xy 73.66 -56.02504) (xy 73.723796 -56.029053) (xy 73.786586 -56.041031) (xy 73.847379 -56.060784)
			(xy 73.905218 -56.088001) (xy 73.959189 -56.122252) (xy 74.008442 -56.162997) (xy 74.052199 -56.209594)
			(xy 74.089772 -56.261309) (xy 74.120566 -56.317324) (xy 74.144098 -56.376757) (xy 74.159995 -56.438671)
			(xy 74.168006 -56.502089) (xy 74.168508 -56.53405) (xy 74.168006 -56.566011) (xy 74.159995 -56.629429)
			(xy 74.144098 -56.691343) (xy 74.120566 -56.750776) (xy 74.089772 -56.806791) (xy 74.052199 -56.858506)
			(xy 74.008442 -56.905103) (xy 73.959189 -56.945848) (xy 73.905218 -56.980099) (xy 73.847379 -57.007316)
			(xy 73.786586 -57.027069) (xy 73.723796 -57.039047) (xy 73.66 -57.043061) (xy 73.596204 -57.039047)
			(xy 73.533414 -57.027069) (xy 73.472621 -57.007316) (xy 73.414782 -56.980099) (xy 73.360811 -56.945848)
			(xy 73.311558 -56.905103) (xy 73.267801 -56.858506) (xy 73.230228 -56.806791) (xy 73.199434 -56.750776)
			(xy 73.175902 -56.691343) (xy 73.160005 -56.629429) (xy 73.151994 -56.566011) (xy 48.633083 -56.566011)
			(xy 50.334672 -58.2676) (xy 50.342074 -58.274435) (xy 50.360673 -58.282144) (xy 50.37074 -58.282586)
		)
		(stroke
			(width 0)
			(type solid)
		)
		(fill yes)
		(layer "In13.Cu")
		(net "P3V3_OCP_V3_2")
	)
	(gr_poly
		(pts
			(xy 66.120518 -391.16) (xy 66.130587 -391.159573) (xy 66.149186 -391.151854) (xy 66.156586 -391.145014)
			(xy 66.533014 -390.768586) (xy 66.539868 -390.761191) (xy 66.54761 -390.742592) (xy 66.548 -390.732518)
			(xy 66.548 -390.449816) (xy 66.547463 -390.438796) (xy 66.538248 -390.418776) (xy 66.53022 -390.411208)
			(xy 66.510842 -390.393943) (xy 66.477185 -390.35444) (xy 66.450109 -390.310166) (xy 66.43028 -390.262207)
			(xy 66.418185 -390.211739) (xy 66.41412 -390.160001) (xy 66.418185 -390.108264) (xy 66.43028 -390.057796)
			(xy 66.450108 -390.009836) (xy 66.477183 -389.965562) (xy 66.510841 -389.926059) (xy 66.53022 -389.908796)
			(xy 66.538241 -389.901223) (xy 66.547455 -389.881206) (xy 66.548 -389.870188) (xy 66.548 -389.797544)
			(xy 66.547609 -389.788051) (xy 66.540723 -389.770357) (xy 66.527903 -389.756352) (xy 66.519552 -389.751824)
			(xy 66.424556 -389.705342) (xy 66.395854 -389.708136) (xy 66.384424 -389.717026) (xy 66.363543 -389.732484)
			(xy 66.317782 -389.757075) (xy 66.268611 -389.77384) (xy 66.217359 -389.782328) (xy 66.191384 -389.782812)
			(xy 66.165991 -389.782303) (xy 66.11586 -389.774171) (xy 66.067678 -389.758118) (xy 66.022687 -389.734559)
			(xy 65.982047 -389.704102) (xy 65.946807 -389.667532) (xy 65.917876 -389.625792) (xy 65.896 -389.579959)
			(xy 65.888362 -389.555736) (xy 65.886838 -389.549894) (xy 65.566544 -388.996174) (xy 65.56248 -388.991856)
			(xy 65.546265 -388.974157) (xy 65.518837 -388.934767) (xy 65.497695 -388.891675) (xy 65.483326 -388.845878)
			(xy 65.476063 -388.798431) (xy 65.475612 -388.774432) (xy 65.47577 -388.76238) (xy 65.477679 -388.738352)
			(xy 65.479422 -388.726426) (xy 65.480692 -388.717536) (xy 65.477644 -388.700518) (xy 65.43548 -388.629652)
			(xy 65.422272 -388.618476) (xy 65.41389 -388.615428) (xy 65.392149 -388.607023) (xy 65.351304 -388.584571)
			(xy 65.314345 -388.556172) (xy 65.282131 -388.522486) (xy 65.255411 -388.484295) (xy 65.234806 -388.442487)
			(xy 65.220794 -388.398034) (xy 65.213701 -388.351967) (xy 65.21323 -388.328662) (xy 65.21373 -388.303264)
			(xy 65.22213 -388.253168) (xy 65.238709 -388.205155) (xy 65.263009 -388.160549) (xy 65.294359 -388.120582)
			(xy 65.312798 -388.10311) (xy 65.32118 -388.09549) (xy 65.329816 -388.075424) (xy 65.327022 -387.97611)
			(xy 65.317624 -387.956552) (xy 65.308734 -387.94944) (xy 65.290171 -387.933639) (xy 65.257441 -387.897513)
			(xy 65.230366 -387.856977) (xy 65.209531 -387.812906) (xy 65.195387 -387.766256) (xy 65.18824 -387.718036)
			(xy 65.18783 -387.693662) (xy 65.188269 -387.669546) (xy 65.195275 -387.621826) (xy 65.209133 -387.575628)
			(xy 65.229551 -387.531931) (xy 65.24244 -387.511544) (xy 65.248282 -387.502654) (xy 65.251838 -387.482588)
			(xy 65.230756 -387.390386) (xy 65.218564 -387.373622) (xy 65.209674 -387.368288) (xy 65.188871 -387.355433)
			(xy 65.150951 -387.324556) (xy 65.117999 -387.288426) (xy 65.090733 -387.247833) (xy 65.069749 -387.203663)
			(xy 65.055508 -387.156882) (xy 65.048318 -387.108513) (xy 65.047876 -387.084062) (xy 65.048437 -387.056779)
			(xy 65.057397 -387.002954) (xy 65.075069 -386.951329) (xy 65.100972 -386.903304) (xy 65.134405 -386.860181)
			(xy 65.154048 -386.841238) (xy 65.161503 -386.833749) (xy 65.170055 -386.814453) (xy 65.170558 -386.8039)
			(xy 65.170558 -386.729224) (xy 65.169971 -386.71869) (xy 65.161438 -386.699418) (xy 65.154048 -386.691886)
			(xy 65.134393 -386.672953) (xy 65.100949 -386.629833) (xy 65.07504 -386.581806) (xy 65.057369 -386.530177)
			(xy 65.048415 -386.476347) (xy 65.047876 -386.449062) (xy 65.04813 -386.43687) (xy 65.048384 -386.427218)
			(xy 65.042288 -386.409184) (xy 64.983614 -386.341874) (xy 64.96685 -386.333238) (xy 64.956944 -386.332222)
			(xy 64.930031 -386.32887) (xy 64.877734 -386.314523) (xy 64.828479 -386.291834) (xy 64.783587 -386.26141)
			(xy 64.744262 -386.224067) (xy 64.711559 -386.180807) (xy 64.686355 -386.13279) (xy 64.669325 -386.081304)
			(xy 64.66459 -386.0546) (xy 64.663066 -386.045202) (xy 64.390016 -385.572762) (xy 64.382904 -385.56692)
			(xy 64.364169 -385.551141) (xy 64.331112 -385.514999) (xy 64.30375 -385.474374) (xy 64.282684 -385.430155)
			(xy 64.268374 -385.383312) (xy 64.261133 -385.33487) (xy 64.26073 -385.31038) (xy 64.261215 -385.284393)
			(xy 64.269349 -385.233059) (xy 64.285413 -385.18363) (xy 64.309013 -385.137322) (xy 64.339566 -385.095276)
			(xy 64.37632 -385.058528) (xy 64.418371 -385.027982) (xy 64.464683 -385.004391) (xy 64.514115 -384.988335)
			(xy 64.565451 -384.98021) (xy 64.591438 -384.979672) (xy 64.617484 -384.980155) (xy 64.668934 -384.988311)
			(xy 64.718469 -385.004432) (xy 64.764864 -385.02812) (xy 64.806972 -385.058787) (xy 64.843752 -385.095677)
			(xy 64.874294 -385.137876) (xy 64.897843 -385.184341) (xy 64.913817 -385.233924) (xy 64.918336 -385.25958)
			(xy 64.919606 -385.268978) (xy 64.943542 -385.31038) (xy 65.460626 -385.31038) (xy 65.461057 -385.284388)
			(xy 65.469192 -385.233046) (xy 65.485259 -385.183608) (xy 65.508862 -385.137293) (xy 65.53942 -385.09524)
			(xy 65.576181 -385.058485) (xy 65.618239 -385.027934) (xy 65.664558 -385.004338) (xy 65.713999 -384.988279)
			(xy 65.765342 -384.980153) (xy 65.791334 -384.979672) (xy 65.817345 -384.980111) (xy 65.868723 -384.988275)
			(xy 65.91819 -385.00438) (xy 65.964526 -385.02803) (xy 66.006589 -385.058642) (xy 66.043342 -385.09546)
			(xy 66.073878 -385.137577) (xy 66.079858 -385.149344) (xy 67.42938 -385.149344) (xy 67.429813 -385.124448)
			(xy 67.437264 -385.075217) (xy 67.452004 -385.027657) (xy 67.4737 -384.982841) (xy 67.501864 -384.941781)
			(xy 67.518534 -384.923284) (xy 67.525138 -384.916426) (xy 67.531996 -384.899408) (xy 67.534282 -384.813048)
			(xy 67.528186 -384.795522) (xy 67.52209 -384.78841) (xy 67.507319 -384.770425) (xy 67.482493 -384.731061)
			(xy 67.463433 -384.688603) (xy 67.450516 -384.643892) (xy 67.443997 -384.597812) (xy 67.443604 -384.574542)
			(xy 67.444114 -384.548553) (xy 67.452239 -384.497215) (xy 67.468296 -384.44778) (xy 67.49189 -384.401466)
			(xy 67.522439 -384.359414) (xy 67.559191 -384.322659) (xy 67.60124 -384.292106) (xy 67.647552 -384.268508)
			(xy 67.696986 -384.252446) (xy 67.748323 -384.244316) (xy 67.774312 -384.243834) (xy 67.797813 -384.244228)
			(xy 67.844344 -384.250865) (xy 67.867022 -384.257042) (xy 67.880484 -384.261106) (xy 67.9069 -384.254502)
			(xy 67.989958 -384.173222) (xy 67.997324 -384.14706) (xy 67.993768 -384.133598) (xy 67.987834 -384.109651)
			(xy 67.981458 -384.06073) (xy 67.981068 -384.036062) (xy 67.981554 -384.008811) (xy 67.98931 -383.954863)
			(xy 68.004665 -383.902568) (xy 68.027307 -383.852991) (xy 68.056773 -383.807141) (xy 68.092464 -383.76595)
			(xy 68.133655 -383.730259) (xy 68.179505 -383.700793) (xy 68.229082 -383.678151) (xy 68.281377 -383.662796)
			(xy 68.335325 -383.65504) (xy 68.389827 -383.65504) (xy 68.443775 -383.662796) (xy 68.49607 -383.678151)
			(xy 68.545647 -383.700793) (xy 68.591497 -383.730259) (xy 68.632688 -383.76595) (xy 68.668379 -383.807141)
			(xy 68.697845 -383.852991) (xy 68.720487 -383.902568) (xy 68.735842 -383.954863) (xy 68.743598 -384.008811)
			(xy 68.744084 -384.036062) (xy 68.7436 -384.063432) (xy 68.737767 -384.10388) (xy 69.080378 -384.10388)
			(xy 69.084449 -384.048258) (xy 69.096575 -383.993821) (xy 69.116498 -383.94173) (xy 69.143794 -383.893095)
			(xy 69.17788 -383.848952) (xy 69.218029 -383.810243) (xy 69.263387 -383.777792) (xy 69.312987 -383.752291)
			(xy 69.365771 -383.734284) (xy 69.420614 -383.724154) (xy 69.476348 -383.722117) (xy 69.531785 -383.728217)
			(xy 69.585742 -383.742323) (xy 69.637071 -383.764135) (xy 69.684677 -383.793189) (xy 69.727545 -383.828864)
			(xy 69.764762 -383.870401) (xy 69.795535 -383.916914) (xy 69.819207 -383.967411) (xy 69.835275 -384.020818)
			(xy 69.843395 -384.075994) (xy 69.843904 -384.10388) (xy 69.843395 -384.131766) (xy 69.835275 -384.186942)
			(xy 69.819207 -384.240349) (xy 69.795535 -384.290846) (xy 69.764762 -384.337359) (xy 69.727545 -384.378896)
			(xy 69.684677 -384.414571) (xy 69.637071 -384.443625) (xy 69.585742 -384.465437) (xy 69.531785 -384.479543)
			(xy 69.476348 -384.485643) (xy 69.420614 -384.483606) (xy 69.365771 -384.473476) (xy 69.312987 -384.455469)
			(xy 69.263387 -384.429968) (xy 69.218029 -384.397517) (xy 69.17788 -384.358808) (xy 69.143794 -384.314665)
			(xy 69.116498 -384.26603) (xy 69.096575 -384.213939) (xy 69.084449 -384.159502) (xy 69.080378 -384.10388)
			(xy 68.737767 -384.10388) (xy 68.735787 -384.11761) (xy 68.720302 -384.170113) (xy 68.697464 -384.21986)
			(xy 68.667744 -384.265828) (xy 68.650104 -384.28676) (xy 68.644008 -384.293872) (xy 68.637658 -384.31089)
			(xy 68.637658 -384.396234) (xy 68.644008 -384.413252) (xy 68.650104 -384.420364) (xy 68.667706 -384.441327)
			(xy 68.69743 -384.487291) (xy 68.720276 -384.537032) (xy 68.735774 -384.589529) (xy 68.743605 -384.643703)
			(xy 68.743609 -384.69844) (xy 68.735786 -384.752615) (xy 68.720296 -384.805114) (xy 68.697458 -384.854859)
			(xy 68.667741 -384.900827) (xy 68.650104 -384.92176) (xy 68.644008 -384.928872) (xy 68.637658 -384.94589)
			(xy 68.637658 -385.031234) (xy 68.644008 -385.048252) (xy 68.650104 -385.055364) (xy 68.66774 -385.076298)
			(xy 68.679491 -385.09448) (xy 69.080378 -385.09448) (xy 69.084449 -385.038858) (xy 69.096575 -384.984421)
			(xy 69.116498 -384.93233) (xy 69.143794 -384.883695) (xy 69.17788 -384.839552) (xy 69.218029 -384.800843)
			(xy 69.263387 -384.768392) (xy 69.312987 -384.742891) (xy 69.365771 -384.724884) (xy 69.420614 -384.714754)
			(xy 69.476348 -384.712717) (xy 69.531785 -384.718817) (xy 69.585742 -384.732923) (xy 69.637071 -384.754735)
			(xy 69.684677 -384.783789) (xy 69.727545 -384.819464) (xy 69.764762 -384.861001) (xy 69.795535 -384.907514)
			(xy 69.819207 -384.958011) (xy 69.835275 -385.011418) (xy 69.843395 -385.066594) (xy 69.843904 -385.09448)
			(xy 69.843395 -385.122366) (xy 69.835275 -385.177542) (xy 69.819207 -385.230949) (xy 69.795535 -385.281446)
			(xy 69.764762 -385.327959) (xy 69.727545 -385.369496) (xy 69.684677 -385.405171) (xy 69.637071 -385.434225)
			(xy 69.585742 -385.456037) (xy 69.531785 -385.470143) (xy 69.476348 -385.476243) (xy 69.420614 -385.474206)
			(xy 69.365771 -385.464076) (xy 69.312987 -385.446069) (xy 69.263387 -385.420568) (xy 69.218029 -385.388117)
			(xy 69.17788 -385.349408) (xy 69.143794 -385.305265) (xy 69.116498 -385.25663) (xy 69.096575 -385.204539)
			(xy 69.084449 -385.150102) (xy 69.080378 -385.09448) (xy 68.679491 -385.09448) (xy 68.697452 -385.122271)
			(xy 68.720289 -385.172018) (xy 68.735781 -385.224518) (xy 68.74361 -385.278693) (xy 68.744084 -385.306062)
			(xy 68.743593 -385.33297) (xy 68.736048 -385.386255) (xy 68.721089 -385.437951) (xy 68.699012 -385.48703)
			(xy 68.670256 -385.532519) (xy 68.635391 -385.573515) (xy 68.595111 -385.609204) (xy 68.550214 -385.638876)
			(xy 68.501592 -385.661944) (xy 68.450211 -385.677948) (xy 68.39709 -385.686572) (xy 68.370196 -385.68757)
			(xy 68.358766 -385.687824) (xy 68.3387 -385.69773) (xy 68.275708 -385.776978) (xy 68.270628 -385.799076)
			(xy 68.272914 -385.810252) (xy 68.276835 -385.829829) (xy 68.281033 -385.869536) (xy 68.281296 -385.8895)
			(xy 68.281041 -385.909591) (xy 68.276846 -385.949552) (xy 68.272914 -385.969256) (xy 68.269866 -385.982718)
			(xy 68.278756 -386.00888) (xy 68.36664 -386.085588) (xy 68.393818 -386.090668) (xy 68.406772 -386.086096)
			(xy 68.438164 -386.075466) (xy 68.503431 -386.063969) (xy 68.536566 -386.063236) (xy 68.56382 -386.063641)
			(xy 68.617772 -386.071394) (xy 68.670073 -386.086745) (xy 68.719656 -386.109384) (xy 68.765513 -386.138848)
			(xy 68.80671 -386.174539) (xy 68.842409 -386.215729) (xy 68.871882 -386.261581) (xy 68.89453 -386.31116)
			(xy 68.909891 -386.363458) (xy 68.917653 -386.417409) (xy 68.917659 -386.471916) (xy 68.909907 -386.525869)
			(xy 68.894556 -386.57817) (xy 68.871918 -386.627754) (xy 68.842454 -386.673611) (xy 68.806763 -386.714808)
			(xy 68.765573 -386.750507) (xy 68.719722 -386.77998) (xy 68.670143 -386.802628) (xy 68.617846 -386.81799)
			(xy 68.563894 -386.825753) (xy 68.509387 -386.825759) (xy 68.455434 -386.818008) (xy 68.403133 -386.802657)
			(xy 68.353549 -386.780019) (xy 68.307692 -386.750556) (xy 68.266494 -386.714866) (xy 68.230795 -386.673676)
			(xy 68.201321 -386.627825) (xy 68.178673 -386.578246) (xy 68.16331 -386.525949) (xy 68.155547 -386.471997)
			(xy 68.155058 -386.444744) (xy 68.155305 -386.424653) (xy 68.159506 -386.384692) (xy 68.16344 -386.364988)
			(xy 68.166488 -386.351526) (xy 68.157598 -386.325364) (xy 68.069714 -386.248656) (xy 68.042536 -386.243576)
			(xy 68.029582 -386.248148) (xy 67.998194 -386.258791) (xy 67.932924 -386.270279) (xy 67.899788 -386.271008)
			(xy 67.872536 -386.270533) (xy 67.818588 -386.262775) (xy 67.766293 -386.247419) (xy 67.716716 -386.224776)
			(xy 67.670866 -386.195309) (xy 67.629676 -386.159616) (xy 67.593984 -386.118425) (xy 67.564518 -386.072573)
			(xy 67.541877 -386.022995) (xy 67.526522 -385.9707) (xy 67.518766 -385.916752) (xy 67.51828 -385.8895)
			(xy 67.518704 -385.863518) (xy 67.525769 -385.812035) (xy 67.539754 -385.761987) (xy 67.5604 -385.714299)
			(xy 67.587326 -385.669854) (xy 67.620034 -385.629474) (xy 67.638676 -385.61137) (xy 67.648074 -385.602734)
			(xy 67.655948 -385.579366) (xy 67.639946 -385.47167) (xy 67.625468 -385.451604) (xy 67.614038 -385.446016)
			(xy 67.590636 -385.433972) (xy 67.547692 -385.403547) (xy 67.51011 -385.366703) (xy 67.478839 -385.324369)
			(xy 67.454671 -385.277617) (xy 67.438214 -385.227626) (xy 67.429885 -385.175659) (xy 67.42938 -385.149344)
			(xy 66.079858 -385.149344) (xy 66.097446 -385.183956) (xy 66.113463 -385.233451) (xy 66.117978 -385.259072)
			(xy 66.119502 -385.26847) (xy 66.392298 -385.740402) (xy 66.399664 -385.746244) (xy 66.418459 -385.762026)
			(xy 66.451572 -385.798249) (xy 66.478978 -385.838962) (xy 66.500076 -385.883273) (xy 66.514403 -385.930213)
			(xy 66.521647 -385.978753) (xy 66.522092 -386.003292) (xy 66.521838 -386.014976) (xy 66.521584 -386.024882)
			(xy 66.527934 -386.042916) (xy 66.587116 -386.109972) (xy 66.604388 -386.118862) (xy 66.61404 -386.119624)
			(xy 66.638376 -386.122272) (xy 66.685926 -386.133908) (xy 66.731242 -386.152421) (xy 66.773337 -386.177408)
			(xy 66.811292 -386.208324) (xy 66.844278 -386.244494) (xy 66.871576 -386.285129) (xy 66.89259 -386.329342)
			(xy 66.906861 -386.376168) (xy 66.914078 -386.424586) (xy 66.914522 -386.449062) (xy 66.914012 -386.475049)
			(xy 66.905882 -386.526384) (xy 66.889821 -386.575814) (xy 66.866225 -386.622124) (xy 66.835675 -386.664172)
			(xy 66.798924 -386.700923) (xy 66.756876 -386.731473) (xy 66.710566 -386.755069) (xy 66.661136 -386.77113)
			(xy 66.609801 -386.77926) (xy 66.557827 -386.77926) (xy 66.506492 -386.77113) (xy 66.457062 -386.755069)
			(xy 66.410752 -386.731473) (xy 66.368704 -386.700923) (xy 66.331953 -386.664172) (xy 66.301403 -386.622124)
			(xy 66.277807 -386.575814) (xy 66.261746 -386.526384) (xy 66.253616 -386.475049) (xy 66.253106 -386.449062)
			(xy 66.25336 -386.437378) (xy 66.253614 -386.427472) (xy 66.247264 -386.409438) (xy 66.188082 -386.342382)
			(xy 66.17081 -386.333492) (xy 66.161158 -386.33273) (xy 66.136971 -386.330089) (xy 66.089706 -386.318544)
			(xy 66.044639 -386.300205) (xy 66.002741 -386.275469) (xy 65.964915 -386.244867) (xy 65.931975 -386.209058)
			(xy 65.90463 -386.168815) (xy 65.883469 -386.125002) (xy 65.868949 -386.078565) (xy 65.86474 -386.0546)
			(xy 65.863216 -386.045202) (xy 65.59042 -385.57327) (xy 65.583054 -385.567428) (xy 65.564298 -385.551602)
			(xy 65.53118 -385.515389) (xy 65.50377 -385.474685) (xy 65.482665 -385.430382) (xy 65.46833 -385.38345)
			(xy 65.461076 -385.334916) (xy 65.460626 -385.31038) (xy 64.943542 -385.31038) (xy 65.192148 -385.740402)
			(xy 65.199514 -385.746244) (xy 65.218291 -385.762048) (xy 65.251423 -385.798256) (xy 65.278842 -385.838961)
			(xy 65.299948 -385.88327) (xy 65.314276 -385.93021) (xy 65.321512 -385.978753) (xy 65.321942 -386.003292)
			(xy 65.321688 -386.015484) (xy 65.321434 -386.025136) (xy 65.32753 -386.04317) (xy 65.386204 -386.11048)
			(xy 65.402968 -386.119116) (xy 65.412874 -386.120132) (xy 65.439644 -386.123456) (xy 65.491675 -386.137677)
			(xy 65.540709 -386.160153) (xy 65.585447 -386.190287) (xy 65.624702 -386.227281) (xy 65.657434 -386.270154)
			(xy 65.682775 -386.317771) (xy 65.700054 -386.368868) (xy 65.708813 -386.422092) (xy 65.709292 -386.449062)
			(xy 65.708729 -386.476344) (xy 65.699765 -386.530166) (xy 65.682089 -386.581787) (xy 65.656182 -386.629808)
			(xy 65.622746 -386.672926) (xy 65.60312 -386.691886) (xy 65.595673 -386.699378) (xy 65.587136 -386.718674)
			(xy 65.58661 -386.729224) (xy 65.58661 -386.8039) (xy 65.587201 -386.814433) (xy 65.595736 -386.833702)
			(xy 65.60312 -386.841238) (xy 65.622775 -386.86017) (xy 65.656219 -386.903291) (xy 65.682127 -386.951317)
			(xy 65.699797 -387.002947) (xy 65.708748 -387.056777) (xy 65.709292 -387.084062) (xy 65.708859 -387.10818)
			(xy 65.701863 -387.155904) (xy 65.688014 -387.202109) (xy 65.667605 -387.245813) (xy 65.654682 -387.26618)
			(xy 65.64884 -387.27507) (xy 65.645284 -387.295136) (xy 65.666366 -387.387338) (xy 65.678558 -387.404102)
			(xy 65.687448 -387.409436) (xy 65.708249 -387.422292) (xy 65.746164 -387.453171) (xy 65.779112 -387.489302)
			(xy 65.806373 -387.529896) (xy 65.827351 -387.574066) (xy 65.841589 -387.620845) (xy 65.848774 -387.669213)
			(xy 65.849246 -387.693662) (xy 65.848808 -387.718033) (xy 65.841652 -387.766246) (xy 65.827504 -387.812889)
			(xy 65.80667 -387.856953) (xy 65.779599 -387.897485) (xy 65.746878 -387.933611) (xy 65.728342 -387.94944)
			(xy 65.719452 -387.956552) (xy 65.710054 -387.97611) (xy 65.70726 -388.075424) (xy 65.715896 -388.09549)
			(xy 65.724278 -388.10311) (xy 65.742701 -388.120597) (xy 65.774045 -388.160564) (xy 65.798344 -388.205167)
			(xy 65.814927 -388.253175) (xy 65.823338 -388.303266) (xy 65.823846 -388.328662) (xy 65.823774 -388.33802)
			(xy 65.822628 -388.356702) (xy 65.82156 -388.366) (xy 65.820544 -388.37489) (xy 65.824354 -388.391654)
			(xy 65.868296 -388.461504) (xy 65.882012 -388.471918) (xy 65.890394 -388.474712) (xy 65.914431 -388.483165)
			(xy 65.959614 -388.506709) (xy 66.000429 -388.537205) (xy 66.035815 -388.573861) (xy 66.064854 -388.615725)
			(xy 66.08679 -388.66171) (xy 66.094356 -388.68604) (xy 66.09588 -388.691882) (xy 66.416174 -389.245602)
			(xy 66.420238 -389.24992) (xy 66.435224 -389.266938) (xy 66.441941 -389.274318) (xy 66.459542 -389.283679)
			(xy 66.479385 -389.285601) (xy 66.489072 -389.283194) (xy 66.511932 -389.276336) (xy 66.522151 -389.272687)
			(xy 66.538444 -389.258387) (xy 66.547429 -389.238659) (xy 66.548 -389.227822) (xy 66.548 -388.74954)
			(xy 66.548434 -388.739475) (xy 66.556164 -388.720886) (xy 66.562986 -388.713472) (xy 67.218814 -388.057644)
			(xy 67.226211 -388.050795) (xy 67.24481 -388.043059) (xy 67.254882 -388.042658) (xy 67.587876 -388.042658)
			(xy 67.596546 -388.042361) (xy 67.612915 -388.036653) (xy 67.61988 -388.031482) (xy 67.639547 -388.016252)
			(xy 67.682549 -387.991254) (xy 67.728812 -387.972984) (xy 67.777291 -387.961854) (xy 67.82689 -387.958116)
			(xy 67.876489 -387.961854) (xy 67.924968 -387.972984) (xy 67.971231 -387.991254) (xy 68.014233 -388.016252)
			(xy 68.0339 -388.031482) (xy 68.040758 -388.036816) (xy 68.057014 -388.042658) (xy 68.126356 -388.042658)
			(xy 68.136421 -388.042223) (xy 68.155006 -388.03449) (xy 68.162424 -388.027672) (xy 69.50456 -386.685536)
			(xy 69.511254 -386.67813) (xy 69.518856 -386.659694) (xy 69.519292 -386.649722) (xy 69.519292 -386.492496)
			(xy 69.518917 -386.48282) (xy 69.511872 -386.4648) (xy 69.505576 -386.457444) (xy 69.485002 -386.4356)
			(xy 69.478495 -386.429298) (xy 69.462223 -386.421369) (xy 69.453252 -386.420106) (xy 69.425495 -386.416668)
			(xy 69.371337 -386.402708) (xy 69.319797 -386.380989) (xy 69.271982 -386.351977) (xy 69.228916 -386.316293)
			(xy 69.191522 -386.274703) (xy 69.160603 -386.228098) (xy 69.13682 -386.177478) (xy 69.120685 -386.123927)
			(xy 69.112542 -386.068595) (xy 69.11213 -386.04063) (xy 69.112591 -386.013377) (xy 69.120345 -385.959425)
			(xy 69.135699 -385.907125) (xy 69.15834 -385.857544) (xy 69.187808 -385.81169) (xy 69.223502 -385.770497)
			(xy 69.264696 -385.734803) (xy 69.310551 -385.705336) (xy 69.360133 -385.682696) (xy 69.412432 -385.667343)
			(xy 69.466385 -385.659591) (xy 69.493638 -385.659122) (xy 69.52144 -385.65962) (xy 69.576457 -385.667681)
			(xy 69.629722 -385.683643) (xy 69.680105 -385.707166) (xy 69.726541 -385.737753) (xy 69.768046 -385.774757)
			(xy 69.80374 -385.817392) (xy 69.832869 -385.864756) (xy 69.854814 -385.915847) (xy 69.862446 -385.942586)
			(xy 69.865494 -385.954016) (xy 69.880988 -385.971796) (xy 69.977508 -386.011928) (xy 70.00113 -386.010404)
			(xy 70.01129 -386.004562) (xy 70.029832 -385.994148) (xy 70.03669 -385.990592) (xy 70.29196 -385.735576)
			(xy 70.298728 -385.728147) (xy 70.306303 -385.709551) (xy 70.306692 -385.699508) (xy 70.306692 -383.92862)
			(xy 70.306186 -383.91754) (xy 70.296955 -383.897398) (xy 70.288912 -383.889758) (xy 70.221094 -383.832354)
			(xy 70.199758 -383.826512) (xy 70.188582 -383.82829) (xy 70.172951 -383.830759) (xy 70.141414 -383.833426)
			(xy 70.12559 -383.833624) (xy 70.098338 -383.833137) (xy 70.044389 -383.82538) (xy 69.992093 -383.810023)
			(xy 69.942515 -383.78738) (xy 69.896664 -383.757912) (xy 69.855474 -383.722219) (xy 69.819782 -383.681028)
			(xy 69.790315 -383.635176) (xy 69.767674 -383.585597) (xy 69.752318 -383.533301) (xy 69.744562 -383.479352)
			(xy 69.744562 -383.424848) (xy 69.752318 -383.370899) (xy 69.767674 -383.318603) (xy 69.790315 -383.269024)
			(xy 69.819782 -383.223172) (xy 69.855474 -383.181981) (xy 69.896664 -383.146288) (xy 69.942515 -383.11682)
			(xy 69.992093 -383.094177) (xy 70.044389 -383.07882) (xy 70.098338 -383.071063) (xy 70.12559 -383.070608)
			(xy 70.141415 -383.070787) (xy 70.172953 -383.073454) (xy 70.188582 -383.075942) (xy 70.199758 -383.07772)
			(xy 70.221094 -383.071878) (xy 70.297548 -383.007108) (xy 70.306692 -382.987042) (xy 70.306692 -382.97739)
			(xy 70.327266 -382.956816) (xy 70.333972 -382.94938) (xy 70.341592 -382.930884) (xy 70.341585 -382.910881)
			(xy 70.333952 -382.89239) (xy 70.327266 -382.884934) (xy 70.295008 -382.852676) (xy 70.287614 -382.84582)
			(xy 70.269015 -382.83807) (xy 70.25894 -382.83769) (xy 67.77736 -382.83769) (xy 67.74815 -382.865376)
			(xy 67.747134 -382.885696) (xy 67.745333 -382.91074) (xy 67.735113 -382.959897) (xy 67.71758 -383.006945)
			(xy 67.693136 -383.050801) (xy 67.662344 -383.090459) (xy 67.625911 -383.125006) (xy 67.584674 -383.153649)
			(xy 67.539581 -383.175729) (xy 67.491669 -383.190739) (xy 67.442038 -383.198334) (xy 67.416934 -383.198878)
			(xy 67.393162 -383.198461) (xy 67.346109 -383.191643) (xy 67.300517 -383.178156) (xy 67.257328 -383.158278)
			(xy 67.21743 -383.13242) (xy 67.199256 -383.11709) (xy 67.192133 -383.111412) (xy 67.175083 -383.105039)
			(xy 67.165982 -383.104644) (xy 67.134486 -383.104644) (xy 67.125384 -383.105025) (xy 67.108337 -383.111412)
			(xy 67.101212 -383.11709) (xy 67.083051 -383.132436) (xy 67.043154 -383.158298) (xy 66.999961 -383.17817)
			(xy 66.954365 -383.191643) (xy 66.907307 -383.198438) (xy 66.883534 -383.198878) (xy 66.856666 -383.198347)
			(xy 66.803639 -383.189645) (xy 66.752717 -383.172481) (xy 66.705242 -383.147307) (xy 66.662464 -383.114786)
			(xy 66.625509 -383.075774) (xy 66.609976 -383.053844) (xy 66.603372 -383.044446) (xy 66.584068 -383.033016)
			(xy 66.49466 -383.02438) (xy 66.483439 -383.023949) (xy 66.462349 -383.031583) (xy 66.45402 -383.039112)
			(xy 65.864994 -383.628138) (xy 65.857598 -383.63499) (xy 65.838999 -383.642732) (xy 65.828926 -383.643124)
			(xy 57.931558 -383.643124) (xy 57.921492 -383.643555) (xy 57.902901 -383.651283) (xy 57.89549 -383.65811)
			(xy 57.622186 -383.931414) (xy 57.615332 -383.938809) (xy 57.60759 -383.957408) (xy 57.6072 -383.967482)
			(xy 57.6072 -384.643709) (xy 57.932322 -384.643709) (xy 57.932322 -384.591735) (xy 57.940452 -384.5404)
			(xy 57.956513 -384.49097) (xy 57.980109 -384.44466) (xy 58.010659 -384.402612) (xy 58.04741 -384.365861)
			(xy 58.089458 -384.335311) (xy 58.135768 -384.311715) (xy 58.185198 -384.295654) (xy 58.236533 -384.287524)
			(xy 58.288507 -384.287524) (xy 58.339842 -384.295654) (xy 58.389272 -384.311715) (xy 58.435582 -384.335311)
			(xy 58.47763 -384.365861) (xy 58.514381 -384.402612) (xy 58.544931 -384.44466) (xy 58.568527 -384.49097)
			(xy 58.584588 -384.5404) (xy 58.592718 -384.591735) (xy 58.593228 -384.617722) (xy 58.592718 -384.643709)
			(xy 59.132218 -384.643709) (xy 59.132218 -384.591735) (xy 59.140348 -384.5404) (xy 59.156409 -384.49097)
			(xy 59.180005 -384.44466) (xy 59.210555 -384.402612) (xy 59.247306 -384.365861) (xy 59.289354 -384.335311)
			(xy 59.335664 -384.311715) (xy 59.385094 -384.295654) (xy 59.436429 -384.287524) (xy 59.488403 -384.287524)
			(xy 59.539738 -384.295654) (xy 59.589168 -384.311715) (xy 59.635478 -384.335311) (xy 59.677526 -384.365861)
			(xy 59.714277 -384.402612) (xy 59.744827 -384.44466) (xy 59.768423 -384.49097) (xy 59.784484 -384.5404)
			(xy 59.792614 -384.591735) (xy 59.793124 -384.617722) (xy 59.792614 -384.643709) (xy 60.332114 -384.643709)
			(xy 60.332114 -384.591735) (xy 60.340244 -384.5404) (xy 60.356305 -384.49097) (xy 60.379901 -384.44466)
			(xy 60.410451 -384.402612) (xy 60.447202 -384.365861) (xy 60.48925 -384.335311) (xy 60.53556 -384.311715)
			(xy 60.58499 -384.295654) (xy 60.636325 -384.287524) (xy 60.688299 -384.287524) (xy 60.739634 -384.295654)
			(xy 60.789064 -384.311715) (xy 60.835374 -384.335311) (xy 60.877422 -384.365861) (xy 60.914173 -384.402612)
			(xy 60.944723 -384.44466) (xy 60.968319 -384.49097) (xy 60.98438 -384.5404) (xy 60.99251 -384.591735)
			(xy 60.99302 -384.617722) (xy 60.99251 -384.643709) (xy 61.532264 -384.643709) (xy 61.532264 -384.591735)
			(xy 61.540394 -384.5404) (xy 61.556455 -384.49097) (xy 61.580051 -384.44466) (xy 61.610601 -384.402612)
			(xy 61.647352 -384.365861) (xy 61.6894 -384.335311) (xy 61.73571 -384.311715) (xy 61.78514 -384.295654)
			(xy 61.836475 -384.287524) (xy 61.888449 -384.287524) (xy 61.939784 -384.295654) (xy 61.989214 -384.311715)
			(xy 62.035524 -384.335311) (xy 62.077572 -384.365861) (xy 62.114323 -384.402612) (xy 62.144873 -384.44466)
			(xy 62.168469 -384.49097) (xy 62.18453 -384.5404) (xy 62.19266 -384.591735) (xy 62.19317 -384.617722)
			(xy 62.19266 -384.643709) (xy 62.73216 -384.643709) (xy 62.73216 -384.591735) (xy 62.74029 -384.5404)
			(xy 62.756351 -384.49097) (xy 62.779947 -384.44466) (xy 62.810497 -384.402612) (xy 62.847248 -384.365861)
			(xy 62.889296 -384.335311) (xy 62.935606 -384.311715) (xy 62.985036 -384.295654) (xy 63.036371 -384.287524)
			(xy 63.088345 -384.287524) (xy 63.13968 -384.295654) (xy 63.18911 -384.311715) (xy 63.23542 -384.335311)
			(xy 63.277468 -384.365861) (xy 63.314219 -384.402612) (xy 63.344769 -384.44466) (xy 63.368365 -384.49097)
			(xy 63.384426 -384.5404) (xy 63.392556 -384.591735) (xy 63.393066 -384.617722) (xy 63.392556 -384.643709)
			(xy 63.93231 -384.643709) (xy 63.93231 -384.591735) (xy 63.94044 -384.5404) (xy 63.956501 -384.49097)
			(xy 63.980097 -384.44466) (xy 64.010647 -384.402612) (xy 64.047398 -384.365861) (xy 64.089446 -384.335311)
			(xy 64.135756 -384.311715) (xy 64.185186 -384.295654) (xy 64.236521 -384.287524) (xy 64.288495 -384.287524)
			(xy 64.33983 -384.295654) (xy 64.38926 -384.311715) (xy 64.43557 -384.335311) (xy 64.477618 -384.365861)
			(xy 64.514369 -384.402612) (xy 64.544919 -384.44466) (xy 64.568515 -384.49097) (xy 64.584576 -384.5404)
			(xy 64.592706 -384.591735) (xy 64.593216 -384.617722) (xy 64.592706 -384.643709) (xy 65.132206 -384.643709)
			(xy 65.132206 -384.591735) (xy 65.140336 -384.5404) (xy 65.156397 -384.49097) (xy 65.179993 -384.44466)
			(xy 65.210543 -384.402612) (xy 65.247294 -384.365861) (xy 65.289342 -384.335311) (xy 65.335652 -384.311715)
			(xy 65.385082 -384.295654) (xy 65.436417 -384.287524) (xy 65.488391 -384.287524) (xy 65.539726 -384.295654)
			(xy 65.589156 -384.311715) (xy 65.635466 -384.335311) (xy 65.677514 -384.365861) (xy 65.714265 -384.402612)
			(xy 65.744815 -384.44466) (xy 65.768411 -384.49097) (xy 65.784472 -384.5404) (xy 65.792602 -384.591735)
			(xy 65.793112 -384.617722) (xy 65.792602 -384.643709) (xy 65.784472 -384.695044) (xy 65.768411 -384.744474)
			(xy 65.744815 -384.790784) (xy 65.714265 -384.832832) (xy 65.677514 -384.869583) (xy 65.635466 -384.900133)
			(xy 65.589156 -384.923729) (xy 65.539726 -384.93979) (xy 65.488391 -384.94792) (xy 65.436417 -384.94792)
			(xy 65.385082 -384.93979) (xy 65.335652 -384.923729) (xy 65.289342 -384.900133) (xy 65.247294 -384.869583)
			(xy 65.210543 -384.832832) (xy 65.179993 -384.790784) (xy 65.156397 -384.744474) (xy 65.140336 -384.695044)
			(xy 65.132206 -384.643709) (xy 64.592706 -384.643709) (xy 64.584576 -384.695044) (xy 64.568515 -384.744474)
			(xy 64.544919 -384.790784) (xy 64.514369 -384.832832) (xy 64.477618 -384.869583) (xy 64.43557 -384.900133)
			(xy 64.38926 -384.923729) (xy 64.33983 -384.93979) (xy 64.288495 -384.94792) (xy 64.236521 -384.94792)
			(xy 64.185186 -384.93979) (xy 64.135756 -384.923729) (xy 64.089446 -384.900133) (xy 64.047398 -384.869583)
			(xy 64.010647 -384.832832) (xy 63.980097 -384.790784) (xy 63.956501 -384.744474) (xy 63.94044 -384.695044)
			(xy 63.93231 -384.643709) (xy 63.392556 -384.643709) (xy 63.384426 -384.695044) (xy 63.368365 -384.744474)
			(xy 63.344769 -384.790784) (xy 63.314219 -384.832832) (xy 63.277468 -384.869583) (xy 63.23542 -384.900133)
			(xy 63.18911 -384.923729) (xy 63.13968 -384.93979) (xy 63.088345 -384.94792) (xy 63.036371 -384.94792)
			(xy 62.985036 -384.93979) (xy 62.935606 -384.923729) (xy 62.889296 -384.900133) (xy 62.847248 -384.869583)
			(xy 62.810497 -384.832832) (xy 62.779947 -384.790784) (xy 62.756351 -384.744474) (xy 62.74029 -384.695044)
			(xy 62.73216 -384.643709) (xy 62.19266 -384.643709) (xy 62.18453 -384.695044) (xy 62.168469 -384.744474)
			(xy 62.144873 -384.790784) (xy 62.114323 -384.832832) (xy 62.077572 -384.869583) (xy 62.035524 -384.900133)
			(xy 61.989214 -384.923729) (xy 61.939784 -384.93979) (xy 61.888449 -384.94792) (xy 61.836475 -384.94792)
			(xy 61.78514 -384.93979) (xy 61.73571 -384.923729) (xy 61.6894 -384.900133) (xy 61.647352 -384.869583)
			(xy 61.610601 -384.832832) (xy 61.580051 -384.790784) (xy 61.556455 -384.744474) (xy 61.540394 -384.695044)
			(xy 61.532264 -384.643709) (xy 60.99251 -384.643709) (xy 60.98438 -384.695044) (xy 60.968319 -384.744474)
			(xy 60.944723 -384.790784) (xy 60.914173 -384.832832) (xy 60.877422 -384.869583) (xy 60.835374 -384.900133)
			(xy 60.789064 -384.923729) (xy 60.739634 -384.93979) (xy 60.688299 -384.94792) (xy 60.636325 -384.94792)
			(xy 60.58499 -384.93979) (xy 60.53556 -384.923729) (xy 60.48925 -384.900133) (xy 60.447202 -384.869583)
			(xy 60.410451 -384.832832) (xy 60.379901 -384.790784) (xy 60.356305 -384.744474) (xy 60.340244 -384.695044)
			(xy 60.332114 -384.643709) (xy 59.792614 -384.643709) (xy 59.784484 -384.695044) (xy 59.768423 -384.744474)
			(xy 59.744827 -384.790784) (xy 59.714277 -384.832832) (xy 59.677526 -384.869583) (xy 59.635478 -384.900133)
			(xy 59.589168 -384.923729) (xy 59.539738 -384.93979) (xy 59.488403 -384.94792) (xy 59.436429 -384.94792)
			(xy 59.385094 -384.93979) (xy 59.335664 -384.923729) (xy 59.289354 -384.900133) (xy 59.247306 -384.869583)
			(xy 59.210555 -384.832832) (xy 59.180005 -384.790784) (xy 59.156409 -384.744474) (xy 59.140348 -384.695044)
			(xy 59.132218 -384.643709) (xy 58.592718 -384.643709) (xy 58.584588 -384.695044) (xy 58.568527 -384.744474)
			(xy 58.544931 -384.790784) (xy 58.514381 -384.832832) (xy 58.47763 -384.869583) (xy 58.435582 -384.900133)
			(xy 58.389272 -384.923729) (xy 58.339842 -384.93979) (xy 58.288507 -384.94792) (xy 58.236533 -384.94792)
			(xy 58.185198 -384.93979) (xy 58.135768 -384.923729) (xy 58.089458 -384.900133) (xy 58.04741 -384.869583)
			(xy 58.010659 -384.832832) (xy 57.980109 -384.790784) (xy 57.956513 -384.744474) (xy 57.940452 -384.695044)
			(xy 57.932322 -384.643709) (xy 57.6072 -384.643709) (xy 57.6072 -385.037584) (xy 57.607657 -385.047736)
			(xy 57.615527 -385.066455) (xy 57.62244 -385.073906) (xy 57.641031 -385.092811) (xy 57.672543 -385.135447)
			(xy 57.696842 -385.182569) (xy 57.713305 -385.232966) (xy 57.717944 -385.259072) (xy 57.719468 -385.26847)
			(xy 57.743694 -385.31038) (xy 58.260488 -385.31038) (xy 58.260983 -385.284392) (xy 58.269117 -385.233058)
			(xy 58.28518 -385.183627) (xy 58.308778 -385.137318) (xy 58.339329 -385.09527) (xy 58.376082 -385.058519)
			(xy 58.418132 -385.02797) (xy 58.464442 -385.004374) (xy 58.513873 -384.988313) (xy 58.565208 -384.980182)
			(xy 58.591196 -384.979672) (xy 58.617206 -384.980145) (xy 58.668583 -384.988303) (xy 58.718049 -385.004404)
			(xy 58.764385 -385.028049) (xy 58.806448 -385.058656) (xy 58.843201 -385.09547) (xy 58.873738 -385.137584)
			(xy 58.897307 -385.183959) (xy 58.913325 -385.233452) (xy 58.91784 -385.259072) (xy 58.919364 -385.26847)
			(xy 58.94359 -385.31038) (xy 59.460638 -385.31038) (xy 59.461057 -385.284388) (xy 59.469192 -385.233044)
			(xy 59.48526 -385.183605) (xy 59.508865 -385.137289) (xy 59.539424 -385.095236) (xy 59.576186 -385.058481)
			(xy 59.618246 -385.02793) (xy 59.664567 -385.004335) (xy 59.714008 -384.988277) (xy 59.765354 -384.980152)
			(xy 59.791346 -384.979672) (xy 59.817357 -384.9801) (xy 59.868736 -384.988265) (xy 59.918203 -385.004373)
			(xy 59.964539 -385.028024) (xy 60.006602 -385.058637) (xy 60.043355 -385.095457) (xy 60.073891 -385.137575)
			(xy 60.097458 -385.183954) (xy 60.113475 -385.233451) (xy 60.11799 -385.259072) (xy 60.119514 -385.26847)
			(xy 60.14374 -385.31038) (xy 60.660534 -385.31038) (xy 60.660957 -385.284388) (xy 60.669092 -385.233045)
			(xy 60.68516 -385.183606) (xy 60.708764 -385.13729) (xy 60.739323 -385.095237) (xy 60.776084 -385.058482)
			(xy 60.818143 -385.027931) (xy 60.864464 -385.004336) (xy 60.913905 -384.988278) (xy 60.96525 -384.980152)
			(xy 60.991242 -384.979672) (xy 61.017253 -384.980103) (xy 61.068632 -384.988268) (xy 61.118099 -385.004375)
			(xy 61.164435 -385.028026) (xy 61.206498 -385.058639) (xy 61.24325 -385.095458) (xy 61.273787 -385.137576)
			(xy 61.297354 -385.183955) (xy 61.313371 -385.233451) (xy 61.317886 -385.259072) (xy 61.31941 -385.26847)
			(xy 61.343636 -385.31038) (xy 61.860684 -385.31038) (xy 61.861183 -385.284393) (xy 61.869316 -385.233058)
			(xy 61.88538 -385.183628) (xy 61.908977 -385.137319) (xy 61.939528 -385.095272) (xy 61.976281 -385.058521)
			(xy 62.018329 -385.027971) (xy 62.064639 -385.004375) (xy 62.11407 -384.988314) (xy 62.165405 -384.980182)
			(xy 62.191392 -384.979672) (xy 62.217436 -384.98014) (xy 62.268876 -384.988327) (xy 62.3184 -385.004468)
			(xy 62.364785 -385.028165) (xy 62.406887 -385.058833) (xy 62.443668 -385.095716) (xy 62.474218 -385.137904)
			(xy 62.497786 -385.184355) (xy 62.513788 -385.233923) (xy 62.51829 -385.25958) (xy 62.51956 -385.268978)
			(xy 62.543496 -385.31038) (xy 63.06058 -385.31038) (xy 63.061083 -385.284393) (xy 63.069216 -385.233059)
			(xy 63.085279 -385.183629) (xy 63.108877 -385.13732) (xy 63.139427 -385.095273) (xy 63.176179 -385.058522)
			(xy 63.218227 -385.027972) (xy 63.264536 -385.004376) (xy 63.313967 -384.988314) (xy 63.365301 -384.980182)
			(xy 63.391288 -384.979672) (xy 63.417298 -384.980152) (xy 63.468674 -384.988309) (xy 63.51814 -385.004409)
			(xy 63.564476 -385.028053) (xy 63.606539 -385.058659) (xy 63.643293 -385.095473) (xy 63.67383 -385.137586)
			(xy 63.697398 -385.18396) (xy 63.713417 -385.233452) (xy 63.717932 -385.259072) (xy 63.719456 -385.26847)
			(xy 63.992252 -385.740402) (xy 63.999618 -385.746244) (xy 64.018403 -385.762037) (xy 64.05152 -385.798256)
			(xy 64.078928 -385.838967) (xy 64.100027 -385.883276) (xy 64.114356 -385.930214) (xy 64.121601 -385.978754)
			(xy 64.122046 -386.003292) (xy 64.121792 -386.015484) (xy 64.121538 -386.025136) (xy 64.127634 -386.04317)
			(xy 64.186308 -386.11048) (xy 64.203072 -386.119116) (xy 64.212978 -386.120132) (xy 64.239737 -386.123509)
			(xy 64.29176 -386.137728) (xy 64.340786 -386.1602) (xy 64.385516 -386.19033) (xy 64.424764 -386.227318)
			(xy 64.45749 -386.270184) (xy 64.482827 -386.317793) (xy 64.500103 -386.368882) (xy 64.50886 -386.422097)
			(xy 64.509396 -386.449062) (xy 64.508866 -386.476347) (xy 64.499911 -386.530178) (xy 64.482238 -386.581808)
			(xy 64.456327 -386.629834) (xy 64.422881 -386.672954) (xy 64.403224 -386.691886) (xy 64.39583 -386.699414)
			(xy 64.3873 -386.718689) (xy 64.386714 -386.729224) (xy 64.386714 -386.8039) (xy 64.387226 -386.814452)
			(xy 64.395773 -386.833747) (xy 64.403224 -386.841238) (xy 64.422862 -386.860186) (xy 64.456297 -386.903307)
			(xy 64.482202 -386.951331) (xy 64.499874 -387.002955) (xy 64.508835 -387.05678) (xy 64.509396 -387.084062)
			(xy 64.508955 -387.108179) (xy 64.501957 -387.155901) (xy 64.488105 -387.202103) (xy 64.467692 -387.245803)
			(xy 64.454786 -387.26618) (xy 64.448944 -387.27507) (xy 64.445388 -387.295136) (xy 64.46647 -387.387338)
			(xy 64.478662 -387.404102) (xy 64.487552 -387.409436) (xy 64.508357 -387.422285) (xy 64.546262 -387.453176)
			(xy 64.579203 -387.489313) (xy 64.606464 -387.529907) (xy 64.627449 -387.574073) (xy 64.6417 -387.620849)
			(xy 64.648907 -387.669213) (xy 64.64935 -387.693662) (xy 64.648947 -387.718036) (xy 64.6418 -387.766257)
			(xy 64.627655 -387.812908) (xy 64.606819 -387.856978) (xy 64.579742 -387.897515) (xy 64.54701 -387.933639)
			(xy 64.528446 -387.94944) (xy 64.519556 -387.956552) (xy 64.510158 -387.97611) (xy 64.507364 -388.075424)
			(xy 64.516 -388.09549) (xy 64.524382 -388.10311) (xy 64.542836 -388.120567) (xy 64.574181 -388.160539)
			(xy 64.598476 -388.205149) (xy 64.615052 -388.253166) (xy 64.623451 -388.303263) (xy 64.62395 -388.328662)
			(xy 64.623881 -388.338021) (xy 64.622738 -388.356703) (xy 64.621664 -388.366) (xy 64.620648 -388.37489)
			(xy 64.624458 -388.391654) (xy 64.6684 -388.461504) (xy 64.682116 -388.471918) (xy 64.690498 -388.474712)
			(xy 64.714595 -388.483193) (xy 64.759886 -388.506818) (xy 64.800781 -388.537429) (xy 64.836213 -388.574226)
			(xy 64.865256 -388.616249) (xy 64.887152 -388.662401) (xy 64.894714 -388.686802) (xy 64.896238 -388.692644)
			(xy 65.216024 -389.245602) (xy 65.220088 -389.24992) (xy 65.236278 -389.26764) (xy 65.263704 -389.307028)
			(xy 65.28485 -389.350114) (xy 65.299227 -389.395906) (xy 65.306504 -389.443346) (xy 65.306956 -389.467344)
			(xy 65.306547 -389.49215) (xy 65.298775 -389.54115) (xy 65.283431 -389.58833) (xy 65.260892 -389.632527)
			(xy 65.231714 -389.672651) (xy 65.196615 -389.707715) (xy 65.156462 -389.736854) (xy 65.112243 -389.75935)
			(xy 65.065048 -389.774648) (xy 65.016041 -389.782371) (xy 64.991234 -389.782812) (xy 64.965841 -389.782282)
			(xy 64.915708 -389.774156) (xy 64.867524 -389.75811) (xy 64.822529 -389.734556) (xy 64.781886 -389.704103)
			(xy 64.746643 -389.667535) (xy 64.717708 -389.625797) (xy 64.695829 -389.579965) (xy 64.688212 -389.555736)
			(xy 64.686688 -389.549894) (xy 64.36614 -388.995412) (xy 64.362076 -388.991094) (xy 64.345977 -388.973421)
			(xy 64.318727 -388.934143) (xy 64.297715 -388.891204) (xy 64.283422 -388.845586) (xy 64.276175 -388.798334)
			(xy 64.275716 -388.774432) (xy 64.275858 -388.76238) (xy 64.277764 -388.73835) (xy 64.279526 -388.726426)
			(xy 64.280796 -388.717536) (xy 64.277748 -388.700518) (xy 64.235584 -388.629652) (xy 64.222376 -388.618476)
			(xy 64.213994 -388.615428) (xy 64.192251 -388.60702) (xy 64.151392 -388.584582) (xy 64.114421 -388.556191)
			(xy 64.082197 -388.522508) (xy 64.055471 -388.484315) (xy 64.034864 -388.442503) (xy 64.020856 -388.398043)
			(xy 64.013772 -388.351969) (xy 64.013334 -388.328662) (xy 64.013849 -388.303266) (xy 64.022259 -388.253176)
			(xy 64.038841 -388.205168) (xy 64.063138 -388.160566) (xy 64.09448 -388.120598) (xy 64.112902 -388.10311)
			(xy 64.121284 -388.09549) (xy 64.12992 -388.075424) (xy 64.127126 -387.97611) (xy 64.117728 -387.956552)
			(xy 64.108838 -387.94944) (xy 64.090298 -387.933616) (xy 64.057578 -387.897489) (xy 64.030508 -387.856955)
			(xy 64.009675 -387.81289) (xy 63.995527 -387.766246) (xy 63.988372 -387.718033) (xy 63.987934 -387.693662)
			(xy 63.98835 -387.669545) (xy 63.995357 -387.621821) (xy 64.009217 -387.575621) (xy 64.029635 -387.531921)
			(xy 64.042544 -387.511544) (xy 64.048386 -387.502654) (xy 64.051942 -387.482588) (xy 64.03086 -387.390386)
			(xy 64.018668 -387.373622) (xy 64.009778 -387.368288) (xy 63.988991 -387.355412) (xy 63.951084 -387.324526)
			(xy 63.918141 -387.288395) (xy 63.890878 -387.247805) (xy 63.86989 -387.203643) (xy 63.855635 -387.156871)
			(xy 63.848425 -387.10851) (xy 63.84798 -387.084062) (xy 63.848533 -387.056778) (xy 63.857483 -387.002948)
			(xy 63.875151 -386.951319) (xy 63.901057 -386.903292) (xy 63.934498 -386.860171) (xy 63.954152 -386.841238)
			(xy 63.961532 -386.833698) (xy 63.97007 -386.814432) (xy 63.970662 -386.8039) (xy 63.970662 -386.729224)
			(xy 63.970145 -386.718673) (xy 63.961603 -386.699377) (xy 63.954152 -386.691886) (xy 63.934521 -386.672931)
			(xy 63.901087 -386.629811) (xy 63.875181 -386.581789) (xy 63.857507 -386.530167) (xy 63.848543 -386.476344)
			(xy 63.84798 -386.449062) (xy 63.848234 -386.43687) (xy 63.848488 -386.427218) (xy 63.842392 -386.409184)
			(xy 63.783718 -386.341874) (xy 63.766954 -386.333238) (xy 63.757048 -386.332222) (xy 63.73014 -386.32886)
			(xy 63.677854 -386.314494) (xy 63.62861 -386.291794) (xy 63.583728 -386.261367) (xy 63.544408 -386.224029)
			(xy 63.511704 -386.180778) (xy 63.486491 -386.132772) (xy 63.469444 -386.081298) (xy 63.464694 -386.0546)
			(xy 63.46317 -386.045202) (xy 63.190374 -385.57327) (xy 63.183008 -385.567428) (xy 63.164263 -385.551589)
			(xy 63.131143 -385.51538) (xy 63.103729 -385.47468) (xy 63.082622 -385.430379) (xy 63.068285 -385.383448)
			(xy 63.061031 -385.334916) (xy 63.06058 -385.31038) (xy 62.543496 -385.31038) (xy 62.792102 -385.740402)
			(xy 62.799468 -385.746244) (xy 62.818263 -385.762025) (xy 62.851377 -385.798248) (xy 62.878783 -385.838961)
			(xy 62.89988 -385.883273) (xy 62.914207 -385.930213) (xy 62.921451 -385.978753) (xy 62.921896 -386.003292)
			(xy 62.921642 -386.015484) (xy 62.921388 -386.025136) (xy 62.927484 -386.04317) (xy 62.986158 -386.11048)
			(xy 63.002922 -386.119116) (xy 63.012828 -386.120132) (xy 63.039593 -386.123468) (xy 63.091616 -386.137695)
			(xy 63.140642 -386.160174) (xy 63.185371 -386.190309) (xy 63.224618 -386.227302) (xy 63.257343 -386.270173)
			(xy 63.282679 -386.317785) (xy 63.299954 -386.368877) (xy 63.308711 -386.422095) (xy 63.309246 -386.449062)
			(xy 63.3087 -386.476347) (xy 63.299747 -386.530176) (xy 63.282077 -386.581805) (xy 63.256169 -386.629831)
			(xy 63.222728 -386.672953) (xy 63.203074 -386.691886) (xy 63.195687 -386.699421) (xy 63.187152 -386.71869)
			(xy 63.186564 -386.729224) (xy 63.186564 -386.8039) (xy 63.18709 -386.81445) (xy 63.195629 -386.833744)
			(xy 63.203074 -386.841238) (xy 63.222721 -386.860176) (xy 63.256153 -386.903302) (xy 63.282055 -386.951328)
			(xy 63.299725 -387.002954) (xy 63.308685 -387.056779) (xy 63.309246 -387.084062) (xy 63.308797 -387.108178)
			(xy 63.3018 -387.1559) (xy 63.287951 -387.202101) (xy 63.267541 -387.245802) (xy 63.254636 -387.26618)
			(xy 63.248794 -387.27507) (xy 63.245238 -387.295136) (xy 63.26632 -387.387338) (xy 63.278512 -387.404102)
			(xy 63.287402 -387.409436) (xy 63.308196 -387.422303) (xy 63.346103 -387.453189) (xy 63.379047 -387.489322)
			(xy 63.40631 -387.529913) (xy 63.427296 -387.574077) (xy 63.441549 -387.620851) (xy 63.448757 -387.669214)
			(xy 63.4492 -387.693662) (xy 63.448779 -387.718035) (xy 63.441633 -387.766255) (xy 63.427491 -387.812904)
			(xy 63.406658 -387.856974) (xy 63.379584 -387.897511) (xy 63.346857 -387.933638) (xy 63.328296 -387.94944)
			(xy 63.319406 -387.956552) (xy 63.310008 -387.97611) (xy 63.307214 -388.075424) (xy 63.31585 -388.09549)
			(xy 63.324232 -388.10311) (xy 63.342676 -388.120577) (xy 63.374025 -388.160546) (xy 63.398323 -388.205153)
			(xy 63.4149 -388.253167) (xy 63.4233 -388.303264) (xy 63.4238 -388.328662) (xy 63.423732 -388.338021)
			(xy 63.422588 -388.356703) (xy 63.421514 -388.366) (xy 63.420498 -388.37489) (xy 63.424308 -388.391654)
			(xy 63.46825 -388.461504) (xy 63.481966 -388.471918) (xy 63.490348 -388.474712) (xy 63.514378 -388.483175)
			(xy 63.55955 -388.506729) (xy 63.600355 -388.53723) (xy 63.635734 -388.573886) (xy 63.664769 -388.615746)
			(xy 63.686707 -388.661724) (xy 63.69431 -388.68604) (xy 63.695834 -388.691882) (xy 64.016128 -389.245602)
			(xy 64.020192 -389.24992) (xy 64.036382 -389.26764) (xy 64.063809 -389.307027) (xy 64.084954 -389.350114)
			(xy 64.099331 -389.395906) (xy 64.106608 -389.443346) (xy 64.10706 -389.467344) (xy 64.106647 -389.49215)
			(xy 64.098875 -389.541149) (xy 64.083531 -389.588329) (xy 64.060993 -389.632525) (xy 64.031815 -389.67265)
			(xy 63.996717 -389.707714) (xy 63.956564 -389.736853) (xy 63.912346 -389.759349) (xy 63.865151 -389.774647)
			(xy 63.816144 -389.782371) (xy 63.791338 -389.782812) (xy 63.765945 -389.782278) (xy 63.715813 -389.774153)
			(xy 63.667628 -389.758107) (xy 63.622634 -389.734554) (xy 63.58199 -389.704101) (xy 63.546747 -389.667534)
			(xy 63.517812 -389.625797) (xy 63.495933 -389.579965) (xy 63.488316 -389.555736) (xy 63.486792 -389.549894)
			(xy 63.166498 -388.996174) (xy 63.162434 -388.991856) (xy 63.146271 -388.974125) (xy 63.118904 -388.934722)
			(xy 63.097815 -388.891631) (xy 63.083488 -388.845846) (xy 63.076254 -388.79842) (xy 63.07582 -388.774432)
			(xy 63.075901 -388.762384) (xy 63.077683 -388.738355) (xy 63.079376 -388.726426) (xy 63.080646 -388.717536)
			(xy 63.077598 -388.700518) (xy 63.035434 -388.629652) (xy 63.022226 -388.618476) (xy 63.013844 -388.615428)
			(xy 62.992091 -388.607047) (xy 62.951233 -388.584603) (xy 62.914263 -388.556207) (xy 62.882042 -388.522519)
			(xy 62.855317 -388.484323) (xy 62.834712 -388.442508) (xy 62.820705 -388.398046) (xy 62.813622 -388.35197)
			(xy 62.813184 -388.328662) (xy 62.813715 -388.303267) (xy 62.822124 -388.253179) (xy 62.838703 -388.205172)
			(xy 62.862996 -388.160569) (xy 62.894333 -388.120599) (xy 62.912752 -388.10311) (xy 62.921134 -388.09549)
			(xy 62.92977 -388.075424) (xy 62.926976 -387.97611) (xy 62.917578 -387.956552) (xy 62.908688 -387.94944)
			(xy 62.890158 -387.933604) (xy 62.857435 -387.897481) (xy 62.830363 -387.85695) (xy 62.809527 -387.812887)
			(xy 62.795378 -387.766245) (xy 62.788222 -387.718032) (xy 62.787784 -387.693662) (xy 62.788192 -387.669544)
			(xy 62.7952 -387.62182) (xy 62.809062 -387.575619) (xy 62.829484 -387.53192) (xy 62.842394 -387.511544)
			(xy 62.848236 -387.502654) (xy 62.851792 -387.482588) (xy 62.83071 -387.390386) (xy 62.818518 -387.373622)
			(xy 62.809628 -387.368288) (xy 62.788829 -387.35543) (xy 62.750926 -387.32454) (xy 62.717984 -387.288404)
			(xy 62.690724 -387.247811) (xy 62.669738 -387.203646) (xy 62.655485 -387.156873) (xy 62.648275 -387.10851)
			(xy 62.64783 -387.084062) (xy 62.648367 -387.056777) (xy 62.657319 -387.002946) (xy 62.67499 -386.951316)
			(xy 62.7009 -386.903289) (xy 62.734345 -386.86017) (xy 62.754002 -386.841238) (xy 62.761389 -386.833704)
			(xy 62.769922 -386.814433) (xy 62.770512 -386.8039) (xy 62.770512 -386.729224) (xy 62.76998 -386.718675)
			(xy 62.761446 -386.69938) (xy 62.754002 -386.691886) (xy 62.73438 -386.672922) (xy 62.700943 -386.629805)
			(xy 62.675034 -386.581786) (xy 62.657358 -386.530165) (xy 62.648393 -386.476343) (xy 62.64783 -386.449062)
			(xy 62.648084 -386.43687) (xy 62.648338 -386.427218) (xy 62.642242 -386.409184) (xy 62.583568 -386.341874)
			(xy 62.566804 -386.333238) (xy 62.556898 -386.332222) (xy 62.529995 -386.32882) (xy 62.47771 -386.314462)
			(xy 62.428467 -386.291769) (xy 62.383583 -386.261349) (xy 62.344263 -386.224015) (xy 62.311557 -386.180769)
			(xy 62.286342 -386.132768) (xy 62.269294 -386.081297) (xy 62.264544 -386.0546) (xy 62.26302 -386.045202)
			(xy 61.98997 -385.572762) (xy 61.982858 -385.56692) (xy 61.964118 -385.551149) (xy 61.931065 -385.515005)
			(xy 61.90371 -385.474377) (xy 61.882653 -385.430156) (xy 61.868354 -385.383312) (xy 61.861127 -385.334869)
			(xy 61.860684 -385.31038) (xy 61.343636 -385.31038) (xy 61.592206 -385.740402) (xy 61.599572 -385.746244)
			(xy 61.618368 -385.762024) (xy 61.651482 -385.798248) (xy 61.678887 -385.838961) (xy 61.699984 -385.883273)
			(xy 61.714311 -385.930213) (xy 61.721555 -385.978753) (xy 61.722 -386.003292) (xy 61.721746 -386.015484)
			(xy 61.721492 -386.025136) (xy 61.727588 -386.04317) (xy 61.786262 -386.11048) (xy 61.803026 -386.119116)
			(xy 61.812932 -386.120132) (xy 61.839697 -386.123465) (xy 61.891721 -386.137692) (xy 61.940747 -386.160172)
			(xy 61.985476 -386.190308) (xy 62.024722 -386.227301) (xy 62.057447 -386.270172) (xy 62.082783 -386.317785)
			(xy 62.100058 -386.368877) (xy 62.108815 -386.422095) (xy 62.10935 -386.449062) (xy 62.108803 -386.476346)
			(xy 62.09985 -386.530176) (xy 62.08218 -386.581804) (xy 62.056273 -386.629831) (xy 62.022832 -386.672953)
			(xy 62.003178 -386.691886) (xy 61.995777 -386.699408) (xy 61.987253 -386.718688) (xy 61.986668 -386.729224)
			(xy 61.986668 -386.8039) (xy 61.987193 -386.81445) (xy 61.995732 -386.833745) (xy 62.003178 -386.841238)
			(xy 62.022826 -386.860176) (xy 62.056257 -386.903301) (xy 62.082159 -386.951328) (xy 62.099829 -387.002954)
			(xy 62.108789 -387.056779) (xy 62.10935 -387.084062) (xy 62.1089 -387.108178) (xy 62.101904 -387.1559)
			(xy 62.088054 -387.202101) (xy 62.067644 -387.245802) (xy 62.05474 -387.26618) (xy 62.048898 -387.27507)
			(xy 62.045342 -387.295136) (xy 62.066424 -387.387338) (xy 62.078616 -387.404102) (xy 62.087506 -387.409436)
			(xy 62.108301 -387.422301) (xy 62.146207 -387.453188) (xy 62.179151 -387.489321) (xy 62.206414 -387.529913)
			(xy 62.227401 -387.574077) (xy 62.241653 -387.620851) (xy 62.248861 -387.669214) (xy 62.249304 -387.693662)
			(xy 62.248882 -387.718035) (xy 62.241736 -387.766255) (xy 62.227594 -387.812904) (xy 62.206761 -387.856974)
			(xy 62.179688 -387.897511) (xy 62.146961 -387.933638) (xy 62.1284 -387.94944) (xy 62.11951 -387.956552)
			(xy 62.110112 -387.97611) (xy 62.107318 -388.075424) (xy 62.115954 -388.09549) (xy 62.124336 -388.10311)
			(xy 62.142781 -388.120576) (xy 62.174129 -388.160545) (xy 62.198427 -388.205153) (xy 62.215004 -388.253167)
			(xy 62.223404 -388.303264) (xy 62.223904 -388.328662) (xy 62.223835 -388.338021) (xy 62.222692 -388.356703)
			(xy 62.221618 -388.366) (xy 62.220602 -388.37489) (xy 62.224412 -388.391654) (xy 62.268354 -388.461504)
			(xy 62.28207 -388.471918) (xy 62.290452 -388.474712) (xy 62.31454 -388.483218) (xy 62.359832 -388.506836)
			(xy 62.400729 -388.537442) (xy 62.436162 -388.574234) (xy 62.465207 -388.616253) (xy 62.487105 -388.662402)
			(xy 62.494668 -388.686802) (xy 62.496192 -388.692644) (xy 62.815978 -389.245602) (xy 62.820042 -389.24992)
			(xy 62.836237 -389.267623) (xy 62.8636 -389.307033) (xy 62.884684 -389.350131) (xy 62.899003 -389.395923)
			(xy 62.906228 -389.443354) (xy 62.906656 -389.467344) (xy 62.906223 -389.492135) (xy 62.89846 -389.541107)
			(xy 62.883132 -389.588261) (xy 62.860617 -389.632438) (xy 62.831469 -389.672548) (xy 62.796405 -389.707605)
			(xy 62.75629 -389.736746) (xy 62.712109 -389.759254) (xy 62.664952 -389.774573) (xy 62.615979 -389.782327)
			(xy 62.591188 -389.782812) (xy 62.565793 -389.782322) (xy 62.515659 -389.77419) (xy 62.467473 -389.758136)
			(xy 62.422479 -389.734576) (xy 62.381836 -389.704118) (xy 62.346594 -389.667545) (xy 62.31766 -389.625803)
			(xy 62.295782 -389.579967) (xy 62.288166 -389.555736) (xy 62.286642 -389.549894) (xy 61.966094 -388.995412)
			(xy 61.96203 -388.991094) (xy 61.945927 -388.973437) (xy 61.91874 -388.934136) (xy 61.897789 -388.891186)
			(xy 61.883554 -388.845569) (xy 61.876359 -388.798326) (xy 61.875924 -388.774432) (xy 61.876005 -388.762384)
			(xy 61.877787 -388.738355) (xy 61.87948 -388.726426) (xy 61.88075 -388.717536) (xy 61.877702 -388.700518)
			(xy 61.835538 -388.629652) (xy 61.82233 -388.618476) (xy 61.813948 -388.615428) (xy 61.792195 -388.607045)
			(xy 61.751338 -388.584601) (xy 61.714368 -388.556205) (xy 61.682146 -388.522518) (xy 61.655422 -388.484323)
			(xy 61.634816 -388.442508) (xy 61.620809 -388.398045) (xy 61.613726 -388.35197) (xy 61.613288 -388.328662)
			(xy 61.613818 -388.303267) (xy 61.622226 -388.253179) (xy 61.638806 -388.205171) (xy 61.663099 -388.160568)
			(xy 61.694437 -388.120599) (xy 61.712856 -388.10311) (xy 61.721238 -388.09549) (xy 61.729874 -388.075424)
			(xy 61.72708 -387.97611) (xy 61.717682 -387.956552) (xy 61.708792 -387.94944) (xy 61.690263 -387.933603)
			(xy 61.65754 -387.89748) (xy 61.630467 -387.856949) (xy 61.609631 -387.812887) (xy 61.595482 -387.766245)
			(xy 61.588326 -387.718032) (xy 61.587888 -387.693662) (xy 61.588296 -387.669544) (xy 61.595304 -387.62182)
			(xy 61.609165 -387.575619) (xy 61.629587 -387.53192) (xy 61.642498 -387.511544) (xy 61.64834 -387.502654)
			(xy 61.651896 -387.482588) (xy 61.630814 -387.390386) (xy 61.618622 -387.373622) (xy 61.609732 -387.368288)
			(xy 61.588934 -387.355429) (xy 61.55103 -387.324538) (xy 61.518089 -387.288403) (xy 61.490828 -387.247811)
			(xy 61.469842 -387.203646) (xy 61.455589 -387.156873) (xy 61.448379 -387.10851) (xy 61.447934 -387.084062)
			(xy 61.448502 -387.056778) (xy 61.457451 -387.00295) (xy 61.475116 -386.951322) (xy 61.501018 -386.903295)
			(xy 61.534454 -386.860172) (xy 61.554106 -386.841238) (xy 61.561494 -386.833705) (xy 61.570026 -386.814434)
			(xy 61.570616 -386.8039) (xy 61.570616 -386.729224) (xy 61.570082 -386.718675) (xy 61.56155 -386.69938)
			(xy 61.554106 -386.691886) (xy 61.534467 -386.67294) (xy 61.501035 -386.629816) (xy 61.475132 -386.581792)
			(xy 61.45746 -386.530168) (xy 61.448497 -386.476344) (xy 61.447934 -386.449062) (xy 61.448188 -386.43687)
			(xy 61.448442 -386.427218) (xy 61.442346 -386.409184) (xy 61.383672 -386.341874) (xy 61.366908 -386.333238)
			(xy 61.357002 -386.332222) (xy 61.3301 -386.328817) (xy 61.277815 -386.31446) (xy 61.228571 -386.291767)
			(xy 61.183688 -386.261347) (xy 61.144367 -386.224014) (xy 61.111661 -386.180768) (xy 61.086447 -386.132767)
			(xy 61.069398 -386.081296) (xy 61.064648 -386.0546) (xy 61.063124 -386.045202) (xy 60.790328 -385.57327)
			(xy 60.782962 -385.567428) (xy 60.764207 -385.5516) (xy 60.73109 -385.515388) (xy 60.703678 -385.474685)
			(xy 60.682574 -385.430382) (xy 60.668238 -385.38345) (xy 60.660984 -385.334916) (xy 60.660534 -385.31038)
			(xy 60.14374 -385.31038) (xy 60.39231 -385.740402) (xy 60.399676 -385.746244) (xy 60.418452 -385.762047)
			(xy 60.451571 -385.798263) (xy 60.478981 -385.838971) (xy 60.500083 -385.883279) (xy 60.514413 -385.930216)
			(xy 60.521658 -385.978754) (xy 60.522104 -386.003292) (xy 60.52185 -386.015484) (xy 60.521596 -386.025136)
			(xy 60.527692 -386.04317) (xy 60.586366 -386.11048) (xy 60.60313 -386.119116) (xy 60.612782 -386.120132)
			(xy 60.639542 -386.123506) (xy 60.691565 -386.137726) (xy 60.74059 -386.160198) (xy 60.78532 -386.190328)
			(xy 60.824568 -386.227317) (xy 60.857294 -386.270183) (xy 60.882631 -386.317792) (xy 60.899907 -386.368881)
			(xy 60.908664 -386.422097) (xy 60.9092 -386.449062) (xy 60.908669 -386.476347) (xy 60.899714 -386.530178)
			(xy 60.882041 -386.581808) (xy 60.85613 -386.629834) (xy 60.822685 -386.672954) (xy 60.803028 -386.691886)
			(xy 60.795635 -386.699415) (xy 60.787104 -386.718689) (xy 60.786518 -386.729224) (xy 60.786518 -386.8039)
			(xy 60.787028 -386.814452) (xy 60.795576 -386.833747) (xy 60.803028 -386.841238) (xy 60.822667 -386.860185)
			(xy 60.856101 -386.903307) (xy 60.882006 -386.951331) (xy 60.899678 -387.002955) (xy 60.908639 -387.056779)
			(xy 60.9092 -387.084062) (xy 60.908758 -387.108179) (xy 60.901761 -387.155901) (xy 60.887909 -387.202102)
			(xy 60.867496 -387.245803) (xy 60.85459 -387.26618) (xy 60.848748 -387.27507) (xy 60.845192 -387.295136)
			(xy 60.866274 -387.387338) (xy 60.878466 -387.404102) (xy 60.887356 -387.409436) (xy 60.908162 -387.422283)
			(xy 60.946066 -387.453175) (xy 60.979008 -387.489312) (xy 61.006268 -387.529907) (xy 61.027253 -387.574073)
			(xy 61.041504 -387.620849) (xy 61.048711 -387.669213) (xy 61.049154 -387.693662) (xy 61.04875 -387.718036)
			(xy 61.041603 -387.766257) (xy 61.027458 -387.812908) (xy 61.006622 -387.856978) (xy 60.979545 -387.897514)
			(xy 60.946814 -387.933639) (xy 60.92825 -387.94944) (xy 60.91936 -387.956552) (xy 60.909962 -387.97611)
			(xy 60.907168 -388.075424) (xy 60.915804 -388.09549) (xy 60.924186 -388.10311) (xy 60.942641 -388.120566)
			(xy 60.973985 -388.160539) (xy 60.998281 -388.205149) (xy 61.014856 -388.253166) (xy 61.023255 -388.303263)
			(xy 61.023754 -388.328662) (xy 61.023685 -388.338021) (xy 61.022542 -388.356703) (xy 61.021468 -388.366)
			(xy 61.020452 -388.37489) (xy 61.024262 -388.391654) (xy 61.068204 -388.461504) (xy 61.08192 -388.471918)
			(xy 61.090302 -388.474712) (xy 61.114323 -388.4832) (xy 61.159496 -388.506748) (xy 61.200302 -388.537243)
			(xy 61.235683 -388.573894) (xy 61.26472 -388.61575) (xy 61.28666 -388.661725) (xy 61.294264 -388.68604)
			(xy 61.295788 -388.691882) (xy 61.616082 -389.245602) (xy 61.620146 -389.24992) (xy 61.636342 -389.267622)
			(xy 61.663705 -389.307033) (xy 61.684789 -389.350131) (xy 61.699107 -389.395923) (xy 61.706332 -389.443354)
			(xy 61.70676 -389.467344) (xy 61.706323 -389.492135) (xy 61.69856 -389.541106) (xy 61.683233 -389.58826)
			(xy 61.660718 -389.632436) (xy 61.63157 -389.672547) (xy 61.596507 -389.707604) (xy 61.556392 -389.736745)
			(xy 61.512212 -389.759252) (xy 61.465056 -389.774572) (xy 61.416083 -389.782327) (xy 61.391292 -389.782812)
			(xy 61.365897 -389.782319) (xy 61.315763 -389.774187) (xy 61.267578 -389.758134) (xy 61.222583 -389.734575)
			(xy 61.181941 -389.704116) (xy 61.146698 -389.667544) (xy 61.117765 -389.625802) (xy 61.095887 -389.579967)
			(xy 61.08827 -389.555736) (xy 61.086746 -389.549894) (xy 60.766452 -388.996174) (xy 60.762388 -388.991856)
			(xy 60.746183 -388.974149) (xy 60.718759 -388.934758) (xy 60.697617 -388.891668) (xy 60.683243 -388.845874)
			(xy 60.67597 -388.798431) (xy 60.67552 -388.774432) (xy 60.675662 -388.76238) (xy 60.677568 -388.73835)
			(xy 60.67933 -388.726426) (xy 60.6806 -388.717536) (xy 60.677552 -388.700518) (xy 60.635388 -388.629652)
			(xy 60.62218 -388.618476) (xy 60.613798 -388.615428) (xy 60.592056 -388.607017) (xy 60.551197 -388.58458)
			(xy 60.514225 -388.55619) (xy 60.482001 -388.522507) (xy 60.455275 -388.484315) (xy 60.434668 -388.442503)
			(xy 60.42066 -388.398043) (xy 60.413576 -388.351969) (xy 60.413138 -388.328662) (xy 60.413652 -388.303266)
			(xy 60.422062 -388.253176) (xy 60.438644 -388.205168) (xy 60.462941 -388.160565) (xy 60.494284 -388.120598)
			(xy 60.512706 -388.10311) (xy 60.521088 -388.09549) (xy 60.529724 -388.075424) (xy 60.52693 -387.97611)
			(xy 60.517532 -387.956552) (xy 60.508642 -387.94944) (xy 60.490103 -387.933615) (xy 60.457382 -387.897488)
			(xy 60.430313 -387.856954) (xy 60.409479 -387.81289) (xy 60.395331 -387.766246) (xy 60.388176 -387.718033)
			(xy 60.387738 -387.693662) (xy 60.388154 -387.669545) (xy 60.395161 -387.621821) (xy 60.40902 -387.57562)
			(xy 60.429439 -387.531921) (xy 60.442348 -387.511544) (xy 60.44819 -387.502654) (xy 60.451746 -387.482588)
			(xy 60.430664 -387.390386) (xy 60.418472 -387.373622) (xy 60.409582 -387.368288) (xy 60.388795 -387.355411)
			(xy 60.350889 -387.324525) (xy 60.317945 -387.288394) (xy 60.290682 -387.247805) (xy 60.269694 -387.203642)
			(xy 60.255439 -387.156871) (xy 60.248229 -387.10851) (xy 60.247784 -387.084062) (xy 60.248336 -387.056778)
			(xy 60.257286 -387.002948) (xy 60.274955 -386.951319) (xy 60.300861 -386.903292) (xy 60.334302 -386.860171)
			(xy 60.353956 -386.841238) (xy 60.361336 -386.833698) (xy 60.369874 -386.814432) (xy 60.370466 -386.8039)
			(xy 60.370466 -386.729224) (xy 60.369948 -386.718673) (xy 60.361406 -386.699377) (xy 60.353956 -386.691886)
			(xy 60.334326 -386.672931) (xy 60.300891 -386.629811) (xy 60.274985 -386.581789) (xy 60.257311 -386.530166)
			(xy 60.248347 -386.476344) (xy 60.247784 -386.449062) (xy 60.248038 -386.43687) (xy 60.248292 -386.427218)
			(xy 60.242196 -386.409184) (xy 60.183522 -386.341874) (xy 60.166758 -386.333238) (xy 60.157106 -386.332222)
			(xy 60.130204 -386.328814) (xy 60.077919 -386.314457) (xy 60.028676 -386.291765) (xy 59.983792 -386.261346)
			(xy 59.944471 -386.224013) (xy 59.911765 -386.180768) (xy 59.886551 -386.132767) (xy 59.869502 -386.081296)
			(xy 59.864752 -386.0546) (xy 59.863228 -386.045202) (xy 59.590432 -385.57327) (xy 59.583066 -385.567428)
			(xy 59.564312 -385.551599) (xy 59.531194 -385.515387) (xy 59.503783 -385.474684) (xy 59.482678 -385.430382)
			(xy 59.468342 -385.38345) (xy 59.461088 -385.334916) (xy 59.460638 -385.31038) (xy 58.94359 -385.31038)
			(xy 59.19216 -385.740402) (xy 59.199526 -385.746244) (xy 59.218313 -385.762035) (xy 59.251429 -385.798255)
			(xy 59.278837 -385.838966) (xy 59.299936 -385.883276) (xy 59.314265 -385.930214) (xy 59.321509 -385.978754)
			(xy 59.321954 -386.003292) (xy 59.3217 -386.015484) (xy 59.321446 -386.025136) (xy 59.327542 -386.04317)
			(xy 59.386216 -386.11048) (xy 59.40298 -386.119116) (xy 59.412886 -386.120132) (xy 59.439646 -386.123503)
			(xy 59.491669 -386.137723) (xy 59.540695 -386.160196) (xy 59.585425 -386.190326) (xy 59.624673 -386.227315)
			(xy 59.657399 -386.270182) (xy 59.682735 -386.317792) (xy 59.700011 -386.368881) (xy 59.708768 -386.422096)
			(xy 59.709304 -386.449062) (xy 59.708878 -386.473264) (xy 59.701805 -386.521149) (xy 59.687818 -386.567488)
			(xy 59.667219 -386.61129) (xy 59.654186 -386.631688) (xy 59.649399 -386.639645) (xy 59.645364 -386.657756)
			(xy 59.646312 -386.666994) (xy 59.65063 -386.697982) (xy 59.652303 -386.707281) (xy 59.661589 -386.723722)
			(xy 59.668664 -386.729986) (xy 59.690752 -386.748668) (xy 59.730524 -386.79068) (xy 59.764686 -386.837368)
			(xy 59.792694 -386.887987) (xy 59.814101 -386.941733) (xy 59.828566 -386.997746) (xy 59.835859 -387.055136)
			(xy 59.836304 -387.084062) (xy 59.835718 -387.117384) (xy 59.826054 -387.183322) (xy 59.806927 -387.247161)
			(xy 59.793378 -387.27761) (xy 59.78913 -387.288075) (xy 59.789244 -387.310634) (xy 59.798978 -387.330985)
			(xy 59.807348 -387.33857) (xy 59.829567 -387.357276) (xy 59.869634 -387.399324) (xy 59.904059 -387.446104)
			(xy 59.932288 -387.496864) (xy 59.953868 -387.550787) (xy 59.968452 -387.607008) (xy 59.975805 -387.664621)
			(xy 59.976258 -387.693662) (xy 59.975779 -387.722667) (xy 59.968468 -387.780214) (xy 59.953947 -387.836376)
			(xy 59.932446 -387.890254) (xy 59.904313 -387.940985) (xy 59.869995 -387.987755) (xy 59.830045 -388.029815)
			(xy 59.807856 -388.0485) (xy 59.800744 -388.054088) (xy 59.7916 -388.069328) (xy 59.77636 -388.152132)
			(xy 59.779154 -388.169404) (xy 59.783726 -388.177532) (xy 59.7963 -388.200719) (xy 59.814175 -388.25034)
			(xy 59.823276 -388.302291) (xy 59.823858 -388.328662) (xy 59.823789 -388.338021) (xy 59.822646 -388.356703)
			(xy 59.821572 -388.366) (xy 59.820556 -388.37489) (xy 59.824366 -388.391654) (xy 59.868308 -388.461504)
			(xy 59.882024 -388.471918) (xy 59.890406 -388.474712) (xy 59.914428 -388.483198) (xy 59.959601 -388.506746)
			(xy 60.000407 -388.537242) (xy 60.035787 -388.573893) (xy 60.064824 -388.61575) (xy 60.086764 -388.661725)
			(xy 60.094368 -388.68604) (xy 60.095892 -388.691882) (xy 60.416186 -389.245602) (xy 60.42025 -389.24992)
			(xy 60.436446 -389.267622) (xy 60.463809 -389.307033) (xy 60.484893 -389.350131) (xy 60.499211 -389.395923)
			(xy 60.506436 -389.443354) (xy 60.506864 -389.467344) (xy 60.506423 -389.492135) (xy 60.49866 -389.541106)
			(xy 60.483333 -389.588259) (xy 60.460819 -389.632435) (xy 60.431671 -389.672545) (xy 60.396609 -389.707603)
			(xy 60.356494 -389.736744) (xy 60.312315 -389.759251) (xy 60.265159 -389.774571) (xy 60.216187 -389.782326)
			(xy 60.191396 -389.782812) (xy 60.166002 -389.782315) (xy 60.115868 -389.774184) (xy 60.067682 -389.758132)
			(xy 60.022688 -389.734573) (xy 59.982045 -389.704115) (xy 59.946802 -389.667543) (xy 59.917869 -389.625802)
			(xy 59.895991 -389.579967) (xy 59.888374 -389.555736) (xy 59.88685 -389.549894) (xy 59.566556 -388.996174)
			(xy 59.562492 -388.991856) (xy 59.546288 -388.974149) (xy 59.518864 -388.934757) (xy 59.497721 -388.891668)
			(xy 59.483348 -388.845873) (xy 59.476074 -388.798431) (xy 59.475624 -388.774432) (xy 59.475766 -388.76238)
			(xy 59.477672 -388.73835) (xy 59.479434 -388.726426) (xy 59.480704 -388.717536) (xy 59.477656 -388.700518)
			(xy 59.435492 -388.629652) (xy 59.422284 -388.618476) (xy 59.413902 -388.615428) (xy 59.392161 -388.607015)
			(xy 59.351302 -388.584578) (xy 59.31433 -388.556189) (xy 59.282106 -388.522506) (xy 59.255379 -388.484314)
			(xy 59.234772 -388.442502) (xy 59.220764 -388.398042) (xy 59.21368 -388.351969) (xy 59.213242 -388.328662)
			(xy 59.213802 -388.302289) (xy 59.222887 -388.25033) (xy 59.240778 -388.20071) (xy 59.253374 -388.177532)
			(xy 59.257946 -388.169404) (xy 59.26074 -388.152132) (xy 59.2455 -388.069328) (xy 59.236356 -388.054088)
			(xy 59.229244 -388.0485) (xy 59.207083 -388.029783) (xy 59.167133 -387.987725) (xy 59.132814 -387.940959)
			(xy 59.104673 -387.890235) (xy 59.083162 -387.836364) (xy 59.068624 -387.780208) (xy 59.061293 -387.722666)
			(xy 59.060842 -387.693662) (xy 59.061442 -387.660341) (xy 59.0711 -387.594403) (xy 59.090222 -387.530563)
			(xy 59.103768 -387.500114) (xy 59.108011 -387.489646) (xy 59.107906 -387.467087) (xy 59.098171 -387.446736)
			(xy 59.089798 -387.439154) (xy 59.067531 -387.420504) (xy 59.027469 -387.378444) (xy 58.99305 -387.331654)
			(xy 58.964828 -387.280884) (xy 58.943256 -387.226953) (xy 58.92868 -387.170725) (xy 58.921336 -387.113105)
			(xy 58.920888 -387.084062) (xy 58.921326 -387.055135) (xy 58.928611 -386.997742) (xy 58.943071 -386.941724)
			(xy 58.964476 -386.887976) (xy 58.992486 -386.837355) (xy 59.026652 -386.790667) (xy 59.066431 -386.748659)
			(xy 59.088528 -386.729986) (xy 59.095494 -386.723633) (xy 59.104756 -386.707234) (xy 59.106562 -386.697982)
			(xy 59.11088 -386.666994) (xy 59.111779 -386.657757) (xy 59.107757 -386.639658) (xy 59.103006 -386.631688)
			(xy 59.090019 -386.611265) (xy 59.069438 -386.567463) (xy 59.055451 -386.521133) (xy 59.048355 -386.47326)
			(xy 59.047888 -386.449062) (xy 59.048142 -386.43687) (xy 59.048396 -386.427218) (xy 59.0423 -386.409184)
			(xy 58.983626 -386.341874) (xy 58.966862 -386.333238) (xy 58.956956 -386.332222) (xy 58.930049 -386.328854)
			(xy 58.877763 -386.314489) (xy 58.828519 -386.29179) (xy 58.783637 -386.261364) (xy 58.744317 -386.224027)
			(xy 58.711613 -386.180776) (xy 58.686399 -386.132772) (xy 58.669352 -386.081298) (xy 58.664602 -386.0546)
			(xy 58.663078 -386.045202) (xy 58.390282 -385.57327) (xy 58.382916 -385.567428) (xy 58.364173 -385.551587)
			(xy 58.331052 -385.515379) (xy 58.303638 -385.474679) (xy 58.282531 -385.430379) (xy 58.268193 -385.383448)
			(xy 58.260939 -385.334916) (xy 58.260488 -385.31038) (xy 57.743694 -385.31038) (xy 57.992264 -385.740402)
			(xy 57.99963 -385.746244) (xy 58.018407 -385.762049) (xy 58.051537 -385.798257) (xy 58.078955 -385.838962)
			(xy 58.100059 -385.883271) (xy 58.114386 -385.930211) (xy 58.121623 -385.978753) (xy 58.122058 -386.003292)
			(xy 58.121804 -386.015484) (xy 58.12155 -386.025136) (xy 58.127646 -386.04317) (xy 58.18632 -386.11048)
			(xy 58.203084 -386.119116) (xy 58.212736 -386.120132) (xy 58.239502 -386.123461) (xy 58.291526 -386.137689)
			(xy 58.340552 -386.160169) (xy 58.385281 -386.190305) (xy 58.424528 -386.227299) (xy 58.457252 -386.270171)
			(xy 58.482588 -386.317784) (xy 58.499863 -386.368877) (xy 58.50862 -386.422095) (xy 58.509154 -386.449062)
			(xy 58.508644 -386.475049) (xy 58.500514 -386.526384) (xy 58.484453 -386.575814) (xy 58.460857 -386.622124)
			(xy 58.430307 -386.664172) (xy 58.393556 -386.700923) (xy 58.351508 -386.731473) (xy 58.305198 -386.755069)
			(xy 58.255768 -386.77113) (xy 58.204433 -386.77926) (xy 58.152459 -386.77926) (xy 58.101124 -386.77113)
			(xy 58.051694 -386.755069) (xy 58.005384 -386.731473) (xy 57.963336 -386.700923) (xy 57.926585 -386.664172)
			(xy 57.896035 -386.622124) (xy 57.872439 -386.575814) (xy 57.856378 -386.526384) (xy 57.848248 -386.475049)
			(xy 57.847738 -386.449062) (xy 57.847992 -386.43687) (xy 57.848246 -386.427218) (xy 57.84215 -386.409184)
			(xy 57.783476 -386.341874) (xy 57.766712 -386.333238) (xy 57.75706 -386.332222) (xy 57.728104 -386.327904)
			(xy 57.716928 -386.325618) (xy 57.695084 -386.331206) (xy 57.625742 -386.388356) (xy 57.617379 -386.395978)
			(xy 57.607754 -386.416423) (xy 57.6072 -386.427726) (xy 57.6072 -386.4356) (xy 57.291986 -386.750814)
			(xy 57.284591 -386.757668) (xy 57.265992 -386.76541) (xy 57.255918 -386.7658) (xy 57.250584 -386.7658)
			(xy 57.240578 -386.766291) (xy 57.222092 -386.773953) (xy 57.207944 -386.788106) (xy 57.200288 -386.806594)
			(xy 57.199784 -386.8166) (xy 57.199784 -386.82676) (xy 57.20715 -386.845048) (xy 57.214262 -386.85216)
			(xy 57.231965 -386.870824) (xy 57.261955 -386.912617) (xy 57.285102 -386.958553) (xy 57.300849 -387.007523)
			(xy 57.308814 -387.058342) (xy 57.309258 -387.084062) (xy 57.308825 -387.108179) (xy 57.301828 -387.155904)
			(xy 57.287978 -387.202107) (xy 57.267568 -387.245811) (xy 57.254648 -387.26618) (xy 57.248806 -387.27507)
			(xy 57.24525 -387.295136) (xy 57.266332 -387.387338) (xy 57.278524 -387.404102) (xy 57.287414 -387.409436)
			(xy 57.308217 -387.422291) (xy 57.346135 -387.453168) (xy 57.379086 -387.489298) (xy 57.406351 -387.529892)
			(xy 57.427331 -387.574062) (xy 57.441571 -387.620843) (xy 57.448757 -387.669212) (xy 57.449212 -387.693662)
			(xy 57.448774 -387.718032) (xy 57.441618 -387.766245) (xy 57.427469 -387.812887) (xy 57.406633 -387.856949)
			(xy 57.37956 -387.89748) (xy 57.346837 -387.933603) (xy 57.328308 -387.94944) (xy 57.319418 -387.956552)
			(xy 57.31002 -387.97611) (xy 57.307226 -388.075424) (xy 57.315862 -388.09549) (xy 57.324244 -388.10311)
			(xy 57.342663 -388.120599) (xy 57.374001 -388.160568) (xy 57.398294 -388.205171) (xy 57.414874 -388.253179)
			(xy 57.423282 -388.303267) (xy 57.423812 -388.328662) (xy 58.013092 -388.328662) (xy 58.013614 -388.303407)
			(xy 58.021927 -388.253585) (xy 58.038328 -388.205811) (xy 58.062369 -388.161388) (xy 58.093393 -388.121528)
			(xy 58.130555 -388.087318) (xy 58.172841 -388.059692) (xy 58.219097 -388.039402) (xy 58.268062 -388.027002)
			(xy 58.3184 -388.022831) (xy 58.368738 -388.027002) (xy 58.417703 -388.039402) (xy 58.463959 -388.059692)
			(xy 58.506245 -388.087318) (xy 58.543407 -388.121528) (xy 58.574431 -388.161388) (xy 58.598472 -388.205811)
			(xy 58.614873 -388.253585) (xy 58.623186 -388.303407) (xy 58.623708 -388.328662) (xy 58.623639 -388.338021)
			(xy 58.622496 -388.356703) (xy 58.621422 -388.366) (xy 58.620406 -388.37489) (xy 58.624216 -388.391654)
			(xy 58.668158 -388.461504) (xy 58.681874 -388.471918) (xy 58.690256 -388.474712) (xy 58.714287 -388.483171)
			(xy 58.759459 -388.506726) (xy 58.800264 -388.537228) (xy 58.835642 -388.573884) (xy 58.864677 -388.615745)
			(xy 58.886615 -388.661724) (xy 58.894218 -388.68604) (xy 58.895742 -388.691882) (xy 59.216036 -389.245602)
			(xy 59.2201 -389.24992) (xy 59.236292 -389.267639) (xy 59.263718 -389.307027) (xy 59.284863 -389.350113)
			(xy 59.299239 -389.395905) (xy 59.306516 -389.443346) (xy 59.306968 -389.467344) (xy 59.306547 -389.492149)
			(xy 59.298776 -389.541148) (xy 59.283432 -389.588327) (xy 59.260894 -389.632523) (xy 59.231717 -389.672647)
			(xy 59.19662 -389.707711) (xy 59.156468 -389.73685) (xy 59.112251 -389.759346) (xy 59.065058 -389.774645)
			(xy 59.016052 -389.78237) (xy 58.991246 -389.782812) (xy 58.965853 -389.782271) (xy 58.915721 -389.774148)
			(xy 58.867537 -389.758103) (xy 58.822542 -389.734551) (xy 58.781899 -389.704099) (xy 58.746656 -389.667533)
			(xy 58.717721 -389.625796) (xy 58.695841 -389.579965) (xy 58.688224 -389.555736) (xy 58.6867 -389.549894)
			(xy 58.366406 -388.996174) (xy 58.362342 -388.991856) (xy 58.346181 -388.974124) (xy 58.318813 -388.934721)
			(xy 58.297723 -388.891631) (xy 58.283396 -388.845846) (xy 58.276162 -388.79842) (xy 58.275728 -388.774432)
			(xy 58.275809 -388.762384) (xy 58.277591 -388.738355) (xy 58.279284 -388.726426) (xy 58.280554 -388.717536)
			(xy 58.277506 -388.700518) (xy 58.235342 -388.629652) (xy 58.222134 -388.618476) (xy 58.213752 -388.615428)
			(xy 58.192 -388.607043) (xy 58.151142 -388.584599) (xy 58.114172 -388.556204) (xy 58.08195 -388.522517)
			(xy 58.055226 -388.484322) (xy 58.03462 -388.442507) (xy 58.020613 -388.398045) (xy 58.01353 -388.35197)
			(xy 58.013092 -388.328662) (xy 57.423812 -388.328662) (xy 57.42374 -388.33802) (xy 57.422594 -388.356702)
			(xy 57.421526 -388.366) (xy 57.42051 -388.37489) (xy 57.42432 -388.391654) (xy 57.468262 -388.461504)
			(xy 57.481978 -388.471918) (xy 57.49036 -388.474712) (xy 57.514393 -388.483169) (xy 57.559569 -388.506719)
			(xy 57.600376 -388.537219) (xy 57.635754 -388.573876) (xy 57.664786 -388.61574) (xy 57.686718 -388.661724)
			(xy 57.694322 -388.68604) (xy 57.695846 -388.691882) (xy 58.01614 -389.245602) (xy 58.020204 -389.24992)
			(xy 58.036421 -389.267618) (xy 58.063853 -389.307007) (xy 58.085 -389.350099) (xy 58.099373 -389.395897)
			(xy 58.10664 -389.443344) (xy 58.107072 -389.467344) (xy 58.106607 -389.492146) (xy 58.098837 -389.541138)
			(xy 58.083495 -389.588311) (xy 58.060961 -389.632501) (xy 58.031788 -389.67262) (xy 57.996696 -389.707679)
			(xy 57.95655 -389.736815) (xy 57.912339 -389.759308) (xy 57.865152 -389.774605) (xy 57.816153 -389.78233)
			(xy 57.79135 -389.782812) (xy 57.765954 -389.782308) (xy 57.715816 -389.774184) (xy 57.667625 -389.758138)
			(xy 57.622625 -389.734583) (xy 57.581977 -389.704128) (xy 57.546728 -389.667558) (xy 57.51779 -389.625816)
			(xy 57.495907 -389.579979) (xy 57.488328 -389.555736) (xy 57.486804 -389.549894) (xy 57.16651 -388.996174)
			(xy 57.162446 -388.991856) (xy 57.146255 -388.974148) (xy 57.118876 -388.934746) (xy 57.097783 -388.891651)
			(xy 57.083464 -388.845857) (xy 57.07625 -388.798423) (xy 57.075832 -388.774432) (xy 57.075918 -388.762384)
			(xy 57.077701 -388.738355) (xy 57.079388 -388.726426) (xy 57.080658 -388.717536) (xy 57.07761 -388.700518)
			(xy 57.035446 -388.629652) (xy 57.022238 -388.618476) (xy 57.013856 -388.615428) (xy 56.992117 -388.607021)
			(xy 56.951275 -388.584566) (xy 56.91432 -388.556166) (xy 56.882111 -388.522479) (xy 56.855394 -388.484289)
			(xy 56.834792 -388.442482) (xy 56.820782 -388.39803) (xy 56.81369 -388.351966) (xy 56.813196 -388.328662)
			(xy 56.813696 -388.303264) (xy 56.822096 -388.253167) (xy 56.838673 -388.205153) (xy 56.862971 -388.160545)
			(xy 56.894319 -388.120576) (xy 56.912764 -388.10311) (xy 56.921146 -388.09549) (xy 56.929782 -388.075424)
			(xy 56.926988 -387.97611) (xy 56.91759 -387.956552) (xy 56.9087 -387.94944) (xy 56.890139 -387.933638)
			(xy 56.857412 -387.897511) (xy 56.830339 -387.856974) (xy 56.809506 -387.812904) (xy 56.795364 -387.766255)
			(xy 56.788218 -387.718035) (xy 56.787796 -387.693662) (xy 56.788235 -387.669546) (xy 56.79524 -387.621826)
			(xy 56.809098 -387.575627) (xy 56.829513 -387.531929) (xy 56.842406 -387.511544) (xy 56.848248 -387.502654)
			(xy 56.851804 -387.482588) (xy 56.830722 -387.390386) (xy 56.81853 -387.373622) (xy 56.80964 -387.368288)
			(xy 56.788839 -387.355432) (xy 56.750923 -387.324553) (xy 56.717973 -387.288422) (xy 56.69071 -387.247828)
			(xy 56.669729 -387.203659) (xy 56.655489 -387.15688) (xy 56.648301 -387.108512) (xy 56.647842 -387.084062)
			(xy 56.648419 -387.055089) (xy 56.658466 -386.998022) (xy 56.678299 -386.943576) (xy 56.692292 -386.9182)
			(xy 56.699404 -386.906262) (xy 56.699404 -386.879592) (xy 56.648604 -386.7912) (xy 56.643837 -386.783637)
			(xy 56.630139 -386.772167) (xy 56.613342 -386.76608) (xy 56.604408 -386.7658) (xy 56.152796 -386.7658)
			(xy 56.143861 -386.766098) (xy 56.127055 -386.772156) (xy 56.113366 -386.783636) (xy 56.1086 -386.7912)
			(xy 56.0578 -386.879592) (xy 56.0578 -386.906262) (xy 56.064912 -386.9182) (xy 56.078902 -386.943578)
			(xy 56.09874 -386.998022) (xy 56.108789 -387.055089) (xy 56.109362 -387.084062) (xy 56.108929 -387.108179)
			(xy 56.101932 -387.155904) (xy 56.088082 -387.202108) (xy 56.067672 -387.245811) (xy 56.054752 -387.26618)
			(xy 56.04891 -387.27507) (xy 56.045354 -387.295136) (xy 56.066436 -387.387338) (xy 56.078628 -387.404102)
			(xy 56.087518 -387.409436) (xy 56.108321 -387.422291) (xy 56.146238 -387.453168) (xy 56.179189 -387.489299)
			(xy 56.206453 -387.529892) (xy 56.227434 -387.574062) (xy 56.241673 -387.620843) (xy 56.248859 -387.669212)
			(xy 56.249316 -387.693662) (xy 56.248878 -387.718032) (xy 56.241722 -387.766245) (xy 56.227573 -387.812887)
			(xy 56.206737 -387.85695) (xy 56.179665 -387.897481) (xy 56.146942 -387.933604) (xy 56.128412 -387.94944)
			(xy 56.119522 -387.956552) (xy 56.110124 -387.97611) (xy 56.10733 -388.075424) (xy 56.115966 -388.09549)
			(xy 56.124348 -388.10311) (xy 56.142767 -388.120599) (xy 56.174104 -388.160569) (xy 56.198397 -388.205172)
			(xy 56.214976 -388.253179) (xy 56.223385 -388.303267) (xy 56.223916 -388.328662) (xy 56.223844 -388.33802)
			(xy 56.222698 -388.356702) (xy 56.22163 -388.366) (xy 56.220614 -388.37489) (xy 56.224424 -388.391654)
			(xy 56.268366 -388.461504) (xy 56.282082 -388.471918) (xy 56.290464 -388.474712) (xy 56.314562 -388.483193)
			(xy 56.359852 -388.506821) (xy 56.400749 -388.537431) (xy 56.436183 -388.574227) (xy 56.465232 -388.616246)
			(xy 56.487138 -388.662395) (xy 56.49468 -388.686802) (xy 56.496204 -388.692644) (xy 56.81599 -389.245602)
			(xy 56.820054 -389.24992) (xy 56.836247 -389.267628) (xy 56.863628 -389.307029) (xy 56.884724 -389.350124)
			(xy 56.899047 -389.395918) (xy 56.906265 -389.443353) (xy 56.906668 -389.467344) (xy 56.906178 -389.492131)
			(xy 56.898417 -389.541095) (xy 56.883092 -389.588241) (xy 56.860581 -389.632411) (xy 56.831439 -389.672515)
			(xy 56.796382 -389.707567) (xy 56.756273 -389.736704) (xy 56.712101 -389.759209) (xy 56.664952 -389.774527)
			(xy 56.615987 -389.782282) (xy 56.5912 -389.782812) (xy 56.565806 -389.782304) (xy 56.515674 -389.774174)
			(xy 56.467489 -389.758123) (xy 56.422496 -389.734565) (xy 56.381854 -389.704108) (xy 56.346612 -389.667538)
			(xy 56.317679 -389.625798) (xy 56.295801 -389.579964) (xy 56.288178 -389.555736) (xy 56.286654 -389.549894)
			(xy 55.966106 -388.995412) (xy 55.962042 -388.991094) (xy 55.945964 -388.973415) (xy 55.918778 -388.934117)
			(xy 55.897822 -388.891172) (xy 55.883572 -388.845561) (xy 55.876356 -388.798324) (xy 55.875936 -388.774432)
			(xy 55.876022 -388.762384) (xy 55.877805 -388.738355) (xy 55.879492 -388.726426) (xy 55.880762 -388.717536)
			(xy 55.877714 -388.700518) (xy 55.83555 -388.629652) (xy 55.822342 -388.618476) (xy 55.81396 -388.615428)
			(xy 55.792221 -388.607021) (xy 55.751379 -388.584567) (xy 55.714423 -388.556167) (xy 55.682213 -388.52248)
			(xy 55.655496 -388.48429) (xy 55.634893 -388.442483) (xy 55.620883 -388.398031) (xy 55.613791 -388.351966)
			(xy 55.6133 -388.328662) (xy 55.6138 -388.303264) (xy 55.6222 -388.253167) (xy 55.638777 -388.205153)
			(xy 55.663075 -388.160546) (xy 55.694424 -388.120577) (xy 55.712868 -388.10311) (xy 55.72125 -388.09549)
			(xy 55.729886 -388.075424) (xy 55.727092 -387.97611) (xy 55.717694 -387.956552) (xy 55.708804 -387.94944)
			(xy 55.690243 -387.933638) (xy 55.657516 -387.897511) (xy 55.630442 -387.856974) (xy 55.609609 -387.812904)
			(xy 55.595467 -387.766255) (xy 55.588321 -387.718035) (xy 55.5879 -387.693662) (xy 55.588339 -387.669546)
			(xy 55.595344 -387.621826) (xy 55.609202 -387.575627) (xy 55.629617 -387.531929) (xy 55.64251 -387.511544)
			(xy 55.648352 -387.502654) (xy 55.651908 -387.482588) (xy 55.630826 -387.390386) (xy 55.618634 -387.373622)
			(xy 55.609744 -387.368288) (xy 55.588942 -387.355432) (xy 55.551026 -387.324553) (xy 55.518076 -387.288423)
			(xy 55.490813 -387.247829) (xy 55.469832 -387.20366) (xy 55.455591 -387.15688) (xy 55.448403 -387.108512)
			(xy 55.447946 -387.084062) (xy 55.448523 -387.055089) (xy 55.45857 -386.998022) (xy 55.478403 -386.943576)
			(xy 55.492396 -386.9182) (xy 55.499508 -386.906262) (xy 55.499508 -386.879592) (xy 55.448708 -386.7912)
			(xy 55.443942 -386.783637) (xy 55.430244 -386.772165) (xy 55.413446 -386.766077) (xy 55.404512 -386.7658)
			(xy 54.952646 -386.7658) (xy 54.943707 -386.766089) (xy 54.926887 -386.772137) (xy 54.913184 -386.783613)
			(xy 54.90845 -386.7912) (xy 54.85765 -386.879592) (xy 54.85765 -386.906262) (xy 54.864762 -386.9182)
			(xy 54.87875 -386.943579) (xy 54.898585 -386.998023) (xy 54.908633 -387.055089) (xy 54.909212 -387.084062)
			(xy 54.908779 -387.10818) (xy 54.901783 -387.155905) (xy 54.887935 -387.202109) (xy 54.867528 -387.245815)
			(xy 54.854602 -387.26618) (xy 54.84876 -387.27507) (xy 54.845204 -387.295136) (xy 54.866286 -387.387338)
			(xy 54.878478 -387.404102) (xy 54.887368 -387.409436) (xy 54.908168 -387.422293) (xy 54.946081 -387.453173)
			(xy 54.979027 -387.489305) (xy 55.006286 -387.529899) (xy 55.027263 -387.574068) (xy 55.0415 -387.620847)
			(xy 55.048684 -387.669213) (xy 55.049166 -387.693662) (xy 55.048728 -387.718033) (xy 55.041573 -387.766246)
			(xy 55.027425 -387.81289) (xy 55.006592 -387.856955) (xy 54.979522 -387.897489) (xy 54.946802 -387.933616)
			(xy 54.928262 -387.94944) (xy 54.919372 -387.956552) (xy 54.909974 -387.97611) (xy 54.90718 -388.075424)
			(xy 54.915816 -388.09549) (xy 54.924198 -388.10311) (xy 54.94262 -388.120598) (xy 54.973962 -388.160566)
			(xy 54.998259 -388.205168) (xy 55.014841 -388.253176) (xy 55.023251 -388.303266) (xy 55.023766 -388.328662)
			(xy 55.023694 -388.33802) (xy 55.022548 -388.356702) (xy 55.02148 -388.366) (xy 55.020464 -388.37489)
			(xy 55.024274 -388.391654) (xy 55.068216 -388.461504) (xy 55.081932 -388.471918) (xy 55.090314 -388.474712)
			(xy 55.114349 -388.483166) (xy 55.15953 -388.506712) (xy 55.200343 -388.537209) (xy 55.235727 -388.573866)
			(xy 55.264763 -388.61573) (xy 55.286699 -388.661714) (xy 55.294276 -388.68604) (xy 55.2958 -388.691882)
			(xy 55.616094 -389.245602) (xy 55.620158 -389.24992) (xy 55.63635 -389.267628) (xy 55.663732 -389.307029)
			(xy 55.684827 -389.350124) (xy 55.69915 -389.395918) (xy 55.706368 -389.443353) (xy 55.706772 -389.467344)
			(xy 55.706283 -389.492131) (xy 55.698521 -389.541095) (xy 55.683197 -389.588242) (xy 55.660686 -389.632412)
			(xy 55.631543 -389.672517) (xy 55.596486 -389.707569) (xy 55.556378 -389.736707) (xy 55.512205 -389.759212)
			(xy 55.465056 -389.774531) (xy 55.416092 -389.782286) (xy 55.391304 -389.782812) (xy 55.36591 -389.782305)
			(xy 55.315777 -389.774175) (xy 55.267592 -389.758124) (xy 55.222598 -389.734566) (xy 55.181956 -389.70411)
			(xy 55.146714 -389.66754) (xy 55.11778 -389.625799) (xy 55.095902 -389.579965) (xy 55.088282 -389.555736)
			(xy 55.086758 -389.549894) (xy 54.766464 -388.996174) (xy 54.7624 -388.991856) (xy 54.746184 -388.974157)
			(xy 54.718755 -388.934768) (xy 54.697611 -388.891676) (xy 54.683241 -388.845878) (xy 54.675978 -388.798432)
			(xy 54.675532 -388.774432) (xy 54.67569 -388.76238) (xy 54.677599 -388.738352) (xy 54.679342 -388.726426)
			(xy 54.680612 -388.717536) (xy 54.677564 -388.700518) (xy 54.6354 -388.629652) (xy 54.622192 -388.618476)
			(xy 54.61381 -388.615428) (xy 54.592068 -388.607024) (xy 54.55122 -388.584573) (xy 54.514259 -388.556175)
			(xy 54.482043 -388.52249) (xy 54.455322 -388.484299) (xy 54.434715 -388.44249) (xy 54.420702 -388.398035)
			(xy 54.413608 -388.351967) (xy 54.41315 -388.328662) (xy 54.413649 -388.303263) (xy 54.422048 -388.253166)
			(xy 54.438624 -388.205149) (xy 54.462919 -388.160539) (xy 54.494264 -388.120567) (xy 54.512718 -388.10311)
			(xy 54.5211 -388.09549) (xy 54.529736 -388.075424) (xy 54.526942 -387.97611) (xy 54.517544 -387.956552)
			(xy 54.508654 -387.94944) (xy 54.49009 -387.933639) (xy 54.457358 -387.897515) (xy 54.430281 -387.856978)
			(xy 54.409445 -387.812908) (xy 54.3953 -387.766257) (xy 54.388153 -387.718036) (xy 54.38775 -387.693662)
			(xy 54.388189 -387.669546) (xy 54.395195 -387.621826) (xy 54.409055 -387.575629) (xy 54.429473 -387.531933)
			(xy 54.44236 -387.511544) (xy 54.448202 -387.502654) (xy 54.451758 -387.482588) (xy 54.430676 -387.390386)
			(xy 54.418484 -387.373622) (xy 54.409594 -387.368288) (xy 54.38879 -387.355434) (xy 54.350868 -387.324558)
			(xy 54.317913 -387.288429) (xy 54.290646 -387.247835) (xy 54.269661 -387.203665) (xy 54.255418 -387.156883)
			(xy 54.248228 -387.108513) (xy 54.247796 -387.084062) (xy 54.248374 -387.055089) (xy 54.258422 -386.998022)
			(xy 54.278257 -386.943579) (xy 54.292246 -386.9182) (xy 54.299358 -386.906262) (xy 54.299358 -386.879592)
			(xy 54.248558 -386.7912) (xy 54.243789 -386.783642) (xy 54.230089 -386.772184) (xy 54.213293 -386.766112)
			(xy 54.204362 -386.7658) (xy 53.999384 -386.7658) (xy 53.989315 -386.766226) (xy 53.970715 -386.773945)
			(xy 53.963316 -386.780786) (xy 53.8226 -386.921502) (xy 53.815742 -386.947664) (xy 53.819552 -386.961126)
			(xy 53.827391 -386.991254) (xy 53.835806 -387.052935) (xy 53.836316 -387.084062) (xy 53.835712 -387.117382)
			(xy 53.826043 -387.183317) (xy 53.80692 -387.247154) (xy 53.79339 -387.27761) (xy 53.789127 -387.288078)
			(xy 53.789201 -387.310652) (xy 53.798959 -387.331008) (xy 53.80736 -387.33857) (xy 53.829606 -387.357245)
			(xy 53.869667 -387.399302) (xy 53.904087 -387.446088) (xy 53.932312 -387.496853) (xy 53.953888 -387.55078)
			(xy 53.96847 -387.607004) (xy 53.975822 -387.66462) (xy 53.97627 -387.693662) (xy 53.975819 -387.722666)
			(xy 53.968488 -387.780208) (xy 53.953951 -387.836364) (xy 53.93244 -387.890236) (xy 53.9043 -387.940961)
			(xy 53.869981 -387.987727) (xy 53.830032 -388.029786) (xy 53.807868 -388.0485) (xy 53.800756 -388.054088)
			(xy 53.791612 -388.069328) (xy 53.776372 -388.152132) (xy 53.779166 -388.169404) (xy 53.783738 -388.177532)
			(xy 53.796334 -388.20071) (xy 53.814224 -388.25033) (xy 53.823308 -388.302289) (xy 53.82387 -388.328662)
			(xy 53.823798 -388.33802) (xy 53.822652 -388.356702) (xy 53.821584 -388.366) (xy 53.820568 -388.37489)
			(xy 53.824378 -388.391654) (xy 53.86832 -388.461504) (xy 53.882036 -388.471918) (xy 53.890418 -388.474712)
			(xy 53.914453 -388.483166) (xy 53.959634 -388.506712) (xy 54.000446 -388.53721) (xy 54.035829 -388.573867)
			(xy 54.064865 -388.615731) (xy 54.0868 -388.661715) (xy 54.09438 -388.68604) (xy 54.095904 -388.691882)
			(xy 54.416198 -389.245602) (xy 54.420262 -389.24992) (xy 54.436454 -389.267628) (xy 54.463835 -389.307029)
			(xy 54.484931 -389.350124) (xy 54.499253 -389.395918) (xy 54.506471 -389.443353) (xy 54.506876 -389.467344)
			(xy 54.506387 -389.492132) (xy 54.498625 -389.541096) (xy 54.483301 -389.588243) (xy 54.46079 -389.632413)
			(xy 54.431648 -389.672518) (xy 54.39659 -389.707571) (xy 54.356482 -389.736709) (xy 54.31231 -389.759215)
			(xy 54.265161 -389.774534) (xy 54.216196 -389.78229) (xy 54.191408 -389.782812) (xy 54.166014 -389.782305)
			(xy 54.11588 -389.774176) (xy 54.067695 -389.758125) (xy 54.022701 -389.734568) (xy 53.982058 -389.704111)
			(xy 53.946815 -389.667541) (xy 53.917881 -389.625801) (xy 53.896002 -389.579966) (xy 53.888386 -389.555736)
			(xy 53.886862 -389.549894) (xy 53.805328 -389.409178) (xy 53.799262 -389.399828) (xy 53.781012 -389.387082)
			(xy 53.759083 -389.383246) (xy 53.748178 -389.385556) (xy 53.731414 -389.389874) (xy 53.710586 -389.417052)
			(xy 53.710586 -390.160002) (xy 54.2854 -390.160002) (xy 54.28936 -390.110948) (xy 54.301137 -390.063164)
			(xy 54.320428 -390.017888) (xy 54.346731 -389.976292) (xy 54.379366 -389.939455) (xy 54.417487 -389.90833)
			(xy 54.460108 -389.883723) (xy 54.506124 -389.866271) (xy 54.554343 -389.856427) (xy 54.603518 -389.854446)
			(xy 54.652373 -389.860378) (xy 54.699644 -389.87407) (xy 54.744106 -389.895168) (xy 54.784609 -389.923124)
			(xy 54.820102 -389.957216) (xy 54.849667 -389.99656) (xy 54.872538 -390.040137) (xy 54.888122 -390.086818)
			(xy 54.896017 -390.135395) (xy 54.896512 -390.160002) (xy 55.48555 -390.160002) (xy 55.48951 -390.110948)
			(xy 55.501287 -390.063164) (xy 55.520578 -390.017888) (xy 55.546881 -389.976292) (xy 55.579516 -389.939455)
			(xy 55.617637 -389.90833) (xy 55.660258 -389.883723) (xy 55.706274 -389.866271) (xy 55.754493 -389.856427)
			(xy 55.803668 -389.854446) (xy 55.852523 -389.860378) (xy 55.899794 -389.87407) (xy 55.944256 -389.895168)
			(xy 55.984759 -389.923124) (xy 56.020252 -389.957216) (xy 56.049817 -389.99656) (xy 56.072688 -390.040137)
			(xy 56.088272 -390.086818) (xy 56.096167 -390.135395) (xy 56.096662 -390.160002) (xy 56.685446 -390.160002)
			(xy 56.689406 -390.110948) (xy 56.701183 -390.063164) (xy 56.720474 -390.017888) (xy 56.746777 -389.976292)
			(xy 56.779412 -389.939455) (xy 56.817533 -389.90833) (xy 56.860154 -389.883723) (xy 56.90617 -389.866271)
			(xy 56.954389 -389.856427) (xy 57.003564 -389.854446) (xy 57.052419 -389.860378) (xy 57.09969 -389.87407)
			(xy 57.144152 -389.895168) (xy 57.184655 -389.923124) (xy 57.220148 -389.957216) (xy 57.249713 -389.99656)
			(xy 57.272584 -390.040137) (xy 57.288168 -390.086818) (xy 57.296063 -390.135395) (xy 57.296558 -390.160002)
			(xy 57.885596 -390.160002) (xy 57.889556 -390.110948) (xy 57.901333 -390.063164) (xy 57.920624 -390.017888)
			(xy 57.946927 -389.976292) (xy 57.979562 -389.939455) (xy 58.017683 -389.90833) (xy 58.060304 -389.883723)
			(xy 58.10632 -389.866271) (xy 58.154539 -389.856427) (xy 58.203714 -389.854446) (xy 58.252569 -389.860378)
			(xy 58.29984 -389.87407) (xy 58.344302 -389.895168) (xy 58.384805 -389.923124) (xy 58.420298 -389.957216)
			(xy 58.449863 -389.99656) (xy 58.472734 -390.040137) (xy 58.488318 -390.086818) (xy 58.496213 -390.135395)
			(xy 58.496708 -390.160002) (xy 59.085492 -390.160002) (xy 59.089452 -390.110948) (xy 59.101229 -390.063164)
			(xy 59.12052 -390.017888) (xy 59.146823 -389.976292) (xy 59.179458 -389.939455) (xy 59.217579 -389.90833)
			(xy 59.2602 -389.883723) (xy 59.306216 -389.866271) (xy 59.354435 -389.856427) (xy 59.40361 -389.854446)
			(xy 59.452465 -389.860378) (xy 59.499736 -389.87407) (xy 59.544198 -389.895168) (xy 59.584701 -389.923124)
			(xy 59.620194 -389.957216) (xy 59.649759 -389.99656) (xy 59.67263 -390.040137) (xy 59.688214 -390.086818)
			(xy 59.696109 -390.135395) (xy 59.696604 -390.160002) (xy 60.285388 -390.160002) (xy 60.289348 -390.110948)
			(xy 60.301125 -390.063164) (xy 60.320416 -390.017888) (xy 60.346719 -389.976292) (xy 60.379354 -389.939455)
			(xy 60.417475 -389.90833) (xy 60.460096 -389.883723) (xy 60.506112 -389.866271) (xy 60.554331 -389.856427)
			(xy 60.603506 -389.854446) (xy 60.652361 -389.860378) (xy 60.699632 -389.87407) (xy 60.744094 -389.895168)
			(xy 60.784597 -389.923124) (xy 60.82009 -389.957216) (xy 60.849655 -389.99656) (xy 60.872526 -390.040137)
			(xy 60.88811 -390.086818) (xy 60.896005 -390.135395) (xy 60.8965 -390.160002) (xy 61.485538 -390.160002)
			(xy 61.489498 -390.110948) (xy 61.501275 -390.063164) (xy 61.520566 -390.017888) (xy 61.546869 -389.976292)
			(xy 61.579504 -389.939455) (xy 61.617625 -389.90833) (xy 61.660246 -389.883723) (xy 61.706262 -389.866271)
			(xy 61.754481 -389.856427) (xy 61.803656 -389.854446) (xy 61.852511 -389.860378) (xy 61.899782 -389.87407)
			(xy 61.944244 -389.895168) (xy 61.984747 -389.923124) (xy 62.02024 -389.957216) (xy 62.049805 -389.99656)
			(xy 62.072676 -390.040137) (xy 62.08826 -390.086818) (xy 62.096155 -390.135395) (xy 62.09665 -390.160002)
			(xy 62.685434 -390.160002) (xy 62.689394 -390.110948) (xy 62.701171 -390.063164) (xy 62.720462 -390.017888)
			(xy 62.746765 -389.976292) (xy 62.7794 -389.939455) (xy 62.817521 -389.90833) (xy 62.860142 -389.883723)
			(xy 62.906158 -389.866271) (xy 62.954377 -389.856427) (xy 63.003552 -389.854446) (xy 63.052407 -389.860378)
			(xy 63.099678 -389.87407) (xy 63.14414 -389.895168) (xy 63.184643 -389.923124) (xy 63.220136 -389.957216)
			(xy 63.249701 -389.99656) (xy 63.272572 -390.040137) (xy 63.288156 -390.086818) (xy 63.296051 -390.135395)
			(xy 63.296546 -390.160002) (xy 63.885584 -390.160002) (xy 63.889544 -390.110948) (xy 63.901321 -390.063164)
			(xy 63.920612 -390.017888) (xy 63.946915 -389.976292) (xy 63.97955 -389.939455) (xy 64.017671 -389.90833)
			(xy 64.060292 -389.883723) (xy 64.106308 -389.866271) (xy 64.154527 -389.856427) (xy 64.203702 -389.854446)
			(xy 64.252557 -389.860378) (xy 64.299828 -389.87407) (xy 64.34429 -389.895168) (xy 64.384793 -389.923124)
			(xy 64.420286 -389.957216) (xy 64.449851 -389.99656) (xy 64.472722 -390.040137) (xy 64.488306 -390.086818)
			(xy 64.496201 -390.135395) (xy 64.496696 -390.160002) (xy 65.08548 -390.160002) (xy 65.08944 -390.110948)
			(xy 65.101217 -390.063164) (xy 65.120508 -390.017888) (xy 65.146811 -389.976292) (xy 65.179446 -389.939455)
			(xy 65.217567 -389.90833) (xy 65.260188 -389.883723) (xy 65.306204 -389.866271) (xy 65.354423 -389.856427)
			(xy 65.403598 -389.854446) (xy 65.452453 -389.860378) (xy 65.499724 -389.87407) (xy 65.544186 -389.895168)
			(xy 65.584689 -389.923124) (xy 65.620182 -389.957216) (xy 65.649747 -389.99656) (xy 65.672618 -390.040137)
			(xy 65.688202 -390.086818) (xy 65.696097 -390.135395) (xy 65.696592 -390.160002) (xy 65.696097 -390.184609)
			(xy 65.688202 -390.233186) (xy 65.672618 -390.279867) (xy 65.649747 -390.323444) (xy 65.620182 -390.362788)
			(xy 65.584689 -390.39688) (xy 65.544186 -390.424836) (xy 65.499724 -390.445934) (xy 65.452453 -390.459626)
			(xy 65.403598 -390.465558) (xy 65.354423 -390.463577) (xy 65.306204 -390.453733) (xy 65.260188 -390.436281)
			(xy 65.217567 -390.411674) (xy 65.179446 -390.380549) (xy 65.146811 -390.343712) (xy 65.120508 -390.302116)
			(xy 65.101217 -390.25684) (xy 65.08944 -390.209056) (xy 65.08548 -390.160002) (xy 64.496696 -390.160002)
			(xy 64.496201 -390.184609) (xy 64.488306 -390.233186) (xy 64.472722 -390.279867) (xy 64.449851 -390.323444)
			(xy 64.420286 -390.362788) (xy 64.384793 -390.39688) (xy 64.34429 -390.424836) (xy 64.299828 -390.445934)
			(xy 64.252557 -390.459626) (xy 64.203702 -390.465558) (xy 64.154527 -390.463577) (xy 64.106308 -390.453733)
			(xy 64.060292 -390.436281) (xy 64.017671 -390.411674) (xy 63.97955 -390.380549) (xy 63.946915 -390.343712)
			(xy 63.920612 -390.302116) (xy 63.901321 -390.25684) (xy 63.889544 -390.209056) (xy 63.885584 -390.160002)
			(xy 63.296546 -390.160002) (xy 63.296051 -390.184609) (xy 63.288156 -390.233186) (xy 63.272572 -390.279867)
			(xy 63.249701 -390.323444) (xy 63.220136 -390.362788) (xy 63.184643 -390.39688) (xy 63.14414 -390.424836)
			(xy 63.099678 -390.445934) (xy 63.052407 -390.459626) (xy 63.003552 -390.465558) (xy 62.954377 -390.463577)
			(xy 62.906158 -390.453733) (xy 62.860142 -390.436281) (xy 62.817521 -390.411674) (xy 62.7794 -390.380549)
			(xy 62.746765 -390.343712) (xy 62.720462 -390.302116) (xy 62.701171 -390.25684) (xy 62.689394 -390.209056)
			(xy 62.685434 -390.160002) (xy 62.09665 -390.160002) (xy 62.096155 -390.184609) (xy 62.08826 -390.233186)
			(xy 62.072676 -390.279867) (xy 62.049805 -390.323444) (xy 62.02024 -390.362788) (xy 61.984747 -390.39688)
			(xy 61.944244 -390.424836) (xy 61.899782 -390.445934) (xy 61.852511 -390.459626) (xy 61.803656 -390.465558)
			(xy 61.754481 -390.463577) (xy 61.706262 -390.453733) (xy 61.660246 -390.436281) (xy 61.617625 -390.411674)
			(xy 61.579504 -390.380549) (xy 61.546869 -390.343712) (xy 61.520566 -390.302116) (xy 61.501275 -390.25684)
			(xy 61.489498 -390.209056) (xy 61.485538 -390.160002) (xy 60.8965 -390.160002) (xy 60.896005 -390.184609)
			(xy 60.88811 -390.233186) (xy 60.872526 -390.279867) (xy 60.849655 -390.323444) (xy 60.82009 -390.362788)
			(xy 60.784597 -390.39688) (xy 60.744094 -390.424836) (xy 60.699632 -390.445934) (xy 60.652361 -390.459626)
			(xy 60.603506 -390.465558) (xy 60.554331 -390.463577) (xy 60.506112 -390.453733) (xy 60.460096 -390.436281)
			(xy 60.417475 -390.411674) (xy 60.379354 -390.380549) (xy 60.346719 -390.343712) (xy 60.320416 -390.302116)
			(xy 60.301125 -390.25684) (xy 60.289348 -390.209056) (xy 60.285388 -390.160002) (xy 59.696604 -390.160002)
			(xy 59.696109 -390.184609) (xy 59.688214 -390.233186) (xy 59.67263 -390.279867) (xy 59.649759 -390.323444)
			(xy 59.620194 -390.362788) (xy 59.584701 -390.39688) (xy 59.544198 -390.424836) (xy 59.499736 -390.445934)
			(xy 59.452465 -390.459626) (xy 59.40361 -390.465558) (xy 59.354435 -390.463577) (xy 59.306216 -390.453733)
			(xy 59.2602 -390.436281) (xy 59.217579 -390.411674) (xy 59.179458 -390.380549) (xy 59.146823 -390.343712)
			(xy 59.12052 -390.302116) (xy 59.101229 -390.25684) (xy 59.089452 -390.209056) (xy 59.085492 -390.160002)
			(xy 58.496708 -390.160002) (xy 58.496213 -390.184609) (xy 58.488318 -390.233186) (xy 58.472734 -390.279867)
			(xy 58.449863 -390.323444) (xy 58.420298 -390.362788) (xy 58.384805 -390.39688) (xy 58.344302 -390.424836)
			(xy 58.29984 -390.445934) (xy 58.252569 -390.459626) (xy 58.203714 -390.465558) (xy 58.154539 -390.463577)
			(xy 58.10632 -390.453733) (xy 58.060304 -390.436281) (xy 58.017683 -390.411674) (xy 57.979562 -390.380549)
			(xy 57.946927 -390.343712) (xy 57.920624 -390.302116) (xy 57.901333 -390.25684) (xy 57.889556 -390.209056)
			(xy 57.885596 -390.160002) (xy 57.296558 -390.160002) (xy 57.296063 -390.184609) (xy 57.288168 -390.233186)
			(xy 57.272584 -390.279867) (xy 57.249713 -390.323444) (xy 57.220148 -390.362788) (xy 57.184655 -390.39688)
			(xy 57.144152 -390.424836) (xy 57.09969 -390.445934) (xy 57.052419 -390.459626) (xy 57.003564 -390.465558)
			(xy 56.954389 -390.463577) (xy 56.90617 -390.453733) (xy 56.860154 -390.436281) (xy 56.817533 -390.411674)
			(xy 56.779412 -390.380549) (xy 56.746777 -390.343712) (xy 56.720474 -390.302116) (xy 56.701183 -390.25684)
			(xy 56.689406 -390.209056) (xy 56.685446 -390.160002) (xy 56.096662 -390.160002) (xy 56.096167 -390.184609)
			(xy 56.088272 -390.233186) (xy 56.072688 -390.279867) (xy 56.049817 -390.323444) (xy 56.020252 -390.362788)
			(xy 55.984759 -390.39688) (xy 55.944256 -390.424836) (xy 55.899794 -390.445934) (xy 55.852523 -390.459626)
			(xy 55.803668 -390.465558) (xy 55.754493 -390.463577) (xy 55.706274 -390.453733) (xy 55.660258 -390.436281)
			(xy 55.617637 -390.411674) (xy 55.579516 -390.380549) (xy 55.546881 -390.343712) (xy 55.520578 -390.302116)
			(xy 55.501287 -390.25684) (xy 55.48951 -390.209056) (xy 55.48555 -390.160002) (xy 54.896512 -390.160002)
			(xy 54.896017 -390.184609) (xy 54.888122 -390.233186) (xy 54.872538 -390.279867) (xy 54.849667 -390.323444)
			(xy 54.820102 -390.362788) (xy 54.784609 -390.39688) (xy 54.744106 -390.424836) (xy 54.699644 -390.445934)
			(xy 54.652373 -390.459626) (xy 54.603518 -390.465558) (xy 54.554343 -390.463577) (xy 54.506124 -390.453733)
			(xy 54.460108 -390.436281) (xy 54.417487 -390.411674) (xy 54.379366 -390.380549) (xy 54.346731 -390.343712)
			(xy 54.320428 -390.302116) (xy 54.301137 -390.25684) (xy 54.28936 -390.209056) (xy 54.2854 -390.160002)
			(xy 53.710586 -390.160002) (xy 53.710586 -390.696704) (xy 53.711009 -390.706774) (xy 53.718723 -390.725379)
			(xy 53.725572 -390.732772) (xy 54.137814 -391.145014) (xy 54.145209 -391.151868) (xy 54.163808 -391.15961)
			(xy 54.173882 -391.16)
		)
		(stroke
			(width 0)
			(type solid)
		)
		(fill yes)
		(layer "In13.Cu")
		(net "P1V8_CPU1_RT0_1A_1D")
	)
	(gr_poly
		(pts
			(xy 439.246264 -370.571014) (xy 439.256138 -370.570546) (xy 439.274426 -370.563092) (xy 439.281824 -370.556536)
			(xy 439.282078 -370.556282) (xy 445.010794 -364.827566) (xy 445.011302 -364.827058) (xy 445.017891 -364.81968)
			(xy 445.025353 -364.80138) (xy 445.02578 -364.791498) (xy 445.02578 -349.601282) (xy 445.025353 -349.591214)
			(xy 445.017632 -349.572616) (xy 445.010794 -349.565214) (xy 437.743346 -342.297766) (xy 437.736234 -342.2904)
			(xy 437.717438 -342.28278) (xy 410.741622 -342.28278) (xy 410.731558 -342.283217) (xy 410.712972 -342.290949)
			(xy 410.705554 -342.297766) (xy 410.096716 -342.906604) (xy 410.08935 -342.913716) (xy 410.08173 -342.932512)
			(xy 410.08173 -352.769678) (xy 419.579552 -352.769678) (xy 419.580041 -352.741767) (xy 419.588178 -352.686542)
			(xy 419.604275 -352.633091) (xy 419.627988 -352.582556) (xy 419.658812 -352.536016) (xy 419.677088 -352.514916)
			(xy 419.683438 -352.507804) (xy 419.690042 -352.490532) (xy 419.690042 -352.40341) (xy 419.683438 -352.386138)
			(xy 419.677088 -352.379026) (xy 419.658799 -352.357936) (xy 419.627973 -352.311395) (xy 419.604261 -352.260858)
			(xy 419.588167 -352.207404) (xy 419.580036 -352.152176) (xy 419.579552 -352.124264) (xy 419.580038 -352.097013)
			(xy 419.587794 -352.043065) (xy 419.603149 -351.99077) (xy 419.625791 -351.941193) (xy 419.655257 -351.895343)
			(xy 419.690948 -351.854152) (xy 419.732139 -351.818461) (xy 419.777989 -351.788995) (xy 419.827566 -351.766353)
			(xy 419.879861 -351.750998) (xy 419.933809 -351.743242) (xy 419.988311 -351.743242) (xy 420.042259 -351.750998)
			(xy 420.094554 -351.766353) (xy 420.144131 -351.788995) (xy 420.189981 -351.818461) (xy 420.231172 -351.854152)
			(xy 420.266863 -351.895343) (xy 420.296329 -351.941193) (xy 420.318971 -351.99077) (xy 420.334326 -352.043065)
			(xy 420.342082 -352.097013) (xy 420.342568 -352.124264) (xy 420.342099 -352.152176) (xy 420.333956 -352.207402)
			(xy 420.317855 -352.260852) (xy 420.294137 -352.311386) (xy 420.26331 -352.357926) (xy 420.245032 -352.379026)
			(xy 420.238682 -352.386138) (xy 420.232078 -352.40341) (xy 420.232078 -352.490532) (xy 420.238682 -352.507804)
			(xy 420.245032 -352.514916) (xy 420.263297 -352.536026) (xy 420.294125 -352.582562) (xy 420.317842 -352.633094)
			(xy 420.333942 -352.686543) (xy 420.34208 -352.741768) (xy 420.342568 -352.769678) (xy 420.342082 -352.796929)
			(xy 420.334326 -352.850877) (xy 420.318971 -352.903172) (xy 420.296329 -352.952749) (xy 420.266863 -352.998599)
			(xy 420.231172 -353.03979) (xy 420.189981 -353.075481) (xy 420.146849 -353.1032) (xy 423.961713 -353.1032)
			(xy 423.965882 -353.047576) (xy 423.978295 -352.993194) (xy 423.998676 -352.94127) (xy 424.026567 -352.892964)
			(xy 424.061348 -352.849355) (xy 424.10224 -352.811417) (xy 424.14833 -352.779998) (xy 424.198588 -352.755799)
			(xy 424.251892 -352.739362) (xy 424.30705 -352.731054) (xy 424.33494 -352.730562) (xy 424.361362 -352.731005)
			(xy 424.413678 -352.73846) (xy 424.464416 -352.753229) (xy 424.51256 -352.775016) (xy 424.557145 -352.803384)
			(xy 424.57751 -352.820224) (xy 424.584368 -352.82632) (xy 424.601386 -352.832416) (xy 424.685714 -352.832416)
			(xy 424.702732 -352.82632) (xy 424.70959 -352.820224) (xy 424.729956 -352.803385) (xy 424.774542 -352.77502)
			(xy 424.822686 -352.753233) (xy 424.873423 -352.738462) (xy 424.925738 -352.731002) (xy 424.978582 -352.731002)
			(xy 425.030897 -352.738462) (xy 425.081634 -352.753233) (xy 425.129778 -352.77502) (xy 425.174364 -352.803385)
			(xy 425.19473 -352.820224) (xy 425.201588 -352.82632) (xy 425.218606 -352.832416) (xy 425.302934 -352.832416)
			(xy 425.319952 -352.82632) (xy 425.32681 -352.820224) (xy 425.340704 -352.80864) (xy 425.370347 -352.787903)
			(xy 425.385992 -352.778822) (xy 425.396406 -352.77298) (xy 425.409614 -352.753676) (xy 425.424854 -352.65106)
			(xy 425.417996 -352.628962) (xy 425.409868 -352.620326) (xy 425.390283 -352.598948) (xy 425.357166 -352.55136)
			(xy 425.331637 -352.499306) (xy 425.314283 -352.443987) (xy 425.305506 -352.386678) (xy 425.304966 -352.35769)
			(xy 425.305471 -352.330117) (xy 425.313412 -352.275545) (xy 425.329128 -352.222684) (xy 425.352291 -352.172638)
			(xy 425.382418 -352.126448) (xy 425.418881 -352.085076) (xy 425.439586 -352.06686) (xy 425.447716 -352.059268)
			(xy 425.457064 -352.039109) (xy 425.45762 -352.027998) (xy 425.45762 -351.950782) (xy 425.457104 -351.939665)
			(xy 425.447731 -351.919505) (xy 425.439586 -351.91192) (xy 425.418879 -351.893705) (xy 425.382409 -351.852337)
			(xy 425.352276 -351.806147) (xy 425.32911 -351.7561) (xy 425.313393 -351.703239) (xy 425.305452 -351.648664)
			(xy 425.304966 -351.62109) (xy 425.305452 -351.593839) (xy 425.313208 -351.539891) (xy 425.328563 -351.487596)
			(xy 425.351205 -351.438019) (xy 425.380671 -351.392169) (xy 425.416362 -351.350978) (xy 425.457553 -351.315287)
			(xy 425.503403 -351.285821) (xy 425.55298 -351.263179) (xy 425.605275 -351.247824) (xy 425.659223 -351.240068)
			(xy 425.713725 -351.240068) (xy 425.767673 -351.247824) (xy 425.819968 -351.263179) (xy 425.869545 -351.285821)
			(xy 425.915395 -351.315287) (xy 425.956586 -351.350978) (xy 425.992277 -351.392169) (xy 426.021743 -351.438019)
			(xy 426.044385 -351.487596) (xy 426.05974 -351.539891) (xy 426.067496 -351.593839) (xy 426.067982 -351.62109)
			(xy 426.067516 -351.648665) (xy 426.059564 -351.703238) (xy 426.04384 -351.756098) (xy 426.02067 -351.806144)
			(xy 425.990537 -351.852333) (xy 425.954069 -351.893704) (xy 425.933362 -351.91192) (xy 425.925233 -351.919513)
			(xy 425.915886 -351.939672) (xy 425.915328 -351.950782) (xy 425.915328 -352.027998) (xy 425.915872 -352.039111)
			(xy 425.925227 -352.05927) (xy 425.933362 -352.06686) (xy 425.954049 -352.085097) (xy 425.990523 -352.126459)
			(xy 426.020659 -352.172644) (xy 426.043829 -352.222687) (xy 426.05955 -352.275545) (xy 426.067495 -352.330117)
			(xy 426.067982 -352.35769) (xy 426.06742 -352.386882) (xy 426.058512 -352.444583) (xy 426.040918 -352.500254)
			(xy 426.015049 -352.552595) (xy 425.981509 -352.600384) (xy 425.94108 -352.642507) (xy 425.894706 -352.677978)
			(xy 425.869354 -352.692462) (xy 425.85894 -352.698304) (xy 425.845478 -352.7171) (xy 425.832707 -352.795078)
			(xy 427.90618 -352.795078) (xy 427.906662 -352.767167) (xy 427.914799 -352.711941) (xy 427.930898 -352.65849)
			(xy 427.954613 -352.607955) (xy 427.985438 -352.561416) (xy 428.003716 -352.540316) (xy 428.010066 -352.533204)
			(xy 428.01667 -352.515932) (xy 428.01667 -352.42881) (xy 428.010066 -352.411538) (xy 428.003716 -352.404426)
			(xy 427.985431 -352.383332) (xy 427.954604 -352.336792) (xy 427.93089 -352.286256) (xy 427.914795 -352.232804)
			(xy 427.906664 -352.177576) (xy 427.90618 -352.149664) (xy 427.906666 -352.122413) (xy 427.914422 -352.068465)
			(xy 427.929777 -352.01617) (xy 427.952419 -351.966593) (xy 427.981885 -351.920743) (xy 428.017576 -351.879552)
			(xy 428.058767 -351.843861) (xy 428.104617 -351.814395) (xy 428.154194 -351.791753) (xy 428.206489 -351.776398)
			(xy 428.260437 -351.768642) (xy 428.314939 -351.768642) (xy 428.368887 -351.776398) (xy 428.421182 -351.791753)
			(xy 428.470759 -351.814395) (xy 428.516609 -351.843861) (xy 428.5578 -351.879552) (xy 428.593491 -351.920743)
			(xy 428.622957 -351.966593) (xy 428.645599 -352.01617) (xy 428.660954 -352.068465) (xy 428.66871 -352.122413)
			(xy 428.669196 -352.149664) (xy 428.66872 -352.177575) (xy 428.660578 -352.232801) (xy 428.644477 -352.286251)
			(xy 428.620762 -352.336785) (xy 428.589937 -352.383325) (xy 428.57166 -352.404426) (xy 428.56531 -352.411538)
			(xy 428.558706 -352.42881) (xy 428.558706 -352.515932) (xy 428.56531 -352.533204) (xy 428.57166 -352.540316)
			(xy 428.589929 -352.561423) (xy 428.620756 -352.60796) (xy 428.644472 -352.658493) (xy 428.660571 -352.711942)
			(xy 428.668708 -352.767167) (xy 428.669196 -352.795078) (xy 428.66871 -352.822329) (xy 428.660954 -352.876277)
			(xy 428.645599 -352.928572) (xy 428.622957 -352.978149) (xy 428.593491 -353.023999) (xy 428.5578 -353.06519)
			(xy 428.516609 -353.100881) (xy 428.473477 -353.1286) (xy 432.288439 -353.1286) (xy 432.292607 -353.072986)
			(xy 432.305016 -353.018615) (xy 432.32539 -352.9667) (xy 432.353273 -352.918401) (xy 432.388044 -352.874798)
			(xy 432.428924 -352.836863) (xy 432.475001 -352.805444) (xy 432.525246 -352.781244) (xy 432.578537 -352.764802)
			(xy 432.633683 -352.756485) (xy 432.661568 -352.755962) (xy 432.687991 -352.756389) (xy 432.740307 -352.763848)
			(xy 432.791046 -352.778621) (xy 432.83919 -352.800411) (xy 432.883773 -352.828782) (xy 432.904138 -352.845624)
			(xy 432.910996 -352.85172) (xy 432.928014 -352.857816) (xy 433.012342 -352.857816) (xy 433.02936 -352.85172)
			(xy 433.036218 -352.845624) (xy 433.056584 -352.828785) (xy 433.10117 -352.80042) (xy 433.149314 -352.778633)
			(xy 433.200051 -352.763862) (xy 433.252366 -352.756402) (xy 433.30521 -352.756402) (xy 433.357525 -352.763862)
			(xy 433.408262 -352.778633) (xy 433.456406 -352.80042) (xy 433.500992 -352.828785) (xy 433.521358 -352.845624)
			(xy 433.528216 -352.85172) (xy 433.545234 -352.857816) (xy 433.629562 -352.857816) (xy 433.64658 -352.85172)
			(xy 433.653438 -352.845624) (xy 433.66733 -352.834037) (xy 433.696974 -352.813302) (xy 433.71262 -352.804222)
			(xy 433.723034 -352.79838) (xy 433.736242 -352.779076) (xy 433.751482 -352.67646) (xy 433.744624 -352.654362)
			(xy 433.736496 -352.645726) (xy 433.716915 -352.624343) (xy 433.683797 -352.576757) (xy 433.658266 -352.524705)
			(xy 433.640912 -352.469387) (xy 433.632134 -352.412078) (xy 433.631594 -352.38309) (xy 433.632124 -352.355518)
			(xy 433.640063 -352.300948) (xy 433.655776 -352.248089) (xy 433.678934 -352.198043) (xy 433.709055 -352.151852)
			(xy 433.745512 -352.110478) (xy 433.766214 -352.09226) (xy 433.774348 -352.084672) (xy 433.783693 -352.064509)
			(xy 433.784248 -352.053398) (xy 433.784248 -351.976182) (xy 433.783723 -351.965067) (xy 433.774356 -351.944907)
			(xy 433.766214 -351.93732) (xy 433.745512 -351.919099) (xy 433.709041 -351.877732) (xy 433.678907 -351.831545)
			(xy 433.655739 -351.781499) (xy 433.640021 -351.728638) (xy 433.63208 -351.674064) (xy 433.631594 -351.64649)
			(xy 433.63208 -351.619239) (xy 433.639836 -351.565291) (xy 433.655191 -351.512996) (xy 433.677833 -351.463419)
			(xy 433.707299 -351.417569) (xy 433.74299 -351.376378) (xy 433.784181 -351.340687) (xy 433.830031 -351.311221)
			(xy 433.879608 -351.288579) (xy 433.931903 -351.273224) (xy 433.985851 -351.265468) (xy 434.040353 -351.265468)
			(xy 434.094301 -351.273224) (xy 434.146596 -351.288579) (xy 434.196173 -351.311221) (xy 434.242023 -351.340687)
			(xy 434.283214 -351.376378) (xy 434.318905 -351.417569) (xy 434.348371 -351.463419) (xy 434.371013 -351.512996)
			(xy 434.386368 -351.565291) (xy 434.394124 -351.619239) (xy 434.39461 -351.64649) (xy 434.394134 -351.674064)
			(xy 434.386183 -351.728636) (xy 434.37046 -351.781496) (xy 434.347292 -351.831542) (xy 434.317161 -351.877732)
			(xy 434.280696 -351.919104) (xy 434.25999 -351.93732) (xy 434.251865 -351.944917) (xy 434.242515 -351.965073)
			(xy 434.241956 -351.976182) (xy 434.241956 -352.053398) (xy 434.242491 -352.064512) (xy 434.251851 -352.084672)
			(xy 434.25999 -352.09226) (xy 434.280683 -352.110491) (xy 434.317155 -352.151855) (xy 434.34729 -352.198041)
			(xy 434.370459 -352.248085) (xy 434.386179 -352.300944) (xy 434.394123 -352.355516) (xy 434.39461 -352.38309)
			(xy 434.394033 -352.412282) (xy 434.385126 -352.469981) (xy 434.367534 -352.525651) (xy 434.341667 -352.577991)
			(xy 434.308129 -352.625781) (xy 434.267703 -352.667904) (xy 434.221332 -352.703377) (xy 434.195982 -352.717862)
			(xy 434.185568 -352.723704) (xy 434.172106 -352.7425) (xy 434.155342 -352.844862) (xy 434.161946 -352.867214)
			(xy 434.16982 -352.87585) (xy 434.18828 -352.896625) (xy 434.219491 -352.942607) (xy 434.243527 -352.992715)
			(xy 434.259854 -353.045836) (xy 434.268111 -353.100793) (xy 434.268626 -353.12858) (xy 434.268147 -353.155197)
			(xy 434.260574 -353.207889) (xy 434.245579 -353.258968) (xy 434.223467 -353.307392) (xy 434.194688 -353.352176)
			(xy 434.159829 -353.392409) (xy 434.119599 -353.427271) (xy 434.074817 -353.456053) (xy 434.026394 -353.478169)
			(xy 433.975317 -353.493168) (xy 433.922625 -353.500745) (xy 433.896008 -353.501198) (xy 433.869586 -353.500736)
			(xy 433.817271 -353.493287) (xy 433.766532 -353.478523) (xy 433.718388 -353.45674) (xy 433.673803 -353.428375)
			(xy 433.653438 -353.411536) (xy 433.64658 -353.40544) (xy 433.629562 -353.399344) (xy 433.545234 -353.399344)
			(xy 433.528216 -353.40544) (xy 433.521358 -353.411536) (xy 433.500992 -353.428375) (xy 433.456406 -353.45674)
			(xy 433.408262 -353.478527) (xy 433.357525 -353.493298) (xy 433.30521 -353.500758) (xy 433.252366 -353.500758)
			(xy 433.200051 -353.493298) (xy 433.149314 -353.478527) (xy 433.10117 -353.45674) (xy 433.056584 -353.428375)
			(xy 433.036218 -353.411536) (xy 433.02936 -353.40544) (xy 433.012342 -353.399344) (xy 432.928014 -353.399344)
			(xy 432.910996 -353.40544) (xy 432.904138 -353.411536) (xy 432.883751 -353.428346) (xy 432.839168 -353.456708)
			(xy 432.791029 -353.478494) (xy 432.740297 -353.493268) (xy 432.687988 -353.500734) (xy 432.661568 -353.501198)
			(xy 432.633683 -353.500715) (xy 432.578537 -353.492398) (xy 432.525246 -353.475956) (xy 432.475001 -353.451756)
			(xy 432.428924 -353.420337) (xy 432.388044 -353.382402) (xy 432.353273 -353.338799) (xy 432.32539 -353.2905)
			(xy 432.305016 -353.238585) (xy 432.292607 -353.184214) (xy 432.288439 -353.1286) (xy 428.473477 -353.1286)
			(xy 428.470759 -353.130347) (xy 428.421182 -353.152989) (xy 428.368887 -353.168344) (xy 428.314939 -353.1761)
			(xy 428.260437 -353.1761) (xy 428.206489 -353.168344) (xy 428.154194 -353.152989) (xy 428.104617 -353.130347)
			(xy 428.058767 -353.100881) (xy 428.017576 -353.06519) (xy 427.981885 -353.023999) (xy 427.952419 -352.978149)
			(xy 427.929777 -352.928572) (xy 427.914422 -352.876277) (xy 427.906666 -352.822329) (xy 427.90618 -352.795078)
			(xy 425.832707 -352.795078) (xy 425.828714 -352.819462) (xy 425.835318 -352.841814) (xy 425.843192 -352.85045)
			(xy 425.861647 -352.871229) (xy 425.89286 -352.91721) (xy 425.916897 -352.967316) (xy 425.933226 -353.020437)
			(xy 425.941483 -353.075393) (xy 425.941998 -353.10318) (xy 425.941547 -353.129798) (xy 425.933973 -353.182493)
			(xy 425.918976 -353.233574) (xy 425.896862 -353.282) (xy 425.868081 -353.326785) (xy 425.833219 -353.367019)
			(xy 425.792985 -353.401881) (xy 425.7482 -353.430662) (xy 425.699774 -353.452776) (xy 425.648693 -353.467773)
			(xy 425.595998 -353.475347) (xy 425.56938 -353.475798) (xy 425.542958 -353.475352) (xy 425.490642 -353.4679)
			(xy 425.439903 -353.453132) (xy 425.391759 -353.431345) (xy 425.347175 -353.402977) (xy 425.32681 -353.386136)
			(xy 425.319952 -353.38004) (xy 425.302934 -353.373944) (xy 425.218606 -353.373944) (xy 425.201588 -353.38004)
			(xy 425.19473 -353.386136) (xy 425.174364 -353.402975) (xy 425.129778 -353.43134) (xy 425.081634 -353.453127)
			(xy 425.030897 -353.467898) (xy 424.978582 -353.475358) (xy 424.925738 -353.475358) (xy 424.873423 -353.467898)
			(xy 424.822686 -353.453127) (xy 424.774542 -353.43134) (xy 424.729956 -353.402975) (xy 424.70959 -353.386136)
			(xy 424.702732 -353.38004) (xy 424.685714 -353.373944) (xy 424.601386 -353.373944) (xy 424.584368 -353.38004)
			(xy 424.57751 -353.386136) (xy 424.557133 -353.40296) (xy 424.512547 -353.431319) (xy 424.464405 -353.453102)
			(xy 424.413671 -353.467873) (xy 424.36136 -353.475336) (xy 424.33494 -353.475798) (xy 424.30705 -353.475346)
			(xy 424.251892 -353.467038) (xy 424.198588 -353.450601) (xy 424.14833 -353.426402) (xy 424.10224 -353.394983)
			(xy 424.061348 -353.357045) (xy 424.026567 -353.313436) (xy 423.998676 -353.26513) (xy 423.978295 -353.213206)
			(xy 423.965882 -353.158824) (xy 423.961713 -353.1032) (xy 420.146849 -353.1032) (xy 420.144131 -353.104947)
			(xy 420.094554 -353.127589) (xy 420.042259 -353.142944) (xy 419.988311 -353.1507) (xy 419.933809 -353.1507)
			(xy 419.879861 -353.142944) (xy 419.827566 -353.127589) (xy 419.777989 -353.104947) (xy 419.732139 -353.075481)
			(xy 419.690948 -353.03979) (xy 419.655257 -352.998599) (xy 419.625791 -352.952749) (xy 419.603149 -352.903172)
			(xy 419.587794 -352.850877) (xy 419.580038 -352.796929) (xy 419.579552 -352.769678) (xy 410.08173 -352.769678)
			(xy 410.08173 -354.001324) (xy 420.537384 -354.001324) (xy 420.541455 -353.945702) (xy 420.553581 -353.891265)
			(xy 420.573504 -353.839174) (xy 420.6008 -353.790539) (xy 420.634886 -353.746396) (xy 420.675035 -353.707687)
			(xy 420.720393 -353.675236) (xy 420.769993 -353.649735) (xy 420.822777 -353.631728) (xy 420.87762 -353.621598)
			(xy 420.933354 -353.619561) (xy 420.988791 -353.625661) (xy 421.042748 -353.639767) (xy 421.094077 -353.661579)
			(xy 421.141683 -353.690633) (xy 421.184551 -353.726308) (xy 421.221768 -353.767845) (xy 421.252541 -353.814358)
			(xy 421.276213 -353.864855) (xy 421.292281 -353.918262) (xy 421.300401 -353.973438) (xy 421.30091 -354.001324)
			(xy 421.300401 -354.02921) (xy 421.292281 -354.084386) (xy 421.276213 -354.137793) (xy 421.252541 -354.18829)
			(xy 421.221768 -354.234803) (xy 421.184551 -354.27634) (xy 421.141683 -354.312015) (xy 421.094077 -354.341069)
			(xy 421.042748 -354.362881) (xy 420.988791 -354.376987) (xy 420.933354 -354.383087) (xy 420.87762 -354.38105)
			(xy 420.822777 -354.37092) (xy 420.769993 -354.352913) (xy 420.720393 -354.327412) (xy 420.675035 -354.294961)
			(xy 420.634886 -354.256252) (xy 420.6008 -354.212109) (xy 420.573504 -354.163474) (xy 420.553581 -354.111383)
			(xy 420.541455 -354.056946) (xy 420.537384 -354.001324) (xy 410.08173 -354.001324) (xy 410.08173 -354.613972)
			(xy 416.45408 -354.613972) (xy 416.458151 -354.55835) (xy 416.470277 -354.503913) (xy 416.4902 -354.451822)
			(xy 416.517496 -354.403187) (xy 416.551582 -354.359044) (xy 416.591731 -354.320335) (xy 416.637089 -354.287884)
			(xy 416.686689 -354.262383) (xy 416.739473 -354.244376) (xy 416.794316 -354.234246) (xy 416.85005 -354.232209)
			(xy 416.905487 -354.238309) (xy 416.959444 -354.252415) (xy 417.010773 -354.274227) (xy 417.058379 -354.303281)
			(xy 417.101247 -354.338956) (xy 417.138464 -354.380493) (xy 417.169237 -354.427006) (xy 417.192909 -354.477503)
			(xy 417.208977 -354.53091) (xy 417.217097 -354.586086) (xy 417.217606 -354.613972) (xy 417.217097 -354.641858)
			(xy 417.208977 -354.697034) (xy 417.192909 -354.750441) (xy 417.182464 -354.772722) (xy 418.51402 -354.772722)
			(xy 418.518091 -354.7171) (xy 418.530217 -354.662663) (xy 418.55014 -354.610572) (xy 418.577436 -354.561937)
			(xy 418.611522 -354.517794) (xy 418.651671 -354.479085) (xy 418.697029 -354.446634) (xy 418.746629 -354.421133)
			(xy 418.799413 -354.403126) (xy 418.854256 -354.392996) (xy 418.90999 -354.390959) (xy 418.965427 -354.397059)
			(xy 419.019384 -354.411165) (xy 419.070713 -354.432977) (xy 419.118319 -354.462031) (xy 419.161187 -354.497706)
			(xy 419.198404 -354.539243) (xy 419.229177 -354.585756) (xy 419.252849 -354.636253) (xy 419.268917 -354.68966)
			(xy 419.277037 -354.744836) (xy 419.277546 -354.772722) (xy 419.277037 -354.800608) (xy 419.268917 -354.855784)
			(xy 419.256615 -354.896674) (xy 419.958264 -354.896674) (xy 419.962335 -354.841052) (xy 419.974461 -354.786615)
			(xy 419.994384 -354.734524) (xy 420.02168 -354.685889) (xy 420.055766 -354.641746) (xy 420.095915 -354.603037)
			(xy 420.141273 -354.570586) (xy 420.190873 -354.545085) (xy 420.243657 -354.527078) (xy 420.2985 -354.516948)
			(xy 420.354234 -354.514911) (xy 420.409671 -354.521011) (xy 420.463628 -354.535117) (xy 420.514957 -354.556929)
			(xy 420.562563 -354.585983) (xy 420.605431 -354.621658) (xy 420.642648 -354.663195) (xy 420.673421 -354.709708)
			(xy 420.697093 -354.760205) (xy 420.713161 -354.813612) (xy 420.721281 -354.868788) (xy 420.72179 -354.896674)
			(xy 420.721281 -354.92456) (xy 420.713161 -354.979736) (xy 420.697093 -355.033143) (xy 420.673421 -355.08364)
			(xy 420.642648 -355.130153) (xy 420.605431 -355.17169) (xy 420.562563 -355.207365) (xy 420.514957 -355.236419)
			(xy 420.463628 -355.258231) (xy 420.409671 -355.272337) (xy 420.354234 -355.278437) (xy 420.2985 -355.2764)
			(xy 420.243657 -355.26627) (xy 420.190873 -355.248263) (xy 420.141273 -355.222762) (xy 420.095915 -355.190311)
			(xy 420.055766 -355.151602) (xy 420.02168 -355.107459) (xy 419.994384 -355.058824) (xy 419.974461 -355.006733)
			(xy 419.962335 -354.952296) (xy 419.958264 -354.896674) (xy 419.256615 -354.896674) (xy 419.252849 -354.909191)
			(xy 419.229177 -354.959688) (xy 419.198404 -355.006201) (xy 419.161187 -355.047738) (xy 419.118319 -355.083413)
			(xy 419.070713 -355.112467) (xy 419.019384 -355.134279) (xy 418.965427 -355.148385) (xy 418.90999 -355.154485)
			(xy 418.854256 -355.152448) (xy 418.799413 -355.142318) (xy 418.746629 -355.124311) (xy 418.697029 -355.09881)
			(xy 418.651671 -355.066359) (xy 418.611522 -355.02765) (xy 418.577436 -354.983507) (xy 418.55014 -354.934872)
			(xy 418.530217 -354.882781) (xy 418.518091 -354.828344) (xy 418.51402 -354.772722) (xy 417.182464 -354.772722)
			(xy 417.169237 -354.800938) (xy 417.138464 -354.847451) (xy 417.101247 -354.888988) (xy 417.058379 -354.924663)
			(xy 417.010773 -354.953717) (xy 416.959444 -354.975529) (xy 416.905487 -354.989635) (xy 416.85005 -354.995735)
			(xy 416.794316 -354.993698) (xy 416.739473 -354.983568) (xy 416.686689 -354.965561) (xy 416.637089 -354.94006)
			(xy 416.591731 -354.907609) (xy 416.551582 -354.8689) (xy 416.517496 -354.824757) (xy 416.4902 -354.776122)
			(xy 416.470277 -354.724031) (xy 416.458151 -354.669594) (xy 416.45408 -354.613972) (xy 410.08173 -354.613972)
			(xy 410.08173 -355.572314) (xy 421.2971 -355.572314) (xy 421.297595 -355.54484) (xy 421.305484 -355.49046)
			(xy 421.321103 -355.437778) (xy 421.344125 -355.387885) (xy 421.374075 -355.341816) (xy 421.391842 -355.320854)
			(xy 421.397938 -355.313742) (xy 421.404288 -355.296724) (xy 421.404288 -355.210872) (xy 421.397938 -355.193854)
			(xy 421.391842 -355.186742) (xy 421.374108 -355.165756) (xy 421.34418 -355.11968) (xy 421.321163 -355.069792)
			(xy 421.30553 -355.01712) (xy 421.297604 -354.962753) (xy 421.2971 -354.935282) (xy 421.297586 -354.908031)
			(xy 421.305342 -354.854083) (xy 421.320697 -354.801788) (xy 421.343339 -354.752211) (xy 421.372805 -354.706361)
			(xy 421.408496 -354.66517) (xy 421.449687 -354.629479) (xy 421.495537 -354.600013) (xy 421.545114 -354.577371)
			(xy 421.597409 -354.562016) (xy 421.651357 -354.55426) (xy 421.705859 -354.55426) (xy 421.759807 -354.562016)
			(xy 421.812102 -354.577371) (xy 421.861679 -354.600013) (xy 421.907529 -354.629479) (xy 421.94872 -354.66517)
			(xy 421.984411 -354.706361) (xy 422.013877 -354.752211) (xy 422.036519 -354.801788) (xy 422.051874 -354.854083)
			(xy 422.05963 -354.908031) (xy 422.060116 -354.935282) (xy 422.059615 -354.962756) (xy 422.051726 -355.017135)
			(xy 422.036109 -355.069817) (xy 422.033462 -355.075553) (xy 422.301867 -355.075553) (xy 422.301867 -355.021047)
			(xy 422.309625 -354.967096) (xy 422.324981 -354.914797) (xy 422.347625 -354.865217) (xy 422.377094 -354.819364)
			(xy 422.412789 -354.778172) (xy 422.453984 -354.74248) (xy 422.499838 -354.713014) (xy 422.54942 -354.690373)
			(xy 422.601719 -354.67502) (xy 422.655671 -354.667266) (xy 422.682924 -354.666804) (xy 422.70816 -354.66719)
			(xy 422.758194 -354.673811) (xy 422.806914 -354.686987) (xy 422.853466 -354.706488) (xy 422.875456 -354.718874)
			(xy 422.885108 -354.724716) (xy 422.907206 -354.726748) (xy 423.001694 -354.69322) (xy 423.017696 -354.677726)
			(xy 423.02176 -354.667312) (xy 423.032479 -354.640545) (xy 423.060763 -354.590304) (xy 423.096289 -354.544893)
			(xy 423.138247 -354.50535) (xy 423.185681 -354.472575) (xy 423.23751 -354.447315) (xy 423.29255 -354.430147)
			(xy 423.349548 -354.421463) (xy 423.378376 -354.420932) (xy 423.40563 -354.421378) (xy 423.459584 -354.429133)
			(xy 423.511884 -354.444488) (xy 423.561467 -354.46713) (xy 423.607322 -354.496599) (xy 423.648516 -354.532295)
			(xy 423.68421 -354.573491) (xy 423.713678 -354.619347) (xy 423.736318 -354.668931) (xy 423.74904 -354.71227)
			(xy 425.889928 -354.71227) (xy 425.890432 -354.684697) (xy 425.898375 -354.630125) (xy 425.914092 -354.577266)
			(xy 425.937255 -354.527219) (xy 425.967381 -354.481029) (xy 426.003843 -354.439656) (xy 426.024548 -354.42144)
			(xy 426.032651 -354.413824) (xy 426.042012 -354.393683) (xy 426.042582 -354.382578) (xy 426.042582 -354.305362)
			(xy 426.042057 -354.294247) (xy 426.032689 -354.274088) (xy 426.024548 -354.2665) (xy 426.003843 -354.248282)
			(xy 425.96737 -354.206916) (xy 425.937236 -354.160728) (xy 425.914069 -354.110681) (xy 425.898352 -354.057819)
			(xy 425.890413 -354.003245) (xy 425.889928 -353.97567) (xy 425.890327 -353.948415) (xy 425.898089 -353.89446)
			(xy 425.913451 -353.842158) (xy 425.936099 -353.792576) (xy 425.965574 -353.746721) (xy 426.001274 -353.705528)
			(xy 426.042474 -353.669834) (xy 426.088334 -353.640368) (xy 426.13792 -353.617728) (xy 426.190224 -353.602375)
			(xy 426.244181 -353.594622) (xy 426.271436 -353.594162) (xy 426.305726 -353.595686) (xy 426.315886 -353.596702)
			(xy 426.33519 -353.590606) (xy 426.405802 -353.531424) (xy 426.4152 -353.51339) (xy 426.416216 -353.50323)
			(xy 426.419119 -353.475051) (xy 426.432297 -353.419956) (xy 426.453481 -353.367416) (xy 426.482204 -353.318589)
			(xy 426.517834 -353.274547) (xy 426.559587 -353.236261) (xy 426.606544 -353.204572) (xy 426.657673 -353.180179)
			(xy 426.711847 -353.163617) (xy 426.767875 -353.155252) (xy 426.7962 -353.154742) (xy 426.814219 -353.154968)
			(xy 426.850094 -353.158399) (xy 426.867828 -353.1616) (xy 426.877226 -353.163378) (xy 426.896276 -353.159568)
			(xy 426.97146 -353.111816) (xy 426.98289 -353.096068) (xy 426.985176 -353.08667) (xy 426.99262 -353.05964)
			(xy 427.014245 -353.007915) (xy 427.043203 -352.959911) (xy 427.078873 -352.91666) (xy 427.120486 -352.879092)
			(xy 427.167147 -352.848016) (xy 427.217853 -352.8241) (xy 427.271512 -352.80786) (xy 427.326969 -352.799644)
			(xy 427.355 -352.799142) (xy 427.382255 -352.799555) (xy 427.43621 -352.807314) (xy 427.488512 -352.822672)
			(xy 427.538096 -352.845318) (xy 427.583951 -352.874791) (xy 427.625145 -352.91049) (xy 427.660839 -352.951689)
			(xy 427.690306 -352.997548) (xy 427.712945 -353.047135) (xy 427.728297 -353.099438) (xy 427.736048 -353.153395)
			(xy 427.736508 -353.18065) (xy 427.736005 -353.208223) (xy 427.72806 -353.262794) (xy 427.712342 -353.315653)
			(xy 427.689179 -353.365699) (xy 427.659053 -353.41189) (xy 427.622592 -353.453263) (xy 427.601888 -353.47148)
			(xy 427.593781 -353.479093) (xy 427.584421 -353.499237) (xy 427.583854 -353.510342) (xy 427.583854 -353.587558)
			(xy 427.584412 -353.59867) (xy 427.593756 -353.618829) (xy 427.601888 -353.62642) (xy 427.622644 -353.644581)
			(xy 427.659109 -353.685959) (xy 427.689236 -353.732156) (xy 427.712397 -353.78221) (xy 427.728109 -353.835077)
			(xy 427.736046 -353.889656) (xy 427.736041 -353.944809) (xy 427.728095 -353.999386) (xy 427.719965 -354.026724)
			(xy 428.864012 -354.026724) (xy 428.868083 -353.971102) (xy 428.880209 -353.916665) (xy 428.900132 -353.864574)
			(xy 428.927428 -353.815939) (xy 428.961514 -353.771796) (xy 429.001663 -353.733087) (xy 429.047021 -353.700636)
			(xy 429.096621 -353.675135) (xy 429.149405 -353.657128) (xy 429.204248 -353.646998) (xy 429.259982 -353.644961)
			(xy 429.315419 -353.651061) (xy 429.369376 -353.665167) (xy 429.420705 -353.686979) (xy 429.468311 -353.716033)
			(xy 429.511179 -353.751708) (xy 429.548396 -353.793245) (xy 429.579169 -353.839758) (xy 429.602841 -353.890255)
			(xy 429.618909 -353.943662) (xy 429.627029 -353.998838) (xy 429.627538 -354.026724) (xy 429.627029 -354.05461)
			(xy 429.618909 -354.109786) (xy 429.602841 -354.163193) (xy 429.579169 -354.21369) (xy 429.548396 -354.260203)
			(xy 429.511179 -354.30174) (xy 429.468311 -354.337415) (xy 429.420705 -354.366469) (xy 429.369376 -354.388281)
			(xy 429.315419 -354.402387) (xy 429.259982 -354.408487) (xy 429.204248 -354.40645) (xy 429.149405 -354.39632)
			(xy 429.096621 -354.378313) (xy 429.047021 -354.352812) (xy 429.001663 -354.320361) (xy 428.961514 -354.281652)
			(xy 428.927428 -354.237509) (xy 428.900132 -354.188874) (xy 428.880209 -354.136783) (xy 428.868083 -354.082346)
			(xy 428.864012 -354.026724) (xy 427.719965 -354.026724) (xy 427.712374 -354.052251) (xy 427.689204 -354.102301)
			(xy 427.65907 -354.148493) (xy 427.622598 -354.189865) (xy 427.601888 -354.20808) (xy 427.593781 -354.215693)
			(xy 427.584421 -354.235837) (xy 427.583854 -354.246942) (xy 427.583854 -354.324158) (xy 427.584412 -354.33527)
			(xy 427.593756 -354.355429) (xy 427.601888 -354.36302) (xy 427.62261 -354.38122) (xy 427.65908 -354.422591)
			(xy 427.689211 -354.468783) (xy 427.712375 -354.518833) (xy 427.728089 -354.571698) (xy 427.736025 -354.626275)
			(xy 427.736508 -354.65385) (xy 427.735998 -354.681102) (xy 427.728248 -354.735051) (xy 427.712898 -354.787348)
			(xy 427.690262 -354.836928) (xy 427.660799 -354.882781) (xy 427.626756 -354.922074) (xy 428.284892 -354.922074)
			(xy 428.288963 -354.866452) (xy 428.301089 -354.812015) (xy 428.321012 -354.759924) (xy 428.348308 -354.711289)
			(xy 428.382394 -354.667146) (xy 428.422543 -354.628437) (xy 428.467901 -354.595986) (xy 428.517501 -354.570485)
			(xy 428.570285 -354.552478) (xy 428.625128 -354.542348) (xy 428.680862 -354.540311) (xy 428.736299 -354.546411)
			(xy 428.790256 -354.560517) (xy 428.841585 -354.582329) (xy 428.889191 -354.611383) (xy 428.932059 -354.647058)
			(xy 428.969276 -354.688595) (xy 429.000049 -354.735108) (xy 429.023721 -354.785605) (xy 429.039789 -354.839012)
			(xy 429.047909 -354.894188) (xy 429.048418 -354.922074) (xy 429.047909 -354.94996) (xy 429.039789 -355.005136)
			(xy 429.023721 -355.058543) (xy 429.000049 -355.10904) (xy 428.969276 -355.155553) (xy 428.932059 -355.19709)
			(xy 428.889191 -355.232765) (xy 428.841585 -355.261819) (xy 428.790256 -355.283631) (xy 428.736299 -355.297737)
			(xy 428.680862 -355.303837) (xy 428.625128 -355.3018) (xy 428.570285 -355.29167) (xy 428.517501 -355.273663)
			(xy 428.467901 -355.248162) (xy 428.422543 -355.215711) (xy 428.382394 -355.177002) (xy 428.348308 -355.132859)
			(xy 428.321012 -355.084224) (xy 428.301089 -355.032133) (xy 428.288963 -354.977696) (xy 428.284892 -354.922074)
			(xy 427.626756 -354.922074) (xy 427.62511 -354.923974) (xy 427.583921 -354.959669) (xy 427.538072 -354.989138)
			(xy 427.488495 -355.011781) (xy 427.4362 -355.027137) (xy 427.382252 -355.034895) (xy 427.355 -355.035358)
			(xy 427.327143 -355.034866) (xy 427.272025 -355.026741) (xy 427.218672 -355.010694) (xy 427.168218 -354.987064)
			(xy 427.121732 -354.956353) (xy 427.080203 -354.919213) (xy 427.044511 -354.876433) (xy 427.015414 -354.828921)
			(xy 426.99353 -354.777685) (xy 426.985938 -354.750878) (xy 426.983652 -354.741988) (xy 426.972984 -354.726748)
			(xy 426.901102 -354.678996) (xy 426.883068 -354.674932) (xy 426.873924 -354.676202) (xy 426.860907 -354.677867)
			(xy 426.834723 -354.67965) (xy 426.8216 -354.679758) (xy 426.807451 -354.679665) (xy 426.779228 -354.67763)
			(xy 426.765212 -354.675694) (xy 426.755052 -354.67417) (xy 426.735494 -354.678996) (xy 426.661072 -354.734876)
			(xy 426.650912 -354.752402) (xy 426.649642 -354.762562) (xy 426.645543 -354.789713) (xy 426.630569 -354.842542)
			(xy 426.608178 -354.892679) (xy 426.578831 -354.939088) (xy 426.543134 -354.980811) (xy 426.501826 -355.016988)
			(xy 426.455759 -355.046869) (xy 426.405885 -355.069839) (xy 426.353233 -355.085422) (xy 426.298891 -355.093298)
			(xy 426.271436 -355.093778) (xy 426.244183 -355.093311) (xy 426.19023 -355.085558) (xy 426.137931 -355.070205)
			(xy 426.088349 -355.047565) (xy 426.042494 -355.018098) (xy 426.0013 -354.982404) (xy 425.965606 -354.941211)
			(xy 425.936138 -354.895357) (xy 425.913497 -354.845775) (xy 425.898143 -354.793476) (xy 425.890389 -354.739523)
			(xy 425.889928 -354.71227) (xy 423.74904 -354.71227) (xy 423.751671 -354.721232) (xy 423.759423 -354.775186)
			(xy 423.759884 -354.80244) (xy 423.759227 -354.834003) (xy 423.748839 -354.896268) (xy 423.728352 -354.955977)
			(xy 423.71391 -354.98405) (xy 423.709084 -354.99294) (xy 423.707052 -355.012498) (xy 423.732706 -355.100636)
			(xy 423.745152 -355.11613) (xy 423.754042 -355.12121) (xy 423.779119 -355.135799) (xy 423.825003 -355.171294)
			(xy 423.864982 -355.21333) (xy 423.898131 -355.260936) (xy 423.923686 -355.313015) (xy 423.941057 -355.368365)
			(xy 423.949843 -355.425706) (xy 423.950384 -355.454712) (xy 423.949898 -355.481963) (xy 423.942142 -355.535911)
			(xy 423.926787 -355.588206) (xy 423.922445 -355.597714) (xy 429.623728 -355.597714) (xy 429.624216 -355.570239)
			(xy 429.632106 -355.51586) (xy 429.647726 -355.463177) (xy 429.67075 -355.413284) (xy 429.700702 -355.367216)
			(xy 429.71847 -355.346254) (xy 429.724566 -355.339142) (xy 429.730916 -355.322124) (xy 429.730916 -355.236272)
			(xy 429.724566 -355.219254) (xy 429.71847 -355.212142) (xy 429.70074 -355.191152) (xy 429.670811 -355.145078)
			(xy 429.647792 -355.09519) (xy 429.632158 -355.04252) (xy 429.624232 -354.988152) (xy 429.623728 -354.960682)
			(xy 429.624214 -354.933431) (xy 429.63197 -354.879483) (xy 429.647325 -354.827188) (xy 429.669967 -354.777611)
			(xy 429.699433 -354.731761) (xy 429.735124 -354.69057) (xy 429.776315 -354.654879) (xy 429.822165 -354.625413)
			(xy 429.871742 -354.602771) (xy 429.924037 -354.587416) (xy 429.977985 -354.57966) (xy 430.032487 -354.57966)
			(xy 430.086435 -354.587416) (xy 430.13873 -354.602771) (xy 430.188307 -354.625413) (xy 430.234157 -354.654879)
			(xy 430.275348 -354.69057) (xy 430.311039 -354.731761) (xy 430.340505 -354.777611) (xy 430.363147 -354.827188)
			(xy 430.378502 -354.879483) (xy 430.386258 -354.933431) (xy 430.386744 -354.960682) (xy 430.386261 -354.988157)
			(xy 430.37837 -355.042537) (xy 430.36275 -355.09522) (xy 430.360106 -355.100948) (xy 430.62859 -355.100948)
			(xy 430.62859 -355.046452) (xy 430.636345 -354.99251) (xy 430.651697 -354.940221) (xy 430.674334 -354.890648)
			(xy 430.703795 -354.844802) (xy 430.73948 -354.803614) (xy 430.780663 -354.767924) (xy 430.826506 -354.738457)
			(xy 430.876076 -354.715814) (xy 430.928363 -354.700455) (xy 430.982304 -354.692694) (xy 431.009552 -354.692204)
			(xy 431.034788 -354.692578) (xy 431.084823 -354.699203) (xy 431.133543 -354.712382) (xy 431.180094 -354.731886)
			(xy 431.202084 -354.744274) (xy 431.211736 -354.750116) (xy 431.233834 -354.752148) (xy 431.328322 -354.71862)
			(xy 431.344324 -354.703126) (xy 431.348388 -354.692712) (xy 431.359084 -354.665935) (xy 431.38737 -354.615692)
			(xy 431.422899 -354.570282) (xy 431.464861 -354.530738) (xy 431.512299 -354.497964) (xy 431.56413 -354.472707)
			(xy 431.619174 -354.455542) (xy 431.676175 -354.446861) (xy 431.705004 -354.446332) (xy 431.732259 -354.446752)
			(xy 431.786213 -354.45451) (xy 431.838514 -354.469869) (xy 431.888097 -354.492515) (xy 431.933952 -354.521987)
			(xy 431.975146 -354.557685) (xy 432.01084 -354.598883) (xy 432.040306 -354.644741) (xy 432.062947 -354.694327)
			(xy 432.075669 -354.73767) (xy 434.216556 -354.73767) (xy 434.21705 -354.710096) (xy 434.224994 -354.655524)
			(xy 434.240712 -354.602664) (xy 434.263877 -354.552617) (xy 434.294005 -354.506427) (xy 434.33047 -354.465056)
			(xy 434.351176 -354.44684) (xy 434.359284 -354.439229) (xy 434.368641 -354.419083) (xy 434.36921 -354.407978)
			(xy 434.36921 -354.330762) (xy 434.368708 -354.319643) (xy 434.359326 -354.299484) (xy 434.351176 -354.2919)
			(xy 434.330457 -354.273698) (xy 434.293988 -354.232326) (xy 434.263858 -354.186135) (xy 434.240693 -354.136085)
			(xy 434.224979 -354.083221) (xy 434.217041 -354.028645) (xy 434.216556 -354.00107) (xy 434.21705 -353.97382)
			(xy 434.224809 -353.919874) (xy 434.240167 -353.867582) (xy 434.262809 -353.818007) (xy 434.292275 -353.772158)
			(xy 434.327965 -353.730969) (xy 434.369153 -353.695278) (xy 434.415001 -353.665811) (xy 434.464576 -353.643169)
			(xy 434.516868 -353.627811) (xy 434.570814 -353.62005) (xy 434.598064 -353.619562) (xy 434.632354 -353.621086)
			(xy 434.642514 -353.622102) (xy 434.661818 -353.616006) (xy 434.73243 -353.556824) (xy 434.741828 -353.53879)
			(xy 434.742844 -353.52863) (xy 434.745817 -353.50046) (xy 434.758992 -353.445371) (xy 434.780171 -353.392837)
			(xy 434.808887 -353.344013) (xy 434.844509 -353.299973) (xy 434.886254 -353.261687) (xy 434.933202 -353.229997)
			(xy 434.984321 -353.205599) (xy 435.038486 -353.189031) (xy 435.094507 -353.180657) (xy 435.122828 -353.180142)
			(xy 435.140847 -353.180364) (xy 435.176722 -353.183798) (xy 435.194456 -353.187) (xy 435.203854 -353.188778)
			(xy 435.222904 -353.184968) (xy 435.298088 -353.137216) (xy 435.309518 -353.121468) (xy 435.311804 -353.11207)
			(xy 435.319223 -353.085032) (xy 435.340849 -353.033306) (xy 435.369811 -352.985301) (xy 435.405483 -352.942049)
			(xy 435.4471 -352.904481) (xy 435.493765 -352.873406) (xy 435.544474 -352.849492) (xy 435.598136 -352.833254)
			(xy 435.653596 -352.825042) (xy 435.681628 -352.824542) (xy 435.708884 -352.824929) (xy 435.76284 -352.832691)
			(xy 435.815143 -352.848053) (xy 435.864726 -352.870703) (xy 435.910582 -352.900178) (xy 435.951775 -352.93588)
			(xy 435.987469 -352.977081) (xy 436.016935 -353.022942) (xy 436.039574 -353.072531) (xy 436.054926 -353.124836)
			(xy 436.062677 -353.178794) (xy 436.063136 -353.20605) (xy 436.062658 -353.233624) (xy 436.054711 -353.288198)
			(xy 436.03899 -353.341058) (xy 436.015823 -353.391105) (xy 435.985691 -353.437295) (xy 435.949223 -353.478665)
			(xy 435.928516 -353.49688) (xy 435.920414 -353.504497) (xy 435.91105 -353.524637) (xy 435.910482 -353.535742)
			(xy 435.910482 -353.612958) (xy 435.911031 -353.624071) (xy 435.92038 -353.644231) (xy 435.928516 -353.65182)
			(xy 435.949271 -353.669981) (xy 435.985733 -353.711361) (xy 436.015858 -353.757558) (xy 436.039017 -353.807612)
			(xy 436.054728 -353.860479) (xy 436.062664 -353.915056) (xy 436.062659 -353.970208) (xy 436.054714 -354.024785)
			(xy 436.038994 -354.077649) (xy 436.015826 -354.127698) (xy 435.985694 -354.173891) (xy 435.949225 -354.215264)
			(xy 435.928516 -354.23348) (xy 435.920414 -354.241097) (xy 435.91105 -354.261237) (xy 435.910482 -354.272342)
			(xy 435.910482 -354.349558) (xy 435.911031 -354.360671) (xy 435.92038 -354.380831) (xy 435.928516 -354.38842)
			(xy 435.949243 -354.406614) (xy 435.985712 -354.447986) (xy 436.015841 -354.49418) (xy 436.039004 -354.544232)
			(xy 436.054717 -354.597097) (xy 436.062653 -354.651674) (xy 436.063136 -354.67925) (xy 436.062598 -354.7065)
			(xy 436.054849 -354.760447) (xy 436.039501 -354.812742) (xy 436.016866 -354.86232) (xy 435.987406 -354.908172)
			(xy 435.95172 -354.949365) (xy 435.910535 -354.985059) (xy 435.864689 -355.014528) (xy 435.815115 -355.037173)
			(xy 435.762823 -355.052532) (xy 435.708878 -355.060293) (xy 435.681628 -355.060758) (xy 435.653772 -355.060241)
			(xy 435.598655 -355.05212) (xy 435.545303 -355.036076) (xy 435.494848 -355.01245) (xy 435.448363 -354.981742)
			(xy 435.406833 -354.944606) (xy 435.37114 -354.901828) (xy 435.342043 -354.854318) (xy 435.320158 -354.803084)
			(xy 435.312566 -354.776278) (xy 435.31028 -354.767388) (xy 435.299612 -354.752148) (xy 435.22773 -354.704396)
			(xy 435.209696 -354.700332) (xy 435.200552 -354.701602) (xy 435.187536 -354.703274) (xy 435.161351 -354.705052)
			(xy 435.148228 -354.705158) (xy 435.134079 -354.705062) (xy 435.105856 -354.703029) (xy 435.09184 -354.701094)
			(xy 435.08168 -354.69957) (xy 435.062122 -354.704396) (xy 434.9877 -354.760276) (xy 434.97754 -354.777802)
			(xy 434.97627 -354.787962) (xy 434.972144 -354.815109) (xy 434.957172 -354.867935) (xy 434.934782 -354.91807)
			(xy 434.905438 -354.964478) (xy 434.869745 -355.006201) (xy 434.82844 -355.042377) (xy 434.782376 -355.07226)
			(xy 434.732505 -355.095231) (xy 434.679857 -355.110817) (xy 434.625518 -355.118696) (xy 434.598064 -355.119178)
			(xy 434.57081 -355.118756) (xy 434.516859 -355.110993) (xy 434.464561 -355.095632) (xy 434.414982 -355.072985)
			(xy 434.36913 -355.043512) (xy 434.32794 -355.007814) (xy 434.292249 -354.966617) (xy 434.262784 -354.92076)
			(xy 434.240145 -354.871177) (xy 434.224793 -354.818876) (xy 434.21704 -354.764924) (xy 434.216556 -354.73767)
			(xy 432.075669 -354.73767) (xy 432.078299 -354.74663) (xy 432.086051 -354.800585) (xy 432.086512 -354.82784)
			(xy 432.085851 -354.859403) (xy 432.075464 -354.921668) (xy 432.054979 -354.981377) (xy 432.040538 -355.00945)
			(xy 432.035712 -355.01834) (xy 432.03368 -355.037898) (xy 432.059334 -355.126036) (xy 432.07178 -355.14153)
			(xy 432.08067 -355.14661) (xy 432.105753 -355.161188) (xy 432.151636 -355.196686) (xy 432.191613 -355.238724)
			(xy 432.224761 -355.286333) (xy 432.250315 -355.338413) (xy 432.267685 -355.393763) (xy 432.276471 -355.451106)
			(xy 432.277012 -355.480112) (xy 432.276526 -355.507363) (xy 432.26877 -355.561311) (xy 432.253415 -355.613606)
			(xy 432.230773 -355.663183) (xy 432.201307 -355.709033) (xy 432.165616 -355.750224) (xy 432.124425 -355.785915)
			(xy 432.078575 -355.815381) (xy 432.028998 -355.838023) (xy 431.976703 -355.853378) (xy 431.922755 -355.861134)
			(xy 431.868253 -355.861134) (xy 431.814305 -355.853378) (xy 431.76201 -355.838023) (xy 431.712433 -355.815381)
			(xy 431.666583 -355.785915) (xy 431.625392 -355.750224) (xy 431.589701 -355.709033) (xy 431.560235 -355.663183)
			(xy 431.537593 -355.613606) (xy 431.522238 -355.561311) (xy 431.514482 -355.507363) (xy 431.513996 -355.480112)
			(xy 431.514637 -355.448548) (xy 431.525032 -355.386283) (xy 431.545525 -355.326574) (xy 431.55997 -355.298502)
			(xy 431.564796 -355.289612) (xy 431.566828 -355.270054) (xy 431.541174 -355.181916) (xy 431.528728 -355.166422)
			(xy 431.519838 -355.161342) (xy 431.512472 -355.157278) (xy 431.50282 -355.151436) (xy 431.480722 -355.149404)
			(xy 431.386234 -355.182932) (xy 431.370232 -355.198426) (xy 431.366168 -355.20884) (xy 431.355453 -355.235608)
			(xy 431.327166 -355.285847) (xy 431.291637 -355.331255) (xy 431.249678 -355.370797) (xy 431.202244 -355.403571)
			(xy 431.150416 -355.428831) (xy 431.095377 -355.446) (xy 431.03838 -355.454687) (xy 431.009552 -355.45522)
			(xy 430.982304 -355.454706) (xy 430.928363 -355.446945) (xy 430.876076 -355.431586) (xy 430.826506 -355.408943)
			(xy 430.780663 -355.379476) (xy 430.73948 -355.343786) (xy 430.703795 -355.302598) (xy 430.674334 -355.256752)
			(xy 430.651697 -355.207179) (xy 430.636345 -355.15489) (xy 430.62859 -355.100948) (xy 430.360106 -355.100948)
			(xy 430.339724 -355.145113) (xy 430.309771 -355.191181) (xy 430.292002 -355.212142) (xy 430.285906 -355.219254)
			(xy 430.279556 -355.236272) (xy 430.279556 -355.322124) (xy 430.285906 -355.339142) (xy 430.292002 -355.346254)
			(xy 430.309726 -355.367249) (xy 430.339657 -355.413322) (xy 430.362677 -355.463208) (xy 430.378312 -355.515877)
			(xy 430.386239 -355.570244) (xy 430.386744 -355.597714) (xy 430.386258 -355.624965) (xy 430.378502 -355.678913)
			(xy 430.363147 -355.731208) (xy 430.340505 -355.780785) (xy 430.311039 -355.826635) (xy 430.275348 -355.867826)
			(xy 430.234157 -355.903517) (xy 430.188307 -355.932983) (xy 430.13873 -355.955625) (xy 430.086435 -355.97098)
			(xy 430.032487 -355.978736) (xy 429.977985 -355.978736) (xy 429.924037 -355.97098) (xy 429.871742 -355.955625)
			(xy 429.822165 -355.932983) (xy 429.776315 -355.903517) (xy 429.735124 -355.867826) (xy 429.699433 -355.826635)
			(xy 429.669967 -355.780785) (xy 429.647325 -355.731208) (xy 429.63197 -355.678913) (xy 429.624214 -355.624965)
			(xy 429.623728 -355.597714) (xy 423.922445 -355.597714) (xy 423.904145 -355.637783) (xy 423.874679 -355.683633)
			(xy 423.838988 -355.724824) (xy 423.797797 -355.760515) (xy 423.751947 -355.789981) (xy 423.70237 -355.812623)
			(xy 423.650075 -355.827978) (xy 423.596127 -355.835734) (xy 423.541625 -355.835734) (xy 423.487677 -355.827978)
			(xy 423.435382 -355.812623) (xy 423.385805 -355.789981) (xy 423.339955 -355.760515) (xy 423.298764 -355.724824)
			(xy 423.263073 -355.683633) (xy 423.233607 -355.637783) (xy 423.210965 -355.588206) (xy 423.19561 -355.535911)
			(xy 423.187854 -355.481963) (xy 423.187368 -355.454712) (xy 423.188012 -355.423149) (xy 423.198407 -355.360883)
			(xy 423.218898 -355.301174) (xy 423.233342 -355.273102) (xy 423.238168 -355.264212) (xy 423.2402 -355.244654)
			(xy 423.214546 -355.156516) (xy 423.2021 -355.141022) (xy 423.19321 -355.135942) (xy 423.185844 -355.131878)
			(xy 423.176192 -355.126036) (xy 423.154094 -355.124004) (xy 423.059606 -355.157532) (xy 423.043604 -355.173026)
			(xy 423.03954 -355.18344) (xy 423.028848 -355.210218) (xy 423.000558 -355.260458) (xy 422.965027 -355.305867)
			(xy 422.923064 -355.345408) (xy 422.875626 -355.378181) (xy 422.823795 -355.403439) (xy 422.768753 -355.420605)
			(xy 422.711753 -355.429289) (xy 422.682924 -355.42982) (xy 422.655671 -355.429334) (xy 422.601719 -355.42158)
			(xy 422.54942 -355.406227) (xy 422.499838 -355.383586) (xy 422.453984 -355.35412) (xy 422.412789 -355.318428)
			(xy 422.377094 -355.277236) (xy 422.347625 -355.231383) (xy 422.324981 -355.181803) (xy 422.309625 -355.129504)
			(xy 422.301867 -355.075553) (xy 422.033462 -355.075553) (xy 422.013088 -355.11971) (xy 421.98314 -355.165779)
			(xy 421.965374 -355.186742) (xy 421.959278 -355.193854) (xy 421.952928 -355.210872) (xy 421.952928 -355.296724)
			(xy 421.959278 -355.313742) (xy 421.965374 -355.320854) (xy 421.983109 -355.341839) (xy 422.013036 -355.387916)
			(xy 422.036053 -355.437804) (xy 422.051686 -355.490476) (xy 422.059612 -355.544843) (xy 422.060116 -355.572314)
			(xy 422.05963 -355.599565) (xy 422.051874 -355.653513) (xy 422.036519 -355.705808) (xy 422.013877 -355.755385)
			(xy 421.984411 -355.801235) (xy 421.94872 -355.842426) (xy 421.907529 -355.878117) (xy 421.861679 -355.907583)
			(xy 421.812102 -355.930225) (xy 421.759807 -355.94558) (xy 421.705859 -355.953336) (xy 421.651357 -355.953336)
			(xy 421.597409 -355.94558) (xy 421.545114 -355.930225) (xy 421.495537 -355.907583) (xy 421.449687 -355.878117)
			(xy 421.408496 -355.842426) (xy 421.372805 -355.801235) (xy 421.343339 -355.755385) (xy 421.320697 -355.705808)
			(xy 421.305342 -355.653513) (xy 421.297586 -355.599565) (xy 421.2971 -355.572314) (xy 410.08173 -355.572314)
			(xy 410.08173 -357.223822) (xy 416.449002 -357.223822) (xy 416.449535 -357.194906) (xy 416.458261 -357.137735)
			(xy 416.475516 -357.082537) (xy 416.500905 -357.030575) (xy 416.533846 -356.983041) (xy 416.573584 -356.941023)
			(xy 416.596068 -356.922832) (xy 416.604822 -356.915264) (xy 416.615007 -356.894509) (xy 416.615626 -356.882954)
			(xy 416.615626 -356.80269) (xy 416.615087 -356.791117) (xy 416.604873 -356.770345) (xy 416.596068 -356.762812)
			(xy 416.573584 -356.744622) (xy 416.53385 -356.702601) (xy 416.500912 -356.655066) (xy 416.475524 -356.603104)
			(xy 416.458268 -356.547907) (xy 416.449538 -356.490738) (xy 416.449002 -356.461822) (xy 416.449488 -356.434571)
			(xy 416.457244 -356.380623) (xy 416.472599 -356.328328) (xy 416.495241 -356.278751) (xy 416.524707 -356.232901)
			(xy 416.560398 -356.19171) (xy 416.601589 -356.156019) (xy 416.647439 -356.126553) (xy 416.697016 -356.103911)
			(xy 416.749311 -356.088556) (xy 416.803259 -356.0808) (xy 416.857761 -356.0808) (xy 416.911709 -356.088556)
			(xy 416.964004 -356.103911) (xy 417.013581 -356.126553) (xy 417.059431 -356.156019) (xy 417.100622 -356.19171)
			(xy 417.136313 -356.232901) (xy 417.165779 -356.278751) (xy 417.188421 -356.328328) (xy 417.203776 -356.380623)
			(xy 417.211532 -356.434571) (xy 417.212018 -356.461822) (xy 417.211475 -356.490738) (xy 417.202755 -356.54791)
			(xy 417.185504 -356.603109) (xy 417.160117 -356.655072) (xy 417.127177 -356.702606) (xy 417.087437 -356.744622)
			(xy 417.064952 -356.762812) (xy 417.056181 -356.770365) (xy 417.046005 -356.791131) (xy 417.045394 -356.80269)
			(xy 417.045394 -356.882954) (xy 417.045993 -356.894518) (xy 417.056168 -356.915289) (xy 417.064952 -356.922832)
			(xy 417.087462 -356.940992) (xy 417.127193 -356.98302) (xy 417.160127 -357.030561) (xy 417.185511 -357.082529)
			(xy 417.202762 -357.137731) (xy 417.211486 -357.194904) (xy 417.212018 -357.223822) (xy 417.211764 -357.240078)
			(xy 417.211002 -357.254556) (xy 417.224718 -357.279194) (xy 417.328096 -357.338122) (xy 417.35629 -357.33736)
			(xy 417.368482 -357.329486) (xy 417.391804 -357.314957) (xy 417.441716 -357.291983) (xy 417.494404 -357.276392)
			(xy 417.548781 -357.268504) (xy 417.576254 -357.268018) (xy 417.603511 -357.268406) (xy 417.65747 -357.276157)
			(xy 417.709776 -357.291509) (xy 417.759365 -357.314149) (xy 417.805228 -357.343616) (xy 417.84643 -357.379309)
			(xy 417.882133 -357.420504) (xy 417.91161 -357.46636) (xy 417.934261 -357.515944) (xy 417.949625 -357.568247)
			(xy 417.957388 -357.622204) (xy 417.957394 -357.676717) (xy 417.949641 -357.730676) (xy 417.934288 -357.782982)
			(xy 417.911648 -357.832571) (xy 417.88218 -357.878433) (xy 417.846486 -357.919635) (xy 417.805291 -357.955337)
			(xy 417.759435 -357.984813) (xy 417.70985 -358.007463) (xy 417.657547 -358.022826) (xy 417.603589 -358.030589)
			(xy 417.549076 -358.030593) (xy 417.495117 -358.02284) (xy 417.442811 -358.007486) (xy 417.393223 -357.984845)
			(xy 417.347361 -357.955376) (xy 417.30616 -357.919681) (xy 417.270459 -357.878486) (xy 417.240984 -357.832629)
			(xy 417.218334 -357.783044) (xy 417.202973 -357.73074) (xy 417.195211 -357.676782) (xy 417.194746 -357.649526)
			(xy 417.195 -357.63327) (xy 417.195762 -357.618792) (xy 417.182046 -357.594154) (xy 417.078668 -357.535226)
			(xy 417.050474 -357.535988) (xy 417.038282 -357.543862) (xy 417.014965 -357.5584) (xy 416.965051 -357.581373)
			(xy 416.912362 -357.596962) (xy 416.857983 -357.604846) (xy 416.83051 -357.60533) (xy 416.80326 -357.604812)
			(xy 416.749315 -357.597058) (xy 416.697022 -357.581705) (xy 416.647446 -357.559067) (xy 416.601597 -357.529604)
			(xy 416.560407 -357.493916) (xy 416.524716 -357.452729) (xy 416.495249 -357.406882) (xy 416.472606 -357.357308)
			(xy 416.457249 -357.305017) (xy 416.44949 -357.251072) (xy 416.449002 -357.223822) (xy 410.08173 -357.223822)
			(xy 410.08173 -358.836214) (xy 417.824664 -358.836214) (xy 417.828735 -358.780592) (xy 417.840861 -358.726155)
			(xy 417.860784 -358.674064) (xy 417.88808 -358.625429) (xy 417.922166 -358.581286) (xy 417.962315 -358.542577)
			(xy 418.007673 -358.510126) (xy 418.057273 -358.484625) (xy 418.110057 -358.466618) (xy 418.1649 -358.456488)
			(xy 418.220634 -358.454451) (xy 418.276071 -358.460551) (xy 418.330028 -358.474657) (xy 418.381357 -358.496469)
			(xy 418.428963 -358.525523) (xy 418.471831 -358.561198) (xy 418.509048 -358.602735) (xy 418.539821 -358.649248)
			(xy 418.563493 -358.699745) (xy 418.579561 -358.753152) (xy 418.587681 -358.808328) (xy 418.58819 -358.836214)
			(xy 418.587681 -358.8641) (xy 418.579561 -358.919276) (xy 418.563493 -358.972683) (xy 418.539821 -359.02318)
			(xy 418.509048 -359.069693) (xy 418.471831 -359.11123) (xy 418.428963 -359.146905) (xy 418.381357 -359.175959)
			(xy 418.330028 -359.197771) (xy 418.276071 -359.211877) (xy 418.220634 -359.217977) (xy 418.1649 -359.21594)
			(xy 418.110057 -359.20581) (xy 418.057273 -359.187803) (xy 418.007673 -359.162302) (xy 417.962315 -359.129851)
			(xy 417.922166 -359.091142) (xy 417.88808 -359.046999) (xy 417.860784 -358.998364) (xy 417.840861 -358.946273)
			(xy 417.828735 -358.891836) (xy 417.824664 -358.836214) (xy 410.08173 -358.836214) (xy 410.08173 -359.904792)
			(xy 421.71696 -359.904792) (xy 421.721031 -359.84917) (xy 421.733157 -359.794733) (xy 421.75308 -359.742642)
			(xy 421.780376 -359.694007) (xy 421.814462 -359.649864) (xy 421.854611 -359.611155) (xy 421.899969 -359.578704)
			(xy 421.949569 -359.553203) (xy 422.002353 -359.535196) (xy 422.057196 -359.525066) (xy 422.11293 -359.523029)
			(xy 422.168367 -359.529129) (xy 422.222324 -359.543235) (xy 422.273653 -359.565047) (xy 422.321259 -359.594101)
			(xy 422.364127 -359.629776) (xy 422.401344 -359.671313) (xy 422.432117 -359.717826) (xy 422.455789 -359.768323)
			(xy 422.471857 -359.82173) (xy 422.473988 -359.836212) (xy 424.433236 -359.836212) (xy 424.437307 -359.78059)
			(xy 424.449433 -359.726153) (xy 424.469356 -359.674062) (xy 424.496652 -359.625427) (xy 424.530738 -359.581284)
			(xy 424.570887 -359.542575) (xy 424.616245 -359.510124) (xy 424.665845 -359.484623) (xy 424.718629 -359.466616)
			(xy 424.773472 -359.456486) (xy 424.829206 -359.454449) (xy 424.884643 -359.460549) (xy 424.9386 -359.474655)
			(xy 424.989929 -359.496467) (xy 425.037535 -359.525521) (xy 425.080403 -359.561196) (xy 425.11762 -359.602733)
			(xy 425.148393 -359.649246) (xy 425.172065 -359.699743) (xy 425.188133 -359.75315) (xy 425.196253 -359.808326)
			(xy 425.196762 -359.836212) (xy 425.196253 -359.864098) (xy 425.188133 -359.919274) (xy 425.172065 -359.972681)
			(xy 425.148393 -360.023178) (xy 425.11762 -360.069691) (xy 425.080403 -360.111228) (xy 425.037535 -360.146903)
			(xy 424.989929 -360.175957) (xy 424.9386 -360.197769) (xy 424.884643 -360.211875) (xy 424.829206 -360.217975)
			(xy 424.773472 -360.215938) (xy 424.718629 -360.205808) (xy 424.665845 -360.187801) (xy 424.616245 -360.1623)
			(xy 424.570887 -360.129849) (xy 424.530738 -360.09114) (xy 424.496652 -360.046997) (xy 424.469356 -359.998362)
			(xy 424.449433 -359.946271) (xy 424.437307 -359.891834) (xy 424.433236 -359.836212) (xy 422.473988 -359.836212)
			(xy 422.479977 -359.876906) (xy 422.480486 -359.904792) (xy 422.479977 -359.932678) (xy 422.471857 -359.987854)
			(xy 422.455789 -360.041261) (xy 422.432117 -360.091758) (xy 422.401344 -360.138271) (xy 422.364127 -360.179808)
			(xy 422.321259 -360.215483) (xy 422.273653 -360.244537) (xy 422.222324 -360.266349) (xy 422.168367 -360.280455)
			(xy 422.11293 -360.286555) (xy 422.057196 -360.284518) (xy 422.002353 -360.274388) (xy 421.949569 -360.256381)
			(xy 421.899969 -360.23088) (xy 421.854611 -360.198429) (xy 421.814462 -360.15972) (xy 421.780376 -360.115577)
			(xy 421.75308 -360.066942) (xy 421.733157 -360.014851) (xy 421.721031 -359.960414) (xy 421.71696 -359.904792)
			(xy 410.08173 -359.904792) (xy 410.08173 -360.7943) (xy 412.920178 -360.7943) (xy 412.924249 -360.738678)
			(xy 412.936375 -360.684241) (xy 412.956298 -360.63215) (xy 412.983594 -360.583515) (xy 413.01768 -360.539372)
			(xy 413.057829 -360.500663) (xy 413.103187 -360.468212) (xy 413.152787 -360.442711) (xy 413.205571 -360.424704)
			(xy 413.260414 -360.414574) (xy 413.316148 -360.412537) (xy 413.371585 -360.418637) (xy 413.425542 -360.432743)
			(xy 413.476871 -360.454555) (xy 413.524477 -360.483609) (xy 413.567345 -360.519284) (xy 413.604562 -360.560821)
			(xy 413.635335 -360.607334) (xy 413.659007 -360.657831) (xy 413.675075 -360.711238) (xy 413.683195 -360.766414)
			(xy 413.683704 -360.7943) (xy 413.683195 -360.822186) (xy 413.675075 -360.877362) (xy 413.659007 -360.930769)
			(xy 413.635335 -360.981266) (xy 413.604562 -361.027779) (xy 413.567345 -361.069316) (xy 413.524477 -361.104991)
			(xy 413.476871 -361.134045) (xy 413.425542 -361.155857) (xy 413.371585 -361.169963) (xy 413.316148 -361.176063)
			(xy 413.260414 -361.174026) (xy 413.205571 -361.163896) (xy 413.152787 -361.145889) (xy 413.103187 -361.120388)
			(xy 413.057829 -361.087937) (xy 413.01768 -361.049228) (xy 412.983594 -361.005085) (xy 412.956298 -360.95645)
			(xy 412.936375 -360.904359) (xy 412.924249 -360.849922) (xy 412.920178 -360.7943) (xy 410.08173 -360.7943)
			(xy 410.08173 -361.3023) (xy 414.979356 -361.3023) (xy 414.983427 -361.246678) (xy 414.995553 -361.192241)
			(xy 415.015476 -361.14015) (xy 415.042772 -361.091515) (xy 415.076858 -361.047372) (xy 415.117007 -361.008663)
			(xy 415.162365 -360.976212) (xy 415.211965 -360.950711) (xy 415.264749 -360.932704) (xy 415.319592 -360.922574)
			(xy 415.375326 -360.920537) (xy 415.430763 -360.926637) (xy 415.48472 -360.940743) (xy 415.536049 -360.962555)
			(xy 415.583655 -360.991609) (xy 415.626523 -361.027284) (xy 415.66374 -361.068821) (xy 415.694513 -361.115334)
			(xy 415.718185 -361.165831) (xy 415.734253 -361.219238) (xy 415.742373 -361.274414) (xy 415.742882 -361.3023)
			(xy 415.742373 -361.330186) (xy 415.734253 -361.385362) (xy 415.718185 -361.438769) (xy 415.694513 -361.489266)
			(xy 415.66374 -361.535779) (xy 415.626523 -361.577316) (xy 415.583655 -361.612991) (xy 415.536049 -361.642045)
			(xy 415.48472 -361.663857) (xy 415.430763 -361.677963) (xy 415.375326 -361.684063) (xy 415.319592 -361.682026)
			(xy 415.264749 -361.671896) (xy 415.211965 -361.653889) (xy 415.162365 -361.628388) (xy 415.117007 -361.595937)
			(xy 415.076858 -361.557228) (xy 415.042772 -361.513085) (xy 415.015476 -361.46445) (xy 414.995553 -361.412359)
			(xy 414.983427 -361.357922) (xy 414.979356 -361.3023) (xy 410.08173 -361.3023) (xy 410.08173 -361.741212)
			(xy 421.89019 -361.741212) (xy 421.8907 -361.712991) (xy 421.899014 -361.657165) (xy 421.915463 -361.603173)
			(xy 421.939686 -361.552194) (xy 421.971156 -361.50534) (xy 422.009186 -361.463634) (xy 422.052946 -361.427986)
			(xy 422.10148 -361.399174) (xy 422.153729 -361.377828) (xy 422.18102 -361.370626) (xy 422.192196 -361.367832)
			(xy 422.209214 -361.354116) (xy 422.253918 -361.263946) (xy 422.254426 -361.241848) (xy 422.249854 -361.23118)
			(xy 422.239727 -361.206976) (xy 422.225476 -361.156479) (xy 422.218285 -361.104506) (xy 422.21785 -361.078272)
			(xy 422.218336 -361.051021) (xy 422.226092 -360.997073) (xy 422.241447 -360.944778) (xy 422.264089 -360.895201)
			(xy 422.293555 -360.849351) (xy 422.329246 -360.80816) (xy 422.370437 -360.772469) (xy 422.416287 -360.743003)
			(xy 422.465864 -360.720361) (xy 422.518159 -360.705006) (xy 422.572107 -360.69725) (xy 422.626609 -360.69725)
			(xy 422.680557 -360.705006) (xy 422.732852 -360.720361) (xy 422.762937 -360.734101) (xy 435.087517 -360.734101)
			(xy 435.091247 -360.680849) (xy 435.102365 -360.628636) (xy 435.120653 -360.578484) (xy 435.145754 -360.53137)
			(xy 435.177178 -360.488216) (xy 435.214312 -360.449865) (xy 435.235096 -360.433112) (xy 435.243847 -360.42554)
			(xy 435.254037 -360.404789) (xy 435.254654 -360.393234) (xy 435.254654 -360.31297) (xy 435.254059 -360.301405)
			(xy 435.243883 -360.280633) (xy 435.235096 -360.273092) (xy 435.212608 -360.254907) (xy 435.172873 -360.212885)
			(xy 435.139935 -360.165349) (xy 435.114547 -360.113387) (xy 435.097292 -360.058189) (xy 435.088564 -360.001018)
			(xy 435.08803 -359.972102) (xy 435.088457 -359.944847) (xy 435.096215 -359.890893) (xy 435.111573 -359.838592)
			(xy 435.134218 -359.78901) (xy 435.163689 -359.743155) (xy 435.199387 -359.701961) (xy 435.240584 -359.666267)
			(xy 435.286441 -359.6368) (xy 435.336026 -359.61416) (xy 435.388329 -359.598807) (xy 435.442283 -359.591055)
			(xy 435.469538 -359.590594) (xy 435.498455 -359.591121) (xy 435.555627 -359.599844) (xy 435.610828 -359.617097)
			(xy 435.66279 -359.642487) (xy 435.710324 -359.675431) (xy 435.752339 -359.715174) (xy 435.770528 -359.73766)
			(xy 435.778072 -359.74644) (xy 435.798845 -359.756611) (xy 435.810406 -359.757218) (xy 435.89067 -359.757218)
			(xy 435.902235 -359.756624) (xy 435.923005 -359.746445) (xy 435.930548 -359.73766) (xy 435.948758 -359.715193)
			(xy 435.990775 -359.675459) (xy 436.038307 -359.642519) (xy 436.090264 -359.617128) (xy 436.145457 -359.599868)
			(xy 436.202623 -359.591133) (xy 436.231538 -359.590594) (xy 436.25879 -359.591042) (xy 436.312739 -359.598804)
			(xy 436.365035 -359.614164) (xy 436.414612 -359.63681) (xy 436.460463 -359.66628) (xy 436.501653 -359.701976)
			(xy 436.537344 -359.743169) (xy 436.566809 -359.789023) (xy 436.58945 -359.838603) (xy 436.604804 -359.8909)
			(xy 436.61256 -359.94485) (xy 436.613046 -359.972102) (xy 436.61255 -360.00102) (xy 436.603819 -360.058193)
			(xy 436.586558 -360.113393) (xy 436.561162 -360.165355) (xy 436.528214 -360.212888) (xy 436.488468 -360.254903)
			(xy 436.46598 -360.273092) (xy 436.457223 -360.280658) (xy 436.447037 -360.301414) (xy 436.446422 -360.31297)
			(xy 436.446422 -360.393234) (xy 436.447023 -360.404798) (xy 436.457195 -360.42557) (xy 436.46598 -360.433112)
			(xy 436.486763 -360.449864) (xy 436.52389 -360.488219) (xy 436.555308 -360.531375) (xy 436.580404 -360.578488)
			(xy 436.598689 -360.62864) (xy 436.609804 -360.680851) (xy 436.613533 -360.734101) (xy 436.609804 -360.787352)
			(xy 436.598688 -360.839562) (xy 436.580403 -360.889714) (xy 436.555307 -360.936827) (xy 436.523888 -360.979983)
			(xy 436.486761 -361.018338) (xy 436.46598 -361.035092) (xy 436.457223 -361.042658) (xy 436.447037 -361.063414)
			(xy 436.446422 -361.07497) (xy 436.446422 -361.155234) (xy 436.447023 -361.166798) (xy 436.457195 -361.18757)
			(xy 436.46598 -361.195112) (xy 436.488465 -361.213301) (xy 436.528201 -361.255321) (xy 436.56114 -361.302856)
			(xy 436.586529 -361.354818) (xy 436.603784 -361.410016) (xy 436.612512 -361.467186) (xy 436.613046 -361.496102)
			(xy 436.612524 -361.523352) (xy 436.604768 -361.577296) (xy 436.589415 -361.629588) (xy 436.566776 -361.679162)
			(xy 436.537313 -361.725011) (xy 436.501626 -361.7662) (xy 436.46044 -361.801892) (xy 436.414594 -361.831359)
			(xy 436.365022 -361.854002) (xy 436.312731 -361.869361) (xy 436.258788 -361.877122) (xy 436.231538 -361.87761)
			(xy 436.20262 -361.877098) (xy 436.145447 -361.868373) (xy 436.090247 -361.851116) (xy 436.038285 -361.825723)
			(xy 435.990751 -361.792776) (xy 435.948737 -361.753031) (xy 435.930548 -361.730544) (xy 435.922971 -361.721799)
			(xy 435.902223 -361.711608) (xy 435.89067 -361.710986) (xy 435.810406 -361.710986) (xy 435.798839 -361.711565)
			(xy 435.778069 -361.721754) (xy 435.770528 -361.730544) (xy 435.752332 -361.753023) (xy 435.710312 -361.792757)
			(xy 435.662778 -361.825695) (xy 435.610818 -361.851084) (xy 435.555622 -361.868341) (xy 435.498454 -361.877073)
			(xy 435.469538 -361.87761) (xy 435.442286 -361.877109) (xy 435.388337 -361.869358) (xy 435.33604 -361.854006)
			(xy 435.28646 -361.831369) (xy 435.240607 -361.801905) (xy 435.199414 -361.766215) (xy 435.163719 -361.725025)
			(xy 435.134251 -361.679175) (xy 435.111608 -361.629598) (xy 435.096251 -361.577302) (xy 435.088494 -361.523354)
			(xy 435.08803 -361.496102) (xy 435.088539 -361.467185) (xy 435.097268 -361.410012) (xy 435.114527 -361.354813)
			(xy 435.139921 -361.302851) (xy 435.172866 -361.255317) (xy 435.212609 -361.213301) (xy 435.235096 -361.195112)
			(xy 435.243847 -361.18754) (xy 435.254037 -361.166789) (xy 435.254654 -361.155234) (xy 435.254654 -361.07497)
			(xy 435.254059 -361.063405) (xy 435.243883 -361.042633) (xy 435.235096 -361.035092) (xy 435.214314 -361.018337)
			(xy 435.17718 -360.979986) (xy 435.145755 -360.936832) (xy 435.120654 -360.889719) (xy 435.102366 -360.839566)
			(xy 435.091248 -360.787354) (xy 435.087517 -360.734101) (xy 422.762937 -360.734101) (xy 422.782429 -360.743003)
			(xy 422.828279 -360.772469) (xy 422.86947 -360.80816) (xy 422.905161 -360.849351) (xy 422.934627 -360.895201)
			(xy 422.957269 -360.944778) (xy 422.972624 -360.997073) (xy 422.98038 -361.051021) (xy 422.980866 -361.078272)
			(xy 422.980375 -361.106494) (xy 422.972062 -361.162322) (xy 422.955613 -361.216317) (xy 422.931389 -361.267298)
			(xy 422.899916 -361.314153) (xy 422.861883 -361.355859) (xy 422.81812 -361.391506) (xy 422.769582 -361.420316)
			(xy 422.717329 -361.441658) (xy 422.690036 -361.448858) (xy 422.67886 -361.451652) (xy 422.661842 -361.465368)
			(xy 422.627464 -361.53471) (xy 424.407836 -361.53471) (xy 424.411907 -361.479088) (xy 424.424033 -361.424651)
			(xy 424.443956 -361.37256) (xy 424.471252 -361.323925) (xy 424.505338 -361.279782) (xy 424.545487 -361.241073)
			(xy 424.590845 -361.208622) (xy 424.640445 -361.183121) (xy 424.693229 -361.165114) (xy 424.748072 -361.154984)
			(xy 424.803806 -361.152947) (xy 424.859243 -361.159047) (xy 424.9132 -361.173153) (xy 424.964529 -361.194965)
			(xy 425.012135 -361.224019) (xy 425.055003 -361.259694) (xy 425.09222 -361.301231) (xy 425.122993 -361.347744)
			(xy 425.146665 -361.398241) (xy 425.162733 -361.451648) (xy 425.170853 -361.506824) (xy 425.171362 -361.53471)
			(xy 425.170853 -361.562596) (xy 425.162733 -361.617772) (xy 425.146665 -361.671179) (xy 425.122993 -361.721676)
			(xy 425.09222 -361.768189) (xy 425.055003 -361.809726) (xy 425.012135 -361.845401) (xy 424.971544 -361.870174)
			(xy 431.124356 -361.870174) (xy 431.124356 -361.785478) (xy 431.132407 -361.701164) (xy 431.148436 -361.617998)
			(xy 431.172297 -361.536731) (xy 431.203776 -361.458101) (xy 431.242587 -361.38282) (xy 431.288377 -361.311568)
			(xy 431.340733 -361.244992) (xy 431.399181 -361.183694) (xy 431.463191 -361.128229) (xy 431.532183 -361.0791)
			(xy 431.605533 -361.036751) (xy 431.682576 -361.001567) (xy 431.762615 -360.973865) (xy 431.844924 -360.953897)
			(xy 431.928759 -360.941844) (xy 432.01336 -360.937814) (xy 432.097961 -360.941844) (xy 432.181796 -360.953897)
			(xy 432.264105 -360.973865) (xy 432.344144 -361.001567) (xy 432.421187 -361.036751) (xy 432.494537 -361.0791)
			(xy 432.563529 -361.128229) (xy 432.627539 -361.183694) (xy 432.685987 -361.244992) (xy 432.738343 -361.311568)
			(xy 432.784133 -361.38282) (xy 432.822944 -361.458101) (xy 432.854423 -361.536731) (xy 432.878284 -361.617998)
			(xy 432.894313 -361.701164) (xy 432.902364 -361.785478) (xy 432.902868 -361.827826) (xy 432.902364 -361.870174)
			(xy 432.894313 -361.954488) (xy 432.878284 -362.037654) (xy 432.854423 -362.118921) (xy 432.822944 -362.197551)
			(xy 432.784133 -362.272832) (xy 432.738343 -362.344084) (xy 432.685987 -362.41066) (xy 432.627539 -362.471958)
			(xy 432.563529 -362.527423) (xy 432.494537 -362.576552) (xy 432.421187 -362.618901) (xy 432.344144 -362.654085)
			(xy 432.264105 -362.681787) (xy 432.181796 -362.701755) (xy 432.097961 -362.713808) (xy 432.01336 -362.717839)
			(xy 431.928759 -362.713808) (xy 431.844924 -362.701755) (xy 431.762615 -362.681787) (xy 431.682576 -362.654085)
			(xy 431.605533 -362.618901) (xy 431.532183 -362.576552) (xy 431.463191 -362.527423) (xy 431.399181 -362.471958)
			(xy 431.340733 -362.41066) (xy 431.288377 -362.344084) (xy 431.242587 -362.272832) (xy 431.203776 -362.197551)
			(xy 431.172297 -362.118921) (xy 431.148436 -362.037654) (xy 431.132407 -361.954488) (xy 431.124356 -361.870174)
			(xy 424.971544 -361.870174) (xy 424.964529 -361.874455) (xy 424.9132 -361.896267) (xy 424.859243 -361.910373)
			(xy 424.803806 -361.916473) (xy 424.748072 -361.914436) (xy 424.693229 -361.904306) (xy 424.640445 -361.886299)
			(xy 424.590845 -361.860798) (xy 424.545487 -361.828347) (xy 424.505338 -361.789638) (xy 424.471252 -361.745495)
			(xy 424.443956 -361.69686) (xy 424.424033 -361.644769) (xy 424.411907 -361.590332) (xy 424.407836 -361.53471)
			(xy 422.627464 -361.53471) (xy 422.617138 -361.555538) (xy 422.61663 -361.577636) (xy 422.621202 -361.588304)
			(xy 422.631327 -361.612509) (xy 422.645578 -361.663005) (xy 422.65277 -361.714978) (xy 422.653206 -361.741212)
			(xy 422.653111 -361.751457) (xy 422.651969 -361.771915) (xy 422.65092 -361.782106) (xy 422.649904 -361.792266)
			(xy 422.656 -361.812078) (xy 422.715944 -361.88396) (xy 422.734232 -361.893358) (xy 422.744392 -361.89412)
			(xy 422.772852 -361.89667) (xy 422.828568 -361.909356) (xy 422.88177 -361.930208) (xy 422.931268 -361.95876)
			(xy 422.975955 -361.994372) (xy 423.014833 -362.03625) (xy 423.047032 -362.083456) (xy 423.071833 -362.134936)
			(xy 423.088681 -362.189537) (xy 423.097199 -362.246041) (xy 423.097706 -362.274612) (xy 423.097235 -362.301594)
			(xy 423.089605 -362.355016) (xy 423.074527 -362.406832) (xy 423.052302 -362.456007) (xy 423.023372 -362.501561)
			(xy 422.988314 -362.542588) (xy 422.947828 -362.578267) (xy 422.902721 -362.607889) (xy 422.878504 -362.619798)
			(xy 422.870122 -362.623862) (xy 422.857168 -362.63707) (xy 422.823132 -362.716064) (xy 422.82237 -362.734606)
			(xy 422.825164 -362.743496) (xy 422.834042 -362.77241) (xy 422.843614 -362.832128) (xy 422.844214 -362.862368)
			(xy 422.843728 -362.889619) (xy 422.837786 -362.930948) (xy 439.741056 -362.930948) (xy 439.741537 -362.903578)
			(xy 439.749349 -362.849399) (xy 439.764834 -362.796896) (xy 439.787673 -362.747148) (xy 439.817395 -362.701182)
			(xy 439.835036 -362.68025) (xy 439.841132 -362.673138) (xy 439.847482 -362.65612) (xy 439.847482 -362.570776)
			(xy 439.841132 -362.553758) (xy 439.835036 -362.546646) (xy 439.817411 -362.525703) (xy 439.787695 -362.479734)
			(xy 439.764856 -362.429989) (xy 439.749362 -362.377491) (xy 439.741531 -362.323317) (xy 439.741056 -362.295948)
			(xy 439.7416 -362.268698) (xy 439.749349 -362.214752) (xy 439.764697 -362.162458) (xy 439.787332 -362.11288)
			(xy 439.816791 -362.067028) (xy 439.852477 -362.025836) (xy 439.893661 -361.990142) (xy 439.939506 -361.960672)
			(xy 439.989079 -361.938027) (xy 440.04137 -361.922667) (xy 440.095314 -361.914906) (xy 440.122564 -361.91444)
			(xy 440.149934 -361.914917) (xy 440.204113 -361.922731) (xy 440.256616 -361.938217) (xy 440.306363 -361.961056)
			(xy 440.35233 -361.990779) (xy 440.373262 -362.00842) (xy 440.380374 -362.014516) (xy 440.397392 -362.020866)
			(xy 440.482736 -362.020866) (xy 440.499754 -362.014516) (xy 440.506866 -362.00842) (xy 440.527799 -361.990779)
			(xy 440.573767 -361.961055) (xy 440.623513 -361.938209) (xy 440.676015 -361.922713) (xy 440.730193 -361.914884)
			(xy 440.784935 -361.914884) (xy 440.839113 -361.922713) (xy 440.891615 -361.938209) (xy 440.941361 -361.961055)
			(xy 440.987329 -361.990779) (xy 441.008262 -362.00842) (xy 441.015374 -362.014516) (xy 441.032392 -362.020866)
			(xy 441.117736 -362.020866) (xy 441.134754 -362.014516) (xy 441.141866 -362.00842) (xy 441.162799 -361.990779)
			(xy 441.208767 -361.961055) (xy 441.258513 -361.938209) (xy 441.311015 -361.922713) (xy 441.365193 -361.914884)
			(xy 441.419935 -361.914884) (xy 441.474113 -361.922713) (xy 441.526615 -361.938209) (xy 441.576361 -361.961055)
			(xy 441.622329 -361.990779) (xy 441.643262 -362.00842) (xy 441.650374 -362.014516) (xy 441.667392 -362.020866)
			(xy 441.752736 -362.020866) (xy 441.769754 -362.014516) (xy 441.776866 -362.00842) (xy 441.780676 -362.005118)
			(xy 441.788794 -361.997516) (xy 441.798146 -361.977364) (xy 441.79871 -361.966256) (xy 441.79871 -361.88904)
			(xy 441.798164 -361.877927) (xy 441.788813 -361.857766) (xy 441.780676 -361.850178) (xy 441.759946 -361.831987)
			(xy 441.723478 -361.790614) (xy 441.693349 -361.744419) (xy 441.670187 -361.694367) (xy 441.654474 -361.641501)
			(xy 441.646539 -361.586924) (xy 441.646056 -361.559348) (xy 441.646537 -361.531978) (xy 441.654349 -361.477799)
			(xy 441.669834 -361.425296) (xy 441.692673 -361.375548) (xy 441.722395 -361.329582) (xy 441.740036 -361.30865)
			(xy 441.746132 -361.301538) (xy 441.752482 -361.28452) (xy 441.752482 -361.199176) (xy 441.746132 -361.182158)
			(xy 441.740036 -361.175046) (xy 441.722442 -361.154075) (xy 441.692715 -361.108114) (xy 441.669866 -361.058374)
			(xy 441.654365 -361.005878) (xy 441.646532 -360.951705) (xy 441.646527 -360.896968) (xy 441.65435 -360.842793)
			(xy 441.66984 -360.790293) (xy 441.69268 -360.740549) (xy 441.722398 -360.694582) (xy 441.740036 -360.67365)
			(xy 441.746132 -360.666538) (xy 441.752482 -360.64952) (xy 441.752482 -360.564176) (xy 441.746132 -360.547158)
			(xy 441.740036 -360.540046) (xy 441.722442 -360.519075) (xy 441.692715 -360.473114) (xy 441.669866 -360.423374)
			(xy 441.654365 -360.370878) (xy 441.646532 -360.316705) (xy 441.646527 -360.261968) (xy 441.65435 -360.207793)
			(xy 441.66984 -360.155293) (xy 441.69268 -360.105549) (xy 441.722398 -360.059582) (xy 441.740036 -360.03865)
			(xy 441.746132 -360.031538) (xy 441.752482 -360.01452) (xy 441.752482 -359.929176) (xy 441.746132 -359.912158)
			(xy 441.740036 -359.905046) (xy 441.722411 -359.884103) (xy 441.692695 -359.838134) (xy 441.669856 -359.788389)
			(xy 441.654362 -359.735891) (xy 441.646531 -359.681717) (xy 441.646056 -359.654348) (xy 441.646535 -359.626774)
			(xy 441.654482 -359.572201) (xy 441.670203 -359.51934) (xy 441.693371 -359.469294) (xy 441.723502 -359.423104)
			(xy 441.759969 -359.381733) (xy 441.780676 -359.363518) (xy 441.788794 -359.355916) (xy 441.798146 -359.335764)
			(xy 441.79871 -359.324656) (xy 441.79871 -359.24744) (xy 441.798164 -359.236327) (xy 441.788813 -359.216166)
			(xy 441.780676 -359.208578) (xy 441.776866 -359.205276) (xy 441.769754 -359.19918) (xy 441.752736 -359.19283)
			(xy 441.667392 -359.19283) (xy 441.650374 -359.19918) (xy 441.643262 -359.205276) (xy 441.622329 -359.222917)
			(xy 441.576361 -359.252641) (xy 441.526615 -359.275487) (xy 441.474113 -359.290983) (xy 441.419935 -359.298812)
			(xy 441.365193 -359.298812) (xy 441.311015 -359.290983) (xy 441.258513 -359.275487) (xy 441.208767 -359.252641)
			(xy 441.162799 -359.222917) (xy 441.141866 -359.205276) (xy 441.134754 -359.19918) (xy 441.117736 -359.19283)
			(xy 441.032392 -359.19283) (xy 441.015374 -359.19918) (xy 441.008262 -359.205276) (xy 440.987329 -359.222917)
			(xy 440.941361 -359.252641) (xy 440.891615 -359.275487) (xy 440.839113 -359.290983) (xy 440.784935 -359.298812)
			(xy 440.730193 -359.298812) (xy 440.676015 -359.290983) (xy 440.623513 -359.275487) (xy 440.573767 -359.252641)
			(xy 440.527799 -359.222917) (xy 440.506866 -359.205276) (xy 440.499754 -359.19918) (xy 440.482736 -359.19283)
			(xy 440.397392 -359.19283) (xy 440.380374 -359.19918) (xy 440.373262 -359.205276) (xy 440.352314 -359.222896)
			(xy 440.306346 -359.252611) (xy 440.256603 -359.275451) (xy 440.204105 -359.290947) (xy 440.149932 -359.29878)
			(xy 440.122564 -359.299256) (xy 440.095314 -359.298756) (xy 440.041369 -359.290996) (xy 439.989078 -359.275638)
			(xy 439.939504 -359.252997) (xy 439.893656 -359.223531) (xy 439.852467 -359.187841) (xy 439.816776 -359.146654)
			(xy 439.787309 -359.100807) (xy 439.764666 -359.051233) (xy 439.749307 -358.998942) (xy 439.741545 -358.944998)
			(xy 439.741056 -358.917748) (xy 439.741537 -358.890378) (xy 439.749349 -358.836199) (xy 439.764834 -358.783696)
			(xy 439.787673 -358.733948) (xy 439.817395 -358.687982) (xy 439.835036 -358.66705) (xy 439.841132 -358.659938)
			(xy 439.847482 -358.64292) (xy 439.847482 -358.557576) (xy 439.841132 -358.540558) (xy 439.835036 -358.533446)
			(xy 439.817411 -358.512503) (xy 439.787695 -358.466534) (xy 439.764856 -358.416789) (xy 439.749362 -358.364291)
			(xy 439.741531 -358.310117) (xy 439.741056 -358.282748) (xy 439.7416 -358.255498) (xy 439.749349 -358.201552)
			(xy 439.764697 -358.149258) (xy 439.787332 -358.09968) (xy 439.816791 -358.053828) (xy 439.852477 -358.012636)
			(xy 439.893661 -357.976942) (xy 439.939506 -357.947472) (xy 439.989079 -357.924827) (xy 440.04137 -357.909467)
			(xy 440.095314 -357.901706) (xy 440.122564 -357.90124) (xy 440.149934 -357.901717) (xy 440.204113 -357.909531)
			(xy 440.256616 -357.925017) (xy 440.306363 -357.947856) (xy 440.35233 -357.977579) (xy 440.373262 -357.99522)
			(xy 440.380374 -358.001316) (xy 440.397392 -358.007666) (xy 440.482736 -358.007666) (xy 440.499754 -358.001316)
			(xy 440.506866 -357.99522) (xy 440.527799 -357.977579) (xy 440.573767 -357.947855) (xy 440.623513 -357.925009)
			(xy 440.676015 -357.909513) (xy 440.730193 -357.901684) (xy 440.784935 -357.901684) (xy 440.839113 -357.909513)
			(xy 440.891615 -357.925009) (xy 440.941361 -357.947855) (xy 440.987329 -357.977579) (xy 441.008262 -357.99522)
			(xy 441.015374 -358.001316) (xy 441.032392 -358.007666) (xy 441.117736 -358.007666) (xy 441.134754 -358.001316)
			(xy 441.141866 -357.99522) (xy 441.162799 -357.977579) (xy 441.208767 -357.947855) (xy 441.258513 -357.925009)
			(xy 441.311015 -357.909513) (xy 441.365193 -357.901684) (xy 441.419935 -357.901684) (xy 441.474113 -357.909513)
			(xy 441.526615 -357.925009) (xy 441.576361 -357.947855) (xy 441.622329 -357.977579) (xy 441.643262 -357.99522)
			(xy 441.650374 -358.001316) (xy 441.667392 -358.007666) (xy 441.752736 -358.007666) (xy 441.769754 -358.001316)
			(xy 441.776866 -357.99522) (xy 441.797799 -357.977579) (xy 441.843767 -357.947855) (xy 441.893513 -357.925009)
			(xy 441.946015 -357.909513) (xy 442.000193 -357.901684) (xy 442.054935 -357.901684) (xy 442.109113 -357.909513)
			(xy 442.161615 -357.925009) (xy 442.211361 -357.947855) (xy 442.257329 -357.977579) (xy 442.278262 -357.99522)
			(xy 442.285374 -358.001316) (xy 442.302392 -358.007666) (xy 442.387736 -358.007666) (xy 442.404754 -358.001316)
			(xy 442.411866 -357.99522) (xy 442.432803 -357.977586) (xy 442.478774 -357.947873) (xy 442.52852 -357.925036)
			(xy 442.58102 -357.909543) (xy 442.635195 -357.901714) (xy 442.662564 -357.90124) (xy 442.689818 -357.901689)
			(xy 442.743772 -357.909442) (xy 442.796073 -357.924796) (xy 442.845656 -357.947438) (xy 442.891512 -357.976907)
			(xy 442.932706 -358.012602) (xy 442.968401 -358.053798) (xy 442.997868 -358.099654) (xy 443.020508 -358.149238)
			(xy 443.03586 -358.20154) (xy 443.043612 -358.255494) (xy 443.044072 -358.282748) (xy 443.043582 -358.310117)
			(xy 443.035771 -358.364296) (xy 443.020288 -358.416799) (xy 442.997451 -358.466546) (xy 442.967731 -358.512514)
			(xy 442.950092 -358.533446) (xy 442.943996 -358.540558) (xy 442.937646 -358.557576) (xy 442.937646 -358.64292)
			(xy 442.943996 -358.659938) (xy 442.950092 -358.66705) (xy 442.96772 -358.687991) (xy 442.997434 -358.733961)
			(xy 443.020272 -358.783707) (xy 443.035766 -358.836205) (xy 443.043597 -358.890379) (xy 443.044072 -358.917748)
			(xy 443.04358 -358.945322) (xy 443.035634 -358.999894) (xy 443.019915 -359.052754) (xy 442.99675 -359.1028)
			(xy 442.966622 -359.14899) (xy 442.930158 -359.190362) (xy 442.909452 -359.208578) (xy 442.90134 -359.216186)
			(xy 442.891984 -359.236334) (xy 442.891418 -359.24744) (xy 442.891418 -359.324656) (xy 442.891989 -359.335766)
			(xy 442.901325 -359.355925) (xy 442.909452 -359.363518) (xy 442.930165 -359.381727) (xy 442.966638 -359.423095)
			(xy 442.996771 -359.469285) (xy 443.019936 -359.519334) (xy 443.035652 -359.572197) (xy 443.043589 -359.626773)
			(xy 443.044072 -359.654348) (xy 443.043582 -359.681717) (xy 443.035771 -359.735896) (xy 443.020288 -359.788399)
			(xy 442.997451 -359.838146) (xy 442.967731 -359.884114) (xy 442.950092 -359.905046) (xy 442.943996 -359.912158)
			(xy 442.937646 -359.929176) (xy 442.937646 -360.01452) (xy 442.943996 -360.031538) (xy 442.950092 -360.03865)
			(xy 442.967779 -360.059545) (xy 442.9975 -360.10552) (xy 443.020342 -360.155272) (xy 443.035833 -360.20778)
			(xy 443.043657 -360.261963) (xy 443.043652 -360.316709) (xy 443.035818 -360.370891) (xy 443.020316 -360.423395)
			(xy 442.997465 -360.473144) (xy 442.967735 -360.519113) (xy 442.950092 -360.540046) (xy 442.943996 -360.547158)
			(xy 442.937646 -360.564176) (xy 442.937646 -360.64952) (xy 442.943996 -360.666538) (xy 442.950092 -360.67365)
			(xy 442.967779 -360.694545) (xy 442.9975 -360.74052) (xy 443.020342 -360.790272) (xy 443.035833 -360.84278)
			(xy 443.043657 -360.896963) (xy 443.043652 -360.951709) (xy 443.035818 -361.005891) (xy 443.020316 -361.058395)
			(xy 442.997465 -361.108144) (xy 442.967735 -361.154113) (xy 442.950092 -361.175046) (xy 442.943996 -361.182158)
			(xy 442.937646 -361.199176) (xy 442.937646 -361.28452) (xy 442.943996 -361.301538) (xy 442.950092 -361.30865)
			(xy 442.96772 -361.329591) (xy 442.997434 -361.375561) (xy 443.020272 -361.425307) (xy 443.035766 -361.477805)
			(xy 443.043597 -361.531979) (xy 443.044072 -361.559348) (xy 443.043667 -361.586602) (xy 443.035903 -361.640555)
			(xy 443.02054 -361.692853) (xy 442.99789 -361.742433) (xy 442.968416 -361.788285) (xy 442.932716 -361.829475)
			(xy 442.891517 -361.865166) (xy 442.845659 -361.894631) (xy 442.796074 -361.917269) (xy 442.743772 -361.932621)
			(xy 442.689818 -361.940373) (xy 442.662564 -361.940856) (xy 442.635192 -361.940422) (xy 442.581012 -361.932598)
			(xy 442.528508 -361.917102) (xy 442.478761 -361.894253) (xy 442.432796 -361.864521) (xy 442.411866 -361.846876)
			(xy 442.404754 -361.84078) (xy 442.387736 -361.83443) (xy 442.302392 -361.83443) (xy 442.285374 -361.84078)
			(xy 442.278262 -361.846876) (xy 442.274452 -361.850178) (xy 442.26634 -361.857786) (xy 442.256984 -361.877934)
			(xy 442.256418 -361.88904) (xy 442.256418 -361.966256) (xy 442.256989 -361.977366) (xy 442.266325 -361.997525)
			(xy 442.274452 -362.005118) (xy 442.295165 -362.023327) (xy 442.331638 -362.064695) (xy 442.361771 -362.110885)
			(xy 442.384936 -362.160934) (xy 442.400652 -362.213797) (xy 442.408589 -362.268373) (xy 442.409072 -362.295948)
			(xy 442.408667 -362.323202) (xy 442.400903 -362.377155) (xy 442.38554 -362.429453) (xy 442.36289 -362.479033)
			(xy 442.333416 -362.524885) (xy 442.297716 -362.566075) (xy 442.256517 -362.601766) (xy 442.210659 -362.631231)
			(xy 442.161074 -362.653869) (xy 442.108772 -362.669221) (xy 442.054818 -362.676973) (xy 442.027564 -362.677456)
			(xy 441.998087 -362.676888) (xy 441.939835 -362.667827) (xy 441.88367 -362.649912) (xy 441.83093 -362.623569)
			(xy 441.782872 -362.589424) (xy 441.761372 -362.569252) (xy 441.754047 -362.562706) (xy 441.735879 -362.555269)
			(xy 441.726066 -362.554774) (xy 441.672726 -362.554774) (xy 441.665868 -362.56214) (xy 441.659319 -362.569463)
			(xy 441.651883 -362.587632) (xy 441.65139 -362.597446) (xy 441.65139 -362.62945) (xy 441.651862 -362.639266)
			(xy 441.659317 -362.65743) (xy 441.665868 -362.664756) (xy 441.686023 -362.686272) (xy 441.72017 -362.734327)
			(xy 441.746519 -362.787062) (xy 441.764445 -362.843223) (xy 441.77352 -362.901472) (xy 441.774072 -362.930948)
			(xy 441.773667 -362.958202) (xy 441.765903 -363.012155) (xy 441.75054 -363.064453) (xy 441.72789 -363.114033)
			(xy 441.698416 -363.159885) (xy 441.662716 -363.201075) (xy 441.621517 -363.236766) (xy 441.575659 -363.266231)
			(xy 441.526074 -363.288869) (xy 441.473772 -363.304221) (xy 441.419818 -363.311973) (xy 441.392564 -363.312456)
			(xy 441.365192 -363.312022) (xy 441.311012 -363.304198) (xy 441.258508 -363.288702) (xy 441.208761 -363.265853)
			(xy 441.162796 -363.236121) (xy 441.141866 -363.218476) (xy 441.134754 -363.21238) (xy 441.117736 -363.20603)
			(xy 441.032392 -363.20603) (xy 441.015374 -363.21238) (xy 441.008262 -363.218476) (xy 440.987329 -363.236117)
			(xy 440.941361 -363.265841) (xy 440.891615 -363.288687) (xy 440.839113 -363.304183) (xy 440.784935 -363.312012)
			(xy 440.730193 -363.312012) (xy 440.676015 -363.304183) (xy 440.623513 -363.288687) (xy 440.573767 -363.265841)
			(xy 440.527799 -363.236117) (xy 440.506866 -363.218476) (xy 440.499754 -363.21238) (xy 440.482736 -363.20603)
			(xy 440.397392 -363.20603) (xy 440.380374 -363.21238) (xy 440.373262 -363.218476) (xy 440.352314 -363.236096)
			(xy 440.306346 -363.265811) (xy 440.256603 -363.288651) (xy 440.204105 -363.304147) (xy 440.149932 -363.31198)
			(xy 440.122564 -363.312456) (xy 440.095314 -363.311956) (xy 440.041369 -363.304196) (xy 439.989078 -363.288838)
			(xy 439.939504 -363.266197) (xy 439.893656 -363.236731) (xy 439.852467 -363.201041) (xy 439.816776 -363.159854)
			(xy 439.787309 -363.114007) (xy 439.764666 -363.064433) (xy 439.749307 -363.012142) (xy 439.741545 -362.958198)
			(xy 439.741056 -362.930948) (xy 422.837786 -362.930948) (xy 422.835972 -362.943567) (xy 422.820617 -362.995862)
			(xy 422.797975 -363.045439) (xy 422.768509 -363.091289) (xy 422.732818 -363.13248) (xy 422.691627 -363.168171)
			(xy 422.645777 -363.197637) (xy 422.5962 -363.220279) (xy 422.543905 -363.235634) (xy 422.489957 -363.24339)
			(xy 422.435455 -363.24339) (xy 422.381507 -363.235634) (xy 422.329212 -363.220279) (xy 422.279635 -363.197637)
			(xy 422.233785 -363.168171) (xy 422.192594 -363.13248) (xy 422.156903 -363.091289) (xy 422.127437 -363.045439)
			(xy 422.104795 -362.995862) (xy 422.08944 -362.943567) (xy 422.081684 -362.889619) (xy 422.081198 -362.862368)
			(xy 422.081733 -362.835388) (xy 422.089352 -362.781968) (xy 422.10442 -362.730155) (xy 422.126636 -362.68098)
			(xy 422.155557 -362.635425) (xy 422.190606 -362.594397) (xy 422.231085 -362.558716) (xy 422.276186 -362.529092)
			(xy 422.3004 -362.517182) (xy 422.308782 -362.513118) (xy 422.321736 -362.49991) (xy 422.355772 -362.420916)
			(xy 422.356534 -362.402374) (xy 422.35374 -362.393484) (xy 422.344857 -362.364572) (xy 422.335288 -362.304852)
			(xy 422.33469 -362.274612) (xy 422.334779 -362.264367) (xy 422.335925 -362.243909) (xy 422.336976 -362.233718)
			(xy 422.337992 -362.223558) (xy 422.331896 -362.203746) (xy 422.271952 -362.131864) (xy 422.253664 -362.122466)
			(xy 422.243504 -362.121704) (xy 422.215055 -362.119049) (xy 422.159343 -362.106377) (xy 422.106143 -362.085539)
			(xy 422.056646 -362.057001) (xy 422.011958 -362.021401) (xy 421.973078 -361.979535) (xy 421.940876 -361.932339)
			(xy 421.916072 -361.880869) (xy 421.899221 -361.826275) (xy 421.890699 -361.769779) (xy 421.89019 -361.741212)
			(xy 410.08173 -361.741212) (xy 410.08173 -362.804964) (xy 412.9311 -362.804964) (xy 412.935171 -362.749342)
			(xy 412.947297 -362.694905) (xy 412.96722 -362.642814) (xy 412.994516 -362.594179) (xy 413.028602 -362.550036)
			(xy 413.068751 -362.511327) (xy 413.114109 -362.478876) (xy 413.163709 -362.453375) (xy 413.216493 -362.435368)
			(xy 413.271336 -362.425238) (xy 413.32707 -362.423201) (xy 413.382507 -362.429301) (xy 413.436464 -362.443407)
			(xy 413.487793 -362.465219) (xy 413.535399 -362.494273) (xy 413.578267 -362.529948) (xy 413.615484 -362.571485)
			(xy 413.646257 -362.617998) (xy 413.669929 -362.668495) (xy 413.685997 -362.721902) (xy 413.694117 -362.777078)
			(xy 413.694626 -362.804964) (xy 413.694117 -362.83285) (xy 413.685997 -362.888026) (xy 413.669929 -362.941433)
			(xy 413.646257 -362.99193) (xy 413.615484 -363.038443) (xy 413.578267 -363.07998) (xy 413.535399 -363.115655)
			(xy 413.487793 -363.144709) (xy 413.436464 -363.166521) (xy 413.382507 -363.180627) (xy 413.32707 -363.186727)
			(xy 413.271336 -363.18469) (xy 413.216493 -363.17456) (xy 413.163709 -363.156553) (xy 413.114109 -363.131052)
			(xy 413.068751 -363.098601) (xy 413.028602 -363.059892) (xy 412.994516 -363.015749) (xy 412.96722 -362.967114)
			(xy 412.947297 -362.915023) (xy 412.935171 -362.860586) (xy 412.9311 -362.804964) (xy 410.08173 -362.804964)
			(xy 410.08173 -363.356144) (xy 415.065208 -363.356144) (xy 415.069279 -363.300522) (xy 415.081405 -363.246085)
			(xy 415.101328 -363.193994) (xy 415.128624 -363.145359) (xy 415.16271 -363.101216) (xy 415.202859 -363.062507)
			(xy 415.248217 -363.030056) (xy 415.297817 -363.004555) (xy 415.350601 -362.986548) (xy 415.405444 -362.976418)
			(xy 415.461178 -362.974381) (xy 415.516615 -362.980481) (xy 415.570572 -362.994587) (xy 415.621901 -363.016399)
			(xy 415.669507 -363.045453) (xy 415.712375 -363.081128) (xy 415.749592 -363.122665) (xy 415.780365 -363.169178)
			(xy 415.804037 -363.219675) (xy 415.820105 -363.273082) (xy 415.828225 -363.328258) (xy 415.828734 -363.356144)
			(xy 415.828225 -363.38403) (xy 415.820105 -363.439206) (xy 415.804037 -363.492613) (xy 415.780365 -363.54311)
			(xy 415.749592 -363.589623) (xy 415.712375 -363.63116) (xy 415.669507 -363.666835) (xy 415.621901 -363.695889)
			(xy 415.570572 -363.717701) (xy 415.516615 -363.731807) (xy 415.461178 -363.737907) (xy 415.405444 -363.73587)
			(xy 415.350601 -363.72574) (xy 415.297817 -363.707733) (xy 415.248217 -363.682232) (xy 415.202859 -363.649781)
			(xy 415.16271 -363.611072) (xy 415.128624 -363.566929) (xy 415.101328 -363.518294) (xy 415.081405 -363.466203)
			(xy 415.069279 -363.411766) (xy 415.065208 -363.356144) (xy 410.08173 -363.356144) (xy 410.08173 -364.079536)
			(xy 412.440372 -364.079536) (xy 412.444443 -364.023914) (xy 412.456569 -363.969477) (xy 412.476492 -363.917386)
			(xy 412.503788 -363.868751) (xy 412.537874 -363.824608) (xy 412.578023 -363.785899) (xy 412.623381 -363.753448)
			(xy 412.672981 -363.727947) (xy 412.725765 -363.70994) (xy 412.780608 -363.69981) (xy 412.836342 -363.697773)
			(xy 412.891779 -363.703873) (xy 412.945736 -363.717979) (xy 412.997065 -363.739791) (xy 413.044671 -363.768845)
			(xy 413.087539 -363.80452) (xy 413.124756 -363.846057) (xy 413.155529 -363.89257) (xy 413.179201 -363.943067)
			(xy 413.182585 -363.954314) (xy 425.230796 -363.954314) (xy 425.234867 -363.898692) (xy 425.246993 -363.844255)
			(xy 425.266916 -363.792164) (xy 425.294212 -363.743529) (xy 425.328298 -363.699386) (xy 425.368447 -363.660677)
			(xy 425.413805 -363.628226) (xy 425.463405 -363.602725) (xy 425.516189 -363.584718) (xy 425.571032 -363.574588)
			(xy 425.626766 -363.572551) (xy 425.682203 -363.578651) (xy 425.73616 -363.592757) (xy 425.787489 -363.614569)
			(xy 425.835095 -363.643623) (xy 425.877963 -363.679298) (xy 425.91518 -363.720835) (xy 425.945953 -363.767348)
			(xy 425.969625 -363.817845) (xy 425.985693 -363.871252) (xy 425.993813 -363.926428) (xy 425.994322 -363.954314)
			(xy 425.993813 -363.9822) (xy 425.985693 -364.037376) (xy 425.969625 -364.090783) (xy 425.945953 -364.14128)
			(xy 425.91518 -364.187793) (xy 425.877963 -364.22933) (xy 425.835095 -364.265005) (xy 425.787489 -364.294059)
			(xy 425.73616 -364.315871) (xy 425.682203 -364.329977) (xy 425.626766 -364.336077) (xy 425.571032 -364.33404)
			(xy 425.516189 -364.32391) (xy 425.463405 -364.305903) (xy 425.413805 -364.280402) (xy 425.368447 -364.247951)
			(xy 425.328298 -364.209242) (xy 425.294212 -364.165099) (xy 425.266916 -364.116464) (xy 425.246993 -364.064373)
			(xy 425.234867 -364.009936) (xy 425.230796 -363.954314) (xy 413.182585 -363.954314) (xy 413.195269 -363.996474)
			(xy 413.203389 -364.05165) (xy 413.203898 -364.079536) (xy 413.203389 -364.107422) (xy 413.195269 -364.162598)
			(xy 413.179201 -364.216005) (xy 413.155529 -364.266502) (xy 413.124756 -364.313015) (xy 413.087539 -364.354552)
			(xy 413.084102 -364.357412) (xy 416.135818 -364.357412) (xy 416.139889 -364.30179) (xy 416.152015 -364.247353)
			(xy 416.171938 -364.195262) (xy 416.199234 -364.146627) (xy 416.23332 -364.102484) (xy 416.273469 -364.063775)
			(xy 416.318827 -364.031324) (xy 416.368427 -364.005823) (xy 416.421211 -363.987816) (xy 416.476054 -363.977686)
			(xy 416.531788 -363.975649) (xy 416.587225 -363.981749) (xy 416.641182 -363.995855) (xy 416.692511 -364.017667)
			(xy 416.740117 -364.046721) (xy 416.782985 -364.082396) (xy 416.820202 -364.123933) (xy 416.850975 -364.170446)
			(xy 416.874647 -364.220943) (xy 416.890715 -364.27435) (xy 416.898835 -364.329526) (xy 416.899344 -364.357412)
			(xy 416.898835 -364.385298) (xy 416.890715 -364.440474) (xy 416.874647 -364.493881) (xy 416.86825 -364.507526)
			(xy 424.072048 -364.507526) (xy 424.076119 -364.451904) (xy 424.088245 -364.397467) (xy 424.108168 -364.345376)
			(xy 424.135464 -364.296741) (xy 424.16955 -364.252598) (xy 424.209699 -364.213889) (xy 424.255057 -364.181438)
			(xy 424.304657 -364.155937) (xy 424.357441 -364.13793) (xy 424.412284 -364.1278) (xy 424.468018 -364.125763)
			(xy 424.523455 -364.131863) (xy 424.577412 -364.145969) (xy 424.628741 -364.167781) (xy 424.676347 -364.196835)
			(xy 424.719215 -364.23251) (xy 424.756432 -364.274047) (xy 424.787205 -364.32056) (xy 424.81052 -364.370296)
			(xy 431.124356 -364.370296) (xy 431.124356 -364.2856) (xy 431.132407 -364.201286) (xy 431.148436 -364.11812)
			(xy 431.172297 -364.036853) (xy 431.203776 -363.958223) (xy 431.242587 -363.882942) (xy 431.288377 -363.81169)
			(xy 431.340733 -363.745114) (xy 431.399181 -363.683816) (xy 431.463191 -363.628351) (xy 431.532183 -363.579222)
			(xy 431.605533 -363.536873) (xy 431.682576 -363.501689) (xy 431.762615 -363.473987) (xy 431.844924 -363.454019)
			(xy 431.928759 -363.441966) (xy 432.01336 -363.437936) (xy 432.097961 -363.441966) (xy 432.181796 -363.454019)
			(xy 432.264105 -363.473987) (xy 432.344144 -363.501689) (xy 432.421187 -363.536873) (xy 432.494537 -363.579222)
			(xy 432.563529 -363.628351) (xy 432.627539 -363.683816) (xy 432.685987 -363.745114) (xy 432.738343 -363.81169)
			(xy 432.784133 -363.882942) (xy 432.822944 -363.958223) (xy 432.854423 -364.036853) (xy 432.878284 -364.11812)
			(xy 432.894313 -364.201286) (xy 432.902364 -364.2856) (xy 432.902868 -364.327948) (xy 432.902364 -364.370296)
			(xy 432.894313 -364.45461) (xy 432.878284 -364.537776) (xy 432.854423 -364.619043) (xy 432.822944 -364.697673)
			(xy 432.784133 -364.772954) (xy 432.738343 -364.844206) (xy 432.685987 -364.910782) (xy 432.627539 -364.97208)
			(xy 432.563529 -365.027545) (xy 432.494537 -365.076674) (xy 432.421187 -365.119023) (xy 432.344144 -365.154207)
			(xy 432.264105 -365.181909) (xy 432.181796 -365.201877) (xy 432.097961 -365.21393) (xy 432.01336 -365.217961)
			(xy 431.928759 -365.21393) (xy 431.844924 -365.201877) (xy 431.762615 -365.181909) (xy 431.682576 -365.154207)
			(xy 431.605533 -365.119023) (xy 431.532183 -365.076674) (xy 431.463191 -365.027545) (xy 431.399181 -364.97208)
			(xy 431.340733 -364.910782) (xy 431.288377 -364.844206) (xy 431.242587 -364.772954) (xy 431.203776 -364.697673)
			(xy 431.172297 -364.619043) (xy 431.148436 -364.537776) (xy 431.132407 -364.45461) (xy 431.124356 -364.370296)
			(xy 424.81052 -364.370296) (xy 424.810877 -364.371057) (xy 424.826945 -364.424464) (xy 424.835065 -364.47964)
			(xy 424.835574 -364.507526) (xy 424.835065 -364.535412) (xy 424.826945 -364.590588) (xy 424.810877 -364.643995)
			(xy 424.787205 -364.694492) (xy 424.756432 -364.741005) (xy 424.719215 -364.782542) (xy 424.676347 -364.818217)
			(xy 424.628741 -364.847271) (xy 424.577412 -364.869083) (xy 424.523455 -364.883189) (xy 424.468018 -364.889289)
			(xy 424.412284 -364.887252) (xy 424.357441 -364.877122) (xy 424.304657 -364.859115) (xy 424.255057 -364.833614)
			(xy 424.209699 -364.801163) (xy 424.16955 -364.762454) (xy 424.135464 -364.718311) (xy 424.108168 -364.669676)
			(xy 424.088245 -364.617585) (xy 424.076119 -364.563148) (xy 424.072048 -364.507526) (xy 416.86825 -364.507526)
			(xy 416.850975 -364.544378) (xy 416.820202 -364.590891) (xy 416.782985 -364.632428) (xy 416.740117 -364.668103)
			(xy 416.692511 -364.697157) (xy 416.641182 -364.718969) (xy 416.587225 -364.733075) (xy 416.531788 -364.739175)
			(xy 416.476054 -364.737138) (xy 416.421211 -364.727008) (xy 416.368427 -364.709001) (xy 416.318827 -364.6835)
			(xy 416.273469 -364.651049) (xy 416.23332 -364.61234) (xy 416.199234 -364.568197) (xy 416.171938 -364.519562)
			(xy 416.152015 -364.467471) (xy 416.139889 -364.413034) (xy 416.135818 -364.357412) (xy 413.084102 -364.357412)
			(xy 413.044671 -364.390227) (xy 412.997065 -364.419281) (xy 412.945736 -364.441093) (xy 412.891779 -364.455199)
			(xy 412.836342 -364.461299) (xy 412.780608 -364.459262) (xy 412.725765 -364.449132) (xy 412.672981 -364.431125)
			(xy 412.623381 -364.405624) (xy 412.578023 -364.373173) (xy 412.537874 -364.334464) (xy 412.503788 -364.290321)
			(xy 412.476492 -364.241686) (xy 412.456569 -364.189595) (xy 412.444443 -364.135158) (xy 412.440372 -364.079536)
			(xy 410.08173 -364.079536) (xy 410.08173 -364.878112) (xy 414.96564 -364.878112) (xy 414.969711 -364.82249)
			(xy 414.981837 -364.768053) (xy 415.00176 -364.715962) (xy 415.029056 -364.667327) (xy 415.063142 -364.623184)
			(xy 415.103291 -364.584475) (xy 415.148649 -364.552024) (xy 415.198249 -364.526523) (xy 415.251033 -364.508516)
			(xy 415.305876 -364.498386) (xy 415.36161 -364.496349) (xy 415.417047 -364.502449) (xy 415.471004 -364.516555)
			(xy 415.522333 -364.538367) (xy 415.569939 -364.567421) (xy 415.612807 -364.603096) (xy 415.650024 -364.644633)
			(xy 415.680797 -364.691146) (xy 415.704469 -364.741643) (xy 415.720537 -364.79505) (xy 415.728657 -364.850226)
			(xy 415.729166 -364.878112) (xy 415.728657 -364.905998) (xy 415.720537 -364.961174) (xy 415.704469 -365.014581)
			(xy 415.680797 -365.065078) (xy 415.650024 -365.111591) (xy 415.612807 -365.153128) (xy 415.569939 -365.188803)
			(xy 415.522333 -365.217857) (xy 415.471872 -365.2393) (xy 417.696648 -365.2393) (xy 417.700719 -365.183678)
			(xy 417.712845 -365.129241) (xy 417.732768 -365.07715) (xy 417.760064 -365.028515) (xy 417.79415 -364.984372)
			(xy 417.834299 -364.945663) (xy 417.879657 -364.913212) (xy 417.929257 -364.887711) (xy 417.982041 -364.869704)
			(xy 418.036884 -364.859574) (xy 418.092618 -364.857537) (xy 418.148055 -364.863637) (xy 418.202012 -364.877743)
			(xy 418.253341 -364.899555) (xy 418.300947 -364.928609) (xy 418.343815 -364.964284) (xy 418.381032 -365.005821)
			(xy 418.411805 -365.052334) (xy 418.435477 -365.102831) (xy 418.451545 -365.156238) (xy 418.458909 -365.20628)
			(xy 418.819582 -365.20628) (xy 418.823653 -365.150658) (xy 418.835779 -365.096221) (xy 418.855702 -365.04413)
			(xy 418.882998 -364.995495) (xy 418.917084 -364.951352) (xy 418.957233 -364.912643) (xy 419.002591 -364.880192)
			(xy 419.052191 -364.854691) (xy 419.104975 -364.836684) (xy 419.159818 -364.826554) (xy 419.215552 -364.824517)
			(xy 419.270989 -364.830617) (xy 419.324946 -364.844723) (xy 419.376275 -364.866535) (xy 419.423881 -364.895589)
			(xy 419.466749 -364.931264) (xy 419.503966 -364.972801) (xy 419.534739 -365.019314) (xy 419.558411 -365.069811)
			(xy 419.570736 -365.110776) (xy 420.772588 -365.110776) (xy 420.776659 -365.055154) (xy 420.788785 -365.000717)
			(xy 420.808708 -364.948626) (xy 420.836004 -364.899991) (xy 420.87009 -364.855848) (xy 420.910239 -364.817139)
			(xy 420.955597 -364.784688) (xy 421.005197 -364.759187) (xy 421.057981 -364.74118) (xy 421.112824 -364.73105)
			(xy 421.168558 -364.729013) (xy 421.223995 -364.735113) (xy 421.277952 -364.749219) (xy 421.329281 -364.771031)
			(xy 421.376887 -364.800085) (xy 421.419755 -364.83576) (xy 421.456972 -364.877297) (xy 421.487745 -364.92381)
			(xy 421.511417 -364.974307) (xy 421.527485 -365.027714) (xy 421.535605 -365.08289) (xy 421.536114 -365.110776)
			(xy 421.535605 -365.138662) (xy 421.527485 -365.193838) (xy 421.511417 -365.247245) (xy 421.487745 -365.297742)
			(xy 421.456972 -365.344255) (xy 421.419755 -365.385792) (xy 421.376887 -365.421467) (xy 421.329281 -365.450521)
			(xy 421.277952 -365.472333) (xy 421.223995 -365.486439) (xy 421.168558 -365.492539) (xy 421.112824 -365.490502)
			(xy 421.057981 -365.480372) (xy 421.005197 -365.462365) (xy 420.955597 -365.436864) (xy 420.910239 -365.404413)
			(xy 420.87009 -365.365704) (xy 420.836004 -365.321561) (xy 420.808708 -365.272926) (xy 420.788785 -365.220835)
			(xy 420.776659 -365.166398) (xy 420.772588 -365.110776) (xy 419.570736 -365.110776) (xy 419.574479 -365.123218)
			(xy 419.582599 -365.178394) (xy 419.583108 -365.20628) (xy 419.582599 -365.234166) (xy 419.574479 -365.289342)
			(xy 419.558411 -365.342749) (xy 419.534739 -365.393246) (xy 419.503966 -365.439759) (xy 419.466749 -365.481296)
			(xy 419.423881 -365.516971) (xy 419.376275 -365.546025) (xy 419.324946 -365.567837) (xy 419.270989 -365.581943)
			(xy 419.215552 -365.588043) (xy 419.159818 -365.586006) (xy 419.104975 -365.575876) (xy 419.052191 -365.557869)
			(xy 419.002591 -365.532368) (xy 418.957233 -365.499917) (xy 418.917084 -365.461208) (xy 418.882998 -365.417065)
			(xy 418.855702 -365.36843) (xy 418.835779 -365.316339) (xy 418.823653 -365.261902) (xy 418.819582 -365.20628)
			(xy 418.458909 -365.20628) (xy 418.459665 -365.211414) (xy 418.460174 -365.2393) (xy 418.459665 -365.267186)
			(xy 418.451545 -365.322362) (xy 418.435477 -365.375769) (xy 418.411805 -365.426266) (xy 418.381032 -365.472779)
			(xy 418.343815 -365.514316) (xy 418.300947 -365.549991) (xy 418.253341 -365.579045) (xy 418.202012 -365.600857)
			(xy 418.148055 -365.614963) (xy 418.092618 -365.621063) (xy 418.036884 -365.619026) (xy 417.982041 -365.608896)
			(xy 417.929257 -365.590889) (xy 417.879657 -365.565388) (xy 417.834299 -365.532937) (xy 417.79415 -365.494228)
			(xy 417.760064 -365.450085) (xy 417.732768 -365.40145) (xy 417.712845 -365.349359) (xy 417.700719 -365.294922)
			(xy 417.696648 -365.2393) (xy 415.471872 -365.2393) (xy 415.471004 -365.239669) (xy 415.417047 -365.253775)
			(xy 415.36161 -365.259875) (xy 415.305876 -365.257838) (xy 415.251033 -365.247708) (xy 415.198249 -365.229701)
			(xy 415.148649 -365.2042) (xy 415.103291 -365.171749) (xy 415.063142 -365.13304) (xy 415.029056 -365.088897)
			(xy 415.00176 -365.040262) (xy 414.981837 -364.988171) (xy 414.969711 -364.933734) (xy 414.96564 -364.878112)
			(xy 410.08173 -364.878112) (xy 410.08173 -365.962438) (xy 411.78302 -365.962438) (xy 411.787091 -365.906816)
			(xy 411.799217 -365.852379) (xy 411.81914 -365.800288) (xy 411.846436 -365.751653) (xy 411.880522 -365.70751)
			(xy 411.920671 -365.668801) (xy 411.966029 -365.63635) (xy 412.015629 -365.610849) (xy 412.068413 -365.592842)
			(xy 412.123256 -365.582712) (xy 412.17899 -365.580675) (xy 412.234427 -365.586775) (xy 412.288384 -365.600881)
			(xy 412.339713 -365.622693) (xy 412.387319 -365.651747) (xy 412.417899 -365.677196) (xy 416.787582 -365.677196)
			(xy 416.791653 -365.621574) (xy 416.803779 -365.567137) (xy 416.823702 -365.515046) (xy 416.850998 -365.466411)
			(xy 416.885084 -365.422268) (xy 416.925233 -365.383559) (xy 416.970591 -365.351108) (xy 417.020191 -365.325607)
			(xy 417.072975 -365.3076) (xy 417.127818 -365.29747) (xy 417.183552 -365.295433) (xy 417.238989 -365.301533)
			(xy 417.292946 -365.315639) (xy 417.344275 -365.337451) (xy 417.391881 -365.366505) (xy 417.434749 -365.40218)
			(xy 417.471966 -365.443717) (xy 417.502739 -365.49023) (xy 417.526411 -365.540727) (xy 417.542479 -365.594134)
			(xy 417.550599 -365.64931) (xy 417.551108 -365.677196) (xy 417.550599 -365.705082) (xy 417.542479 -365.760258)
			(xy 417.526411 -365.813665) (xy 417.502739 -365.864162) (xy 417.471966 -365.910675) (xy 417.434749 -365.952212)
			(xy 417.391881 -365.987887) (xy 417.344275 -366.016941) (xy 417.292946 -366.038753) (xy 417.238989 -366.052859)
			(xy 417.183552 -366.058959) (xy 417.127818 -366.056922) (xy 417.072975 -366.046792) (xy 417.020191 -366.028785)
			(xy 416.970591 -366.003284) (xy 416.925233 -365.970833) (xy 416.885084 -365.932124) (xy 416.850998 -365.887981)
			(xy 416.823702 -365.839346) (xy 416.803779 -365.787255) (xy 416.791653 -365.732818) (xy 416.787582 -365.677196)
			(xy 412.417899 -365.677196) (xy 412.430187 -365.687422) (xy 412.467404 -365.728959) (xy 412.498177 -365.775472)
			(xy 412.521849 -365.825969) (xy 412.537917 -365.879376) (xy 412.546037 -365.934552) (xy 412.546546 -365.962438)
			(xy 412.546037 -365.990324) (xy 412.537917 -366.0455) (xy 412.521849 -366.098907) (xy 412.498177 -366.149404)
			(xy 412.467404 -366.195917) (xy 412.430187 -366.237454) (xy 412.387319 -366.273129) (xy 412.339713 -366.302183)
			(xy 412.288384 -366.323995) (xy 412.234427 -366.338101) (xy 412.17899 -366.344201) (xy 412.123256 -366.342164)
			(xy 412.068413 -366.332034) (xy 412.015629 -366.314027) (xy 411.966029 -366.288526) (xy 411.920671 -366.256075)
			(xy 411.880522 -366.217366) (xy 411.846436 -366.173223) (xy 411.81914 -366.124588) (xy 411.799217 -366.072497)
			(xy 411.787091 -366.01806) (xy 411.78302 -365.962438) (xy 410.08173 -365.962438) (xy 410.08173 -366.169956)
			(xy 410.082141 -366.179566) (xy 410.089187 -366.19745) (xy 410.095446 -366.204754) (xy 410.149548 -366.262666)
			(xy 410.166566 -366.270794) (xy 410.176472 -366.271302) (xy 410.205075 -366.273743) (xy 410.261128 -366.286131)
			(xy 410.314691 -366.306777) (xy 410.364556 -366.335217) (xy 410.409597 -366.370807) (xy 410.448796 -366.412744)
			(xy 410.481269 -366.460082) (xy 410.506281 -366.511751) (xy 410.523269 -366.566585) (xy 410.531849 -366.623345)
			(xy 410.532326 -366.652048) (xy 410.531816 -366.67991) (xy 410.523707 -366.735041) (xy 410.510175 -366.780064)
			(xy 412.411162 -366.780064) (xy 412.415233 -366.724442) (xy 412.427359 -366.670005) (xy 412.447282 -366.617914)
			(xy 412.474578 -366.569279) (xy 412.508664 -366.525136) (xy 412.548813 -366.486427) (xy 412.594171 -366.453976)
			(xy 412.643771 -366.428475) (xy 412.696555 -366.410468) (xy 412.751398 -366.400338) (xy 412.807132 -366.398301)
			(xy 412.862569 -366.404401) (xy 412.916526 -366.418507) (xy 412.967855 -366.440319) (xy 413.015461 -366.469373)
			(xy 413.058329 -366.505048) (xy 413.095546 -366.546585) (xy 413.126319 -366.593098) (xy 413.149991 -366.643595)
			(xy 413.166059 -366.697002) (xy 413.174179 -366.752178) (xy 413.174688 -366.780064) (xy 413.174179 -366.80795)
			(xy 413.167256 -366.854994) (xy 423.83532 -366.854994) (xy 423.839391 -366.799372) (xy 423.851517 -366.744935)
			(xy 423.87144 -366.692844) (xy 423.898736 -366.644209) (xy 423.932822 -366.600066) (xy 423.972971 -366.561357)
			(xy 424.018329 -366.528906) (xy 424.067929 -366.503405) (xy 424.120713 -366.485398) (xy 424.175556 -366.475268)
			(xy 424.23129 -366.473231) (xy 424.286727 -366.479331) (xy 424.340684 -366.493437) (xy 424.392013 -366.515249)
			(xy 424.434289 -366.54105) (xy 427.288196 -366.54105) (xy 427.292267 -366.485428) (xy 427.304393 -366.430991)
			(xy 427.324316 -366.3789) (xy 427.351612 -366.330265) (xy 427.385698 -366.286122) (xy 427.425847 -366.247413)
			(xy 427.471205 -366.214962) (xy 427.520805 -366.189461) (xy 427.573589 -366.171454) (xy 427.628432 -366.161324)
			(xy 427.684166 -366.159287) (xy 427.739603 -366.165387) (xy 427.79356 -366.179493) (xy 427.844889 -366.201305)
			(xy 427.892495 -366.230359) (xy 427.935363 -366.266034) (xy 427.97258 -366.307571) (xy 428.003353 -366.354084)
			(xy 428.027025 -366.404581) (xy 428.043093 -366.457988) (xy 428.051213 -366.513164) (xy 428.051722 -366.54105)
			(xy 428.051213 -366.568936) (xy 428.043093 -366.624112) (xy 428.027025 -366.677519) (xy 428.003353 -366.728016)
			(xy 427.97258 -366.774529) (xy 427.935363 -366.816066) (xy 427.892495 -366.851741) (xy 427.844889 -366.880795)
			(xy 427.79356 -366.902607) (xy 427.739603 -366.916713) (xy 427.684166 -366.922813) (xy 427.628432 -366.920776)
			(xy 427.573589 -366.910646) (xy 427.520805 -366.892639) (xy 427.471205 -366.867138) (xy 427.425847 -366.834687)
			(xy 427.385698 -366.795978) (xy 427.351612 -366.751835) (xy 427.324316 -366.7032) (xy 427.304393 -366.651109)
			(xy 427.292267 -366.596672) (xy 427.288196 -366.54105) (xy 424.434289 -366.54105) (xy 424.439619 -366.544303)
			(xy 424.482487 -366.579978) (xy 424.519704 -366.621515) (xy 424.550477 -366.668028) (xy 424.574149 -366.718525)
			(xy 424.590217 -366.771932) (xy 424.598337 -366.827108) (xy 424.598846 -366.854994) (xy 424.598337 -366.88288)
			(xy 424.590217 -366.938056) (xy 424.574149 -366.991463) (xy 424.550477 -367.04196) (xy 424.519704 -367.088473)
			(xy 424.482487 -367.13001) (xy 424.439619 -367.165685) (xy 424.392013 -367.194739) (xy 424.340684 -367.216551)
			(xy 424.286727 -367.230657) (xy 424.23129 -367.236757) (xy 424.175556 -367.23472) (xy 424.120713 -367.22459)
			(xy 424.067929 -367.206583) (xy 424.018329 -367.181082) (xy 423.972971 -367.148631) (xy 423.932822 -367.109922)
			(xy 423.898736 -367.065779) (xy 423.87144 -367.017144) (xy 423.851517 -366.965053) (xy 423.839391 -366.910616)
			(xy 423.83532 -366.854994) (xy 413.167256 -366.854994) (xy 413.166059 -366.863126) (xy 413.149991 -366.916533)
			(xy 413.126319 -366.96703) (xy 413.095546 -367.013543) (xy 413.058329 -367.05508) (xy 413.015461 -367.090755)
			(xy 412.967855 -367.119809) (xy 412.916526 -367.141621) (xy 412.862569 -367.155727) (xy 412.807132 -367.161827)
			(xy 412.751398 -367.15979) (xy 412.696555 -367.14966) (xy 412.643771 -367.131653) (xy 412.594171 -367.106152)
			(xy 412.548813 -367.073701) (xy 412.508664 -367.034992) (xy 412.474578 -366.990849) (xy 412.447282 -366.942214)
			(xy 412.427359 -366.890123) (xy 412.415233 -366.835686) (xy 412.411162 -366.780064) (xy 410.510175 -366.780064)
			(xy 410.507668 -366.788407) (xy 410.484041 -366.838874) (xy 410.453326 -366.88537) (xy 410.416178 -366.926905)
			(xy 410.373386 -366.962598) (xy 410.325858 -366.99169) (xy 410.300424 -367.003076) (xy 410.2862 -367.008918)
			(xy 410.26969 -367.034572) (xy 410.270198 -367.143538) (xy 410.270733 -367.153491) (xy 410.278394 -367.171871)
			(xy 410.292445 -367.185982) (xy 410.30144 -367.190274) (xy 410.985149 -367.473484) (xy 415.2044 -367.473484)
			(xy 415.208471 -367.417862) (xy 415.220597 -367.363425) (xy 415.24052 -367.311334) (xy 415.267816 -367.262699)
			(xy 415.301902 -367.218556) (xy 415.342051 -367.179847) (xy 415.387409 -367.147396) (xy 415.437009 -367.121895)
			(xy 415.489793 -367.103888) (xy 415.544636 -367.093758) (xy 415.60037 -367.091721) (xy 415.655807 -367.097821)
			(xy 415.709764 -367.111927) (xy 415.761093 -367.133739) (xy 415.808699 -367.162793) (xy 415.851567 -367.198468)
			(xy 415.888784 -367.240005) (xy 415.919557 -367.286518) (xy 415.943229 -367.337015) (xy 415.959297 -367.390422)
			(xy 415.967417 -367.445598) (xy 415.967926 -367.473484) (xy 416.4744 -367.473484) (xy 416.478471 -367.417862)
			(xy 416.490597 -367.363425) (xy 416.51052 -367.311334) (xy 416.537816 -367.262699) (xy 416.571902 -367.218556)
			(xy 416.612051 -367.179847) (xy 416.657409 -367.147396) (xy 416.707009 -367.121895) (xy 416.759793 -367.103888)
			(xy 416.814636 -367.093758) (xy 416.87037 -367.091721) (xy 416.925807 -367.097821) (xy 416.979764 -367.111927)
			(xy 417.031093 -367.133739) (xy 417.078699 -367.162793) (xy 417.121567 -367.198468) (xy 417.158784 -367.240005)
			(xy 417.189557 -367.286518) (xy 417.213229 -367.337015) (xy 417.229297 -367.390422) (xy 417.237417 -367.445598)
			(xy 417.237773 -367.465102) (xy 418.560502 -367.465102) (xy 418.564573 -367.40948) (xy 418.576699 -367.355043)
			(xy 418.596622 -367.302952) (xy 418.623918 -367.254317) (xy 418.658004 -367.210174) (xy 418.698153 -367.171465)
			(xy 418.743511 -367.139014) (xy 418.793111 -367.113513) (xy 418.845895 -367.095506) (xy 418.900738 -367.085376)
			(xy 418.956472 -367.083339) (xy 419.011909 -367.089439) (xy 419.065866 -367.103545) (xy 419.117195 -367.125357)
			(xy 419.164801 -367.154411) (xy 419.207669 -367.190086) (xy 419.244886 -367.231623) (xy 419.275659 -367.278136)
			(xy 419.299331 -367.328633) (xy 419.315399 -367.38204) (xy 419.323519 -367.437216) (xy 419.324028 -367.465102)
			(xy 419.323519 -367.492988) (xy 419.315399 -367.548164) (xy 419.299331 -367.601571) (xy 419.275659 -367.652068)
			(xy 419.244886 -367.698581) (xy 419.207669 -367.740118) (xy 419.164801 -367.775793) (xy 419.117195 -367.804847)
			(xy 419.065866 -367.826659) (xy 419.011909 -367.840765) (xy 418.956472 -367.846865) (xy 418.900738 -367.844828)
			(xy 418.845895 -367.834698) (xy 418.793111 -367.816691) (xy 418.743511 -367.79119) (xy 418.698153 -367.758739)
			(xy 418.658004 -367.72003) (xy 418.623918 -367.675887) (xy 418.596622 -367.627252) (xy 418.576699 -367.575161)
			(xy 418.564573 -367.520724) (xy 418.560502 -367.465102) (xy 417.237773 -367.465102) (xy 417.237926 -367.473484)
			(xy 417.237417 -367.50137) (xy 417.229297 -367.556546) (xy 417.213229 -367.609953) (xy 417.189557 -367.66045)
			(xy 417.158784 -367.706963) (xy 417.121567 -367.7485) (xy 417.078699 -367.784175) (xy 417.031093 -367.813229)
			(xy 416.979764 -367.835041) (xy 416.925807 -367.849147) (xy 416.87037 -367.855247) (xy 416.814636 -367.85321)
			(xy 416.759793 -367.84308) (xy 416.707009 -367.825073) (xy 416.657409 -367.799572) (xy 416.612051 -367.767121)
			(xy 416.571902 -367.728412) (xy 416.537816 -367.684269) (xy 416.51052 -367.635634) (xy 416.490597 -367.583543)
			(xy 416.478471 -367.529106) (xy 416.4744 -367.473484) (xy 415.967926 -367.473484) (xy 415.967417 -367.50137)
			(xy 415.959297 -367.556546) (xy 415.943229 -367.609953) (xy 415.919557 -367.66045) (xy 415.888784 -367.706963)
			(xy 415.851567 -367.7485) (xy 415.808699 -367.784175) (xy 415.761093 -367.813229) (xy 415.709764 -367.835041)
			(xy 415.655807 -367.849147) (xy 415.60037 -367.855247) (xy 415.544636 -367.85321) (xy 415.489793 -367.84308)
			(xy 415.437009 -367.825073) (xy 415.387409 -367.799572) (xy 415.342051 -367.767121) (xy 415.301902 -367.728412)
			(xy 415.267816 -367.684269) (xy 415.24052 -367.635634) (xy 415.220597 -367.583543) (xy 415.208471 -367.529106)
			(xy 415.2044 -367.473484) (xy 410.985149 -367.473484) (xy 412.85845 -368.249454) (xy 431.997356 -368.249454)
			(xy 432.001427 -368.193832) (xy 432.013553 -368.139395) (xy 432.033476 -368.087304) (xy 432.060772 -368.038669)
			(xy 432.094858 -367.994526) (xy 432.135007 -367.955817) (xy 432.180365 -367.923366) (xy 432.229965 -367.897865)
			(xy 432.282749 -367.879858) (xy 432.337592 -367.869728) (xy 432.393326 -367.867691) (xy 432.448763 -367.873791)
			(xy 432.50272 -367.887897) (xy 432.554049 -367.909709) (xy 432.601655 -367.938763) (xy 432.644523 -367.974438)
			(xy 432.68174 -368.015975) (xy 432.712513 -368.062488) (xy 432.736185 -368.112985) (xy 432.752253 -368.166392)
			(xy 432.760373 -368.221568) (xy 432.760882 -368.249454) (xy 432.760373 -368.27734) (xy 432.752253 -368.332516)
			(xy 432.736185 -368.385923) (xy 432.712513 -368.43642) (xy 432.68174 -368.482933) (xy 432.644523 -368.52447)
			(xy 432.601655 -368.560145) (xy 432.554049 -368.589199) (xy 432.50272 -368.611011) (xy 432.448763 -368.625117)
			(xy 432.393326 -368.631217) (xy 432.337592 -368.62918) (xy 432.282749 -368.61905) (xy 432.229965 -368.601043)
			(xy 432.180365 -368.575542) (xy 432.135007 -368.543091) (xy 432.094858 -368.504382) (xy 432.060772 -368.460239)
			(xy 432.033476 -368.411604) (xy 432.013553 -368.359513) (xy 432.001427 -368.305076) (xy 431.997356 -368.249454)
			(xy 412.85845 -368.249454) (xy 413.913753 -368.686588) (xy 426.728634 -368.686588) (xy 426.732705 -368.630966)
			(xy 426.744831 -368.576529) (xy 426.764754 -368.524438) (xy 426.79205 -368.475803) (xy 426.826136 -368.43166)
			(xy 426.866285 -368.392951) (xy 426.911643 -368.3605) (xy 426.961243 -368.334999) (xy 427.014027 -368.316992)
			(xy 427.06887 -368.306862) (xy 427.124604 -368.304825) (xy 427.180041 -368.310925) (xy 427.233998 -368.325031)
			(xy 427.285327 -368.346843) (xy 427.332933 -368.375897) (xy 427.375801 -368.411572) (xy 427.413018 -368.453109)
			(xy 427.443791 -368.499622) (xy 427.467463 -368.550119) (xy 427.483531 -368.603526) (xy 427.491651 -368.658702)
			(xy 427.492039 -368.679984) (xy 428.63973 -368.679984) (xy 428.643801 -368.624362) (xy 428.655927 -368.569925)
			(xy 428.67585 -368.517834) (xy 428.703146 -368.469199) (xy 428.737232 -368.425056) (xy 428.777381 -368.386347)
			(xy 428.822739 -368.353896) (xy 428.872339 -368.328395) (xy 428.925123 -368.310388) (xy 428.979966 -368.300258)
			(xy 429.0357 -368.298221) (xy 429.091137 -368.304321) (xy 429.145094 -368.318427) (xy 429.196423 -368.340239)
			(xy 429.244029 -368.369293) (xy 429.286897 -368.404968) (xy 429.324114 -368.446505) (xy 429.354887 -368.493018)
			(xy 429.378559 -368.543515) (xy 429.394627 -368.596922) (xy 429.402747 -368.652098) (xy 429.403256 -368.679984)
			(xy 429.402747 -368.70787) (xy 429.396459 -368.750596) (xy 432.715414 -368.750596) (xy 432.719485 -368.694974)
			(xy 432.731611 -368.640537) (xy 432.751534 -368.588446) (xy 432.77883 -368.539811) (xy 432.812916 -368.495668)
			(xy 432.853065 -368.456959) (xy 432.898423 -368.424508) (xy 432.948023 -368.399007) (xy 433.000807 -368.381)
			(xy 433.05565 -368.37087) (xy 433.111384 -368.368833) (xy 433.166821 -368.374933) (xy 433.220778 -368.389039)
			(xy 433.272107 -368.410851) (xy 433.319713 -368.439905) (xy 433.362581 -368.47558) (xy 433.399798 -368.517117)
			(xy 433.430571 -368.56363) (xy 433.454243 -368.614127) (xy 433.470311 -368.667534) (xy 433.478431 -368.72271)
			(xy 433.47894 -368.750596) (xy 433.478431 -368.778482) (xy 433.470311 -368.833658) (xy 433.454243 -368.887065)
			(xy 433.430571 -368.937562) (xy 433.399798 -368.984075) (xy 433.362581 -369.025612) (xy 433.319713 -369.061287)
			(xy 433.272107 -369.090341) (xy 433.220778 -369.112153) (xy 433.166821 -369.126259) (xy 433.111384 -369.132359)
			(xy 433.05565 -369.130322) (xy 433.000807 -369.120192) (xy 432.948023 -369.102185) (xy 432.898423 -369.076684)
			(xy 432.853065 -369.044233) (xy 432.812916 -369.005524) (xy 432.77883 -368.961381) (xy 432.751534 -368.912746)
			(xy 432.731611 -368.860655) (xy 432.719485 -368.806218) (xy 432.715414 -368.750596) (xy 429.396459 -368.750596)
			(xy 429.394627 -368.763046) (xy 429.378559 -368.816453) (xy 429.354887 -368.86695) (xy 429.324114 -368.913463)
			(xy 429.286897 -368.955) (xy 429.244029 -368.990675) (xy 429.196423 -369.019729) (xy 429.145094 -369.041541)
			(xy 429.091137 -369.055647) (xy 429.0357 -369.061747) (xy 428.979966 -369.05971) (xy 428.925123 -369.04958)
			(xy 428.872339 -369.031573) (xy 428.822739 -369.006072) (xy 428.777381 -368.973621) (xy 428.737232 -368.934912)
			(xy 428.703146 -368.890769) (xy 428.67585 -368.842134) (xy 428.655927 -368.790043) (xy 428.643801 -368.735606)
			(xy 428.63973 -368.679984) (xy 427.492039 -368.679984) (xy 427.49216 -368.686588) (xy 427.491651 -368.714474)
			(xy 427.483531 -368.76965) (xy 427.467463 -368.823057) (xy 427.443791 -368.873554) (xy 427.413018 -368.920067)
			(xy 427.375801 -368.961604) (xy 427.332933 -368.997279) (xy 427.285327 -369.026333) (xy 427.233998 -369.048145)
			(xy 427.180041 -369.062251) (xy 427.124604 -369.068351) (xy 427.06887 -369.066314) (xy 427.014027 -369.056184)
			(xy 426.961243 -369.038177) (xy 426.911643 -369.012676) (xy 426.866285 -368.980225) (xy 426.826136 -368.941516)
			(xy 426.79205 -368.897373) (xy 426.764754 -368.848738) (xy 426.744831 -368.796647) (xy 426.732705 -368.74221)
			(xy 426.728634 -368.686588) (xy 413.913753 -368.686588) (xy 418.453824 -370.567204) (xy 418.458511 -370.569)
			(xy 418.468363 -370.570913) (xy 418.473382 -370.571014)
		)
		(stroke
			(width 0)
			(type solid)
		)
		(fill yes)
		(layer "In13.Cu")
		(net "GND")
	)
	(gr_poly
		(pts
			(xy 195.87972 -366.431576) (xy 195.889788 -366.431149) (xy 195.908385 -366.423426) (xy 195.915788 -366.41659)
			(xy 205.277466 -357.054912) (xy 205.284318 -357.047516) (xy 205.292062 -357.028917) (xy 205.292452 -357.018844)
			(xy 205.292452 -349.720154) (xy 205.292885 -349.710089) (xy 205.300617 -349.691501) (xy 205.307438 -349.684086)
			(xy 206.591408 -348.400116) (xy 206.59824 -348.392712) (xy 206.605943 -348.374114) (xy 206.606394 -348.364048)
			(xy 206.606394 -344.66022) (xy 206.605965 -344.650538) (xy 206.598811 -344.632543) (xy 206.585537 -344.618442)
			(xy 206.57693 -344.613992) (xy 206.492856 -344.575638) (xy 206.483925 -344.571948) (xy 206.464648 -344.570876)
			(xy 206.446349 -344.577034) (xy 206.438754 -344.583004) (xy 206.4385 -344.583258) (xy 206.417638 -344.600557)
			(xy 206.371951 -344.629703) (xy 206.3226 -344.652093) (xy 206.270578 -344.667277) (xy 206.21693 -344.674948)
			(xy 206.189834 -344.67546) (xy 206.162583 -344.674999) (xy 206.108635 -344.667247) (xy 206.05634 -344.651896)
			(xy 206.006762 -344.629258) (xy 205.96091 -344.599795) (xy 205.919718 -344.564106) (xy 205.884026 -344.522917)
			(xy 205.854558 -344.477068) (xy 205.831916 -344.427492) (xy 205.81656 -344.375198) (xy 205.808803 -344.321251)
			(xy 205.808803 -344.266749) (xy 205.81656 -344.212802) (xy 205.831916 -344.160508) (xy 205.854558 -344.110932)
			(xy 205.884026 -344.065083) (xy 205.919718 -344.023894) (xy 205.96091 -343.988205) (xy 206.006762 -343.958742)
			(xy 206.05634 -343.936104) (xy 206.108635 -343.920753) (xy 206.162583 -343.913001) (xy 206.189834 -343.912444)
			(xy 206.216934 -343.912915) (xy 206.270588 -343.92058) (xy 206.322617 -343.935763) (xy 206.371972 -343.95816)
			(xy 206.417658 -343.98732) (xy 206.4385 -344.004646) (xy 206.438754 -344.0049) (xy 206.44638 -344.010823)
			(xy 206.464665 -344.016985) (xy 206.483932 -344.015951) (xy 206.492856 -344.012266) (xy 206.57693 -343.973912)
			(xy 206.585548 -343.969469) (xy 206.59886 -343.955395) (xy 206.605968 -343.937373) (xy 206.606394 -343.927684)
			(xy 206.606394 -331.48778) (xy 206.605967 -331.477712) (xy 206.598247 -331.459113) (xy 206.591408 -331.451712)
			(xy 206.489808 -331.350112) (xy 206.482411 -331.343263) (xy 206.463813 -331.335524) (xy 206.45374 -331.335126)
			(xy 206.001874 -331.335126) (xy 206.00162 -331.334872) (xy 205.998771 -331.332164) (xy 205.992395 -331.327565)
			(xy 205.98892 -331.325728) (xy 205.983493 -331.323148) (xy 205.971813 -331.320331) (xy 205.965806 -331.32014)
			(xy 197.871334 -331.32014) (xy 197.86127 -331.320576) (xy 197.842687 -331.328312) (xy 197.835266 -331.335126)
			(xy 196.925438 -332.244954) (xy 196.918596 -332.252354) (xy 196.910875 -332.270952) (xy 196.910452 -332.281022)
			(xy 196.910452 -338.879942) (xy 198.275192 -338.879942) (xy 198.279263 -338.82432) (xy 198.291389 -338.769883)
			(xy 198.311312 -338.717792) (xy 198.338608 -338.669157) (xy 198.372694 -338.625014) (xy 198.412843 -338.586305)
			(xy 198.458201 -338.553854) (xy 198.507801 -338.528353) (xy 198.560585 -338.510346) (xy 198.615428 -338.500216)
			(xy 198.671162 -338.498179) (xy 198.726599 -338.504279) (xy 198.780556 -338.518385) (xy 198.831885 -338.540197)
			(xy 198.879491 -338.569251) (xy 198.922359 -338.604926) (xy 198.959576 -338.646463) (xy 198.990349 -338.692976)
			(xy 199.014021 -338.743473) (xy 199.030089 -338.79688) (xy 199.038209 -338.852056) (xy 199.038718 -338.879942)
			(xy 199.038209 -338.907828) (xy 199.030089 -338.963004) (xy 199.014021 -339.016411) (xy 198.990349 -339.066908)
			(xy 198.959576 -339.113421) (xy 198.922359 -339.154958) (xy 198.879491 -339.190633) (xy 198.831885 -339.219687)
			(xy 198.780556 -339.241499) (xy 198.726599 -339.255605) (xy 198.671162 -339.261705) (xy 198.615428 -339.259668)
			(xy 198.560585 -339.249538) (xy 198.507801 -339.231531) (xy 198.458201 -339.20603) (xy 198.412843 -339.173579)
			(xy 198.372694 -339.13487) (xy 198.338608 -339.090727) (xy 198.311312 -339.042092) (xy 198.291389 -338.990001)
			(xy 198.279263 -338.935564) (xy 198.275192 -338.879942) (xy 196.910452 -338.879942) (xy 196.910452 -340.121748)
			(xy 203.227938 -340.121748) (xy 203.232009 -340.066126) (xy 203.244135 -340.011689) (xy 203.264058 -339.959598)
			(xy 203.291354 -339.910963) (xy 203.32544 -339.86682) (xy 203.365589 -339.828111) (xy 203.410947 -339.79566)
			(xy 203.460547 -339.770159) (xy 203.513331 -339.752152) (xy 203.568174 -339.742022) (xy 203.623908 -339.739985)
			(xy 203.679345 -339.746085) (xy 203.733302 -339.760191) (xy 203.784631 -339.782003) (xy 203.832237 -339.811057)
			(xy 203.875105 -339.846732) (xy 203.912322 -339.888269) (xy 203.943095 -339.934782) (xy 203.966767 -339.985279)
			(xy 203.982835 -340.038686) (xy 203.990955 -340.093862) (xy 203.991464 -340.121748) (xy 203.990955 -340.149634)
			(xy 203.982835 -340.20481) (xy 203.966767 -340.258217) (xy 203.943095 -340.308714) (xy 203.912322 -340.355227)
			(xy 203.875105 -340.396764) (xy 203.832237 -340.432439) (xy 203.784631 -340.461493) (xy 203.733302 -340.483305)
			(xy 203.679345 -340.497411) (xy 203.623908 -340.503511) (xy 203.568174 -340.501474) (xy 203.513331 -340.491344)
			(xy 203.460547 -340.473337) (xy 203.410947 -340.447836) (xy 203.365589 -340.415385) (xy 203.32544 -340.376676)
			(xy 203.291354 -340.332533) (xy 203.264058 -340.283898) (xy 203.244135 -340.231807) (xy 203.232009 -340.17737)
			(xy 203.227938 -340.121748) (xy 196.910452 -340.121748) (xy 196.910452 -341.346282) (xy 196.910012 -341.356344)
			(xy 196.902272 -341.374923) (xy 196.895466 -341.38235) (xy 195.761102 -342.516714) (xy 195.753708 -342.52357)
			(xy 195.735109 -342.531319) (xy 195.725034 -342.5317) (xy 160.52419 -342.5317) (xy 160.514764 -342.532081)
			(xy 160.497191 -342.538907) (xy 160.483281 -342.551632) (xy 160.478724 -342.559894) (xy 160.438338 -342.641682)
			(xy 160.434462 -342.650363) (xy 160.432805 -342.669289) (xy 160.438184 -342.68751) (xy 160.443672 -342.695276)
			(xy 160.458589 -342.715342) (xy 160.483606 -342.758635) (xy 160.502758 -342.804822) (xy 160.515715 -342.853115)
			(xy 160.522258 -342.902686) (xy 160.522579 -342.922352) (xy 202.582016 -342.922352) (xy 202.586087 -342.86673)
			(xy 202.598213 -342.812293) (xy 202.618136 -342.760202) (xy 202.645432 -342.711567) (xy 202.679518 -342.667424)
			(xy 202.719667 -342.628715) (xy 202.765025 -342.596264) (xy 202.814625 -342.570763) (xy 202.867409 -342.552756)
			(xy 202.922252 -342.542626) (xy 202.977986 -342.540589) (xy 203.033423 -342.546689) (xy 203.08738 -342.560795)
			(xy 203.138709 -342.582607) (xy 203.186315 -342.611661) (xy 203.229183 -342.647336) (xy 203.2664 -342.688873)
			(xy 203.297173 -342.735386) (xy 203.320845 -342.785883) (xy 203.336913 -342.83929) (xy 203.345033 -342.894466)
			(xy 203.345542 -342.922352) (xy 203.345033 -342.950238) (xy 203.336913 -343.005414) (xy 203.320845 -343.058821)
			(xy 203.297173 -343.109318) (xy 203.2664 -343.155831) (xy 203.229183 -343.197368) (xy 203.186315 -343.233043)
			(xy 203.138709 -343.262097) (xy 203.08738 -343.283909) (xy 203.033423 -343.298015) (xy 202.977986 -343.304115)
			(xy 202.922252 -343.302078) (xy 202.867409 -343.291948) (xy 202.814625 -343.273941) (xy 202.765025 -343.24844)
			(xy 202.719667 -343.215989) (xy 202.679518 -343.17728) (xy 202.645432 -343.133137) (xy 202.618136 -343.084502)
			(xy 202.598213 -343.032411) (xy 202.586087 -342.977974) (xy 202.582016 -342.922352) (xy 160.522579 -342.922352)
			(xy 160.522666 -342.927686) (xy 160.522133 -342.956603) (xy 160.513407 -343.013774) (xy 160.496154 -343.068974)
			(xy 160.470767 -343.120938) (xy 160.437829 -343.168476) (xy 160.398095 -343.210499) (xy 160.3756 -343.228676)
			(xy 160.36677 -343.236266) (xy 160.356585 -343.257176) (xy 160.356042 -343.268808) (xy 160.356042 -343.348564)
			(xy 160.356613 -343.360186) (xy 160.366801 -343.381081) (xy 160.3756 -343.388696) (xy 160.398082 -343.406887)
			(xy 160.437816 -343.448906) (xy 160.470752 -343.496441) (xy 160.496134 -343.548403) (xy 160.513382 -343.603601)
			(xy 160.522099 -343.660771) (xy 160.522666 -343.689686) (xy 160.52218 -343.716937) (xy 160.514424 -343.770885)
			(xy 160.499069 -343.82318) (xy 160.486954 -343.849706) (xy 160.851086 -343.849706) (xy 160.855157 -343.794084)
			(xy 160.867283 -343.739647) (xy 160.887206 -343.687556) (xy 160.914502 -343.638921) (xy 160.948588 -343.594778)
			(xy 160.988737 -343.556069) (xy 161.034095 -343.523618) (xy 161.083695 -343.498117) (xy 161.136479 -343.48011)
			(xy 161.191322 -343.46998) (xy 161.247056 -343.467943) (xy 161.302493 -343.474043) (xy 161.35645 -343.488149)
			(xy 161.407779 -343.509961) (xy 161.455385 -343.539015) (xy 161.498253 -343.57469) (xy 161.53547 -343.616227)
			(xy 161.566243 -343.66274) (xy 161.589915 -343.713237) (xy 161.605983 -343.766644) (xy 161.614103 -343.82182)
			(xy 161.614612 -343.849706) (xy 161.614103 -343.877592) (xy 161.605983 -343.932768) (xy 161.589915 -343.986175)
			(xy 161.566243 -344.036672) (xy 161.53547 -344.083185) (xy 161.498253 -344.124722) (xy 161.455385 -344.160397)
			(xy 161.407779 -344.189451) (xy 161.35645 -344.211263) (xy 161.302493 -344.225369) (xy 161.247056 -344.231469)
			(xy 161.191322 -344.229432) (xy 161.136479 -344.219302) (xy 161.083695 -344.201295) (xy 161.034095 -344.175794)
			(xy 160.988737 -344.143343) (xy 160.948588 -344.104634) (xy 160.914502 -344.060491) (xy 160.887206 -344.011856)
			(xy 160.867283 -343.959765) (xy 160.855157 -343.905328) (xy 160.851086 -343.849706) (xy 160.486954 -343.849706)
			(xy 160.476427 -343.872757) (xy 160.446961 -343.918607) (xy 160.41127 -343.959798) (xy 160.370079 -343.995489)
			(xy 160.324229 -344.024955) (xy 160.274652 -344.047597) (xy 160.222357 -344.062952) (xy 160.168409 -344.070708)
			(xy 160.113907 -344.070708) (xy 160.059959 -344.062952) (xy 160.007664 -344.047597) (xy 159.958087 -344.024955)
			(xy 159.912237 -343.995489) (xy 159.871046 -343.959798) (xy 159.835355 -343.918607) (xy 159.805889 -343.872757)
			(xy 159.783247 -343.82318) (xy 159.767892 -343.770885) (xy 159.760136 -343.716937) (xy 159.75965 -343.689686)
			(xy 159.760185 -343.66077) (xy 159.768915 -343.603601) (xy 159.786172 -343.548405) (xy 159.811561 -343.496445)
			(xy 159.844502 -343.448911) (xy 159.884238 -343.406893) (xy 159.906716 -343.388696) (xy 159.915556 -343.38111)
			(xy 159.925767 -343.3602) (xy 159.926274 -343.348564) (xy 159.926274 -343.268808) (xy 159.925698 -343.257188)
			(xy 159.915505 -343.236301) (xy 159.906716 -343.228676) (xy 159.884229 -343.210487) (xy 159.844485 -343.168471)
			(xy 159.811539 -343.120938) (xy 159.786146 -343.068976) (xy 159.768888 -343.013776) (xy 159.760159 -342.956603)
			(xy 159.75965 -342.927686) (xy 159.760038 -342.902683) (xy 159.766564 -342.853105) (xy 159.779516 -342.804806)
			(xy 159.79867 -342.758615) (xy 159.8237 -342.715324) (xy 159.838644 -342.695276) (xy 159.844133 -342.687518)
			(xy 159.849471 -342.669291) (xy 159.84783 -342.65037) (xy 159.843978 -342.641682) (xy 159.803592 -342.559894)
			(xy 159.799004 -342.551666) (xy 159.785088 -342.538991) (xy 159.767537 -342.532192) (xy 159.758126 -342.5317)
			(xy 155.923742 -342.5317) (xy 155.917733 -342.531868) (xy 155.906051 -342.534694) (xy 155.900628 -342.537288)
			(xy 155.897152 -342.539125) (xy 155.890768 -342.543713) (xy 155.887928 -342.546432) (xy 154.865832 -343.568528)
			(xy 154.863128 -343.57138) (xy 154.858538 -343.57776) (xy 154.856688 -343.581228) (xy 154.854104 -343.586655)
			(xy 154.851277 -343.598334) (xy 154.8511 -343.604342) (xy 154.8511 -345.078304) (xy 160.503106 -345.078304)
			(xy 160.507177 -345.022682) (xy 160.519303 -344.968245) (xy 160.539226 -344.916154) (xy 160.566522 -344.867519)
			(xy 160.600608 -344.823376) (xy 160.640757 -344.784667) (xy 160.686115 -344.752216) (xy 160.735715 -344.726715)
			(xy 160.788499 -344.708708) (xy 160.843342 -344.698578) (xy 160.899076 -344.696541) (xy 160.954513 -344.702641)
			(xy 161.00847 -344.716747) (xy 161.059799 -344.738559) (xy 161.107405 -344.767613) (xy 161.150273 -344.803288)
			(xy 161.174565 -344.8304) (xy 201.363834 -344.8304) (xy 201.36434 -344.801482) (xy 201.373069 -344.74431)
			(xy 201.390329 -344.68911) (xy 201.415723 -344.637149) (xy 201.448669 -344.589615) (xy 201.488413 -344.547599)
			(xy 201.5109 -344.52941) (xy 201.519693 -344.521789) (xy 201.529884 -344.500899) (xy 201.530458 -344.489278)
			(xy 201.530458 -344.409522) (xy 201.529906 -344.397891) (xy 201.519728 -344.376981) (xy 201.5109 -344.36939)
			(xy 201.488412 -344.351205) (xy 201.448677 -344.309184) (xy 201.415738 -344.261648) (xy 201.390351 -344.209685)
			(xy 201.373096 -344.154487) (xy 201.364368 -344.097316) (xy 201.363834 -344.0684) (xy 201.36432 -344.041149)
			(xy 201.372076 -343.987201) (xy 201.387431 -343.934906) (xy 201.410073 -343.885329) (xy 201.439539 -343.839479)
			(xy 201.47523 -343.798288) (xy 201.516421 -343.762597) (xy 201.562271 -343.733131) (xy 201.611848 -343.710489)
			(xy 201.664143 -343.695134) (xy 201.718091 -343.687378) (xy 201.772593 -343.687378) (xy 201.826541 -343.695134)
			(xy 201.878836 -343.710489) (xy 201.928413 -343.733131) (xy 201.974263 -343.762597) (xy 202.015454 -343.798288)
			(xy 202.051145 -343.839479) (xy 202.080611 -343.885329) (xy 202.103253 -343.934906) (xy 202.118608 -343.987201)
			(xy 202.126364 -344.041149) (xy 202.12685 -344.0684) (xy 202.126351 -344.097318) (xy 202.11762 -344.154491)
			(xy 202.10036 -344.209691) (xy 202.074965 -344.261653) (xy 202.042017 -344.309186) (xy 202.002272 -344.351201)
			(xy 201.979784 -344.36939) (xy 201.970988 -344.377008) (xy 201.960799 -344.397901) (xy 201.960226 -344.409522)
			(xy 201.960226 -344.489278) (xy 201.960783 -344.500908) (xy 201.970958 -344.521818) (xy 201.979784 -344.52941)
			(xy 202.002269 -344.547599) (xy 202.042005 -344.589619) (xy 202.074944 -344.637154) (xy 202.100332 -344.689116)
			(xy 202.117588 -344.744314) (xy 202.126316 -344.801484) (xy 202.12685 -344.8304) (xy 202.126364 -344.857651)
			(xy 202.118608 -344.911599) (xy 202.103253 -344.963894) (xy 202.080611 -345.013471) (xy 202.051145 -345.059321)
			(xy 202.015454 -345.100512) (xy 201.974263 -345.136203) (xy 201.928413 -345.165669) (xy 201.878836 -345.188311)
			(xy 201.826541 -345.203666) (xy 201.772593 -345.211422) (xy 201.718091 -345.211422) (xy 201.664143 -345.203666)
			(xy 201.611848 -345.188311) (xy 201.562271 -345.165669) (xy 201.516421 -345.136203) (xy 201.47523 -345.100512)
			(xy 201.439539 -345.059321) (xy 201.410073 -345.013471) (xy 201.387431 -344.963894) (xy 201.372076 -344.911599)
			(xy 201.36432 -344.857651) (xy 201.363834 -344.8304) (xy 161.174565 -344.8304) (xy 161.18749 -344.844825)
			(xy 161.218263 -344.891338) (xy 161.241935 -344.941835) (xy 161.258003 -344.995242) (xy 161.266123 -345.050418)
			(xy 161.266632 -345.078304) (xy 161.266123 -345.10619) (xy 161.258003 -345.161366) (xy 161.241935 -345.214773)
			(xy 161.218263 -345.26527) (xy 161.18749 -345.311783) (xy 161.150273 -345.35332) (xy 161.107405 -345.388995)
			(xy 161.059799 -345.418049) (xy 161.00847 -345.439861) (xy 160.954513 -345.453967) (xy 160.899076 -345.460067)
			(xy 160.843342 -345.45803) (xy 160.788499 -345.4479) (xy 160.735715 -345.429893) (xy 160.686115 -345.404392)
			(xy 160.640757 -345.371941) (xy 160.600608 -345.333232) (xy 160.566522 -345.289089) (xy 160.539226 -345.240454)
			(xy 160.519303 -345.188363) (xy 160.507177 -345.133926) (xy 160.503106 -345.078304) (xy 154.8511 -345.078304)
			(xy 154.8511 -346.211652) (xy 165.219634 -346.211652) (xy 165.22012 -346.184401) (xy 165.227876 -346.130453)
			(xy 165.243231 -346.078158) (xy 165.265873 -346.028581) (xy 165.295339 -345.982731) (xy 165.33103 -345.94154)
			(xy 165.372221 -345.905849) (xy 165.418071 -345.876383) (xy 165.467648 -345.853741) (xy 165.519943 -345.838386)
			(xy 165.573891 -345.83063) (xy 165.628393 -345.83063) (xy 165.682341 -345.838386) (xy 165.734636 -345.853741)
			(xy 165.784213 -345.876383) (xy 165.830063 -345.905849) (xy 165.871254 -345.94154) (xy 165.906945 -345.982731)
			(xy 165.936411 -346.028581) (xy 165.959053 -346.078158) (xy 165.974408 -346.130453) (xy 165.982164 -346.184401)
			(xy 165.98265 -346.211652) (xy 165.98265 -346.211906) (xy 165.982064 -346.242274) (xy 165.972446 -346.302076)
			(xy 167.694608 -346.302076) (xy 167.698679 -346.246454) (xy 167.710805 -346.192017) (xy 167.730728 -346.139926)
			(xy 167.758024 -346.091291) (xy 167.79211 -346.047148) (xy 167.832259 -346.008439) (xy 167.877617 -345.975988)
			(xy 167.927217 -345.950487) (xy 167.980001 -345.93248) (xy 168.034844 -345.92235) (xy 168.090578 -345.920313)
			(xy 168.146015 -345.926413) (xy 168.199972 -345.940519) (xy 168.251301 -345.962331) (xy 168.298907 -345.991385)
			(xy 168.341775 -346.02706) (xy 168.378992 -346.068597) (xy 168.409765 -346.11511) (xy 168.433437 -346.165607)
			(xy 168.449505 -346.219014) (xy 168.457625 -346.27419) (xy 168.458134 -346.302076) (xy 168.457625 -346.329962)
			(xy 168.449505 -346.385138) (xy 168.433437 -346.438545) (xy 168.409765 -346.489042) (xy 168.378992 -346.535555)
			(xy 168.341775 -346.577092) (xy 168.334676 -346.583) (xy 201.363834 -346.583) (xy 201.36434 -346.554082)
			(xy 201.373069 -346.49691) (xy 201.390329 -346.44171) (xy 201.415723 -346.389749) (xy 201.448669 -346.342215)
			(xy 201.488413 -346.300199) (xy 201.5109 -346.28201) (xy 201.519693 -346.274389) (xy 201.529884 -346.253499)
			(xy 201.530458 -346.241878) (xy 201.530458 -346.162122) (xy 201.529906 -346.150491) (xy 201.519728 -346.129581)
			(xy 201.5109 -346.12199) (xy 201.488412 -346.103805) (xy 201.448677 -346.061784) (xy 201.415738 -346.014248)
			(xy 201.390351 -345.962285) (xy 201.373096 -345.907087) (xy 201.364368 -345.849916) (xy 201.363834 -345.821)
			(xy 201.36432 -345.793749) (xy 201.372076 -345.739801) (xy 201.387431 -345.687506) (xy 201.410073 -345.637929)
			(xy 201.439539 -345.592079) (xy 201.47523 -345.550888) (xy 201.516421 -345.515197) (xy 201.562271 -345.485731)
			(xy 201.611848 -345.463089) (xy 201.664143 -345.447734) (xy 201.718091 -345.439978) (xy 201.772593 -345.439978)
			(xy 201.826541 -345.447734) (xy 201.878836 -345.463089) (xy 201.928413 -345.485731) (xy 201.974263 -345.515197)
			(xy 202.015454 -345.550888) (xy 202.051145 -345.592079) (xy 202.080611 -345.637929) (xy 202.103253 -345.687506)
			(xy 202.118608 -345.739801) (xy 202.126364 -345.793749) (xy 202.12685 -345.821) (xy 202.126351 -345.849918)
			(xy 202.11762 -345.907091) (xy 202.10036 -345.962291) (xy 202.074965 -346.014253) (xy 202.042017 -346.061786)
			(xy 202.002272 -346.103801) (xy 201.979784 -346.12199) (xy 201.970988 -346.129608) (xy 201.960799 -346.150501)
			(xy 201.960226 -346.162122) (xy 201.960226 -346.241878) (xy 201.960783 -346.253508) (xy 201.970958 -346.274418)
			(xy 201.979784 -346.28201) (xy 202.002269 -346.300199) (xy 202.042005 -346.342219) (xy 202.074944 -346.389754)
			(xy 202.100332 -346.441716) (xy 202.117588 -346.496914) (xy 202.126316 -346.554084) (xy 202.12685 -346.583)
			(xy 202.126364 -346.610251) (xy 202.118608 -346.664199) (xy 202.103253 -346.716494) (xy 202.080611 -346.766071)
			(xy 202.051145 -346.811921) (xy 202.015454 -346.853112) (xy 201.974263 -346.888803) (xy 201.928413 -346.918269)
			(xy 201.878836 -346.940911) (xy 201.826541 -346.956266) (xy 201.772593 -346.964022) (xy 201.718091 -346.964022)
			(xy 201.664143 -346.956266) (xy 201.611848 -346.940911) (xy 201.562271 -346.918269) (xy 201.516421 -346.888803)
			(xy 201.47523 -346.853112) (xy 201.439539 -346.811921) (xy 201.410073 -346.766071) (xy 201.387431 -346.716494)
			(xy 201.372076 -346.664199) (xy 201.36432 -346.610251) (xy 201.363834 -346.583) (xy 168.334676 -346.583)
			(xy 168.298907 -346.612767) (xy 168.251301 -346.641821) (xy 168.199972 -346.663633) (xy 168.146015 -346.677739)
			(xy 168.090578 -346.683839) (xy 168.034844 -346.681802) (xy 167.980001 -346.671672) (xy 167.927217 -346.653665)
			(xy 167.877617 -346.628164) (xy 167.832259 -346.595713) (xy 167.79211 -346.557004) (xy 167.758024 -346.512861)
			(xy 167.730728 -346.464226) (xy 167.710805 -346.412135) (xy 167.698679 -346.357698) (xy 167.694608 -346.302076)
			(xy 165.972446 -346.302076) (xy 165.97242 -346.302239) (xy 165.953408 -346.359923) (xy 165.939978 -346.387166)
			(xy 165.93403 -346.39961) (xy 165.928387 -346.426599) (xy 165.930175 -346.454113) (xy 165.939261 -346.480145)
			(xy 165.954984 -346.502794) (xy 165.976196 -346.520409) (xy 166.001348 -346.531704) (xy 166.014908 -346.534232)
			(xy 166.041624 -346.538778) (xy 166.093505 -346.554432) (xy 166.142648 -346.577269) (xy 166.188066 -346.60683)
			(xy 166.228844 -346.642521) (xy 166.264161 -346.683623) (xy 166.293307 -346.729308) (xy 166.315695 -346.778659)
			(xy 166.330874 -346.83068) (xy 166.338539 -346.884326) (xy 166.339012 -346.911422) (xy 166.338526 -346.938673)
			(xy 166.33077 -346.992621) (xy 166.315415 -347.044916) (xy 166.292773 -347.094493) (xy 166.263307 -347.140343)
			(xy 166.227616 -347.181534) (xy 166.186425 -347.217225) (xy 166.140575 -347.246691) (xy 166.09206 -347.268848)
			(xy 203.547 -347.268848) (xy 203.547 -347.214352) (xy 203.554755 -347.160411) (xy 203.570108 -347.108122)
			(xy 203.592745 -347.05855) (xy 203.622206 -347.012704) (xy 203.657892 -346.971517) (xy 203.699075 -346.935828)
			(xy 203.744918 -346.906362) (xy 203.794488 -346.88372) (xy 203.846775 -346.868363) (xy 203.900716 -346.860603)
			(xy 203.927964 -346.860114) (xy 203.955334 -346.860598) (xy 204.009512 -346.868411) (xy 204.062015 -346.883896)
			(xy 204.111762 -346.906733) (xy 204.15773 -346.936454) (xy 204.178662 -346.954094) (xy 204.178916 -346.954348)
			(xy 204.18599 -346.959953) (xy 204.202917 -346.966188) (xy 204.211936 -346.96654) (xy 204.278992 -346.96654)
			(xy 204.28801 -346.966192) (xy 204.304928 -346.95994) (xy 204.312012 -346.954348) (xy 204.312012 -346.954094)
			(xy 204.312266 -346.954094) (xy 204.333199 -346.936456) (xy 204.379172 -346.906745) (xy 204.428919 -346.883908)
			(xy 204.481419 -346.868417) (xy 204.535595 -346.860588) (xy 204.562964 -346.860114) (xy 204.589876 -346.860595)
			(xy 204.643163 -346.868196) (xy 204.694856 -346.883196) (xy 204.743935 -346.905299) (xy 204.766926 -346.919296)
			(xy 204.76718 -346.919296) (xy 204.775203 -346.923891) (xy 204.793311 -346.927542) (xy 204.802486 -346.926408)
			(xy 204.869288 -346.915486) (xy 204.878413 -346.913542) (xy 204.894436 -346.904011) (xy 204.90053 -346.896944)
			(xy 204.91875 -346.875108) (xy 204.960565 -346.836565) (xy 205.007637 -346.804656) (xy 205.058924 -346.780086)
			(xy 205.11329 -346.763401) (xy 205.16953 -346.75497) (xy 205.197964 -346.75445) (xy 205.225212 -346.755012)
			(xy 205.279155 -346.762762) (xy 205.331446 -346.778111) (xy 205.38102 -346.800744) (xy 205.426869 -346.830203)
			(xy 205.468058 -346.865887) (xy 205.50375 -346.907069) (xy 205.533218 -346.952911) (xy 205.555862 -347.002481)
			(xy 205.571221 -347.054768) (xy 205.578983 -347.10871) (xy 205.579472 -347.135958) (xy 205.578988 -347.163328)
			(xy 205.571176 -347.217506) (xy 205.555691 -347.270009) (xy 205.532853 -347.319757) (xy 205.503132 -347.365724)
			(xy 205.485492 -347.386656) (xy 205.485238 -347.38691) (xy 205.479634 -347.393984) (xy 205.473399 -347.410911)
			(xy 205.473046 -347.41993) (xy 205.473046 -347.486986) (xy 205.4734 -347.496003) (xy 205.479649 -347.512921)
			(xy 205.485238 -347.520006) (xy 205.485492 -347.520006) (xy 205.485492 -347.52026) (xy 205.503125 -347.541197)
			(xy 205.532838 -347.587169) (xy 205.555675 -347.636915) (xy 205.571168 -347.689414) (xy 205.578997 -347.743589)
			(xy 205.579472 -347.770958) (xy 205.578986 -347.798209) (xy 205.57123 -347.852157) (xy 205.555875 -347.904452)
			(xy 205.533233 -347.954029) (xy 205.503767 -347.999879) (xy 205.468076 -348.04107) (xy 205.426885 -348.076761)
			(xy 205.381035 -348.106227) (xy 205.331458 -348.128869) (xy 205.279163 -348.144224) (xy 205.225215 -348.15198)
			(xy 205.170713 -348.15198) (xy 205.116765 -348.144224) (xy 205.06447 -348.128869) (xy 205.014893 -348.106227)
			(xy 204.969043 -348.076761) (xy 204.927852 -348.04107) (xy 204.892161 -347.999879) (xy 204.862695 -347.954029)
			(xy 204.840053 -347.904452) (xy 204.824698 -347.852157) (xy 204.816942 -347.798209) (xy 204.816456 -347.770958)
			(xy 204.816456 -347.770704) (xy 204.816596 -347.756361) (xy 204.818759 -347.727756) (xy 204.820774 -347.713554)
			(xy 204.822806 -347.700346) (xy 204.813408 -347.675708) (xy 204.736446 -347.611192) (xy 204.729468 -347.605905)
			(xy 204.713039 -347.599903) (xy 204.695548 -347.599767) (xy 204.68717 -347.602302) (xy 204.657048 -347.612043)
			(xy 204.594616 -347.62251) (xy 204.562964 -347.62313) (xy 204.535592 -347.622702) (xy 204.481411 -347.614878)
			(xy 204.428907 -347.599381) (xy 204.37916 -347.57653) (xy 204.333196 -347.546796) (xy 204.312266 -347.52915)
			(xy 204.312012 -347.528896) (xy 204.304927 -347.523308) (xy 204.288009 -347.517062) (xy 204.278992 -347.516704)
			(xy 204.211936 -347.516704) (xy 204.202921 -347.517077) (xy 204.186004 -347.523313) (xy 204.178916 -347.528896)
			(xy 204.178916 -347.52915) (xy 204.178662 -347.52915) (xy 204.157711 -347.546766) (xy 204.111744 -347.576483)
			(xy 204.062002 -347.599324) (xy 204.009505 -347.61482) (xy 203.955332 -347.622654) (xy 203.927964 -347.62313)
			(xy 203.900716 -347.622597) (xy 203.846775 -347.614837) (xy 203.794488 -347.59948) (xy 203.744918 -347.576838)
			(xy 203.699075 -347.547372) (xy 203.657892 -347.511683) (xy 203.622206 -347.470496) (xy 203.592745 -347.42465)
			(xy 203.570108 -347.375078) (xy 203.554755 -347.322789) (xy 203.547 -347.268848) (xy 166.09206 -347.268848)
			(xy 166.090998 -347.269333) (xy 166.038703 -347.284688) (xy 165.984755 -347.292444) (xy 165.930253 -347.292444)
			(xy 165.876305 -347.284688) (xy 165.82401 -347.269333) (xy 165.774433 -347.246691) (xy 165.728583 -347.217225)
			(xy 165.687392 -347.181534) (xy 165.651701 -347.140343) (xy 165.622235 -347.094493) (xy 165.599593 -347.044916)
			(xy 165.584238 -346.992621) (xy 165.576482 -346.938673) (xy 165.575996 -346.911422) (xy 165.575996 -346.911168)
			(xy 165.576616 -346.880802) (xy 165.586247 -346.820838) (xy 165.605245 -346.763153) (xy 165.618668 -346.735908)
			(xy 165.624614 -346.723465) (xy 165.630247 -346.696478) (xy 165.628455 -346.668967) (xy 165.619367 -346.642939)
			(xy 165.603648 -346.620292) (xy 165.582442 -346.602675) (xy 165.557295 -346.591375) (xy 165.543738 -346.588842)
			(xy 165.517029 -346.584266) (xy 165.465153 -346.56861) (xy 165.416014 -346.545772) (xy 165.3706 -346.516212)
			(xy 165.329825 -346.480524) (xy 165.294508 -346.439427) (xy 165.265362 -346.393747) (xy 165.24297 -346.344402)
			(xy 165.227785 -346.292386) (xy 165.220112 -346.238745) (xy 165.219634 -346.211652) (xy 154.8511 -346.211652)
			(xy 154.8511 -347.260164) (xy 156.09138 -347.260164) (xy 156.095451 -347.204542) (xy 156.107577 -347.150105)
			(xy 156.1275 -347.098014) (xy 156.154796 -347.049379) (xy 156.188882 -347.005236) (xy 156.229031 -346.966527)
			(xy 156.274389 -346.934076) (xy 156.323989 -346.908575) (xy 156.376773 -346.890568) (xy 156.431616 -346.880438)
			(xy 156.48735 -346.878401) (xy 156.542787 -346.884501) (xy 156.596744 -346.898607) (xy 156.648073 -346.920419)
			(xy 156.695679 -346.949473) (xy 156.738547 -346.985148) (xy 156.775764 -347.026685) (xy 156.806537 -347.073198)
			(xy 156.830209 -347.123695) (xy 156.846277 -347.177102) (xy 156.854397 -347.232278) (xy 156.854906 -347.260164)
			(xy 156.854397 -347.28805) (xy 156.846277 -347.343226) (xy 156.830209 -347.396633) (xy 156.806537 -347.44713)
			(xy 156.775764 -347.493643) (xy 156.738547 -347.53518) (xy 156.695679 -347.570855) (xy 156.648073 -347.599909)
			(xy 156.596744 -347.621721) (xy 156.542787 -347.635827) (xy 156.48735 -347.641927) (xy 156.431616 -347.63989)
			(xy 156.376773 -347.62976) (xy 156.323989 -347.611753) (xy 156.274389 -347.586252) (xy 156.229031 -347.553801)
			(xy 156.188882 -347.515092) (xy 156.154796 -347.470949) (xy 156.1275 -347.422314) (xy 156.107577 -347.370223)
			(xy 156.095451 -347.315786) (xy 156.09138 -347.260164) (xy 154.8511 -347.260164) (xy 154.8511 -348.807278)
			(xy 158.315912 -348.807278) (xy 158.319983 -348.751656) (xy 158.332109 -348.697219) (xy 158.352032 -348.645128)
			(xy 158.379328 -348.596493) (xy 158.413414 -348.55235) (xy 158.453563 -348.513641) (xy 158.498921 -348.48119)
			(xy 158.548521 -348.455689) (xy 158.601305 -348.437682) (xy 158.656148 -348.427552) (xy 158.711882 -348.425515)
			(xy 158.767319 -348.431615) (xy 158.821276 -348.445721) (xy 158.872605 -348.467533) (xy 158.920211 -348.496587)
			(xy 158.963079 -348.532262) (xy 159.000296 -348.573799) (xy 159.031069 -348.620312) (xy 159.054741 -348.670809)
			(xy 159.070809 -348.724216) (xy 159.078929 -348.779392) (xy 159.079438 -348.807278) (xy 159.078929 -348.835164)
			(xy 159.070809 -348.89034) (xy 159.054741 -348.943747) (xy 159.031069 -348.994244) (xy 159.000296 -349.040757)
			(xy 158.963079 -349.082294) (xy 158.920211 -349.117969) (xy 158.872605 -349.147023) (xy 158.821276 -349.168835)
			(xy 158.767319 -349.182941) (xy 158.711882 -349.189041) (xy 158.656148 -349.187004) (xy 158.601305 -349.176874)
			(xy 158.548521 -349.158867) (xy 158.498921 -349.133366) (xy 158.453563 -349.100915) (xy 158.413414 -349.062206)
			(xy 158.379328 -349.018063) (xy 158.352032 -348.969428) (xy 158.332109 -348.917337) (xy 158.319983 -348.8629)
			(xy 158.315912 -348.807278) (xy 154.8511 -348.807278) (xy 154.8511 -349.270828) (xy 156.241748 -349.270828)
			(xy 156.245819 -349.215206) (xy 156.257945 -349.160769) (xy 156.277868 -349.108678) (xy 156.305164 -349.060043)
			(xy 156.33925 -349.0159) (xy 156.379399 -348.977191) (xy 156.424757 -348.94474) (xy 156.474357 -348.919239)
			(xy 156.527141 -348.901232) (xy 156.581984 -348.891102) (xy 156.637718 -348.889065) (xy 156.693155 -348.895165)
			(xy 156.747112 -348.909271) (xy 156.798441 -348.931083) (xy 156.846047 -348.960137) (xy 156.888915 -348.995812)
			(xy 156.926132 -349.037349) (xy 156.956905 -349.083862) (xy 156.980577 -349.134359) (xy 156.996645 -349.187766)
			(xy 157.004765 -349.242942) (xy 157.005274 -349.270828) (xy 157.004765 -349.298714) (xy 157.000421 -349.328232)
			(xy 165.391846 -349.328232) (xy 165.392346 -349.30034) (xy 165.400459 -349.245149) (xy 165.416529 -349.19173)
			(xy 165.440215 -349.141225) (xy 165.47101 -349.094712) (xy 165.508257 -349.053184) (xy 165.551158 -349.017529)
			(xy 165.574726 -349.002604) (xy 165.583715 -348.996529) (xy 165.595954 -348.978641) (xy 165.598348 -348.96806)
			(xy 165.611556 -348.892876) (xy 165.612903 -348.882232) (xy 165.60766 -348.861452) (xy 165.601396 -348.852744)
			(xy 165.601396 -348.85249) (xy 165.585731 -348.832176) (xy 165.55946 -348.788114) (xy 165.539321 -348.740933)
			(xy 165.525677 -348.691482) (xy 165.518773 -348.640649) (xy 165.518338 -348.615) (xy 165.518907 -348.586442)
			(xy 165.527415 -348.529964) (xy 165.544241 -348.475384) (xy 165.569009 -348.423918) (xy 165.601167 -348.376716)
			(xy 165.620192 -348.355412) (xy 165.62705 -348.348046) (xy 165.633908 -348.330012) (xy 165.632384 -348.239334)
			(xy 165.624764 -348.221554) (xy 165.617652 -348.214442) (xy 165.596896 -348.192852) (xy 165.561726 -348.14438)
			(xy 165.534565 -348.091007) (xy 165.516081 -348.034044) (xy 165.506728 -347.974892) (xy 165.506146 -347.944948)
			(xy 165.506632 -347.917697) (xy 165.514388 -347.863749) (xy 165.529743 -347.811454) (xy 165.552385 -347.761877)
			(xy 165.581851 -347.716027) (xy 165.617542 -347.674836) (xy 165.658733 -347.639145) (xy 165.704583 -347.609679)
			(xy 165.75416 -347.587037) (xy 165.806455 -347.571682) (xy 165.860403 -347.563926) (xy 165.914905 -347.563926)
			(xy 165.968853 -347.571682) (xy 166.021148 -347.587037) (xy 166.070725 -347.609679) (xy 166.116575 -347.639145)
			(xy 166.157766 -347.674836) (xy 166.193457 -347.716027) (xy 166.222923 -347.761877) (xy 166.245565 -347.811454)
			(xy 166.26092 -347.863749) (xy 166.268676 -347.917697) (xy 166.269162 -347.944948) (xy 166.268622 -347.973507)
			(xy 166.264541 -348.000574) (xy 167.718484 -348.000574) (xy 167.722555 -347.944952) (xy 167.734681 -347.890515)
			(xy 167.754604 -347.838424) (xy 167.7819 -347.789789) (xy 167.815986 -347.745646) (xy 167.856135 -347.706937)
			(xy 167.901493 -347.674486) (xy 167.951093 -347.648985) (xy 168.003877 -347.630978) (xy 168.05872 -347.620848)
			(xy 168.114454 -347.618811) (xy 168.169891 -347.624911) (xy 168.223848 -347.639017) (xy 168.275177 -347.660829)
			(xy 168.322783 -347.689883) (xy 168.365651 -347.725558) (xy 168.402868 -347.767095) (xy 168.433641 -347.813608)
			(xy 168.457313 -347.864105) (xy 168.473381 -347.917512) (xy 168.481501 -347.972688) (xy 168.48201 -348.000574)
			(xy 168.481501 -348.02846) (xy 168.473381 -348.083636) (xy 168.457313 -348.137043) (xy 168.433641 -348.18754)
			(xy 168.402868 -348.234053) (xy 168.365651 -348.27559) (xy 168.322783 -348.311265) (xy 168.275177 -348.340319)
			(xy 168.223848 -348.362131) (xy 168.169891 -348.376237) (xy 168.114454 -348.382337) (xy 168.05872 -348.3803)
			(xy 168.003877 -348.37017) (xy 167.951093 -348.352163) (xy 167.901493 -348.326662) (xy 167.856135 -348.294211)
			(xy 167.815986 -348.255502) (xy 167.7819 -348.211359) (xy 167.754604 -348.162724) (xy 167.734681 -348.110633)
			(xy 167.722555 -348.056196) (xy 167.718484 -348.000574) (xy 166.264541 -348.000574) (xy 166.260107 -348.029986)
			(xy 166.243274 -348.084567) (xy 166.2185 -348.136032) (xy 166.186336 -348.183232) (xy 166.167308 -348.204536)
			(xy 166.16045 -348.211902) (xy 166.153592 -348.229936) (xy 166.155116 -348.320614) (xy 166.162736 -348.338394)
			(xy 166.169848 -348.345506) (xy 166.190579 -348.367119) (xy 166.225752 -348.415585) (xy 166.252918 -348.468952)
			(xy 166.271408 -348.52591) (xy 166.280768 -348.585058) (xy 166.281354 -348.615) (xy 166.280879 -348.642893)
			(xy 166.272762 -348.698085) (xy 166.256687 -348.751504) (xy 166.232997 -348.80201) (xy 166.202198 -348.848523)
			(xy 166.164948 -348.89005) (xy 166.122043 -348.925703) (xy 166.098474 -348.940628) (xy 166.089474 -348.946689)
			(xy 166.077241 -348.964587) (xy 166.074852 -348.975172) (xy 166.061644 -349.050356) (xy 166.060279 -349.060999)
			(xy 166.065535 -349.081781) (xy 166.071804 -349.090488) (xy 166.071804 -349.090742) (xy 166.087438 -349.111079)
			(xy 166.113714 -349.155134) (xy 166.133859 -349.202309) (xy 166.14751 -349.251756) (xy 166.154423 -349.302584)
			(xy 166.154862 -349.328232) (xy 166.154275 -349.359057) (xy 166.144345 -349.419902) (xy 166.124751 -349.478355)
			(xy 166.096003 -349.532892) (xy 166.0779 -349.557848) (xy 166.072057 -349.566446) (xy 166.067217 -349.586646)
			(xy 166.068502 -349.596964) (xy 166.080948 -349.669862) (xy 166.083133 -349.680028) (xy 166.094427 -349.697465)
			(xy 166.102792 -349.703644) (xy 166.121171 -349.716344) (xy 168.5704 -349.716344) (xy 168.574471 -349.660722)
			(xy 168.586597 -349.606285) (xy 168.60652 -349.554194) (xy 168.633816 -349.505559) (xy 168.667902 -349.461416)
			(xy 168.708051 -349.422707) (xy 168.753409 -349.390256) (xy 168.803009 -349.364755) (xy 168.855793 -349.346748)
			(xy 168.910636 -349.336618) (xy 168.96637 -349.334581) (xy 169.021807 -349.340681) (xy 169.075764 -349.354787)
			(xy 169.127093 -349.376599) (xy 169.174699 -349.405653) (xy 169.217567 -349.441328) (xy 169.254784 -349.482865)
			(xy 169.285557 -349.529378) (xy 169.309229 -349.579875) (xy 169.325297 -349.633282) (xy 169.333417 -349.688458)
			(xy 169.333926 -349.716344) (xy 169.333417 -349.74423) (xy 169.325297 -349.799406) (xy 169.309229 -349.852813)
			(xy 169.285557 -349.90331) (xy 169.254784 -349.949823) (xy 169.217567 -349.99136) (xy 169.174699 -350.027035)
			(xy 169.127093 -350.056089) (xy 169.075764 -350.077901) (xy 169.021807 -350.092007) (xy 168.96637 -350.098107)
			(xy 168.910636 -350.09607) (xy 168.855793 -350.08594) (xy 168.803009 -350.067933) (xy 168.753409 -350.042432)
			(xy 168.708051 -350.009981) (xy 168.667902 -349.971272) (xy 168.633816 -349.927129) (xy 168.60652 -349.878494)
			(xy 168.586597 -349.826403) (xy 168.574471 -349.771966) (xy 168.5704 -349.716344) (xy 166.121171 -349.716344)
			(xy 166.124874 -349.718903) (xy 166.164991 -349.754562) (xy 166.199711 -349.795494) (xy 166.228348 -349.840891)
			(xy 166.250337 -349.889854) (xy 166.265242 -349.941417) (xy 166.272769 -349.994561) (xy 166.273226 -350.021398)
			(xy 166.27274 -350.048649) (xy 166.264984 -350.102597) (xy 166.249629 -350.154892) (xy 166.226987 -350.204469)
			(xy 166.197521 -350.250319) (xy 166.16183 -350.29151) (xy 166.120639 -350.327201) (xy 166.074789 -350.356667)
			(xy 166.025212 -350.379309) (xy 165.972917 -350.394664) (xy 165.918969 -350.40242) (xy 165.864467 -350.40242)
			(xy 165.810519 -350.394664) (xy 165.758224 -350.379309) (xy 165.708647 -350.356667) (xy 165.662797 -350.327201)
			(xy 165.621606 -350.29151) (xy 165.585915 -350.250319) (xy 165.556449 -350.204469) (xy 165.533807 -350.154892)
			(xy 165.518452 -350.102597) (xy 165.510696 -350.048649) (xy 165.51021 -350.021398) (xy 165.510819 -349.990574)
			(xy 165.520742 -349.92973) (xy 165.540331 -349.871277) (xy 165.569073 -349.81674) (xy 165.587172 -349.791782)
			(xy 165.592998 -349.783173) (xy 165.597849 -349.762982) (xy 165.59657 -349.752666) (xy 165.584124 -349.679768)
			(xy 165.581899 -349.669614) (xy 165.570631 -349.652173) (xy 165.56228 -349.645986) (xy 165.540159 -349.63078)
			(xy 165.500044 -349.595112) (xy 165.465328 -349.55417) (xy 165.436696 -349.508764) (xy 165.414714 -349.459792)
			(xy 165.399817 -349.408222) (xy 165.392299 -349.355072) (xy 165.391846 -349.328232) (xy 157.000421 -349.328232)
			(xy 156.996645 -349.35389) (xy 156.980577 -349.407297) (xy 156.956905 -349.457794) (xy 156.926132 -349.504307)
			(xy 156.888915 -349.545844) (xy 156.846047 -349.581519) (xy 156.798441 -349.610573) (xy 156.747112 -349.632385)
			(xy 156.693155 -349.646491) (xy 156.637718 -349.652591) (xy 156.581984 -349.650554) (xy 156.527141 -349.640424)
			(xy 156.474357 -349.622417) (xy 156.424757 -349.596916) (xy 156.379399 -349.564465) (xy 156.33925 -349.525756)
			(xy 156.305164 -349.481613) (xy 156.277868 -349.432978) (xy 156.257945 -349.380887) (xy 156.245819 -349.32645)
			(xy 156.241748 -349.270828) (xy 154.8511 -349.270828) (xy 154.8511 -350.091502) (xy 158.361886 -350.091502)
			(xy 158.365957 -350.03588) (xy 158.378083 -349.981443) (xy 158.398006 -349.929352) (xy 158.425302 -349.880717)
			(xy 158.459388 -349.836574) (xy 158.499537 -349.797865) (xy 158.544895 -349.765414) (xy 158.594495 -349.739913)
			(xy 158.647279 -349.721906) (xy 158.702122 -349.711776) (xy 158.757856 -349.709739) (xy 158.813293 -349.715839)
			(xy 158.86725 -349.729945) (xy 158.918579 -349.751757) (xy 158.966185 -349.780811) (xy 159.009053 -349.816486)
			(xy 159.04627 -349.858023) (xy 159.077043 -349.904536) (xy 159.100715 -349.955033) (xy 159.116783 -350.00844)
			(xy 159.124903 -350.063616) (xy 159.125412 -350.091502) (xy 159.124903 -350.119388) (xy 159.116783 -350.174564)
			(xy 159.100715 -350.227971) (xy 159.077043 -350.278468) (xy 159.04627 -350.324981) (xy 159.009053 -350.366518)
			(xy 158.966185 -350.402193) (xy 158.918579 -350.431247) (xy 158.86725 -350.453059) (xy 158.813293 -350.467165)
			(xy 158.757856 -350.473265) (xy 158.702122 -350.471228) (xy 158.647279 -350.461098) (xy 158.594495 -350.443091)
			(xy 158.544895 -350.41759) (xy 158.499537 -350.385139) (xy 158.459388 -350.34643) (xy 158.425302 -350.302287)
			(xy 158.398006 -350.253652) (xy 158.378083 -350.201561) (xy 158.365957 -350.147124) (xy 158.361886 -350.091502)
			(xy 154.8511 -350.091502) (xy 154.8511 -350.732344) (xy 168.5704 -350.732344) (xy 168.574471 -350.676722)
			(xy 168.586597 -350.622285) (xy 168.60652 -350.570194) (xy 168.633816 -350.521559) (xy 168.667902 -350.477416)
			(xy 168.708051 -350.438707) (xy 168.753409 -350.406256) (xy 168.803009 -350.380755) (xy 168.855793 -350.362748)
			(xy 168.910636 -350.352618) (xy 168.96637 -350.350581) (xy 169.021807 -350.356681) (xy 169.075764 -350.370787)
			(xy 169.127093 -350.392599) (xy 169.174699 -350.421653) (xy 169.217567 -350.457328) (xy 169.254784 -350.498865)
			(xy 169.285557 -350.545378) (xy 169.309229 -350.595875) (xy 169.325297 -350.649282) (xy 169.333417 -350.704458)
			(xy 169.333926 -350.732344) (xy 169.333417 -350.76023) (xy 169.325297 -350.815406) (xy 169.309229 -350.868813)
			(xy 169.285557 -350.91931) (xy 169.254784 -350.965823) (xy 169.217567 -351.00736) (xy 169.174699 -351.043035)
			(xy 169.127093 -351.072089) (xy 169.075764 -351.093901) (xy 169.021807 -351.108007) (xy 168.96637 -351.114107)
			(xy 168.910636 -351.11207) (xy 168.855793 -351.10194) (xy 168.803009 -351.083933) (xy 168.753409 -351.058432)
			(xy 168.708051 -351.025981) (xy 168.667902 -350.987272) (xy 168.633816 -350.943129) (xy 168.60652 -350.894494)
			(xy 168.586597 -350.842403) (xy 168.574471 -350.787966) (xy 168.5704 -350.732344) (xy 154.8511 -350.732344)
			(xy 154.8511 -351.398078) (xy 158.417512 -351.398078) (xy 158.421583 -351.342456) (xy 158.433709 -351.288019)
			(xy 158.453632 -351.235928) (xy 158.480928 -351.187293) (xy 158.515014 -351.14315) (xy 158.555163 -351.104441)
			(xy 158.600521 -351.07199) (xy 158.650121 -351.046489) (xy 158.702905 -351.028482) (xy 158.757748 -351.018352)
			(xy 158.813482 -351.016315) (xy 158.868919 -351.022415) (xy 158.922876 -351.036521) (xy 158.974205 -351.058333)
			(xy 159.021811 -351.087387) (xy 159.064679 -351.123062) (xy 159.101896 -351.164599) (xy 159.132669 -351.211112)
			(xy 159.156341 -351.261609) (xy 159.172409 -351.315016) (xy 159.180529 -351.370192) (xy 159.181038 -351.398078)
			(xy 159.180529 -351.425964) (xy 159.172409 -351.48114) (xy 159.156341 -351.534547) (xy 159.132669 -351.585044)
			(xy 159.12092 -351.602802) (xy 159.687512 -351.602802) (xy 159.691583 -351.54718) (xy 159.703709 -351.492743)
			(xy 159.723632 -351.440652) (xy 159.750928 -351.392017) (xy 159.785014 -351.347874) (xy 159.825163 -351.309165)
			(xy 159.870521 -351.276714) (xy 159.920121 -351.251213) (xy 159.972905 -351.233206) (xy 160.027748 -351.223076)
			(xy 160.083482 -351.221039) (xy 160.138919 -351.227139) (xy 160.192876 -351.241245) (xy 160.244205 -351.263057)
			(xy 160.291811 -351.292111) (xy 160.334679 -351.327786) (xy 160.371896 -351.369323) (xy 160.402669 -351.415836)
			(xy 160.426341 -351.466333) (xy 160.442409 -351.51974) (xy 160.450529 -351.574916) (xy 160.451038 -351.602802)
			(xy 160.450529 -351.630688) (xy 160.443367 -351.679356) (xy 160.907633 -351.679356) (xy 160.907633 -351.624844)
			(xy 160.915391 -351.570887) (xy 160.93075 -351.518584) (xy 160.953396 -351.468999) (xy 160.982868 -351.423142)
			(xy 161.018567 -351.381946) (xy 161.059766 -351.34625) (xy 161.105625 -351.316781) (xy 161.155212 -351.294139)
			(xy 161.207517 -351.278785) (xy 161.261474 -351.271031) (xy 161.28873 -351.27057) (xy 161.314483 -351.27099)
			(xy 161.36552 -351.277935) (xy 161.415158 -351.291681) (xy 161.462497 -351.311979) (xy 161.506676 -351.338459)
			(xy 161.546892 -351.37064) (xy 161.582414 -351.407938) (xy 161.597848 -351.428558) (xy 161.606183 -351.439287)
			(xy 161.627314 -351.456343) (xy 161.652198 -351.467214) (xy 161.679069 -351.471129) (xy 161.706021 -351.467811)
			(xy 161.73114 -351.457494) (xy 161.752644 -351.440912) (xy 161.76117 -351.430336) (xy 161.779334 -351.407289)
			(xy 161.8215 -351.366484) (xy 161.869419 -351.33262) (xy 161.921961 -351.306498) (xy 161.977885 -351.288733)
			(xy 162.035869 -351.279745) (xy 162.065208 -351.279206) (xy 162.065462 -351.279206) (xy 162.092718 -351.279638)
			(xy 162.146675 -351.287391) (xy 162.198979 -351.302744) (xy 162.248566 -351.325386) (xy 162.294426 -351.354854)
			(xy 162.335624 -351.390549) (xy 162.371323 -351.431744) (xy 162.400796 -351.477601) (xy 162.423442 -351.527185)
			(xy 162.437965 -351.57664) (xy 164.057836 -351.57664) (xy 164.061907 -351.521018) (xy 164.074033 -351.466581)
			(xy 164.093956 -351.41449) (xy 164.121252 -351.365855) (xy 164.155338 -351.321712) (xy 164.195487 -351.283003)
			(xy 164.240845 -351.250552) (xy 164.290445 -351.225051) (xy 164.343229 -351.207044) (xy 164.398072 -351.196914)
			(xy 164.453806 -351.194877) (xy 164.509243 -351.200977) (xy 164.5632 -351.215083) (xy 164.614529 -351.236895)
			(xy 164.662135 -351.265949) (xy 164.705003 -351.301624) (xy 164.74222 -351.343161) (xy 164.772993 -351.389674)
			(xy 164.796665 -351.440171) (xy 164.812733 -351.493578) (xy 164.820853 -351.548754) (xy 164.821362 -351.57664)
			(xy 164.820853 -351.604526) (xy 164.812733 -351.659702) (xy 164.796665 -351.713109) (xy 164.772993 -351.763606)
			(xy 164.74222 -351.810119) (xy 164.705003 -351.851656) (xy 164.662135 -351.887331) (xy 164.614529 -351.916385)
			(xy 164.5632 -351.938197) (xy 164.509243 -351.952303) (xy 164.453806 -351.958403) (xy 164.398072 -351.956366)
			(xy 164.343229 -351.946236) (xy 164.290445 -351.928229) (xy 164.240845 -351.902728) (xy 164.195487 -351.870277)
			(xy 164.155338 -351.831568) (xy 164.121252 -351.787425) (xy 164.093956 -351.73879) (xy 164.074033 -351.686699)
			(xy 164.061907 -351.632262) (xy 164.057836 -351.57664) (xy 162.437965 -351.57664) (xy 162.438801 -351.579488)
			(xy 162.446559 -351.633444) (xy 162.446559 -351.687956) (xy 162.438801 -351.741912) (xy 162.423442 -351.794215)
			(xy 162.400796 -351.843799) (xy 162.371323 -351.889656) (xy 162.335624 -351.930851) (xy 162.294426 -351.966546)
			(xy 162.248566 -351.996014) (xy 162.198979 -352.018656) (xy 162.146675 -352.034009) (xy 162.092718 -352.041762)
			(xy 162.065462 -352.042222) (xy 162.039708 -352.041811) (xy 161.988671 -352.034865) (xy 161.939033 -352.021117)
			(xy 161.891694 -352.000818) (xy 161.847515 -351.974337) (xy 161.807299 -351.942154) (xy 161.771778 -351.904855)
			(xy 161.756344 -351.884234) (xy 161.748018 -351.873497) (xy 161.726885 -351.856443) (xy 161.701999 -351.845574)
			(xy 161.675126 -351.84166) (xy 161.648173 -351.844979) (xy 161.623053 -351.855297) (xy 161.601548 -351.87188)
			(xy 161.593022 -351.882456) (xy 161.57486 -351.905505) (xy 161.532694 -351.94631) (xy 161.484774 -351.980174)
			(xy 161.432232 -352.006296) (xy 161.376308 -352.024061) (xy 161.318323 -352.033048) (xy 161.288984 -352.033586)
			(xy 161.28873 -352.033586) (xy 161.261474 -352.033169) (xy 161.207517 -352.025415) (xy 161.155212 -352.010061)
			(xy 161.105625 -351.987419) (xy 161.059766 -351.95795) (xy 161.018567 -351.922254) (xy 160.982868 -351.881058)
			(xy 160.953396 -351.835201) (xy 160.93075 -351.785616) (xy 160.915391 -351.733313) (xy 160.907633 -351.679356)
			(xy 160.443367 -351.679356) (xy 160.442409 -351.685864) (xy 160.426341 -351.739271) (xy 160.402669 -351.789768)
			(xy 160.371896 -351.836281) (xy 160.334679 -351.877818) (xy 160.291811 -351.913493) (xy 160.244205 -351.942547)
			(xy 160.192876 -351.964359) (xy 160.138919 -351.978465) (xy 160.083482 -351.984565) (xy 160.027748 -351.982528)
			(xy 159.972905 -351.972398) (xy 159.920121 -351.954391) (xy 159.870521 -351.92889) (xy 159.825163 -351.896439)
			(xy 159.785014 -351.85773) (xy 159.750928 -351.813587) (xy 159.723632 -351.764952) (xy 159.703709 -351.712861)
			(xy 159.691583 -351.658424) (xy 159.687512 -351.602802) (xy 159.12092 -351.602802) (xy 159.101896 -351.631557)
			(xy 159.064679 -351.673094) (xy 159.021811 -351.708769) (xy 158.974205 -351.737823) (xy 158.922876 -351.759635)
			(xy 158.868919 -351.773741) (xy 158.813482 -351.779841) (xy 158.757748 -351.777804) (xy 158.702905 -351.767674)
			(xy 158.650121 -351.749667) (xy 158.600521 -351.724166) (xy 158.555163 -351.691715) (xy 158.515014 -351.653006)
			(xy 158.480928 -351.608863) (xy 158.453632 -351.560228) (xy 158.433709 -351.508137) (xy 158.421583 -351.4537)
			(xy 158.417512 -351.398078) (xy 154.8511 -351.398078) (xy 154.8511 -352.102928) (xy 156.238192 -352.102928)
			(xy 156.242263 -352.047306) (xy 156.254389 -351.992869) (xy 156.274312 -351.940778) (xy 156.301608 -351.892143)
			(xy 156.335694 -351.848) (xy 156.375843 -351.809291) (xy 156.421201 -351.77684) (xy 156.470801 -351.751339)
			(xy 156.523585 -351.733332) (xy 156.578428 -351.723202) (xy 156.634162 -351.721165) (xy 156.689599 -351.727265)
			(xy 156.743556 -351.741371) (xy 156.794885 -351.763183) (xy 156.842491 -351.792237) (xy 156.885359 -351.827912)
			(xy 156.922576 -351.869449) (xy 156.953349 -351.915962) (xy 156.977021 -351.966459) (xy 156.993089 -352.019866)
			(xy 157.001209 -352.075042) (xy 157.001718 -352.102928) (xy 157.001209 -352.130814) (xy 156.993089 -352.18599)
			(xy 156.977021 -352.239397) (xy 156.953349 -352.289894) (xy 156.922576 -352.336407) (xy 156.885359 -352.377944)
			(xy 156.842491 -352.413619) (xy 156.794885 -352.442673) (xy 156.743556 -352.464485) (xy 156.689599 -352.478591)
			(xy 156.634162 -352.484691) (xy 156.578428 -352.482654) (xy 156.523585 -352.472524) (xy 156.470801 -352.454517)
			(xy 156.421201 -352.429016) (xy 156.375843 -352.396565) (xy 156.335694 -352.357856) (xy 156.301608 -352.313713)
			(xy 156.274312 -352.265078) (xy 156.254389 -352.212987) (xy 156.242263 -352.15855) (xy 156.238192 -352.102928)
			(xy 154.8511 -352.102928) (xy 154.8511 -352.950272) (xy 178.85537 -352.950272) (xy 178.855851 -352.922361)
			(xy 178.863989 -352.867135) (xy 178.880088 -352.813684) (xy 178.903803 -352.763149) (xy 178.934629 -352.71661)
			(xy 178.952906 -352.69551) (xy 178.958799 -352.68833) (xy 178.965452 -352.671007) (xy 178.96586 -352.661728)
			(xy 178.96586 -352.584004) (xy 178.959256 -352.566732) (xy 178.952906 -352.55962) (xy 178.934617 -352.538529)
			(xy 178.903791 -352.491989) (xy 178.880078 -352.441452) (xy 178.863984 -352.387998) (xy 178.855853 -352.33277)
			(xy 178.85537 -352.304858) (xy 178.855856 -352.277607) (xy 178.863612 -352.223659) (xy 178.878967 -352.171364)
			(xy 178.901609 -352.121787) (xy 178.931075 -352.075937) (xy 178.966766 -352.034746) (xy 179.007957 -351.999055)
			(xy 179.053807 -351.969589) (xy 179.103384 -351.946947) (xy 179.155679 -351.931592) (xy 179.209627 -351.923836)
			(xy 179.264129 -351.923836) (xy 179.318077 -351.931592) (xy 179.370372 -351.946947) (xy 179.419949 -351.969589)
			(xy 179.465799 -351.999055) (xy 179.50699 -352.034746) (xy 179.542681 -352.075937) (xy 179.572147 -352.121787)
			(xy 179.594789 -352.171364) (xy 179.610144 -352.223659) (xy 179.6179 -352.277607) (xy 179.618386 -352.304858)
			(xy 179.617909 -352.332769) (xy 179.609768 -352.387995) (xy 179.593667 -352.441445) (xy 179.569952 -352.491979)
			(xy 179.539127 -352.538519) (xy 179.52085 -352.55962) (xy 179.514939 -352.566787) (xy 179.508298 -352.58412)
			(xy 179.507896 -352.593402) (xy 179.507896 -352.671126) (xy 179.5145 -352.688398) (xy 179.52085 -352.69551)
			(xy 179.539115 -352.71662) (xy 179.569943 -352.763156) (xy 179.593659 -352.813688) (xy 179.609759 -352.867137)
			(xy 179.617898 -352.922362) (xy 179.618386 -352.950272) (xy 179.6179 -352.977523) (xy 179.610144 -353.031471)
			(xy 179.594789 -353.083766) (xy 179.572147 -353.133343) (xy 179.542681 -353.179193) (xy 179.50699 -353.220384)
			(xy 179.465799 -353.256075) (xy 179.422658 -353.2838) (xy 183.237633 -353.2838) (xy 183.241801 -353.228186)
			(xy 183.25421 -353.173815) (xy 183.274583 -353.1219) (xy 183.302466 -353.073601) (xy 183.337236 -353.029997)
			(xy 183.378116 -352.992062) (xy 183.424192 -352.960642) (xy 183.474437 -352.936441) (xy 183.527727 -352.919998)
			(xy 183.582873 -352.91168) (xy 183.610758 -352.911156) (xy 183.63718 -352.91159) (xy 183.689497 -352.919048)
			(xy 183.740235 -352.933819) (xy 183.788379 -352.955607) (xy 183.832963 -352.983977) (xy 183.853328 -353.000818)
			(xy 183.860186 -353.00666) (xy 183.877204 -353.01301) (xy 183.961532 -353.01301) (xy 183.97855 -353.00666)
			(xy 183.985408 -353.000818) (xy 184.005774 -352.983979) (xy 184.05036 -352.955614) (xy 184.098504 -352.933827)
			(xy 184.149241 -352.919056) (xy 184.201556 -352.911596) (xy 184.2544 -352.911596) (xy 184.306715 -352.919056)
			(xy 184.357452 -352.933827) (xy 184.405596 -352.955614) (xy 184.450182 -352.983979) (xy 184.470548 -353.000818)
			(xy 184.477406 -353.00666) (xy 184.494424 -353.01301) (xy 184.578752 -353.01301) (xy 184.59577 -353.00666)
			(xy 184.602628 -353.000818) (xy 184.614414 -352.990981) (xy 184.639338 -352.973051) (xy 184.652412 -352.965004)
			(xy 184.652666 -352.96475) (xy 184.661833 -352.958508) (xy 184.674091 -352.94006) (xy 184.676288 -352.92919)
			(xy 184.690004 -352.840798) (xy 184.683654 -352.819208) (xy 184.676034 -352.810826) (xy 184.658169 -352.789823)
			(xy 184.62806 -352.743633) (xy 184.604911 -352.69359) (xy 184.589205 -352.640736) (xy 184.58127 -352.586173)
			(xy 184.580784 -352.558604) (xy 184.581258 -352.53103) (xy 184.58921 -352.476458) (xy 184.604933 -352.423598)
			(xy 184.628102 -352.373552) (xy 184.658233 -352.327362) (xy 184.694698 -352.28599) (xy 184.715404 -352.267774)
			(xy 184.723492 -352.26023) (xy 184.732839 -352.24021) (xy 184.733438 -352.229166) (xy 184.733438 -352.151442)
			(xy 184.732866 -352.140393) (xy 184.723506 -352.12037) (xy 184.715404 -352.112834) (xy 184.694707 -352.094608)
			(xy 184.658235 -352.053242) (xy 184.628101 -352.007055) (xy 184.604933 -351.95701) (xy 184.589214 -351.904151)
			(xy 184.581271 -351.849578) (xy 184.580784 -351.822004) (xy 184.58127 -351.794753) (xy 184.589026 -351.740805)
			(xy 184.604381 -351.68851) (xy 184.627023 -351.638933) (xy 184.656489 -351.593083) (xy 184.69218 -351.551892)
			(xy 184.733371 -351.516201) (xy 184.779221 -351.486735) (xy 184.828798 -351.464093) (xy 184.881093 -351.448738)
			(xy 184.935041 -351.440982) (xy 184.989543 -351.440982) (xy 185.043491 -351.448738) (xy 185.095786 -351.464093)
			(xy 185.145363 -351.486735) (xy 185.191213 -351.516201) (xy 185.232404 -351.551892) (xy 185.268095 -351.593083)
			(xy 185.297561 -351.638933) (xy 185.320203 -351.68851) (xy 185.335558 -351.740805) (xy 185.343314 -351.794753)
			(xy 185.3438 -351.822004) (xy 185.343337 -351.849579) (xy 185.335384 -351.904152) (xy 185.319658 -351.957012)
			(xy 185.296488 -352.007057) (xy 185.266355 -352.053247) (xy 185.229887 -352.094618) (xy 185.20918 -352.112834)
			(xy 185.201086 -352.120372) (xy 185.191743 -352.140397) (xy 185.191146 -352.151442) (xy 185.191146 -352.229166)
			(xy 185.191719 -352.240215) (xy 185.201079 -352.260237) (xy 185.20918 -352.267774) (xy 185.229878 -352.286)
			(xy 185.26635 -352.327365) (xy 185.296484 -352.373552) (xy 185.319653 -352.423597) (xy 185.335372 -352.476457)
			(xy 185.343314 -352.53103) (xy 185.3438 -352.558604) (xy 185.343259 -352.587026) (xy 185.334845 -352.643242)
			(xy 185.318173 -352.697584) (xy 185.293614 -352.748848) (xy 185.261712 -352.795894) (xy 185.223177 -352.83768)
			(xy 185.178861 -352.873278) (xy 185.15457 -352.888042) (xy 185.144664 -352.89363) (xy 185.131964 -352.912172)
			(xy 185.121245 -352.975672) (xy 187.181998 -352.975672) (xy 187.182472 -352.94776) (xy 187.190611 -352.892534)
			(xy 187.20671 -352.839083) (xy 187.230427 -352.788548) (xy 187.261255 -352.742009) (xy 187.279534 -352.72091)
			(xy 187.285431 -352.713733) (xy 187.292081 -352.696407) (xy 187.292488 -352.687128) (xy 187.292488 -352.609404)
			(xy 187.285884 -352.592132) (xy 187.279534 -352.58502) (xy 187.261234 -352.563939) (xy 187.230412 -352.517395)
			(xy 187.206702 -352.466855) (xy 187.19061 -352.4134) (xy 187.182481 -352.35817) (xy 187.181998 -352.330258)
			(xy 187.182484 -352.303007) (xy 187.19024 -352.249059) (xy 187.205595 -352.196764) (xy 187.228237 -352.147187)
			(xy 187.257703 -352.101337) (xy 187.293394 -352.060146) (xy 187.334585 -352.024455) (xy 187.380435 -351.994989)
			(xy 187.430012 -351.972347) (xy 187.482307 -351.956992) (xy 187.536255 -351.949236) (xy 187.590757 -351.949236)
			(xy 187.644705 -351.956992) (xy 187.697 -351.972347) (xy 187.746577 -351.994989) (xy 187.792427 -352.024455)
			(xy 187.833618 -352.060146) (xy 187.869309 -352.101337) (xy 187.898775 -352.147187) (xy 187.921417 -352.196764)
			(xy 187.936772 -352.249059) (xy 187.944528 -352.303007) (xy 187.945014 -352.330258) (xy 187.944555 -352.35817)
			(xy 187.936412 -352.413397) (xy 187.920309 -352.466848) (xy 187.896589 -352.517383) (xy 187.865758 -352.563921)
			(xy 187.847478 -352.58502) (xy 187.84157 -352.592189) (xy 187.834926 -352.609521) (xy 187.834524 -352.618802)
			(xy 187.834524 -352.696526) (xy 187.841128 -352.713798) (xy 187.847478 -352.72091) (xy 187.865731 -352.74203)
			(xy 187.896563 -352.788562) (xy 187.920284 -352.839092) (xy 187.936386 -352.892539) (xy 187.944526 -352.947762)
			(xy 187.945014 -352.975672) (xy 187.944528 -353.002923) (xy 187.936772 -353.056871) (xy 187.921417 -353.109166)
			(xy 187.898775 -353.158743) (xy 187.869309 -353.204593) (xy 187.833618 -353.245784) (xy 187.792427 -353.281475)
			(xy 187.749286 -353.3092) (xy 191.564233 -353.3092) (xy 191.568401 -353.253584) (xy 191.580811 -353.19921)
			(xy 191.601187 -353.147293) (xy 191.629072 -353.098992) (xy 191.663845 -353.055387) (xy 191.704728 -353.017452)
			(xy 191.750809 -352.986033) (xy 191.801057 -352.961833) (xy 191.854351 -352.945392) (xy 191.9095 -352.937078)
			(xy 191.937386 -352.936556) (xy 191.963807 -352.937032) (xy 192.016121 -352.944479) (xy 192.066859 -352.959241)
			(xy 192.115004 -352.98102) (xy 192.15959 -353.009381) (xy 192.179956 -353.026218) (xy 192.186814 -353.03206)
			(xy 192.203832 -353.03841) (xy 192.28816 -353.03841) (xy 192.305178 -353.03206) (xy 192.312036 -353.026218)
			(xy 192.332402 -353.009379) (xy 192.376988 -352.981014) (xy 192.425132 -352.959227) (xy 192.475869 -352.944456)
			(xy 192.528184 -352.936996) (xy 192.581028 -352.936996) (xy 192.633343 -352.944456) (xy 192.68408 -352.959227)
			(xy 192.732224 -352.981014) (xy 192.77681 -353.009379) (xy 192.797176 -353.026218) (xy 192.804034 -353.03206)
			(xy 192.821052 -353.03841) (xy 192.90538 -353.03841) (xy 192.922398 -353.03206) (xy 192.929256 -353.026218)
			(xy 192.943154 -353.014639) (xy 192.972794 -352.993899) (xy 192.988438 -352.984816) (xy 192.998264 -352.978642)
			(xy 193.011493 -352.959605) (xy 193.013838 -352.94824) (xy 193.0273 -352.857054) (xy 193.020442 -352.834956)
			(xy 193.012314 -352.82632) (xy 192.992734 -352.804937) (xy 192.959615 -352.757351) (xy 192.934083 -352.705299)
			(xy 192.916729 -352.649981) (xy 192.907952 -352.592672) (xy 192.907412 -352.563684) (xy 192.907931 -352.536111)
			(xy 192.915872 -352.481541) (xy 192.931586 -352.428682) (xy 192.954746 -352.378635) (xy 192.98487 -352.332444)
			(xy 193.021329 -352.291071) (xy 193.042032 -352.272854) (xy 193.050133 -352.265323) (xy 193.059472 -352.245293)
			(xy 193.060066 -352.234246) (xy 193.060066 -352.156522) (xy 193.059497 -352.145473) (xy 193.050133 -352.125451)
			(xy 193.042032 -352.117914) (xy 193.021331 -352.099692) (xy 192.984858 -352.058326) (xy 192.954724 -352.012139)
			(xy 192.931556 -351.962093) (xy 192.915838 -351.909232) (xy 192.907898 -351.854658) (xy 192.907412 -351.827084)
			(xy 192.907898 -351.799833) (xy 192.915654 -351.745885) (xy 192.931009 -351.69359) (xy 192.953651 -351.644013)
			(xy 192.983117 -351.598163) (xy 193.018808 -351.556972) (xy 193.059999 -351.521281) (xy 193.105849 -351.491815)
			(xy 193.155426 -351.469173) (xy 193.207721 -351.453818) (xy 193.261669 -351.446062) (xy 193.316171 -351.446062)
			(xy 193.370119 -351.453818) (xy 193.422414 -351.469173) (xy 193.471991 -351.491815) (xy 193.517841 -351.521281)
			(xy 193.559032 -351.556972) (xy 193.594723 -351.598163) (xy 193.624189 -351.644013) (xy 193.646831 -351.69359)
			(xy 193.662186 -351.745885) (xy 193.669942 -351.799833) (xy 193.670428 -351.827084) (xy 193.669942 -351.854658)
			(xy 193.661992 -351.909229) (xy 193.64627 -351.962088) (xy 193.623104 -352.012134) (xy 193.592976 -352.058324)
			(xy 193.556513 -352.099697) (xy 193.535808 -352.117914) (xy 193.527727 -352.125465) (xy 193.518376 -352.145479)
			(xy 193.517774 -352.156522) (xy 193.517774 -352.234246) (xy 193.518349 -352.245295) (xy 193.527707 -352.265318)
			(xy 193.535808 -352.272854) (xy 193.556502 -352.291084) (xy 193.592973 -352.332449) (xy 193.623107 -352.378635)
			(xy 193.646276 -352.428679) (xy 193.661996 -352.481538) (xy 193.66994 -352.53611) (xy 193.670428 -352.563684)
			(xy 193.669837 -352.592875) (xy 193.660932 -352.650574) (xy 193.643341 -352.706243) (xy 193.617476 -352.758583)
			(xy 193.583941 -352.806372) (xy 193.543517 -352.848496) (xy 193.497149 -352.88397) (xy 193.4718 -352.898456)
			(xy 193.461878 -352.904519) (xy 193.448379 -352.923421) (xy 193.445892 -352.934778) (xy 193.430906 -353.02571)
			(xy 193.437764 -353.047808) (xy 193.445638 -353.056444) (xy 193.464098 -353.077219) (xy 193.495309 -353.123201)
			(xy 193.519344 -353.173309) (xy 193.535671 -353.22643) (xy 193.543929 -353.281387) (xy 193.544444 -353.309174)
			(xy 193.543919 -353.335788) (xy 193.536348 -353.388476) (xy 193.521355 -353.43955) (xy 193.499246 -353.48797)
			(xy 193.470472 -353.53275) (xy 193.435617 -353.572981) (xy 193.395392 -353.607841) (xy 193.350615 -353.636621)
			(xy 193.302198 -353.658737) (xy 193.251127 -353.673737) (xy 193.19844 -353.681316) (xy 193.171826 -353.681792)
			(xy 193.145405 -353.681321) (xy 193.09309 -353.673875) (xy 193.042351 -353.659113) (xy 192.994207 -353.637332)
			(xy 192.949621 -353.608969) (xy 192.929256 -353.59213) (xy 192.922398 -353.586288) (xy 192.90538 -353.579938)
			(xy 192.821052 -353.579938) (xy 192.804034 -353.586288) (xy 192.797176 -353.59213) (xy 192.77681 -353.608969)
			(xy 192.732224 -353.637334) (xy 192.68408 -353.659121) (xy 192.633343 -353.673892) (xy 192.581028 -353.681352)
			(xy 192.528184 -353.681352) (xy 192.475869 -353.673892) (xy 192.425132 -353.659121) (xy 192.376988 -353.637334)
			(xy 192.332402 -353.608969) (xy 192.312036 -353.59213) (xy 192.305178 -353.586288) (xy 192.28816 -353.579938)
			(xy 192.203832 -353.579938) (xy 192.186814 -353.586288) (xy 192.179956 -353.59213) (xy 192.159598 -353.608978)
			(xy 192.115007 -353.637334) (xy 192.066861 -353.659112) (xy 192.016122 -353.673877) (xy 191.963808 -353.681334)
			(xy 191.937386 -353.681792) (xy 191.9095 -353.681322) (xy 191.854351 -353.673008) (xy 191.801057 -353.656567)
			(xy 191.750809 -353.632367) (xy 191.704728 -353.600948) (xy 191.663845 -353.563013) (xy 191.629072 -353.519408)
			(xy 191.601187 -353.471107) (xy 191.580811 -353.41919) (xy 191.568401 -353.364816) (xy 191.564233 -353.3092)
			(xy 187.749286 -353.3092) (xy 187.746577 -353.310941) (xy 187.697 -353.333583) (xy 187.644705 -353.348938)
			(xy 187.590757 -353.356694) (xy 187.536255 -353.356694) (xy 187.482307 -353.348938) (xy 187.430012 -353.333583)
			(xy 187.380435 -353.310941) (xy 187.334585 -353.281475) (xy 187.293394 -353.245784) (xy 187.257703 -353.204593)
			(xy 187.228237 -353.158743) (xy 187.205595 -353.109166) (xy 187.19024 -353.056871) (xy 187.182484 -353.002923)
			(xy 187.181998 -352.975672) (xy 185.121245 -352.975672) (xy 185.1152 -353.011486) (xy 185.121296 -353.033076)
			(xy 185.128662 -353.041712) (xy 185.145403 -353.062036) (xy 185.173607 -353.106501) (xy 185.195266 -353.154496)
			(xy 185.209948 -353.205062) (xy 185.217362 -353.257192) (xy 185.217816 -353.28352) (xy 185.217816 -353.283774)
			(xy 185.217342 -353.310391) (xy 185.209769 -353.363084) (xy 185.194774 -353.414163) (xy 185.172662 -353.462588)
			(xy 185.143883 -353.507373) (xy 185.109023 -353.547606) (xy 185.068792 -353.582469) (xy 185.024009 -353.61125)
			(xy 184.975586 -353.633366) (xy 184.924508 -353.648364) (xy 184.871815 -353.65594) (xy 184.845198 -353.656392)
			(xy 184.818776 -353.655937) (xy 184.76646 -353.648487) (xy 184.715722 -353.633721) (xy 184.667577 -353.611937)
			(xy 184.622993 -353.58357) (xy 184.602628 -353.56673) (xy 184.59577 -353.560888) (xy 184.578752 -353.554538)
			(xy 184.494424 -353.554538) (xy 184.477406 -353.560888) (xy 184.470548 -353.56673) (xy 184.450182 -353.583569)
			(xy 184.405596 -353.611934) (xy 184.357452 -353.633721) (xy 184.306715 -353.648492) (xy 184.2544 -353.655952)
			(xy 184.201556 -353.655952) (xy 184.149241 -353.648492) (xy 184.098504 -353.633721) (xy 184.05036 -353.611934)
			(xy 184.005774 -353.583569) (xy 183.985408 -353.56673) (xy 183.97855 -353.560888) (xy 183.961532 -353.554538)
			(xy 183.877204 -353.554538) (xy 183.860186 -353.560888) (xy 183.853328 -353.56673) (xy 183.832943 -353.583544)
			(xy 183.78836 -353.611905) (xy 183.74022 -353.63369) (xy 183.689487 -353.648463) (xy 183.637178 -353.655929)
			(xy 183.610758 -353.656392) (xy 183.582873 -353.65592) (xy 183.527727 -353.647602) (xy 183.474437 -353.631159)
			(xy 183.424192 -353.606958) (xy 183.378116 -353.575538) (xy 183.337236 -353.537603) (xy 183.302466 -353.493999)
			(xy 183.274583 -353.4457) (xy 183.25421 -353.393785) (xy 183.241801 -353.339414) (xy 183.237633 -353.2838)
			(xy 179.422658 -353.2838) (xy 179.419949 -353.285541) (xy 179.370372 -353.308183) (xy 179.318077 -353.323538)
			(xy 179.264129 -353.331294) (xy 179.209627 -353.331294) (xy 179.155679 -353.323538) (xy 179.103384 -353.308183)
			(xy 179.053807 -353.285541) (xy 179.007957 -353.256075) (xy 178.966766 -353.220384) (xy 178.931075 -353.179193)
			(xy 178.901609 -353.133343) (xy 178.878967 -353.083766) (xy 178.863612 -353.031471) (xy 178.855856 -352.977523)
			(xy 178.85537 -352.950272) (xy 154.8511 -352.950272) (xy 154.8511 -353.89439) (xy 157.69539 -353.89439)
			(xy 157.699461 -353.838768) (xy 157.711587 -353.784331) (xy 157.73151 -353.73224) (xy 157.758806 -353.683605)
			(xy 157.792892 -353.639462) (xy 157.833041 -353.600753) (xy 157.878399 -353.568302) (xy 157.927999 -353.542801)
			(xy 157.980783 -353.524794) (xy 158.035626 -353.514664) (xy 158.09136 -353.512627) (xy 158.146797 -353.518727)
			(xy 158.200754 -353.532833) (xy 158.252083 -353.554645) (xy 158.299689 -353.583699) (xy 158.342557 -353.619374)
			(xy 158.379774 -353.660911) (xy 158.410547 -353.707424) (xy 158.411153 -353.708716) (xy 159.770824 -353.708716)
			(xy 159.774895 -353.653094) (xy 159.787021 -353.598657) (xy 159.806944 -353.546566) (xy 159.83424 -353.497931)
			(xy 159.868326 -353.453788) (xy 159.908475 -353.415079) (xy 159.953833 -353.382628) (xy 160.003433 -353.357127)
			(xy 160.056217 -353.33912) (xy 160.11106 -353.32899) (xy 160.166794 -353.326953) (xy 160.219895 -353.332796)
			(xy 165.19474 -353.332796) (xy 165.198811 -353.277174) (xy 165.210937 -353.222737) (xy 165.23086 -353.170646)
			(xy 165.258156 -353.122011) (xy 165.292242 -353.077868) (xy 165.332391 -353.039159) (xy 165.377749 -353.006708)
			(xy 165.427349 -352.981207) (xy 165.480133 -352.9632) (xy 165.534976 -352.95307) (xy 165.59071 -352.951033)
			(xy 165.646147 -352.957133) (xy 165.700104 -352.971239) (xy 165.751433 -352.993051) (xy 165.799039 -353.022105)
			(xy 165.841907 -353.05778) (xy 165.879124 -353.099317) (xy 165.909897 -353.14583) (xy 165.933569 -353.196327)
			(xy 165.949637 -353.249734) (xy 165.957757 -353.30491) (xy 165.958266 -353.332796) (xy 165.957757 -353.360682)
			(xy 165.949637 -353.415858) (xy 165.933569 -353.469265) (xy 165.909897 -353.519762) (xy 165.879124 -353.566275)
			(xy 165.841907 -353.607812) (xy 165.799039 -353.643487) (xy 165.751433 -353.672541) (xy 165.700104 -353.694353)
			(xy 165.646147 -353.708459) (xy 165.59071 -353.714559) (xy 165.534976 -353.712522) (xy 165.480133 -353.702392)
			(xy 165.427349 -353.684385) (xy 165.377749 -353.658884) (xy 165.332391 -353.626433) (xy 165.292242 -353.587724)
			(xy 165.258156 -353.543581) (xy 165.23086 -353.494946) (xy 165.210937 -353.442855) (xy 165.198811 -353.388418)
			(xy 165.19474 -353.332796) (xy 160.219895 -353.332796) (xy 160.222231 -353.333053) (xy 160.276188 -353.347159)
			(xy 160.327517 -353.368971) (xy 160.375123 -353.398025) (xy 160.417991 -353.4337) (xy 160.455208 -353.475237)
			(xy 160.485981 -353.52175) (xy 160.509653 -353.572247) (xy 160.525721 -353.625654) (xy 160.533841 -353.68083)
			(xy 160.53435 -353.708716) (xy 160.533841 -353.736602) (xy 160.525721 -353.791778) (xy 160.509653 -353.845185)
			(xy 160.485981 -353.895682) (xy 160.471544 -353.917504) (xy 161.123628 -353.917504) (xy 161.127699 -353.861882)
			(xy 161.139825 -353.807445) (xy 161.159748 -353.755354) (xy 161.187044 -353.706719) (xy 161.22113 -353.662576)
			(xy 161.261279 -353.623867) (xy 161.306637 -353.591416) (xy 161.356237 -353.565915) (xy 161.409021 -353.547908)
			(xy 161.463864 -353.537778) (xy 161.519598 -353.535741) (xy 161.575035 -353.541841) (xy 161.628992 -353.555947)
			(xy 161.680321 -353.577759) (xy 161.727927 -353.606813) (xy 161.770795 -353.642488) (xy 161.808012 -353.684025)
			(xy 161.838785 -353.730538) (xy 161.862457 -353.781035) (xy 161.878525 -353.834442) (xy 161.886645 -353.889618)
			(xy 161.887154 -353.917504) (xy 161.886645 -353.94539) (xy 161.878525 -354.000566) (xy 161.862457 -354.053973)
			(xy 161.838785 -354.10447) (xy 161.808012 -354.150983) (xy 161.780294 -354.181918) (xy 179.813202 -354.181918)
			(xy 179.817273 -354.126296) (xy 179.829399 -354.071859) (xy 179.849322 -354.019768) (xy 179.876618 -353.971133)
			(xy 179.910704 -353.92699) (xy 179.950853 -353.888281) (xy 179.996211 -353.85583) (xy 180.045811 -353.830329)
			(xy 180.098595 -353.812322) (xy 180.153438 -353.802192) (xy 180.209172 -353.800155) (xy 180.264609 -353.806255)
			(xy 180.318566 -353.820361) (xy 180.369895 -353.842173) (xy 180.417501 -353.871227) (xy 180.460369 -353.906902)
			(xy 180.497586 -353.948439) (xy 180.528359 -353.994952) (xy 180.552031 -354.045449) (xy 180.568099 -354.098856)
			(xy 180.576219 -354.154032) (xy 180.576728 -354.181918) (xy 180.576219 -354.209804) (xy 180.568099 -354.26498)
			(xy 180.552031 -354.318387) (xy 180.528359 -354.368884) (xy 180.497586 -354.415397) (xy 180.460369 -354.456934)
			(xy 180.417501 -354.492609) (xy 180.369895 -354.521663) (xy 180.318566 -354.543475) (xy 180.264609 -354.557581)
			(xy 180.209172 -354.563681) (xy 180.153438 -354.561644) (xy 180.098595 -354.551514) (xy 180.045811 -354.533507)
			(xy 179.996211 -354.508006) (xy 179.950853 -354.475555) (xy 179.910704 -354.436846) (xy 179.876618 -354.392703)
			(xy 179.849322 -354.344068) (xy 179.829399 -354.291977) (xy 179.817273 -354.23754) (xy 179.813202 -354.181918)
			(xy 161.780294 -354.181918) (xy 161.770795 -354.19252) (xy 161.727927 -354.228195) (xy 161.680321 -354.257249)
			(xy 161.628992 -354.279061) (xy 161.575035 -354.293167) (xy 161.519598 -354.299267) (xy 161.463864 -354.29723)
			(xy 161.409021 -354.2871) (xy 161.356237 -354.269093) (xy 161.306637 -354.243592) (xy 161.261279 -354.211141)
			(xy 161.22113 -354.172432) (xy 161.187044 -354.128289) (xy 161.159748 -354.079654) (xy 161.139825 -354.027563)
			(xy 161.127699 -353.973126) (xy 161.123628 -353.917504) (xy 160.471544 -353.917504) (xy 160.455208 -353.942195)
			(xy 160.417991 -353.983732) (xy 160.375123 -354.019407) (xy 160.327517 -354.048461) (xy 160.276188 -354.070273)
			(xy 160.222231 -354.084379) (xy 160.166794 -354.090479) (xy 160.11106 -354.088442) (xy 160.056217 -354.078312)
			(xy 160.003433 -354.060305) (xy 159.953833 -354.034804) (xy 159.908475 -354.002353) (xy 159.868326 -353.963644)
			(xy 159.83424 -353.919501) (xy 159.806944 -353.870866) (xy 159.787021 -353.818775) (xy 159.774895 -353.764338)
			(xy 159.770824 -353.708716) (xy 158.411153 -353.708716) (xy 158.434219 -353.757921) (xy 158.450287 -353.811328)
			(xy 158.458407 -353.866504) (xy 158.458916 -353.89439) (xy 158.458407 -353.922276) (xy 158.450287 -353.977452)
			(xy 158.434219 -354.030859) (xy 158.410547 -354.081356) (xy 158.379774 -354.127869) (xy 158.342557 -354.169406)
			(xy 158.299689 -354.205081) (xy 158.252083 -354.234135) (xy 158.200754 -354.255947) (xy 158.146797 -354.270053)
			(xy 158.09136 -354.276153) (xy 158.035626 -354.274116) (xy 157.980783 -354.263986) (xy 157.927999 -354.245979)
			(xy 157.878399 -354.220478) (xy 157.833041 -354.188027) (xy 157.792892 -354.149318) (xy 157.758806 -354.105175)
			(xy 157.73151 -354.05654) (xy 157.711587 -354.004449) (xy 157.699461 -353.950012) (xy 157.69539 -353.89439)
			(xy 154.8511 -353.89439) (xy 154.8511 -354.968302) (xy 176.841656 -354.968302) (xy 176.845727 -354.91268)
			(xy 176.857853 -354.858243) (xy 176.877776 -354.806152) (xy 176.905072 -354.757517) (xy 176.939158 -354.713374)
			(xy 176.979307 -354.674665) (xy 177.024665 -354.642214) (xy 177.074265 -354.616713) (xy 177.127049 -354.598706)
			(xy 177.181892 -354.588576) (xy 177.237626 -354.586539) (xy 177.293063 -354.592639) (xy 177.34702 -354.606745)
			(xy 177.398349 -354.628557) (xy 177.445955 -354.657611) (xy 177.488823 -354.693286) (xy 177.52604 -354.734823)
			(xy 177.556813 -354.781336) (xy 177.580485 -354.831833) (xy 177.596553 -354.88524) (xy 177.604673 -354.940416)
			(xy 177.605182 -354.968302) (xy 177.604834 -354.987352) (xy 179.031136 -354.987352) (xy 179.035207 -354.93173)
			(xy 179.047333 -354.877293) (xy 179.067256 -354.825202) (xy 179.094552 -354.776567) (xy 179.128638 -354.732424)
			(xy 179.168787 -354.693715) (xy 179.214145 -354.661264) (xy 179.263745 -354.635763) (xy 179.316529 -354.617756)
			(xy 179.371372 -354.607626) (xy 179.427106 -354.605589) (xy 179.482543 -354.611689) (xy 179.5365 -354.625795)
			(xy 179.587829 -354.647607) (xy 179.635435 -354.676661) (xy 179.678303 -354.712336) (xy 179.71552 -354.753873)
			(xy 179.746293 -354.800386) (xy 179.769965 -354.850883) (xy 179.786033 -354.90429) (xy 179.794153 -354.959466)
			(xy 179.794662 -354.987352) (xy 179.794153 -355.015238) (xy 179.786033 -355.070414) (xy 179.769965 -355.123821)
			(xy 179.746293 -355.174318) (xy 179.71552 -355.220831) (xy 179.678303 -355.262368) (xy 179.635435 -355.298043)
			(xy 179.587829 -355.327097) (xy 179.5365 -355.348909) (xy 179.482543 -355.363015) (xy 179.427106 -355.369115)
			(xy 179.371372 -355.367078) (xy 179.316529 -355.356948) (xy 179.263745 -355.338941) (xy 179.214145 -355.31344)
			(xy 179.168787 -355.280989) (xy 179.128638 -355.24228) (xy 179.094552 -355.198137) (xy 179.067256 -355.149502)
			(xy 179.047333 -355.097411) (xy 179.035207 -355.042974) (xy 179.031136 -354.987352) (xy 177.604834 -354.987352)
			(xy 177.604673 -354.996188) (xy 177.596553 -355.051364) (xy 177.580485 -355.104771) (xy 177.556813 -355.155268)
			(xy 177.52604 -355.201781) (xy 177.488823 -355.243318) (xy 177.445955 -355.278993) (xy 177.398349 -355.308047)
			(xy 177.34702 -355.329859) (xy 177.293063 -355.343965) (xy 177.237626 -355.350065) (xy 177.181892 -355.348028)
			(xy 177.127049 -355.337898) (xy 177.074265 -355.319891) (xy 177.024665 -355.29439) (xy 176.979307 -355.261939)
			(xy 176.939158 -355.22323) (xy 176.905072 -355.179087) (xy 176.877776 -355.130452) (xy 176.857853 -355.078361)
			(xy 176.845727 -355.023924) (xy 176.841656 -354.968302) (xy 154.8511 -354.968302) (xy 154.8511 -355.48443)
			(xy 177.846988 -355.48443) (xy 177.851059 -355.428808) (xy 177.863185 -355.374371) (xy 177.883108 -355.32228)
			(xy 177.910404 -355.273645) (xy 177.94449 -355.229502) (xy 177.984639 -355.190793) (xy 178.029997 -355.158342)
			(xy 178.079597 -355.132841) (xy 178.132381 -355.114834) (xy 178.187224 -355.104704) (xy 178.242958 -355.102667)
			(xy 178.298395 -355.108767) (xy 178.352352 -355.122873) (xy 178.403681 -355.144685) (xy 178.451287 -355.173739)
			(xy 178.494155 -355.209414) (xy 178.531372 -355.250951) (xy 178.562145 -355.297464) (xy 178.585817 -355.347961)
			(xy 178.601885 -355.401368) (xy 178.610005 -355.456544) (xy 178.610514 -355.48443) (xy 178.610005 -355.512316)
			(xy 178.601885 -355.567492) (xy 178.585817 -355.620899) (xy 178.562145 -355.671396) (xy 178.531372 -355.717909)
			(xy 178.500013 -355.752908) (xy 180.572918 -355.752908) (xy 180.573405 -355.725433) (xy 180.581296 -355.671054)
			(xy 180.596916 -355.618371) (xy 180.61994 -355.568478) (xy 180.649892 -355.52241) (xy 180.66766 -355.501448)
			(xy 180.667914 -355.501194) (xy 180.673511 -355.494114) (xy 180.679751 -355.477192) (xy 180.680106 -355.468174)
			(xy 180.680106 -355.40061) (xy 180.679743 -355.391594) (xy 180.673499 -355.374677) (xy 180.667914 -355.36759)
			(xy 180.667406 -355.367082) (xy 180.649669 -355.346139) (xy 180.619787 -355.300105) (xy 180.596821 -355.250259)
			(xy 180.581247 -355.197633) (xy 180.573388 -355.143317) (xy 180.572918 -355.115876) (xy 180.573404 -355.088625)
			(xy 180.58116 -355.034677) (xy 180.596515 -354.982382) (xy 180.619157 -354.932805) (xy 180.648623 -354.886955)
			(xy 180.684314 -354.845764) (xy 180.725505 -354.810073) (xy 180.771355 -354.780607) (xy 180.820932 -354.757965)
			(xy 180.873227 -354.74261) (xy 180.927175 -354.734854) (xy 180.981677 -354.734854) (xy 181.035625 -354.74261)
			(xy 181.08792 -354.757965) (xy 181.137497 -354.780607) (xy 181.183347 -354.810073) (xy 181.224538 -354.845764)
			(xy 181.260229 -354.886955) (xy 181.289695 -354.932805) (xy 181.312337 -354.982382) (xy 181.327692 -355.034677)
			(xy 181.335448 -355.088625) (xy 181.335934 -355.115876) (xy 181.335425 -355.14335) (xy 181.327537 -355.197728)
			(xy 181.311922 -355.25041) (xy 181.309272 -355.256154) (xy 181.577661 -355.256154) (xy 181.577661 -355.201646)
			(xy 181.585419 -355.147692) (xy 181.600777 -355.095392) (xy 181.623423 -355.045809) (xy 181.652894 -354.999955)
			(xy 181.688592 -354.958762) (xy 181.729789 -354.923069) (xy 181.775646 -354.893602) (xy 181.825231 -354.870963)
			(xy 181.877533 -354.85561) (xy 181.931488 -354.847858) (xy 181.958742 -354.847398) (xy 181.958996 -354.847398)
			(xy 181.9842 -354.847791) (xy 182.034168 -354.854432) (xy 182.082823 -354.86761) (xy 182.129312 -354.887095)
			(xy 182.151274 -354.899468) (xy 182.16118 -354.90531) (xy 182.183024 -354.907342) (xy 182.277766 -354.873814)
			(xy 182.293514 -354.85832) (xy 182.297578 -354.847906) (xy 182.308279 -354.821132) (xy 182.336565 -354.770889)
			(xy 182.372094 -354.725479) (xy 182.414055 -354.685936) (xy 182.461492 -354.653162) (xy 182.513322 -354.627904)
			(xy 182.568365 -354.610738) (xy 182.625365 -354.602055) (xy 182.654194 -354.601526) (xy 182.681448 -354.601961)
			(xy 182.735402 -354.609718) (xy 182.787702 -354.625075) (xy 182.837285 -354.647719) (xy 182.88314 -354.67719)
			(xy 182.924333 -354.712887) (xy 182.960027 -354.754083) (xy 182.989494 -354.79994) (xy 183.012135 -354.849524)
			(xy 183.024857 -354.892864) (xy 185.165746 -354.892864) (xy 185.16624 -354.86529) (xy 185.174184 -354.810718)
			(xy 185.189903 -354.757858) (xy 185.213067 -354.707811) (xy 185.243196 -354.661621) (xy 185.27966 -354.62025)
			(xy 185.300366 -354.602034) (xy 185.308437 -354.594475) (xy 185.317791 -354.574466) (xy 185.3184 -354.563426)
			(xy 185.3184 -354.485702) (xy 185.31783 -354.474653) (xy 185.308466 -354.454632) (xy 185.300366 -354.447094)
			(xy 185.279642 -354.428897) (xy 185.243174 -354.387524) (xy 185.213044 -354.341331) (xy 185.189881 -354.291281)
			(xy 185.174167 -354.238416) (xy 185.16623 -354.183839) (xy 185.165746 -354.156264) (xy 185.166244 -354.129014)
			(xy 185.174004 -354.075069) (xy 185.189362 -354.022777) (xy 185.212004 -353.973203) (xy 185.241469 -353.927355)
			(xy 185.277159 -353.886166) (xy 185.318347 -353.850476) (xy 185.364194 -353.821009) (xy 185.413768 -353.798365)
			(xy 185.466059 -353.783007) (xy 185.520004 -353.775245) (xy 185.547254 -353.774756) (xy 185.547762 -353.774756)
			(xy 185.581544 -353.77628) (xy 185.591704 -353.777296) (xy 185.611008 -353.7712) (xy 185.674 -353.718368)
			(xy 185.681282 -353.711637) (xy 185.690568 -353.694138) (xy 185.692034 -353.684332) (xy 185.692034 -353.68357)
			(xy 185.695048 -353.65543) (xy 185.708241 -353.600398) (xy 185.729422 -353.547919) (xy 185.758125 -353.499147)
			(xy 185.793721 -353.455152) (xy 185.835427 -353.4169) (xy 185.882328 -353.385232) (xy 185.933394 -353.360842)
			(xy 185.987504 -353.344266) (xy 186.043469 -353.335869) (xy 186.071764 -353.335336) (xy 186.072018 -353.335336)
			(xy 186.090037 -353.335559) (xy 186.125912 -353.338992) (xy 186.143646 -353.342194) (xy 186.153298 -353.343972)
			(xy 186.172348 -353.340416) (xy 186.247278 -353.29241) (xy 186.258708 -353.276662) (xy 186.260994 -353.267264)
			(xy 186.268418 -353.240228) (xy 186.290044 -353.188502) (xy 186.319005 -353.140498) (xy 186.354678 -353.097246)
			(xy 186.396293 -353.059678) (xy 186.442958 -353.028603) (xy 186.493666 -353.004689) (xy 186.547327 -352.98845)
			(xy 186.602786 -352.980236) (xy 186.630818 -352.979736) (xy 186.658073 -352.980138) (xy 186.712029 -352.987899)
			(xy 186.764331 -353.003259) (xy 186.813914 -353.025907) (xy 186.859769 -353.055381) (xy 186.900963 -353.091081)
			(xy 186.936656 -353.132281) (xy 186.966123 -353.178141) (xy 186.988762 -353.227728) (xy 187.004114 -353.280032)
			(xy 187.011866 -353.333989) (xy 187.012326 -353.361244) (xy 187.011813 -353.388817) (xy 187.003869 -353.443387)
			(xy 186.988152 -353.496246) (xy 186.964991 -353.546292) (xy 186.934868 -353.592482) (xy 186.898409 -353.633856)
			(xy 186.877706 -353.652074) (xy 186.869643 -353.65964) (xy 186.860282 -353.679643) (xy 186.859672 -353.690682)
			(xy 186.859672 -353.768406) (xy 186.86027 -353.779452) (xy 186.869612 -353.799475) (xy 186.877706 -353.807014)
			(xy 186.898428 -353.825213) (xy 186.934897 -353.866584) (xy 186.965028 -353.912777) (xy 186.988192 -353.962827)
			(xy 187.003906 -354.015692) (xy 187.011842 -354.070269) (xy 187.012326 -354.097844) (xy 187.011813 -354.125417)
			(xy 187.003869 -354.179987) (xy 186.995742 -354.207318) (xy 188.13983 -354.207318) (xy 188.143901 -354.151696)
			(xy 188.156027 -354.097259) (xy 188.17595 -354.045168) (xy 188.203246 -353.996533) (xy 188.237332 -353.95239)
			(xy 188.277481 -353.913681) (xy 188.322839 -353.88123) (xy 188.372439 -353.855729) (xy 188.425223 -353.837722)
			(xy 188.480066 -353.827592) (xy 188.5358 -353.825555) (xy 188.591237 -353.831655) (xy 188.645194 -353.845761)
			(xy 188.696523 -353.867573) (xy 188.744129 -353.896627) (xy 188.786997 -353.932302) (xy 188.824214 -353.973839)
			(xy 188.854987 -354.020352) (xy 188.878659 -354.070849) (xy 188.894727 -354.124256) (xy 188.902847 -354.179432)
			(xy 188.903356 -354.207318) (xy 188.902847 -354.235204) (xy 188.894727 -354.29038) (xy 188.878659 -354.343787)
			(xy 188.854987 -354.394284) (xy 188.824214 -354.440797) (xy 188.786997 -354.482334) (xy 188.744129 -354.518009)
			(xy 188.696523 -354.547063) (xy 188.645194 -354.568875) (xy 188.591237 -354.582981) (xy 188.5358 -354.589081)
			(xy 188.480066 -354.587044) (xy 188.425223 -354.576914) (xy 188.372439 -354.558907) (xy 188.322839 -354.533406)
			(xy 188.277481 -354.500955) (xy 188.237332 -354.462246) (xy 188.203246 -354.418103) (xy 188.17595 -354.369468)
			(xy 188.156027 -354.317377) (xy 188.143901 -354.26294) (xy 188.13983 -354.207318) (xy 186.995742 -354.207318)
			(xy 186.988152 -354.232846) (xy 186.964991 -354.282892) (xy 186.934868 -354.329082) (xy 186.898409 -354.370456)
			(xy 186.877706 -354.388674) (xy 186.869643 -354.39624) (xy 186.860282 -354.416243) (xy 186.859672 -354.427282)
			(xy 186.859672 -354.505006) (xy 186.86027 -354.516052) (xy 186.869612 -354.536075) (xy 186.877706 -354.543614)
			(xy 186.898428 -354.561813) (xy 186.934897 -354.603184) (xy 186.965028 -354.649377) (xy 186.988192 -354.699427)
			(xy 187.003906 -354.752292) (xy 187.011842 -354.806869) (xy 187.012326 -354.834444) (xy 187.011863 -354.861696)
			(xy 187.004101 -354.915643) (xy 186.988741 -354.967937) (xy 186.966096 -355.017513) (xy 186.936627 -355.063363)
			(xy 186.902567 -355.102668) (xy 187.56071 -355.102668) (xy 187.564781 -355.047046) (xy 187.576907 -354.992609)
			(xy 187.59683 -354.940518) (xy 187.624126 -354.891883) (xy 187.658212 -354.84774) (xy 187.698361 -354.809031)
			(xy 187.743719 -354.77658) (xy 187.793319 -354.751079) (xy 187.846103 -354.733072) (xy 187.900946 -354.722942)
			(xy 187.95668 -354.720905) (xy 188.012117 -354.727005) (xy 188.066074 -354.741111) (xy 188.117403 -354.762923)
			(xy 188.165009 -354.791977) (xy 188.207877 -354.827652) (xy 188.245094 -354.869189) (xy 188.275867 -354.915702)
			(xy 188.299539 -354.966199) (xy 188.315607 -355.019606) (xy 188.323727 -355.074782) (xy 188.324236 -355.102668)
			(xy 188.323727 -355.130554) (xy 188.315607 -355.18573) (xy 188.299539 -355.239137) (xy 188.275867 -355.289634)
			(xy 188.245094 -355.336147) (xy 188.207877 -355.377684) (xy 188.165009 -355.413359) (xy 188.117403 -355.442413)
			(xy 188.066074 -355.464225) (xy 188.012117 -355.478331) (xy 187.95668 -355.484431) (xy 187.900946 -355.482394)
			(xy 187.846103 -355.472264) (xy 187.793319 -355.454257) (xy 187.743719 -355.428756) (xy 187.698361 -355.396305)
			(xy 187.658212 -355.357596) (xy 187.624126 -355.313453) (xy 187.59683 -355.264818) (xy 187.576907 -355.212727)
			(xy 187.564781 -355.15829) (xy 187.56071 -355.102668) (xy 186.902567 -355.102668) (xy 186.900934 -355.104552)
			(xy 186.859742 -355.140243) (xy 186.813891 -355.169709) (xy 186.764313 -355.19235) (xy 186.712018 -355.207707)
			(xy 186.65807 -355.215465) (xy 186.630818 -355.215952) (xy 186.602962 -355.215448) (xy 186.547844 -355.207326)
			(xy 186.494491 -355.19128) (xy 186.444036 -355.167652) (xy 186.397551 -355.136943) (xy 186.356021 -355.099805)
			(xy 186.320329 -355.057026) (xy 186.291232 -355.009514) (xy 186.269348 -354.958279) (xy 186.261756 -354.931472)
			(xy 186.25947 -354.922582) (xy 186.248802 -354.907342) (xy 186.17692 -354.85959) (xy 186.158886 -354.855526)
			(xy 186.149742 -354.856796) (xy 186.136726 -354.858469) (xy 186.110541 -354.860246) (xy 186.097418 -354.860352)
			(xy 186.083269 -354.860256) (xy 186.055046 -354.858223) (xy 186.04103 -354.856288) (xy 186.031124 -354.854764)
			(xy 186.011312 -354.85959) (xy 185.93689 -354.91547) (xy 185.92673 -354.932996) (xy 185.92546 -354.943156)
			(xy 185.921339 -354.970304) (xy 185.906367 -355.023131) (xy 185.883977 -355.073266) (xy 185.854633 -355.119675)
			(xy 185.818939 -355.161398) (xy 185.777633 -355.197574) (xy 185.731569 -355.227457) (xy 185.681697 -355.250428)
			(xy 185.629048 -355.266013) (xy 185.574708 -355.273891) (xy 185.547254 -355.274372) (xy 185.52 -355.273965)
			(xy 185.466048 -355.266201) (xy 185.413749 -355.250838) (xy 185.364169 -355.228189) (xy 185.318317 -355.198715)
			(xy 185.277127 -355.163015) (xy 185.241436 -355.121817) (xy 185.211971 -355.075959) (xy 185.189333 -355.026374)
			(xy 185.173981 -354.974072) (xy 185.166229 -354.920118) (xy 185.165746 -354.892864) (xy 183.024857 -354.892864)
			(xy 183.027488 -354.901825) (xy 183.035241 -354.95578) (xy 183.035702 -354.983034) (xy 183.03504 -355.014597)
			(xy 183.024654 -355.076862) (xy 183.004169 -355.136571) (xy 182.989728 -355.164644) (xy 182.984902 -355.173534)
			(xy 182.98287 -355.193092) (xy 183.00573 -355.271578) (xy 183.008976 -355.280999) (xy 183.021387 -355.29656)
			(xy 183.02986 -355.301804) (xy 183.054938 -355.31639) (xy 183.100822 -355.351886) (xy 183.140799 -355.393923)
			(xy 183.173948 -355.44153) (xy 183.199503 -355.493609) (xy 183.216874 -355.548959) (xy 183.22566 -355.6063)
			(xy 183.226202 -355.635306) (xy 183.225716 -355.662557) (xy 183.21796 -355.716505) (xy 183.202605 -355.7688)
			(xy 183.198263 -355.778308) (xy 188.899546 -355.778308) (xy 188.900026 -355.750833) (xy 188.907918 -355.696453)
			(xy 188.923539 -355.64377) (xy 188.946565 -355.593877) (xy 188.976519 -355.547809) (xy 188.994288 -355.526848)
			(xy 188.994542 -355.526594) (xy 189.000142 -355.519517) (xy 189.00638 -355.502593) (xy 189.006734 -355.493574)
			(xy 189.006734 -355.42601) (xy 189.006365 -355.416995) (xy 189.000125 -355.400078) (xy 188.994542 -355.39299)
			(xy 188.994034 -355.392482) (xy 188.976301 -355.371535) (xy 188.946418 -355.325503) (xy 188.923451 -355.275658)
			(xy 188.907876 -355.223033) (xy 188.900016 -355.168717) (xy 188.899546 -355.141276) (xy 188.900032 -355.114025)
			(xy 188.907788 -355.060077) (xy 188.923143 -355.007782) (xy 188.945785 -354.958205) (xy 188.975251 -354.912355)
			(xy 189.010942 -354.871164) (xy 189.052133 -354.835473) (xy 189.097983 -354.806007) (xy 189.14756 -354.783365)
			(xy 189.199855 -354.76801) (xy 189.253803 -354.760254) (xy 189.308305 -354.760254) (xy 189.362253 -354.76801)
			(xy 189.414548 -354.783365) (xy 189.464125 -354.806007) (xy 189.509975 -354.835473) (xy 189.551166 -354.871164)
			(xy 189.586857 -354.912355) (xy 189.616323 -354.958205) (xy 189.638965 -355.007782) (xy 189.65432 -355.060077)
			(xy 189.662076 -355.114025) (xy 189.662562 -355.141276) (xy 189.662071 -355.168751) (xy 189.654182 -355.22313)
			(xy 189.638563 -355.275813) (xy 189.635916 -355.281549) (xy 189.904384 -355.281549) (xy 189.904384 -355.227051)
			(xy 189.912139 -355.173106) (xy 189.927493 -355.120815) (xy 189.950131 -355.07124) (xy 189.979594 -355.025392)
			(xy 190.015282 -354.984203) (xy 190.056468 -354.948512) (xy 190.102314 -354.919046) (xy 190.151887 -354.896403)
			(xy 190.204177 -354.881046) (xy 190.258121 -354.873286) (xy 190.28537 -354.872798) (xy 190.285624 -354.872798)
			(xy 190.310828 -354.873179) (xy 190.360797 -354.879823) (xy 190.409452 -354.893005) (xy 190.455941 -354.912493)
			(xy 190.477902 -354.924868) (xy 190.487808 -354.93071) (xy 190.509652 -354.932742) (xy 190.604394 -354.899214)
			(xy 190.620142 -354.88372) (xy 190.624206 -354.873306) (xy 190.634884 -354.846522) (xy 190.663173 -354.796278)
			(xy 190.698704 -354.750867) (xy 190.740669 -354.711325) (xy 190.788109 -354.678551) (xy 190.839943 -354.653295)
			(xy 190.894989 -354.636132) (xy 190.951992 -354.627453) (xy 190.980822 -354.626926) (xy 191.008077 -354.627335)
			(xy 191.062032 -354.635095) (xy 191.114333 -354.650456) (xy 191.163915 -354.673103) (xy 191.20977 -354.702577)
			(xy 191.250963 -354.738276) (xy 191.286657 -354.779475) (xy 191.316123 -354.825334) (xy 191.338764 -354.87492)
			(xy 191.351487 -354.918264) (xy 193.492374 -354.918264) (xy 193.492893 -354.890691) (xy 193.500836 -354.836121)
			(xy 193.516551 -354.783263) (xy 193.539711 -354.733217) (xy 193.569834 -354.687026) (xy 193.606292 -354.645652)
			(xy 193.626994 -354.627434) (xy 193.635054 -354.619864) (xy 193.644417 -354.599864) (xy 193.645028 -354.588826)
			(xy 193.645028 -354.511102) (xy 193.644481 -354.500049) (xy 193.635103 -354.480027) (xy 193.626994 -354.472494)
			(xy 193.606276 -354.454291) (xy 193.569806 -354.41292) (xy 193.539675 -354.366729) (xy 193.516511 -354.316679)
			(xy 193.500796 -354.263815) (xy 193.492858 -354.209239) (xy 193.492374 -354.181664) (xy 193.492844 -354.154413)
			(xy 193.500605 -354.100465) (xy 193.515964 -354.048171) (xy 193.538608 -353.998595) (xy 193.568076 -353.952746)
			(xy 193.603769 -353.911557) (xy 193.64496 -353.875866) (xy 193.690811 -353.846399) (xy 193.740388 -353.823758)
			(xy 193.792683 -353.808401) (xy 193.846631 -353.800643) (xy 193.873882 -353.800156) (xy 193.87439 -353.800156)
			(xy 193.908172 -353.80168) (xy 193.918332 -353.802696) (xy 193.937636 -353.7966) (xy 194.000628 -353.743768)
			(xy 194.007915 -353.737041) (xy 194.017198 -353.719539) (xy 194.018662 -353.709732) (xy 194.018662 -353.70897)
			(xy 194.021649 -353.680826) (xy 194.034843 -353.625792) (xy 194.056026 -353.573311) (xy 194.084732 -353.524538)
			(xy 194.120331 -353.480542) (xy 194.16204 -353.44229) (xy 194.208945 -353.410622) (xy 194.260014 -353.386234)
			(xy 194.314127 -353.369661) (xy 194.370095 -353.361267) (xy 194.398392 -353.360736) (xy 194.398646 -353.360736)
			(xy 194.416665 -353.360955) (xy 194.45254 -353.364391) (xy 194.470274 -353.367594) (xy 194.479926 -353.369372)
			(xy 194.498976 -353.365816) (xy 194.573906 -353.31781) (xy 194.585336 -353.302062) (xy 194.587622 -353.292664)
			(xy 194.59502 -353.26562) (xy 194.616649 -353.213893) (xy 194.645613 -353.165887) (xy 194.681288 -353.122635)
			(xy 194.722907 -353.085068) (xy 194.769575 -353.053993) (xy 194.820286 -353.030081) (xy 194.873951 -353.013845)
			(xy 194.929413 -353.005634) (xy 194.957446 -353.005136) (xy 194.9847 -353.005535) (xy 195.038654 -353.013299)
			(xy 195.090953 -353.028662) (xy 195.140533 -353.051312) (xy 195.186385 -353.080787) (xy 195.227576 -353.116488)
			(xy 195.263267 -353.157687) (xy 195.292731 -353.203546) (xy 195.315369 -353.253132) (xy 195.33072 -353.305435)
			(xy 195.338471 -353.35939) (xy 195.338954 -353.386644) (xy 195.338466 -353.414218) (xy 195.33052 -353.46879)
			(xy 195.314801 -353.521651) (xy 195.291635 -353.571697) (xy 195.261506 -353.617887) (xy 195.22504 -353.659258)
			(xy 195.204334 -353.677474) (xy 195.196259 -353.685029) (xy 195.186907 -353.705041) (xy 195.1863 -353.716082)
			(xy 195.1863 -353.793806) (xy 195.18692 -353.804849) (xy 195.196249 -353.824871) (xy 195.204334 -353.832414)
			(xy 195.225062 -353.850607) (xy 195.261529 -353.89198) (xy 195.291659 -353.938174) (xy 195.314821 -353.988226)
			(xy 195.330534 -354.041091) (xy 195.33847 -354.095668) (xy 195.338954 -354.123244) (xy 195.338466 -354.150818)
			(xy 195.33052 -354.20539) (xy 195.314801 -354.258251) (xy 195.291635 -354.308297) (xy 195.261506 -354.354487)
			(xy 195.22504 -354.395858) (xy 195.204334 -354.414074) (xy 195.196259 -354.421629) (xy 195.186907 -354.441641)
			(xy 195.1863 -354.452682) (xy 195.1863 -354.530406) (xy 195.18692 -354.541449) (xy 195.196249 -354.561471)
			(xy 195.204334 -354.569014) (xy 195.225062 -354.587207) (xy 195.261529 -354.62858) (xy 195.291659 -354.674774)
			(xy 195.314821 -354.724826) (xy 195.330534 -354.777691) (xy 195.33847 -354.832268) (xy 195.338954 -354.859844)
			(xy 195.338463 -354.887094) (xy 195.330702 -354.941039) (xy 195.315344 -354.993331) (xy 195.292701 -355.042906)
			(xy 195.263234 -355.088753) (xy 195.227543 -355.129942) (xy 195.186355 -355.165633) (xy 195.140507 -355.1951)
			(xy 195.090933 -355.217743) (xy 195.038641 -355.233102) (xy 194.984696 -355.240863) (xy 194.957446 -355.241352)
			(xy 194.92959 -355.240823) (xy 194.874473 -355.232705) (xy 194.821121 -355.216663) (xy 194.770667 -355.193038)
			(xy 194.724181 -355.162332) (xy 194.682651 -355.125197) (xy 194.646958 -355.082421) (xy 194.617861 -355.034911)
			(xy 194.595976 -354.983678) (xy 194.588384 -354.956872) (xy 194.586098 -354.947982) (xy 194.57543 -354.932742)
			(xy 194.503548 -354.88499) (xy 194.485514 -354.880926) (xy 194.47637 -354.882196) (xy 194.463354 -354.883866)
			(xy 194.437169 -354.885645) (xy 194.424046 -354.885752) (xy 194.409897 -354.885653) (xy 194.381674 -354.883622)
			(xy 194.367658 -354.881688) (xy 194.357752 -354.880164) (xy 194.33794 -354.88499) (xy 194.263518 -354.94087)
			(xy 194.253358 -354.958396) (xy 194.252088 -354.968556) (xy 194.248037 -354.995716) (xy 194.233061 -355.048548)
			(xy 194.210665 -355.098688) (xy 194.181314 -355.1451) (xy 194.145612 -355.186825) (xy 194.104298 -355.223001)
			(xy 194.058225 -355.252881) (xy 194.008344 -355.275848) (xy 193.955686 -355.291427) (xy 193.901339 -355.299296)
			(xy 193.873882 -355.299772) (xy 193.846627 -355.299362) (xy 193.792672 -355.291601) (xy 193.740371 -355.276241)
			(xy 193.690789 -355.253594) (xy 193.644934 -355.224121) (xy 193.60374 -355.188421) (xy 193.568047 -355.147223)
			(xy 193.53858 -355.101364) (xy 193.51594 -355.051778) (xy 193.500587 -354.999475) (xy 193.492834 -354.945519)
			(xy 193.492374 -354.918264) (xy 191.351487 -354.918264) (xy 191.354117 -354.927223) (xy 191.361869 -354.981179)
			(xy 191.36233 -355.008434) (xy 191.361665 -355.039996) (xy 191.351279 -355.102261) (xy 191.330796 -355.161971)
			(xy 191.316356 -355.190044) (xy 191.31153 -355.198934) (xy 191.309498 -355.218492) (xy 191.332358 -355.296978)
			(xy 191.335594 -355.306404) (xy 191.348012 -355.321963) (xy 191.356488 -355.327204) (xy 191.381573 -355.34178)
			(xy 191.427455 -355.377278) (xy 191.467431 -355.419317) (xy 191.500578 -355.466927) (xy 191.526132 -355.519007)
			(xy 191.543502 -355.574357) (xy 191.552288 -355.6317) (xy 191.55283 -355.660706) (xy 191.552344 -355.687957)
			(xy 191.544588 -355.741905) (xy 191.529233 -355.7942) (xy 191.506591 -355.843777) (xy 191.477125 -355.889627)
			(xy 191.441434 -355.930818) (xy 191.400243 -355.966509) (xy 191.354393 -355.995975) (xy 191.304816 -356.018617)
			(xy 191.252521 -356.033972) (xy 191.198573 -356.041728) (xy 191.144071 -356.041728) (xy 191.090123 -356.033972)
			(xy 191.037828 -356.018617) (xy 190.988251 -355.995975) (xy 190.942401 -355.966509) (xy 190.90121 -355.930818)
			(xy 190.865519 -355.889627) (xy 190.836053 -355.843777) (xy 190.813411 -355.7942) (xy 190.798056 -355.741905)
			(xy 190.7903 -355.687957) (xy 190.789814 -355.660706) (xy 190.79045 -355.629142) (xy 190.800847 -355.566876)
			(xy 190.821342 -355.507168) (xy 190.835788 -355.479096) (xy 190.840614 -355.470206) (xy 190.842646 -355.450648)
			(xy 190.819786 -355.372162) (xy 190.816558 -355.362734) (xy 190.804133 -355.347177) (xy 190.795656 -355.341936)
			(xy 190.78829 -355.337872) (xy 190.778384 -355.33203) (xy 190.75654 -355.329998) (xy 190.661798 -355.363526)
			(xy 190.64605 -355.37902) (xy 190.641986 -355.389434) (xy 190.631336 -355.41623) (xy 190.603042 -355.466472)
			(xy 190.567505 -355.511882) (xy 190.525536 -355.551423) (xy 190.478092 -355.584194) (xy 190.426255 -355.609449)
			(xy 190.371206 -355.62661) (xy 190.314201 -355.635287) (xy 190.28537 -355.635814) (xy 190.258121 -355.635314)
			(xy 190.204177 -355.627554) (xy 190.151887 -355.612197) (xy 190.102314 -355.589554) (xy 190.056468 -355.560088)
			(xy 190.015282 -355.524397) (xy 189.979594 -355.483208) (xy 189.950131 -355.43736) (xy 189.927493 -355.387785)
			(xy 189.912139 -355.335494) (xy 189.904384 -355.281549) (xy 189.635916 -355.281549) (xy 189.615539 -355.325706)
			(xy 189.585588 -355.371774) (xy 189.56782 -355.392736) (xy 189.567566 -355.39299) (xy 189.561974 -355.400072)
			(xy 189.555732 -355.416993) (xy 189.555374 -355.42601) (xy 189.555374 -355.493574) (xy 189.555749 -355.502589)
			(xy 189.561985 -355.519506) (xy 189.567566 -355.526594) (xy 189.568074 -355.527102) (xy 189.5858 -355.548054)
			(xy 189.615685 -355.594085) (xy 189.638653 -355.643928) (xy 189.654229 -355.696553) (xy 189.662091 -355.750867)
			(xy 189.662562 -355.778308) (xy 189.662076 -355.805559) (xy 189.65432 -355.859507) (xy 189.638965 -355.911802)
			(xy 189.616323 -355.961379) (xy 189.586857 -356.007229) (xy 189.551166 -356.04842) (xy 189.509975 -356.084111)
			(xy 189.464125 -356.113577) (xy 189.414548 -356.136219) (xy 189.362253 -356.151574) (xy 189.308305 -356.15933)
			(xy 189.253803 -356.15933) (xy 189.199855 -356.151574) (xy 189.14756 -356.136219) (xy 189.097983 -356.113577)
			(xy 189.052133 -356.084111) (xy 189.010942 -356.04842) (xy 188.975251 -356.007229) (xy 188.945785 -355.961379)
			(xy 188.923143 -355.911802) (xy 188.907788 -355.859507) (xy 188.900032 -355.805559) (xy 188.899546 -355.778308)
			(xy 183.198263 -355.778308) (xy 183.179963 -355.818377) (xy 183.150497 -355.864227) (xy 183.114806 -355.905418)
			(xy 183.073615 -355.941109) (xy 183.027765 -355.970575) (xy 182.978188 -355.993217) (xy 182.925893 -356.008572)
			(xy 182.871945 -356.016328) (xy 182.817443 -356.016328) (xy 182.763495 -356.008572) (xy 182.7112 -355.993217)
			(xy 182.661623 -355.970575) (xy 182.615773 -355.941109) (xy 182.574582 -355.905418) (xy 182.538891 -355.864227)
			(xy 182.509425 -355.818377) (xy 182.486783 -355.7688) (xy 182.471428 -355.716505) (xy 182.463672 -355.662557)
			(xy 182.463186 -355.635306) (xy 182.463826 -355.603742) (xy 182.474222 -355.541477) (xy 182.494715 -355.481768)
			(xy 182.50916 -355.453696) (xy 182.513986 -355.444806) (xy 182.516018 -355.425248) (xy 182.493158 -355.346762)
			(xy 182.48994 -355.337329) (xy 182.477508 -355.321774) (xy 182.469028 -355.316536) (xy 182.461662 -355.312472)
			(xy 182.451756 -355.30663) (xy 182.429912 -355.304598) (xy 182.33517 -355.338126) (xy 182.319422 -355.35362)
			(xy 182.315358 -355.364034) (xy 182.304648 -355.390804) (xy 182.276361 -355.441044) (xy 182.240832 -355.486452)
			(xy 182.198872 -355.525994) (xy 182.151437 -355.558768) (xy 182.099608 -355.584027) (xy 182.044568 -355.601196)
			(xy 181.98757 -355.609882) (xy 181.958742 -355.610414) (xy 181.931488 -355.609942) (xy 181.877533 -355.60219)
			(xy 181.825231 -355.586837) (xy 181.775646 -355.564198) (xy 181.729789 -355.534731) (xy 181.688592 -355.499038)
			(xy 181.652894 -355.457845) (xy 181.623423 -355.411991) (xy 181.600777 -355.362408) (xy 181.585419 -355.310108)
			(xy 181.577661 -355.256154) (xy 181.309272 -355.256154) (xy 181.288903 -355.300303) (xy 181.258957 -355.346373)
			(xy 181.241192 -355.367336) (xy 181.240938 -355.36759) (xy 181.235342 -355.37467) (xy 181.229103 -355.391592)
			(xy 181.228746 -355.40061) (xy 181.228746 -355.468174) (xy 181.229106 -355.477191) (xy 181.23535 -355.494108)
			(xy 181.240938 -355.501194) (xy 181.241446 -355.501702) (xy 181.259168 -355.522658) (xy 181.289054 -355.568687)
			(xy 181.312023 -355.61853) (xy 181.327601 -355.671153) (xy 181.335463 -355.725468) (xy 181.335934 -355.752908)
			(xy 181.335448 -355.780159) (xy 181.327692 -355.834107) (xy 181.312337 -355.886402) (xy 181.289695 -355.935979)
			(xy 181.260229 -355.981829) (xy 181.224538 -356.02302) (xy 181.183347 -356.058711) (xy 181.137497 -356.088177)
			(xy 181.08792 -356.110819) (xy 181.035625 -356.126174) (xy 180.981677 -356.13393) (xy 180.927175 -356.13393)
			(xy 180.873227 -356.126174) (xy 180.820932 -356.110819) (xy 180.771355 -356.088177) (xy 180.725505 -356.058711)
			(xy 180.684314 -356.02302) (xy 180.648623 -355.981829) (xy 180.619157 -355.935979) (xy 180.596515 -355.886402)
			(xy 180.58116 -355.834107) (xy 180.573404 -355.780159) (xy 180.572918 -355.752908) (xy 178.500013 -355.752908)
			(xy 178.494155 -355.759446) (xy 178.451287 -355.795121) (xy 178.403681 -355.824175) (xy 178.352352 -355.845987)
			(xy 178.298395 -355.860093) (xy 178.242958 -355.866193) (xy 178.187224 -355.864156) (xy 178.132381 -355.854026)
			(xy 178.079597 -355.836019) (xy 178.029997 -355.810518) (xy 177.984639 -355.778067) (xy 177.94449 -355.739358)
			(xy 177.910404 -355.695215) (xy 177.883108 -355.64658) (xy 177.863185 -355.594489) (xy 177.851059 -355.540052)
			(xy 177.846988 -355.48443) (xy 154.8511 -355.48443) (xy 154.8511 -356.287324) (xy 154.851362 -356.294968)
			(xy 154.85589 -356.30957) (xy 154.85999 -356.316026) (xy 154.991054 -356.507288) (xy 154.997404 -356.514908)
			(xy 158.040832 -359.873296) (xy 158.044688 -359.87731) (xy 158.053786 -359.883721) (xy 158.058866 -359.885996)
			(xy 158.993486 -360.273153) (xy 172.666349 -360.273153) (xy 172.666349 -360.218646) (xy 172.674107 -360.164693)
			(xy 172.689463 -360.112394) (xy 172.712107 -360.062813) (xy 172.741576 -360.016959) (xy 172.777271 -359.975765)
			(xy 172.818465 -359.940071) (xy 172.86432 -359.910603) (xy 172.913902 -359.887961) (xy 172.966201 -359.872605)
			(xy 173.020154 -359.864849) (xy 173.074661 -359.86485) (xy 173.128613 -359.872608) (xy 173.180912 -359.887966)
			(xy 173.230493 -359.91061) (xy 173.276347 -359.94008) (xy 173.317539 -359.975776) (xy 173.353233 -360.016971)
			(xy 173.3827 -360.062826) (xy 173.405342 -360.112408) (xy 173.420696 -360.164708) (xy 173.428452 -360.21866)
			(xy 173.428914 -360.245914) (xy 173.428704 -360.263673) (xy 173.425396 -360.299036) (xy 173.42231 -360.316526)
			(xy 173.420715 -360.328459) (xy 173.427489 -360.351528) (xy 173.435264 -360.360722) (xy 173.499526 -360.429556)
			(xy 173.52264 -360.437684) (xy 173.534578 -360.43616) (xy 173.546215 -360.434823) (xy 173.5696 -360.433428)
			(xy 173.581314 -360.433366) (xy 173.608564 -360.433865) (xy 173.66251 -360.441622) (xy 173.714803 -360.456978)
			(xy 173.764379 -360.479619) (xy 173.810228 -360.509084) (xy 173.851417 -360.544774) (xy 173.887109 -360.585963)
			(xy 173.916575 -360.631811) (xy 173.939218 -360.681385) (xy 173.954575 -360.733678) (xy 173.962334 -360.787624)
			(xy 173.962822 -360.814874) (xy 173.962822 -360.815382) (xy 173.962411 -360.840282) (xy 173.955895 -360.889655)
			(xy 173.943011 -360.93776) (xy 173.933866 -360.960924) (xy 173.928532 -360.973624) (xy 173.932342 -361.000802)
			(xy 173.995842 -361.08132) (xy 174.001647 -361.088146) (xy 174.016888 -361.097548) (xy 174.034436 -361.101118)
			(xy 174.04334 -361.100116) (xy 174.043594 -361.100116) (xy 174.058542 -361.097863) (xy 174.088676 -361.095448)
			(xy 174.103792 -361.09529) (xy 174.131046 -361.095747) (xy 174.184998 -361.103503) (xy 174.237298 -361.118858)
			(xy 174.286879 -361.1415) (xy 174.332734 -361.170968) (xy 174.373929 -361.206662) (xy 174.409624 -361.247856)
			(xy 174.439093 -361.293709) (xy 174.461737 -361.343291) (xy 174.477094 -361.39559) (xy 174.484852 -361.449542)
			(xy 174.484853 -361.504049) (xy 174.477096 -361.558001) (xy 174.461741 -361.610301) (xy 174.439098 -361.659882)
			(xy 174.40963 -361.705737) (xy 174.373935 -361.746931) (xy 174.332742 -361.782626) (xy 174.286888 -361.812095)
			(xy 174.237306 -361.834738) (xy 174.185007 -361.850095) (xy 174.131055 -361.857853) (xy 174.076548 -361.857853)
			(xy 174.022595 -361.850096) (xy 173.970296 -361.834739) (xy 173.920715 -361.812096) (xy 173.87486 -361.782628)
			(xy 173.833667 -361.746933) (xy 173.797972 -361.705739) (xy 173.768503 -361.659885) (xy 173.74586 -361.610303)
			(xy 173.730504 -361.558004) (xy 173.722747 -361.504052) (xy 173.722284 -361.476798) (xy 173.722284 -361.47629)
			(xy 173.722717 -361.451391) (xy 173.729224 -361.402018) (xy 173.7421 -361.353913) (xy 173.75124 -361.330748)
			(xy 173.756574 -361.318048) (xy 173.752764 -361.29087) (xy 173.689264 -361.210352) (xy 173.683461 -361.203525)
			(xy 173.668218 -361.194125) (xy 173.65067 -361.190554) (xy 173.641766 -361.191556) (xy 173.641512 -361.191556)
			(xy 173.626564 -361.193808) (xy 173.59643 -361.196224) (xy 173.581314 -361.196382) (xy 173.55406 -361.195932)
			(xy 173.500108 -361.188176) (xy 173.447808 -361.17282) (xy 173.398226 -361.150177) (xy 173.352372 -361.120709)
			(xy 173.311178 -361.085013) (xy 173.275484 -361.043819) (xy 173.246017 -360.997963) (xy 173.223376 -360.948381)
			(xy 173.208022 -360.896081) (xy 173.200268 -360.842128) (xy 173.199806 -360.814874) (xy 173.200014 -360.797115)
			(xy 173.203323 -360.761752) (xy 173.20641 -360.744262) (xy 173.208034 -360.73233) (xy 173.201243 -360.709255)
			(xy 173.193456 -360.700066) (xy 173.129194 -360.631232) (xy 173.10608 -360.623104) (xy 173.094142 -360.624628)
			(xy 173.082505 -360.625963) (xy 173.05912 -360.62736) (xy 173.047406 -360.627422) (xy 173.020152 -360.626951)
			(xy 172.9662 -360.619195) (xy 172.913901 -360.603839) (xy 172.864319 -360.581196) (xy 172.818464 -360.551728)
			(xy 172.77727 -360.516034) (xy 172.741575 -360.47484) (xy 172.712106 -360.428986) (xy 172.689463 -360.379404)
			(xy 172.674106 -360.327105) (xy 172.666349 -360.273153) (xy 158.993486 -360.273153) (xy 164.626544 -362.60659)
			(xy 164.63123 -362.608394) (xy 164.641082 -362.610323) (xy 164.646102 -362.6104) (xy 165.645846 -362.6104)
			(xy 165.657377 -362.609848) (xy 165.678132 -362.599793) (xy 165.685724 -362.591096) (xy 165.735254 -362.528358)
			(xy 165.741795 -362.51891) (xy 165.746683 -362.496488) (xy 165.744652 -362.485178) (xy 165.739693 -362.463287)
			(xy 165.734341 -362.418721) (xy 165.733984 -362.396278) (xy 165.733984 -361.532678) (xy 165.73447 -361.505409)
			(xy 165.742232 -361.451425) (xy 165.757597 -361.399095) (xy 165.780254 -361.349485) (xy 165.80974 -361.303604)
			(xy 165.845455 -361.262387) (xy 165.886672 -361.226672) (xy 165.932553 -361.197186) (xy 165.982163 -361.174529)
			(xy 166.034493 -361.159164) (xy 166.088477 -361.151402) (xy 166.143015 -361.151402) (xy 166.196999 -361.159164)
			(xy 166.249329 -361.174529) (xy 166.298939 -361.197186) (xy 166.34482 -361.226672) (xy 166.386037 -361.262387)
			(xy 166.421752 -361.303604) (xy 166.451238 -361.349485) (xy 166.473895 -361.399095) (xy 166.48926 -361.451425)
			(xy 166.497022 -361.505409) (xy 166.497508 -361.532678) (xy 166.497508 -362.396278) (xy 166.495476 -362.433108)
			(xy 166.495476 -362.433616) (xy 166.49446 -362.444284) (xy 166.501064 -362.464096) (xy 166.558214 -362.528104)
			(xy 166.565681 -362.535612) (xy 166.584979 -362.544264) (xy 166.595552 -362.544868) (xy 166.621683 -362.54558)
			(xy 166.673389 -362.553269) (xy 166.723564 -362.567936) (xy 166.771271 -362.589307) (xy 166.793672 -362.60278)
			(xy 166.795471 -362.603809) (xy 174.761723 -362.603809) (xy 174.761729 -362.549315) (xy 174.769489 -362.495375)
			(xy 174.784847 -362.44309) (xy 174.80749 -362.393522) (xy 174.836956 -362.347681) (xy 174.872646 -362.306499)
			(xy 174.913833 -362.270816) (xy 174.95968 -362.241358) (xy 175.009252 -362.218724) (xy 175.06154 -362.203375)
			(xy 175.115481 -362.195624) (xy 175.169975 -362.195628) (xy 175.223915 -362.203387) (xy 175.276201 -362.218744)
			(xy 175.32577 -362.241385) (xy 175.371611 -362.27085) (xy 175.412794 -362.306539) (xy 175.448478 -362.347725)
			(xy 175.477937 -362.393571) (xy 175.500572 -362.443142) (xy 175.515922 -362.49543) (xy 175.523675 -362.549371)
			(xy 175.52416 -362.576618) (xy 175.52289 -362.607098) (xy 175.522589 -362.618125) (xy 175.530221 -362.638797)
			(xy 175.537622 -362.646976) (xy 175.60036 -362.709714) (xy 175.621188 -362.717334) (xy 175.63211 -362.716572)
			(xy 175.632618 -362.716572) (xy 175.663098 -362.715302) (xy 175.690349 -362.715776) (xy 175.744297 -362.723532)
			(xy 175.796592 -362.738887) (xy 175.846169 -362.761527) (xy 175.89202 -362.790993) (xy 175.933211 -362.826685)
			(xy 175.968903 -362.867875) (xy 175.998369 -362.913725) (xy 176.021011 -362.963302) (xy 176.036367 -363.015596)
			(xy 176.044124 -363.069544) (xy 176.044125 -363.124047) (xy 176.036369 -363.177994) (xy 176.021014 -363.230289)
			(xy 175.998374 -363.279867) (xy 175.968908 -363.325718) (xy 175.933217 -363.366909) (xy 175.892028 -363.402601)
			(xy 175.846178 -363.432068) (xy 175.796601 -363.45471) (xy 175.744306 -363.470066) (xy 175.690359 -363.477824)
			(xy 175.635856 -363.477825) (xy 175.581908 -363.470069) (xy 175.529613 -363.454715) (xy 175.480035 -363.432075)
			(xy 175.434184 -363.40261) (xy 175.392993 -363.366919) (xy 175.357301 -363.32573) (xy 175.327833 -363.27988)
			(xy 175.305191 -363.230303) (xy 175.289834 -363.178009) (xy 175.282076 -363.124061) (xy 175.28159 -363.09681)
			(xy 175.28286 -363.06633) (xy 175.283131 -363.055305) (xy 175.275518 -363.034635) (xy 175.268128 -363.026452)
			(xy 175.20539 -362.963714) (xy 175.184562 -362.956094) (xy 175.17364 -362.956856) (xy 175.173132 -362.956856)
			(xy 175.142652 -362.958126) (xy 175.115405 -362.95757) (xy 175.061466 -362.949808) (xy 175.00918 -362.934449)
			(xy 174.959613 -362.911805) (xy 174.913773 -362.882338) (xy 174.872592 -362.846647) (xy 174.83691 -362.805459)
			(xy 174.807453 -362.759612) (xy 174.784821 -362.710039) (xy 174.769473 -362.65775) (xy 174.761723 -362.603809)
			(xy 166.795471 -362.603809) (xy 166.799837 -362.606307) (xy 166.813497 -362.610172) (xy 166.820596 -362.6104)
			(xy 167.879522 -362.6104) (xy 167.88959 -362.610827) (xy 167.908189 -362.618547) (xy 167.91559 -362.625386)
			(xy 168.998392 -363.708188) (xy 170.730926 -363.708188) (xy 170.731412 -363.680937) (xy 170.739168 -363.626989)
			(xy 170.754523 -363.574694) (xy 170.777165 -363.525117) (xy 170.806631 -363.479267) (xy 170.842322 -363.438076)
			(xy 170.883513 -363.402385) (xy 170.929363 -363.372919) (xy 170.97894 -363.350277) (xy 171.031235 -363.334922)
			(xy 171.085183 -363.327166) (xy 171.139685 -363.327166) (xy 171.193633 -363.334922) (xy 171.245928 -363.350277)
			(xy 171.295505 -363.372919) (xy 171.341355 -363.402385) (xy 171.382546 -363.438076) (xy 171.418237 -363.479267)
			(xy 171.447703 -363.525117) (xy 171.470345 -363.574694) (xy 171.4857 -363.626989) (xy 171.493456 -363.680937)
			(xy 171.493942 -363.708188) (xy 171.493571 -363.732446) (xy 171.487408 -363.780568) (xy 171.475193 -363.827521)
			(xy 171.46651 -363.850174) (xy 171.461783 -363.862923) (xy 171.458616 -363.889922) (xy 171.462692 -363.916798)
			(xy 171.466041 -363.924342) (xy 179.856638 -363.924342) (xy 179.857119 -363.896972) (xy 179.864932 -363.842793)
			(xy 179.880417 -363.79029) (xy 179.903256 -363.740543) (xy 179.932978 -363.694576) (xy 179.950618 -363.673644)
			(xy 179.950872 -363.67339) (xy 179.956477 -363.666317) (xy 179.962711 -363.649389) (xy 179.963064 -363.64037)
			(xy 179.963064 -363.573314) (xy 179.962708 -363.564297) (xy 179.95646 -363.54738) (xy 179.950872 -363.540294)
			(xy 179.950618 -363.540294) (xy 179.950618 -363.54004) (xy 179.932987 -363.519101) (xy 179.903273 -363.473131)
			(xy 179.880436 -363.423385) (xy 179.864943 -363.370886) (xy 179.857113 -363.316711) (xy 179.856638 -363.289342)
			(xy 179.857119 -363.261768) (xy 179.865067 -363.207195) (xy 179.880788 -363.154335) (xy 179.903955 -363.104289)
			(xy 179.934085 -363.058099) (xy 179.970551 -363.016728) (xy 179.991258 -362.998512) (xy 179.999337 -362.990961)
			(xy 180.008687 -362.970946) (xy 180.009292 -362.959904) (xy 180.009292 -362.88218) (xy 180.008682 -362.871136)
			(xy 179.999347 -362.851114) (xy 179.991258 -362.843572) (xy 179.970522 -362.825388) (xy 179.934055 -362.784013)
			(xy 179.903927 -362.737817) (xy 179.880766 -362.687764) (xy 179.865055 -362.634897) (xy 179.857121 -362.580318)
			(xy 179.856638 -362.552742) (xy 179.857119 -362.525372) (xy 179.864932 -362.471193) (xy 179.880417 -362.41869)
			(xy 179.903256 -362.368943) (xy 179.932978 -362.322976) (xy 179.950618 -362.302044) (xy 179.950872 -362.30179)
			(xy 179.956477 -362.294717) (xy 179.962711 -362.277789) (xy 179.963064 -362.26877) (xy 179.963064 -362.201714)
			(xy 179.962708 -362.192697) (xy 179.95646 -362.17578) (xy 179.950872 -362.168694) (xy 179.950618 -362.168694)
			(xy 179.950618 -362.16844) (xy 179.933019 -362.147474) (xy 179.903293 -362.101512) (xy 179.880446 -362.051771)
			(xy 179.864947 -361.999274) (xy 179.857114 -361.9451) (xy 179.85711 -361.890363) (xy 179.864933 -361.836188)
			(xy 179.880423 -361.783689) (xy 179.903263 -361.733944) (xy 179.932981 -361.687977) (xy 179.950618 -361.667044)
			(xy 179.950872 -361.66679) (xy 179.956477 -361.659717) (xy 179.962711 -361.642789) (xy 179.963064 -361.63377)
			(xy 179.963064 -361.566714) (xy 179.962708 -361.557697) (xy 179.95646 -361.54078) (xy 179.950872 -361.533694)
			(xy 179.950618 -361.533694) (xy 179.950618 -361.53344) (xy 179.933019 -361.512474) (xy 179.903293 -361.466512)
			(xy 179.880446 -361.416771) (xy 179.864947 -361.364274) (xy 179.857114 -361.3101) (xy 179.85711 -361.255363)
			(xy 179.864933 -361.201188) (xy 179.880423 -361.148689) (xy 179.903263 -361.098944) (xy 179.932981 -361.052977)
			(xy 179.950618 -361.032044) (xy 179.950872 -361.03179) (xy 179.956477 -361.024717) (xy 179.962711 -361.007789)
			(xy 179.963064 -360.99877) (xy 179.963064 -360.931714) (xy 179.962708 -360.922697) (xy 179.95646 -360.90578)
			(xy 179.950872 -360.898694) (xy 179.950618 -360.898694) (xy 179.950618 -360.89844) (xy 179.932987 -360.877501)
			(xy 179.903273 -360.831531) (xy 179.880436 -360.781785) (xy 179.864943 -360.729286) (xy 179.857113 -360.675111)
			(xy 179.856638 -360.647742) (xy 179.857119 -360.620168) (xy 179.865067 -360.565595) (xy 179.880788 -360.512735)
			(xy 179.903955 -360.462689) (xy 179.934085 -360.416499) (xy 179.970551 -360.375128) (xy 179.991258 -360.356912)
			(xy 179.999337 -360.349361) (xy 180.008687 -360.329346) (xy 180.009292 -360.318304) (xy 180.009292 -360.24058)
			(xy 180.008682 -360.229536) (xy 179.999347 -360.209514) (xy 179.991258 -360.201972) (xy 179.970522 -360.183788)
			(xy 179.934055 -360.142413) (xy 179.903927 -360.096217) (xy 179.880766 -360.046164) (xy 179.865055 -359.993297)
			(xy 179.857121 -359.938718) (xy 179.856638 -359.911142) (xy 179.857119 -359.883772) (xy 179.864932 -359.829593)
			(xy 179.880417 -359.77709) (xy 179.903256 -359.727343) (xy 179.932978 -359.681376) (xy 179.950618 -359.660444)
			(xy 179.950872 -359.66019) (xy 179.956477 -359.653117) (xy 179.962711 -359.636189) (xy 179.963064 -359.62717)
			(xy 179.963064 -359.560114) (xy 179.962708 -359.551097) (xy 179.95646 -359.53418) (xy 179.950872 -359.527094)
			(xy 179.950618 -359.527094) (xy 179.950618 -359.52684) (xy 179.932987 -359.505901) (xy 179.903273 -359.459931)
			(xy 179.880436 -359.410185) (xy 179.864943 -359.357686) (xy 179.857113 -359.303511) (xy 179.856638 -359.276142)
			(xy 179.857095 -359.248888) (xy 179.864847 -359.194935) (xy 179.8802 -359.142634) (xy 179.902841 -359.093051)
			(xy 179.932309 -359.047195) (xy 179.968004 -359.006001) (xy 180.009198 -358.970306) (xy 180.055054 -358.940839)
			(xy 180.104637 -358.918199) (xy 180.156938 -358.902846) (xy 180.210892 -358.895094) (xy 180.238146 -358.894634)
			(xy 180.265515 -358.895123) (xy 180.319694 -358.902934) (xy 180.372197 -358.918418) (xy 180.421944 -358.941254)
			(xy 180.467912 -358.970975) (xy 180.488844 -358.988614) (xy 180.489098 -358.988868) (xy 180.496175 -358.994468)
			(xy 180.513099 -359.000705) (xy 180.522118 -359.00106) (xy 180.589174 -359.00106) (xy 180.598191 -359.000699)
			(xy 180.615108 -358.994455) (xy 180.622194 -358.988868) (xy 180.622194 -358.988614) (xy 180.622448 -358.988614)
			(xy 180.643381 -358.970973) (xy 180.689349 -358.941249) (xy 180.739095 -358.918403) (xy 180.791597 -358.902907)
			(xy 180.845775 -358.895078) (xy 180.900517 -358.895078) (xy 180.954695 -358.902907) (xy 181.007197 -358.918403)
			(xy 181.056943 -358.941249) (xy 181.102911 -358.970973) (xy 181.123844 -358.988614) (xy 181.124098 -358.988868)
			(xy 181.131175 -358.994468) (xy 181.148099 -359.000705) (xy 181.157118 -359.00106) (xy 181.224174 -359.00106)
			(xy 181.233191 -359.000699) (xy 181.250108 -358.994455) (xy 181.257194 -358.988868) (xy 181.257194 -358.988614)
			(xy 181.257448 -358.988614) (xy 181.278381 -358.970973) (xy 181.324349 -358.941249) (xy 181.374095 -358.918403)
			(xy 181.426597 -358.902907) (xy 181.480775 -358.895078) (xy 181.535517 -358.895078) (xy 181.589695 -358.902907)
			(xy 181.642197 -358.918403) (xy 181.691943 -358.941249) (xy 181.737911 -358.970973) (xy 181.758844 -358.988614)
			(xy 181.759098 -358.988868) (xy 181.766175 -358.994468) (xy 181.783099 -359.000705) (xy 181.792118 -359.00106)
			(xy 181.859174 -359.00106) (xy 181.868191 -359.000699) (xy 181.885108 -358.994455) (xy 181.892194 -358.988868)
			(xy 181.892194 -358.988614) (xy 181.892448 -358.988614) (xy 181.913391 -358.970988) (xy 181.95936 -358.941274)
			(xy 182.009105 -358.918435) (xy 182.061604 -358.902941) (xy 182.115778 -358.89511) (xy 182.143146 -358.894634)
			(xy 182.1704 -358.895035) (xy 182.224353 -358.902799) (xy 182.276652 -358.918162) (xy 182.326232 -358.940812)
			(xy 182.372085 -358.970287) (xy 182.413275 -359.005987) (xy 182.448966 -359.047186) (xy 182.478431 -359.093045)
			(xy 182.501069 -359.14263) (xy 182.51642 -359.194933) (xy 182.524171 -359.248888) (xy 182.524654 -359.276142)
			(xy 182.524165 -359.303512) (xy 182.516355 -359.35769) (xy 182.500871 -359.410193) (xy 182.478034 -359.459941)
			(xy 182.448314 -359.505908) (xy 182.430674 -359.52684) (xy 182.43042 -359.527094) (xy 182.42482 -359.534171)
			(xy 182.418584 -359.551096) (xy 182.418228 -359.560114) (xy 182.418228 -359.62717) (xy 182.418593 -359.636186)
			(xy 182.424835 -359.653103) (xy 182.43042 -359.66019) (xy 182.430674 -359.66019) (xy 182.430674 -359.660444)
			(xy 182.448296 -359.68139) (xy 182.478012 -359.727358) (xy 182.500851 -359.777102) (xy 182.516346 -359.8296)
			(xy 182.524178 -359.883774) (xy 182.524654 -359.911142) (xy 182.524161 -359.938392) (xy 182.5164 -359.992337)
			(xy 182.501042 -360.044629) (xy 182.4784 -360.094203) (xy 182.448933 -360.140051) (xy 182.413243 -360.18124)
			(xy 182.372055 -360.216931) (xy 182.326207 -360.246398) (xy 182.276633 -360.269041) (xy 182.224341 -360.2844)
			(xy 182.170396 -360.292161) (xy 182.143146 -360.29265) (xy 182.115776 -360.292169) (xy 182.061597 -360.284357)
			(xy 182.009094 -360.268872) (xy 181.959347 -360.246033) (xy 181.91338 -360.216311) (xy 181.892448 -360.19867)
			(xy 181.892194 -360.198416) (xy 181.885112 -360.192823) (xy 181.868192 -360.186579) (xy 181.859174 -360.186224)
			(xy 181.792118 -360.186224) (xy 181.783101 -360.186585) (xy 181.766184 -360.192829) (xy 181.759098 -360.198416)
			(xy 181.759098 -360.19867) (xy 181.758844 -360.19867) (xy 181.737911 -360.216311) (xy 181.691943 -360.246035)
			(xy 181.642197 -360.268881) (xy 181.589695 -360.284377) (xy 181.535517 -360.292206) (xy 181.480775 -360.292206)
			(xy 181.426597 -360.284377) (xy 181.374095 -360.268881) (xy 181.324349 -360.246035) (xy 181.278381 -360.216311)
			(xy 181.257448 -360.19867) (xy 181.257194 -360.198416) (xy 181.250112 -360.192823) (xy 181.233192 -360.186579)
			(xy 181.224174 -360.186224) (xy 181.157118 -360.186224) (xy 181.148101 -360.186585) (xy 181.131184 -360.192829)
			(xy 181.124098 -360.198416) (xy 181.124098 -360.19867) (xy 181.123844 -360.19867) (xy 181.102911 -360.216311)
			(xy 181.056943 -360.246035) (xy 181.007197 -360.268881) (xy 180.954695 -360.284377) (xy 180.900517 -360.292206)
			(xy 180.845775 -360.292206) (xy 180.791597 -360.284377) (xy 180.739095 -360.268881) (xy 180.689349 -360.246035)
			(xy 180.643381 -360.216311) (xy 180.622448 -360.19867) (xy 180.622194 -360.198416) (xy 180.615112 -360.192823)
			(xy 180.598192 -360.186579) (xy 180.589174 -360.186224) (xy 180.522118 -360.186224) (xy 180.513101 -360.186585)
			(xy 180.496184 -360.192829) (xy 180.489098 -360.198416) (xy 180.488844 -360.19867) (xy 180.485034 -360.201972)
			(xy 180.476922 -360.20958) (xy 180.467567 -360.229728) (xy 180.467 -360.240834) (xy 180.467 -360.318304)
			(xy 180.467621 -360.329347) (xy 180.476949 -360.349368) (xy 180.485034 -360.356912) (xy 180.505761 -360.375106)
			(xy 180.542229 -360.416479) (xy 180.572358 -360.462673) (xy 180.595521 -360.512724) (xy 180.611234 -360.565589)
			(xy 180.61917 -360.620166) (xy 180.619654 -360.647742) (xy 180.619165 -360.675112) (xy 180.611355 -360.72929)
			(xy 180.595871 -360.781793) (xy 180.573034 -360.831541) (xy 180.543314 -360.877508) (xy 180.525674 -360.89844)
			(xy 180.52542 -360.898694) (xy 180.51982 -360.905771) (xy 180.513584 -360.922696) (xy 180.513228 -360.931714)
			(xy 180.513228 -360.99877) (xy 180.513593 -361.007786) (xy 180.519835 -361.024703) (xy 180.52542 -361.03179)
			(xy 180.525674 -361.03179) (xy 180.525674 -361.032044) (xy 180.543356 -361.052943) (xy 180.573079 -361.098917)
			(xy 180.595922 -361.148669) (xy 180.611415 -361.201176) (xy 180.619239 -361.255359) (xy 180.619235 -361.310104)
			(xy 180.611401 -361.364286) (xy 180.595899 -361.416791) (xy 180.573048 -361.466539) (xy 180.568874 -361.472993)
			(xy 185.652165 -361.472993) (xy 185.655896 -361.419741) (xy 185.667013 -361.367529) (xy 185.685299 -361.317376)
			(xy 185.710397 -361.270262) (xy 185.741818 -361.227107) (xy 185.778948 -361.188752) (xy 185.79973 -361.171998)
			(xy 185.808533 -361.164387) (xy 185.818718 -361.143489) (xy 185.819288 -361.131866) (xy 185.819288 -361.05211)
			(xy 185.818733 -361.04048) (xy 185.808556 -361.01957) (xy 185.79973 -361.011978) (xy 185.777242 -360.993792)
			(xy 185.737506 -360.951772) (xy 185.704567 -360.904236) (xy 185.679179 -360.852274) (xy 185.661924 -360.797075)
			(xy 185.653197 -360.739904) (xy 185.652664 -360.710988) (xy 185.653167 -360.683738) (xy 185.660924 -360.629792)
			(xy 185.676279 -360.577499) (xy 185.69892 -360.527924) (xy 185.728385 -360.482075) (xy 185.764074 -360.440886)
			(xy 185.805262 -360.405194) (xy 185.85111 -360.375727) (xy 185.900684 -360.353085) (xy 185.952976 -360.337727)
			(xy 186.006922 -360.329968) (xy 186.034172 -360.32948) (xy 186.06309 -360.329988) (xy 186.120263 -360.338715)
			(xy 186.175463 -360.355973) (xy 186.227425 -360.381366) (xy 186.274959 -360.414313) (xy 186.316974 -360.454058)
			(xy 186.335162 -360.476546) (xy 186.342788 -360.485334) (xy 186.363675 -360.495526) (xy 186.375294 -360.496104)
			(xy 186.45505 -360.496104) (xy 186.466683 -360.495578) (xy 186.487593 -360.48538) (xy 186.495182 -360.476546)
			(xy 186.51337 -360.45406) (xy 186.555392 -360.414327) (xy 186.602928 -360.38139) (xy 186.654889 -360.356003)
			(xy 186.710087 -360.338746) (xy 186.767256 -360.330016) (xy 186.796172 -360.32948) (xy 186.823424 -360.329981)
			(xy 186.877373 -360.337734) (xy 186.929669 -360.353086) (xy 186.979248 -360.375724) (xy 187.025101 -360.405188)
			(xy 187.066294 -360.440878) (xy 187.101988 -360.482067) (xy 187.131456 -360.527917) (xy 187.1541 -360.577494)
			(xy 187.169457 -360.629788) (xy 187.177216 -360.683736) (xy 187.17768 -360.710988) (xy 187.177161 -360.739905)
			(xy 187.168433 -360.797076) (xy 187.151176 -360.852276) (xy 187.125784 -360.904237) (xy 187.092841 -360.951771)
			(xy 187.0531 -360.993788) (xy 187.030614 -361.011978) (xy 187.021812 -361.01959) (xy 187.011629 -361.040488)
			(xy 187.011056 -361.05211) (xy 187.011056 -361.131866) (xy 187.011609 -361.143497) (xy 187.021786 -361.164408)
			(xy 187.030614 -361.171998) (xy 187.051386 -361.188765) (xy 187.088519 -361.227115) (xy 187.119942 -361.270268)
			(xy 187.145044 -361.31738) (xy 187.163332 -361.367531) (xy 187.17445 -361.419742) (xy 187.178181 -361.472993)
			(xy 187.174452 -361.526244) (xy 187.163336 -361.578455) (xy 187.14505 -361.628607) (xy 187.11995 -361.67572)
			(xy 187.088528 -361.718873) (xy 187.051397 -361.757225) (xy 187.030614 -361.773978) (xy 187.021812 -361.78159)
			(xy 187.011629 -361.802488) (xy 187.011056 -361.81411) (xy 187.011056 -361.893866) (xy 187.011609 -361.905497)
			(xy 187.021786 -361.926408) (xy 187.030614 -361.933998) (xy 187.053099 -361.952187) (xy 187.092834 -361.994207)
			(xy 187.125772 -362.041743) (xy 187.15116 -362.093704) (xy 187.168416 -362.148902) (xy 187.177145 -362.206072)
			(xy 187.17768 -362.234988) (xy 187.177233 -362.262242) (xy 187.169477 -362.316195) (xy 187.154121 -362.368495)
			(xy 187.131478 -362.418077) (xy 187.102009 -362.463931) (xy 187.094223 -362.472916) (xy 190.790826 -362.472916)
			(xy 190.790826 -362.38822) (xy 190.798877 -362.303906) (xy 190.814906 -362.22074) (xy 190.838767 -362.139473)
			(xy 190.870246 -362.060843) (xy 190.909057 -361.985562) (xy 190.954847 -361.91431) (xy 191.007203 -361.847734)
			(xy 191.065651 -361.786436) (xy 191.129661 -361.730971) (xy 191.198653 -361.681842) (xy 191.272003 -361.639493)
			(xy 191.349046 -361.604309) (xy 191.429085 -361.576607) (xy 191.511394 -361.556639) (xy 191.595229 -361.544586)
			(xy 191.67983 -361.540556) (xy 191.764431 -361.544586) (xy 191.848266 -361.556639) (xy 191.930575 -361.576607)
			(xy 192.010614 -361.604309) (xy 192.087657 -361.639493) (xy 192.161007 -361.681842) (xy 192.229999 -361.730971)
			(xy 192.294009 -361.786436) (xy 192.352457 -361.847734) (xy 192.404813 -361.91431) (xy 192.450603 -361.985562)
			(xy 192.489414 -362.060843) (xy 192.520893 -362.139473) (xy 192.544754 -362.22074) (xy 192.560783 -362.303906)
			(xy 192.568834 -362.38822) (xy 192.569338 -362.430568) (xy 192.568834 -362.472916) (xy 192.560783 -362.55723)
			(xy 192.544754 -362.640396) (xy 192.520893 -362.721663) (xy 192.489414 -362.800293) (xy 192.450603 -362.875574)
			(xy 192.404813 -362.946826) (xy 192.352457 -363.013402) (xy 192.294009 -363.0747) (xy 192.229999 -363.130165)
			(xy 192.161007 -363.179294) (xy 192.087657 -363.221643) (xy 192.010614 -363.256827) (xy 191.930575 -363.284529)
			(xy 191.848266 -363.304497) (xy 191.764431 -363.31655) (xy 191.67983 -363.320581) (xy 191.595229 -363.31655)
			(xy 191.511394 -363.304497) (xy 191.429085 -363.284529) (xy 191.349046 -363.256827) (xy 191.272003 -363.221643)
			(xy 191.198653 -363.179294) (xy 191.129661 -363.130165) (xy 191.065651 -363.0747) (xy 191.007203 -363.013402)
			(xy 190.954847 -362.946826) (xy 190.909057 -362.875574) (xy 190.870246 -362.800293) (xy 190.838767 -362.721663)
			(xy 190.814906 -362.640396) (xy 190.798877 -362.55723) (xy 190.790826 -362.472916) (xy 187.094223 -362.472916)
			(xy 187.066313 -362.505125) (xy 187.025118 -362.540819) (xy 186.979263 -362.570286) (xy 186.92968 -362.592927)
			(xy 186.877379 -362.608281) (xy 186.823426 -362.616035) (xy 186.796172 -362.616496) (xy 186.767257 -362.615928)
			(xy 186.710088 -362.607209) (xy 186.65489 -362.589961) (xy 186.602928 -362.564579) (xy 186.555393 -362.531644)
			(xy 186.513374 -362.491912) (xy 186.495182 -362.46943) (xy 186.487585 -362.460613) (xy 186.466676 -362.450438)
			(xy 186.45505 -362.449872) (xy 186.375294 -362.449872) (xy 186.36366 -362.450397) (xy 186.342749 -362.460593)
			(xy 186.335162 -362.46943) (xy 186.317 -362.491938) (xy 186.274973 -362.53167) (xy 186.227432 -362.564605)
			(xy 186.175465 -362.589989) (xy 186.120263 -362.607241) (xy 186.06309 -362.615964) (xy 186.034172 -362.616496)
			(xy 186.00692 -362.616048) (xy 185.95297 -362.608288) (xy 185.900674 -362.592928) (xy 185.851095 -362.570283)
			(xy 185.805245 -362.540813) (xy 185.764054 -362.505117) (xy 185.728363 -362.463923) (xy 185.698898 -362.418069)
			(xy 185.676258 -362.368489) (xy 185.660904 -362.316191) (xy 185.653149 -362.262241) (xy 185.652664 -362.234988)
			(xy 185.653221 -362.206072) (xy 185.661939 -362.148902) (xy 185.679187 -362.093703) (xy 185.704572 -362.04174)
			(xy 185.73751 -361.994206) (xy 185.777246 -361.952188) (xy 185.79973 -361.933998) (xy 185.808533 -361.926387)
			(xy 185.818718 -361.905489) (xy 185.819288 -361.893866) (xy 185.819288 -361.81411) (xy 185.818733 -361.80248)
			(xy 185.808556 -361.78157) (xy 185.79973 -361.773978) (xy 185.778937 -361.757238) (xy 185.741809 -361.718882)
			(xy 185.71039 -361.675725) (xy 185.685293 -361.62861) (xy 185.667009 -361.578457) (xy 185.655894 -361.526245)
			(xy 185.652165 -361.472993) (xy 180.568874 -361.472993) (xy 180.543318 -361.512507) (xy 180.525674 -361.53344)
			(xy 180.52542 -361.533694) (xy 180.51982 -361.540771) (xy 180.513584 -361.557696) (xy 180.513228 -361.566714)
			(xy 180.513228 -361.63377) (xy 180.513593 -361.642786) (xy 180.519835 -361.659703) (xy 180.52542 -361.66679)
			(xy 180.525674 -361.66679) (xy 180.525674 -361.667044) (xy 180.543356 -361.687943) (xy 180.573079 -361.733917)
			(xy 180.595922 -361.783669) (xy 180.611415 -361.836176) (xy 180.619239 -361.890359) (xy 180.619235 -361.945104)
			(xy 180.611401 -361.999286) (xy 180.595899 -362.051791) (xy 180.573048 -362.101539) (xy 180.543318 -362.147507)
			(xy 180.525674 -362.16844) (xy 180.52542 -362.168694) (xy 180.51982 -362.175771) (xy 180.513584 -362.192696)
			(xy 180.513228 -362.201714) (xy 180.513228 -362.26877) (xy 180.513593 -362.277786) (xy 180.519835 -362.294703)
			(xy 180.52542 -362.30179) (xy 180.525674 -362.30179) (xy 180.525674 -362.302044) (xy 180.543296 -362.32299)
			(xy 180.573012 -362.368958) (xy 180.595851 -362.418702) (xy 180.611346 -362.4712) (xy 180.619178 -362.525374)
			(xy 180.619654 -362.552742) (xy 180.619164 -362.580316) (xy 180.611219 -362.634888) (xy 180.5955 -362.687748)
			(xy 180.572334 -362.737795) (xy 180.542205 -362.783985) (xy 180.50574 -362.825356) (xy 180.485034 -362.843572)
			(xy 180.47696 -362.851128) (xy 180.467608 -362.871139) (xy 180.467 -362.88218) (xy 180.467 -362.95965)
			(xy 180.46758 -362.970758) (xy 180.47691 -362.990917) (xy 180.485034 -362.998512) (xy 180.488844 -363.001814)
			(xy 180.489098 -363.002068) (xy 180.496175 -363.007668) (xy 180.513099 -363.013905) (xy 180.522118 -363.01426)
			(xy 180.589174 -363.01426) (xy 180.598191 -363.013899) (xy 180.615108 -363.007655) (xy 180.622194 -363.002068)
			(xy 180.622194 -363.001814) (xy 180.622448 -363.001814) (xy 180.643381 -362.984173) (xy 180.689349 -362.954449)
			(xy 180.739095 -362.931603) (xy 180.791597 -362.916107) (xy 180.845775 -362.908278) (xy 180.900517 -362.908278)
			(xy 180.954695 -362.916107) (xy 181.007197 -362.931603) (xy 181.056943 -362.954449) (xy 181.102911 -362.984173)
			(xy 181.123844 -363.001814) (xy 181.124098 -363.002068) (xy 181.131175 -363.007668) (xy 181.148099 -363.013905)
			(xy 181.157118 -363.01426) (xy 181.224174 -363.01426) (xy 181.233191 -363.013899) (xy 181.250108 -363.007655)
			(xy 181.257194 -363.002068) (xy 181.257194 -363.001814) (xy 181.257448 -363.001814) (xy 181.278381 -362.984173)
			(xy 181.324349 -362.954449) (xy 181.374095 -362.931603) (xy 181.426597 -362.916107) (xy 181.480775 -362.908278)
			(xy 181.535517 -362.908278) (xy 181.589695 -362.916107) (xy 181.642197 -362.931603) (xy 181.691943 -362.954449)
			(xy 181.737911 -362.984173) (xy 181.758844 -363.001814) (xy 181.759098 -363.002068) (xy 181.766175 -363.007668)
			(xy 181.783099 -363.013905) (xy 181.792118 -363.01426) (xy 181.859174 -363.01426) (xy 181.868191 -363.013899)
			(xy 181.885108 -363.007655) (xy 181.892194 -363.002068) (xy 181.892194 -363.001814) (xy 181.892448 -363.001814)
			(xy 181.913391 -362.984188) (xy 181.95936 -362.954474) (xy 182.009105 -362.931635) (xy 182.061604 -362.916141)
			(xy 182.115778 -362.90831) (xy 182.143146 -362.907834) (xy 182.1704 -362.908235) (xy 182.224353 -362.915999)
			(xy 182.276652 -362.931362) (xy 182.326232 -362.954012) (xy 182.372085 -362.983487) (xy 182.413275 -363.019187)
			(xy 182.448966 -363.060386) (xy 182.478431 -363.106245) (xy 182.501069 -363.15583) (xy 182.51642 -363.208133)
			(xy 182.524171 -363.262088) (xy 182.524654 -363.289342) (xy 182.524165 -363.316712) (xy 182.516355 -363.37089)
			(xy 182.500871 -363.423393) (xy 182.478034 -363.473141) (xy 182.448314 -363.519108) (xy 182.430674 -363.54004)
			(xy 182.43042 -363.540294) (xy 182.42482 -363.547371) (xy 182.418584 -363.564296) (xy 182.418228 -363.573314)
			(xy 182.418228 -363.64037) (xy 182.418593 -363.649386) (xy 182.424835 -363.666303) (xy 182.43042 -363.67339)
			(xy 182.430674 -363.67339) (xy 182.430674 -363.673644) (xy 182.448296 -363.69459) (xy 182.478012 -363.740558)
			(xy 182.500851 -363.790302) (xy 182.516346 -363.8428) (xy 182.524178 -363.896974) (xy 182.524654 -363.924342)
			(xy 182.524161 -363.951592) (xy 182.5164 -364.005537) (xy 182.501042 -364.057829) (xy 182.4784 -364.107403)
			(xy 182.448933 -364.153251) (xy 182.413243 -364.19444) (xy 182.372055 -364.230131) (xy 182.326207 -364.259598)
			(xy 182.276633 -364.282241) (xy 182.224341 -364.2976) (xy 182.170396 -364.305361) (xy 182.143146 -364.30585)
			(xy 182.115776 -364.305369) (xy 182.061597 -364.297557) (xy 182.009094 -364.282072) (xy 181.959347 -364.259233)
			(xy 181.91338 -364.229511) (xy 181.892448 -364.21187) (xy 181.892194 -364.211616) (xy 181.885112 -364.206023)
			(xy 181.868192 -364.199779) (xy 181.859174 -364.199424) (xy 181.792118 -364.199424) (xy 181.783101 -364.199785)
			(xy 181.766184 -364.206029) (xy 181.759098 -364.211616) (xy 181.758844 -364.21187) (xy 181.737911 -364.229511)
			(xy 181.691943 -364.259235) (xy 181.642197 -364.282081) (xy 181.589695 -364.297577) (xy 181.535517 -364.305406)
			(xy 181.480775 -364.305406) (xy 181.426597 -364.297577) (xy 181.374095 -364.282081) (xy 181.324349 -364.259235)
			(xy 181.278381 -364.229511) (xy 181.257448 -364.21187) (xy 181.257194 -364.211616) (xy 181.250112 -364.206023)
			(xy 181.233192 -364.199779) (xy 181.224174 -364.199424) (xy 181.157118 -364.199424) (xy 181.148101 -364.199785)
			(xy 181.131184 -364.206029) (xy 181.124098 -364.211616) (xy 181.124098 -364.21187) (xy 181.123844 -364.21187)
			(xy 181.102911 -364.229511) (xy 181.056943 -364.259235) (xy 181.007197 -364.282081) (xy 180.954695 -364.297577)
			(xy 180.900517 -364.305406) (xy 180.845775 -364.305406) (xy 180.791597 -364.297577) (xy 180.739095 -364.282081)
			(xy 180.689349 -364.259235) (xy 180.643381 -364.229511) (xy 180.622448 -364.21187) (xy 180.622194 -364.211616)
			(xy 180.615112 -364.206023) (xy 180.598192 -364.199779) (xy 180.589174 -364.199424) (xy 180.522118 -364.199424)
			(xy 180.513101 -364.199785) (xy 180.496184 -364.206029) (xy 180.489098 -364.211616) (xy 180.489098 -364.21187)
			(xy 180.488844 -364.21187) (xy 180.467902 -364.229497) (xy 180.421933 -364.259212) (xy 180.372188 -364.282051)
			(xy 180.319689 -364.297544) (xy 180.265515 -364.305375) (xy 180.238146 -364.30585) (xy 180.210896 -364.305302)
			(xy 180.15695 -364.297552) (xy 180.104657 -364.282204) (xy 180.05508 -364.25957) (xy 180.009228 -364.230111)
			(xy 179.968036 -364.194426) (xy 179.932342 -364.153242) (xy 179.902872 -364.107398) (xy 179.880226 -364.057826)
			(xy 179.864866 -364.005536) (xy 179.857104 -363.951592) (xy 179.856638 -363.924342) (xy 171.466041 -363.924342)
			(xy 171.473723 -363.941643) (xy 171.490924 -363.962692) (xy 171.513074 -363.97845) (xy 171.5386 -363.987798)
			(xy 171.552108 -363.989366) (xy 171.580275 -363.99237) (xy 171.635365 -364.005537) (xy 171.687901 -364.026709)
			(xy 171.736726 -364.055421) (xy 171.780768 -364.091039) (xy 171.819055 -364.13278) (xy 171.850746 -364.179727)
			(xy 171.875144 -364.230845) (xy 171.891711 -364.285009) (xy 171.900082 -364.341029) (xy 171.900596 -364.36935)
			(xy 171.90011 -364.396601) (xy 171.892354 -364.450549) (xy 171.876999 -364.502844) (xy 171.854357 -364.552421)
			(xy 171.824891 -364.598271) (xy 171.7892 -364.639462) (xy 171.748009 -364.675153) (xy 171.702159 -364.704619)
			(xy 171.652582 -364.727261) (xy 171.600287 -364.742616) (xy 171.546339 -364.750372) (xy 171.491837 -364.750372)
			(xy 171.437889 -364.742616) (xy 171.385594 -364.727261) (xy 171.336017 -364.704619) (xy 171.290167 -364.675153)
			(xy 171.248976 -364.639462) (xy 171.213285 -364.598271) (xy 171.183819 -364.552421) (xy 171.161177 -364.502844)
			(xy 171.145822 -364.450549) (xy 171.138066 -364.396601) (xy 171.13758 -364.36935) (xy 171.137961 -364.345093)
			(xy 171.14412 -364.296971) (xy 171.15633 -364.250018) (xy 171.165012 -364.227364) (xy 171.169676 -364.214594)
			(xy 171.172849 -364.187606) (xy 171.168781 -364.160738) (xy 171.15776 -364.135898) (xy 171.14057 -364.114852)
			(xy 171.118432 -364.099094) (xy 171.092917 -364.089743) (xy 171.079414 -364.088172) (xy 171.051232 -364.085294)
			(xy 170.996135 -364.072113) (xy 170.943595 -364.050926) (xy 170.894767 -364.0222) (xy 170.850725 -363.986568)
			(xy 170.812439 -363.944812) (xy 170.780752 -363.897852) (xy 170.756359 -363.846721) (xy 170.739799 -363.792544)
			(xy 170.731435 -363.736514) (xy 170.730926 -363.708188) (xy 168.998392 -363.708188) (xy 171.691808 -366.401604)
			(xy 171.699207 -366.408449) (xy 171.717805 -366.41618) (xy 171.727876 -366.41659) (xy 175.29175 -366.41659)
			(xy 175.303689 -366.41595) (xy 175.325025 -366.405228) (xy 175.332644 -366.396016) (xy 175.381158 -366.33023)
			(xy 175.387766 -366.320228) (xy 175.391763 -366.296626) (xy 175.388778 -366.285018) (xy 175.380966 -366.25774)
			(xy 175.37255 -366.201628) (xy 175.372014 -366.173258) (xy 175.372014 -366.173004) (xy 175.372552 -366.144474)
			(xy 175.381061 -366.088053) (xy 175.397874 -366.033527) (xy 175.422617 -365.982111) (xy 175.454738 -365.934952)
			(xy 175.493522 -365.8931) (xy 175.538104 -365.857488) (xy 175.587491 -365.828909) (xy 175.613822 -365.817912)
			(xy 175.626776 -365.812832) (xy 175.643794 -365.791242) (xy 175.657256 -365.689134) (xy 175.658074 -365.680095)
			(xy 175.654022 -365.662417) (xy 175.644053 -365.647266) (xy 175.636936 -365.641636) (xy 175.613344 -365.623531)
			(xy 175.571543 -365.581235) (xy 175.536817 -365.532961) (xy 175.510007 -365.479881) (xy 175.491764 -365.423282)
			(xy 175.482531 -365.364537) (xy 175.481996 -365.334804) (xy 175.482482 -365.307553) (xy 175.490238 -365.253605)
			(xy 175.505593 -365.20131) (xy 175.528235 -365.151733) (xy 175.557701 -365.105883) (xy 175.593392 -365.064692)
			(xy 175.634583 -365.029001) (xy 175.680433 -364.999535) (xy 175.73001 -364.976893) (xy 175.782305 -364.961538)
			(xy 175.836253 -364.953782) (xy 175.890755 -364.953782) (xy 175.944703 -364.961538) (xy 175.983869 -364.973038)
			(xy 190.790826 -364.973038) (xy 190.790826 -364.888342) (xy 190.798877 -364.804028) (xy 190.814906 -364.720862)
			(xy 190.838767 -364.639595) (xy 190.870246 -364.560965) (xy 190.909057 -364.485684) (xy 190.954847 -364.414432)
			(xy 191.007203 -364.347856) (xy 191.065651 -364.286558) (xy 191.129661 -364.231093) (xy 191.198653 -364.181964)
			(xy 191.272003 -364.139615) (xy 191.349046 -364.104431) (xy 191.429085 -364.076729) (xy 191.511394 -364.056761)
			(xy 191.595229 -364.044708) (xy 191.67983 -364.040678) (xy 191.764431 -364.044708) (xy 191.848266 -364.056761)
			(xy 191.930575 -364.076729) (xy 192.010614 -364.104431) (xy 192.087657 -364.139615) (xy 192.161007 -364.181964)
			(xy 192.229999 -364.231093) (xy 192.294009 -364.286558) (xy 192.352457 -364.347856) (xy 192.404813 -364.414432)
			(xy 192.450603 -364.485684) (xy 192.489414 -364.560965) (xy 192.520893 -364.639595) (xy 192.544754 -364.720862)
			(xy 192.560783 -364.804028) (xy 192.568834 -364.888342) (xy 192.569338 -364.93069) (xy 192.568834 -364.973038)
			(xy 192.560783 -365.057352) (xy 192.544754 -365.140518) (xy 192.520893 -365.221785) (xy 192.489414 -365.300415)
			(xy 192.450603 -365.375696) (xy 192.404813 -365.446948) (xy 192.352457 -365.513524) (xy 192.294009 -365.574822)
			(xy 192.229999 -365.630287) (xy 192.161007 -365.679416) (xy 192.087657 -365.721765) (xy 192.010614 -365.756949)
			(xy 191.930575 -365.784651) (xy 191.848266 -365.804619) (xy 191.764431 -365.816672) (xy 191.67983 -365.820703)
			(xy 191.595229 -365.816672) (xy 191.511394 -365.804619) (xy 191.429085 -365.784651) (xy 191.349046 -365.756949)
			(xy 191.272003 -365.721765) (xy 191.198653 -365.679416) (xy 191.129661 -365.630287) (xy 191.065651 -365.574822)
			(xy 191.007203 -365.513524) (xy 190.954847 -365.446948) (xy 190.909057 -365.375696) (xy 190.870246 -365.300415)
			(xy 190.838767 -365.221785) (xy 190.814906 -365.140518) (xy 190.798877 -365.057352) (xy 190.790826 -364.973038)
			(xy 175.983869 -364.973038) (xy 175.996998 -364.976893) (xy 176.046575 -364.999535) (xy 176.092425 -365.029001)
			(xy 176.133616 -365.064692) (xy 176.169307 -365.105883) (xy 176.198773 -365.151733) (xy 176.221415 -365.20131)
			(xy 176.23677 -365.253605) (xy 176.244526 -365.307553) (xy 176.245012 -365.334804) (xy 176.244473 -365.363334)
			(xy 176.235964 -365.419755) (xy 176.219151 -365.474282) (xy 176.194408 -365.525698) (xy 176.162288 -365.572858)
			(xy 176.123505 -365.614711) (xy 176.078924 -365.650325) (xy 176.029538 -365.678906) (xy 176.003204 -365.689896)
			(xy 175.99025 -365.694976) (xy 175.973232 -365.716566) (xy 175.95977 -365.818674) (xy 175.958953 -365.827712)
			(xy 175.963009 -365.845386) (xy 175.972982 -365.860532) (xy 175.98009 -365.866172) (xy 176.00227 -365.883188)
			(xy 176.041931 -365.922584) (xy 176.059084 -365.944658) (xy 176.059084 -365.944912) (xy 176.064528 -365.951563)
			(xy 176.078824 -365.961085) (xy 176.095457 -365.965371) (xy 176.104042 -365.964978) (xy 176.203356 -365.956342)
			(xy 176.2252 -365.94161) (xy 176.231042 -365.929926) (xy 176.243331 -365.906726) (xy 176.273321 -365.863636)
			(xy 176.308938 -365.825067) (xy 176.349508 -365.791748) (xy 176.394265 -365.764308) (xy 176.442363 -365.743266)
			(xy 176.492893 -365.72902) (xy 176.544898 -365.72184) (xy 176.571148 -365.721392) (xy 176.598397 -365.721881)
			(xy 176.65234 -365.729643) (xy 176.704629 -365.745002) (xy 176.7542 -365.767646) (xy 176.800044 -365.797114)
			(xy 176.841229 -365.832805) (xy 176.876915 -365.873994) (xy 176.906377 -365.919842) (xy 176.929014 -365.969416)
			(xy 176.944367 -366.021707) (xy 176.952122 -366.075651) (xy 176.952656 -366.1029) (xy 176.952656 -366.103154)
			(xy 176.952134 -366.132006) (xy 176.943446 -366.189053) (xy 176.926247 -366.244135) (xy 176.914048 -366.270286)
			(xy 176.91056 -366.278165) (xy 176.908545 -366.295268) (xy 176.912335 -366.312066) (xy 176.916588 -366.319562)
			(xy 176.962054 -366.392714) (xy 176.966895 -366.399847) (xy 176.980349 -366.410608) (xy 176.996619 -366.416273)
			(xy 177.005234 -366.41659) (xy 187.03163 -366.41659) (xy 187.03665 -366.41668) (xy 187.046503 -366.418596)
			(xy 187.051188 -366.4204) (xy 187.06846 -366.427766) (xy 187.073146 -366.429569) (xy 187.082998 -366.431496)
			(xy 187.088018 -366.431576)
		)
		(stroke
			(width 0)
			(type solid)
		)
		(fill yes)
		(layer "In13.Cu")
		(net "GND")
	)
	(gr_poly
		(pts
			(xy 22.68855 -418.44214) (xy 22.698615 -418.441706) (xy 22.7172 -418.433972) (xy 22.724618 -418.427154)
			(xy 25.041098 -416.110674) (xy 25.04794 -416.103274) (xy 25.055666 -416.084676) (xy 25.056084 -416.074606)
			(xy 25.056084 -412.338266) (xy 25.056513 -412.328198) (xy 25.064234 -412.309601) (xy 25.07107 -412.302198)
			(xy 26.711656 -410.661612) (xy 26.719057 -410.654773) (xy 26.737655 -410.647057) (xy 26.747724 -410.646626)
			(xy 31.796482 -410.646626) (xy 31.806532 -410.64612) (xy 31.825092 -410.638398) (xy 31.83255 -410.63164)
			(xy 32.822134 -409.642056) (xy 32.828945 -409.634712) (xy 32.836672 -409.616248) (xy 32.83712 -409.606242)
			(xy 32.83712 -409.426918) (xy 32.837585 -409.40234) (xy 32.84524 -409.353786) (xy 32.860397 -409.307026)
			(xy 32.882681 -409.263213) (xy 32.911544 -409.223425) (xy 32.92856 -409.205684) (xy 33.904682 -408.229562)
			(xy 33.911489 -408.222216) (xy 33.91921 -408.203753) (xy 33.919668 -408.193748) (xy 33.919668 -396.13586)
			(xy 33.919237 -396.125794) (xy 33.911509 -396.107203) (xy 33.904682 -396.099792) (xy 30.277054 -392.472164)
			(xy 30.270207 -392.464766) (xy 30.262478 -392.446167) (xy 30.262068 -392.436096) (xy 30.262068 -384.960876)
			(xy 30.26164 -384.950808) (xy 30.253916 -384.932213) (xy 30.247082 -384.924808) (xy 29.917898 -384.595624)
			(xy 29.885132 -384.590544) (xy 29.8704 -384.598418) (xy 29.842983 -384.612022) (xy 29.784891 -384.631282)
			(xy 29.724471 -384.641027) (xy 29.69387 -384.641598) (xy 29.66662 -384.64111) (xy 29.612677 -384.63335)
			(xy 29.560386 -384.617992) (xy 29.510813 -384.595349) (xy 29.464967 -384.565882) (xy 29.423782 -384.53019)
			(xy 29.388094 -384.489001) (xy 29.358632 -384.443152) (xy 29.335994 -384.393576) (xy 29.320642 -384.341284)
			(xy 29.312887 -384.28734) (xy 29.312362 -384.26009) (xy 29.312821 -384.233527) (xy 29.320189 -384.180913)
			(xy 29.334782 -384.12983) (xy 29.356317 -384.081264) (xy 29.384378 -384.036153) (xy 29.418424 -383.995369)
			(xy 29.457796 -383.9597) (xy 29.479494 -383.944368) (xy 29.489477 -383.936892) (xy 29.501206 -383.914913)
			(xy 29.501846 -383.902458) (xy 29.501846 -383.728722) (xy 29.501165 -383.716276) (xy 29.489458 -383.6943)
			(xy 29.479494 -383.686812) (xy 29.456119 -383.670305) (xy 29.414127 -383.631434) (xy 29.378406 -383.58673)
			(xy 29.349758 -383.537195) (xy 29.328825 -383.48394) (xy 29.316074 -383.428156) (xy 29.311793 -383.371094)
			(xy 29.316076 -383.314033) (xy 29.328828 -383.25825) (xy 29.349763 -383.204995) (xy 29.378413 -383.155461)
			(xy 29.414134 -383.110758) (xy 29.456128 -383.071888) (xy 29.479494 -383.055368) (xy 29.489477 -383.047892)
			(xy 29.501206 -383.025913) (xy 29.501846 -383.013458) (xy 29.501846 -381.796544) (xy 29.501315 -381.786554)
			(xy 29.493607 -381.768116) (xy 29.48686 -381.76073) (xy 28.483052 -380.756922) (xy 28.466004 -380.739208)
			(xy 28.437132 -380.699418) (xy 28.414844 -380.6556) (xy 28.39969 -380.608832) (xy 28.392043 -380.560269)
			(xy 28.391612 -380.535688) (xy 28.391612 -378.367036) (xy 28.391296 -378.358553) (xy 28.385732 -378.342526)
			(xy 28.37521 -378.329218) (xy 28.368244 -378.324364) (xy 28.285948 -378.27077) (xy 28.260548 -378.268992)
			(xy 28.24861 -378.274326) (xy 28.224109 -378.284691) (xy 28.172956 -378.299299) (xy 28.120269 -378.306658)
			(xy 28.09367 -378.307092) (xy 28.06556 -378.30659) (xy 28.009947 -378.298341) (xy 27.956146 -378.282026)
			(xy 27.905319 -378.257997) (xy 27.858566 -378.226773) (xy 27.837384 -378.208286) (xy 27.830272 -378.201682)
			(xy 27.813 -378.195078) (xy 27.725624 -378.194824) (xy 27.708352 -378.201682) (xy 27.700986 -378.208032)
			(xy 27.679861 -378.226441) (xy 27.633224 -378.257502) (xy 27.582543 -378.281401) (xy 27.528909 -378.297624)
			(xy 27.473479 -378.305821) (xy 27.445462 -378.30633) (xy 27.416724 -378.305806) (xy 27.359901 -378.297177)
			(xy 27.305015 -378.28012) (xy 27.25331 -378.255021) (xy 27.205955 -378.222449) (xy 27.184604 -378.203206)
			(xy 27.177492 -378.196602) (xy 27.159966 -378.18949) (xy 27.070558 -378.18949) (xy 27.053032 -378.196602)
			(xy 27.04592 -378.203206) (xy 27.024594 -378.222479) (xy 26.977232 -378.25505) (xy 26.925521 -378.280147)
			(xy 26.87063 -378.297205) (xy 26.813802 -378.305836) (xy 26.785062 -378.30633) (xy 26.754196 -378.305716)
			(xy 26.693276 -378.29574) (xy 26.634756 -378.276085) (xy 26.580164 -378.247265) (xy 26.555192 -378.229114)
			(xy 26.547572 -378.223526) (xy 26.529792 -378.218446) (xy 26.443686 -378.225304) (xy 26.426922 -378.233178)
			(xy 26.420318 -378.240036) (xy 26.402266 -378.258348) (xy 26.362093 -378.290446) (xy 26.317971 -378.316855)
			(xy 26.2707 -378.337095) (xy 26.221138 -378.350799) (xy 26.170185 -378.357719) (xy 26.144474 -378.358146)
			(xy 26.117223 -378.357658) (xy 26.063276 -378.349899) (xy 26.010982 -378.334542) (xy 25.961406 -378.3119)
			(xy 25.915556 -378.282434) (xy 25.874366 -378.246743) (xy 25.838674 -378.205554) (xy 25.809206 -378.159705)
			(xy 25.786562 -378.110129) (xy 25.771203 -378.057836) (xy 25.763442 -378.003889) (xy 25.762966 -377.976638)
			(xy 25.763436 -377.949667) (xy 25.771041 -377.896262) (xy 25.78609 -377.844461) (xy 25.808283 -377.795295)
			(xy 25.837179 -377.749744) (xy 25.872201 -377.708716) (xy 25.912651 -377.673028) (xy 25.957724 -377.643392)
			(xy 25.981914 -377.631452) (xy 25.992836 -377.626372) (xy 26.007314 -377.60783) (xy 26.029158 -377.50496)
			(xy 26.023062 -377.4821) (xy 26.015188 -377.472956) (xy 25.997598 -377.452029) (xy 25.967965 -377.40609)
			(xy 25.945192 -377.356392) (xy 25.929745 -377.303953) (xy 25.921941 -377.249846) (xy 25.921462 -377.222512)
			(xy 25.921995 -377.193596) (xy 25.930722 -377.136425) (xy 25.947977 -377.081226) (xy 25.973364 -377.029263)
			(xy 26.006304 -376.981728) (xy 26.04604 -376.939708) (xy 26.068528 -376.921522) (xy 26.077313 -376.91398)
			(xy 26.087488 -376.893208) (xy 26.088086 -376.881644) (xy 26.088086 -376.80138) (xy 26.087473 -376.789822)
			(xy 26.077291 -376.769063) (xy 26.068528 -376.761502) (xy 26.047746 -376.744748) (xy 26.010616 -376.706393)
			(xy 25.979196 -376.663237) (xy 25.954098 -376.616123) (xy 25.935811 -376.565971) (xy 25.924695 -376.513759)
			(xy 25.920964 -376.460507) (xy 25.924692 -376.407256) (xy 25.935807 -376.355043) (xy 25.954092 -376.30489)
			(xy 25.979188 -376.257775) (xy 26.010607 -376.214618) (xy 26.047735 -376.176262) (xy 26.068528 -376.159522)
			(xy 26.077313 -376.15198) (xy 26.087488 -376.131208) (xy 26.088086 -376.119644) (xy 26.088086 -376.03938)
			(xy 26.087473 -376.027822) (xy 26.077291 -376.007063) (xy 26.068528 -375.999502) (xy 26.046045 -375.981312)
			(xy 26.006308 -375.939294) (xy 25.97337 -375.89176) (xy 25.947986 -375.839797) (xy 25.930738 -375.784598)
			(xy 25.92202 -375.727428) (xy 25.921462 -375.698512) (xy 25.922015 -375.668963) (xy 25.931126 -375.610571)
			(xy 25.949131 -375.554282) (xy 25.975601 -375.501443) (xy 26.009901 -375.453317) (xy 26.030174 -375.431812)
			(xy 26.037286 -375.424446) (xy 26.044652 -375.406666) (xy 26.04516 -375.315988) (xy 26.038048 -375.297954)
			(xy 26.030936 -375.290588) (xy 26.011263 -375.269161) (xy 25.977977 -375.221458) (xy 25.952315 -375.169258)
			(xy 25.93487 -375.113768) (xy 25.926046 -375.056274) (xy 25.925526 -375.02719) (xy 25.926012 -374.999939)
			(xy 25.933768 -374.945991) (xy 25.949123 -374.893696) (xy 25.971765 -374.844119) (xy 26.001231 -374.798269)
			(xy 26.036922 -374.757078) (xy 26.078113 -374.721387) (xy 26.123963 -374.691921) (xy 26.17354 -374.669279)
			(xy 26.225835 -374.653924) (xy 26.279783 -374.646168) (xy 26.334285 -374.646168) (xy 26.388233 -374.653924)
			(xy 26.440528 -374.669279) (xy 26.490105 -374.691921) (xy 26.535955 -374.721387) (xy 26.577146 -374.757078)
			(xy 26.612837 -374.798269) (xy 26.642303 -374.844119) (xy 26.664945 -374.893696) (xy 26.6803 -374.945991)
			(xy 26.688056 -374.999939) (xy 26.688542 -375.02719) (xy 26.687988 -375.056738) (xy 26.678875 -375.115128)
			(xy 26.660866 -375.171414) (xy 26.634391 -375.224249) (xy 26.600085 -375.272369) (xy 26.57983 -375.29389)
			(xy 26.572718 -375.301256) (xy 26.565352 -375.319036) (xy 26.564844 -375.409714) (xy 26.571956 -375.427748)
			(xy 26.579068 -375.435114) (xy 26.598741 -375.456541) (xy 26.632026 -375.504244) (xy 26.657688 -375.556444)
			(xy 26.675133 -375.611934) (xy 26.683956 -375.669428) (xy 26.684478 -375.698512) (xy 26.683943 -375.727428)
			(xy 26.675214 -375.784598) (xy 26.657958 -375.839795) (xy 26.63257 -375.891757) (xy 26.599632 -375.939292)
			(xy 26.559897 -375.981313) (xy 26.537412 -375.999502) (xy 26.528625 -376.007042) (xy 26.518451 -376.027815)
			(xy 26.517854 -376.03938) (xy 26.517854 -376.119644) (xy 26.518473 -376.131198) (xy 26.528666 -376.151944)
			(xy 26.537412 -376.159522) (xy 26.551649 -376.170899) (xy 26.578114 -376.195958) (xy 26.590244 -376.20956)
			(xy 26.597356 -376.217688) (xy 26.61666 -376.226578) (xy 26.713434 -376.228356) (xy 26.733246 -376.220228)
			(xy 26.740612 -376.212354) (xy 26.758708 -376.193789) (xy 26.799046 -376.161224) (xy 26.84342 -376.134418)
			(xy 26.891013 -376.113863) (xy 26.940951 -376.099938) (xy 26.992313 -376.0929) (xy 27.018234 -376.092466)
			(xy 27.046972 -376.09299) (xy 27.103796 -376.101618) (xy 27.158682 -376.118675) (xy 27.210388 -376.143773)
			(xy 27.257743 -376.176344) (xy 27.279092 -376.19559) (xy 27.286204 -376.202194) (xy 27.30373 -376.209306)
			(xy 27.393138 -376.209306) (xy 27.410664 -376.202194) (xy 27.417776 -376.19559) (xy 27.439102 -376.176317)
			(xy 27.486464 -376.143746) (xy 27.538175 -376.118648) (xy 27.593066 -376.10159) (xy 27.649894 -376.092959)
			(xy 27.678634 -376.092466) (xy 27.705884 -376.092954) (xy 27.75983 -376.100714) (xy 27.812122 -376.116072)
			(xy 27.861697 -376.138715) (xy 27.907545 -376.168182) (xy 27.948733 -376.203873) (xy 27.984423 -376.245062)
			(xy 28.013889 -376.290911) (xy 28.036531 -376.340486) (xy 28.051887 -376.392778) (xy 28.059646 -376.446724)
			(xy 28.060142 -376.473974) (xy 28.059666 -376.501705) (xy 28.051675 -376.556586) (xy 28.035815 -376.60973)
			(xy 28.012419 -376.660014) (xy 27.981983 -376.706376) (xy 27.945149 -376.747838) (xy 27.924252 -376.766074)
			(xy 27.915362 -376.77344) (xy 27.905964 -376.79376) (xy 27.906726 -376.895106) (xy 27.916632 -376.915426)
			(xy 27.925522 -376.922538) (xy 27.947143 -376.940756) (xy 27.985289 -376.982485) (xy 28.016856 -377.029388)
			(xy 28.041154 -377.080437) (xy 28.057649 -377.134514) (xy 28.065981 -377.190434) (xy 28.066492 -377.218702)
			(xy 28.065902 -377.249398) (xy 28.056117 -377.310005) (xy 28.036754 -377.368263) (xy 28.023058 -377.39574)
			(xy 28.016708 -377.407424) (xy 28.017216 -377.433332) (xy 28.073604 -377.530614) (xy 28.095702 -377.543822)
			(xy 28.10891 -377.54433) (xy 28.132936 -377.545635) (xy 28.180397 -377.553556) (xy 28.22648 -377.567398)
			(xy 28.24861 -377.576842) (xy 28.260548 -377.582176) (xy 28.285948 -377.580398) (xy 28.368244 -377.526804)
			(xy 28.375205 -377.52195) (xy 28.385699 -377.508625) (xy 28.391289 -377.492611) (xy 28.391612 -377.484132)
			(xy 28.391612 -376.214894) (xy 28.391074 -376.204907) (xy 28.38336 -376.186475) (xy 28.376626 -376.17908)
			(xy 25.549352 -373.351806) (xy 25.542004 -373.345002) (xy 25.523542 -373.337286) (xy 25.513538 -373.33682)
			(xy 20.501102 -373.33682) (xy 20.476525 -373.336354) (xy 20.42797 -373.328697) (xy 20.381211 -373.313541)
			(xy 20.337398 -373.291257) (xy 20.29761 -373.262395) (xy 20.279868 -373.24538) (xy 18.796762 -371.762274)
			(xy 18.779684 -371.744573) (xy 18.750752 -371.704799) (xy 18.728406 -371.660984) (xy 18.713198 -371.614211)
			(xy 18.705504 -371.565632) (xy 18.705068 -371.54104) (xy 18.705068 -371.009164) (xy 18.704587 -370.9992)
			(xy 18.697003 -370.980771) (xy 18.690336 -370.97335) (xy 17.230344 -369.513358) (xy 17.222999 -369.50655)
			(xy 17.204535 -369.498829) (xy 17.19453 -369.498372) (xy 6.324092 -369.498372) (xy 6.314022 -369.498796)
			(xy 6.295417 -369.506509) (xy 6.288024 -369.513358) (xy 5.989066 -369.812316) (xy 5.982251 -369.819659)
			(xy 5.974514 -369.838122) (xy 5.97408 -369.84813) (xy 5.97408 -376.70105) (xy 8.208781 -376.70105)
			(xy 8.21251 -376.647799) (xy 8.223627 -376.595587) (xy 8.241913 -376.545435) (xy 8.267012 -376.498321)
			(xy 8.298433 -376.455167) (xy 8.335563 -376.416813) (xy 8.356346 -376.40006) (xy 8.365129 -376.392519)
			(xy 8.375299 -376.371744) (xy 8.375904 -376.360182) (xy 8.375904 -376.279918) (xy 8.375322 -376.268352)
			(xy 8.365135 -376.247581) (xy 8.356346 -376.24004) (xy 8.335563 -376.223287) (xy 8.298433 -376.184933)
			(xy 8.267012 -376.141779) (xy 8.241913 -376.094665) (xy 8.223627 -376.044513) (xy 8.21251 -375.992301)
			(xy 8.208781 -375.93905) (xy 8.21251 -375.885799) (xy 8.223627 -375.833587) (xy 8.241913 -375.783435)
			(xy 8.267012 -375.736321) (xy 8.298433 -375.693167) (xy 8.335563 -375.654813) (xy 8.356346 -375.63806)
			(xy 8.365129 -375.630519) (xy 8.375299 -375.609744) (xy 8.375904 -375.598182) (xy 8.375904 -375.517918)
			(xy 8.375322 -375.506352) (xy 8.365135 -375.485581) (xy 8.356346 -375.47804) (xy 8.33387 -375.45984)
			(xy 8.294137 -375.417821) (xy 8.261199 -375.370287) (xy 8.23581 -375.318328) (xy 8.218551 -375.263133)
			(xy 8.209818 -375.205965) (xy 8.20928 -375.17705) (xy 8.209766 -375.149799) (xy 8.217522 -375.095851)
			(xy 8.232877 -375.043556) (xy 8.255519 -374.993979) (xy 8.284985 -374.948129) (xy 8.320676 -374.906938)
			(xy 8.361867 -374.871247) (xy 8.407717 -374.841781) (xy 8.457294 -374.819139) (xy 8.509589 -374.803784)
			(xy 8.563537 -374.796028) (xy 8.618039 -374.796028) (xy 8.671987 -374.803784) (xy 8.724282 -374.819139)
			(xy 8.773859 -374.841781) (xy 8.819709 -374.871247) (xy 8.8609 -374.906938) (xy 8.896591 -374.948129)
			(xy 8.926057 -374.993979) (xy 8.948699 -375.043556) (xy 8.964054 -375.095851) (xy 8.97181 -375.149799)
			(xy 8.972296 -375.17705) (xy 8.971743 -375.205966) (xy 8.963022 -375.263135) (xy 8.945771 -375.318334)
			(xy 8.920385 -375.370295) (xy 8.887448 -375.41783) (xy 8.847713 -375.459849) (xy 8.82523 -375.47804)
			(xy 8.816443 -375.485577) (xy 8.806276 -375.506355) (xy 8.805672 -375.517918) (xy 8.805672 -375.598182)
			(xy 8.806228 -375.609752) (xy 8.81643 -375.630525) (xy 8.82523 -375.63806) (xy 8.846013 -375.654813)
			(xy 8.883144 -375.693166) (xy 8.914565 -375.736321) (xy 8.939664 -375.783435) (xy 8.95795 -375.833587)
			(xy 8.969067 -375.885798) (xy 8.972797 -375.93905) (xy 8.969067 -375.992302) (xy 8.95795 -376.044513)
			(xy 8.939664 -376.094665) (xy 8.914565 -376.141779) (xy 8.883144 -376.184934) (xy 8.846013 -376.223287)
			(xy 8.82523 -376.24004) (xy 8.816443 -376.247577) (xy 8.806276 -376.268355) (xy 8.805672 -376.279918)
			(xy 8.805672 -376.360182) (xy 8.806228 -376.371752) (xy 8.81643 -376.392525) (xy 8.82523 -376.40006)
			(xy 8.846013 -376.416813) (xy 8.883144 -376.455166) (xy 8.914565 -376.498321) (xy 8.939664 -376.545435)
			(xy 8.95795 -376.595587) (xy 8.969067 -376.647798) (xy 8.972797 -376.70105) (xy 10.494781 -376.70105)
			(xy 10.49851 -376.647799) (xy 10.509627 -376.595587) (xy 10.527913 -376.545435) (xy 10.553012 -376.498321)
			(xy 10.584433 -376.455167) (xy 10.621563 -376.416813) (xy 10.642346 -376.40006) (xy 10.651129 -376.392519)
			(xy 10.661299 -376.371744) (xy 10.661904 -376.360182) (xy 10.661904 -376.279918) (xy 10.661322 -376.268352)
			(xy 10.651135 -376.247581) (xy 10.642346 -376.24004) (xy 10.621563 -376.223287) (xy 10.584433 -376.184933)
			(xy 10.553012 -376.141779) (xy 10.527913 -376.094665) (xy 10.509627 -376.044513) (xy 10.49851 -375.992301)
			(xy 10.494781 -375.93905) (xy 10.49851 -375.885799) (xy 10.509627 -375.833587) (xy 10.527913 -375.783435)
			(xy 10.553012 -375.736321) (xy 10.584433 -375.693167) (xy 10.621563 -375.654813) (xy 10.642346 -375.63806)
			(xy 10.651129 -375.630519) (xy 10.661299 -375.609744) (xy 10.661904 -375.598182) (xy 10.661904 -375.517918)
			(xy 10.661322 -375.506352) (xy 10.651135 -375.485581) (xy 10.642346 -375.47804) (xy 10.61987 -375.45984)
			(xy 10.580137 -375.417821) (xy 10.547199 -375.370287) (xy 10.52181 -375.318328) (xy 10.504551 -375.263133)
			(xy 10.495818 -375.205965) (xy 10.49528 -375.17705) (xy 10.495766 -375.149799) (xy 10.503522 -375.095851)
			(xy 10.518877 -375.043556) (xy 10.541519 -374.993979) (xy 10.570985 -374.948129) (xy 10.606676 -374.906938)
			(xy 10.647867 -374.871247) (xy 10.693717 -374.841781) (xy 10.743294 -374.819139) (xy 10.795589 -374.803784)
			(xy 10.849537 -374.796028) (xy 10.904039 -374.796028) (xy 10.957987 -374.803784) (xy 11.010282 -374.819139)
			(xy 11.059859 -374.841781) (xy 11.105709 -374.871247) (xy 11.1469 -374.906938) (xy 11.182591 -374.948129)
			(xy 11.212057 -374.993979) (xy 11.234699 -375.043556) (xy 11.250054 -375.095851) (xy 11.25781 -375.149799)
			(xy 11.258296 -375.17705) (xy 11.257743 -375.205966) (xy 11.249022 -375.263135) (xy 11.231771 -375.318334)
			(xy 11.206385 -375.370295) (xy 11.173448 -375.41783) (xy 11.133713 -375.459849) (xy 11.11123 -375.47804)
			(xy 11.102443 -375.485577) (xy 11.092276 -375.506355) (xy 11.091672 -375.517918) (xy 11.091672 -375.598182)
			(xy 11.092228 -375.609752) (xy 11.10243 -375.630525) (xy 11.11123 -375.63806) (xy 11.132013 -375.654813)
			(xy 11.169144 -375.693166) (xy 11.200565 -375.736321) (xy 11.225664 -375.783435) (xy 11.24395 -375.833587)
			(xy 11.255067 -375.885798) (xy 11.258797 -375.93905) (xy 11.255067 -375.992302) (xy 11.24395 -376.044513)
			(xy 11.225664 -376.094665) (xy 11.200565 -376.141779) (xy 11.169144 -376.184934) (xy 11.132013 -376.223287)
			(xy 11.11123 -376.24004) (xy 11.102443 -376.247577) (xy 11.092276 -376.268355) (xy 11.091672 -376.279918)
			(xy 11.091672 -376.360182) (xy 11.092228 -376.371752) (xy 11.10243 -376.392525) (xy 11.11123 -376.40006)
			(xy 11.132013 -376.416813) (xy 11.169144 -376.455166) (xy 11.200565 -376.498321) (xy 11.225664 -376.545435)
			(xy 11.24395 -376.595587) (xy 11.255067 -376.647798) (xy 11.258797 -376.70105) (xy 11.255067 -376.754302)
			(xy 11.24395 -376.806513) (xy 11.225664 -376.856665) (xy 11.200565 -376.903779) (xy 11.169144 -376.946934)
			(xy 11.132013 -376.985287) (xy 11.11123 -377.00204) (xy 11.102443 -377.009577) (xy 11.092276 -377.030355)
			(xy 11.091672 -377.041918) (xy 11.091672 -377.122182) (xy 11.092228 -377.133752) (xy 11.10243 -377.154525)
			(xy 11.11123 -377.16206) (xy 11.133701 -377.180266) (xy 11.173435 -377.222284) (xy 11.206375 -377.269816)
			(xy 11.231765 -377.321774) (xy 11.249025 -377.376968) (xy 11.257758 -377.434135) (xy 11.258296 -377.46305)
			(xy 11.25781 -377.490301) (xy 11.250054 -377.544249) (xy 11.234699 -377.596544) (xy 11.212057 -377.646121)
			(xy 11.182591 -377.691971) (xy 11.1469 -377.733162) (xy 11.105709 -377.768853) (xy 11.059859 -377.798319)
			(xy 11.010282 -377.820961) (xy 10.957987 -377.836316) (xy 10.904039 -377.844072) (xy 10.849537 -377.844072)
			(xy 10.795589 -377.836316) (xy 10.743294 -377.820961) (xy 10.693717 -377.798319) (xy 10.647867 -377.768853)
			(xy 10.606676 -377.733162) (xy 10.570985 -377.691971) (xy 10.541519 -377.646121) (xy 10.518877 -377.596544)
			(xy 10.503522 -377.544249) (xy 10.495766 -377.490301) (xy 10.49528 -377.46305) (xy 10.495804 -377.434133)
			(xy 10.504528 -377.376961) (xy 10.521783 -377.321761) (xy 10.547173 -377.269798) (xy 10.580117 -377.222265)
			(xy 10.61986 -377.180249) (xy 10.642346 -377.16206) (xy 10.651129 -377.154519) (xy 10.661299 -377.133744)
			(xy 10.661904 -377.122182) (xy 10.661904 -377.041918) (xy 10.661322 -377.030352) (xy 10.651135 -377.009581)
			(xy 10.642346 -377.00204) (xy 10.621563 -376.985287) (xy 10.584433 -376.946933) (xy 10.553012 -376.903779)
			(xy 10.527913 -376.856665) (xy 10.509627 -376.806513) (xy 10.49851 -376.754301) (xy 10.494781 -376.70105)
			(xy 8.972797 -376.70105) (xy 8.969067 -376.754302) (xy 8.95795 -376.806513) (xy 8.939664 -376.856665)
			(xy 8.914565 -376.903779) (xy 8.883144 -376.946934) (xy 8.846013 -376.985287) (xy 8.82523 -377.00204)
			(xy 8.816443 -377.009577) (xy 8.806276 -377.030355) (xy 8.805672 -377.041918) (xy 8.805672 -377.122182)
			(xy 8.806228 -377.133752) (xy 8.81643 -377.154525) (xy 8.82523 -377.16206) (xy 8.847701 -377.180266)
			(xy 8.887435 -377.222284) (xy 8.920375 -377.269816) (xy 8.945765 -377.321774) (xy 8.963025 -377.376968)
			(xy 8.971758 -377.434135) (xy 8.972296 -377.46305) (xy 8.97181 -377.490301) (xy 8.964054 -377.544249)
			(xy 8.948699 -377.596544) (xy 8.926057 -377.646121) (xy 8.896591 -377.691971) (xy 8.8609 -377.733162)
			(xy 8.819709 -377.768853) (xy 8.773859 -377.798319) (xy 8.724282 -377.820961) (xy 8.671987 -377.836316)
			(xy 8.618039 -377.844072) (xy 8.563537 -377.844072) (xy 8.509589 -377.836316) (xy 8.457294 -377.820961)
			(xy 8.407717 -377.798319) (xy 8.361867 -377.768853) (xy 8.320676 -377.733162) (xy 8.284985 -377.691971)
			(xy 8.255519 -377.646121) (xy 8.232877 -377.596544) (xy 8.217522 -377.544249) (xy 8.209766 -377.490301)
			(xy 8.20928 -377.46305) (xy 8.209804 -377.434133) (xy 8.218528 -377.376961) (xy 8.235783 -377.321761)
			(xy 8.261173 -377.269798) (xy 8.294117 -377.222265) (xy 8.33386 -377.180249) (xy 8.356346 -377.16206)
			(xy 8.365129 -377.154519) (xy 8.375299 -377.133744) (xy 8.375904 -377.122182) (xy 8.375904 -377.041918)
			(xy 8.375322 -377.030352) (xy 8.365135 -377.009581) (xy 8.356346 -377.00204) (xy 8.335563 -376.985287)
			(xy 8.298433 -376.946933) (xy 8.267012 -376.903779) (xy 8.241913 -376.856665) (xy 8.223627 -376.806513)
			(xy 8.21251 -376.754301) (xy 8.208781 -376.70105) (xy 5.97408 -376.70105) (xy 5.97408 -377.963938)
			(xy 14.292072 -377.963938) (xy 14.292535 -377.937592) (xy 14.299764 -377.885398) (xy 14.314103 -377.834694)
			(xy 14.335281 -377.786445) (xy 14.362894 -377.741567) (xy 14.396418 -377.700914) (xy 14.415516 -377.68276)
			(xy 14.42339 -377.675648) (xy 14.431772 -377.656852) (xy 14.43355 -377.562364) (xy 14.42593 -377.543314)
			(xy 14.41831 -377.535694) (xy 14.397291 -377.514057) (xy 14.361641 -377.465399) (xy 14.334096 -377.411735)
			(xy 14.315343 -377.354404) (xy 14.30585 -377.294836) (xy 14.30528 -377.264676) (xy 14.305729 -377.23727)
			(xy 14.313582 -377.183025) (xy 14.329122 -377.130463) (xy 14.352029 -377.080668) (xy 14.38183 -377.034666)
			(xy 14.399514 -377.013724) (xy 14.40561 -377.006612) (xy 14.41196 -376.989594) (xy 14.41196 -376.903996)
			(xy 14.40561 -376.886978) (xy 14.399514 -376.879866) (xy 14.381832 -376.858924) (xy 14.352039 -376.812919)
			(xy 14.329139 -376.763124) (xy 14.313605 -376.710562) (xy 14.305756 -376.656318) (xy 14.30528 -376.628914)
			(xy 14.305825 -376.598573) (xy 14.315443 -376.538657) (xy 14.334423 -376.481018) (xy 14.362287 -376.427111)
			(xy 14.398332 -376.378293) (xy 14.41958 -376.356626) (xy 14.4272 -376.34926) (xy 14.43482 -376.330718)
			(xy 14.43482 -376.237246) (xy 14.4272 -376.218704) (xy 14.41958 -376.211338) (xy 14.39832 -376.189683)
			(xy 14.362282 -376.140862) (xy 14.334429 -376.08695) (xy 14.315462 -376.029309) (xy 14.305862 -375.969391)
			(xy 14.30528 -375.93905) (xy 14.305804 -375.910133) (xy 14.314528 -375.852961) (xy 14.331783 -375.797761)
			(xy 14.357173 -375.745798) (xy 14.390117 -375.698265) (xy 14.42986 -375.656249) (xy 14.452346 -375.63806)
			(xy 14.461129 -375.630519) (xy 14.471299 -375.609744) (xy 14.471904 -375.598182) (xy 14.471904 -375.517918)
			(xy 14.471322 -375.506352) (xy 14.461135 -375.485581) (xy 14.452346 -375.47804) (xy 14.42987 -375.45984)
			(xy 14.390137 -375.417821) (xy 14.357199 -375.370287) (xy 14.33181 -375.318328) (xy 14.314551 -375.263133)
			(xy 14.305818 -375.205965) (xy 14.30528 -375.17705) (xy 14.305766 -375.149799) (xy 14.313522 -375.095851)
			(xy 14.328877 -375.043556) (xy 14.351519 -374.993979) (xy 14.380985 -374.948129) (xy 14.416676 -374.906938)
			(xy 14.457867 -374.871247) (xy 14.503717 -374.841781) (xy 14.553294 -374.819139) (xy 14.605589 -374.803784)
			(xy 14.659537 -374.796028) (xy 14.714039 -374.796028) (xy 14.767987 -374.803784) (xy 14.820282 -374.819139)
			(xy 14.869859 -374.841781) (xy 14.915709 -374.871247) (xy 14.9569 -374.906938) (xy 14.992591 -374.948129)
			(xy 15.022057 -374.993979) (xy 15.044699 -375.043556) (xy 15.060054 -375.095851) (xy 15.06781 -375.149799)
			(xy 15.068296 -375.17705) (xy 15.067743 -375.205966) (xy 15.059022 -375.263135) (xy 15.041771 -375.318334)
			(xy 15.016385 -375.370295) (xy 14.983448 -375.41783) (xy 14.943713 -375.459849) (xy 14.92123 -375.47804)
			(xy 14.912443 -375.485577) (xy 14.902276 -375.506355) (xy 14.901672 -375.517918) (xy 14.901672 -375.598182)
			(xy 14.902228 -375.609752) (xy 14.91243 -375.630525) (xy 14.92123 -375.63806) (xy 14.943701 -375.656266)
			(xy 14.983435 -375.698284) (xy 15.016375 -375.745816) (xy 15.041765 -375.797774) (xy 15.059025 -375.852968)
			(xy 15.067758 -375.910135) (xy 15.068296 -375.93905) (xy 15.067706 -375.969389) (xy 15.058096 -376.029302)
			(xy 15.039125 -376.086939) (xy 15.011272 -376.140847) (xy 14.975238 -376.189668) (xy 14.953996 -376.211338)
			(xy 14.946376 -376.218704) (xy 14.938756 -376.237246) (xy 14.938756 -376.330718) (xy 14.946376 -376.34926)
			(xy 14.953996 -376.356626) (xy 14.975234 -376.378301) (xy 15.011276 -376.427116) (xy 15.039134 -376.481023)
			(xy 15.058105 -376.53866) (xy 15.067711 -376.598574) (xy 15.068296 -376.628914) (xy 15.067847 -376.65632)
			(xy 15.059995 -376.710566) (xy 15.044456 -376.763128) (xy 15.021548 -376.812923) (xy 14.991746 -376.858924)
			(xy 14.974062 -376.879866) (xy 14.967966 -376.886978) (xy 14.961616 -376.903996) (xy 14.961616 -376.989594)
			(xy 14.967966 -377.006612) (xy 14.974062 -377.013724) (xy 14.991735 -377.034673) (xy 15.021531 -377.080675)
			(xy 15.044432 -377.130469) (xy 15.059969 -377.183029) (xy 15.06782 -377.237272) (xy 15.068296 -377.264676)
			(xy 15.067853 -377.291023) (xy 15.060621 -377.343219) (xy 15.046279 -377.393923) (xy 15.025097 -377.442172)
			(xy 14.99748 -377.48705) (xy 14.963953 -377.527701) (xy 14.944852 -377.545854) (xy 14.936978 -377.552966)
			(xy 14.928596 -377.571762) (xy 14.926818 -377.66625) (xy 14.934438 -377.6853) (xy 14.942058 -377.69292)
			(xy 14.963096 -377.71454) (xy 14.998741 -377.763204) (xy 15.026281 -377.816872) (xy 15.045029 -377.874206)
			(xy 15.054519 -377.933777) (xy 15.054911 -377.95454) (xy 16.559276 -377.95454) (xy 16.559865 -377.924417)
			(xy 16.56934 -377.864921) (xy 16.588047 -377.807653) (xy 16.615519 -377.754036) (xy 16.651074 -377.705401)
			(xy 16.672052 -377.683776) (xy 16.679418 -377.67641) (xy 16.687038 -377.658376) (xy 16.687546 -377.56592)
			(xy 16.68018 -377.547632) (xy 16.672814 -377.540266) (xy 16.652346 -377.5187) (xy 16.617644 -377.470424)
			(xy 16.590855 -377.417347) (xy 16.572626 -377.360757) (xy 16.563401 -377.302023) (xy 16.562832 -377.272296)
			(xy 16.563335 -377.243378) (xy 16.572066 -377.186206) (xy 16.589326 -377.131006) (xy 16.61472 -377.079044)
			(xy 16.647667 -377.031511) (xy 16.687411 -376.989495) (xy 16.709898 -376.971306) (xy 16.718652 -376.963737)
			(xy 16.72884 -376.942984) (xy 16.729456 -376.931428) (xy 16.729456 -376.851164) (xy 16.728864 -376.839599)
			(xy 16.718686 -376.818826) (xy 16.709898 -376.811286) (xy 16.687407 -376.793103) (xy 16.647673 -376.751082)
			(xy 16.614735 -376.703545) (xy 16.589347 -376.651582) (xy 16.572093 -376.596383) (xy 16.563366 -376.539212)
			(xy 16.562832 -376.510296) (xy 16.563308 -376.483052) (xy 16.571066 -376.429118) (xy 16.586423 -376.376839)
			(xy 16.609066 -376.327278) (xy 16.638534 -376.281445) (xy 16.674227 -376.240275) (xy 16.715418 -376.204605)
			(xy 16.738092 -376.189494) (xy 16.74876 -376.182382) (xy 16.760952 -376.160538) (xy 16.763746 -376.051064)
			(xy 16.752316 -376.028458) (xy 16.742156 -376.021092) (xy 16.721253 -376.00571) (xy 16.68343 -375.970175)
			(xy 16.650778 -375.929836) (xy 16.623903 -375.885439) (xy 16.6033 -375.837806) (xy 16.589352 -375.787818)
			(xy 16.582316 -375.736399) (xy 16.581882 -375.71045) (xy 16.582315 -375.684786) (xy 16.589185 -375.633921)
			(xy 16.602819 -375.584437) (xy 16.622972 -375.537232) (xy 16.649278 -375.493158) (xy 16.681262 -375.453015)
			(xy 16.718345 -375.417527) (xy 16.738854 -375.402094) (xy 16.747998 -375.39549) (xy 16.758666 -375.376186)
			(xy 16.76654 -375.276618) (xy 16.75892 -375.256044) (xy 16.750792 -375.247916) (xy 16.729976 -375.226332)
			(xy 16.694724 -375.177826) (xy 16.667497 -375.124401) (xy 16.648966 -375.067374) (xy 16.639587 -375.008149)
			(xy 16.639032 -374.978168) (xy 16.639518 -374.950917) (xy 16.647274 -374.896969) (xy 16.662629 -374.844674)
			(xy 16.685271 -374.795097) (xy 16.714737 -374.749247) (xy 16.750428 -374.708056) (xy 16.791619 -374.672365)
			(xy 16.837469 -374.642899) (xy 16.887046 -374.620257) (xy 16.939341 -374.604902) (xy 16.993289 -374.597146)
			(xy 17.047791 -374.597146) (xy 17.101739 -374.604902) (xy 17.154034 -374.620257) (xy 17.203611 -374.642899)
			(xy 17.249461 -374.672365) (xy 17.290652 -374.708056) (xy 17.326343 -374.749247) (xy 17.355809 -374.795097)
			(xy 17.378451 -374.844674) (xy 17.393806 -374.896969) (xy 17.401562 -374.950917) (xy 17.402048 -374.978168)
			(xy 17.401616 -375.003832) (xy 17.394745 -375.054697) (xy 17.38111 -375.10418) (xy 17.360956 -375.151385)
			(xy 17.33465 -375.195458) (xy 17.302666 -375.235602) (xy 17.265584 -375.27109) (xy 17.245076 -375.286524)
			(xy 17.235932 -375.293128) (xy 17.225264 -375.312432) (xy 17.21739 -375.412) (xy 17.22501 -375.432574)
			(xy 17.233138 -375.440702) (xy 17.25395 -375.46229) (xy 17.289205 -375.510794) (xy 17.316434 -375.564217)
			(xy 17.334966 -375.621244) (xy 17.344343 -375.680469) (xy 17.344898 -375.71045) (xy 17.344444 -375.737695)
			(xy 17.33668 -375.791629) (xy 17.321318 -375.843908) (xy 17.298671 -375.893469) (xy 17.2692 -375.939301)
			(xy 17.233505 -375.980471) (xy 17.192313 -376.016141) (xy 17.169638 -376.031252) (xy 17.15897 -376.038364)
			(xy 17.146778 -376.060208) (xy 17.143984 -376.169682) (xy 17.155414 -376.192288) (xy 17.165574 -376.199654)
			(xy 17.186458 -376.21506) (xy 17.224281 -376.250592) (xy 17.256933 -376.290928) (xy 17.28381 -376.33532)
			(xy 17.304416 -376.382949) (xy 17.318368 -376.432933) (xy 17.32541 -376.484348) (xy 17.325848 -376.510296)
			(xy 17.325346 -376.539214) (xy 17.316617 -376.596387) (xy 17.299357 -376.651587) (xy 17.273962 -376.703549)
			(xy 17.241015 -376.751082) (xy 17.20127 -376.793097) (xy 17.178782 -376.811286) (xy 17.170028 -376.818855)
			(xy 17.159841 -376.839608) (xy 17.159224 -376.851164) (xy 17.159224 -376.931428) (xy 17.159827 -376.942992)
			(xy 17.169998 -376.963764) (xy 17.178782 -376.971306) (xy 17.201265 -376.989498) (xy 17.241001 -377.031517)
			(xy 17.27394 -377.079052) (xy 17.299329 -377.131013) (xy 17.316585 -377.18621) (xy 17.325314 -377.24338)
			(xy 17.325848 -377.272296) (xy 17.325275 -377.302419) (xy 17.315795 -377.361916) (xy 17.297085 -377.419184)
			(xy 17.269609 -377.472801) (xy 17.234051 -377.521435) (xy 17.213072 -377.54306) (xy 17.205706 -377.550426)
			(xy 17.198086 -377.56846) (xy 17.197578 -377.660916) (xy 17.204944 -377.679204) (xy 17.21231 -377.68657)
			(xy 17.232799 -377.708117) (xy 17.267497 -377.756399) (xy 17.294282 -377.80948) (xy 17.312506 -377.866075)
			(xy 17.321726 -377.924812) (xy 17.322292 -377.95454) (xy 17.321806 -377.981791) (xy 17.31405 -378.035739)
			(xy 17.298695 -378.088034) (xy 17.276053 -378.137611) (xy 17.246587 -378.183461) (xy 17.210896 -378.224652)
			(xy 17.169705 -378.260343) (xy 17.123855 -378.289809) (xy 17.074278 -378.312451) (xy 17.021983 -378.327806)
			(xy 16.968035 -378.335562) (xy 16.913533 -378.335562) (xy 16.859585 -378.327806) (xy 16.80729 -378.312451)
			(xy 16.757713 -378.289809) (xy 16.711863 -378.260343) (xy 16.670672 -378.224652) (xy 16.634981 -378.183461)
			(xy 16.605515 -378.137611) (xy 16.582873 -378.088034) (xy 16.567518 -378.035739) (xy 16.559762 -377.981791)
			(xy 16.559276 -377.95454) (xy 15.054911 -377.95454) (xy 15.055088 -377.963938) (xy 15.054596 -377.991648)
			(xy 15.046568 -378.046482) (xy 15.030685 -378.099577) (xy 15.007284 -378.149813) (xy 14.976857 -378.196133)
			(xy 14.958822 -378.217176) (xy 14.952726 -378.224288) (xy 14.946122 -378.24156) (xy 14.946376 -378.328174)
			(xy 14.95298 -378.345446) (xy 14.95933 -378.352558) (xy 14.977614 -378.373652) (xy 15.00844 -378.420193)
			(xy 15.032153 -378.470729) (xy 15.048248 -378.524181) (xy 15.056381 -378.579408) (xy 15.056866 -378.60732)
			(xy 15.05638 -378.634571) (xy 15.048624 -378.688519) (xy 15.033269 -378.740814) (xy 15.010627 -378.790391)
			(xy 14.981161 -378.836241) (xy 14.94547 -378.877432) (xy 14.904279 -378.913123) (xy 14.858429 -378.942589)
			(xy 14.808852 -378.965231) (xy 14.756557 -378.980586) (xy 14.702609 -378.988342) (xy 14.648107 -378.988342)
			(xy 14.594159 -378.980586) (xy 14.541864 -378.965231) (xy 14.492287 -378.942589) (xy 14.446437 -378.913123)
			(xy 14.405246 -378.877432) (xy 14.369555 -378.836241) (xy 14.340089 -378.790391) (xy 14.317447 -378.740814)
			(xy 14.302092 -378.688519) (xy 14.294336 -378.634571) (xy 14.29385 -378.60732) (xy 14.294333 -378.57961)
			(xy 14.302366 -378.524776) (xy 14.318251 -378.471681) (xy 14.341654 -378.421445) (xy 14.372081 -378.375126)
			(xy 14.390116 -378.354082) (xy 14.396212 -378.34697) (xy 14.402816 -378.329698) (xy 14.402562 -378.243084)
			(xy 14.395958 -378.225812) (xy 14.389608 -378.2187) (xy 14.371357 -378.197578) (xy 14.340525 -378.151046)
			(xy 14.316805 -378.100517) (xy 14.300702 -378.047071) (xy 14.292561 -377.991848) (xy 14.292072 -377.963938)
			(xy 5.97408 -377.963938) (xy 5.97408 -381.41402) (xy 6.528562 -381.41402) (xy 6.528988 -381.38764)
			(xy 6.536251 -381.335383) (xy 6.55064 -381.284623) (xy 6.571882 -381.236329) (xy 6.599573 -381.19142)
			(xy 6.633183 -381.150752) (xy 6.672074 -381.115099) (xy 6.715503 -381.085142) (xy 6.738874 -381.072898)
			(xy 6.751214 -381.066166) (xy 6.77194 -381.047195) (xy 6.786699 -381.023287) (xy 6.794371 -380.996257)
			(xy 6.794374 -380.96816) (xy 6.786706 -380.94113) (xy 6.771951 -380.917219) (xy 6.751229 -380.898244)
			(xy 6.738874 -380.891542) (xy 6.715506 -380.879296) (xy 6.672083 -380.849334) (xy 6.633198 -380.813679)
			(xy 6.599593 -380.77301) (xy 6.571906 -380.728102) (xy 6.550665 -380.679809) (xy 6.536274 -380.629053)
			(xy 6.529009 -380.576799) (xy 6.528562 -380.55042) (xy 6.529048 -380.523169) (xy 6.536804 -380.469221)
			(xy 6.552159 -380.416926) (xy 6.574801 -380.367349) (xy 6.604267 -380.321499) (xy 6.639958 -380.280308)
			(xy 6.681149 -380.244617) (xy 6.726999 -380.215151) (xy 6.776576 -380.192509) (xy 6.828871 -380.177154)
			(xy 6.882819 -380.169398) (xy 6.937321 -380.169398) (xy 6.991269 -380.177154) (xy 7.043564 -380.192509)
			(xy 7.093141 -380.215151) (xy 7.138991 -380.244617) (xy 7.180182 -380.280308) (xy 7.215873 -380.321499)
			(xy 7.245339 -380.367349) (xy 7.267981 -380.416926) (xy 7.283336 -380.469221) (xy 7.291092 -380.523169)
			(xy 7.291578 -380.55042) (xy 7.291135 -380.5768) (xy 7.283879 -380.629058) (xy 7.269495 -380.679818)
			(xy 7.248257 -380.728114) (xy 7.220568 -380.773024) (xy 7.186959 -380.813693) (xy 7.148068 -380.849344)
			(xy 7.138344 -380.856051) (xy 9.436082 -380.856051) (xy 9.436082 -380.801549) (xy 9.443838 -380.747602)
			(xy 9.459193 -380.695308) (xy 9.481834 -380.645731) (xy 9.5113 -380.599881) (xy 9.546991 -380.558691)
			(xy 9.588181 -380.523) (xy 9.634031 -380.493534) (xy 9.683608 -380.470893) (xy 9.735902 -380.455538)
			(xy 9.789849 -380.447782) (xy 9.8171 -380.447296) (xy 9.842716 -380.447723) (xy 9.893486 -380.454584)
			(xy 9.942881 -380.46818) (xy 9.990009 -380.488269) (xy 10.034024 -380.514487) (xy 10.054336 -380.5301)
			(xy 10.062464 -380.53645) (xy 10.082276 -380.542038) (xy 10.17524 -380.529846) (xy 10.19302 -380.519432)
			(xy 10.199116 -380.51105) (xy 10.208935 -380.498203) (xy 10.230428 -380.474041) (xy 10.242042 -380.46279)
			(xy 10.249916 -380.45517) (xy 10.25779 -380.435866) (xy 10.256012 -380.3396) (xy 10.247376 -380.32055)
			(xy 10.239248 -380.313184) (xy 10.219468 -380.294997) (xy 10.184674 -380.254051) (xy 10.155972 -380.208626)
			(xy 10.133932 -380.159621) (xy 10.118989 -380.108008) (xy 10.11144 -380.054808) (xy 10.110978 -380.027942)
			(xy 10.111464 -380.000691) (xy 10.11922 -379.946743) (xy 10.134575 -379.894448) (xy 10.157217 -379.844871)
			(xy 10.186683 -379.799021) (xy 10.222374 -379.75783) (xy 10.263565 -379.722139) (xy 10.309415 -379.692673)
			(xy 10.358992 -379.670031) (xy 10.411287 -379.654676) (xy 10.465235 -379.64692) (xy 10.519737 -379.64692)
			(xy 10.573685 -379.654676) (xy 10.62598 -379.670031) (xy 10.675557 -379.692673) (xy 10.721407 -379.722139)
			(xy 10.762598 -379.75783) (xy 10.798289 -379.799021) (xy 10.827755 -379.844871) (xy 10.850397 -379.894448)
			(xy 10.865752 -379.946743) (xy 10.873508 -380.000691) (xy 10.873994 -380.027942) (xy 10.873606 -380.053088)
			(xy 12.10945 -380.053088) (xy 12.109966 -380.025484) (xy 12.117913 -379.97085) (xy 12.133654 -379.917933)
			(xy 12.15686 -379.867839) (xy 12.187045 -379.821613) (xy 12.22358 -379.780222) (xy 12.244324 -379.762004)
			(xy 12.252452 -379.755146) (xy 12.26185 -379.735842) (xy 12.264898 -379.63856) (xy 12.25677 -379.619002)
			(xy 12.248896 -379.611382) (xy 12.230736 -379.593319) (xy 12.198897 -379.553199) (xy 12.17271 -379.50918)
			(xy 12.152646 -379.462055) (xy 12.139067 -379.412668) (xy 12.132215 -379.36191) (xy 12.131802 -379.3363)
			(xy 12.132268 -379.30893) (xy 12.140085 -379.254751) (xy 12.155575 -379.202247) (xy 12.178416 -379.152501)
			(xy 12.208141 -379.106534) (xy 12.225782 -379.085602) (xy 12.231878 -379.07849) (xy 12.238228 -379.061472)
			(xy 12.238228 -378.976128) (xy 12.231878 -378.95911) (xy 12.225782 -378.951998) (xy 12.208126 -378.93108)
			(xy 12.178417 -378.885103) (xy 12.155585 -378.835352) (xy 12.140098 -378.782848) (xy 12.132274 -378.72867)
			(xy 12.131802 -378.7013) (xy 12.132288 -378.674049) (xy 12.140044 -378.620101) (xy 12.155399 -378.567806)
			(xy 12.178041 -378.518229) (xy 12.207507 -378.472379) (xy 12.243198 -378.431188) (xy 12.284389 -378.395497)
			(xy 12.330239 -378.366031) (xy 12.379816 -378.343389) (xy 12.432111 -378.328034) (xy 12.486059 -378.320278)
			(xy 12.540561 -378.320278) (xy 12.594509 -378.328034) (xy 12.646804 -378.343389) (xy 12.696381 -378.366031)
			(xy 12.742231 -378.395497) (xy 12.783422 -378.431188) (xy 12.819113 -378.472379) (xy 12.848579 -378.518229)
			(xy 12.871221 -378.567806) (xy 12.886576 -378.620101) (xy 12.894332 -378.674049) (xy 12.894818 -378.7013)
			(xy 12.894372 -378.728671) (xy 12.886552 -378.782852) (xy 12.87106 -378.835356) (xy 12.848213 -378.885103)
			(xy 12.818482 -378.931068) (xy 12.800838 -378.951998) (xy 12.794742 -378.95911) (xy 12.788392 -378.976128)
			(xy 12.788392 -379.061472) (xy 12.794742 -379.07849) (xy 12.800838 -379.085602) (xy 12.818498 -379.106517)
			(xy 12.848205 -379.152495) (xy 12.871037 -379.202247) (xy 12.886523 -379.254751) (xy 12.894347 -379.30893)
			(xy 12.894818 -379.3363) (xy 12.894374 -379.363907) (xy 12.886414 -379.418544) (xy 12.870659 -379.471463)
			(xy 12.84744 -379.521558) (xy 12.817241 -379.567781) (xy 12.780694 -379.609168) (xy 12.759944 -379.627384)
			(xy 12.751816 -379.634242) (xy 12.742418 -379.653546) (xy 12.73937 -379.750828) (xy 12.747498 -379.770386)
			(xy 12.755372 -379.778006) (xy 12.773568 -379.796033) (xy 12.805406 -379.836161) (xy 12.831589 -379.880187)
			(xy 12.851646 -379.927319) (xy 12.865217 -379.976712) (xy 12.872058 -380.027476) (xy 12.872466 -380.053088)
			(xy 12.872004 -380.080663) (xy 12.864052 -380.135236) (xy 12.848327 -380.188097) (xy 12.825157 -380.238143)
			(xy 12.795023 -380.284332) (xy 12.758554 -380.325703) (xy 12.737846 -380.343918) (xy 12.72921 -380.351284)
			(xy 12.719812 -380.37135) (xy 12.72032 -380.471934) (xy 12.729718 -380.492) (xy 12.738354 -380.499366)
			(xy 12.759369 -380.517586) (xy 12.796408 -380.559077) (xy 12.827037 -380.605502) (xy 12.850607 -380.655879)
			(xy 12.866619 -380.709142) (xy 12.874734 -380.764165) (xy 12.87526 -380.791974) (xy 12.874774 -380.819225)
			(xy 12.867018 -380.873173) (xy 12.851663 -380.925468) (xy 12.829021 -380.975045) (xy 12.799555 -381.020895)
			(xy 12.763864 -381.062086) (xy 12.722673 -381.097777) (xy 12.676823 -381.127243) (xy 12.627246 -381.149885)
			(xy 12.574951 -381.16524) (xy 12.521003 -381.172996) (xy 12.466501 -381.172996) (xy 12.412553 -381.16524)
			(xy 12.360258 -381.149885) (xy 12.310681 -381.127243) (xy 12.264831 -381.097777) (xy 12.22364 -381.062086)
			(xy 12.187949 -381.020895) (xy 12.158483 -380.975045) (xy 12.135841 -380.925468) (xy 12.120486 -380.873173)
			(xy 12.11273 -380.819225) (xy 12.112244 -380.791974) (xy 12.112745 -380.764401) (xy 12.120688 -380.709829)
			(xy 12.136405 -380.656969) (xy 12.159569 -380.606922) (xy 12.189696 -380.560732) (xy 12.226159 -380.51936)
			(xy 12.246864 -380.501144) (xy 12.2555 -380.493778) (xy 12.264898 -380.473712) (xy 12.26439 -380.373128)
			(xy 12.254992 -380.353062) (xy 12.246356 -380.345696) (xy 12.225325 -380.327494) (xy 12.188286 -380.286)
			(xy 12.157659 -380.239571) (xy 12.134092 -380.18919) (xy 12.118084 -380.135924) (xy 12.109973 -380.080898)
			(xy 12.10945 -380.053088) (xy 10.873606 -380.053088) (xy 10.873597 -380.053653) (xy 10.866669 -380.104608)
			(xy 10.852958 -380.154169) (xy 10.832712 -380.20144) (xy 10.806299 -380.245561) (xy 10.774197 -380.285734)
			(xy 10.755884 -380.303786) (xy 10.74801 -380.311406) (xy 10.740136 -380.33071) (xy 10.741914 -380.426976)
			(xy 10.75055 -380.446026) (xy 10.758678 -380.453392) (xy 10.7785 -380.471535) (xy 10.81329 -380.512491)
			(xy 10.841985 -380.557926) (xy 10.864018 -380.606939) (xy 10.878952 -380.658559) (xy 10.886491 -380.711765)
			(xy 10.886948 -380.738634) (xy 10.886454 -380.765884) (xy 10.878694 -380.81983) (xy 10.863336 -380.872122)
			(xy 10.840694 -380.921696) (xy 10.811228 -380.967545) (xy 10.775538 -381.008734) (xy 10.73435 -381.044425)
			(xy 10.688502 -381.073891) (xy 10.638927 -381.096534) (xy 10.586635 -381.111893) (xy 10.53269 -381.119654)
			(xy 10.50544 -381.120142) (xy 10.479824 -381.119706) (xy 10.429054 -381.11285) (xy 10.379659 -381.099256)
			(xy 10.33253 -381.079169) (xy 10.288516 -381.052951) (xy 10.268204 -381.037338) (xy 10.260076 -381.030988)
			(xy 10.240264 -381.0254) (xy 10.1473 -381.037592) (xy 10.12952 -381.048006) (xy 10.123424 -381.056388)
			(xy 10.105294 -381.079848) (xy 10.062978 -381.121375) (xy 10.014752 -381.155861) (xy 9.961775 -381.182479)
			(xy 9.90532 -381.200587) (xy 9.846744 -381.209752) (xy 9.8171 -381.210312) (xy 9.789849 -381.209818)
			(xy 9.735902 -381.202062) (xy 9.683608 -381.186707) (xy 9.634031 -381.164066) (xy 9.588181 -381.1346)
			(xy 9.546991 -381.098909) (xy 9.5113 -381.057719) (xy 9.481834 -381.011869) (xy 9.459193 -380.962292)
			(xy 9.443838 -380.909998) (xy 9.436082 -380.856051) (xy 7.138344 -380.856051) (xy 7.104637 -380.8793)
			(xy 7.081266 -380.891542) (xy 7.068887 -380.898211) (xy 7.04815 -380.91719) (xy 7.033383 -380.94111)
			(xy 7.025709 -380.968153) (xy 7.025712 -380.996264) (xy 7.03339 -381.023306) (xy 7.048161 -381.047224)
			(xy 7.068902 -381.066199) (xy 7.081266 -381.072898) (xy 7.104634 -381.085144) (xy 7.148057 -381.115106)
			(xy 7.186942 -381.150761) (xy 7.220547 -381.19143) (xy 7.248234 -381.236338) (xy 7.269475 -381.284631)
			(xy 7.283866 -381.335387) (xy 7.291131 -381.387641) (xy 7.291427 -381.40513) (xy 15.882112 -381.40513)
			(xy 15.882593 -381.37776) (xy 15.890407 -381.323582) (xy 15.905892 -381.271079) (xy 15.928731 -381.221332)
			(xy 15.958452 -381.175364) (xy 15.976092 -381.154432) (xy 15.982188 -381.14732) (xy 15.988538 -381.130302)
			(xy 15.988538 -381.044958) (xy 15.982188 -381.02794) (xy 15.976092 -381.020828) (xy 15.958482 -380.999871)
			(xy 15.928759 -380.953906) (xy 15.905914 -380.904164) (xy 15.890417 -380.851666) (xy 15.882586 -380.797491)
			(xy 15.882583 -380.742754) (xy 15.890407 -380.688578) (xy 15.905898 -380.636078) (xy 15.928737 -380.586333)
			(xy 15.958455 -380.540365) (xy 15.976092 -380.519432) (xy 15.982188 -380.51232) (xy 15.988538 -380.495302)
			(xy 15.988538 -380.409958) (xy 15.982188 -380.39294) (xy 15.976092 -380.385828) (xy 15.958482 -380.364871)
			(xy 15.928759 -380.318906) (xy 15.905914 -380.269164) (xy 15.890417 -380.216666) (xy 15.882586 -380.162491)
			(xy 15.882583 -380.107754) (xy 15.890407 -380.053578) (xy 15.905898 -380.001078) (xy 15.928737 -379.951333)
			(xy 15.958455 -379.905365) (xy 15.976092 -379.884432) (xy 15.982188 -379.87732) (xy 15.988538 -379.860302)
			(xy 15.988538 -379.774958) (xy 15.982188 -379.75794) (xy 15.976092 -379.750828) (xy 15.958482 -379.729871)
			(xy 15.928759 -379.683906) (xy 15.905914 -379.634164) (xy 15.890417 -379.581666) (xy 15.882586 -379.527491)
			(xy 15.882583 -379.472754) (xy 15.890407 -379.418578) (xy 15.905898 -379.366078) (xy 15.928737 -379.316333)
			(xy 15.958455 -379.270365) (xy 15.976092 -379.249432) (xy 15.982188 -379.24232) (xy 15.988538 -379.225302)
			(xy 15.988538 -379.139958) (xy 15.982188 -379.12294) (xy 15.976092 -379.115828) (xy 15.958451 -379.094897)
			(xy 15.92874 -379.048924) (xy 15.905904 -378.999176) (xy 15.890414 -378.946675) (xy 15.882586 -378.892499)
			(xy 15.882112 -378.86513) (xy 15.882598 -378.837879) (xy 15.890354 -378.783931) (xy 15.905709 -378.731636)
			(xy 15.928351 -378.682059) (xy 15.957817 -378.636209) (xy 15.993508 -378.595018) (xy 16.034699 -378.559327)
			(xy 16.080549 -378.529861) (xy 16.130126 -378.507219) (xy 16.182421 -378.491864) (xy 16.236369 -378.484108)
			(xy 16.290871 -378.484108) (xy 16.344819 -378.491864) (xy 16.397114 -378.507219) (xy 16.446691 -378.529861)
			(xy 16.492541 -378.559327) (xy 16.533732 -378.595018) (xy 16.569423 -378.636209) (xy 16.598889 -378.682059)
			(xy 16.621531 -378.731636) (xy 16.636886 -378.783931) (xy 16.644642 -378.837879) (xy 16.645128 -378.86513)
			(xy 16.644697 -378.892502) (xy 16.636873 -378.946683) (xy 16.621377 -378.999187) (xy 16.598527 -379.048934)
			(xy 16.568794 -379.094898) (xy 16.551148 -379.115828) (xy 16.545052 -379.12294) (xy 16.538702 -379.139958)
			(xy 16.538702 -379.225302) (xy 16.545052 -379.24232) (xy 16.551148 -379.249432) (xy 16.568819 -379.27034)
			(xy 16.598545 -379.316312) (xy 16.62139 -379.366062) (xy 16.636885 -379.418568) (xy 16.644711 -379.47275)
			(xy 16.644708 -379.527495) (xy 16.636875 -379.581676) (xy 16.621374 -379.63418) (xy 16.598523 -379.683928)
			(xy 16.568792 -379.729896) (xy 16.551148 -379.750828) (xy 16.545052 -379.75794) (xy 16.538702 -379.774958)
			(xy 16.538702 -379.860302) (xy 16.545052 -379.87732) (xy 16.551148 -379.884432) (xy 16.568819 -379.90534)
			(xy 16.598545 -379.951312) (xy 16.62139 -380.001062) (xy 16.636885 -380.053568) (xy 16.644711 -380.10775)
			(xy 16.644708 -380.162495) (xy 16.636875 -380.216676) (xy 16.621374 -380.26918) (xy 16.598523 -380.318928)
			(xy 16.568792 -380.364896) (xy 16.551148 -380.385828) (xy 16.545052 -380.39294) (xy 16.538702 -380.409958)
			(xy 16.538702 -380.495302) (xy 16.545052 -380.51232) (xy 16.551148 -380.519432) (xy 16.568819 -380.54034)
			(xy 16.598545 -380.586312) (xy 16.62139 -380.636062) (xy 16.636885 -380.688568) (xy 16.644711 -380.74275)
			(xy 16.644708 -380.797495) (xy 16.644405 -380.799594) (xy 18.005552 -380.799594) (xy 18.005939 -380.774164)
			(xy 18.012698 -380.723755) (xy 18.026095 -380.674691) (xy 18.045893 -380.627843) (xy 18.071741 -380.584041)
			(xy 18.103179 -380.544061) (xy 18.121122 -380.526036) (xy 18.128488 -380.518924) (xy 18.136362 -380.500382)
			(xy 18.136616 -380.406656) (xy 18.128742 -380.388114) (xy 18.121376 -380.380748) (xy 18.10012 -380.35909)
			(xy 18.064082 -380.310269) (xy 18.036228 -380.256358) (xy 18.01726 -380.198718) (xy 18.007659 -380.138801)
			(xy 18.007076 -380.10846) (xy 18.007582 -380.079721) (xy 18.01621 -380.022893) (xy 18.033264 -379.968002)
			(xy 18.05836 -379.916291) (xy 18.090928 -379.868929) (xy 18.1102 -379.847602) (xy 18.116804 -379.84049)
			(xy 18.123916 -379.822964) (xy 18.123916 -379.733556) (xy 18.116804 -379.71603) (xy 18.1102 -379.708918)
			(xy 18.090929 -379.687591) (xy 18.058364 -379.640229) (xy 18.033273 -379.588517) (xy 18.016223 -379.533626)
			(xy 18.007601 -379.476799) (xy 18.007601 -379.419321) (xy 18.016223 -379.362494) (xy 18.033273 -379.307603)
			(xy 18.058364 -379.255891) (xy 18.090929 -379.208529) (xy 18.1102 -379.187202) (xy 18.116804 -379.18009)
			(xy 18.123916 -379.162564) (xy 18.123916 -379.073156) (xy 18.116804 -379.05563) (xy 18.1102 -379.048518)
			(xy 18.090921 -379.027198) (xy 18.058354 -378.979835) (xy 18.033262 -378.928122) (xy 18.016213 -378.873229)
			(xy 18.007595 -378.8164) (xy 18.007076 -378.78766) (xy 18.007541 -378.760408) (xy 18.015302 -378.706461)
			(xy 18.030661 -378.654167) (xy 18.053306 -378.60459) (xy 18.082775 -378.558741) (xy 18.118469 -378.517552)
			(xy 18.15966 -378.481861) (xy 18.205511 -378.452395) (xy 18.255089 -378.429753) (xy 18.307384 -378.414397)
			(xy 18.361332 -378.406639) (xy 18.388584 -378.406152) (xy 18.417229 -378.406637) (xy 18.473874 -378.415214)
			(xy 18.528601 -378.432164) (xy 18.580178 -378.457104) (xy 18.627447 -378.489474) (xy 18.669346 -378.528548)
			(xy 18.687542 -378.550678) (xy 18.6944 -378.559314) (xy 18.713704 -378.56922) (xy 18.811748 -378.574554)
			(xy 18.832068 -378.56668) (xy 18.839688 -378.558806) (xy 18.861356 -378.537509) (xy 18.910208 -378.501392)
			(xy 18.964166 -378.473475) (xy 19.021868 -378.454464) (xy 19.081854 -378.444839) (xy 19.11223 -378.444252)
			(xy 19.14149 -378.444813) (xy 19.199321 -378.453759) (xy 19.255112 -378.471422) (xy 19.307555 -378.497388)
			(xy 19.355424 -378.53105) (xy 19.376898 -378.550932) (xy 19.38401 -378.55779) (xy 19.402044 -378.565156)
			(xy 19.492468 -378.565156) (xy 19.510502 -378.55779) (xy 19.517614 -378.550932) (xy 19.539048 -378.531001)
			(xy 19.586919 -378.497327) (xy 19.639371 -378.471358) (xy 19.695174 -378.453703) (xy 19.753018 -378.444778)
			(xy 19.782282 -378.444252) (xy 19.811862 -378.444836) (xy 19.870315 -378.453966) (xy 19.926657 -378.472009)
			(xy 19.979539 -378.498533) (xy 20.027693 -378.532901) (xy 20.069964 -378.574291) (xy 20.088098 -378.597668)
			(xy 20.095686 -378.606789) (xy 20.116888 -378.617376) (xy 20.128738 -378.617988) (xy 20.210272 -378.617988)
			(xy 20.222117 -378.617357) (xy 20.243308 -378.60677) (xy 20.250912 -378.597668) (xy 20.260074 -378.585618)
			(xy 20.280037 -378.562857) (xy 20.29079 -378.552202) (xy 20.298664 -378.544582) (xy 20.306538 -378.525024)
			(xy 20.303744 -378.428504) (xy 20.294854 -378.409454) (xy 20.286726 -378.402342) (xy 20.266449 -378.384128)
			(xy 20.230747 -378.342943) (xy 20.201264 -378.297102) (xy 20.178597 -378.247534) (xy 20.163208 -378.195247)
			(xy 20.155409 -378.141304) (xy 20.1549 -378.114052) (xy 20.155347 -378.086223) (xy 20.163428 -378.031153)
			(xy 20.179427 -377.977844) (xy 20.203003 -377.927425) (xy 20.233657 -377.880968) (xy 20.270736 -377.839458)
			(xy 20.313455 -377.803779) (xy 20.360905 -377.774686) (xy 20.386294 -377.763278) (xy 20.395946 -377.759214)
			(xy 20.41017 -377.744482) (xy 20.443444 -377.656344) (xy 20.442428 -377.63577) (xy 20.43811 -377.626372)
			(xy 20.42649 -377.600731) (xy 20.410102 -377.546875) (xy 20.4018 -377.491197) (xy 20.40128 -377.46305)
			(xy 20.401804 -377.434133) (xy 20.410528 -377.376961) (xy 20.427783 -377.321761) (xy 20.453173 -377.269798)
			(xy 20.486117 -377.222265) (xy 20.52586 -377.180249) (xy 20.548346 -377.16206) (xy 20.557129 -377.154519)
			(xy 20.567299 -377.133744) (xy 20.567904 -377.122182) (xy 20.567904 -377.041918) (xy 20.567322 -377.030352)
			(xy 20.557135 -377.009581) (xy 20.548346 -377.00204) (xy 20.527563 -376.985287) (xy 20.490433 -376.946933)
			(xy 20.459012 -376.903779) (xy 20.433913 -376.856665) (xy 20.415627 -376.806513) (xy 20.40451 -376.754301)
			(xy 20.400781 -376.70105) (xy 20.40451 -376.647799) (xy 20.415627 -376.595587) (xy 20.433913 -376.545435)
			(xy 20.459012 -376.498321) (xy 20.490433 -376.455167) (xy 20.527563 -376.416813) (xy 20.548346 -376.40006)
			(xy 20.557129 -376.392519) (xy 20.567299 -376.371744) (xy 20.567904 -376.360182) (xy 20.567904 -376.279918)
			(xy 20.567322 -376.268352) (xy 20.557135 -376.247581) (xy 20.548346 -376.24004) (xy 20.527563 -376.223287)
			(xy 20.490433 -376.184933) (xy 20.459012 -376.141779) (xy 20.433913 -376.094665) (xy 20.415627 -376.044513)
			(xy 20.40451 -375.992301) (xy 20.400781 -375.93905) (xy 20.40451 -375.885799) (xy 20.415627 -375.833587)
			(xy 20.433913 -375.783435) (xy 20.459012 -375.736321) (xy 20.490433 -375.693167) (xy 20.527563 -375.654813)
			(xy 20.548346 -375.63806) (xy 20.557129 -375.630519) (xy 20.567299 -375.609744) (xy 20.567904 -375.598182)
			(xy 20.567904 -375.517918) (xy 20.567322 -375.506352) (xy 20.557135 -375.485581) (xy 20.548346 -375.47804)
			(xy 20.52587 -375.45984) (xy 20.486137 -375.417821) (xy 20.453199 -375.370287) (xy 20.42781 -375.318328)
			(xy 20.410551 -375.263133) (xy 20.401818 -375.205965) (xy 20.40128 -375.17705) (xy 20.401766 -375.149799)
			(xy 20.409522 -375.095851) (xy 20.424877 -375.043556) (xy 20.447519 -374.993979) (xy 20.476985 -374.948129)
			(xy 20.512676 -374.906938) (xy 20.553867 -374.871247) (xy 20.599717 -374.841781) (xy 20.649294 -374.819139)
			(xy 20.701589 -374.803784) (xy 20.755537 -374.796028) (xy 20.810039 -374.796028) (xy 20.863987 -374.803784)
			(xy 20.916282 -374.819139) (xy 20.965859 -374.841781) (xy 21.011709 -374.871247) (xy 21.0529 -374.906938)
			(xy 21.088591 -374.948129) (xy 21.118057 -374.993979) (xy 21.140699 -375.043556) (xy 21.156054 -375.095851)
			(xy 21.16381 -375.149799) (xy 21.164296 -375.17705) (xy 21.163743 -375.205966) (xy 21.155022 -375.263135)
			(xy 21.137771 -375.318334) (xy 21.112385 -375.370295) (xy 21.079448 -375.41783) (xy 21.039713 -375.459849)
			(xy 21.01723 -375.47804) (xy 21.008443 -375.485577) (xy 20.998276 -375.506355) (xy 20.997672 -375.517918)
			(xy 20.997672 -375.598182) (xy 20.998228 -375.609752) (xy 21.00843 -375.630525) (xy 21.01723 -375.63806)
			(xy 21.038013 -375.654813) (xy 21.075144 -375.693166) (xy 21.106565 -375.736321) (xy 21.131664 -375.783435)
			(xy 21.14995 -375.833587) (xy 21.161067 -375.885798) (xy 21.164797 -375.93905) (xy 21.161067 -375.992302)
			(xy 21.14995 -376.044513) (xy 21.131664 -376.094665) (xy 21.106565 -376.141779) (xy 21.075144 -376.184934)
			(xy 21.038013 -376.223287) (xy 21.01723 -376.24004) (xy 21.008443 -376.247577) (xy 20.998276 -376.268355)
			(xy 20.997672 -376.279918) (xy 20.997672 -376.360182) (xy 20.998228 -376.371752) (xy 21.00843 -376.392525)
			(xy 21.01723 -376.40006) (xy 21.038013 -376.416813) (xy 21.075144 -376.455166) (xy 21.106565 -376.498321)
			(xy 21.131664 -376.545435) (xy 21.14995 -376.595587) (xy 21.154341 -376.616209) (xy 22.153395 -376.616209)
			(xy 22.157124 -376.562959) (xy 22.168239 -376.510749) (xy 22.186523 -376.460598) (xy 22.211619 -376.413485)
			(xy 22.243037 -376.370331) (xy 22.280165 -376.331978) (xy 22.300946 -376.315224) (xy 22.3097 -376.307655)
			(xy 22.319886 -376.286901) (xy 22.320504 -376.275346) (xy 22.320504 -376.195082) (xy 22.319942 -376.183513)
			(xy 22.309741 -376.162742) (xy 22.300946 -376.155204) (xy 22.280177 -376.138434) (xy 22.243048 -376.100082)
			(xy 22.211628 -376.056929) (xy 22.18653 -376.009818) (xy 22.168243 -375.959668) (xy 22.157126 -375.907458)
			(xy 22.153395 -375.854209) (xy 22.157124 -375.800959) (xy 22.168239 -375.748749) (xy 22.186523 -375.698598)
			(xy 22.211619 -375.651485) (xy 22.243037 -375.608331) (xy 22.280165 -375.569978) (xy 22.300946 -375.553224)
			(xy 22.3097 -375.545655) (xy 22.319886 -375.524901) (xy 22.320504 -375.513346) (xy 22.320504 -375.433082)
			(xy 22.319942 -375.421513) (xy 22.309741 -375.400742) (xy 22.300946 -375.393204) (xy 22.278453 -375.375024)
			(xy 22.238721 -375.333001) (xy 22.205785 -375.285463) (xy 22.180398 -375.2335) (xy 22.163144 -375.178301)
			(xy 22.154415 -375.12113) (xy 22.15388 -375.092214) (xy 22.154366 -375.064963) (xy 22.162122 -375.011015)
			(xy 22.177477 -374.95872) (xy 22.200119 -374.909143) (xy 22.229585 -374.863293) (xy 22.265276 -374.822102)
			(xy 22.306467 -374.786411) (xy 22.352317 -374.756945) (xy 22.401894 -374.734303) (xy 22.454189 -374.718948)
			(xy 22.508137 -374.711192) (xy 22.562639 -374.711192) (xy 22.616587 -374.718948) (xy 22.668882 -374.734303)
			(xy 22.718459 -374.756945) (xy 22.764309 -374.786411) (xy 22.8055 -374.822102) (xy 22.841191 -374.863293)
			(xy 22.870657 -374.909143) (xy 22.893299 -374.95872) (xy 22.908654 -375.011015) (xy 22.91641 -375.064963)
			(xy 22.916896 -375.092214) (xy 22.916318 -375.121129) (xy 22.907601 -375.178297) (xy 22.890355 -375.233495)
			(xy 22.864975 -375.285457) (xy 22.832042 -375.332992) (xy 22.792311 -375.375012) (xy 22.76983 -375.393204)
			(xy 22.761059 -375.400757) (xy 22.750883 -375.421523) (xy 22.750272 -375.433082) (xy 22.750272 -375.513346)
			(xy 22.750848 -375.524914) (xy 22.761036 -375.545686) (xy 22.76983 -375.553224) (xy 22.790627 -375.569961)
			(xy 22.827759 -375.608315) (xy 22.859181 -375.651472) (xy 22.884281 -375.698587) (xy 22.902567 -375.748741)
			(xy 22.913683 -375.800955) (xy 22.917412 -375.854209) (xy 22.913681 -375.907462) (xy 22.902562 -375.959675)
			(xy 22.884274 -376.009829) (xy 22.859172 -376.056943) (xy 22.827748 -376.100098) (xy 22.790614 -376.138451)
			(xy 22.76983 -376.155204) (xy 22.761059 -376.162757) (xy 22.750883 -376.183523) (xy 22.750272 -376.195082)
			(xy 22.750272 -376.275346) (xy 22.750848 -376.286914) (xy 22.761036 -376.307686) (xy 22.76983 -376.315224)
			(xy 22.790627 -376.331961) (xy 22.827759 -376.370315) (xy 22.859181 -376.413472) (xy 22.884281 -376.460587)
			(xy 22.902567 -376.510741) (xy 22.913683 -376.562955) (xy 22.917412 -376.616209) (xy 22.913681 -376.669462)
			(xy 22.902562 -376.721675) (xy 22.884274 -376.771829) (xy 22.859172 -376.818943) (xy 22.827748 -376.862098)
			(xy 22.790614 -376.900451) (xy 22.76983 -376.917204) (xy 22.761059 -376.924757) (xy 22.750883 -376.945523)
			(xy 22.750272 -376.957082) (xy 22.750272 -377.037346) (xy 22.750848 -377.048914) (xy 22.761036 -377.069686)
			(xy 22.76983 -377.077224) (xy 22.792331 -377.095394) (xy 22.832064 -377.137419) (xy 22.865 -377.184958)
			(xy 22.890385 -377.236924) (xy 22.907638 -377.292125) (xy 22.916363 -377.349297) (xy 22.916896 -377.378214)
			(xy 22.916393 -377.405147) (xy 22.908811 -377.458476) (xy 22.8938 -377.510208) (xy 22.87166 -377.559313)
			(xy 22.84283 -377.604813) (xy 22.82571 -377.62561) (xy 22.818852 -377.633738) (xy 22.812756 -377.653804)
			(xy 22.823678 -377.7488) (xy 22.834346 -377.767088) (xy 22.842982 -377.773438) (xy 22.866608 -377.791547)
			(xy 22.908468 -377.833868) (xy 22.943245 -377.882178) (xy 22.970093 -377.935305) (xy 22.988361 -377.991958)
			(xy 22.997606 -378.050761) (xy 22.998176 -378.080524) (xy 22.997696 -378.10853) (xy 22.989523 -378.163942)
			(xy 22.973341 -378.217566) (xy 22.949498 -378.26825) (xy 22.918505 -378.314906) (xy 22.900132 -378.336048)
			(xy 22.893528 -378.343414) (xy 22.886924 -378.36094) (xy 22.888448 -378.450348) (xy 22.895814 -378.46762)
			(xy 22.902672 -378.474732) (xy 22.922864 -378.496215) (xy 22.957006 -378.544279) (xy 22.983348 -378.597023)
			(xy 23.001265 -378.653191) (xy 23.010329 -378.711446) (xy 23.010876 -378.740924) (xy 23.01039 -378.768175)
			(xy 23.002634 -378.822123) (xy 22.987279 -378.874418) (xy 22.964637 -378.923995) (xy 22.935171 -378.969845)
			(xy 22.89948 -379.011036) (xy 22.858289 -379.046727) (xy 22.812439 -379.076193) (xy 22.762862 -379.098835)
			(xy 22.710567 -379.11419) (xy 22.656619 -379.121946) (xy 22.602117 -379.121946) (xy 22.548169 -379.11419)
			(xy 22.495874 -379.098835) (xy 22.446297 -379.076193) (xy 22.400447 -379.046727) (xy 22.359256 -379.011036)
			(xy 22.323565 -378.969845) (xy 22.294099 -378.923995) (xy 22.271457 -378.874418) (xy 22.256102 -378.822123)
			(xy 22.248346 -378.768175) (xy 22.24786 -378.740924) (xy 22.248385 -378.71292) (xy 22.256549 -378.65751)
			(xy 22.272722 -378.603888) (xy 22.296554 -378.553203) (xy 22.327536 -378.506545) (xy 22.345904 -378.4854)
			(xy 22.352508 -378.478034) (xy 22.359112 -378.460508) (xy 22.357588 -378.3711) (xy 22.350222 -378.353828)
			(xy 22.343364 -378.346716) (xy 22.323201 -378.325207) (xy 22.289054 -378.277151) (xy 22.262705 -378.224414)
			(xy 22.244782 -378.168251) (xy 22.23571 -378.11) (xy 22.23516 -378.080524) (xy 22.235614 -378.053589)
			(xy 22.243206 -378.000258) (xy 22.258227 -377.948525) (xy 22.280379 -377.899421) (xy 22.30922 -377.853922)
			(xy 22.326346 -377.833128) (xy 22.333204 -377.825) (xy 22.3393 -377.804934) (xy 22.328378 -377.709938)
			(xy 22.31771 -377.69165) (xy 22.309074 -377.6853) (xy 22.28543 -377.667212) (xy 22.243569 -377.624889)
			(xy 22.208792 -377.576575) (xy 22.181946 -377.523443) (xy 22.163683 -377.466786) (xy 22.154445 -377.407978)
			(xy 22.15388 -377.378214) (xy 22.154378 -377.349296) (xy 22.163107 -377.292122) (xy 22.180367 -377.236922)
			(xy 22.205762 -377.18496) (xy 22.238711 -377.137426) (xy 22.278458 -377.095412) (xy 22.300946 -377.077224)
			(xy 22.3097 -377.069655) (xy 22.319886 -377.048901) (xy 22.320504 -377.037346) (xy 22.320504 -376.957082)
			(xy 22.319942 -376.945513) (xy 22.309741 -376.924742) (xy 22.300946 -376.917204) (xy 22.280177 -376.900434)
			(xy 22.243048 -376.862082) (xy 22.211628 -376.818929) (xy 22.18653 -376.771818) (xy 22.168243 -376.721668)
			(xy 22.157126 -376.669458) (xy 22.153395 -376.616209) (xy 21.154341 -376.616209) (xy 21.161067 -376.647798)
			(xy 21.164797 -376.70105) (xy 21.161067 -376.754302) (xy 21.14995 -376.806513) (xy 21.131664 -376.856665)
			(xy 21.106565 -376.903779) (xy 21.075144 -376.946934) (xy 21.038013 -376.985287) (xy 21.01723 -377.00204)
			(xy 21.008443 -377.009577) (xy 20.998276 -377.030355) (xy 20.997672 -377.041918) (xy 20.997672 -377.122182)
			(xy 20.998228 -377.133752) (xy 21.00843 -377.154525) (xy 21.01723 -377.16206) (xy 21.039701 -377.180266)
			(xy 21.079435 -377.222284) (xy 21.112375 -377.269816) (xy 21.137765 -377.321774) (xy 21.155025 -377.376968)
			(xy 21.163758 -377.434135) (xy 21.164296 -377.46305) (xy 21.163853 -377.49088) (xy 21.155772 -377.545949)
			(xy 21.139772 -377.599259) (xy 21.116195 -377.649678) (xy 21.085541 -377.696135) (xy 21.048461 -377.737644)
			(xy 21.005742 -377.773324) (xy 20.958291 -377.802416) (xy 20.932902 -377.813824) (xy 20.92325 -377.817888)
			(xy 20.909026 -377.83262) (xy 20.875752 -377.920758) (xy 20.876768 -377.941332) (xy 20.881086 -377.95073)
			(xy 20.888452 -377.966986) (xy 20.892425 -377.975526) (xy 20.905503 -377.989068) (xy 20.922589 -377.996973)
			(xy 20.941376 -377.998175) (xy 20.959329 -377.992513) (xy 20.974027 -377.980749) (xy 20.97913 -377.972828)
			(xy 20.993908 -377.94856) (xy 21.029543 -377.904305) (xy 21.071346 -377.865824) (xy 21.118394 -377.833968)
			(xy 21.169645 -377.809441) (xy 21.223967 -377.792785) (xy 21.280159 -377.78437) (xy 21.308568 -377.783852)
			(xy 21.335817 -377.784408) (xy 21.38976 -377.792159) (xy 21.442051 -377.807508) (xy 21.491625 -377.830143)
			(xy 21.537474 -377.859602) (xy 21.578663 -377.895286) (xy 21.614355 -377.936469) (xy 21.643823 -377.982312)
			(xy 21.666467 -378.031882) (xy 21.681826 -378.08417) (xy 21.689587 -378.138111) (xy 21.690076 -378.16536)
			(xy 21.689633 -378.19266) (xy 21.681852 -378.246704) (xy 21.666445 -378.299085) (xy 21.643725 -378.348734)
			(xy 21.614157 -378.394636) (xy 21.596604 -378.41555) (xy 21.59 -378.422916) (xy 21.583904 -378.44095)
			(xy 21.587206 -378.530104) (xy 21.594826 -378.547376) (xy 21.601938 -378.554488) (xy 21.623017 -378.576118)
			(xy 21.658744 -378.624811) (xy 21.686349 -378.678527) (xy 21.705141 -378.735923) (xy 21.714652 -378.795563)
			(xy 21.715222 -378.82576) (xy 21.714729 -378.8545) (xy 21.706098 -378.911328) (xy 21.68904 -378.966219)
			(xy 21.663942 -379.01793) (xy 21.631371 -379.065292) (xy 21.612098 -379.086618) (xy 21.605494 -379.09373)
			(xy 21.598382 -379.111256) (xy 21.598382 -379.200664) (xy 21.605494 -379.21819) (xy 21.612098 -379.225302)
			(xy 21.631339 -379.246655) (xy 21.663911 -379.294009) (xy 21.689011 -379.345714) (xy 21.706068 -379.400599)
			(xy 21.714697 -379.457423) (xy 21.715222 -379.48616) (xy 21.714752 -379.51353) (xy 21.706938 -379.56771)
			(xy 21.691451 -379.620214) (xy 21.668609 -379.669961) (xy 21.638884 -379.715927) (xy 21.621242 -379.736858)
			(xy 21.615146 -379.74397) (xy 21.608796 -379.760988) (xy 21.608796 -379.846332) (xy 21.615146 -379.86335)
			(xy 21.621242 -379.870462) (xy 21.638884 -379.891392) (xy 21.668594 -379.937366) (xy 21.691429 -379.987114)
			(xy 21.706919 -380.039615) (xy 21.714748 -380.093791) (xy 21.715222 -380.12116) (xy 21.714631 -380.151355)
			(xy 21.705111 -380.210989) (xy 21.686316 -380.26838) (xy 21.658718 -380.322094) (xy 21.623003 -380.370792)
			(xy 21.601938 -380.392432) (xy 21.594826 -380.399544) (xy 21.587206 -380.416816) (xy 21.583904 -380.50597)
			(xy 21.59 -380.524004) (xy 21.596604 -380.53137) (xy 21.614134 -380.552301) (xy 21.643695 -380.598202)
			(xy 21.666411 -380.647848) (xy 21.68182 -380.700224) (xy 21.689607 -380.754262) (xy 21.690076 -380.78156)
			(xy 21.689631 -380.807303) (xy 21.68954 -380.807976) (xy 25.408128 -380.807976) (xy 25.408547 -380.781076)
			(xy 25.416102 -380.727809) (xy 25.431074 -380.676133) (xy 25.453165 -380.627077) (xy 25.481935 -380.581616)
			(xy 25.516812 -380.540652) (xy 25.536652 -380.52248) (xy 25.544526 -380.515368) (xy 25.553416 -380.496826)
			(xy 25.556718 -380.402084) (xy 25.549352 -380.383034) (xy 25.541986 -380.375414) (xy 25.521744 -380.353929)
			(xy 25.487525 -380.305831) (xy 25.461121 -380.253037) (xy 25.443162 -380.196807) (xy 25.434077 -380.138482)
			(xy 25.433528 -380.108968) (xy 25.433968 -380.081597) (xy 25.441791 -380.027416) (xy 25.457286 -379.974913)
			(xy 25.480134 -379.925166) (xy 25.509864 -379.879201) (xy 25.527508 -379.85827) (xy 25.533604 -379.851158)
			(xy 25.539954 -379.83414) (xy 25.539954 -379.748796) (xy 25.533604 -379.731778) (xy 25.527508 -379.724666)
			(xy 25.509888 -379.703719) (xy 25.480173 -379.65775) (xy 25.457333 -379.608007) (xy 25.441838 -379.555509)
			(xy 25.434005 -379.501336) (xy 25.433528 -379.473968) (xy 25.434095 -379.444527) (xy 25.443132 -379.386344)
			(xy 25.461004 -379.33024) (xy 25.487284 -379.277549) (xy 25.521349 -379.229522) (xy 25.541478 -379.20803)
			(xy 25.54859 -379.200918) (xy 25.555956 -379.182122) (xy 25.554178 -379.089412) (xy 25.54605 -379.071124)
			(xy 25.538684 -379.064012) (xy 25.520399 -379.045947) (xy 25.488359 -379.005753) (xy 25.462003 -378.961624)
			(xy 25.441808 -378.914356) (xy 25.428139 -378.864805) (xy 25.421245 -378.813869) (xy 25.420828 -378.788168)
			(xy 25.421225 -378.760913) (xy 25.428987 -378.706957) (xy 25.444349 -378.654656) (xy 25.466998 -378.605073)
			(xy 25.496473 -378.559219) (xy 25.532174 -378.518025) (xy 25.573373 -378.482332) (xy 25.619233 -378.452866)
			(xy 25.66882 -378.430226) (xy 25.721124 -378.414873) (xy 25.775081 -378.40712) (xy 25.802336 -378.40666)
			(xy 25.831075 -378.407173) (xy 25.887903 -378.415799) (xy 25.942793 -378.432853) (xy 25.994505 -378.457947)
			(xy 26.041867 -378.490513) (xy 26.063194 -378.509784) (xy 26.070306 -378.516388) (xy 26.087832 -378.5235)
			(xy 26.17724 -378.5235) (xy 26.194766 -378.516388) (xy 26.201878 -378.509784) (xy 26.223205 -378.490514)
			(xy 26.270568 -378.457949) (xy 26.322279 -378.432858) (xy 26.37717 -378.415808) (xy 26.433997 -378.407186)
			(xy 26.491475 -378.407186) (xy 26.548302 -378.415808) (xy 26.603193 -378.432858) (xy 26.654904 -378.457949)
			(xy 26.702267 -378.490514) (xy 26.723594 -378.509784) (xy 26.730706 -378.516388) (xy 26.748232 -378.5235)
			(xy 26.83764 -378.5235) (xy 26.855166 -378.516388) (xy 26.862278 -378.509784) (xy 26.883597 -378.490504)
			(xy 26.93096 -378.457937) (xy 26.982674 -378.432846) (xy 27.037567 -378.415797) (xy 27.094396 -378.407178)
			(xy 27.123136 -378.40666) (xy 27.152189 -378.40722) (xy 27.209625 -378.416011) (xy 27.265063 -378.433414)
			(xy 27.317218 -378.459027) (xy 27.364884 -378.492256) (xy 27.406957 -378.532332) (xy 27.425142 -378.554996)
			(xy 27.432254 -378.56414) (xy 27.45232 -378.5743) (xy 27.554428 -378.57684) (xy 27.575002 -378.567696)
			(xy 27.582622 -378.558806) (xy 27.600825 -378.538308) (xy 27.642111 -378.502243) (xy 27.688133 -378.472457)
			(xy 27.737943 -378.449563) (xy 27.790517 -378.434032) (xy 27.844772 -378.426185) (xy 27.872182 -378.42571)
			(xy 27.899435 -378.426172) (xy 27.953387 -378.433927) (xy 28.005686 -378.449282) (xy 28.055267 -378.471923)
			(xy 28.101121 -378.501391) (xy 28.142315 -378.537085) (xy 28.178009 -378.578279) (xy 28.207477 -378.624133)
			(xy 28.230118 -378.673714) (xy 28.245473 -378.726013) (xy 28.253228 -378.779965) (xy 28.25369 -378.807218)
			(xy 28.25318 -378.835957) (xy 28.244554 -378.892786) (xy 28.227501 -378.947677) (xy 28.202407 -378.999388)
			(xy 28.169838 -379.04675) (xy 28.150566 -379.068076) (xy 28.143962 -379.075188) (xy 28.13685 -379.092714)
			(xy 28.13685 -379.182122) (xy 28.143962 -379.199648) (xy 28.150566 -379.20676) (xy 28.169855 -379.228071)
			(xy 28.202421 -379.275436) (xy 28.227512 -379.32715) (xy 28.244561 -379.382043) (xy 28.253182 -379.438873)
			(xy 28.25318 -379.496353) (xy 28.244555 -379.553182) (xy 28.227502 -379.608074) (xy 28.202407 -379.659787)
			(xy 28.169839 -379.707149) (xy 28.150566 -379.728476) (xy 28.143962 -379.735588) (xy 28.13685 -379.753114)
			(xy 28.13685 -379.842522) (xy 28.143962 -379.860048) (xy 28.150566 -379.86716) (xy 28.169846 -379.888479)
			(xy 28.202411 -379.935843) (xy 28.227501 -379.987557) (xy 28.24455 -380.04245) (xy 28.25317 -380.099278)
			(xy 28.25369 -380.128018) (xy 28.25311 -380.157458) (xy 28.244074 -380.215641) (xy 28.226206 -380.271744)
			(xy 28.199929 -380.324436) (xy 28.165867 -380.372464) (xy 28.14574 -380.393956) (xy 28.138882 -380.401068)
			(xy 28.131516 -380.418848) (xy 28.130754 -380.509018) (xy 28.137866 -380.527052) (xy 28.144724 -380.534418)
			(xy 28.164114 -380.555734) (xy 28.196836 -380.603167) (xy 28.222048 -380.654983) (xy 28.239178 -380.710002)
			(xy 28.247835 -380.766972) (xy 28.248356 -380.795784) (xy 28.247898 -380.823389) (xy 28.239929 -380.87802)
			(xy 28.224171 -380.930933) (xy 28.200952 -380.981023) (xy 28.170757 -381.027244) (xy 28.152852 -381.04826)
			(xy 28.146248 -381.05588) (xy 28.139644 -381.07493) (xy 28.145486 -381.166624) (xy 28.154122 -381.184912)
			(xy 28.161742 -381.191516) (xy 28.181621 -381.209687) (xy 28.216553 -381.250681) (xy 28.245368 -381.296182)
			(xy 28.267495 -381.345285) (xy 28.282492 -381.397013) (xy 28.290061 -381.450337) (xy 28.29052 -381.477266)
			(xy 28.290013 -381.504517) (xy 28.282261 -381.558466) (xy 28.26691 -381.610763) (xy 28.244272 -381.660342)
			(xy 28.214809 -381.706194) (xy 28.17912 -381.747387) (xy 28.137931 -381.783081) (xy 28.092082 -381.81255)
			(xy 28.042506 -381.835194) (xy 27.990211 -381.850551) (xy 27.936263 -381.85831) (xy 27.909012 -381.858774)
			(xy 27.882656 -381.858307) (xy 27.830447 -381.851041) (xy 27.779735 -381.836659) (xy 27.731484 -381.815435)
			(xy 27.686613 -381.787773) (xy 27.645976 -381.754199) (xy 27.627834 -381.735076) (xy 27.620722 -381.727456)
			(xy 27.602942 -381.719074) (xy 27.51074 -381.714756) (xy 27.492198 -381.721614) (xy 27.484578 -381.728472)
			(xy 27.463411 -381.747032) (xy 27.41662 -381.778333) (xy 27.365739 -381.802421) (xy 27.311871 -381.818773)
			(xy 27.256186 -381.827034) (xy 27.228038 -381.827532) (xy 27.200375 -381.827041) (xy 27.145625 -381.819074)
			(xy 27.0926 -381.803286) (xy 27.042409 -381.780008) (xy 26.996104 -381.749729) (xy 26.975054 -381.731774)
			(xy 26.967942 -381.72517) (xy 26.950162 -381.71882) (xy 26.86177 -381.720598) (xy 26.844244 -381.727964)
			(xy 26.837386 -381.734568) (xy 26.81591 -381.754503) (xy 26.768013 -381.788255) (xy 26.71552 -381.814291)
			(xy 26.659666 -381.831999) (xy 26.601761 -381.840963) (xy 26.572464 -381.841502) (xy 26.546974 -381.84109)
			(xy 26.496449 -381.834307) (xy 26.447277 -381.820855) (xy 26.400335 -381.800972) (xy 26.35646 -381.775012)
			(xy 26.316435 -381.74344) (xy 26.298398 -381.725424) (xy 26.291032 -381.717804) (xy 26.271728 -381.709676)
			(xy 26.17597 -381.711454) (xy 26.15692 -381.720344) (xy 26.149808 -381.728218) (xy 26.131629 -381.747742)
			(xy 26.090799 -381.782074) (xy 26.045582 -381.810379) (xy 25.996861 -381.832107) (xy 25.945588 -381.846831)
			(xy 25.892763 -381.854265) (xy 25.86609 -381.85471) (xy 25.838839 -381.854232) (xy 25.784891 -381.846474)
			(xy 25.732596 -381.831117) (xy 25.683019 -381.808475) (xy 25.637169 -381.779008) (xy 25.595978 -381.743316)
			(xy 25.560287 -381.702125) (xy 25.530821 -381.656274) (xy 25.50818 -381.606697) (xy 25.492825 -381.554401)
			(xy 25.485068 -381.500453) (xy 25.484582 -381.473202) (xy 25.485165 -381.442144) (xy 25.495229 -381.38085)
			(xy 25.515091 -381.321996) (xy 25.544226 -381.267138) (xy 25.56256 -381.242062) (xy 25.568656 -381.233934)
			(xy 25.57399 -381.215392) (xy 25.563576 -381.125476) (xy 25.554432 -381.108458) (xy 25.546558 -381.102108)
			(xy 25.52529 -381.083892) (xy 25.487817 -381.042282) (xy 25.456825 -380.995644) (xy 25.432982 -380.944977)
			(xy 25.416797 -380.891371) (xy 25.408618 -380.835974) (xy 25.408128 -380.807976) (xy 21.68954 -380.807976)
			(xy 21.682701 -380.85832) (xy 21.668976 -380.907942) (xy 21.648705 -380.955269) (xy 21.622254 -380.999441)
			(xy 21.60651 -381.019812) (xy 21.600668 -381.027178) (xy 21.59508 -381.044958) (xy 21.600414 -381.132334)
			(xy 21.608034 -381.149098) (xy 21.615146 -381.155956) (xy 21.633035 -381.17399) (xy 21.664398 -381.213947)
			(xy 21.690182 -381.257712) (xy 21.709931 -381.304511) (xy 21.723296 -381.353517) (xy 21.730041 -381.403862)
			(xy 21.730462 -381.42926) (xy 21.729976 -381.456511) (xy 21.72222 -381.510459) (xy 21.706865 -381.562754)
			(xy 21.684223 -381.612331) (xy 21.654757 -381.658181) (xy 21.619066 -381.699372) (xy 21.577875 -381.735063)
			(xy 21.532025 -381.764529) (xy 21.482448 -381.787171) (xy 21.430153 -381.802526) (xy 21.376205 -381.810282)
			(xy 21.321703 -381.810282) (xy 21.267755 -381.802526) (xy 21.21546 -381.787171) (xy 21.165883 -381.764529)
			(xy 21.120033 -381.735063) (xy 21.078842 -381.699372) (xy 21.043151 -381.658181) (xy 21.013685 -381.612331)
			(xy 20.991043 -381.562754) (xy 20.975688 -381.510459) (xy 20.967932 -381.456511) (xy 20.967446 -381.42926)
			(xy 20.967897 -381.403517) (xy 20.974825 -381.3525) (xy 20.988548 -381.302878) (xy 21.008819 -381.255551)
			(xy 21.035268 -381.211379) (xy 21.051012 -381.191008) (xy 21.056854 -381.183642) (xy 21.062442 -381.165862)
			(xy 21.057108 -381.078486) (xy 21.049488 -381.061722) (xy 21.042376 -381.054864) (xy 21.033534 -381.046143)
			(xy 21.016883 -381.027713) (xy 21.009102 -381.018034) (xy 21.001736 -381.008382) (xy 20.979892 -380.998222)
			(xy 20.87372 -381.001778) (xy 20.852638 -381.013208) (xy 20.84578 -381.023368) (xy 20.830474 -381.044859)
			(xy 20.794837 -381.083769) (xy 20.754179 -381.117397) (xy 20.709276 -381.145103) (xy 20.660984 -381.166358)
			(xy 20.610223 -381.180756) (xy 20.557963 -381.188023) (xy 20.531582 -381.188468) (xy 20.503346 -381.187942)
			(xy 20.447491 -381.179616) (xy 20.393474 -381.163148) (xy 20.342474 -381.138898) (xy 20.295605 -381.107396)
			(xy 20.253891 -381.06933) (xy 20.235672 -381.047752) (xy 20.228068 -381.039366) (xy 20.20761 -381.029744)
			(xy 20.196302 -381.02921) (xy 20.117562 -381.02921) (xy 20.106274 -381.02982) (xy 20.085845 -381.039433)
			(xy 20.078192 -381.047752) (xy 20.059979 -381.069337) (xy 20.018268 -381.107409) (xy 19.971399 -381.138916)
			(xy 19.920397 -381.163168) (xy 19.866377 -381.179636) (xy 19.810519 -381.187959) (xy 19.782282 -381.188468)
			(xy 19.753023 -381.187894) (xy 19.695192 -381.178951) (xy 19.639402 -381.161291) (xy 19.586959 -381.135327)
			(xy 19.539089 -381.101669) (xy 19.517614 -381.081788) (xy 19.510502 -381.07493) (xy 19.492468 -381.067564)
			(xy 19.402044 -381.067564) (xy 19.38401 -381.07493) (xy 19.376898 -381.081788) (xy 19.355462 -381.101717)
			(xy 19.307591 -381.135391) (xy 19.25514 -381.16136) (xy 19.199338 -381.179014) (xy 19.141494 -381.187941)
			(xy 19.11223 -381.188468) (xy 19.08491 -381.188023) (xy 19.03083 -381.180225) (xy 18.978417 -381.164786)
			(xy 18.928746 -381.142022) (xy 18.882833 -381.112399) (xy 18.841621 -381.076524) (xy 18.823432 -381.056134)
			(xy 18.816066 -381.047752) (xy 18.796508 -381.038608) (xy 18.69821 -381.037592) (xy 18.678144 -381.046482)
			(xy 18.670778 -381.05461) (xy 18.652632 -381.074166) (xy 18.611793 -381.108492) (xy 18.566569 -381.136791)
			(xy 18.517842 -381.158512) (xy 18.466563 -381.17323) (xy 18.413734 -381.180659) (xy 18.38706 -381.181102)
			(xy 18.359807 -381.180659) (xy 18.305858 -381.172897) (xy 18.253562 -381.157537) (xy 18.203984 -381.134891)
			(xy 18.158134 -381.10542) (xy 18.116944 -381.069724) (xy 18.081253 -381.028529) (xy 18.051787 -380.982675)
			(xy 18.029147 -380.933095) (xy 18.013793 -380.880797) (xy 18.006037 -380.826847) (xy 18.005552 -380.799594)
			(xy 16.644405 -380.799594) (xy 16.636875 -380.851676) (xy 16.621374 -380.90418) (xy 16.598523 -380.953928)
			(xy 16.568792 -380.999896) (xy 16.551148 -381.020828) (xy 16.545052 -381.02794) (xy 16.538702 -381.044958)
			(xy 16.538702 -381.130302) (xy 16.545052 -381.14732) (xy 16.551148 -381.154432) (xy 16.568761 -381.175386)
			(xy 16.598478 -381.221352) (xy 16.62132 -381.271094) (xy 16.636817 -381.32359) (xy 16.644651 -381.377762)
			(xy 16.645128 -381.40513) (xy 16.644642 -381.432381) (xy 16.636886 -381.486329) (xy 16.621531 -381.538624)
			(xy 16.598889 -381.588201) (xy 16.569423 -381.634051) (xy 16.533732 -381.675242) (xy 16.492541 -381.710933)
			(xy 16.446691 -381.740399) (xy 16.397114 -381.763041) (xy 16.344819 -381.778396) (xy 16.290871 -381.786152)
			(xy 16.236369 -381.786152) (xy 16.182421 -381.778396) (xy 16.130126 -381.763041) (xy 16.080549 -381.740399)
			(xy 16.034699 -381.710933) (xy 15.993508 -381.675242) (xy 15.957817 -381.634051) (xy 15.928351 -381.588201)
			(xy 15.905709 -381.538624) (xy 15.890354 -381.486329) (xy 15.882598 -381.432381) (xy 15.882112 -381.40513)
			(xy 7.291427 -381.40513) (xy 7.291578 -381.41402) (xy 7.291092 -381.441271) (xy 7.283336 -381.495219)
			(xy 7.267981 -381.547514) (xy 7.245339 -381.597091) (xy 7.215873 -381.642941) (xy 7.180182 -381.684132)
			(xy 7.138991 -381.719823) (xy 7.093141 -381.749289) (xy 7.043564 -381.771931) (xy 6.991269 -381.787286)
			(xy 6.937321 -381.795042) (xy 6.882819 -381.795042) (xy 6.828871 -381.787286) (xy 6.776576 -381.771931)
			(xy 6.726999 -381.749289) (xy 6.681149 -381.719823) (xy 6.639958 -381.684132) (xy 6.604267 -381.642941)
			(xy 6.574801 -381.597091) (xy 6.552159 -381.547514) (xy 6.536804 -381.495219) (xy 6.529048 -381.441271)
			(xy 6.528562 -381.41402) (xy 5.97408 -381.41402) (xy 5.97408 -383.878074) (xy 5.974516 -383.888139)
			(xy 5.982247 -383.906726) (xy 5.989066 -383.914142) (xy 7.274306 -385.199382) (xy 7.281704 -385.206229)
			(xy 7.300302 -385.213964) (xy 7.310374 -385.214368) (xy 8.482076 -385.214368) (xy 8.510639 -385.214926)
			(xy 8.567063 -385.223858) (xy 8.621395 -385.241505) (xy 8.672298 -385.267434) (xy 8.718519 -385.301005)
			(xy 8.739124 -385.320794) (xy 11.45032 -388.03199) (xy 11.470136 -388.052582) (xy 11.503748 -388.098797)
			(xy 11.529723 -388.149697) (xy 11.547422 -388.204032) (xy 11.556411 -388.260466) (xy 11.557 -388.289038)
			(xy 11.557 -389.22833) (xy 11.907264 -389.22833) (xy 11.911335 -389.172708) (xy 11.923461 -389.118271)
			(xy 11.943384 -389.06618) (xy 11.97068 -389.017545) (xy 12.004766 -388.973402) (xy 12.044915 -388.934693)
			(xy 12.090273 -388.902242) (xy 12.139873 -388.876741) (xy 12.192657 -388.858734) (xy 12.2475 -388.848604)
			(xy 12.303234 -388.846567) (xy 12.358671 -388.852667) (xy 12.412628 -388.866773) (xy 12.463957 -388.888585)
			(xy 12.511563 -388.917639) (xy 12.554431 -388.953314) (xy 12.591648 -388.994851) (xy 12.622421 -389.041364)
			(xy 12.646093 -389.091861) (xy 12.662161 -389.145268) (xy 12.670281 -389.200444) (xy 12.67079 -389.22833)
			(xy 12.670281 -389.256216) (xy 12.662161 -389.311392) (xy 12.646093 -389.364799) (xy 12.622421 -389.415296)
			(xy 12.591648 -389.461809) (xy 12.554431 -389.503346) (xy 12.511563 -389.539021) (xy 12.463957 -389.568075)
			(xy 12.455935 -389.571484) (xy 20.902166 -389.571484) (xy 20.906237 -389.515862) (xy 20.918363 -389.461425)
			(xy 20.938286 -389.409334) (xy 20.965582 -389.360699) (xy 20.999668 -389.316556) (xy 21.039817 -389.277847)
			(xy 21.085175 -389.245396) (xy 21.134775 -389.219895) (xy 21.187559 -389.201888) (xy 21.242402 -389.191758)
			(xy 21.298136 -389.189721) (xy 21.353573 -389.195821) (xy 21.40753 -389.209927) (xy 21.458859 -389.231739)
			(xy 21.506465 -389.260793) (xy 21.549333 -389.296468) (xy 21.58655 -389.338005) (xy 21.617323 -389.384518)
			(xy 21.640995 -389.435015) (xy 21.657063 -389.488422) (xy 21.665183 -389.543598) (xy 21.665692 -389.571484)
			(xy 21.665183 -389.59937) (xy 21.657063 -389.654546) (xy 21.640995 -389.707953) (xy 21.617323 -389.75845)
			(xy 21.58655 -389.804963) (xy 21.549333 -389.8465) (xy 21.506465 -389.882175) (xy 21.458859 -389.911229)
			(xy 21.40753 -389.933041) (xy 21.353573 -389.947147) (xy 21.298136 -389.953247) (xy 21.242402 -389.95121)
			(xy 21.187559 -389.94108) (xy 21.134775 -389.923073) (xy 21.085175 -389.897572) (xy 21.039817 -389.865121)
			(xy 20.999668 -389.826412) (xy 20.965582 -389.782269) (xy 20.938286 -389.733634) (xy 20.918363 -389.681543)
			(xy 20.906237 -389.627106) (xy 20.902166 -389.571484) (xy 12.455935 -389.571484) (xy 12.412628 -389.589887)
			(xy 12.358671 -389.603993) (xy 12.303234 -389.610093) (xy 12.2475 -389.608056) (xy 12.192657 -389.597926)
			(xy 12.139873 -389.579919) (xy 12.090273 -389.554418) (xy 12.044915 -389.521967) (xy 12.004766 -389.483258)
			(xy 11.97068 -389.439115) (xy 11.943384 -389.39048) (xy 11.923461 -389.338389) (xy 11.911335 -389.283952)
			(xy 11.907264 -389.22833) (xy 11.557 -389.22833) (xy 11.557 -390.219184) (xy 11.84986 -390.219184)
			(xy 11.853931 -390.163562) (xy 11.866057 -390.109125) (xy 11.88598 -390.057034) (xy 11.913276 -390.008399)
			(xy 11.947362 -389.964256) (xy 11.987511 -389.925547) (xy 12.032869 -389.893096) (xy 12.082469 -389.867595)
			(xy 12.135253 -389.849588) (xy 12.190096 -389.839458) (xy 12.24583 -389.837421) (xy 12.301267 -389.843521)
			(xy 12.355224 -389.857627) (xy 12.406553 -389.879439) (xy 12.454159 -389.908493) (xy 12.497027 -389.944168)
			(xy 12.534244 -389.985705) (xy 12.565017 -390.032218) (xy 12.588689 -390.082715) (xy 12.604757 -390.136122)
			(xy 12.612877 -390.191298) (xy 12.613386 -390.219184) (xy 12.612877 -390.24707) (xy 12.604757 -390.302246)
			(xy 12.588689 -390.355653) (xy 12.565017 -390.40615) (xy 12.534244 -390.452663) (xy 12.497027 -390.4942)
			(xy 12.454159 -390.529875) (xy 12.406553 -390.558929) (xy 12.355224 -390.580741) (xy 12.301267 -390.594847)
			(xy 12.24583 -390.600947) (xy 12.190096 -390.59891) (xy 12.135253 -390.58878) (xy 12.082469 -390.570773)
			(xy 12.032869 -390.545272) (xy 11.987511 -390.512821) (xy 11.947362 -390.474112) (xy 11.913276 -390.429969)
			(xy 11.88598 -390.381334) (xy 11.866057 -390.329243) (xy 11.853931 -390.274806) (xy 11.84986 -390.219184)
			(xy 11.557 -390.219184) (xy 11.557 -390.89228) (xy 16.845547 -390.89228) (xy 16.849529 -390.839131)
			(xy 16.861389 -390.787169) (xy 16.880861 -390.737556) (xy 16.90751 -390.691398) (xy 16.940741 -390.649728)
			(xy 16.979811 -390.613476) (xy 17.023848 -390.583452) (xy 17.071868 -390.560327) (xy 17.122798 -390.544617)
			(xy 17.175501 -390.536674) (xy 17.20215 -390.536176) (xy 17.22851 -390.536672) (xy 17.280651 -390.544458)
			(xy 17.331072 -390.559853) (xy 17.37867 -390.582519) (xy 17.422403 -390.61196) (xy 17.44218 -390.629394)
			(xy 17.449292 -390.635744) (xy 17.467072 -390.642602) (xy 17.554448 -390.642602) (xy 17.572228 -390.635744)
			(xy 17.57934 -390.629394) (xy 17.599135 -390.611984) (xy 17.642872 -390.582557) (xy 17.690467 -390.559894)
			(xy 17.74088 -390.544488) (xy 17.793013 -390.536675) (xy 17.81937 -390.536176) (xy 17.84573 -390.53666)
			(xy 17.897872 -390.544449) (xy 17.948294 -390.559846) (xy 17.995891 -390.582515) (xy 18.039623 -390.611959)
			(xy 18.0594 -390.629394) (xy 18.066512 -390.635744) (xy 18.084292 -390.642602) (xy 18.171668 -390.642602)
			(xy 18.189448 -390.635744) (xy 18.19656 -390.629394) (xy 18.216347 -390.611974) (xy 18.260086 -390.582549)
			(xy 18.307683 -390.559888) (xy 18.358098 -390.544484) (xy 18.410232 -390.536674) (xy 18.43659 -390.536176)
			(xy 18.461586 -390.536601) (xy 18.511085 -390.543597) (xy 18.559123 -390.55744) (xy 18.604755 -390.577857)
			(xy 18.647087 -390.604449) (xy 18.66646 -390.62025) (xy 18.673572 -390.626346) (xy 18.690082 -390.632442)
			(xy 18.774156 -390.632442) (xy 18.790666 -390.626346) (xy 18.797778 -390.62025) (xy 18.817138 -390.604432)
			(xy 18.85947 -390.577833) (xy 18.905105 -390.557415) (xy 18.953146 -390.543578) (xy 19.002651 -390.536595)
			(xy 19.027648 -390.536176) (xy 19.053974 -390.536628) (xy 19.106051 -390.544396) (xy 19.156413 -390.559754)
			(xy 19.203962 -390.582368) (xy 19.247659 -390.611743) (xy 19.267424 -390.62914) (xy 19.277076 -390.637776)
			(xy 19.301714 -390.643872) (xy 19.408648 -390.616948) (xy 19.427444 -390.599676) (xy 19.431762 -390.587738)
			(xy 19.44086 -390.563228) (xy 19.464763 -390.516732) (xy 19.494791 -390.473936) (xy 19.530383 -390.435642)
			(xy 19.57087 -390.402567) (xy 19.615495 -390.37533) (xy 19.663421 -390.354442) (xy 19.71375 -390.340295)
			(xy 19.76554 -390.333153) (xy 19.79168 -390.332722) (xy 19.818936 -390.333124) (xy 19.872893 -390.340879)
			(xy 19.925198 -390.356234) (xy 19.974784 -390.378878) (xy 20.020644 -390.408347) (xy 20.061842 -390.444044)
			(xy 20.087094 -390.473184) (xy 20.905976 -390.473184) (xy 20.910047 -390.417562) (xy 20.922173 -390.363125)
			(xy 20.942096 -390.311034) (xy 20.969392 -390.262399) (xy 21.003478 -390.218256) (xy 21.043627 -390.179547)
			(xy 21.088985 -390.147096) (xy 21.138585 -390.121595) (xy 21.191369 -390.103588) (xy 21.246212 -390.093458)
			(xy 21.301946 -390.091421) (xy 21.357383 -390.097521) (xy 21.41134 -390.111627) (xy 21.462669 -390.133439)
			(xy 21.510275 -390.162493) (xy 21.553143 -390.198168) (xy 21.59036 -390.239705) (xy 21.621133 -390.286218)
			(xy 21.644805 -390.336715) (xy 21.660873 -390.390122) (xy 21.668993 -390.445298) (xy 21.669502 -390.473184)
			(xy 21.668993 -390.50107) (xy 21.660873 -390.556246) (xy 21.644805 -390.609653) (xy 21.621133 -390.66015)
			(xy 21.59036 -390.706663) (xy 21.553143 -390.7482) (xy 21.510275 -390.783875) (xy 21.462669 -390.812929)
			(xy 21.41134 -390.834741) (xy 21.357383 -390.848847) (xy 21.301946 -390.854947) (xy 21.246212 -390.85291)
			(xy 21.191369 -390.84278) (xy 21.138585 -390.824773) (xy 21.088985 -390.799272) (xy 21.043627 -390.766821)
			(xy 21.003478 -390.728112) (xy 20.969392 -390.683969) (xy 20.942096 -390.635334) (xy 20.922173 -390.583243)
			(xy 20.910047 -390.528806) (xy 20.905976 -390.473184) (xy 20.087094 -390.473184) (xy 20.097541 -390.48524)
			(xy 20.127013 -390.531098) (xy 20.149659 -390.580683) (xy 20.165017 -390.632987) (xy 20.172775 -390.686944)
			(xy 20.172775 -390.741456) (xy 20.165017 -390.795413) (xy 20.149659 -390.847717) (xy 20.129297 -390.8923)
			(xy 25.924276 -390.8923) (xy 25.928259 -390.839151) (xy 25.940119 -390.787188) (xy 25.95959 -390.737574)
			(xy 25.986238 -390.691416) (xy 26.019467 -390.649744) (xy 26.058536 -390.613491) (xy 26.102572 -390.583464)
			(xy 26.150591 -390.560336) (xy 26.20152 -390.544623) (xy 26.254223 -390.536676) (xy 26.280872 -390.536176)
			(xy 26.307232 -390.536658) (xy 26.359374 -390.544448) (xy 26.409796 -390.559846) (xy 26.457393 -390.582515)
			(xy 26.501125 -390.611959) (xy 26.520902 -390.629394) (xy 26.528014 -390.635744) (xy 26.545794 -390.642602)
			(xy 26.63317 -390.642602) (xy 26.65095 -390.635744) (xy 26.658062 -390.629394) (xy 26.677848 -390.611973)
			(xy 26.721588 -390.582548) (xy 26.769185 -390.559887) (xy 26.8196 -390.544484) (xy 26.871734 -390.536674)
			(xy 26.898092 -390.536176) (xy 26.924453 -390.536646) (xy 26.976595 -390.544439) (xy 27.027017 -390.55984)
			(xy 27.074614 -390.582511) (xy 27.118346 -390.611958) (xy 27.138122 -390.629394) (xy 27.145234 -390.635744)
			(xy 27.163014 -390.642602) (xy 27.25039 -390.642602) (xy 27.26817 -390.635744) (xy 27.275282 -390.629394)
			(xy 27.29506 -390.611964) (xy 27.338802 -390.58254) (xy 27.386401 -390.559881) (xy 27.436818 -390.54448)
			(xy 27.488954 -390.536672) (xy 27.515312 -390.536176) (xy 27.540308 -390.536589) (xy 27.589808 -390.543588)
			(xy 27.637846 -390.557433) (xy 27.683478 -390.577853) (xy 27.72581 -390.604448) (xy 27.745182 -390.62025)
			(xy 27.752294 -390.626346) (xy 27.768804 -390.632442) (xy 27.852878 -390.632442) (xy 27.869388 -390.626346)
			(xy 27.8765 -390.62025) (xy 27.895852 -390.604422) (xy 27.938186 -390.577825) (xy 27.983823 -390.557409)
			(xy 28.031866 -390.543574) (xy 28.081372 -390.536593) (xy 28.10637 -390.536176) (xy 28.133805 -390.53668)
			(xy 28.188024 -390.545101) (xy 28.21432 -390.55294) (xy 28.22575 -390.556496) (xy 28.24861 -390.553194)
			(xy 28.334462 -390.49452) (xy 28.345892 -390.4742) (xy 28.346654 -390.462516) (xy 28.348971 -390.433797)
			(xy 28.361097 -390.377473) (xy 28.381556 -390.323614) (xy 28.409882 -390.273444) (xy 28.445432 -390.228105)
			(xy 28.487397 -390.188628) (xy 28.534821 -390.155912) (xy 28.586626 -390.130701) (xy 28.641634 -390.113568)
			(xy 28.698593 -390.104903) (xy 28.7274 -390.104376) (xy 28.75465 -390.104894) (xy 28.808595 -390.11265)
			(xy 28.860888 -390.128005) (xy 28.910463 -390.150645) (xy 28.956311 -390.18011) (xy 28.9975 -390.2158)
			(xy 29.03319 -390.256989) (xy 29.062655 -390.302837) (xy 29.085295 -390.352412) (xy 29.10065 -390.404705)
			(xy 29.108406 -390.45865) (xy 29.108406 -390.51315) (xy 29.10065 -390.567095) (xy 29.085295 -390.619388)
			(xy 29.062655 -390.668963) (xy 29.03319 -390.714811) (xy 28.9975 -390.756) (xy 28.956311 -390.79169)
			(xy 28.910463 -390.821155) (xy 28.860888 -390.843795) (xy 28.808595 -390.85915) (xy 28.75465 -390.866906)
			(xy 28.7274 -390.867392) (xy 28.693996 -390.866697) (xy 28.628208 -390.855075) (xy 28.59659 -390.844278)
			(xy 28.585414 -390.840214) (xy 28.5623 -390.8425) (xy 28.474162 -390.897618) (xy 28.461716 -390.91743)
			(xy 28.460446 -390.929114) (xy 28.457324 -390.955063) (xy 28.444379 -391.0057) (xy 28.424171 -391.053902)
			(xy 28.397134 -391.098631) (xy 28.36385 -391.138928) (xy 28.325032 -391.173926) (xy 28.281516 -391.202875)
			(xy 28.234235 -391.225151) (xy 28.184206 -391.240277) (xy 28.132503 -391.247927) (xy 28.10637 -391.248392)
			(xy 28.081375 -391.24794) (xy 28.031876 -391.240951) (xy 27.983839 -391.227115) (xy 27.938206 -391.206704)
			(xy 27.895873 -391.180117) (xy 27.8765 -391.164318) (xy 27.869388 -391.158222) (xy 27.852878 -391.152126)
			(xy 27.768804 -391.152126) (xy 27.752294 -391.158222) (xy 27.745182 -391.164318) (xy 27.725796 -391.180103)
			(xy 27.683472 -391.206708) (xy 27.637844 -391.227133) (xy 27.589808 -391.240977) (xy 27.540308 -391.247969)
			(xy 27.515312 -391.248392) (xy 27.488951 -391.247927) (xy 27.436808 -391.240135) (xy 27.386386 -391.224733)
			(xy 27.338788 -391.20206) (xy 27.295058 -391.172611) (xy 27.275282 -391.155174) (xy 27.26817 -391.148824)
			(xy 27.25039 -391.141966) (xy 27.163014 -391.141966) (xy 27.145234 -391.148824) (xy 27.138122 -391.155174)
			(xy 27.118352 -391.172614) (xy 27.074607 -391.202033) (xy 27.027006 -391.22469) (xy 26.976587 -391.24009)
			(xy 26.924451 -391.247896) (xy 26.898092 -391.248392) (xy 26.871731 -391.247939) (xy 26.819587 -391.240144)
			(xy 26.769165 -391.22474) (xy 26.721567 -391.202064) (xy 26.677837 -391.172612) (xy 26.658062 -391.155174)
			(xy 26.65095 -391.148824) (xy 26.63317 -391.141966) (xy 26.545794 -391.141966) (xy 26.528014 -391.148824)
			(xy 26.520902 -391.155174) (xy 26.50114 -391.172623) (xy 26.457393 -391.202042) (xy 26.40979 -391.224696)
			(xy 26.359369 -391.240094) (xy 26.307231 -391.247897) (xy 26.280872 -391.248392) (xy 26.254223 -391.247924)
			(xy 26.20152 -391.239977) (xy 26.150591 -391.224264) (xy 26.102572 -391.201136) (xy 26.058536 -391.171109)
			(xy 26.019467 -391.134856) (xy 25.986238 -391.093184) (xy 25.95959 -391.047026) (xy 25.940119 -390.997412)
			(xy 25.928259 -390.945449) (xy 25.924276 -390.8923) (xy 20.129297 -390.8923) (xy 20.127013 -390.897302)
			(xy 20.097541 -390.94316) (xy 20.061842 -390.984356) (xy 20.020644 -391.020053) (xy 19.974784 -391.049522)
			(xy 19.925198 -391.072166) (xy 19.872893 -391.087521) (xy 19.818936 -391.095276) (xy 19.79168 -391.095738)
			(xy 19.762096 -391.095179) (xy 19.703637 -391.086042) (xy 19.64729 -391.06799) (xy 19.594405 -391.041455)
			(xy 19.546251 -391.007075) (xy 19.524726 -390.986772) (xy 19.515582 -390.977882) (xy 19.491198 -390.97077)
			(xy 19.383248 -390.993884) (xy 19.363944 -391.010394) (xy 19.359118 -391.022332) (xy 19.348961 -391.046979)
			(xy 19.322322 -391.093153) (xy 19.289095 -391.134839) (xy 19.250024 -391.171104) (xy 19.205982 -391.201138)
			(xy 19.157955 -391.22427) (xy 19.107015 -391.239981) (xy 19.054302 -391.247922) (xy 19.027648 -391.248392)
			(xy 19.002653 -391.247952) (xy 18.953153 -391.240961) (xy 18.905116 -391.227122) (xy 18.859484 -391.206708)
			(xy 18.817151 -391.180118) (xy 18.797778 -391.164318) (xy 18.790666 -391.158222) (xy 18.774156 -391.152126)
			(xy 18.690082 -391.152126) (xy 18.673572 -391.158222) (xy 18.66646 -391.164318) (xy 18.647082 -391.180114)
			(xy 18.604756 -391.206717) (xy 18.559125 -391.22714) (xy 18.511088 -391.240982) (xy 18.461586 -391.247971)
			(xy 18.43659 -391.248392) (xy 18.410229 -391.247941) (xy 18.358085 -391.240145) (xy 18.307663 -391.22474)
			(xy 18.260065 -391.202064) (xy 18.216335 -391.172613) (xy 18.19656 -391.155174) (xy 18.189448 -391.148824)
			(xy 18.171668 -391.141966) (xy 18.084292 -391.141966) (xy 18.066512 -391.148824) (xy 18.0594 -391.155174)
			(xy 18.039599 -391.172577) (xy 17.995862 -391.202002) (xy 17.948269 -391.224666) (xy 17.897857 -391.240074)
			(xy 17.845726 -391.24789) (xy 17.81937 -391.248392) (xy 17.79301 -391.247893) (xy 17.740869 -391.240108)
			(xy 17.690447 -391.224715) (xy 17.642849 -391.202049) (xy 17.599117 -391.172608) (xy 17.57934 -391.155174)
			(xy 17.572228 -391.148824) (xy 17.554448 -391.141966) (xy 17.467072 -391.141966) (xy 17.449292 -391.148824)
			(xy 17.44218 -391.155174) (xy 17.422387 -391.172586) (xy 17.378648 -391.20201) (xy 17.331053 -391.224672)
			(xy 17.280639 -391.240078) (xy 17.228507 -391.247892) (xy 17.20215 -391.248392) (xy 17.175501 -391.247886)
			(xy 17.122798 -391.239943) (xy 17.071868 -391.224233) (xy 17.023848 -391.201108) (xy 16.979811 -391.171084)
			(xy 16.940741 -391.134832) (xy 16.90751 -391.093162) (xy 16.880861 -391.047004) (xy 16.861389 -390.997391)
			(xy 16.849529 -390.945429) (xy 16.845547 -390.89228) (xy 11.557 -390.89228) (xy 11.557 -391.761726)
			(xy 18.769076 -391.761726) (xy 18.769579 -391.734475) (xy 18.777332 -391.680526) (xy 18.792684 -391.62823)
			(xy 18.815323 -391.578651) (xy 18.844787 -391.532798) (xy 18.880476 -391.491606) (xy 18.921665 -391.455912)
			(xy 18.967514 -391.426443) (xy 19.01709 -391.403799) (xy 19.069385 -391.388441) (xy 19.123333 -391.380682)
			(xy 19.150584 -391.380218) (xy 19.176567 -391.380641) (xy 19.22805 -391.387704) (xy 19.278098 -391.401688)
			(xy 19.325786 -391.422335) (xy 19.370231 -391.449262) (xy 19.410611 -391.481971) (xy 19.428714 -391.500614)
			(xy 19.435826 -391.508234) (xy 19.454114 -391.516362) (xy 19.546824 -391.519156) (xy 19.56562 -391.51179)
			(xy 19.572986 -391.504678) (xy 19.594416 -391.48501) (xy 19.642122 -391.451735) (xy 19.694323 -391.42608)
			(xy 19.749811 -391.408639) (xy 19.807302 -391.399815) (xy 19.836384 -391.399268) (xy 19.863634 -391.399793)
			(xy 19.917579 -391.407547) (xy 19.969871 -391.422899) (xy 20.019447 -391.445536) (xy 20.065296 -391.474998)
			(xy 20.106486 -391.510686) (xy 20.142178 -391.551872) (xy 20.171645 -391.597718) (xy 20.194287 -391.647291)
			(xy 20.209645 -391.699582) (xy 20.215843 -391.742676) (xy 20.730716 -391.742676) (xy 20.734787 -391.687054)
			(xy 20.746913 -391.632617) (xy 20.766836 -391.580526) (xy 20.794132 -391.531891) (xy 20.828218 -391.487748)
			(xy 20.868367 -391.449039) (xy 20.913725 -391.416588) (xy 20.963325 -391.391087) (xy 21.016109 -391.37308)
			(xy 21.070952 -391.36295) (xy 21.126686 -391.360913) (xy 21.182123 -391.367013) (xy 21.23608 -391.381119)
			(xy 21.287409 -391.402931) (xy 21.335015 -391.431985) (xy 21.377883 -391.46766) (xy 21.4151 -391.509197)
			(xy 21.445873 -391.55571) (xy 21.469545 -391.606207) (xy 21.485613 -391.659614) (xy 21.493733 -391.71479)
			(xy 21.494242 -391.742676) (xy 21.493733 -391.770562) (xy 21.487557 -391.812526) (xy 27.862276 -391.812526)
			(xy 27.862779 -391.785275) (xy 27.870532 -391.731326) (xy 27.885884 -391.67903) (xy 27.908523 -391.629451)
			(xy 27.937987 -391.583598) (xy 27.973676 -391.542406) (xy 28.014865 -391.506712) (xy 28.060714 -391.477243)
			(xy 28.11029 -391.454599) (xy 28.162585 -391.439241) (xy 28.216533 -391.431482) (xy 28.243784 -391.431018)
			(xy 28.273907 -391.431608) (xy 28.333402 -391.441086) (xy 28.390669 -391.459793) (xy 28.444286 -391.487264)
			(xy 28.492922 -391.522818) (xy 28.514548 -391.543794) (xy 28.522422 -391.551668) (xy 28.542234 -391.559288)
			(xy 28.640024 -391.554208) (xy 28.659074 -391.544302) (xy 28.665932 -391.535666) (xy 28.68415 -391.513789)
			(xy 28.725992 -391.475185) (xy 28.773102 -391.443223) (xy 28.824436 -391.41861) (xy 28.878856 -391.401893)
			(xy 28.935155 -391.393442) (xy 28.96362 -391.392918) (xy 28.990875 -391.393336) (xy 29.044828 -391.401097)
			(xy 29.097129 -391.416457) (xy 29.146711 -391.439103) (xy 29.192565 -391.468576) (xy 29.233758 -391.504274)
			(xy 29.269452 -391.545472) (xy 29.298919 -391.59133) (xy 29.321559 -391.640914) (xy 29.336913 -391.693217)
			(xy 29.344667 -391.747171) (xy 29.345128 -391.774426) (xy 29.344717 -391.800035) (xy 29.337855 -391.850792)
			(xy 29.324271 -391.900177) (xy 29.304209 -391.947303) (xy 29.278029 -391.991325) (xy 29.246201 -392.031453)
			(xy 29.228034 -392.049508) (xy 29.218636 -392.058398) (xy 29.211016 -392.082782) (xy 29.231082 -392.191494)
			(xy 29.247084 -392.211306) (xy 29.259022 -392.216386) (xy 29.284595 -392.227703) (xy 29.332418 -392.256689)
			(xy 29.375495 -392.292347) (xy 29.412903 -392.333914) (xy 29.443839 -392.380499) (xy 29.46764 -392.431103)
			(xy 29.483795 -392.484639) (xy 29.491959 -392.539961) (xy 29.492448 -392.567922) (xy 29.491943 -392.595172)
			(xy 29.484184 -392.649117) (xy 29.468828 -392.701409) (xy 29.446188 -392.750983) (xy 29.416723 -392.796832)
			(xy 29.381034 -392.838021) (xy 29.339846 -392.873712) (xy 29.293999 -392.903179) (xy 29.244426 -392.925822)
			(xy 29.192135 -392.94118) (xy 29.13819 -392.948942) (xy 29.11094 -392.94943) (xy 29.080673 -392.948837)
			(xy 29.0209 -392.939271) (xy 28.963386 -392.920389) (xy 28.909575 -392.892664) (xy 28.860815 -392.856792)
			(xy 28.83916 -392.835638) (xy 28.832048 -392.828272) (xy 28.813506 -392.820652) (xy 28.720288 -392.820652)
			(xy 28.701746 -392.828272) (xy 28.694634 -392.835638) (xy 28.672998 -392.856814) (xy 28.624238 -392.892693)
			(xy 28.570422 -392.92042) (xy 28.512903 -392.939298) (xy 28.453123 -392.948853) (xy 28.422854 -392.94943)
			(xy 28.395603 -392.948965) (xy 28.341655 -392.941203) (xy 28.289362 -392.925843) (xy 28.239786 -392.903198)
			(xy 28.193936 -392.873729) (xy 28.152747 -392.838036) (xy 28.117057 -392.796844) (xy 28.08759 -392.750993)
			(xy 28.064949 -392.701416) (xy 28.049592 -392.649121) (xy 28.041833 -392.595173) (xy 28.041346 -392.567922)
			(xy 28.041819 -392.541189) (xy 28.049324 -392.488253) (xy 28.064134 -392.436879) (xy 28.085961 -392.38807)
			(xy 28.114378 -392.342781) (xy 28.131262 -392.32205) (xy 28.138882 -392.312652) (xy 28.14447 -392.289284)
			(xy 28.120086 -392.186414) (xy 28.104592 -392.167872) (xy 28.093416 -392.1633) (xy 28.068068 -392.151839)
			(xy 28.020679 -392.122711) (xy 27.978019 -392.087013) (xy 27.940992 -392.045501) (xy 27.910382 -391.999054)
			(xy 27.886838 -391.948656) (xy 27.870858 -391.895375) (xy 27.862781 -391.840339) (xy 27.862276 -391.812526)
			(xy 21.487557 -391.812526) (xy 21.485613 -391.825738) (xy 21.469545 -391.879145) (xy 21.445873 -391.929642)
			(xy 21.4151 -391.976155) (xy 21.377883 -392.017692) (xy 21.335015 -392.053367) (xy 21.287409 -392.082421)
			(xy 21.23608 -392.104233) (xy 21.182123 -392.118339) (xy 21.126686 -392.124439) (xy 21.070952 -392.122402)
			(xy 21.016109 -392.112272) (xy 20.963325 -392.094265) (xy 20.913725 -392.068764) (xy 20.868367 -392.036313)
			(xy 20.828218 -391.997604) (xy 20.794132 -391.953461) (xy 20.766836 -391.904826) (xy 20.746913 -391.852735)
			(xy 20.734787 -391.798298) (xy 20.730716 -391.742676) (xy 20.215843 -391.742676) (xy 20.217404 -391.753526)
			(xy 20.217892 -391.780776) (xy 20.217454 -391.807389) (xy 20.210053 -391.860097) (xy 20.195392 -391.911264)
			(xy 20.173755 -391.959893) (xy 20.145564 -392.00504) (xy 20.111367 -392.045826) (xy 20.091908 -392.063986)
			(xy 20.081748 -392.07313) (xy 20.07362 -392.099038) (xy 20.098004 -392.212068) (xy 20.116292 -392.232134)
			(xy 20.1295 -392.236198) (xy 20.154903 -392.244743) (xy 20.203216 -392.267948) (xy 20.247807 -392.297683)
			(xy 20.2878 -392.333364) (xy 20.322409 -392.374289) (xy 20.350951 -392.419653) (xy 20.372867 -392.468564)
			(xy 20.387726 -392.52006) (xy 20.395234 -392.573128) (xy 20.395692 -392.599926) (xy 20.395246 -392.627179)
			(xy 20.387486 -392.681129) (xy 20.372127 -392.733425) (xy 20.349481 -392.783003) (xy 20.341544 -392.795352)
			(xy 24.261552 -392.795352) (xy 24.261552 -392.740848) (xy 24.269308 -392.686899) (xy 24.284663 -392.634603)
			(xy 24.307303 -392.585024) (xy 24.336769 -392.539172) (xy 24.37246 -392.49798) (xy 24.41365 -392.462286)
			(xy 24.4595 -392.432817) (xy 24.509077 -392.410173) (xy 24.561372 -392.394814) (xy 24.61532 -392.387054)
			(xy 24.642572 -392.386566) (xy 24.668493 -392.386996) (xy 24.719856 -392.394035) (xy 24.769793 -392.407961)
			(xy 24.817387 -392.428516) (xy 24.861761 -392.455323) (xy 24.902098 -392.487889) (xy 24.920194 -392.506454)
			(xy 24.92756 -392.514328) (xy 24.946864 -392.522456) (xy 25.043384 -392.521186) (xy 25.062434 -392.51255)
			(xy 25.0698 -392.504422) (xy 25.087992 -392.484869) (xy 25.128845 -392.450472) (xy 25.174096 -392.42211)
			(xy 25.222861 -392.400337) (xy 25.274187 -392.385579) (xy 25.327069 -392.378126) (xy 25.353772 -392.377676)
			(xy 25.381025 -392.378169) (xy 25.434977 -392.385923) (xy 25.487276 -392.401276) (xy 25.536857 -392.423916)
			(xy 25.582712 -392.453382) (xy 25.623906 -392.489074) (xy 25.659601 -392.530266) (xy 25.689071 -392.576118)
			(xy 25.711714 -392.625698) (xy 25.727071 -392.677996) (xy 25.734829 -392.731947) (xy 25.734829 -392.786453)
			(xy 25.727071 -392.840404) (xy 25.711714 -392.892702) (xy 25.689071 -392.942282) (xy 25.659601 -392.988134)
			(xy 25.623906 -393.029326) (xy 25.582712 -393.065018) (xy 25.536857 -393.094484) (xy 25.487276 -393.117124)
			(xy 25.434977 -393.132477) (xy 25.381025 -393.140231) (xy 25.353772 -393.140692) (xy 25.327851 -393.140246)
			(xy 25.276489 -393.133212) (xy 25.226551 -393.119291) (xy 25.178957 -393.098738) (xy 25.134583 -393.071933)
			(xy 25.094245 -393.039369) (xy 25.07615 -393.020804) (xy 25.068784 -393.01293) (xy 25.04948 -393.004802)
			(xy 24.95296 -393.006072) (xy 24.93391 -393.014708) (xy 24.926544 -393.022836) (xy 24.908391 -393.042427)
			(xy 24.867529 -393.076819) (xy 24.822269 -393.105175) (xy 24.773496 -393.126941) (xy 24.722164 -393.14169)
			(xy 24.669277 -393.149136) (xy 24.642572 -393.149582) (xy 24.61532 -393.149146) (xy 24.561372 -393.141386)
			(xy 24.509077 -393.126027) (xy 24.4595 -393.103383) (xy 24.41365 -393.073914) (xy 24.37246 -393.03822)
			(xy 24.336769 -392.997028) (xy 24.307303 -392.951176) (xy 24.284663 -392.901597) (xy 24.269308 -392.849301)
			(xy 24.261552 -392.795352) (xy 20.341544 -392.795352) (xy 20.320011 -392.828855) (xy 20.284315 -392.870045)
			(xy 20.243121 -392.905736) (xy 20.197267 -392.935201) (xy 20.147686 -392.957841) (xy 20.095388 -392.973195)
			(xy 20.041437 -392.980949) (xy 20.014184 -392.981434) (xy 19.985268 -392.98088) (xy 19.928097 -392.972162)
			(xy 19.872898 -392.954913) (xy 19.820936 -392.929528) (xy 19.773401 -392.896589) (xy 19.731384 -392.856852)
			(xy 19.713194 -392.834368) (xy 19.705636 -392.825602) (xy 19.684874 -392.815422) (xy 19.673316 -392.81481)
			(xy 19.593052 -392.81481) (xy 19.581488 -392.815407) (xy 19.560716 -392.825583) (xy 19.553174 -392.834368)
			(xy 19.53499 -392.856857) (xy 19.492969 -392.896594) (xy 19.445433 -392.929533) (xy 19.393471 -392.954921)
			(xy 19.338272 -392.972175) (xy 19.281101 -392.980901) (xy 19.252184 -392.981434) (xy 19.224934 -392.980937)
			(xy 19.170988 -392.973179) (xy 19.118695 -392.957823) (xy 19.069119 -392.935182) (xy 19.02327 -392.905717)
			(xy 18.982081 -392.870026) (xy 18.946389 -392.828838) (xy 18.916923 -392.78299) (xy 18.89428 -392.733415)
			(xy 18.878923 -392.681122) (xy 18.871164 -392.627176) (xy 18.870676 -392.599926) (xy 18.871129 -392.574237)
			(xy 18.878021 -392.523325) (xy 18.891684 -392.473798) (xy 18.91187 -392.426553) (xy 18.938215 -392.382444)
			(xy 18.970241 -392.342271) (xy 19.007369 -392.306759) (xy 19.027902 -392.291316) (xy 19.039078 -392.283188)
			(xy 19.050254 -392.257788) (xy 19.036284 -392.142218) (xy 19.01952 -392.12012) (xy 19.006566 -392.11504)
			(xy 18.980604 -392.103918) (xy 18.932023 -392.07511) (xy 18.888218 -392.039457) (xy 18.850147 -391.997737)
			(xy 18.81864 -391.950861) (xy 18.794387 -391.899854) (xy 18.777916 -391.845829) (xy 18.769588 -391.789966)
			(xy 18.769076 -391.761726) (xy 11.557 -391.761726) (xy 11.557 -392.463528) (xy 11.55645 -392.492103)
			(xy 11.547472 -392.548545) (xy 11.529771 -392.602886) (xy 11.503785 -392.653788) (xy 11.489006 -392.674094)
			(xy 11.892278 -392.674094) (xy 11.896349 -392.618472) (xy 11.908475 -392.564035) (xy 11.928398 -392.511944)
			(xy 11.955694 -392.463309) (xy 11.98978 -392.419166) (xy 12.029929 -392.380457) (xy 12.075287 -392.348006)
			(xy 12.124887 -392.322505) (xy 12.177671 -392.304498) (xy 12.232514 -392.294368) (xy 12.288248 -392.292331)
			(xy 12.343685 -392.298431) (xy 12.397642 -392.312537) (xy 12.448971 -392.334349) (xy 12.496577 -392.363403)
			(xy 12.539445 -392.399078) (xy 12.576662 -392.440615) (xy 12.607435 -392.487128) (xy 12.631107 -392.537625)
			(xy 12.647175 -392.591032) (xy 12.655295 -392.646208) (xy 12.655804 -392.674094) (xy 12.655295 -392.70198)
			(xy 12.647175 -392.757156) (xy 12.631107 -392.810563) (xy 12.607435 -392.86106) (xy 12.576662 -392.907573)
			(xy 12.562991 -392.922831) (xy 15.26665 -392.922831) (xy 15.26665 -392.868329) (xy 15.274406 -392.814381)
			(xy 15.289761 -392.762087) (xy 15.312402 -392.71251) (xy 15.341868 -392.66666) (xy 15.37756 -392.62547)
			(xy 15.41875 -392.589778) (xy 15.4646 -392.560312) (xy 15.514177 -392.537671) (xy 15.566471 -392.522316)
			(xy 15.620419 -392.51456) (xy 15.64767 -392.514074) (xy 15.676293 -392.514562) (xy 15.732896 -392.523107)
			(xy 15.787589 -392.540011) (xy 15.839143 -392.564893) (xy 15.863062 -392.580622) (xy 15.871698 -392.586464)
			(xy 15.891256 -392.590528) (xy 15.983204 -392.571986) (xy 15.999968 -392.56081) (xy 16.005556 -392.55192)
			(xy 16.020677 -392.529346) (xy 16.056374 -392.488382) (xy 16.097522 -392.452896) (xy 16.143288 -392.423608)
			(xy 16.192746 -392.401109) (xy 16.244896 -392.385854) (xy 16.298682 -392.378152) (xy 16.32585 -392.377676)
			(xy 16.353102 -392.378154) (xy 16.40705 -392.38591) (xy 16.459345 -392.401266) (xy 16.508923 -392.423907)
			(xy 16.554774 -392.453374) (xy 16.595964 -392.489066) (xy 16.631656 -392.530256) (xy 16.661123 -392.576107)
			(xy 16.683764 -392.625685) (xy 16.69912 -392.67798) (xy 16.706876 -392.731928) (xy 16.706876 -392.786432)
			(xy 16.69912 -392.84038) (xy 16.683764 -392.892675) (xy 16.661123 -392.942253) (xy 16.631656 -392.988104)
			(xy 16.595964 -393.029294) (xy 16.554774 -393.064986) (xy 16.508923 -393.094453) (xy 16.459345 -393.117094)
			(xy 16.40705 -393.13245) (xy 16.353102 -393.140206) (xy 16.32585 -393.140692) (xy 16.297228 -393.1402)
			(xy 16.240624 -393.131657) (xy 16.185931 -393.114755) (xy 16.134377 -393.089873) (xy 16.110458 -393.074144)
			(xy 16.101822 -393.068302) (xy 16.082264 -393.064238) (xy 15.990316 -393.08278) (xy 15.973552 -393.093956)
			(xy 15.967964 -393.102846) (xy 15.952818 -393.125403) (xy 15.917126 -393.166369) (xy 15.875984 -393.201857)
			(xy 15.830222 -393.231148) (xy 15.780767 -393.25365) (xy 15.728621 -393.268907) (xy 15.674837 -393.276612)
			(xy 15.64767 -393.27709) (xy 15.620419 -393.2766) (xy 15.566471 -393.268844) (xy 15.514177 -393.253489)
			(xy 15.4646 -393.230848) (xy 15.41875 -393.201382) (xy 15.37756 -393.16569) (xy 15.341868 -393.1245)
			(xy 15.312402 -393.07865) (xy 15.289761 -393.029073) (xy 15.274406 -392.976779) (xy 15.26665 -392.922831)
			(xy 12.562991 -392.922831) (xy 12.539445 -392.94911) (xy 12.496577 -392.984785) (xy 12.448971 -393.013839)
			(xy 12.397642 -393.035651) (xy 12.343685 -393.049757) (xy 12.288248 -393.055857) (xy 12.232514 -393.05382)
			(xy 12.177671 -393.04369) (xy 12.124887 -393.025683) (xy 12.075287 -393.000182) (xy 12.029929 -392.967731)
			(xy 11.98978 -392.929022) (xy 11.955694 -392.884879) (xy 11.928398 -392.836244) (xy 11.908475 -392.784153)
			(xy 11.896349 -392.729716) (xy 11.892278 -392.674094) (xy 11.489006 -392.674094) (xy 11.470154 -392.699997)
			(xy 11.45032 -392.720576) (xy 10.588752 -393.582144) (xy 16.440148 -393.582144) (xy 16.444219 -393.526522)
			(xy 16.456345 -393.472085) (xy 16.476268 -393.419994) (xy 16.503564 -393.371359) (xy 16.53765 -393.327216)
			(xy 16.577799 -393.288507) (xy 16.623157 -393.256056) (xy 16.672757 -393.230555) (xy 16.725541 -393.212548)
			(xy 16.780384 -393.202418) (xy 16.836118 -393.200381) (xy 16.891555 -393.206481) (xy 16.945512 -393.220587)
			(xy 16.996841 -393.242399) (xy 17.044447 -393.271453) (xy 17.087315 -393.307128) (xy 17.124532 -393.348665)
			(xy 17.155305 -393.395178) (xy 17.178977 -393.445675) (xy 17.189926 -393.482068) (xy 23.315166 -393.482068)
			(xy 23.319237 -393.426446) (xy 23.331363 -393.372009) (xy 23.351286 -393.319918) (xy 23.378582 -393.271283)
			(xy 23.412668 -393.22714) (xy 23.452817 -393.188431) (xy 23.498175 -393.15598) (xy 23.547775 -393.130479)
			(xy 23.600559 -393.112472) (xy 23.655402 -393.102342) (xy 23.711136 -393.100305) (xy 23.766573 -393.106405)
			(xy 23.82053 -393.120511) (xy 23.871859 -393.142323) (xy 23.919465 -393.171377) (xy 23.962333 -393.207052)
			(xy 23.99955 -393.248589) (xy 24.030323 -393.295102) (xy 24.053995 -393.345599) (xy 24.070063 -393.399006)
			(xy 24.078183 -393.454182) (xy 24.078692 -393.482068) (xy 24.078183 -393.509954) (xy 24.070063 -393.56513)
			(xy 24.053995 -393.618537) (xy 24.030323 -393.669034) (xy 23.99955 -393.715547) (xy 23.962333 -393.757084)
			(xy 23.957065 -393.761468) (xy 25.528776 -393.761468) (xy 25.532847 -393.705846) (xy 25.544973 -393.651409)
			(xy 25.564896 -393.599318) (xy 25.592192 -393.550683) (xy 25.626278 -393.50654) (xy 25.666427 -393.467831)
			(xy 25.711785 -393.43538) (xy 25.761385 -393.409879) (xy 25.814169 -393.391872) (xy 25.869012 -393.381742)
			(xy 25.924746 -393.379705) (xy 25.980183 -393.385805) (xy 26.03414 -393.399911) (xy 26.085469 -393.421723)
			(xy 26.133075 -393.450777) (xy 26.175943 -393.486452) (xy 26.21316 -393.527989) (xy 26.243933 -393.574502)
			(xy 26.267605 -393.624999) (xy 26.283673 -393.678406) (xy 26.291793 -393.733582) (xy 26.292302 -393.761468)
			(xy 26.291793 -393.789354) (xy 26.283673 -393.84453) (xy 26.267605 -393.897937) (xy 26.243933 -393.948434)
			(xy 26.21316 -393.994947) (xy 26.175943 -394.036484) (xy 26.133075 -394.072159) (xy 26.085469 -394.101213)
			(xy 26.03414 -394.123025) (xy 25.980183 -394.137131) (xy 25.924746 -394.143231) (xy 25.869012 -394.141194)
			(xy 25.814169 -394.131064) (xy 25.761385 -394.113057) (xy 25.711785 -394.087556) (xy 25.666427 -394.055105)
			(xy 25.626278 -394.016396) (xy 25.592192 -393.972253) (xy 25.564896 -393.923618) (xy 25.544973 -393.871527)
			(xy 25.532847 -393.81709) (xy 25.528776 -393.761468) (xy 23.957065 -393.761468) (xy 23.919465 -393.792759)
			(xy 23.871859 -393.821813) (xy 23.82053 -393.843625) (xy 23.766573 -393.857731) (xy 23.711136 -393.863831)
			(xy 23.655402 -393.861794) (xy 23.600559 -393.851664) (xy 23.547775 -393.833657) (xy 23.498175 -393.808156)
			(xy 23.452817 -393.775705) (xy 23.412668 -393.736996) (xy 23.378582 -393.692853) (xy 23.351286 -393.644218)
			(xy 23.331363 -393.592127) (xy 23.319237 -393.53769) (xy 23.315166 -393.482068) (xy 17.189926 -393.482068)
			(xy 17.195045 -393.499082) (xy 17.203165 -393.554258) (xy 17.203674 -393.582144) (xy 17.203165 -393.61003)
			(xy 17.195045 -393.665206) (xy 17.178977 -393.718613) (xy 17.155305 -393.76911) (xy 17.124532 -393.815623)
			(xy 17.087315 -393.85716) (xy 17.044447 -393.892835) (xy 16.996841 -393.921889) (xy 16.945512 -393.943701)
			(xy 16.891555 -393.957807) (xy 16.836118 -393.963907) (xy 16.780384 -393.96187) (xy 16.725541 -393.95174)
			(xy 16.672757 -393.933733) (xy 16.623157 -393.908232) (xy 16.577799 -393.875781) (xy 16.53765 -393.837072)
			(xy 16.503564 -393.792929) (xy 16.476268 -393.744294) (xy 16.456345 -393.692203) (xy 16.444219 -393.637766)
			(xy 16.440148 -393.582144) (xy 10.588752 -393.582144) (xy 10.14222 -394.028676) (xy 12.113766 -394.028676)
			(xy 12.117837 -393.973054) (xy 12.129963 -393.918617) (xy 12.149886 -393.866526) (xy 12.177182 -393.817891)
			(xy 12.211268 -393.773748) (xy 12.251417 -393.735039) (xy 12.296775 -393.702588) (xy 12.346375 -393.677087)
			(xy 12.399159 -393.65908) (xy 12.454002 -393.64895) (xy 12.509736 -393.646913) (xy 12.565173 -393.653013)
			(xy 12.61913 -393.667119) (xy 12.670459 -393.688931) (xy 12.718065 -393.717985) (xy 12.760933 -393.75366)
			(xy 12.79815 -393.795197) (xy 12.828923 -393.84171) (xy 12.852595 -393.892207) (xy 12.868663 -393.945614)
			(xy 12.876783 -394.00079) (xy 12.877292 -394.028676) (xy 12.877028 -394.043154) (xy 13.681962 -394.043154)
			(xy 13.686033 -393.987532) (xy 13.698159 -393.933095) (xy 13.718082 -393.881004) (xy 13.745378 -393.832369)
			(xy 13.779464 -393.788226) (xy 13.819613 -393.749517) (xy 13.864971 -393.717066) (xy 13.914571 -393.691565)
			(xy 13.967355 -393.673558) (xy 14.022198 -393.663428) (xy 14.077932 -393.661391) (xy 14.133369 -393.667491)
			(xy 14.187326 -393.681597) (xy 14.238655 -393.703409) (xy 14.286261 -393.732463) (xy 14.329129 -393.768138)
			(xy 14.366346 -393.809675) (xy 14.397119 -393.856188) (xy 14.420791 -393.906685) (xy 14.436859 -393.960092)
			(xy 14.444979 -394.015268) (xy 14.445488 -394.043154) (xy 14.444979 -394.07104) (xy 14.436859 -394.126216)
			(xy 14.420791 -394.179623) (xy 14.397119 -394.23012) (xy 14.366346 -394.276633) (xy 14.336044 -394.310452)
			(xy 22.100762 -394.310452) (xy 22.100762 -394.255948) (xy 22.108518 -394.201998) (xy 22.123874 -394.149702)
			(xy 22.146516 -394.100123) (xy 22.175983 -394.054271) (xy 22.211675 -394.013079) (xy 22.252866 -393.977386)
			(xy 22.298718 -393.947918) (xy 22.348296 -393.925276) (xy 22.400593 -393.90992) (xy 22.454542 -393.902162)
			(xy 22.481794 -393.901676) (xy 22.510712 -393.90217) (xy 22.567886 -393.9109) (xy 22.623086 -393.928161)
			(xy 22.675049 -393.953557) (xy 22.722582 -393.986506) (xy 22.764596 -394.026253) (xy 22.782784 -394.048742)
			(xy 22.79035 -394.057499) (xy 22.811106 -394.067683) (xy 22.822662 -394.0683) (xy 22.902926 -394.0683)
			(xy 22.914488 -394.067687) (xy 22.93526 -394.057523) (xy 22.942804 -394.048742) (xy 22.961003 -394.026265)
			(xy 23.00302 -393.986528) (xy 23.050553 -393.953587) (xy 23.102513 -393.928197) (xy 23.157709 -393.91094)
			(xy 23.214878 -393.902211) (xy 23.243794 -393.901676) (xy 23.271046 -393.902171) (xy 23.324995 -393.909927)
			(xy 23.377292 -393.925282) (xy 23.42687 -393.947923) (xy 23.472722 -393.97739) (xy 23.513914 -394.013082)
			(xy 23.549607 -394.054273) (xy 23.579074 -394.100124) (xy 23.601716 -394.149703) (xy 23.617072 -394.201999)
			(xy 23.624829 -394.255948) (xy 23.624829 -394.310452) (xy 23.617072 -394.364401) (xy 23.601716 -394.416697)
			(xy 23.579074 -394.466276) (xy 23.549607 -394.512127) (xy 23.513914 -394.553318) (xy 23.472722 -394.58901)
			(xy 23.42687 -394.618477) (xy 23.377292 -394.641118) (xy 23.324995 -394.656473) (xy 23.271046 -394.664229)
			(xy 23.243794 -394.664692) (xy 23.214877 -394.664181) (xy 23.157705 -394.655451) (xy 23.102506 -394.638191)
			(xy 23.050544 -394.612799) (xy 23.003011 -394.579854) (xy 22.960994 -394.540112) (xy 22.942804 -394.517626)
			(xy 22.935249 -394.508858) (xy 22.914484 -394.498681) (xy 22.902926 -394.498068) (xy 22.822662 -394.498068)
			(xy 22.811095 -394.49865) (xy 22.790322 -394.508834) (xy 22.782784 -394.517626) (xy 22.764609 -394.540123)
			(xy 22.722585 -394.579856) (xy 22.675046 -394.612792) (xy 22.623082 -394.638178) (xy 22.567882 -394.655432)
			(xy 22.510711 -394.664158) (xy 22.481794 -394.664692) (xy 22.454542 -394.664238) (xy 22.400593 -394.65648)
			(xy 22.348296 -394.641124) (xy 22.298718 -394.618482) (xy 22.252866 -394.589014) (xy 22.211675 -394.553321)
			(xy 22.175983 -394.512129) (xy 22.146516 -394.466277) (xy 22.123874 -394.416698) (xy 22.108518 -394.364402)
			(xy 22.100762 -394.310452) (xy 14.336044 -394.310452) (xy 14.329129 -394.31817) (xy 14.286261 -394.353845)
			(xy 14.238655 -394.382899) (xy 14.187326 -394.404711) (xy 14.133369 -394.418817) (xy 14.077932 -394.424917)
			(xy 14.022198 -394.42288) (xy 13.967355 -394.41275) (xy 13.914571 -394.394743) (xy 13.864971 -394.369242)
			(xy 13.819613 -394.336791) (xy 13.779464 -394.298082) (xy 13.745378 -394.253939) (xy 13.718082 -394.205304)
			(xy 13.698159 -394.153213) (xy 13.686033 -394.098776) (xy 13.681962 -394.043154) (xy 12.877028 -394.043154)
			(xy 12.876783 -394.056562) (xy 12.868663 -394.111738) (xy 12.852595 -394.165145) (xy 12.828923 -394.215642)
			(xy 12.79815 -394.262155) (xy 12.760933 -394.303692) (xy 12.718065 -394.339367) (xy 12.670459 -394.368421)
			(xy 12.61913 -394.390233) (xy 12.565173 -394.404339) (xy 12.509736 -394.410439) (xy 12.454002 -394.408402)
			(xy 12.399159 -394.398272) (xy 12.346375 -394.380265) (xy 12.296775 -394.354764) (xy 12.251417 -394.322313)
			(xy 12.211268 -394.283604) (xy 12.177182 -394.239461) (xy 12.149886 -394.190826) (xy 12.129963 -394.138735)
			(xy 12.117837 -394.084298) (xy 12.113766 -394.028676) (xy 10.14222 -394.028676) (xy 9.208008 -394.962888)
			(xy 12.04036 -394.962888) (xy 12.044431 -394.907266) (xy 12.056557 -394.852829) (xy 12.07648 -394.800738)
			(xy 12.103776 -394.752103) (xy 12.137862 -394.70796) (xy 12.178011 -394.669251) (xy 12.223369 -394.6368)
			(xy 12.272969 -394.611299) (xy 12.325753 -394.593292) (xy 12.380596 -394.583162) (xy 12.43633 -394.581125)
			(xy 12.491767 -394.587225) (xy 12.545724 -394.601331) (xy 12.597053 -394.623143) (xy 12.644659 -394.652197)
			(xy 12.687527 -394.687872) (xy 12.724744 -394.729409) (xy 12.755517 -394.775922) (xy 12.779189 -394.826419)
			(xy 12.795257 -394.879826) (xy 12.803377 -394.935002) (xy 12.803886 -394.962888) (xy 12.803377 -394.990774)
			(xy 12.795257 -395.04595) (xy 12.779189 -395.099357) (xy 12.755517 -395.149854) (xy 12.724744 -395.196367)
			(xy 12.687527 -395.237904) (xy 12.644659 -395.273579) (xy 12.597053 -395.302633) (xy 12.545724 -395.324445)
			(xy 12.491767 -395.338551) (xy 12.43633 -395.344651) (xy 12.380596 -395.342614) (xy 12.325753 -395.332484)
			(xy 12.272969 -395.314477) (xy 12.223369 -395.288976) (xy 12.178011 -395.256525) (xy 12.137862 -395.217816)
			(xy 12.103776 -395.173673) (xy 12.07648 -395.125038) (xy 12.056557 -395.072947) (xy 12.044431 -395.01851)
			(xy 12.04036 -394.962888) (xy 9.208008 -394.962888) (xy 8.109966 -396.06093) (xy 12.002514 -396.06093)
			(xy 12.006585 -396.005308) (xy 12.018711 -395.950871) (xy 12.038634 -395.89878) (xy 12.06593 -395.850145)
			(xy 12.100016 -395.806002) (xy 12.140165 -395.767293) (xy 12.185523 -395.734842) (xy 12.235123 -395.709341)
			(xy 12.287907 -395.691334) (xy 12.34275 -395.681204) (xy 12.398484 -395.679167) (xy 12.453921 -395.685267)
			(xy 12.507878 -395.699373) (xy 12.559207 -395.721185) (xy 12.606813 -395.750239) (xy 12.649681 -395.785914)
			(xy 12.686898 -395.827451) (xy 12.717671 -395.873964) (xy 12.741343 -395.924461) (xy 12.753438 -395.964664)
			(xy 19.52498 -395.964664) (xy 19.525405 -395.937292) (xy 19.53323 -395.88311) (xy 19.548728 -395.830606)
			(xy 19.571579 -395.78086) (xy 19.601314 -395.734896) (xy 19.61896 -395.713966) (xy 19.625056 -395.706854)
			(xy 19.631406 -395.689836) (xy 19.631406 -395.604492) (xy 19.625056 -395.587474) (xy 19.61896 -395.580362)
			(xy 19.60133 -395.559423) (xy 19.571618 -395.513451) (xy 19.548781 -395.463706) (xy 19.533287 -395.411207)
			(xy 19.525456 -395.357033) (xy 19.52498 -395.329664) (xy 19.525466 -395.302413) (xy 19.533222 -395.248465)
			(xy 19.548577 -395.19617) (xy 19.571219 -395.146593) (xy 19.600685 -395.100743) (xy 19.636376 -395.059552)
			(xy 19.677567 -395.023861) (xy 19.723417 -394.994395) (xy 19.772994 -394.971753) (xy 19.825289 -394.956398)
			(xy 19.879237 -394.948642) (xy 19.933739 -394.948642) (xy 19.987687 -394.956398) (xy 20.039982 -394.971753)
			(xy 20.089559 -394.994395) (xy 20.135409 -395.023861) (xy 20.1766 -395.059552) (xy 20.212291 -395.100743)
			(xy 20.241757 -395.146593) (xy 20.264399 -395.19617) (xy 20.279754 -395.248465) (xy 20.28751 -395.302413)
			(xy 20.287996 -395.329664) (xy 20.28751 -395.357034) (xy 20.279697 -395.411212) (xy 20.264213 -395.463715)
			(xy 20.241375 -395.513462) (xy 20.211655 -395.55943) (xy 20.194016 -395.580362) (xy 20.18792 -395.587474)
			(xy 20.18157 -395.604492) (xy 20.18157 -395.689836) (xy 20.18792 -395.706854) (xy 20.194016 -395.713966)
			(xy 20.211655 -395.734898) (xy 20.23933 -395.77772) (xy 28.172664 -395.77772) (xy 28.173126 -395.750349)
			(xy 28.180943 -395.69617) (xy 28.196432 -395.643666) (xy 28.219275 -395.593919) (xy 28.249001 -395.547953)
			(xy 28.266644 -395.527022) (xy 28.27274 -395.51991) (xy 28.27909 -395.502892) (xy 28.27909 -395.417548)
			(xy 28.27274 -395.40053) (xy 28.266644 -395.393418) (xy 28.249007 -395.372484) (xy 28.219293 -395.326513)
			(xy 28.196456 -395.276766) (xy 28.180965 -395.224265) (xy 28.173137 -395.170089) (xy 28.172664 -395.14272)
			(xy 28.17315 -395.115469) (xy 28.180906 -395.061521) (xy 28.196261 -395.009226) (xy 28.218903 -394.959649)
			(xy 28.248369 -394.913799) (xy 28.28406 -394.872608) (xy 28.325251 -394.836917) (xy 28.371101 -394.807451)
			(xy 28.420678 -394.784809) (xy 28.472973 -394.769454) (xy 28.526921 -394.761698) (xy 28.581423 -394.761698)
			(xy 28.635371 -394.769454) (xy 28.687666 -394.784809) (xy 28.737243 -394.807451) (xy 28.783093 -394.836917)
			(xy 28.824284 -394.872608) (xy 28.859975 -394.913799) (xy 28.889441 -394.959649) (xy 28.912083 -395.009226)
			(xy 28.927438 -395.061521) (xy 28.935194 -395.115469) (xy 28.93568 -395.14272) (xy 28.935231 -395.170091)
			(xy 28.927409 -395.224271) (xy 28.911917 -395.276774) (xy 28.889071 -395.326521) (xy 28.859343 -395.372487)
			(xy 28.8417 -395.393418) (xy 28.835604 -395.40053) (xy 28.829254 -395.417548) (xy 28.829254 -395.502892)
			(xy 28.835604 -395.51991) (xy 28.8417 -395.527022) (xy 28.859316 -395.547973) (xy 28.889031 -395.59394)
			(xy 28.911872 -395.643683) (xy 28.927368 -395.69618) (xy 28.935203 -395.750352) (xy 28.93568 -395.77772)
			(xy 28.935194 -395.804971) (xy 28.927438 -395.858919) (xy 28.912083 -395.911214) (xy 28.889441 -395.960791)
			(xy 28.859975 -396.006641) (xy 28.824284 -396.047832) (xy 28.783093 -396.083523) (xy 28.737243 -396.112989)
			(xy 28.687666 -396.135631) (xy 28.635371 -396.150986) (xy 28.581423 -396.158742) (xy 28.526921 -396.158742)
			(xy 28.472973 -396.150986) (xy 28.420678 -396.135631) (xy 28.371101 -396.112989) (xy 28.325251 -396.083523)
			(xy 28.28406 -396.047832) (xy 28.248369 -396.006641) (xy 28.218903 -395.960791) (xy 28.196261 -395.911214)
			(xy 28.180906 -395.858919) (xy 28.17315 -395.804971) (xy 28.172664 -395.77772) (xy 20.23933 -395.77772)
			(xy 20.241366 -395.780871) (xy 20.264202 -395.830619) (xy 20.279693 -395.883119) (xy 20.287522 -395.937295)
			(xy 20.287996 -395.964664) (xy 20.28751 -395.991915) (xy 20.279754 -396.045863) (xy 20.264399 -396.098158)
			(xy 20.241757 -396.147735) (xy 20.212291 -396.193585) (xy 20.1766 -396.234776) (xy 20.135409 -396.270467)
			(xy 20.089559 -396.299933) (xy 20.039982 -396.322575) (xy 19.987687 -396.33793) (xy 19.933739 -396.345686)
			(xy 19.879237 -396.345686) (xy 19.825289 -396.33793) (xy 19.772994 -396.322575) (xy 19.723417 -396.299933)
			(xy 19.677567 -396.270467) (xy 19.636376 -396.234776) (xy 19.600685 -396.193585) (xy 19.571219 -396.147735)
			(xy 19.548577 -396.098158) (xy 19.533222 -396.045863) (xy 19.525466 -395.991915) (xy 19.52498 -395.964664)
			(xy 12.753438 -395.964664) (xy 12.757411 -395.977868) (xy 12.765531 -396.033044) (xy 12.76604 -396.06093)
			(xy 12.765531 -396.088816) (xy 12.757411 -396.143992) (xy 12.741343 -396.197399) (xy 12.717671 -396.247896)
			(xy 12.686898 -396.294409) (xy 12.649681 -396.335946) (xy 12.606813 -396.371621) (xy 12.559207 -396.400675)
			(xy 12.507878 -396.422487) (xy 12.453921 -396.436593) (xy 12.398484 -396.442693) (xy 12.34275 -396.440656)
			(xy 12.287907 -396.430526) (xy 12.235123 -396.412519) (xy 12.185523 -396.387018) (xy 12.140165 -396.354567)
			(xy 12.100016 -396.315858) (xy 12.06593 -396.271715) (xy 12.038634 -396.22308) (xy 12.018711 -396.170989)
			(xy 12.006585 -396.116552) (xy 12.002514 -396.06093) (xy 8.109966 -396.06093) (xy 7.475728 -396.695168)
			(xy 7.468942 -396.70259) (xy 7.461333 -396.721187) (xy 7.460996 -396.731236) (xy 7.460996 -398.878552)
			(xy 19.56308 -398.878552) (xy 19.563557 -398.851182) (xy 19.571369 -398.797003) (xy 19.586855 -398.744499)
			(xy 19.609694 -398.694752) (xy 19.639419 -398.648785) (xy 19.65706 -398.627854) (xy 19.663156 -398.620742)
			(xy 19.669506 -398.603724) (xy 19.669506 -398.51838) (xy 19.663156 -398.501362) (xy 19.65706 -398.49425)
			(xy 19.639424 -398.473315) (xy 19.609713 -398.427343) (xy 19.586877 -398.377596) (xy 19.571385 -398.325096)
			(xy 19.563555 -398.270921) (xy 19.56308 -398.243552) (xy 19.563499 -398.217882) (xy 19.570385 -398.167007)
			(xy 19.584026 -398.117513) (xy 19.604176 -398.070293) (xy 19.630472 -398.026199) (xy 19.662439 -397.986026)
			(xy 19.680682 -397.967962) (xy 19.687787 -397.960528) (xy 19.69591 -397.941656) (xy 19.69643 -397.931386)
			(xy 19.69643 -397.85798) (xy 19.695957 -397.847701) (xy 19.687813 -397.828823) (xy 19.680682 -397.821404)
			(xy 19.662461 -397.803318) (xy 19.630484 -397.763154) (xy 19.604181 -397.719066) (xy 19.584026 -397.67185)
			(xy 19.570383 -397.622358) (xy 19.563498 -397.571483) (xy 19.56308 -397.545814) (xy 19.563535 -397.518443)
			(xy 19.571352 -397.464263) (xy 19.586843 -397.411759) (xy 19.609688 -397.362012) (xy 19.639416 -397.316046)
			(xy 19.65706 -397.295116) (xy 19.663156 -397.288004) (xy 19.669506 -397.270986) (xy 19.669506 -397.185642)
			(xy 19.663156 -397.168624) (xy 19.65706 -397.161512) (xy 19.639406 -397.140592) (xy 19.609698 -397.094615)
			(xy 19.586865 -397.044864) (xy 19.571378 -396.992361) (xy 19.563552 -396.938184) (xy 19.56308 -396.910814)
			(xy 19.563566 -396.883563) (xy 19.571322 -396.829615) (xy 19.586677 -396.77732) (xy 19.609319 -396.727743)
			(xy 19.638785 -396.681893) (xy 19.674476 -396.640702) (xy 19.715667 -396.605011) (xy 19.761517 -396.575545)
			(xy 19.811094 -396.552903) (xy 19.863389 -396.537548) (xy 19.917337 -396.529792) (xy 19.971839 -396.529792)
			(xy 20.025787 -396.537548) (xy 20.078082 -396.552903) (xy 20.127659 -396.575545) (xy 20.173509 -396.605011)
			(xy 20.2147 -396.640702) (xy 20.250391 -396.681893) (xy 20.279857 -396.727743) (xy 20.302499 -396.77732)
			(xy 20.317854 -396.829615) (xy 20.32561 -396.883563) (xy 20.326096 -396.910814) (xy 20.325639 -396.938185)
			(xy 20.317819 -396.992364) (xy 20.302328 -397.044867) (xy 20.279484 -397.094614) (xy 20.249758 -397.140581)
			(xy 20.232116 -397.161512) (xy 20.22602 -397.168624) (xy 20.21967 -397.185642) (xy 20.21967 -397.270986)
			(xy 20.22602 -397.288004) (xy 20.232116 -397.295116) (xy 20.249732 -397.316067) (xy 20.279446 -397.362035)
			(xy 20.302287 -397.411778) (xy 20.317783 -397.464274) (xy 20.324947 -397.51381) (xy 28.152598 -397.51381)
			(xy 28.15307 -397.48644) (xy 28.160887 -397.432261) (xy 28.176374 -397.379758) (xy 28.199215 -397.330011)
			(xy 28.228938 -397.284044) (xy 28.246578 -397.263112) (xy 28.252674 -397.256) (xy 28.259024 -397.238982)
			(xy 28.259024 -397.153638) (xy 28.252674 -397.13662) (xy 28.246578 -397.129508) (xy 28.228926 -397.108587)
			(xy 28.199217 -397.06261) (xy 28.176384 -397.01286) (xy 28.160896 -396.960357) (xy 28.15307 -396.90618)
			(xy 28.152598 -396.87881) (xy 28.153084 -396.851559) (xy 28.16084 -396.797611) (xy 28.176195 -396.745316)
			(xy 28.198837 -396.695739) (xy 28.228303 -396.649889) (xy 28.263994 -396.608698) (xy 28.305185 -396.573007)
			(xy 28.351035 -396.543541) (xy 28.400612 -396.520899) (xy 28.452907 -396.505544) (xy 28.506855 -396.497788)
			(xy 28.561357 -396.497788) (xy 28.615305 -396.505544) (xy 28.6676 -396.520899) (xy 28.717177 -396.543541)
			(xy 28.763027 -396.573007) (xy 28.804218 -396.608698) (xy 28.839909 -396.649889) (xy 28.869375 -396.695739)
			(xy 28.892017 -396.745316) (xy 28.907372 -396.797611) (xy 28.915128 -396.851559) (xy 28.915614 -396.87881)
			(xy 28.91515 -396.90618) (xy 28.907331 -396.960359) (xy 28.891842 -397.012862) (xy 28.868999 -397.062609)
			(xy 28.839275 -397.108576) (xy 28.821634 -397.129508) (xy 28.815538 -397.13662) (xy 28.809188 -397.153638)
			(xy 28.809188 -397.238982) (xy 28.815538 -397.256) (xy 28.821634 -397.263112) (xy 28.839251 -397.284062)
			(xy 28.868965 -397.33003) (xy 28.891804 -397.379773) (xy 28.907301 -397.43227) (xy 28.915136 -397.486442)
			(xy 28.915614 -397.51381) (xy 28.915128 -397.541061) (xy 28.907372 -397.595009) (xy 28.892017 -397.647304)
			(xy 28.869375 -397.696881) (xy 28.839909 -397.742731) (xy 28.804218 -397.783922) (xy 28.763027 -397.819613)
			(xy 28.717177 -397.849079) (xy 28.6676 -397.871721) (xy 28.615305 -397.887076) (xy 28.561357 -397.894832)
			(xy 28.506855 -397.894832) (xy 28.452907 -397.887076) (xy 28.400612 -397.871721) (xy 28.351035 -397.849079)
			(xy 28.305185 -397.819613) (xy 28.263994 -397.783922) (xy 28.228303 -397.742731) (xy 28.198837 -397.696881)
			(xy 28.176195 -397.647304) (xy 28.16084 -397.595009) (xy 28.153084 -397.541061) (xy 28.152598 -397.51381)
			(xy 20.324947 -397.51381) (xy 20.325618 -397.518446) (xy 20.326096 -397.545814) (xy 20.325662 -397.571483)
			(xy 20.31878 -397.622359) (xy 20.305143 -397.671853) (xy 20.284995 -397.719073) (xy 20.258702 -397.763167)
			(xy 20.226736 -397.80334) (xy 20.208494 -397.821404) (xy 20.201401 -397.828847) (xy 20.193272 -397.847712)
			(xy 20.192746 -397.85798) (xy 20.192746 -397.931386) (xy 20.193244 -397.941662) (xy 20.201371 -397.960539)
			(xy 20.208494 -397.967962) (xy 20.226761 -397.986003) (xy 20.258731 -398.026178) (xy 20.285026 -398.070276)
			(xy 20.305172 -398.117501) (xy 20.318807 -398.167) (xy 20.325682 -398.217881) (xy 20.326096 -398.243552)
			(xy 20.325527 -398.273028) (xy 20.316465 -398.33128) (xy 20.29855 -398.387445) (xy 20.272207 -398.440185)
			(xy 20.238064 -398.488244) (xy 20.217892 -398.509744) (xy 20.211344 -398.517069) (xy 20.203907 -398.535237)
			(xy 20.203414 -398.54505) (xy 20.203414 -398.577054) (xy 20.203878 -398.586871) (xy 20.211338 -398.605035)
			(xy 20.217892 -398.61236) (xy 20.231608 -398.627346) (xy 20.239228 -398.635982) (xy 20.260056 -398.644872)
			(xy 20.36191 -398.641316) (xy 20.381976 -398.631156) (xy 20.389088 -398.621758) (xy 20.407229 -398.598733)
			(xy 20.449382 -398.558002) (xy 20.497271 -398.524202) (xy 20.549769 -398.498128) (xy 20.605639 -398.480395)
			(xy 20.663564 -398.471421) (xy 20.692872 -398.470882) (xy 20.721929 -398.471455) (xy 20.77937 -398.480283)
			(xy 20.834807 -398.497722) (xy 20.886956 -398.52337) (xy 20.934611 -398.556633) (xy 20.956016 -398.576292)
			(xy 20.963382 -398.58315) (xy 20.981162 -398.590262) (xy 21.071332 -398.590262) (xy 21.089112 -398.58315)
			(xy 21.096478 -398.576292) (xy 21.117891 -398.556639) (xy 21.165535 -398.523356) (xy 21.217681 -398.497695)
			(xy 21.273119 -398.480251) (xy 21.330563 -398.471428) (xy 21.359622 -398.470882) (xy 21.386871 -398.47139)
			(xy 21.440815 -398.479149) (xy 21.493106 -398.494505) (xy 21.542679 -398.517147) (xy 21.588525 -398.546613)
			(xy 21.629712 -398.582304) (xy 21.6654 -398.623492) (xy 21.694864 -398.66934) (xy 21.717502 -398.718915)
			(xy 21.732856 -398.771206) (xy 21.740612 -398.825151) (xy 21.740612 -398.879649) (xy 21.732856 -398.933594)
			(xy 21.717502 -398.985885) (xy 21.694864 -399.03546) (xy 21.6654 -399.081308) (xy 21.629712 -399.122496)
			(xy 21.588526 -399.158187) (xy 21.542679 -399.187653) (xy 21.493106 -399.210295) (xy 21.440815 -399.225651)
			(xy 21.386871 -399.23341) (xy 21.359622 -399.233898) (xy 21.330564 -399.233334) (xy 21.273123 -399.224505)
			(xy 21.217686 -399.207064) (xy 21.165536 -399.181413) (xy 21.117882 -399.148148) (xy 21.096478 -399.128488)
			(xy 21.089112 -399.12163) (xy 21.071332 -399.114518) (xy 20.981162 -399.114518) (xy 20.963382 -399.12163)
			(xy 20.956016 -399.128488) (xy 20.934618 -399.148157) (xy 20.886969 -399.181435) (xy 20.834819 -399.207092)
			(xy 20.779378 -399.224533) (xy 20.721932 -399.233353) (xy 20.692872 -399.233898) (xy 20.665778 -399.233464)
			(xy 20.612138 -399.225788) (xy 20.560125 -399.210593) (xy 20.510787 -399.188187) (xy 20.465119 -399.159021)
			(xy 20.42404 -399.123682) (xy 20.405852 -399.103596) (xy 20.398232 -399.09496) (xy 20.377404 -399.08607)
			(xy 20.27555 -399.089626) (xy 20.255484 -399.099786) (xy 20.248372 -399.109184) (xy 20.230239 -399.132216)
			(xy 20.188086 -399.172949) (xy 20.140196 -399.20675) (xy 20.087696 -399.232823) (xy 20.031824 -399.250554)
			(xy 19.973897 -399.259524) (xy 19.944588 -399.26006) (xy 19.917333 -399.259656) (xy 19.863377 -399.251896)
			(xy 19.811075 -399.236536) (xy 19.761492 -399.213889) (xy 19.715636 -399.184415) (xy 19.674442 -399.148715)
			(xy 19.638749 -399.107516) (xy 19.609282 -399.061656) (xy 19.586643 -399.012069) (xy 19.571291 -398.959764)
			(xy 19.56354 -398.905807) (xy 19.56308 -398.878552) (xy 7.460996 -398.878552) (xy 7.460996 -400.48307)
			(xy 23.694136 -400.48307) (xy 23.694576 -400.455699) (xy 23.702399 -400.401518) (xy 23.717893 -400.349014)
			(xy 23.740741 -400.299268) (xy 23.770472 -400.253303) (xy 23.788116 -400.232372) (xy 23.794212 -400.22526)
			(xy 23.800562 -400.208242) (xy 23.800562 -400.122898) (xy 23.794212 -400.10588) (xy 23.788116 -400.098768)
			(xy 23.770498 -400.077819) (xy 23.740782 -400.031851) (xy 23.717942 -399.982108) (xy 23.702446 -399.929611)
			(xy 23.694613 -399.875438) (xy 23.694136 -399.84807) (xy 23.694527 -399.820814) (xy 23.702289 -399.766859)
			(xy 23.717651 -399.714557) (xy 23.740301 -399.664973) (xy 23.769776 -399.619118) (xy 23.805477 -399.577925)
			(xy 23.846678 -399.542231) (xy 23.892538 -399.512765) (xy 23.942126 -399.490125) (xy 23.994431 -399.474774)
			(xy 24.048388 -399.467022) (xy 24.075644 -399.466562) (xy 24.105766 -399.467165) (xy 24.165261 -399.476638)
			(xy 24.222529 -399.495341) (xy 24.276146 -399.52281) (xy 24.324782 -399.558362) (xy 24.346408 -399.579338)
			(xy 24.35352 -399.586704) (xy 24.372316 -399.594324) (xy 24.464772 -399.594324) (xy 24.483568 -399.586704)
			(xy 24.49068 -399.579338) (xy 24.512297 -399.558349) (xy 24.560927 -399.52278) (xy 24.614545 -399.495301)
			(xy 24.671818 -399.476595) (xy 24.731319 -399.467128) (xy 24.761444 -399.466562) (xy 24.788814 -399.467046)
			(xy 24.842993 -399.474857) (xy 24.895496 -399.490341) (xy 24.945243 -399.513179) (xy 24.99121 -399.542902)
			(xy 25.012142 -399.560542) (xy 25.019254 -399.566638) (xy 25.036272 -399.572988) (xy 25.121616 -399.572988)
			(xy 25.138634 -399.566638) (xy 25.145746 -399.560542) (xy 25.166693 -399.542921) (xy 25.212661 -399.513205)
			(xy 25.262405 -399.490365) (xy 25.314902 -399.47487) (xy 25.369076 -399.467038) (xy 25.396444 -399.466562)
			(xy 25.423695 -399.467037) (xy 25.477642 -399.474799) (xy 25.529935 -399.490158) (xy 25.57951 -399.512802)
			(xy 25.625359 -399.54227) (xy 25.666548 -399.577962) (xy 25.702239 -399.619152) (xy 25.731705 -399.665002)
			(xy 25.754347 -399.714579) (xy 25.769704 -399.766872) (xy 25.777464 -399.820819) (xy 25.777952 -399.84807)
			(xy 25.77748 -399.87544) (xy 25.769665 -399.929619) (xy 25.754178 -399.982123) (xy 25.731338 -400.03187)
			(xy 25.701613 -400.077837) (xy 25.683972 -400.098768) (xy 25.677876 -400.10588) (xy 25.671526 -400.122898)
			(xy 25.671526 -400.208242) (xy 25.677876 -400.22526) (xy 25.683972 -400.232372) (xy 25.701607 -400.253307)
			(xy 25.73132 -400.299279) (xy 25.754158 -400.349025) (xy 25.76965 -400.401526) (xy 25.777478 -400.455701)
			(xy 25.777952 -400.48307) (xy 25.777394 -400.510318) (xy 25.769643 -400.564261) (xy 25.754294 -400.616552)
			(xy 25.731659 -400.666126) (xy 25.725734 -400.675348) (xy 27.191462 -400.675348) (xy 27.191889 -400.64897)
			(xy 27.199135 -400.596713) (xy 27.21351 -400.545953) (xy 27.234739 -400.497656) (xy 27.262418 -400.452744)
			(xy 27.29602 -400.412072) (xy 27.31516 -400.393916) (xy 27.322678 -400.386475) (xy 27.33123 -400.367147)
			(xy 27.33167 -400.356578) (xy 27.33167 -400.281648) (xy 27.331059 -400.271115) (xy 27.322551 -400.251837)
			(xy 27.31516 -400.24431) (xy 27.295999 -400.226174) (xy 27.262389 -400.185504) (xy 27.234707 -400.140589)
			(xy 27.213481 -400.092288) (xy 27.199116 -400.041521) (xy 27.191887 -399.989258) (xy 27.191462 -399.962878)
			(xy 27.191948 -399.935627) (xy 27.199704 -399.881679) (xy 27.215059 -399.829384) (xy 27.237701 -399.779807)
			(xy 27.267167 -399.733957) (xy 27.302858 -399.692766) (xy 27.344049 -399.657075) (xy 27.389899 -399.627609)
			(xy 27.439476 -399.604967) (xy 27.491771 -399.589612) (xy 27.545719 -399.581856) (xy 27.600221 -399.581856)
			(xy 27.654169 -399.589612) (xy 27.706464 -399.604967) (xy 27.756041 -399.627609) (xy 27.801891 -399.657075)
			(xy 27.843082 -399.692766) (xy 27.878773 -399.733957) (xy 27.908239 -399.779807) (xy 27.930881 -399.829384)
			(xy 27.946236 -399.881679) (xy 27.953992 -399.935627) (xy 27.954478 -399.962878) (xy 27.954055 -399.989256)
			(xy 27.946806 -400.041512) (xy 27.93243 -400.092272) (xy 27.9112 -400.140569) (xy 27.883521 -400.185481)
			(xy 27.84992 -400.226153) (xy 27.83078 -400.24431) (xy 27.82331 -400.251783) (xy 27.814786 -400.271093)
			(xy 27.81427 -400.281648) (xy 27.81427 -400.356578) (xy 27.814855 -400.367114) (xy 27.82338 -400.386393)
			(xy 27.83078 -400.393916) (xy 27.849913 -400.412081) (xy 27.883524 -400.452745) (xy 27.911209 -400.497654)
			(xy 27.932439 -400.54595) (xy 27.946811 -400.596712) (xy 27.954048 -400.648969) (xy 27.954478 -400.675348)
			(xy 27.953992 -400.702599) (xy 27.946236 -400.756547) (xy 27.930881 -400.808842) (xy 27.908239 -400.858419)
			(xy 27.878773 -400.904269) (xy 27.843082 -400.94546) (xy 27.801891 -400.981151) (xy 27.756041 -401.010617)
			(xy 27.706464 -401.033259) (xy 27.654169 -401.048614) (xy 27.600221 -401.05637) (xy 27.545719 -401.05637)
			(xy 27.491771 -401.048614) (xy 27.439476 -401.033259) (xy 27.389899 -401.010617) (xy 27.344049 -400.981151)
			(xy 27.302858 -400.94546) (xy 27.267167 -400.904269) (xy 27.237701 -400.858419) (xy 27.215059 -400.808842)
			(xy 27.199704 -400.756547) (xy 27.191948 -400.702599) (xy 27.191462 -400.675348) (xy 25.725734 -400.675348)
			(xy 25.7022 -400.711974) (xy 25.666516 -400.753164) (xy 25.625334 -400.788856) (xy 25.579491 -400.818324)
			(xy 25.529921 -400.840968) (xy 25.477634 -400.856327) (xy 25.423692 -400.864089) (xy 25.396444 -400.864578)
			(xy 25.369074 -400.864092) (xy 25.314896 -400.856279) (xy 25.262393 -400.840795) (xy 25.212646 -400.817958)
			(xy 25.166678 -400.788237) (xy 25.145746 -400.770598) (xy 25.138634 -400.764502) (xy 25.121616 -400.758152)
			(xy 25.036272 -400.758152) (xy 25.019254 -400.764502) (xy 25.012142 -400.770598) (xy 24.991205 -400.788231)
			(xy 24.945233 -400.817943) (xy 24.895487 -400.840781) (xy 24.842988 -400.856273) (xy 24.788813 -400.864103)
			(xy 24.761444 -400.864578) (xy 24.731322 -400.863971) (xy 24.671828 -400.854498) (xy 24.614561 -400.835795)
			(xy 24.560943 -400.808327) (xy 24.512306 -400.772777) (xy 24.49068 -400.751802) (xy 24.483568 -400.744436)
			(xy 24.464772 -400.736816) (xy 24.372316 -400.736816) (xy 24.35352 -400.744436) (xy 24.346408 -400.751802)
			(xy 24.324803 -400.772804) (xy 24.276169 -400.808369) (xy 24.222547 -400.835845) (xy 24.165273 -400.854548)
			(xy 24.10577 -400.864013) (xy 24.075644 -400.864578) (xy 24.048391 -400.864104) (xy 23.994439 -400.856352)
			(xy 23.942139 -400.841) (xy 23.892557 -400.81836) (xy 23.846703 -400.788894) (xy 23.805509 -400.753201)
			(xy 23.769814 -400.712009) (xy 23.740346 -400.666155) (xy 23.717705 -400.616574) (xy 23.702351 -400.564275)
			(xy 23.694597 -400.510323) (xy 23.694136 -400.48307) (xy 7.460996 -400.48307) (xy 7.460996 -401.426243)
			(xy 19.533319 -401.426243) (xy 19.533319 -401.371737) (xy 19.541076 -401.317787) (xy 19.556432 -401.265489)
			(xy 19.579075 -401.21591) (xy 19.608543 -401.170057) (xy 19.644236 -401.128865) (xy 19.685428 -401.093171)
			(xy 19.731281 -401.063704) (xy 19.780861 -401.041062) (xy 19.833159 -401.025706) (xy 19.887109 -401.017949)
			(xy 19.914362 -401.017486) (xy 19.944485 -401.018071) (xy 20.003981 -401.027547) (xy 20.061249 -401.046254)
			(xy 20.114867 -401.073727) (xy 20.163501 -401.109284) (xy 20.185126 -401.130262) (xy 20.192238 -401.137628)
			(xy 20.211034 -401.145248) (xy 20.30349 -401.145248) (xy 20.322286 -401.137628) (xy 20.329398 -401.130262)
			(xy 20.351011 -401.109268) (xy 20.399642 -401.073699) (xy 20.453261 -401.046221) (xy 20.510534 -401.027516)
			(xy 20.570037 -401.018051) (xy 20.600162 -401.017486) (xy 20.627531 -401.017978) (xy 20.681709 -401.02579)
			(xy 20.734212 -401.041273) (xy 20.783959 -401.064109) (xy 20.829927 -401.093828) (xy 20.85086 -401.111466)
			(xy 20.857972 -401.117562) (xy 20.87499 -401.123912) (xy 20.960334 -401.123912) (xy 20.977352 -401.117562)
			(xy 20.984464 -401.111466) (xy 21.005394 -401.093825) (xy 21.051368 -401.064115) (xy 21.101116 -401.04128)
			(xy 21.153617 -401.025789) (xy 21.207793 -401.01796) (xy 21.235162 -401.017486) (xy 21.262416 -401.017959)
			(xy 21.31637 -401.025711) (xy 21.368672 -401.041064) (xy 21.418256 -401.063704) (xy 21.464113 -401.09317)
			(xy 21.50531 -401.128863) (xy 21.541007 -401.170056) (xy 21.570478 -401.215911) (xy 21.593123 -401.265492)
			(xy 21.608481 -401.317792) (xy 21.616239 -401.371746) (xy 21.616239 -401.426254) (xy 21.608481 -401.480208)
			(xy 21.593123 -401.532508) (xy 21.570478 -401.582089) (xy 21.541007 -401.627944) (xy 21.50531 -401.669137)
			(xy 21.464113 -401.70483) (xy 21.418256 -401.734296) (xy 21.368672 -401.756936) (xy 21.31637 -401.772289)
			(xy 21.262416 -401.780041) (xy 21.235162 -401.780502) (xy 21.207793 -401.779999) (xy 21.153616 -401.77219)
			(xy 21.101113 -401.75671) (xy 21.051365 -401.733876) (xy 21.005397 -401.704159) (xy 20.984464 -401.686522)
			(xy 20.977352 -401.680426) (xy 20.960334 -401.674076) (xy 20.87499 -401.674076) (xy 20.857972 -401.680426)
			(xy 20.85086 -401.686522) (xy 20.829919 -401.70415) (xy 20.783948 -401.733863) (xy 20.734203 -401.7567)
			(xy 20.681704 -401.772194) (xy 20.62753 -401.780026) (xy 20.600162 -401.780502) (xy 20.570039 -401.779906)
			(xy 20.510544 -401.770433) (xy 20.453275 -401.751729) (xy 20.399658 -401.724258) (xy 20.351023 -401.688703)
			(xy 20.329398 -401.667726) (xy 20.322286 -401.66036) (xy 20.30349 -401.65274) (xy 20.211034 -401.65274)
			(xy 20.192238 -401.66036) (xy 20.185126 -401.667726) (xy 20.1635 -401.688706) (xy 20.114873 -401.724277)
			(xy 20.061257 -401.751758) (xy 20.003986 -401.770466) (xy 19.944486 -401.779935) (xy 19.914362 -401.780502)
			(xy 19.887109 -401.780031) (xy 19.833159 -401.772274) (xy 19.780861 -401.756918) (xy 19.731281 -401.734276)
			(xy 19.685428 -401.704809) (xy 19.644236 -401.669115) (xy 19.608543 -401.627923) (xy 19.579075 -401.58207)
			(xy 19.556432 -401.532491) (xy 19.541076 -401.480193) (xy 19.533319 -401.426243) (xy 7.460996 -401.426243)
			(xy 7.460996 -402.56079) (xy 11.742672 -402.56079) (xy 11.746743 -402.505168) (xy 11.758869 -402.450731)
			(xy 11.778792 -402.39864) (xy 11.806088 -402.350005) (xy 11.840174 -402.305862) (xy 11.880323 -402.267153)
			(xy 11.925681 -402.234702) (xy 11.975281 -402.209201) (xy 12.028065 -402.191194) (xy 12.082908 -402.181064)
			(xy 12.138642 -402.179027) (xy 12.194079 -402.185127) (xy 12.248036 -402.199233) (xy 12.299365 -402.221045)
			(xy 12.346971 -402.250099) (xy 12.389839 -402.285774) (xy 12.427056 -402.327311) (xy 12.457829 -402.373824)
			(xy 12.481501 -402.424321) (xy 12.497569 -402.477728) (xy 12.505689 -402.532904) (xy 12.506198 -402.56079)
			(xy 12.505689 -402.588676) (xy 12.497569 -402.643852) (xy 12.481501 -402.697259) (xy 12.457829 -402.747756)
			(xy 12.427056 -402.794269) (xy 12.389839 -402.835806) (xy 12.346971 -402.871481) (xy 12.299365 -402.900535)
			(xy 12.248036 -402.922347) (xy 12.194079 -402.936453) (xy 12.138642 -402.942553) (xy 12.082908 -402.940516)
			(xy 12.028065 -402.930386) (xy 11.975281 -402.912379) (xy 11.925681 -402.886878) (xy 11.880323 -402.854427)
			(xy 11.840174 -402.815718) (xy 11.806088 -402.771575) (xy 11.778792 -402.72294) (xy 11.758869 -402.670849)
			(xy 11.746743 -402.616412) (xy 11.742672 -402.56079) (xy 7.460996 -402.56079) (xy 7.460996 -402.720556)
			(xy 7.461435 -402.730588) (xy 7.469009 -402.749163) (xy 7.475728 -402.756624) (xy 7.939278 -403.220174)
			(xy 14.510764 -403.220174) (xy 14.514835 -403.164552) (xy 14.526961 -403.110115) (xy 14.546884 -403.058024)
			(xy 14.57418 -403.009389) (xy 14.608266 -402.965246) (xy 14.648415 -402.926537) (xy 14.693773 -402.894086)
			(xy 14.743373 -402.868585) (xy 14.796157 -402.850578) (xy 14.851 -402.840448) (xy 14.906734 -402.838411)
			(xy 14.962171 -402.844511) (xy 15.016128 -402.858617) (xy 15.067457 -402.880429) (xy 15.115063 -402.909483)
			(xy 15.157931 -402.945158) (xy 15.195148 -402.986695) (xy 15.225921 -403.033208) (xy 15.249593 -403.083705)
			(xy 15.265661 -403.137112) (xy 15.273781 -403.192288) (xy 15.27429 -403.220174) (xy 15.780764 -403.220174)
			(xy 15.784835 -403.164552) (xy 15.796961 -403.110115) (xy 15.816884 -403.058024) (xy 15.84418 -403.009389)
			(xy 15.878266 -402.965246) (xy 15.918415 -402.926537) (xy 15.963773 -402.894086) (xy 16.013373 -402.868585)
			(xy 16.066157 -402.850578) (xy 16.121 -402.840448) (xy 16.176734 -402.838411) (xy 16.232171 -402.844511)
			(xy 16.286128 -402.858617) (xy 16.337457 -402.880429) (xy 16.385063 -402.909483) (xy 16.427931 -402.945158)
			(xy 16.465148 -402.986695) (xy 16.495921 -403.033208) (xy 16.519593 -403.083705) (xy 16.535661 -403.137112)
			(xy 16.543781 -403.192288) (xy 16.54429 -403.220174) (xy 16.543781 -403.24806) (xy 16.535661 -403.303236)
			(xy 16.528937 -403.325584) (xy 16.923764 -403.325584) (xy 16.927835 -403.269962) (xy 16.939961 -403.215525)
			(xy 16.959884 -403.163434) (xy 16.98718 -403.114799) (xy 17.021266 -403.070656) (xy 17.061415 -403.031947)
			(xy 17.106773 -402.999496) (xy 17.156373 -402.973995) (xy 17.209157 -402.955988) (xy 17.264 -402.945858)
			(xy 17.319734 -402.943821) (xy 17.375171 -402.949921) (xy 17.429128 -402.964027) (xy 17.480457 -402.985839)
			(xy 17.528063 -403.014893) (xy 17.570931 -403.050568) (xy 17.608148 -403.092105) (xy 17.638921 -403.138618)
			(xy 17.662593 -403.189115) (xy 17.663073 -403.19071) (xy 18.073622 -403.19071) (xy 18.077693 -403.135088)
			(xy 18.089819 -403.080651) (xy 18.109742 -403.02856) (xy 18.137038 -402.979925) (xy 18.171124 -402.935782)
			(xy 18.211273 -402.897073) (xy 18.256631 -402.864622) (xy 18.306231 -402.839121) (xy 18.359015 -402.821114)
			(xy 18.413858 -402.810984) (xy 18.469592 -402.808947) (xy 18.525029 -402.815047) (xy 18.578986 -402.829153)
			(xy 18.630315 -402.850965) (xy 18.677921 -402.880019) (xy 18.720789 -402.915694) (xy 18.758006 -402.957231)
			(xy 18.788779 -403.003744) (xy 18.812451 -403.054241) (xy 18.828519 -403.107648) (xy 18.836639 -403.162824)
			(xy 18.837148 -403.19071) (xy 18.836639 -403.218596) (xy 18.828519 -403.273772) (xy 18.812451 -403.327179)
			(xy 18.788779 -403.377676) (xy 18.758006 -403.424189) (xy 18.720789 -403.465726) (xy 18.677921 -403.501401)
			(xy 18.630315 -403.530455) (xy 18.578986 -403.552267) (xy 18.525029 -403.566373) (xy 18.469592 -403.572473)
			(xy 18.413858 -403.570436) (xy 18.359015 -403.560306) (xy 18.306231 -403.542299) (xy 18.256631 -403.516798)
			(xy 18.211273 -403.484347) (xy 18.171124 -403.445638) (xy 18.137038 -403.401495) (xy 18.109742 -403.35286)
			(xy 18.089819 -403.300769) (xy 18.077693 -403.246332) (xy 18.073622 -403.19071) (xy 17.663073 -403.19071)
			(xy 17.678661 -403.242522) (xy 17.686781 -403.297698) (xy 17.68729 -403.325584) (xy 17.686781 -403.35347)
			(xy 17.678661 -403.408646) (xy 17.662593 -403.462053) (xy 17.638921 -403.51255) (xy 17.608148 -403.559063)
			(xy 17.570931 -403.6006) (xy 17.528063 -403.636275) (xy 17.480457 -403.665329) (xy 17.429128 -403.687141)
			(xy 17.375171 -403.701247) (xy 17.319734 -403.707347) (xy 17.264 -403.70531) (xy 17.209157 -403.69518)
			(xy 17.156373 -403.677173) (xy 17.106773 -403.651672) (xy 17.061415 -403.619221) (xy 17.021266 -403.580512)
			(xy 16.98718 -403.536369) (xy 16.959884 -403.487734) (xy 16.939961 -403.435643) (xy 16.927835 -403.381206)
			(xy 16.923764 -403.325584) (xy 16.528937 -403.325584) (xy 16.519593 -403.356643) (xy 16.495921 -403.40714)
			(xy 16.465148 -403.453653) (xy 16.427931 -403.49519) (xy 16.385063 -403.530865) (xy 16.337457 -403.559919)
			(xy 16.286128 -403.581731) (xy 16.232171 -403.595837) (xy 16.176734 -403.601937) (xy 16.121 -403.5999)
			(xy 16.066157 -403.58977) (xy 16.013373 -403.571763) (xy 15.963773 -403.546262) (xy 15.918415 -403.513811)
			(xy 15.878266 -403.475102) (xy 15.84418 -403.430959) (xy 15.816884 -403.382324) (xy 15.796961 -403.330233)
			(xy 15.784835 -403.275796) (xy 15.780764 -403.220174) (xy 15.27429 -403.220174) (xy 15.273781 -403.24806)
			(xy 15.265661 -403.303236) (xy 15.249593 -403.356643) (xy 15.225921 -403.40714) (xy 15.195148 -403.453653)
			(xy 15.157931 -403.49519) (xy 15.115063 -403.530865) (xy 15.067457 -403.559919) (xy 15.016128 -403.581731)
			(xy 14.962171 -403.595837) (xy 14.906734 -403.601937) (xy 14.851 -403.5999) (xy 14.796157 -403.58977)
			(xy 14.743373 -403.571763) (xy 14.693773 -403.546262) (xy 14.648415 -403.513811) (xy 14.608266 -403.475102)
			(xy 14.57418 -403.430959) (xy 14.546884 -403.382324) (xy 14.526961 -403.330233) (xy 14.514835 -403.275796)
			(xy 14.510764 -403.220174) (xy 7.939278 -403.220174) (xy 8.935974 -404.21687) (xy 9.284714 -404.21687)
			(xy 9.288785 -404.161248) (xy 9.300911 -404.106811) (xy 9.320834 -404.05472) (xy 9.34813 -404.006085)
			(xy 9.382216 -403.961942) (xy 9.422365 -403.923233) (xy 9.467723 -403.890782) (xy 9.517323 -403.865281)
			(xy 9.570107 -403.847274) (xy 9.62495 -403.837144) (xy 9.680684 -403.835107) (xy 9.736121 -403.841207)
			(xy 9.789546 -403.855174) (xy 11.803124 -403.855174) (xy 11.807195 -403.799552) (xy 11.819321 -403.745115)
			(xy 11.839244 -403.693024) (xy 11.86654 -403.644389) (xy 11.900626 -403.600246) (xy 11.940775 -403.561537)
			(xy 11.986133 -403.529086) (xy 12.035733 -403.503585) (xy 12.088517 -403.485578) (xy 12.14336 -403.475448)
			(xy 12.199094 -403.473411) (xy 12.254531 -403.479511) (xy 12.308488 -403.493617) (xy 12.359817 -403.515429)
			(xy 12.407423 -403.544483) (xy 12.450291 -403.580158) (xy 12.487508 -403.621695) (xy 12.518281 -403.668208)
			(xy 12.541953 -403.718705) (xy 12.558021 -403.772112) (xy 12.566141 -403.827288) (xy 12.56665 -403.855174)
			(xy 12.566141 -403.88306) (xy 12.558021 -403.938236) (xy 12.541953 -403.991643) (xy 12.518281 -404.04214)
			(xy 12.487508 -404.088653) (xy 12.450291 -404.13019) (xy 12.407423 -404.165865) (xy 12.359817 -404.194919)
			(xy 12.308488 -404.216731) (xy 12.254531 -404.230837) (xy 12.199094 -404.236937) (xy 12.14336 -404.2349)
			(xy 12.088517 -404.22477) (xy 12.035733 -404.206763) (xy 11.986133 -404.181262) (xy 11.940775 -404.148811)
			(xy 11.900626 -404.110102) (xy 11.86654 -404.065959) (xy 11.839244 -404.017324) (xy 11.819321 -403.965233)
			(xy 11.807195 -403.910796) (xy 11.803124 -403.855174) (xy 9.789546 -403.855174) (xy 9.790078 -403.855313)
			(xy 9.841407 -403.877125) (xy 9.889013 -403.906179) (xy 9.931881 -403.941854) (xy 9.969098 -403.983391)
			(xy 9.999871 -404.029904) (xy 10.023543 -404.080401) (xy 10.039611 -404.133808) (xy 10.047731 -404.188984)
			(xy 10.04824 -404.21687) (xy 10.047731 -404.244756) (xy 10.039611 -404.299932) (xy 10.023543 -404.353339)
			(xy 9.999871 -404.403836) (xy 9.969098 -404.450349) (xy 9.931881 -404.491886) (xy 9.889013 -404.527561)
			(xy 9.841407 -404.556615) (xy 9.790078 -404.578427) (xy 9.736121 -404.592533) (xy 9.680684 -404.598633)
			(xy 9.62495 -404.596596) (xy 9.570107 -404.586466) (xy 9.517323 -404.568459) (xy 9.467723 -404.542958)
			(xy 9.422365 -404.510507) (xy 9.382216 -404.471798) (xy 9.34813 -404.427655) (xy 9.320834 -404.37902)
			(xy 9.300911 -404.326929) (xy 9.288785 -404.272492) (xy 9.284714 -404.21687) (xy 8.935974 -404.21687)
			(xy 9.408414 -404.68931) (xy 20.193506 -404.68931) (xy 20.197577 -404.633688) (xy 20.209703 -404.579251)
			(xy 20.229626 -404.52716) (xy 20.256922 -404.478525) (xy 20.291008 -404.434382) (xy 20.331157 -404.395673)
			(xy 20.376515 -404.363222) (xy 20.426115 -404.337721) (xy 20.478899 -404.319714) (xy 20.533742 -404.309584)
			(xy 20.589476 -404.307547) (xy 20.644913 -404.313647) (xy 20.69887 -404.327753) (xy 20.750199 -404.349565)
			(xy 20.797805 -404.378619) (xy 20.840673 -404.414294) (xy 20.87789 -404.455831) (xy 20.908663 -404.502344)
			(xy 20.932335 -404.552841) (xy 20.948403 -404.606248) (xy 20.956523 -404.661424) (xy 20.957032 -404.68931)
			(xy 20.956523 -404.717196) (xy 20.948403 -404.772372) (xy 20.932335 -404.825779) (xy 20.908663 -404.876276)
			(xy 20.87789 -404.922789) (xy 20.840673 -404.964326) (xy 20.797805 -405.000001) (xy 20.750199 -405.029055)
			(xy 20.69887 -405.050867) (xy 20.644913 -405.064973) (xy 20.589476 -405.071073) (xy 20.533742 -405.069036)
			(xy 20.478899 -405.058906) (xy 20.426115 -405.040899) (xy 20.376515 -405.015398) (xy 20.331157 -404.982947)
			(xy 20.291008 -404.944238) (xy 20.256922 -404.900095) (xy 20.229626 -404.85146) (xy 20.209703 -404.799369)
			(xy 20.197577 -404.744932) (xy 20.193506 -404.68931) (xy 9.408414 -404.68931) (xy 10.653855 -405.934751)
			(xy 14.302972 -405.934751) (xy 14.302972 -405.880249) (xy 14.310728 -405.826301) (xy 14.326083 -405.774005)
			(xy 14.348724 -405.724428) (xy 14.378191 -405.678577) (xy 14.413882 -405.637386) (xy 14.455072 -405.601694)
			(xy 14.500923 -405.572227) (xy 14.5505 -405.549585) (xy 14.602795 -405.53423) (xy 14.656743 -405.526472)
			(xy 14.683994 -405.525986) (xy 14.713337 -405.526528) (xy 14.771331 -405.535514) (xy 14.827264 -405.553275)
			(xy 14.879819 -405.579391) (xy 14.927754 -405.613248) (xy 14.969939 -405.654045) (xy 15.005379 -405.700822)
			(xy 15.019782 -405.726392) (xy 15.027447 -405.739632) (xy 15.049269 -405.76106) (xy 15.076451 -405.775076)
			(xy 15.106563 -405.780428) (xy 15.136911 -405.776636) (xy 15.16478 -405.764039) (xy 15.187677 -405.743765)
			(xy 15.196058 -405.730964) (xy 15.21095 -405.707329) (xy 15.2466 -405.66432) (xy 15.288146 -405.626974)
			(xy 15.334697 -405.596092) (xy 15.385257 -405.572334) (xy 15.438742 -405.556209) (xy 15.494008 -405.548062)
			(xy 15.52194 -405.547576) (xy 15.549192 -405.548054) (xy 15.60314 -405.55581) (xy 15.655435 -405.571166)
			(xy 15.705013 -405.593807) (xy 15.750864 -405.623274) (xy 15.792054 -405.658966) (xy 15.827746 -405.700156)
			(xy 15.857213 -405.746007) (xy 15.879854 -405.795585) (xy 15.89521 -405.84788) (xy 15.902966 -405.901828)
			(xy 15.902966 -405.956332) (xy 15.89521 -406.01028) (xy 15.892127 -406.020778) (xy 22.643338 -406.020778)
			(xy 22.64375 -405.995078) (xy 22.65065 -405.944142) (xy 22.664322 -405.894593) (xy 22.684518 -405.847326)
			(xy 22.710874 -405.803197) (xy 22.742913 -405.763003) (xy 22.761194 -405.744934) (xy 22.768814 -405.737822)
			(xy 22.776688 -405.71928) (xy 22.777704 -405.625554) (xy 22.770084 -405.607012) (xy 22.762464 -405.599646)
			(xy 22.741488 -405.578031) (xy 22.705977 -405.529382) (xy 22.678555 -405.475756) (xy 22.659903 -405.418487)
			(xy 22.650485 -405.358998) (xy 22.649942 -405.328882) (xy 22.650387 -405.301511) (xy 22.658209 -405.247331)
			(xy 22.673702 -405.194827) (xy 22.696549 -405.14508) (xy 22.726278 -405.099115) (xy 22.743922 -405.078184)
			(xy 22.750018 -405.071072) (xy 22.756368 -405.054054) (xy 22.756368 -404.96871) (xy 22.750018 -404.951692)
			(xy 22.743922 -404.94458) (xy 22.726264 -404.923661) (xy 22.69654 -404.877691) (xy 22.673696 -404.827942)
			(xy 22.658202 -404.775438) (xy 22.650375 -404.721258) (xy 22.650377 -404.666515) (xy 22.658207 -404.612335)
			(xy 22.673706 -404.559832) (xy 22.696553 -404.510085) (xy 22.72628 -404.464117) (xy 22.743922 -404.443184)
			(xy 22.750018 -404.436072) (xy 22.756368 -404.419054) (xy 22.756368 -404.33371) (xy 22.750018 -404.316692)
			(xy 22.743922 -404.30958) (xy 22.72631 -404.288626) (xy 22.696594 -404.242659) (xy 22.673752 -404.192918)
			(xy 22.658255 -404.140422) (xy 22.65042 -404.08625) (xy 22.649942 -404.058882) (xy 22.650428 -404.031631)
			(xy 22.658184 -403.977683) (xy 22.673539 -403.925388) (xy 22.696181 -403.875811) (xy 22.725647 -403.829961)
			(xy 22.761338 -403.78877) (xy 22.802529 -403.753079) (xy 22.848379 -403.723613) (xy 22.897956 -403.700971)
			(xy 22.950251 -403.685616) (xy 23.004199 -403.67786) (xy 23.058701 -403.67786) (xy 23.112649 -403.685616)
			(xy 23.164944 -403.700971) (xy 23.214521 -403.723613) (xy 23.260371 -403.753079) (xy 23.301562 -403.78877)
			(xy 23.337253 -403.829961) (xy 23.366719 -403.875811) (xy 23.389361 -403.925388) (xy 23.404716 -403.977683)
			(xy 23.412472 -404.031631) (xy 23.412958 -404.058882) (xy 23.412492 -404.086252) (xy 23.404675 -404.140432)
			(xy 23.389187 -404.192935) (xy 23.366345 -404.242682) (xy 23.33662 -404.288649) (xy 23.318978 -404.30958)
			(xy 23.312882 -404.316692) (xy 23.306532 -404.33371) (xy 23.306532 -404.419054) (xy 23.312882 -404.436072)
			(xy 23.318978 -404.443184) (xy 23.323804 -404.448772) (xy 23.330662 -404.4569) (xy 23.34895 -404.466298)
			(xy 23.443692 -404.472394) (xy 23.462996 -404.465282) (xy 23.470616 -404.45817) (xy 23.491895 -404.439221)
			(xy 23.539032 -404.407212) (xy 23.590401 -404.382562) (xy 23.644862 -404.365818) (xy 23.701207 -404.357351)
			(xy 23.729696 -404.356824) (xy 23.759819 -404.357405) (xy 23.819314 -404.366885) (xy 23.876582 -404.385593)
			(xy 23.930199 -404.413067) (xy 23.978834 -404.448623) (xy 24.00046 -404.4696) (xy 24.007572 -404.476966)
			(xy 24.026368 -404.484586) (xy 24.118824 -404.484586) (xy 24.13762 -404.476966) (xy 24.144732 -404.4696)
			(xy 24.166364 -404.448627) (xy 24.214991 -404.413058) (xy 24.268605 -404.385577) (xy 24.325874 -404.366867)
			(xy 24.385372 -404.357393) (xy 24.415496 -404.356824) (xy 24.441793 -404.357286) (xy 24.493889 -404.364503)
			(xy 24.544499 -404.378814) (xy 24.59266 -404.399948) (xy 24.637458 -404.427503) (xy 24.678041 -404.460956)
			(xy 24.696166 -404.480014) (xy 24.703278 -404.487634) (xy 24.721566 -404.496016) (xy 24.814022 -404.499318)
			(xy 24.833072 -404.49246) (xy 24.840438 -404.485348) (xy 24.861768 -404.466081) (xy 24.909129 -404.433514)
			(xy 24.96084 -404.40842) (xy 25.01573 -404.391369) (xy 25.072557 -404.382745) (xy 25.101296 -404.382224)
			(xy 25.131419 -404.382805) (xy 25.190914 -404.392285) (xy 25.248182 -404.410993) (xy 25.301799 -404.438467)
			(xy 25.350434 -404.474023) (xy 25.37206 -404.495) (xy 25.379172 -404.502366) (xy 25.397968 -404.509986)
			(xy 25.490424 -404.509986) (xy 25.50922 -404.502366) (xy 25.516332 -404.495) (xy 25.537964 -404.474027)
			(xy 25.586591 -404.438458) (xy 25.640205 -404.410977) (xy 25.697474 -404.392267) (xy 25.756972 -404.382793)
			(xy 25.787096 -404.382224) (xy 25.81435 -404.382659) (xy 25.868304 -404.390416) (xy 25.920604 -404.405774)
			(xy 25.970186 -404.428418) (xy 26.016041 -404.457888) (xy 26.057235 -404.493585) (xy 26.092928 -404.534781)
			(xy 26.122396 -404.580638) (xy 26.145036 -404.630222) (xy 26.16039 -404.682524) (xy 26.168143 -404.736478)
			(xy 26.168604 -404.763732) (xy 26.168156 -404.791103) (xy 26.160333 -404.845283) (xy 26.14484 -404.897786)
			(xy 26.121995 -404.947532) (xy 26.092267 -404.993499) (xy 26.074624 -405.01443) (xy 26.068528 -405.021542)
			(xy 26.062178 -405.03856) (xy 26.062178 -405.123904) (xy 26.068528 -405.140922) (xy 26.074624 -405.148034)
			(xy 26.092249 -405.168977) (xy 26.121962 -405.214947) (xy 26.144801 -405.264692) (xy 26.160295 -405.31719)
			(xy 26.168127 -405.371364) (xy 26.168604 -405.398732) (xy 26.168145 -405.425093) (xy 26.160898 -405.477315)
			(xy 26.146532 -405.528043) (xy 26.125321 -405.57631) (xy 26.097669 -405.621199) (xy 26.081228 -405.64181)
			(xy 26.075132 -405.649176) (xy 26.06929 -405.666702) (xy 26.0731 -405.754078) (xy 26.080466 -405.771096)
			(xy 26.087324 -405.777954) (xy 26.107808 -405.799505) (xy 26.142506 -405.847786) (xy 26.169292 -405.900866)
			(xy 26.187517 -405.95746) (xy 26.196739 -406.016196) (xy 26.197306 -406.045924) (xy 26.196845 -406.073176)
			(xy 26.189085 -406.127125) (xy 26.173726 -406.17942) (xy 26.151082 -406.228997) (xy 26.121613 -406.274848)
			(xy 26.085919 -406.316038) (xy 26.044727 -406.351729) (xy 25.998875 -406.381195) (xy 25.949296 -406.403836)
			(xy 25.896999 -406.41919) (xy 25.84305 -406.426946) (xy 25.815798 -406.427432) (xy 25.785674 -406.426868)
			(xy 25.726177 -406.417386) (xy 25.668909 -406.398674) (xy 25.615292 -406.371196) (xy 25.566658 -406.335636)
			(xy 25.545034 -406.314656) (xy 25.537922 -406.30729) (xy 25.519126 -406.29967) (xy 25.42667 -406.29967)
			(xy 25.407874 -406.30729) (xy 25.400762 -406.314656) (xy 25.379126 -406.335624) (xy 25.330501 -406.371196)
			(xy 25.276887 -406.398679) (xy 25.219619 -406.41739) (xy 25.160122 -406.426863) (xy 25.129998 -406.427432)
			(xy 25.1037 -406.426988) (xy 25.051602 -406.419769) (xy 25.000992 -406.405455) (xy 24.952831 -406.384318)
			(xy 24.908034 -406.356759) (xy 24.867451 -406.323303) (xy 24.849328 -406.304242) (xy 24.842216 -406.296622)
			(xy 24.823928 -406.28824) (xy 24.731472 -406.284938) (xy 24.712422 -406.291796) (xy 24.705056 -406.298908)
			(xy 24.683722 -406.31817) (xy 24.636363 -406.35074) (xy 24.584653 -406.375835) (xy 24.529763 -406.392887)
			(xy 24.472937 -406.401511) (xy 24.444198 -406.402032) (xy 24.414074 -406.401468) (xy 24.354577 -406.391986)
			(xy 24.297309 -406.373274) (xy 24.243692 -406.345796) (xy 24.195058 -406.310236) (xy 24.173434 -406.289256)
			(xy 24.166322 -406.28189) (xy 24.147526 -406.27427) (xy 24.05507 -406.27427) (xy 24.036274 -406.28189)
			(xy 24.029162 -406.289256) (xy 24.007526 -406.310224) (xy 23.958901 -406.345796) (xy 23.905287 -406.373279)
			(xy 23.848019 -406.39199) (xy 23.788522 -406.401463) (xy 23.758398 -406.402032) (xy 23.730987 -406.401592)
			(xy 23.676728 -406.393743) (xy 23.624152 -406.378209) (xy 23.574342 -406.355307) (xy 23.528323 -406.325511)
			(xy 23.487043 -406.289434) (xy 23.468838 -406.268936) (xy 23.461472 -406.260554) (xy 23.441406 -406.251156)
			(xy 23.342092 -406.251156) (xy 23.321772 -406.260554) (xy 23.31466 -406.268936) (xy 23.296441 -406.28946)
			(xy 23.255134 -406.325592) (xy 23.209079 -406.355436) (xy 23.159225 -406.378377) (xy 23.106598 -406.393941)
			(xy 23.052286 -406.401807) (xy 23.024846 -406.402286) (xy 22.997593 -406.401802) (xy 22.943642 -406.394051)
			(xy 22.891343 -406.378699) (xy 22.841762 -406.35606) (xy 22.795907 -406.326595) (xy 22.754714 -406.290903)
			(xy 22.719019 -406.249712) (xy 22.689551 -406.203859) (xy 22.666909 -406.154279) (xy 22.651555 -406.101982)
			(xy 22.6438 -406.048031) (xy 22.643338 -406.020778) (xy 15.892127 -406.020778) (xy 15.879854 -406.062575)
			(xy 15.857213 -406.112153) (xy 15.827746 -406.158004) (xy 15.792054 -406.199194) (xy 15.750864 -406.234886)
			(xy 15.705013 -406.264353) (xy 15.655435 -406.286994) (xy 15.60314 -406.30235) (xy 15.549192 -406.310106)
			(xy 15.52194 -406.310592) (xy 15.492597 -406.310034) (xy 15.434604 -406.301053) (xy 15.37867 -406.283296)
			(xy 15.326115 -406.257182) (xy 15.27818 -406.223328) (xy 15.235995 -406.182531) (xy 15.200555 -406.135756)
			(xy 15.186152 -406.110186) (xy 15.178439 -406.096978) (xy 15.156625 -406.075557) (xy 15.129453 -406.061544)
			(xy 15.099353 -406.05619) (xy 15.069016 -406.059975) (xy 15.041153 -406.07256) (xy 15.018258 -406.09282)
			(xy 15.009876 -406.105614) (xy 14.994953 -406.129229) (xy 14.959309 -406.172239) (xy 14.917769 -406.209586)
			(xy 14.871223 -406.240472) (xy 14.820668 -406.264233) (xy 14.767187 -406.280362) (xy 14.711924 -406.288514)
			(xy 14.683994 -406.289002) (xy 14.656743 -406.288528) (xy 14.602795 -406.28077) (xy 14.5505 -406.265415)
			(xy 14.500923 -406.242773) (xy 14.455072 -406.213306) (xy 14.413882 -406.177614) (xy 14.378191 -406.136423)
			(xy 14.348724 -406.090572) (xy 14.326083 -406.040995) (xy 14.310728 -405.988699) (xy 14.302972 -405.934751)
			(xy 10.653855 -405.934751) (xy 11.346688 -406.627584) (xy 11.716764 -406.627584) (xy 11.720835 -406.571962)
			(xy 11.732961 -406.517525) (xy 11.752884 -406.465434) (xy 11.78018 -406.416799) (xy 11.814266 -406.372656)
			(xy 11.854415 -406.333947) (xy 11.899773 -406.301496) (xy 11.949373 -406.275995) (xy 12.002157 -406.257988)
			(xy 12.057 -406.247858) (xy 12.112734 -406.245821) (xy 12.168171 -406.251921) (xy 12.222128 -406.266027)
			(xy 12.273457 -406.287839) (xy 12.321063 -406.316893) (xy 12.363931 -406.352568) (xy 12.401148 -406.394105)
			(xy 12.431921 -406.440618) (xy 12.455593 -406.491115) (xy 12.471661 -406.544522) (xy 12.479781 -406.599698)
			(xy 12.48029 -406.627584) (xy 12.479781 -406.65547) (xy 12.471661 -406.710646) (xy 12.455593 -406.764053)
			(xy 12.431921 -406.81455) (xy 12.401148 -406.861063) (xy 12.363931 -406.9026) (xy 12.321063 -406.938275)
			(xy 12.273457 -406.967329) (xy 12.222128 -406.989141) (xy 12.168171 -407.003247) (xy 12.112734 -407.009347)
			(xy 12.057 -407.00731) (xy 12.002157 -406.99718) (xy 11.949373 -406.979173) (xy 11.899773 -406.953672)
			(xy 11.854415 -406.921221) (xy 11.814266 -406.882512) (xy 11.78018 -406.838369) (xy 11.752884 -406.789734)
			(xy 11.732961 -406.737643) (xy 11.720835 -406.683206) (xy 11.716764 -406.627584) (xy 11.346688 -406.627584)
			(xy 12.227814 -407.50871) (xy 18.001232 -407.50871) (xy 18.005303 -407.453088) (xy 18.017429 -407.398651)
			(xy 18.037352 -407.34656) (xy 18.064648 -407.297925) (xy 18.098734 -407.253782) (xy 18.138883 -407.215073)
			(xy 18.184241 -407.182622) (xy 18.233841 -407.157121) (xy 18.286625 -407.139114) (xy 18.341468 -407.128984)
			(xy 18.397202 -407.126947) (xy 18.452639 -407.133047) (xy 18.506596 -407.147153) (xy 18.557925 -407.168965)
			(xy 18.605531 -407.198019) (xy 18.648399 -407.233694) (xy 18.685616 -407.275231) (xy 18.716389 -407.321744)
			(xy 18.740061 -407.372241) (xy 18.756129 -407.425648) (xy 18.764249 -407.480824) (xy 18.764758 -407.50871)
			(xy 18.764249 -407.536596) (xy 18.756129 -407.591772) (xy 18.740061 -407.645179) (xy 18.716389 -407.695676)
			(xy 18.685616 -407.742189) (xy 18.648399 -407.783726) (xy 18.605531 -407.819401) (xy 18.557925 -407.848455)
			(xy 18.506596 -407.870267) (xy 18.452639 -407.884373) (xy 18.397202 -407.890473) (xy 18.341468 -407.888436)
			(xy 18.286625 -407.878306) (xy 18.233841 -407.860299) (xy 18.184241 -407.834798) (xy 18.138883 -407.802347)
			(xy 18.098734 -407.763638) (xy 18.064648 -407.719495) (xy 18.037352 -407.67086) (xy 18.017429 -407.618769)
			(xy 18.005303 -407.564332) (xy 18.001232 -407.50871) (xy 12.227814 -407.50871) (xy 12.99845 -408.279346)
			(xy 13.01824 -408.299949) (xy 13.051798 -408.346177) (xy 13.077721 -408.397082) (xy 13.09537 -408.451411)
			(xy 13.104313 -408.507832) (xy 13.104511 -408.517852) (xy 32.401762 -408.517852) (xy 32.405833 -408.46223)
			(xy 32.417959 -408.407793) (xy 32.437882 -408.355702) (xy 32.465178 -408.307067) (xy 32.499264 -408.262924)
			(xy 32.539413 -408.224215) (xy 32.584771 -408.191764) (xy 32.634371 -408.166263) (xy 32.687155 -408.148256)
			(xy 32.741998 -408.138126) (xy 32.797732 -408.136089) (xy 32.853169 -408.142189) (xy 32.907126 -408.156295)
			(xy 32.958455 -408.178107) (xy 33.006061 -408.207161) (xy 33.048929 -408.242836) (xy 33.086146 -408.284373)
			(xy 33.116919 -408.330886) (xy 33.140591 -408.381383) (xy 33.156659 -408.43479) (xy 33.164779 -408.489966)
			(xy 33.165288 -408.517852) (xy 33.164779 -408.545738) (xy 33.156659 -408.600914) (xy 33.140591 -408.654321)
			(xy 33.116919 -408.704818) (xy 33.086146 -408.751331) (xy 33.048929 -408.792868) (xy 33.006061 -408.828543)
			(xy 32.958455 -408.857597) (xy 32.907126 -408.879409) (xy 32.853169 -408.893515) (xy 32.797732 -408.899615)
			(xy 32.741998 -408.897578) (xy 32.687155 -408.887448) (xy 32.634371 -408.869441) (xy 32.584771 -408.84394)
			(xy 32.539413 -408.811489) (xy 32.499264 -408.77278) (xy 32.465178 -408.728637) (xy 32.437882 -408.680002)
			(xy 32.417959 -408.627911) (xy 32.405833 -408.573474) (xy 32.401762 -408.517852) (xy 13.104511 -408.517852)
			(xy 13.104876 -408.536394) (xy 13.104876 -409.167584) (xy 18.447764 -409.167584) (xy 18.451835 -409.111962)
			(xy 18.463961 -409.057525) (xy 18.483884 -409.005434) (xy 18.51118 -408.956799) (xy 18.545266 -408.912656)
			(xy 18.585415 -408.873947) (xy 18.630773 -408.841496) (xy 18.680373 -408.815995) (xy 18.733157 -408.797988)
			(xy 18.788 -408.787858) (xy 18.843734 -408.785821) (xy 18.899171 -408.791921) (xy 18.953128 -408.806027)
			(xy 19.004457 -408.827839) (xy 19.052063 -408.856893) (xy 19.094931 -408.892568) (xy 19.132148 -408.934105)
			(xy 19.162921 -408.980618) (xy 19.186593 -409.031115) (xy 19.202661 -409.084522) (xy 19.210781 -409.139698)
			(xy 19.21129 -409.167584) (xy 19.210781 -409.19547) (xy 19.202661 -409.250646) (xy 19.186593 -409.304053)
			(xy 19.162921 -409.35455) (xy 19.132148 -409.401063) (xy 19.113761 -409.421584) (xy 21.165564 -409.421584)
			(xy 21.169635 -409.365962) (xy 21.181761 -409.311525) (xy 21.201684 -409.259434) (xy 21.22898 -409.210799)
			(xy 21.263066 -409.166656) (xy 21.303215 -409.127947) (xy 21.348573 -409.095496) (xy 21.398173 -409.069995)
			(xy 21.450957 -409.051988) (xy 21.5058 -409.041858) (xy 21.561534 -409.039821) (xy 21.616971 -409.045921)
			(xy 21.670928 -409.060027) (xy 21.722257 -409.081839) (xy 21.769863 -409.110893) (xy 21.812731 -409.146568)
			(xy 21.849948 -409.188105) (xy 21.880721 -409.234618) (xy 21.904393 -409.285115) (xy 21.920461 -409.338522)
			(xy 21.928581 -409.393698) (xy 21.92909 -409.421584) (xy 21.928581 -409.44947) (xy 21.920461 -409.504646)
			(xy 21.904393 -409.558053) (xy 21.880721 -409.60855) (xy 21.849948 -409.655063) (xy 21.812731 -409.6966)
			(xy 21.769863 -409.732275) (xy 21.722257 -409.761329) (xy 21.670928 -409.783141) (xy 21.616971 -409.797247)
			(xy 21.561534 -409.803347) (xy 21.5058 -409.80131) (xy 21.450957 -409.79118) (xy 21.398173 -409.773173)
			(xy 21.348573 -409.747672) (xy 21.303215 -409.715221) (xy 21.263066 -409.676512) (xy 21.22898 -409.632369)
			(xy 21.201684 -409.583734) (xy 21.181761 -409.531643) (xy 21.169635 -409.477206) (xy 21.165564 -409.421584)
			(xy 19.113761 -409.421584) (xy 19.094931 -409.4426) (xy 19.052063 -409.478275) (xy 19.004457 -409.507329)
			(xy 18.953128 -409.529141) (xy 18.899171 -409.543247) (xy 18.843734 -409.549347) (xy 18.788 -409.54731)
			(xy 18.733157 -409.53718) (xy 18.680373 -409.519173) (xy 18.630773 -409.493672) (xy 18.585415 -409.461221)
			(xy 18.545266 -409.422512) (xy 18.51118 -409.378369) (xy 18.483884 -409.329734) (xy 18.463961 -409.277643)
			(xy 18.451835 -409.223206) (xy 18.447764 -409.167584) (xy 13.104876 -409.167584) (xy 13.104876 -410.460444)
			(xy 13.10432 -410.489008) (xy 13.095394 -410.545436) (xy 13.077752 -410.599772) (xy 13.05247 -410.64942)
			(xy 17.970752 -410.64942) (xy 17.974823 -410.593798) (xy 17.986949 -410.539361) (xy 18.006872 -410.48727)
			(xy 18.034168 -410.438635) (xy 18.068254 -410.394492) (xy 18.108403 -410.355783) (xy 18.153761 -410.323332)
			(xy 18.203361 -410.297831) (xy 18.256145 -410.279824) (xy 18.310988 -410.269694) (xy 18.366722 -410.267657)
			(xy 18.422159 -410.273757) (xy 18.476116 -410.287863) (xy 18.527445 -410.309675) (xy 18.575051 -410.338729)
			(xy 18.617919 -410.374404) (xy 18.655136 -410.415941) (xy 18.685909 -410.462454) (xy 18.709581 -410.512951)
			(xy 18.725649 -410.566358) (xy 18.733769 -410.621534) (xy 18.734278 -410.64942) (xy 18.733769 -410.677306)
			(xy 18.725649 -410.732482) (xy 18.709581 -410.785889) (xy 18.685909 -410.836386) (xy 18.655136 -410.882899)
			(xy 18.617919 -410.924436) (xy 18.575051 -410.960111) (xy 18.527445 -410.989165) (xy 18.476116 -411.010977)
			(xy 18.422159 -411.025083) (xy 18.366722 -411.031183) (xy 18.310988 -411.029146) (xy 18.256145 -411.019016)
			(xy 18.203361 -411.001009) (xy 18.153761 -410.975508) (xy 18.108403 -410.943057) (xy 18.068254 -410.904348)
			(xy 18.034168 -410.860205) (xy 18.006872 -410.81157) (xy 17.986949 -410.759479) (xy 17.974823 -410.705042)
			(xy 17.970752 -410.64942) (xy 13.05247 -410.64942) (xy 13.051828 -410.65068) (xy 13.018262 -410.696908)
			(xy 12.99845 -410.717492) (xy 11.881358 -411.834584) (xy 18.448018 -411.834584) (xy 18.452089 -411.778962)
			(xy 18.464215 -411.724525) (xy 18.484138 -411.672434) (xy 18.511434 -411.623799) (xy 18.54552 -411.579656)
			(xy 18.585669 -411.540947) (xy 18.631027 -411.508496) (xy 18.680627 -411.482995) (xy 18.733411 -411.464988)
			(xy 18.788254 -411.454858) (xy 18.843988 -411.452821) (xy 18.899425 -411.458921) (xy 18.953382 -411.473027)
			(xy 19.004711 -411.494839) (xy 19.052317 -411.523893) (xy 19.095185 -411.559568) (xy 19.132402 -411.601105)
			(xy 19.163175 -411.647618) (xy 19.186847 -411.698115) (xy 19.202915 -411.751522) (xy 19.211035 -411.806698)
			(xy 19.211544 -411.834584) (xy 19.211035 -411.86247) (xy 19.202915 -411.917646) (xy 19.186847 -411.971053)
			(xy 19.163175 -412.02155) (xy 19.132402 -412.068063) (xy 19.095185 -412.1096) (xy 19.052317 -412.145275)
			(xy 19.004711 -412.174329) (xy 18.953382 -412.196141) (xy 18.899425 -412.210247) (xy 18.843988 -412.216347)
			(xy 18.788254 -412.21431) (xy 18.733411 -412.20418) (xy 18.680627 -412.186173) (xy 18.631027 -412.160672)
			(xy 18.585669 -412.128221) (xy 18.54552 -412.089512) (xy 18.511434 -412.045369) (xy 18.484138 -411.996734)
			(xy 18.464215 -411.944643) (xy 18.452089 -411.890206) (xy 18.448018 -411.834584) (xy 11.881358 -411.834584)
			(xy 11.732514 -411.983428) (xy 11.72567 -411.990827) (xy 11.717944 -412.009426) (xy 11.717528 -412.019496)
			(xy 11.717528 -412.903162) (xy 17.542 -412.903162) (xy 17.546071 -412.84754) (xy 17.558197 -412.793103)
			(xy 17.57812 -412.741012) (xy 17.605416 -412.692377) (xy 17.639502 -412.648234) (xy 17.679651 -412.609525)
			(xy 17.725009 -412.577074) (xy 17.774609 -412.551573) (xy 17.827393 -412.533566) (xy 17.882236 -412.523436)
			(xy 17.93797 -412.521399) (xy 17.993407 -412.527499) (xy 18.047364 -412.541605) (xy 18.098693 -412.563417)
			(xy 18.146299 -412.592471) (xy 18.189167 -412.628146) (xy 18.226384 -412.669683) (xy 18.257157 -412.716196)
			(xy 18.280829 -412.766693) (xy 18.296897 -412.8201) (xy 18.305017 -412.875276) (xy 18.305526 -412.903162)
			(xy 18.305017 -412.931048) (xy 18.296897 -412.986224) (xy 18.280829 -413.039631) (xy 18.257157 -413.090128)
			(xy 18.226384 -413.136641) (xy 18.189167 -413.178178) (xy 18.146299 -413.213853) (xy 18.098693 -413.242907)
			(xy 18.047364 -413.264719) (xy 17.993407 -413.278825) (xy 17.93797 -413.284925) (xy 17.882236 -413.282888)
			(xy 17.827393 -413.272758) (xy 17.774609 -413.254751) (xy 17.725009 -413.22925) (xy 17.679651 -413.196799)
			(xy 17.639502 -413.15809) (xy 17.605416 -413.113947) (xy 17.57812 -413.065312) (xy 17.558197 -413.013221)
			(xy 17.546071 -412.958784) (xy 17.542 -412.903162) (xy 11.717528 -412.903162) (xy 11.717528 -413.485584)
			(xy 15.907764 -413.485584) (xy 15.911835 -413.429962) (xy 15.923961 -413.375525) (xy 15.943884 -413.323434)
			(xy 15.97118 -413.274799) (xy 16.005266 -413.230656) (xy 16.045415 -413.191947) (xy 16.090773 -413.159496)
			(xy 16.140373 -413.133995) (xy 16.193157 -413.115988) (xy 16.248 -413.105858) (xy 16.303734 -413.103821)
			(xy 16.359171 -413.109921) (xy 16.413128 -413.124027) (xy 16.464457 -413.145839) (xy 16.512063 -413.174893)
			(xy 16.554931 -413.210568) (xy 16.592148 -413.252105) (xy 16.622921 -413.298618) (xy 16.646593 -413.349115)
			(xy 16.662661 -413.402522) (xy 16.664643 -413.415988) (xy 18.764502 -413.415988) (xy 18.768573 -413.360366)
			(xy 18.780699 -413.305929) (xy 18.800622 -413.253838) (xy 18.827918 -413.205203) (xy 18.862004 -413.16106)
			(xy 18.902153 -413.122351) (xy 18.947511 -413.0899) (xy 18.997111 -413.064399) (xy 19.049895 -413.046392)
			(xy 19.104738 -413.036262) (xy 19.160472 -413.034225) (xy 19.215909 -413.040325) (xy 19.269866 -413.054431)
			(xy 19.321195 -413.076243) (xy 19.368801 -413.105297) (xy 19.411669 -413.140972) (xy 19.448886 -413.182509)
			(xy 19.479659 -413.229022) (xy 19.503331 -413.279519) (xy 19.519399 -413.332926) (xy 19.527519 -413.388102)
			(xy 19.528028 -413.415988) (xy 19.527519 -413.443874) (xy 19.519399 -413.49905) (xy 19.503331 -413.552457)
			(xy 19.479659 -413.602954) (xy 19.448886 -413.649467) (xy 19.411669 -413.691004) (xy 19.368801 -413.726679)
			(xy 19.321195 -413.755733) (xy 19.269866 -413.777545) (xy 19.215909 -413.791651) (xy 19.160472 -413.797751)
			(xy 19.104738 -413.795714) (xy 19.049895 -413.785584) (xy 18.997111 -413.767577) (xy 18.947511 -413.742076)
			(xy 18.902153 -413.709625) (xy 18.862004 -413.670916) (xy 18.827918 -413.626773) (xy 18.800622 -413.578138)
			(xy 18.780699 -413.526047) (xy 18.768573 -413.47161) (xy 18.764502 -413.415988) (xy 16.664643 -413.415988)
			(xy 16.670781 -413.457698) (xy 16.67129 -413.485584) (xy 16.670781 -413.51347) (xy 16.662661 -413.568646)
			(xy 16.646593 -413.622053) (xy 16.622921 -413.67255) (xy 16.592148 -413.719063) (xy 16.554931 -413.7606)
			(xy 16.512063 -413.796275) (xy 16.464457 -413.825329) (xy 16.413128 -413.847141) (xy 16.359171 -413.861247)
			(xy 16.303734 -413.867347) (xy 16.248 -413.86531) (xy 16.193157 -413.85518) (xy 16.140373 -413.837173)
			(xy 16.090773 -413.811672) (xy 16.045415 -413.779221) (xy 16.005266 -413.740512) (xy 15.97118 -413.696369)
			(xy 15.943884 -413.647734) (xy 15.923961 -413.595643) (xy 15.911835 -413.541206) (xy 15.907764 -413.485584)
			(xy 11.717528 -413.485584) (xy 11.717528 -413.993584) (xy 13.240764 -413.993584) (xy 13.244835 -413.937962)
			(xy 13.256961 -413.883525) (xy 13.276884 -413.831434) (xy 13.30418 -413.782799) (xy 13.338266 -413.738656)
			(xy 13.378415 -413.699947) (xy 13.423773 -413.667496) (xy 13.473373 -413.641995) (xy 13.526157 -413.623988)
			(xy 13.581 -413.613858) (xy 13.636734 -413.611821) (xy 13.692171 -413.617921) (xy 13.746128 -413.632027)
			(xy 13.797457 -413.653839) (xy 13.845063 -413.682893) (xy 13.887931 -413.718568) (xy 13.925148 -413.760105)
			(xy 13.955921 -413.806618) (xy 13.979593 -413.857115) (xy 13.995661 -413.910522) (xy 14.003781 -413.965698)
			(xy 14.00429 -413.993584) (xy 14.510764 -413.993584) (xy 14.514835 -413.937962) (xy 14.526961 -413.883525)
			(xy 14.546884 -413.831434) (xy 14.57418 -413.782799) (xy 14.608266 -413.738656) (xy 14.648415 -413.699947)
			(xy 14.693773 -413.667496) (xy 14.743373 -413.641995) (xy 14.796157 -413.623988) (xy 14.851 -413.613858)
			(xy 14.906734 -413.611821) (xy 14.962171 -413.617921) (xy 15.016128 -413.632027) (xy 15.067457 -413.653839)
			(xy 15.115063 -413.682893) (xy 15.157931 -413.718568) (xy 15.195148 -413.760105) (xy 15.225921 -413.806618)
			(xy 15.249593 -413.857115) (xy 15.265661 -413.910522) (xy 15.273781 -413.965698) (xy 15.27429 -413.993584)
			(xy 15.273781 -414.02147) (xy 15.265661 -414.076646) (xy 15.249593 -414.130053) (xy 15.225921 -414.18055)
			(xy 15.195148 -414.227063) (xy 15.157931 -414.2686) (xy 15.115063 -414.304275) (xy 15.067457 -414.333329)
			(xy 15.016128 -414.355141) (xy 14.962171 -414.369247) (xy 14.906734 -414.375347) (xy 14.851 -414.37331)
			(xy 14.796157 -414.36318) (xy 14.743373 -414.345173) (xy 14.693773 -414.319672) (xy 14.648415 -414.287221)
			(xy 14.608266 -414.248512) (xy 14.57418 -414.204369) (xy 14.546884 -414.155734) (xy 14.526961 -414.103643)
			(xy 14.514835 -414.049206) (xy 14.510764 -413.993584) (xy 14.00429 -413.993584) (xy 14.003781 -414.02147)
			(xy 13.995661 -414.076646) (xy 13.979593 -414.130053) (xy 13.955921 -414.18055) (xy 13.925148 -414.227063)
			(xy 13.887931 -414.2686) (xy 13.845063 -414.304275) (xy 13.797457 -414.333329) (xy 13.746128 -414.355141)
			(xy 13.692171 -414.369247) (xy 13.636734 -414.375347) (xy 13.581 -414.37331) (xy 13.526157 -414.36318)
			(xy 13.473373 -414.345173) (xy 13.423773 -414.319672) (xy 13.378415 -414.287221) (xy 13.338266 -414.248512)
			(xy 13.30418 -414.204369) (xy 13.276884 -414.155734) (xy 13.256961 -414.103643) (xy 13.244835 -414.049206)
			(xy 13.240764 -413.993584) (xy 11.717528 -413.993584) (xy 11.717528 -414.308798) (xy 11.717951 -414.318868)
			(xy 11.725668 -414.33747) (xy 11.732514 -414.344866) (xy 12.143232 -414.755584) (xy 16.034764 -414.755584)
			(xy 16.038835 -414.699962) (xy 16.050961 -414.645525) (xy 16.070884 -414.593434) (xy 16.09818 -414.544799)
			(xy 16.132266 -414.500656) (xy 16.172415 -414.461947) (xy 16.217773 -414.429496) (xy 16.267373 -414.403995)
			(xy 16.320157 -414.385988) (xy 16.375 -414.375858) (xy 16.430734 -414.373821) (xy 16.486171 -414.379921)
			(xy 16.540128 -414.394027) (xy 16.591457 -414.415839) (xy 16.639063 -414.444893) (xy 16.681931 -414.480568)
			(xy 16.719148 -414.522105) (xy 16.749921 -414.568618) (xy 16.773593 -414.619115) (xy 16.789661 -414.672522)
			(xy 16.797781 -414.727698) (xy 16.79829 -414.755584) (xy 16.797781 -414.78347) (xy 16.789661 -414.838646)
			(xy 16.773593 -414.892053) (xy 16.749921 -414.94255) (xy 16.719148 -414.989063) (xy 16.681931 -415.0306)
			(xy 16.639063 -415.066275) (xy 16.591457 -415.095329) (xy 16.540128 -415.117141) (xy 16.486171 -415.131247)
			(xy 16.430734 -415.137347) (xy 16.375 -415.13531) (xy 16.320157 -415.12518) (xy 16.267373 -415.107173)
			(xy 16.217773 -415.081672) (xy 16.172415 -415.049221) (xy 16.132266 -415.010512) (xy 16.09818 -414.966369)
			(xy 16.070884 -414.917734) (xy 16.050961 -414.865643) (xy 16.038835 -414.811206) (xy 16.034764 -414.755584)
			(xy 12.143232 -414.755584) (xy 12.266676 -414.879028) (xy 12.287272 -414.900466) (xy 12.321908 -414.948777)
			(xy 12.348236 -415.002073) (xy 12.365555 -415.058939) (xy 12.370054 -415.088324) (xy 12.371324 -415.096706)
			(xy 12.378436 -415.111438) (xy 12.531852 -415.264854) (xy 12.538695 -415.272253) (xy 12.546417 -415.290852)
			(xy 12.546838 -415.300922) (xy 12.546838 -415.823471) (xy 18.86304 -415.823471) (xy 18.86304 -415.768969)
			(xy 18.870796 -415.715022) (xy 18.886151 -415.662728) (xy 18.908792 -415.613151) (xy 18.938257 -415.567301)
			(xy 18.973948 -415.526111) (xy 19.015138 -415.49042) (xy 19.060988 -415.460954) (xy 19.110564 -415.438312)
			(xy 19.162858 -415.422957) (xy 19.216805 -415.4152) (xy 19.244056 -415.414714) (xy 19.270419 -415.415193)
			(xy 19.32264 -415.422472) (xy 19.373363 -415.43687) (xy 19.42162 -415.458113) (xy 19.466494 -415.485797)
			(xy 19.50713 -415.519394) (xy 19.542755 -415.558265) (xy 19.572689 -415.60167) (xy 19.584924 -415.625026)
			(xy 19.591646 -415.637388) (xy 19.610658 -415.658118) (xy 19.634603 -415.672877) (xy 19.661665 -415.680548)
			(xy 19.689793 -415.680548) (xy 19.716855 -415.672877) (xy 19.7408 -415.658118) (xy 19.759812 -415.637388)
			(xy 19.766534 -415.625026) (xy 19.778775 -415.601643) (xy 19.808708 -415.558174) (xy 19.844346 -415.519244)
			(xy 19.885007 -415.485596) (xy 19.929918 -415.457872) (xy 19.97822 -415.4366) (xy 20.028993 -415.422188)
			(xy 20.081267 -415.414909) (xy 20.107656 -415.41446) (xy 20.134909 -415.414927) (xy 20.18886 -415.422684)
			(xy 20.241158 -415.438039) (xy 20.290738 -415.460681) (xy 20.336592 -415.490149) (xy 20.377785 -415.525842)
			(xy 20.413479 -415.567035) (xy 20.442947 -415.612888) (xy 20.465589 -415.662468) (xy 20.480946 -415.714766)
			(xy 20.488703 -415.768717) (xy 20.488703 -415.823223) (xy 20.480946 -415.877174) (xy 20.465589 -415.929472)
			(xy 20.442947 -415.979052) (xy 20.413479 -416.024905) (xy 20.377785 -416.066098) (xy 20.336592 -416.101791)
			(xy 20.290738 -416.131259) (xy 20.241158 -416.153901) (xy 20.18886 -416.169256) (xy 20.134909 -416.177013)
			(xy 20.107656 -416.177476) (xy 20.081293 -416.176993) (xy 20.029072 -416.169715) (xy 19.978349 -416.155318)
			(xy 19.930092 -416.134076) (xy 19.885218 -416.106393) (xy 19.844581 -416.072796) (xy 19.808957 -416.033925)
			(xy 19.779022 -415.99052) (xy 19.766788 -415.967164) (xy 19.760097 -415.954762) (xy 19.741114 -415.933951)
			(xy 19.717161 -415.919127) (xy 19.690067 -415.911421) (xy 19.661899 -415.911421) (xy 19.634805 -415.919127)
			(xy 19.610852 -415.933951) (xy 19.591869 -415.954762) (xy 19.585178 -415.967164) (xy 19.572923 -415.99054)
			(xy 19.542993 -416.034009) (xy 19.507357 -416.07294) (xy 19.466698 -416.106588) (xy 19.421789 -416.134314)
			(xy 19.373489 -416.155586) (xy 19.322718 -416.17) (xy 19.270445 -416.17728) (xy 19.244056 -416.17773)
			(xy 19.216805 -416.17724) (xy 19.162858 -416.169483) (xy 19.110564 -416.154128) (xy 19.060988 -416.131486)
			(xy 19.015138 -416.10202) (xy 18.973948 -416.066329) (xy 18.938257 -416.025139) (xy 18.908792 -415.979289)
			(xy 18.886151 -415.929712) (xy 18.870796 -415.877418) (xy 18.86304 -415.823471) (xy 12.546838 -415.823471)
			(xy 12.546838 -416.788346) (xy 12.547367 -416.798337) (xy 12.555071 -416.81678) (xy 12.561824 -416.82416)
			(xy 13.169027 -417.431474) (xy 14.048992 -417.431474) (xy 14.053063 -417.375852) (xy 14.065189 -417.321415)
			(xy 14.085112 -417.269324) (xy 14.112408 -417.220689) (xy 14.146494 -417.176546) (xy 14.186643 -417.137837)
			(xy 14.232001 -417.105386) (xy 14.281601 -417.079885) (xy 14.334385 -417.061878) (xy 14.389228 -417.051748)
			(xy 14.444962 -417.049711) (xy 14.500399 -417.055811) (xy 14.554356 -417.069917) (xy 14.605685 -417.091729)
			(xy 14.653291 -417.120783) (xy 14.696159 -417.156458) (xy 14.733376 -417.197995) (xy 14.764149 -417.244508)
			(xy 14.787821 -417.295005) (xy 14.803889 -417.348412) (xy 14.812009 -417.403588) (xy 14.812518 -417.431474)
			(xy 14.812009 -417.45936) (xy 14.809673 -417.475231) (xy 15.348442 -417.475231) (xy 15.348442 -417.420729)
			(xy 15.356198 -417.366782) (xy 15.371553 -417.314488) (xy 15.394194 -417.264912) (xy 15.42366 -417.219062)
			(xy 15.459351 -417.177872) (xy 15.50054 -417.142181) (xy 15.54639 -417.112715) (xy 15.595966 -417.090074)
			(xy 15.64826 -417.074719) (xy 15.702207 -417.066962) (xy 15.729458 -417.066476) (xy 15.756828 -417.066948)
			(xy 15.811008 -417.074762) (xy 15.863512 -417.090248) (xy 15.913259 -417.113089) (xy 15.959225 -417.142814)
			(xy 15.980156 -417.160456) (xy 15.987268 -417.166552) (xy 16.004286 -417.172902) (xy 16.08963 -417.172902)
			(xy 16.106648 -417.166552) (xy 16.11376 -417.160456) (xy 16.13469 -417.142815) (xy 16.180664 -417.113105)
			(xy 16.230412 -417.09027) (xy 16.282913 -417.074779) (xy 16.337089 -417.06695) (xy 16.364458 -417.066476)
			(xy 16.391711 -417.066931) (xy 16.445663 -417.074688) (xy 16.497962 -417.090044) (xy 16.547542 -417.112687)
			(xy 16.593396 -417.142155) (xy 16.63459 -417.177849) (xy 16.670284 -417.219042) (xy 16.699752 -417.264896)
			(xy 16.722395 -417.314477) (xy 16.737752 -417.366775) (xy 16.745509 -417.420727) (xy 16.745509 -417.475233)
			(xy 16.737752 -417.529185) (xy 16.722395 -417.581483) (xy 16.699752 -417.631064) (xy 16.670284 -417.676918)
			(xy 16.667492 -417.68014) (xy 19.28444 -417.68014) (xy 19.288511 -417.624518) (xy 19.300637 -417.570081)
			(xy 19.32056 -417.51799) (xy 19.347856 -417.469355) (xy 19.381942 -417.425212) (xy 19.422091 -417.386503)
			(xy 19.467449 -417.354052) (xy 19.517049 -417.328551) (xy 19.569833 -417.310544) (xy 19.624676 -417.300414)
			(xy 19.68041 -417.298377) (xy 19.735847 -417.304477) (xy 19.789804 -417.318583) (xy 19.841133 -417.340395)
			(xy 19.888739 -417.369449) (xy 19.931607 -417.405124) (xy 19.968824 -417.446661) (xy 19.999597 -417.493174)
			(xy 20.023269 -417.543671) (xy 20.039337 -417.597078) (xy 20.047457 -417.652254) (xy 20.047966 -417.68014)
			(xy 20.047457 -417.708026) (xy 20.039337 -417.763202) (xy 20.023269 -417.816609) (xy 19.999597 -417.867106)
			(xy 19.968824 -417.913619) (xy 19.931607 -417.955156) (xy 19.888739 -417.990831) (xy 19.841133 -418.019885)
			(xy 19.789804 -418.041697) (xy 19.735847 -418.055803) (xy 19.68041 -418.061903) (xy 19.624676 -418.059866)
			(xy 19.569833 -418.049736) (xy 19.517049 -418.031729) (xy 19.467449 -418.006228) (xy 19.422091 -417.973777)
			(xy 19.381942 -417.935068) (xy 19.347856 -417.890925) (xy 19.32056 -417.84229) (xy 19.300637 -417.790199)
			(xy 19.288511 -417.735762) (xy 19.28444 -417.68014) (xy 16.667492 -417.68014) (xy 16.63459 -417.718111)
			(xy 16.593396 -417.753805) (xy 16.547542 -417.783273) (xy 16.497962 -417.805916) (xy 16.445663 -417.821272)
			(xy 16.391711 -417.829029) (xy 16.364458 -417.829492) (xy 16.337089 -417.828994) (xy 16.282911 -417.821184)
			(xy 16.230408 -417.805703) (xy 16.180661 -417.782868) (xy 16.134693 -417.75315) (xy 16.11376 -417.735512)
			(xy 16.106648 -417.729416) (xy 16.08963 -417.723066) (xy 16.004286 -417.723066) (xy 15.987268 -417.729416)
			(xy 15.980156 -417.735512) (xy 15.959215 -417.75314) (xy 15.913245 -417.782853) (xy 15.863499 -417.805691)
			(xy 15.811001 -417.821185) (xy 15.756827 -417.829016) (xy 15.729458 -417.829492) (xy 15.702207 -417.828998)
			(xy 15.64826 -417.821241) (xy 15.595966 -417.805886) (xy 15.54639 -417.783245) (xy 15.50054 -417.753779)
			(xy 15.459351 -417.718088) (xy 15.42366 -417.676898) (xy 15.394194 -417.631048) (xy 15.371553 -417.581472)
			(xy 15.356198 -417.529178) (xy 15.348442 -417.475231) (xy 14.809673 -417.475231) (xy 14.803889 -417.514536)
			(xy 14.787821 -417.567943) (xy 14.764149 -417.61844) (xy 14.733376 -417.664953) (xy 14.696159 -417.70649)
			(xy 14.653291 -417.742165) (xy 14.605685 -417.771219) (xy 14.554356 -417.793031) (xy 14.500399 -417.807137)
			(xy 14.444962 -417.813237) (xy 14.389228 -417.8112) (xy 14.334385 -417.80107) (xy 14.281601 -417.783063)
			(xy 14.232001 -417.757562) (xy 14.186643 -417.725111) (xy 14.146494 -417.686402) (xy 14.112408 -417.642259)
			(xy 14.085112 -417.593624) (xy 14.065189 -417.541533) (xy 14.053063 -417.487096) (xy 14.048992 -417.431474)
			(xy 13.169027 -417.431474) (xy 13.945616 -418.208206) (xy 13.953016 -418.215049) (xy 13.971614 -418.222777)
			(xy 13.981684 -418.223192) (xy 21.366988 -418.223192) (xy 21.395551 -418.223751) (xy 21.451973 -418.232685)
			(xy 21.506303 -418.250335) (xy 21.557204 -418.276265) (xy 21.603421 -418.309839) (xy 21.624036 -418.329618)
			(xy 21.721826 -418.427154) (xy 21.72917 -418.433966) (xy 21.747633 -418.441696) (xy 21.75764 -418.44214)
		)
		(stroke
			(width 0)
			(type solid)
		)
		(fill yes)
		(layer "In13.Cu")
		(net "GND")
	)
	(gr_poly
		(pts
			(xy 162.213798 -399.214086) (xy 162.216846 -399.21307) (xy 162.233102 -399.157444) (xy 162.235742 -399.146195)
			(xy 162.231762 -399.123457) (xy 162.225482 -399.113756) (xy 162.20881 -399.089393) (xy 162.182392 -399.036603)
			(xy 162.164435 -398.980369) (xy 162.15537 -398.922038) (xy 162.15487 -398.892522) (xy 162.155356 -398.865271)
			(xy 162.163112 -398.811323) (xy 162.178467 -398.759028) (xy 162.201109 -398.709451) (xy 162.230575 -398.663601)
			(xy 162.266266 -398.62241) (xy 162.307457 -398.586719) (xy 162.353307 -398.557253) (xy 162.402884 -398.534611)
			(xy 162.455179 -398.519256) (xy 162.509127 -398.5115) (xy 162.563629 -398.5115) (xy 162.617577 -398.519256)
			(xy 162.669872 -398.534611) (xy 162.719449 -398.557253) (xy 162.765299 -398.586719) (xy 162.80649 -398.62241)
			(xy 162.842181 -398.663601) (xy 162.871647 -398.709451) (xy 162.894289 -398.759028) (xy 162.909644 -398.811323)
			(xy 162.9174 -398.865271) (xy 162.917886 -398.892522) (xy 162.917308 -398.923028) (xy 162.907634 -398.983267)
			(xy 162.888488 -399.041195) (xy 162.87496 -399.068544) (xy 162.868864 -399.080228) (xy 162.869626 -399.106898)
			(xy 162.921696 -399.192496) (xy 162.926517 -399.199749) (xy 162.940021 -399.210726) (xy 162.956428 -399.216529)
			(xy 162.96513 -399.21688) (xy 165.005258 -399.21688) (xy 165.015323 -399.216446) (xy 165.03391 -399.208714)
			(xy 165.041326 -399.201894) (xy 165.04412 -399.1991) (xy 165.05174 -399.180558) (xy 165.05174 -390.535922)
			(xy 165.051307 -390.526225) (xy 165.044125 -390.508208) (xy 165.03777 -390.50087) (xy 165.016942 -390.479026)
			(xy 165.010537 -390.472795) (xy 164.994536 -390.464865) (xy 164.9857 -390.463532) (xy 164.961092 -390.460345)
			(xy 164.913295 -390.447031) (xy 164.868278 -390.426165) (xy 164.827228 -390.398294) (xy 164.791224 -390.364154)
			(xy 164.761214 -390.324641) (xy 164.737986 -390.280797) (xy 164.722153 -390.233773) (xy 164.714131 -390.184809)
			(xy 164.714131 -390.135192) (xy 164.722153 -390.086227) (xy 164.737986 -390.039204) (xy 164.761213 -389.995359)
			(xy 164.791224 -389.955847) (xy 164.827228 -389.921706) (xy 164.868278 -389.893836) (xy 164.913294 -389.872969)
			(xy 164.961092 -389.859655) (xy 164.9857 -389.856472) (xy 164.994536 -389.855145) (xy 165.01053 -389.847203)
			(xy 165.016942 -389.840978) (xy 165.03777 -389.819134) (xy 165.044144 -389.81181) (xy 165.05131 -389.793783)
			(xy 165.05174 -389.784082) (xy 165.05174 -388.638542) (xy 165.035484 -388.61365) (xy 165.021768 -388.6073)
			(xy 164.999042 -388.596615) (xy 164.957142 -388.568942) (xy 164.920341 -388.534779) (xy 164.889632 -388.49505)
			(xy 164.865845 -388.450827) (xy 164.849624 -388.403306) (xy 164.841405 -388.353769) (xy 164.84092 -388.328662)
			(xy 164.84142 -388.303264) (xy 164.84982 -388.253168) (xy 164.866399 -388.205154) (xy 164.890698 -388.160548)
			(xy 164.922047 -388.12058) (xy 164.940488 -388.10311) (xy 164.94887 -388.09549) (xy 164.957506 -388.075424)
			(xy 164.954712 -387.97611) (xy 164.945314 -387.956552) (xy 164.936424 -387.94944) (xy 164.917862 -387.933638)
			(xy 164.885133 -387.897513) (xy 164.858058 -387.856976) (xy 164.837223 -387.812906) (xy 164.82308 -387.766256)
			(xy 164.815934 -387.718035) (xy 164.81552 -387.693662) (xy 164.815959 -387.669546) (xy 164.822965 -387.621826)
			(xy 164.836823 -387.575628) (xy 164.85724 -387.531931) (xy 164.87013 -387.511544) (xy 164.875972 -387.502654)
			(xy 164.879528 -387.482588) (xy 164.858446 -387.390386) (xy 164.846254 -387.373622) (xy 164.837364 -387.368288)
			(xy 164.816561 -387.355433) (xy 164.778643 -387.324555) (xy 164.745691 -387.288425) (xy 164.718426 -387.247831)
			(xy 164.697444 -387.203662) (xy 164.683202 -387.156881) (xy 164.676013 -387.108512) (xy 164.675566 -387.084062)
			(xy 164.676127 -387.056779) (xy 164.685087 -387.002954) (xy 164.702758 -386.951329) (xy 164.728661 -386.903303)
			(xy 164.762093 -386.860179) (xy 164.781738 -386.841238) (xy 164.789182 -386.833744) (xy 164.797718 -386.814449)
			(xy 164.798248 -386.8039) (xy 164.798248 -386.729224) (xy 164.79766 -386.71869) (xy 164.789126 -386.699419)
			(xy 164.781738 -386.691886) (xy 164.762083 -386.672953) (xy 164.728641 -386.629832) (xy 164.702733 -386.581805)
			(xy 164.685062 -386.530176) (xy 164.676108 -386.476347) (xy 164.675566 -386.449062) (xy 164.67582 -386.43687)
			(xy 164.676074 -386.427218) (xy 164.669978 -386.409184) (xy 164.611304 -386.341874) (xy 164.59454 -386.333238)
			(xy 164.584634 -386.332222) (xy 164.557722 -386.328869) (xy 164.505425 -386.314521) (xy 164.456172 -386.291831)
			(xy 164.411281 -386.261407) (xy 164.371958 -386.224064) (xy 164.339256 -386.180804) (xy 164.314053 -386.132788)
			(xy 164.297024 -386.081302) (xy 164.29228 -386.0546) (xy 164.290756 -386.045202) (xy 164.017706 -385.572762)
			(xy 164.010594 -385.56692) (xy 163.99186 -385.551141) (xy 163.958803 -385.514998) (xy 163.931442 -385.474373)
			(xy 163.910377 -385.430155) (xy 163.896067 -385.383312) (xy 163.888827 -385.33487) (xy 163.88842 -385.31038)
			(xy 163.88894 -385.283541) (xy 163.897617 -385.23057) (xy 163.905692 -385.20497) (xy 163.910264 -385.191254)
			(xy 163.90366 -385.16306) (xy 163.687506 -384.946906) (xy 163.680108 -384.940058) (xy 163.66151 -384.93232)
			(xy 163.651438 -384.93192) (xy 163.350956 -384.93192) (xy 163.341332 -384.932323) (xy 163.323434 -384.939399)
			(xy 163.309404 -384.952575) (xy 163.304982 -384.96113) (xy 163.259516 -385.058158) (xy 163.263326 -385.087114)
			(xy 163.272978 -385.098544) (xy 163.291534 -385.121805) (xy 163.320832 -385.173591) (xy 163.340409 -385.229777)
			(xy 163.345622 -385.259072) (xy 163.347146 -385.26847) (xy 163.619942 -385.740402) (xy 163.627308 -385.746244)
			(xy 163.646086 -385.762048) (xy 163.679218 -385.798256) (xy 163.706638 -385.838961) (xy 163.727743 -385.88327)
			(xy 163.742072 -385.93021) (xy 163.749309 -385.978752) (xy 163.749736 -386.003292) (xy 163.749482 -386.015484)
			(xy 163.749228 -386.025136) (xy 163.755324 -386.04317) (xy 163.813998 -386.11048) (xy 163.830762 -386.119116)
			(xy 163.840668 -386.120132) (xy 163.867438 -386.123456) (xy 163.91947 -386.137676) (xy 163.968505 -386.160151)
			(xy 164.013244 -386.190285) (xy 164.0525 -386.227279) (xy 164.085232 -386.270153) (xy 164.110574 -386.317769)
			(xy 164.127853 -386.368867) (xy 164.136612 -386.422092) (xy 164.137086 -386.449062) (xy 164.136523 -386.476344)
			(xy 164.127558 -386.530166) (xy 164.109883 -386.581787) (xy 164.083975 -386.629807) (xy 164.050539 -386.672925)
			(xy 164.030914 -386.691886) (xy 164.023468 -386.699379) (xy 164.014931 -386.718674) (xy 164.014404 -386.729224)
			(xy 164.014404 -386.8039) (xy 164.014995 -386.814433) (xy 164.023529 -386.833702) (xy 164.030914 -386.841238)
			(xy 164.05057 -386.86017) (xy 164.084014 -386.90329) (xy 164.109922 -386.951317) (xy 164.127592 -387.002947)
			(xy 164.136544 -387.056777) (xy 164.137086 -387.084062) (xy 164.136653 -387.108179) (xy 164.129657 -387.155904)
			(xy 164.115808 -387.202108) (xy 164.095399 -387.245813) (xy 164.082476 -387.26618) (xy 164.076634 -387.27507)
			(xy 164.073078 -387.295136) (xy 164.09416 -387.387338) (xy 164.106352 -387.404102) (xy 164.115242 -387.409436)
			(xy 164.136043 -387.422292) (xy 164.173959 -387.45317) (xy 164.206907 -387.489301) (xy 164.234169 -387.529895)
			(xy 164.255148 -387.574065) (xy 164.269386 -387.620845) (xy 164.276571 -387.669212) (xy 164.27704 -387.693662)
			(xy 164.276602 -387.718033) (xy 164.269446 -387.766246) (xy 164.255298 -387.812888) (xy 164.234463 -387.856952)
			(xy 164.207392 -387.897485) (xy 164.174671 -387.933609) (xy 164.156136 -387.94944) (xy 164.147246 -387.956552)
			(xy 164.137848 -387.97611) (xy 164.135054 -388.075424) (xy 164.14369 -388.09549) (xy 164.152072 -388.10311)
			(xy 164.170495 -388.120597) (xy 164.20184 -388.160564) (xy 164.226139 -388.205167) (xy 164.242723 -388.253175)
			(xy 164.251134 -388.303266) (xy 164.25164 -388.328662) (xy 164.251568 -388.33802) (xy 164.250422 -388.356702)
			(xy 164.249354 -388.366) (xy 164.248338 -388.37489) (xy 164.252148 -388.391654) (xy 164.29609 -388.461504)
			(xy 164.309806 -388.471918) (xy 164.318188 -388.474712) (xy 164.342284 -388.483195) (xy 164.387572 -388.506824)
			(xy 164.428466 -388.537436) (xy 164.463898 -388.574232) (xy 164.492944 -388.616252) (xy 164.514848 -388.6624)
			(xy 164.522404 -388.686802) (xy 164.523928 -388.692644) (xy 164.843714 -389.245602) (xy 164.847778 -389.24992)
			(xy 164.863969 -389.267628) (xy 164.891349 -389.30703) (xy 164.912443 -389.350125) (xy 164.926765 -389.395918)
			(xy 164.933983 -389.443353) (xy 164.934392 -389.467344) (xy 164.933903 -389.492132) (xy 164.926142 -389.541097)
			(xy 164.910817 -389.588245) (xy 164.888307 -389.632416) (xy 164.859164 -389.672523) (xy 164.824108 -389.707577)
			(xy 164.783999 -389.736717) (xy 164.739827 -389.759225) (xy 164.692678 -389.774546) (xy 164.643712 -389.782304)
			(xy 164.618924 -389.782812) (xy 164.593529 -389.782306) (xy 164.543394 -389.774179) (xy 164.495206 -389.75813)
			(xy 164.45021 -389.734574) (xy 164.409565 -389.704118) (xy 164.37432 -389.667547) (xy 164.345384 -389.625806)
			(xy 164.323504 -389.579971) (xy 164.315902 -389.555736) (xy 164.314378 -389.549894) (xy 163.99383 -388.995412)
			(xy 163.989766 -388.991094) (xy 163.973687 -388.973416) (xy 163.946499 -388.934118) (xy 163.925541 -388.891174)
			(xy 163.911291 -388.845562) (xy 163.904073 -388.798325) (xy 163.90366 -388.774432) (xy 163.903746 -388.762384)
			(xy 163.905529 -388.738355) (xy 163.907216 -388.726426) (xy 163.908486 -388.717536) (xy 163.905438 -388.700518)
			(xy 163.863274 -388.629652) (xy 163.850066 -388.618476) (xy 163.841684 -388.615428) (xy 163.819943 -388.607023)
			(xy 163.779099 -388.58457) (xy 163.74214 -388.556171) (xy 163.709928 -388.522485) (xy 163.683208 -388.484294)
			(xy 163.662604 -388.442486) (xy 163.648592 -388.398033) (xy 163.641499 -388.351967) (xy 163.641024 -388.328662)
			(xy 163.641524 -388.303264) (xy 163.649924 -388.253168) (xy 163.666503 -388.205154) (xy 163.690802 -388.160548)
			(xy 163.722152 -388.120581) (xy 163.740592 -388.10311) (xy 163.748974 -388.09549) (xy 163.75761 -388.075424)
			(xy 163.754816 -387.97611) (xy 163.745418 -387.956552) (xy 163.736528 -387.94944) (xy 163.717965 -387.933638)
			(xy 163.685236 -387.897513) (xy 163.658161 -387.856976) (xy 163.637326 -387.812906) (xy 163.623183 -387.766256)
			(xy 163.616036 -387.718036) (xy 163.615624 -387.693662) (xy 163.616063 -387.669546) (xy 163.623069 -387.621826)
			(xy 163.636927 -387.575628) (xy 163.657344 -387.531931) (xy 163.670234 -387.511544) (xy 163.676076 -387.502654)
			(xy 163.679632 -387.482588) (xy 163.65855 -387.390386) (xy 163.646358 -387.373622) (xy 163.637468 -387.368288)
			(xy 163.616665 -387.355433) (xy 163.578746 -387.324556) (xy 163.545794 -387.288425) (xy 163.518529 -387.247832)
			(xy 163.497546 -387.203662) (xy 163.483304 -387.156881) (xy 163.476115 -387.108512) (xy 163.47567 -387.084062)
			(xy 163.476231 -387.056779) (xy 163.485191 -387.002954) (xy 163.502862 -386.951329) (xy 163.528765 -386.903303)
			(xy 163.562198 -386.860179) (xy 163.581842 -386.841238) (xy 163.589298 -386.833749) (xy 163.597851 -386.814453)
			(xy 163.598352 -386.8039) (xy 163.598352 -386.729224) (xy 163.597765 -386.71869) (xy 163.589231 -386.699419)
			(xy 163.581842 -386.691886) (xy 163.562187 -386.672953) (xy 163.528744 -386.629832) (xy 163.502836 -386.581806)
			(xy 163.485165 -386.530177) (xy 163.476211 -386.476347) (xy 163.47567 -386.449062) (xy 163.475924 -386.43687)
			(xy 163.476178 -386.427218) (xy 163.470082 -386.409184) (xy 163.411408 -386.341874) (xy 163.394644 -386.333238)
			(xy 163.384738 -386.332222) (xy 163.357826 -386.32887) (xy 163.305529 -386.314522) (xy 163.256274 -386.291832)
			(xy 163.211383 -386.261408) (xy 163.17206 -386.224065) (xy 163.139358 -386.180806) (xy 163.114154 -386.132789)
			(xy 163.097124 -386.081303) (xy 163.092384 -386.0546) (xy 163.09086 -386.045202) (xy 162.818064 -385.57327)
			(xy 162.810698 -385.567428) (xy 162.791921 -385.551623) (xy 162.758792 -385.515415) (xy 162.731375 -385.47471)
			(xy 162.710273 -385.430401) (xy 162.695948 -385.383461) (xy 162.688715 -385.334919) (xy 162.68827 -385.31038)
			(xy 162.688702 -385.285969) (xy 162.695872 -385.237675) (xy 162.710068 -385.190962) (xy 162.730982 -385.146846)
			(xy 162.758157 -385.106285) (xy 162.791003 -385.070164) (xy 162.828806 -385.039267) (xy 162.84956 -385.026408)
			(xy 162.861244 -385.019296) (xy 162.874452 -384.996436) (xy 162.874452 -384.98272) (xy 162.874035 -384.9727)
			(xy 162.866367 -384.954184) (xy 162.852192 -384.940017) (xy 162.833673 -384.932359) (xy 162.823652 -384.93192)
			(xy 162.793426 -384.93192) (xy 162.786314 -384.934206) (xy 162.76281 -384.940879) (xy 162.714477 -384.94802)
			(xy 162.690048 -384.94843) (xy 162.66562 -384.948006) (xy 162.617291 -384.940858) (xy 162.593782 -384.934206)
			(xy 162.58667 -384.93192) (xy 162.15106 -384.93192) (xy 162.141446 -384.932339) (xy 162.123575 -384.939436)
			(xy 162.109575 -384.952616) (xy 162.105086 -384.96113) (xy 162.05962 -385.058158) (xy 162.06343 -385.087114)
			(xy 162.073082 -385.098544) (xy 162.091702 -385.121877) (xy 162.1211 -385.173825) (xy 162.140739 -385.230192)
			(xy 162.14598 -385.25958) (xy 162.14725 -385.268978) (xy 162.419792 -385.740402) (xy 162.427158 -385.746244)
			(xy 162.445938 -385.762047) (xy 162.479075 -385.798252) (xy 162.506499 -385.838957) (xy 162.527608 -385.883266)
			(xy 162.541939 -385.930208) (xy 162.549177 -385.978752) (xy 162.549586 -386.003292) (xy 162.549332 -386.015484)
			(xy 162.549078 -386.025136) (xy 162.555174 -386.04317) (xy 162.613848 -386.11048) (xy 162.630612 -386.119116)
			(xy 162.640518 -386.120132) (xy 162.667285 -386.12346) (xy 162.719311 -386.137686) (xy 162.768339 -386.160164)
			(xy 162.813071 -386.1903) (xy 162.85232 -386.227294) (xy 162.885047 -386.270166) (xy 162.910384 -386.31778)
			(xy 162.927661 -386.368874) (xy 162.936418 -386.422094) (xy 162.936936 -386.449062) (xy 162.936373 -386.476344)
			(xy 162.92741 -386.530167) (xy 162.909736 -386.58179) (xy 162.883831 -386.629813) (xy 162.850398 -386.672934)
			(xy 162.830764 -386.691886) (xy 162.823324 -386.699381) (xy 162.814796 -386.718676) (xy 162.814254 -386.729224)
			(xy 162.814254 -386.8039) (xy 162.814846 -386.814432) (xy 162.823387 -386.833696) (xy 162.830764 -386.841238)
			(xy 162.850417 -386.860172) (xy 162.883856 -386.903293) (xy 162.909761 -386.95132) (xy 162.927428 -387.002949)
			(xy 162.936378 -387.056778) (xy 162.936936 -387.084062) (xy 162.936503 -387.10818) (xy 162.929508 -387.155905)
			(xy 162.915661 -387.20211) (xy 162.895254 -387.245816) (xy 162.882326 -387.26618) (xy 162.876484 -387.27507)
			(xy 162.872928 -387.295136) (xy 162.89401 -387.387338) (xy 162.906202 -387.404102) (xy 162.915092 -387.409436)
			(xy 162.935896 -387.42229) (xy 162.973817 -387.453166) (xy 163.00677 -387.489295) (xy 163.034036 -387.529889)
			(xy 163.055019 -387.57406) (xy 163.069259 -387.620841) (xy 163.076445 -387.669211) (xy 163.07689 -387.693662)
			(xy 163.076453 -387.718033) (xy 163.069297 -387.766247) (xy 163.05515 -387.812891) (xy 163.034318 -387.856957)
			(xy 163.00725 -387.897492) (xy 162.974531 -387.933621) (xy 162.955986 -387.94944) (xy 162.947096 -387.956552)
			(xy 162.937698 -387.97611) (xy 162.934904 -388.075424) (xy 162.94354 -388.09549) (xy 162.951922 -388.10311)
			(xy 162.970343 -388.120599) (xy 163.001682 -388.160567) (xy 163.025977 -388.20517) (xy 163.042558 -388.253178)
			(xy 163.050967 -388.303267) (xy 163.05149 -388.328662) (xy 163.051418 -388.33802) (xy 163.050272 -388.356702)
			(xy 163.049204 -388.366) (xy 163.048188 -388.37489) (xy 163.051998 -388.391654) (xy 163.09594 -388.461504)
			(xy 163.109656 -388.471918) (xy 163.118038 -388.474712) (xy 163.142072 -388.483167) (xy 163.18725 -388.506715)
			(xy 163.22806 -388.537214) (xy 163.263441 -388.573871) (xy 163.292475 -388.615735) (xy 163.314409 -388.661719)
			(xy 163.322 -388.68604) (xy 163.323524 -388.691882) (xy 163.643818 -389.245602) (xy 163.647882 -389.24992)
			(xy 163.664073 -389.267628) (xy 163.691453 -389.30703) (xy 163.712547 -389.350125) (xy 163.726868 -389.395919)
			(xy 163.734085 -389.443353) (xy 163.734496 -389.467344) (xy 163.734007 -389.492132) (xy 163.726246 -389.541097)
			(xy 163.710921 -389.588246) (xy 163.688411 -389.632417) (xy 163.659269 -389.672524) (xy 163.624212 -389.707579)
			(xy 163.584104 -389.736719) (xy 163.539931 -389.759227) (xy 163.492782 -389.774549) (xy 163.443816 -389.782308)
			(xy 163.419028 -389.782812) (xy 163.393633 -389.782306) (xy 163.343497 -389.77418) (xy 163.295309 -389.758131)
			(xy 163.250312 -389.734575) (xy 163.209667 -389.704119) (xy 163.174421 -389.667549) (xy 163.145485 -389.625808)
			(xy 163.123605 -389.579972) (xy 163.116006 -389.555736) (xy 163.114482 -389.549894) (xy 162.794188 -388.996174)
			(xy 162.790124 -388.991856) (xy 162.773907 -388.974158) (xy 162.746476 -388.934769) (xy 162.72533 -388.891677)
			(xy 162.710959 -388.845879) (xy 162.703695 -388.798432) (xy 162.703256 -388.774432) (xy 162.703414 -388.76238)
			(xy 162.705323 -388.738352) (xy 162.707066 -388.726426) (xy 162.708336 -388.717536) (xy 162.705288 -388.700518)
			(xy 162.663124 -388.629652) (xy 162.649916 -388.618476) (xy 162.641534 -388.615428) (xy 162.619796 -388.60702)
			(xy 162.578957 -388.584564) (xy 162.542005 -388.556162) (xy 162.509797 -388.522475) (xy 162.483083 -388.484285)
			(xy 162.462482 -388.442479) (xy 162.448473 -388.398028) (xy 162.441382 -388.351965) (xy 162.440874 -388.328662)
			(xy 162.441373 -388.303264) (xy 162.449773 -388.253167) (xy 162.466349 -388.205151) (xy 162.490646 -388.160542)
			(xy 162.521992 -388.120571) (xy 162.540442 -388.10311) (xy 162.548824 -388.09549) (xy 162.55746 -388.075424)
			(xy 162.554666 -387.97611) (xy 162.545268 -387.956552) (xy 162.536378 -387.94944) (xy 162.517818 -387.933637)
			(xy 162.485093 -387.897509) (xy 162.458022 -387.856972) (xy 162.437191 -387.812902) (xy 162.42305 -387.766253)
			(xy 162.415904 -387.718035) (xy 162.415474 -387.693662) (xy 162.415913 -387.669546) (xy 162.422918 -387.621825)
			(xy 162.436774 -387.575627) (xy 162.457189 -387.531928) (xy 162.470084 -387.511544) (xy 162.475926 -387.502654)
			(xy 162.479482 -387.482588) (xy 162.4584 -387.390386) (xy 162.446208 -387.373622) (xy 162.437318 -387.368288)
			(xy 162.416513 -387.355435) (xy 162.378588 -387.32456) (xy 162.345631 -387.288431) (xy 162.318362 -387.247838)
			(xy 162.297375 -387.203667) (xy 162.283131 -387.156885) (xy 162.275941 -387.108514) (xy 162.27552 -387.084062)
			(xy 162.276081 -387.05678) (xy 162.285042 -387.002956) (xy 162.302715 -386.951332) (xy 162.328621 -386.903309)
			(xy 162.362057 -386.860189) (xy 162.381692 -386.841238) (xy 162.389142 -386.833746) (xy 162.397686 -386.814451)
			(xy 162.398202 -386.8039) (xy 162.398202 -386.729224) (xy 162.397616 -386.718689) (xy 162.389088 -386.699412)
			(xy 162.381692 -386.691886) (xy 162.362034 -386.672955) (xy 162.328587 -386.629835) (xy 162.302674 -386.581809)
			(xy 162.285 -386.530179) (xy 162.276045 -386.476348) (xy 162.27552 -386.449062) (xy 162.275774 -386.43687)
			(xy 162.276028 -386.427218) (xy 162.269932 -386.409184) (xy 162.211258 -386.341874) (xy 162.194494 -386.333238)
			(xy 162.184588 -386.332222) (xy 162.157673 -386.328873) (xy 162.10537 -386.314532) (xy 162.056109 -386.291846)
			(xy 162.011211 -386.261424) (xy 161.971881 -386.224081) (xy 161.939173 -386.180821) (xy 161.913965 -386.132801)
			(xy 161.896932 -386.081312) (xy 161.892234 -386.0546) (xy 161.89071 -386.045202) (xy 161.61766 -385.572762)
			(xy 161.610548 -385.56692) (xy 161.591816 -385.55114) (xy 161.558764 -385.514995) (xy 161.531407 -385.474369)
			(xy 161.510344 -385.430151) (xy 161.496037 -385.383309) (xy 161.488798 -385.334869) (xy 161.488374 -385.31038)
			(xy 161.488806 -385.285969) (xy 161.495976 -385.237676) (xy 161.510173 -385.190963) (xy 161.531086 -385.146846)
			(xy 161.558262 -385.106286) (xy 161.591108 -385.070165) (xy 161.628911 -385.039268) (xy 161.649664 -385.026408)
			(xy 161.661348 -385.019296) (xy 161.674556 -384.996436) (xy 161.674556 -384.98272) (xy 161.674139 -384.972699)
			(xy 161.666471 -384.954183) (xy 161.652297 -384.940015) (xy 161.633777 -384.932356) (xy 161.623756 -384.93192)
			(xy 161.59353 -384.93192) (xy 161.586418 -384.934206) (xy 161.562914 -384.94088) (xy 161.514581 -384.948021)
			(xy 161.490152 -384.94843) (xy 161.465724 -384.948006) (xy 161.417395 -384.940859) (xy 161.393886 -384.934206)
			(xy 161.386774 -384.93192) (xy 160.95091 -384.93192) (xy 160.941291 -384.932331) (xy 160.923406 -384.939417)
			(xy 160.90939 -384.952595) (xy 160.904936 -384.96113) (xy 160.85947 -385.058158) (xy 160.86328 -385.087114)
			(xy 160.872932 -385.098544) (xy 160.89149 -385.121804) (xy 160.920792 -385.173589) (xy 160.940372 -385.229775)
			(xy 160.945576 -385.259072) (xy 160.9471 -385.26847) (xy 161.219896 -385.740402) (xy 161.227262 -385.746244)
			(xy 161.246042 -385.762047) (xy 161.279179 -385.798253) (xy 161.306602 -385.838957) (xy 161.327711 -385.883266)
			(xy 161.342042 -385.930208) (xy 161.349279 -385.978752) (xy 161.34969 -386.003292) (xy 161.349436 -386.015484)
			(xy 161.349182 -386.025136) (xy 161.355278 -386.04317) (xy 161.413952 -386.11048) (xy 161.430716 -386.119116)
			(xy 161.440622 -386.120132) (xy 161.467389 -386.12346) (xy 161.519414 -386.137686) (xy 161.568442 -386.160165)
			(xy 161.613173 -386.190301) (xy 161.652422 -386.227295) (xy 161.685148 -386.270167) (xy 161.710485 -386.317781)
			(xy 161.727761 -386.368875) (xy 161.736518 -386.422094) (xy 161.73704 -386.449062) (xy 161.736477 -386.476344)
			(xy 161.727514 -386.530167) (xy 161.70984 -386.58179) (xy 161.683936 -386.629813) (xy 161.650502 -386.672935)
			(xy 161.630868 -386.691886) (xy 161.623427 -386.699381) (xy 161.614899 -386.718676) (xy 161.614358 -386.729224)
			(xy 161.614358 -386.8039) (xy 161.61495 -386.814432) (xy 161.623491 -386.833695) (xy 161.630868 -386.841238)
			(xy 161.650521 -386.860172) (xy 161.68396 -386.903293) (xy 161.709864 -386.951321) (xy 161.727531 -387.002949)
			(xy 161.736481 -387.056778) (xy 161.73704 -387.084062) (xy 161.736607 -387.10818) (xy 161.729612 -387.155905)
			(xy 161.715765 -387.20211) (xy 161.695359 -387.245816) (xy 161.68243 -387.26618) (xy 161.676588 -387.27507)
			(xy 161.673032 -387.295136) (xy 161.694114 -387.387338) (xy 161.706306 -387.404102) (xy 161.715196 -387.409436)
			(xy 161.736 -387.42229) (xy 161.77392 -387.453166) (xy 161.806873 -387.489296) (xy 161.834139 -387.52989)
			(xy 161.855121 -387.57406) (xy 161.869361 -387.620842) (xy 161.876548 -387.669211) (xy 161.876994 -387.693662)
			(xy 161.876557 -387.718033) (xy 161.869401 -387.766247) (xy 161.855255 -387.812891) (xy 161.834422 -387.856957)
			(xy 161.807354 -387.897493) (xy 161.774636 -387.933622) (xy 161.75609 -387.94944) (xy 161.7472 -387.956552)
			(xy 161.737802 -387.97611) (xy 161.735008 -388.075424) (xy 161.743644 -388.09549) (xy 161.752026 -388.10311)
			(xy 161.770446 -388.120599) (xy 161.801786 -388.160567) (xy 161.82608 -388.20517) (xy 161.842661 -388.253178)
			(xy 161.85107 -388.303267) (xy 161.851594 -388.328662) (xy 161.851522 -388.33802) (xy 161.850376 -388.356702)
			(xy 161.849308 -388.366) (xy 161.848292 -388.37489) (xy 161.852102 -388.391654) (xy 161.896044 -388.461504)
			(xy 161.90976 -388.471918) (xy 161.918142 -388.474712) (xy 161.942235 -388.483198) (xy 161.987517 -388.506832)
			(xy 162.028404 -388.537448) (xy 162.06383 -388.574245) (xy 162.092871 -388.616264) (xy 162.11477 -388.662411)
			(xy 162.122358 -388.686802) (xy 162.123882 -388.692644) (xy 162.443668 -389.245602) (xy 162.447732 -389.24992)
			(xy 162.463947 -389.267619) (xy 162.491377 -389.307009) (xy 162.512522 -389.3501) (xy 162.526894 -389.395898)
			(xy 162.53416 -389.443344) (xy 162.5346 -389.467344) (xy 162.534135 -389.492147) (xy 162.526365 -389.541141)
			(xy 162.511024 -389.588315) (xy 162.48849 -389.632507) (xy 162.459317 -389.672629) (xy 162.424226 -389.70769)
			(xy 162.38408 -389.736829) (xy 162.339869 -389.759326) (xy 162.292682 -389.774627) (xy 162.243681 -389.782356)
			(xy 162.218878 -389.782812) (xy 162.193485 -389.782303) (xy 162.143355 -389.774169) (xy 162.095174 -389.758116)
			(xy 162.050183 -389.734557) (xy 162.009544 -389.7041) (xy 161.974305 -389.667529) (xy 161.945375 -389.62579)
			(xy 161.923499 -389.579957) (xy 161.915856 -389.555736) (xy 161.914332 -389.549894) (xy 161.593784 -388.995412)
			(xy 161.58972 -388.991094) (xy 161.573616 -388.973425) (xy 161.546378 -388.934139) (xy 161.525369 -388.891199)
			(xy 161.511068 -388.845583) (xy 161.503802 -388.798334) (xy 161.50336 -388.774432) (xy 161.503518 -388.76238)
			(xy 161.505427 -388.738352) (xy 161.50717 -388.726426) (xy 161.50844 -388.717536) (xy 161.505392 -388.700518)
			(xy 161.463228 -388.629652) (xy 161.45002 -388.618476) (xy 161.441638 -388.615428) (xy 161.4199 -388.60702)
			(xy 161.37906 -388.584564) (xy 161.342108 -388.556163) (xy 161.3099 -388.522476) (xy 161.283185 -388.484286)
			(xy 161.262584 -388.44248) (xy 161.248575 -388.398029) (xy 161.241483 -388.351965) (xy 161.240978 -388.328662)
			(xy 161.241477 -388.303264) (xy 161.249877 -388.253167) (xy 161.266453 -388.205151) (xy 161.29075 -388.160543)
			(xy 161.322097 -388.120572) (xy 161.340546 -388.10311) (xy 161.348928 -388.09549) (xy 161.357564 -388.075424)
			(xy 161.35477 -387.97611) (xy 161.345372 -387.956552) (xy 161.336482 -387.94944) (xy 161.317922 -387.933637)
			(xy 161.285197 -387.89751) (xy 161.258125 -387.856973) (xy 161.237294 -387.812903) (xy 161.223152 -387.766254)
			(xy 161.216007 -387.718035) (xy 161.215578 -387.693662) (xy 161.216017 -387.669546) (xy 161.223022 -387.621825)
			(xy 161.236879 -387.575627) (xy 161.257293 -387.531928) (xy 161.270188 -387.511544) (xy 161.27603 -387.502654)
			(xy 161.279586 -387.482588) (xy 161.258504 -387.390386) (xy 161.246312 -387.373622) (xy 161.237422 -387.368288)
			(xy 161.216622 -387.355431) (xy 161.178708 -387.324551) (xy 161.14576 -387.28842) (xy 161.118499 -387.247826)
			(xy 161.097519 -387.203657) (xy 161.08328 -387.156878) (xy 161.076092 -387.108511) (xy 161.075624 -387.084062)
			(xy 161.076185 -387.05678) (xy 161.085147 -387.002956) (xy 161.10282 -386.951333) (xy 161.128726 -386.90331)
			(xy 161.162162 -386.86019) (xy 161.181796 -386.841238) (xy 161.189245 -386.833746) (xy 161.197789 -386.814451)
			(xy 161.198306 -386.8039) (xy 161.198306 -386.729224) (xy 161.19772 -386.718689) (xy 161.189193 -386.699412)
			(xy 161.181796 -386.691886) (xy 161.162138 -386.672955) (xy 161.12869 -386.629836) (xy 161.102777 -386.581809)
			(xy 161.085103 -386.530179) (xy 161.076147 -386.476348) (xy 161.075624 -386.449062) (xy 161.075878 -386.43687)
			(xy 161.076132 -386.427218) (xy 161.070036 -386.409184) (xy 161.011362 -386.341874) (xy 160.994598 -386.333238)
			(xy 160.984692 -386.332222) (xy 160.957777 -386.328873) (xy 160.905473 -386.314532) (xy 160.856212 -386.291847)
			(xy 160.811313 -386.261425) (xy 160.771983 -386.224083) (xy 160.739274 -386.180822) (xy 160.714066 -386.132802)
			(xy 160.697033 -386.081312) (xy 160.692338 -386.0546) (xy 160.690814 -386.045202) (xy 160.418018 -385.57327)
			(xy 160.410652 -385.567428) (xy 160.391873 -385.551625) (xy 160.358738 -385.515419) (xy 160.331317 -385.474714)
			(xy 160.310211 -385.430405) (xy 160.295883 -385.383463) (xy 160.288649 -385.33492) (xy 160.288224 -385.31038)
			(xy 160.288656 -385.285968) (xy 160.295825 -385.237674) (xy 160.31002 -385.190959) (xy 160.330932 -385.14684)
			(xy 160.358105 -385.106277) (xy 160.390949 -385.070152) (xy 160.428749 -385.03925) (xy 160.449514 -385.026408)
			(xy 160.461198 -385.019296) (xy 160.474406 -384.996436) (xy 160.474406 -384.98272) (xy 160.47399 -384.972696)
			(xy 160.466324 -384.954171) (xy 160.452151 -384.939991) (xy 160.43363 -384.932315) (xy 160.423606 -384.93192)
			(xy 160.39338 -384.93192) (xy 160.386268 -384.934206) (xy 160.362764 -384.940876) (xy 160.314431 -384.94801)
			(xy 160.290002 -384.94843) (xy 160.265574 -384.94801) (xy 160.217242 -384.940869) (xy 160.193736 -384.934206)
			(xy 160.186624 -384.93192) (xy 159.751014 -384.93192) (xy 159.741395 -384.93233) (xy 159.723508 -384.939415)
			(xy 159.709491 -384.952593) (xy 159.70504 -384.96113) (xy 159.659574 -385.058158) (xy 159.663384 -385.087114)
			(xy 159.673036 -385.098544) (xy 159.691594 -385.121804) (xy 159.720896 -385.173589) (xy 159.740475 -385.229775)
			(xy 159.74568 -385.259072) (xy 159.747204 -385.26847) (xy 160.02 -385.740402) (xy 160.027366 -385.746244)
			(xy 160.046146 -385.762047) (xy 160.079282 -385.798253) (xy 160.106705 -385.838957) (xy 160.127814 -385.883266)
			(xy 160.142144 -385.930208) (xy 160.149382 -385.978752) (xy 160.149794 -386.003292) (xy 160.14954 -386.015484)
			(xy 160.149286 -386.025136) (xy 160.155382 -386.04317) (xy 160.214056 -386.11048) (xy 160.23082 -386.119116)
			(xy 160.240472 -386.120132) (xy 160.267242 -386.123456) (xy 160.319273 -386.137677) (xy 160.368308 -386.160152)
			(xy 160.413046 -386.190286) (xy 160.452301 -386.22728) (xy 160.485033 -386.270154) (xy 160.510375 -386.31777)
			(xy 160.527654 -386.368868) (xy 160.536413 -386.422092) (xy 160.53689 -386.449062) (xy 160.53638 -386.475049)
			(xy 160.52825 -386.526384) (xy 160.512189 -386.575814) (xy 160.488593 -386.622124) (xy 160.458043 -386.664172)
			(xy 160.421292 -386.700923) (xy 160.379244 -386.731473) (xy 160.332934 -386.755069) (xy 160.283504 -386.77113)
			(xy 160.232169 -386.77926) (xy 160.180195 -386.77926) (xy 160.12886 -386.77113) (xy 160.07943 -386.755069)
			(xy 160.03312 -386.731473) (xy 159.991072 -386.700923) (xy 159.954321 -386.664172) (xy 159.923771 -386.622124)
			(xy 159.900175 -386.575814) (xy 159.884114 -386.526384) (xy 159.875984 -386.475049) (xy 159.875474 -386.449062)
			(xy 159.875728 -386.43687) (xy 159.875982 -386.427218) (xy 159.869886 -386.409184) (xy 159.811212 -386.341874)
			(xy 159.794448 -386.333238) (xy 159.784796 -386.332222) (xy 159.757881 -386.328874) (xy 159.705577 -386.314533)
			(xy 159.656314 -386.291848) (xy 159.611416 -386.261426) (xy 159.572084 -386.224084) (xy 159.539376 -386.180823)
			(xy 159.514166 -386.132803) (xy 159.497133 -386.081313) (xy 159.492442 -386.0546) (xy 159.490918 -386.045202)
			(xy 159.218122 -385.57327) (xy 159.210756 -385.567428) (xy 159.191977 -385.551625) (xy 159.158841 -385.515419)
			(xy 159.13142 -385.474715) (xy 159.110313 -385.430405) (xy 159.095986 -385.383463) (xy 159.088752 -385.33492)
			(xy 159.088328 -385.31038) (xy 159.08876 -385.285968) (xy 159.09593 -385.237674) (xy 159.110125 -385.190959)
			(xy 159.131036 -385.146841) (xy 159.15821 -385.106278) (xy 159.191054 -385.070153) (xy 159.228854 -385.039252)
			(xy 159.249618 -385.026408) (xy 159.261302 -385.019296) (xy 159.27451 -384.996436) (xy 159.27451 -384.98272)
			(xy 159.274094 -384.972695) (xy 159.266428 -384.95417) (xy 159.252255 -384.939989) (xy 159.233734 -384.932312)
			(xy 159.22371 -384.93192) (xy 159.193484 -384.93192) (xy 159.186372 -384.934206) (xy 159.162868 -384.940876)
			(xy 159.114535 -384.948011) (xy 159.090106 -384.94843) (xy 159.065678 -384.94801) (xy 159.017346 -384.94087)
			(xy 158.99384 -384.934206) (xy 158.986728 -384.93192) (xy 158.550864 -384.93192) (xy 158.54125 -384.932339)
			(xy 158.523378 -384.939434) (xy 158.509376 -384.952614) (xy 158.50489 -384.96113) (xy 158.459424 -385.058158)
			(xy 158.463234 -385.087114) (xy 158.472886 -385.098544) (xy 158.491442 -385.121805) (xy 158.520739 -385.173591)
			(xy 158.540315 -385.229777) (xy 158.54553 -385.259072) (xy 158.547054 -385.26847) (xy 158.81985 -385.740402)
			(xy 158.827216 -385.746244) (xy 158.845993 -385.762049) (xy 158.879125 -385.798256) (xy 158.906544 -385.838961)
			(xy 158.927649 -385.88327) (xy 158.941977 -385.930211) (xy 158.949214 -385.978753) (xy 158.949644 -386.003292)
			(xy 158.94939 -386.015484) (xy 158.949136 -386.025136) (xy 158.955232 -386.04317) (xy 159.013906 -386.11048)
			(xy 159.03067 -386.119116) (xy 159.040576 -386.120132) (xy 159.067345 -386.123457) (xy 159.119377 -386.137678)
			(xy 159.168411 -386.160153) (xy 159.213148 -386.190287) (xy 159.252403 -386.227281) (xy 159.285135 -386.270155)
			(xy 159.310476 -386.317771) (xy 159.327755 -386.368868) (xy 159.336513 -386.422092) (xy 159.336994 -386.449062)
			(xy 159.336527 -386.473259) (xy 159.329431 -386.521132) (xy 159.315443 -386.567463) (xy 159.294861 -386.611264)
			(xy 159.281876 -386.631688) (xy 159.277126 -386.639659) (xy 159.273106 -386.657757) (xy 159.274002 -386.666994)
			(xy 159.27832 -386.697982) (xy 159.280125 -386.707234) (xy 159.289385 -386.723636) (xy 159.296354 -386.729986)
			(xy 159.318448 -386.748661) (xy 159.35822 -386.790672) (xy 159.39238 -386.837361) (xy 159.420384 -386.887983)
			(xy 159.441786 -386.94173) (xy 159.456243 -386.997745) (xy 159.463526 -387.055136) (xy 159.463994 -387.084062)
			(xy 159.46339 -387.117382) (xy 159.453721 -387.183317) (xy 159.434596 -387.247154) (xy 159.421068 -387.27761)
			(xy 159.416806 -387.288079) (xy 159.41688 -387.310653) (xy 159.426636 -387.331011) (xy 159.435038 -387.33857)
			(xy 159.457285 -387.357244) (xy 159.497348 -387.3993) (xy 159.531769 -387.446087) (xy 159.559996 -387.496851)
			(xy 159.581573 -387.550779) (xy 159.596155 -387.607003) (xy 159.603508 -387.66462) (xy 159.603948 -387.693662)
			(xy 159.603497 -387.722666) (xy 159.596167 -387.78021) (xy 159.581632 -387.836368) (xy 159.560123 -387.890242)
			(xy 159.531986 -387.94097) (xy 159.497671 -387.987741) (xy 159.457726 -388.029805) (xy 159.435546 -388.0485)
			(xy 159.428434 -388.054088) (xy 159.41929 -388.069328) (xy 159.40405 -388.152132) (xy 159.406844 -388.169404)
			(xy 159.411416 -388.177532) (xy 159.424009 -388.200711) (xy 159.441895 -388.250331) (xy 159.450976 -388.302289)
			(xy 159.451548 -388.328662) (xy 160.040828 -388.328662) (xy 160.04135 -388.303407) (xy 160.049663 -388.253585)
			(xy 160.066064 -388.205811) (xy 160.090105 -388.161388) (xy 160.121129 -388.121528) (xy 160.158291 -388.087318)
			(xy 160.200577 -388.059692) (xy 160.246833 -388.039402) (xy 160.295798 -388.027002) (xy 160.346136 -388.022831)
			(xy 160.396474 -388.027002) (xy 160.445439 -388.039402) (xy 160.491695 -388.059692) (xy 160.533981 -388.087318)
			(xy 160.571143 -388.121528) (xy 160.602167 -388.161388) (xy 160.626208 -388.205811) (xy 160.642609 -388.253585)
			(xy 160.650922 -388.303407) (xy 160.651444 -388.328662) (xy 160.651375 -388.338021) (xy 160.650232 -388.356703)
			(xy 160.649158 -388.366) (xy 160.648142 -388.37489) (xy 160.651952 -388.391654) (xy 160.695894 -388.461504)
			(xy 160.70961 -388.471918) (xy 160.717992 -388.474712) (xy 160.742011 -388.483205) (xy 160.787184 -388.506752)
			(xy 160.827991 -388.537245) (xy 160.863372 -388.573896) (xy 160.89241 -388.615751) (xy 160.91435 -388.661726)
			(xy 160.921954 -388.68604) (xy 160.923478 -388.691882) (xy 161.243772 -389.245602) (xy 161.247836 -389.24992)
			(xy 161.264034 -389.267633) (xy 161.291458 -389.307023) (xy 161.312601 -389.350112) (xy 161.326976 -389.395904)
			(xy 161.334252 -389.443346) (xy 161.334704 -389.467344) (xy 161.334247 -389.492148) (xy 161.326477 -389.541143)
			(xy 161.311136 -389.588319) (xy 161.288601 -389.632512) (xy 161.259428 -389.672635) (xy 161.224335 -389.707698)
			(xy 161.184188 -389.736838) (xy 161.139976 -389.759336) (xy 161.092788 -389.774638) (xy 161.043786 -389.782367)
			(xy 161.018982 -389.782812) (xy 160.993587 -389.782327) (xy 160.943453 -389.774194) (xy 160.895267 -389.75814)
			(xy 160.850272 -389.734579) (xy 160.80963 -389.70412) (xy 160.774387 -389.667547) (xy 160.745454 -389.625804)
			(xy 160.723576 -389.579967) (xy 160.71596 -389.555736) (xy 160.714436 -389.549894) (xy 160.394142 -388.996174)
			(xy 160.390078 -388.991856) (xy 160.373923 -388.974118) (xy 160.346553 -388.934718) (xy 160.325461 -388.891629)
			(xy 160.311133 -388.845845) (xy 160.303898 -388.798419) (xy 160.303464 -388.774432) (xy 160.303544 -388.762384)
			(xy 160.305327 -388.738355) (xy 160.30702 -388.726426) (xy 160.30829 -388.717536) (xy 160.305242 -388.700518)
			(xy 160.263078 -388.629652) (xy 160.24987 -388.618476) (xy 160.241488 -388.615428) (xy 160.219744 -388.607023)
			(xy 160.178885 -388.584584) (xy 160.141914 -388.556193) (xy 160.10969 -388.522509) (xy 160.082964 -388.484316)
			(xy 160.062358 -388.442504) (xy 160.04835 -388.398043) (xy 160.041266 -388.35197) (xy 160.040828 -388.328662)
			(xy 159.451548 -388.328662) (xy 159.451476 -388.33802) (xy 159.45033 -388.356702) (xy 159.449262 -388.366)
			(xy 159.448246 -388.37489) (xy 159.452056 -388.391654) (xy 159.495998 -388.461504) (xy 159.509714 -388.471918)
			(xy 159.518096 -388.474712) (xy 159.542132 -388.483165) (xy 159.587316 -388.506709) (xy 159.62813 -388.537205)
			(xy 159.663516 -388.573862) (xy 159.692555 -388.615726) (xy 159.714491 -388.661711) (xy 159.722058 -388.68604)
			(xy 159.723582 -388.691882) (xy 160.043876 -389.245602) (xy 160.04794 -389.24992) (xy 160.064155 -389.267619)
			(xy 160.091584 -389.307009) (xy 160.112729 -389.3501) (xy 160.1271 -389.395898) (xy 160.134366 -389.443344)
			(xy 160.134808 -389.467344) (xy 160.134343 -389.492147) (xy 160.126573 -389.541141) (xy 160.111232 -389.588316)
			(xy 160.088698 -389.632509) (xy 160.059526 -389.672631) (xy 160.024434 -389.707694) (xy 159.984289 -389.736833)
			(xy 159.940077 -389.759331) (xy 159.89289 -389.774633) (xy 159.84389 -389.782363) (xy 159.819086 -389.782812)
			(xy 159.793693 -389.782303) (xy 159.743562 -389.774171) (xy 159.695379 -389.758118) (xy 159.650388 -389.73456)
			(xy 159.609748 -389.704103) (xy 159.574508 -389.667533) (xy 159.545576 -389.625793) (xy 159.5237 -389.57996)
			(xy 159.516064 -389.555736) (xy 159.51454 -389.549894) (xy 159.194246 -388.996174) (xy 159.190182 -388.991856)
			(xy 159.173994 -388.974146) (xy 159.14662 -388.934743) (xy 159.125532 -388.891648) (xy 159.111216 -388.845855)
			(xy 159.104003 -388.798422) (xy 159.103568 -388.774432) (xy 159.103654 -388.762384) (xy 159.105437 -388.738355)
			(xy 159.107124 -388.726426) (xy 159.108394 -388.717536) (xy 159.105346 -388.700518) (xy 159.063182 -388.629652)
			(xy 159.049974 -388.618476) (xy 159.041592 -388.615428) (xy 159.019851 -388.607023) (xy 158.979005 -388.584571)
			(xy 158.942046 -388.556172) (xy 158.909832 -388.522486) (xy 158.883112 -388.484295) (xy 158.862507 -388.442488)
			(xy 158.848495 -388.398034) (xy 158.841402 -388.351967) (xy 158.840932 -388.328662) (xy 158.841514 -388.302291)
			(xy 158.850615 -388.25034) (xy 158.868489 -388.200719) (xy 158.881064 -388.177532) (xy 158.885636 -388.169404)
			(xy 158.88843 -388.152132) (xy 158.87319 -388.069328) (xy 158.864046 -388.054088) (xy 158.856934 -388.0485)
			(xy 158.834745 -388.029815) (xy 158.794796 -387.987754) (xy 158.760479 -387.940984) (xy 158.732346 -387.890254)
			(xy 158.710847 -387.836376) (xy 158.696325 -387.780213) (xy 158.689015 -387.722667) (xy 158.688532 -387.693662)
			(xy 158.689135 -387.660342) (xy 158.698801 -387.594406) (xy 158.717923 -387.530568) (xy 158.731458 -387.500114)
			(xy 158.735725 -387.489643) (xy 158.735658 -387.467062) (xy 158.725911 -387.446693) (xy 158.717488 -387.439154)
			(xy 158.695243 -387.420479) (xy 158.655185 -387.378422) (xy 158.62077 -387.331635) (xy 158.59255 -387.280869)
			(xy 158.57098 -387.226942) (xy 158.556406 -387.170718) (xy 158.549063 -387.113103) (xy 158.548578 -387.084062)
			(xy 158.549023 -387.055136) (xy 158.556316 -386.997746) (xy 158.570781 -386.941732) (xy 158.592187 -386.887986)
			(xy 158.620194 -386.837365) (xy 158.654355 -386.790677) (xy 158.694126 -386.748663) (xy 158.716218 -386.729986)
			(xy 158.723283 -386.723716) (xy 158.732555 -386.707274) (xy 158.734252 -386.697982) (xy 158.73857 -386.666994)
			(xy 158.739518 -386.657756) (xy 158.735482 -386.639646) (xy 158.730696 -386.631688) (xy 158.717664 -386.61129)
			(xy 158.697065 -386.567488) (xy 158.68308 -386.521148) (xy 158.676007 -386.473264) (xy 158.675578 -386.449062)
			(xy 158.675832 -386.43687) (xy 158.676086 -386.427218) (xy 158.66999 -386.409184) (xy 158.611316 -386.341874)
			(xy 158.594552 -386.333238) (xy 158.584646 -386.332222) (xy 158.557733 -386.32887) (xy 158.505435 -386.314524)
			(xy 158.45618 -386.291834) (xy 158.411288 -386.26141) (xy 158.371963 -386.224068) (xy 158.33926 -386.180808)
			(xy 158.314056 -386.132791) (xy 158.297026 -386.081304) (xy 158.292292 -386.0546) (xy 158.290768 -386.045202)
			(xy 158.017972 -385.57327) (xy 158.010606 -385.567428) (xy 157.991829 -385.551624) (xy 157.958699 -385.515416)
			(xy 157.931281 -385.474711) (xy 157.910178 -385.430401) (xy 157.895853 -385.383461) (xy 157.88862 -385.334919)
			(xy 157.888178 -385.31038) (xy 157.88861 -385.285969) (xy 157.89578 -385.237676) (xy 157.909977 -385.190963)
			(xy 157.93089 -385.146847) (xy 157.958066 -385.106287) (xy 157.990913 -385.070166) (xy 158.028716 -385.03927)
			(xy 158.049468 -385.026408) (xy 158.061152 -385.019296) (xy 158.07436 -384.996436) (xy 158.07436 -384.98272)
			(xy 158.073943 -384.972699) (xy 158.066275 -384.954182) (xy 158.052101 -384.940013) (xy 158.033581 -384.932353)
			(xy 158.02356 -384.93192) (xy 157.993588 -384.93192) (xy 157.986476 -384.934206) (xy 157.962972 -384.940877)
			(xy 157.914639 -384.948012) (xy 157.89021 -384.94843) (xy 157.865781 -384.948011) (xy 157.817449 -384.940871)
			(xy 157.793944 -384.934206) (xy 157.786832 -384.93192) (xy 157.350968 -384.93192) (xy 157.341353 -384.932338)
			(xy 157.32348 -384.939433) (xy 157.309477 -384.952613) (xy 157.304994 -384.96113) (xy 157.259528 -385.058158)
			(xy 157.263338 -385.087114) (xy 157.27299 -385.098544) (xy 157.291546 -385.121806) (xy 157.320843 -385.173591)
			(xy 157.340418 -385.229777) (xy 157.345634 -385.259072) (xy 157.347158 -385.26847) (xy 157.619954 -385.740402)
			(xy 157.62732 -385.746244) (xy 157.646097 -385.762049) (xy 157.679228 -385.798257) (xy 157.706647 -385.838962)
			(xy 157.727752 -385.88327) (xy 157.74208 -385.930211) (xy 157.749316 -385.978753) (xy 157.749748 -386.003292)
			(xy 157.749494 -386.015484) (xy 157.74924 -386.025136) (xy 157.755336 -386.04317) (xy 157.81401 -386.11048)
			(xy 157.830774 -386.119116) (xy 157.840426 -386.120132) (xy 157.867193 -386.12346) (xy 157.919218 -386.137687)
			(xy 157.968245 -386.160166) (xy 158.012975 -386.190302) (xy 158.052223 -386.227296) (xy 158.084949 -386.270168)
			(xy 158.110286 -386.317782) (xy 158.127562 -386.368875) (xy 158.136319 -386.422095) (xy 158.136844 -386.449062)
			(xy 158.136281 -386.476344) (xy 158.127318 -386.530167) (xy 158.109645 -386.58179) (xy 158.08374 -386.629814)
			(xy 158.050307 -386.672936) (xy 158.030672 -386.691886) (xy 158.023231 -386.699381) (xy 158.014702 -386.718676)
			(xy 158.014162 -386.729224) (xy 158.014162 -386.8039) (xy 158.014754 -386.814432) (xy 158.023296 -386.833695)
			(xy 158.030672 -386.841238) (xy 158.050325 -386.860172) (xy 158.083763 -386.903294) (xy 158.109667 -386.951321)
			(xy 158.127334 -387.002949) (xy 158.136283 -387.056778) (xy 158.136844 -387.084062) (xy 158.136411 -387.10818)
			(xy 158.129416 -387.155905) (xy 158.115569 -387.20211) (xy 158.095163 -387.245817) (xy 158.082234 -387.26618)
			(xy 158.076392 -387.27507) (xy 158.072836 -387.295136) (xy 158.093918 -387.387338) (xy 158.10611 -387.404102)
			(xy 158.115 -387.409436) (xy 158.135803 -387.42229) (xy 158.173723 -387.453166) (xy 158.206676 -387.489296)
			(xy 158.233941 -387.52989) (xy 158.254923 -387.574061) (xy 158.269163 -387.620842) (xy 158.27635 -387.669212)
			(xy 158.276798 -387.693662) (xy 158.276361 -387.718033) (xy 158.269205 -387.766247) (xy 158.255059 -387.812892)
			(xy 158.234227 -387.856958) (xy 158.207159 -387.897494) (xy 158.174441 -387.933623) (xy 158.155894 -387.94944)
			(xy 158.147004 -387.956552) (xy 158.137606 -387.97611) (xy 158.134812 -388.075424) (xy 158.143448 -388.09549)
			(xy 158.15183 -388.10311) (xy 158.17025 -388.120599) (xy 158.201589 -388.160568) (xy 158.225883 -388.20517)
			(xy 158.242464 -388.253178) (xy 158.250873 -388.303267) (xy 158.251398 -388.328662) (xy 158.251326 -388.33802)
			(xy 158.25018 -388.356702) (xy 158.249112 -388.366) (xy 158.248096 -388.37489) (xy 158.251906 -388.391654)
			(xy 158.295848 -388.461504) (xy 158.309564 -388.471918) (xy 158.317946 -388.474712) (xy 158.34198 -388.483168)
			(xy 158.387157 -388.506717) (xy 158.427966 -388.537216) (xy 158.463346 -388.573873) (xy 158.492379 -388.615737)
			(xy 158.514312 -388.661721) (xy 158.521908 -388.68604) (xy 158.523432 -388.691882) (xy 158.843726 -389.245602)
			(xy 158.84779 -389.24992) (xy 158.863981 -389.267628) (xy 158.89136 -389.30703) (xy 158.912453 -389.350125)
			(xy 158.926774 -389.395919) (xy 158.933991 -389.443353) (xy 158.934404 -389.467344) (xy 158.933915 -389.492132)
			(xy 158.926154 -389.541098) (xy 158.910829 -389.588247) (xy 158.888319 -389.632419) (xy 158.859177 -389.672526)
			(xy 158.82412 -389.707582) (xy 158.784012 -389.736723) (xy 158.73984 -389.759232) (xy 158.69269 -389.774556)
			(xy 158.643724 -389.782315) (xy 158.618936 -389.782812) (xy 158.593541 -389.782307) (xy 158.543404 -389.774181)
			(xy 158.495215 -389.758134) (xy 158.450217 -389.734578) (xy 158.40957 -389.704122) (xy 158.374324 -389.667552)
			(xy 158.345387 -389.625811) (xy 158.323506 -389.579975) (xy 158.315914 -389.555736) (xy 158.31439 -389.549894)
			(xy 157.994096 -388.996174) (xy 157.990032 -388.991856) (xy 157.973815 -388.974158) (xy 157.946383 -388.934769)
			(xy 157.925237 -388.891678) (xy 157.910865 -388.84588) (xy 157.903601 -388.798432) (xy 157.903164 -388.774432)
			(xy 157.903322 -388.76238) (xy 157.905231 -388.738352) (xy 157.906974 -388.726426) (xy 157.908244 -388.717536)
			(xy 157.905196 -388.700518) (xy 157.863032 -388.629652) (xy 157.849824 -388.618476) (xy 157.841442 -388.615428)
			(xy 157.819704 -388.60702) (xy 157.778864 -388.584565) (xy 157.741911 -388.556163) (xy 157.709702 -388.522476)
			(xy 157.682987 -388.484286) (xy 157.662386 -388.44248) (xy 157.648376 -388.398029) (xy 157.641285 -388.351965)
			(xy 157.640782 -388.328662) (xy 157.641281 -388.303264) (xy 157.649681 -388.253167) (xy 157.666258 -388.205152)
			(xy 157.690555 -388.160543) (xy 157.721902 -388.120573) (xy 157.74035 -388.10311) (xy 157.748732 -388.09549)
			(xy 157.757368 -388.075424) (xy 157.754574 -387.97611) (xy 157.745176 -387.956552) (xy 157.736286 -387.94944)
			(xy 157.717726 -387.933637) (xy 157.685 -387.89751) (xy 157.657929 -387.856973) (xy 157.637097 -387.812903)
			(xy 157.622955 -387.766254) (xy 157.61581 -387.718035) (xy 157.615382 -387.693662) (xy 157.615821 -387.669546)
			(xy 157.622826 -387.621825) (xy 157.636683 -387.575627) (xy 157.657097 -387.531928) (xy 157.669992 -387.511544)
			(xy 157.675834 -387.502654) (xy 157.67939 -387.482588) (xy 157.658308 -387.390386) (xy 157.646116 -387.373622)
			(xy 157.637226 -387.368288) (xy 157.616425 -387.355431) (xy 157.578511 -387.324552) (xy 157.545563 -387.28842)
			(xy 157.518301 -387.247827) (xy 157.497321 -387.203658) (xy 157.483082 -387.156879) (xy 157.475894 -387.108511)
			(xy 157.475428 -387.084062) (xy 157.475989 -387.05678) (xy 157.484951 -387.002956) (xy 157.502624 -386.951333)
			(xy 157.52853 -386.90331) (xy 157.561966 -386.86019) (xy 157.5816 -386.841238) (xy 157.589049 -386.833746)
			(xy 157.597592 -386.814451) (xy 157.59811 -386.8039) (xy 157.59811 -386.729224) (xy 157.597524 -386.718688)
			(xy 157.588997 -386.699411) (xy 157.5816 -386.691886) (xy 157.561942 -386.672955) (xy 157.528494 -386.629836)
			(xy 157.50258 -386.581809) (xy 157.484906 -386.530179) (xy 157.47595 -386.476348) (xy 157.475428 -386.449062)
			(xy 157.475682 -386.43687) (xy 157.475936 -386.427218) (xy 157.46984 -386.409184) (xy 157.411166 -386.341874)
			(xy 157.394402 -386.333238) (xy 157.38475 -386.332222) (xy 157.357837 -386.32887) (xy 157.305539 -386.314524)
			(xy 157.256283 -386.291835) (xy 157.21139 -386.261412) (xy 157.172065 -386.224069) (xy 157.139361 -386.180809)
			(xy 157.114156 -386.132792) (xy 157.097126 -386.081305) (xy 157.092396 -386.0546) (xy 157.090872 -386.045202)
			(xy 156.818076 -385.57327) (xy 156.81071 -385.567428) (xy 156.791933 -385.551624) (xy 156.758802 -385.515416)
			(xy 156.731384 -385.474711) (xy 156.710281 -385.430402) (xy 156.695956 -385.383461) (xy 156.688722 -385.334919)
			(xy 156.688282 -385.31038) (xy 156.688714 -385.285969) (xy 156.695884 -385.237676) (xy 156.710081 -385.190963)
			(xy 156.730995 -385.146847) (xy 156.758171 -385.106288) (xy 156.791018 -385.070167) (xy 156.828821 -385.039271)
			(xy 156.849572 -385.026408) (xy 156.861256 -385.019296) (xy 156.874464 -384.996436) (xy 156.874464 -384.98272)
			(xy 156.874047 -384.972699) (xy 156.86638 -384.954181) (xy 156.852205 -384.940011) (xy 156.833685 -384.93235)
			(xy 156.823664 -384.93192) (xy 156.793438 -384.93192) (xy 156.786326 -384.934206) (xy 156.762822 -384.94088)
			(xy 156.714489 -384.948023) (xy 156.69006 -384.94843) (xy 156.665632 -384.948007) (xy 156.617302 -384.94086)
			(xy 156.593794 -384.934206) (xy 156.586682 -384.93192) (xy 156.151072 -384.93192) (xy 156.141457 -384.932337)
			(xy 156.123583 -384.939431) (xy 156.109578 -384.952611) (xy 156.105098 -384.96113) (xy 156.059632 -385.058158)
			(xy 156.063442 -385.087114) (xy 156.073094 -385.098544) (xy 156.091719 -385.121874) (xy 156.121124 -385.173821)
			(xy 156.140768 -385.230188) (xy 156.145992 -385.25958) (xy 156.147262 -385.268978) (xy 156.419804 -385.740402)
			(xy 156.42717 -385.746244) (xy 156.44595 -385.762047) (xy 156.479085 -385.798253) (xy 156.506508 -385.838958)
			(xy 156.527617 -385.883267) (xy 156.541947 -385.930208) (xy 156.549185 -385.978752) (xy 156.549598 -386.003292)
			(xy 156.549344 -386.015484) (xy 156.54909 -386.025136) (xy 156.555186 -386.04317) (xy 156.61386 -386.11048)
			(xy 156.630624 -386.119116) (xy 156.64053 -386.120132) (xy 156.667296 -386.12346) (xy 156.719321 -386.137688)
			(xy 156.768347 -386.160167) (xy 156.813077 -386.190303) (xy 156.852325 -386.227298) (xy 156.885051 -386.270169)
			(xy 156.910387 -386.317783) (xy 156.927662 -386.368876) (xy 156.936419 -386.422095) (xy 156.936948 -386.449062)
			(xy 156.936385 -386.476344) (xy 156.927422 -386.530167) (xy 156.909749 -386.581791) (xy 156.883845 -386.629814)
			(xy 156.850412 -386.672937) (xy 156.830776 -386.691886) (xy 156.823334 -386.699381) (xy 156.814804 -386.718676)
			(xy 156.814266 -386.729224) (xy 156.814266 -386.8039) (xy 156.814858 -386.814431) (xy 156.8234 -386.833694)
			(xy 156.830776 -386.841238) (xy 156.850429 -386.860172) (xy 156.883866 -386.903294) (xy 156.90977 -386.951321)
			(xy 156.927436 -387.00295) (xy 156.936386 -387.056778) (xy 156.936948 -387.084062) (xy 156.936515 -387.108179)
			(xy 156.929518 -387.155904) (xy 156.915668 -387.202107) (xy 156.895257 -387.24581) (xy 156.882338 -387.26618)
			(xy 156.876496 -387.27507) (xy 156.87294 -387.295136) (xy 156.894022 -387.387338) (xy 156.906214 -387.404102)
			(xy 156.915104 -387.409436) (xy 156.935907 -387.42229) (xy 156.973827 -387.453167) (xy 157.006779 -387.489297)
			(xy 157.034044 -387.529891) (xy 157.055026 -387.574061) (xy 157.069265 -387.620842) (xy 157.076452 -387.669212)
			(xy 157.076902 -387.693662) (xy 157.076464 -387.718032) (xy 157.069308 -387.766244) (xy 157.055158 -387.812886)
			(xy 157.034322 -387.856948) (xy 157.007249 -387.897479) (xy 156.974525 -387.933601) (xy 156.955998 -387.94944)
			(xy 156.947108 -387.956552) (xy 156.93771 -387.97611) (xy 156.934916 -388.075424) (xy 156.943552 -388.09549)
			(xy 156.951934 -388.10311) (xy 156.970354 -388.120599) (xy 157.001692 -388.160568) (xy 157.025986 -388.205171)
			(xy 157.042566 -388.253178) (xy 157.050976 -388.303267) (xy 157.051502 -388.328662) (xy 157.05143 -388.33802)
			(xy 157.050284 -388.356702) (xy 157.049216 -388.366) (xy 157.0482 -388.37489) (xy 157.05201 -388.391654)
			(xy 157.095952 -388.461504) (xy 157.109668 -388.471918) (xy 157.11805 -388.474712) (xy 157.142084 -388.483168)
			(xy 157.18726 -388.506717) (xy 157.228068 -388.537217) (xy 157.263448 -388.573874) (xy 157.292481 -388.615738)
			(xy 157.314414 -388.661722) (xy 157.322012 -388.68604) (xy 157.323536 -388.691882) (xy 157.64383 -389.245602)
			(xy 157.647894 -389.24992) (xy 157.664085 -389.267628) (xy 157.691463 -389.307031) (xy 157.712556 -389.350126)
			(xy 157.726877 -389.395919) (xy 157.734094 -389.443353) (xy 157.734508 -389.467344) (xy 157.734019 -389.492132)
			(xy 157.726258 -389.541098) (xy 157.710933 -389.588248) (xy 157.688423 -389.63242) (xy 157.659281 -389.672528)
			(xy 157.624225 -389.707584) (xy 157.584117 -389.736725) (xy 157.539944 -389.759235) (xy 157.492794 -389.774559)
			(xy 157.443829 -389.782319) (xy 157.41904 -389.782812) (xy 157.393644 -389.782307) (xy 157.343507 -389.774182)
			(xy 157.295318 -389.758135) (xy 157.250319 -389.73458) (xy 157.209672 -389.704124) (xy 157.174425 -389.667554)
			(xy 157.145488 -389.625812) (xy 157.123606 -389.579976) (xy 157.116018 -389.555736) (xy 157.114494 -389.549894)
			(xy 156.7942 -388.996174) (xy 156.790136 -388.991856) (xy 156.773919 -388.974158) (xy 156.746486 -388.934769)
			(xy 156.72534 -388.891678) (xy 156.710968 -388.84588) (xy 156.703704 -388.798432) (xy 156.703268 -388.774432)
			(xy 156.703426 -388.76238) (xy 156.705335 -388.738352) (xy 156.707078 -388.726426) (xy 156.708348 -388.717536)
			(xy 156.7053 -388.700518) (xy 156.663136 -388.629652) (xy 156.649928 -388.618476) (xy 156.641546 -388.615428)
			(xy 156.619808 -388.607021) (xy 156.578967 -388.584565) (xy 156.542013 -388.556164) (xy 156.509805 -388.522477)
			(xy 156.483089 -388.484287) (xy 156.462487 -388.442481) (xy 156.448478 -388.398029) (xy 156.441386 -388.351965)
			(xy 156.440886 -388.328662) (xy 156.441385 -388.303264) (xy 156.449785 -388.253167) (xy 156.466362 -388.205152)
			(xy 156.490659 -388.160544) (xy 156.522007 -388.120574) (xy 156.540454 -388.10311) (xy 156.548836 -388.09549)
			(xy 156.557472 -388.075424) (xy 156.554678 -387.97611) (xy 156.54528 -387.956552) (xy 156.53639 -387.94944)
			(xy 156.517829 -387.933637) (xy 156.485104 -387.89751) (xy 156.458032 -387.856973) (xy 156.437199 -387.812903)
			(xy 156.423058 -387.766254) (xy 156.415912 -387.718035) (xy 156.415486 -387.693662) (xy 156.415925 -387.669546)
			(xy 156.42293 -387.621826) (xy 156.436787 -387.575627) (xy 156.457202 -387.531928) (xy 156.470096 -387.511544)
			(xy 156.475938 -387.502654) (xy 156.479494 -387.482588) (xy 156.458412 -387.390386) (xy 156.44622 -387.373622)
			(xy 156.43733 -387.368288) (xy 156.416529 -387.355432) (xy 156.378614 -387.324552) (xy 156.345666 -387.288421)
			(xy 156.318404 -387.247827) (xy 156.297424 -387.203658) (xy 156.283184 -387.156879) (xy 156.275996 -387.108511)
			(xy 156.275532 -387.084062) (xy 156.276093 -387.056779) (xy 156.285052 -387.002953) (xy 156.302722 -386.951327)
			(xy 156.328623 -386.903299) (xy 156.362053 -386.860172) (xy 156.381704 -386.841238) (xy 156.389152 -386.833746)
			(xy 156.397694 -386.814451) (xy 156.398214 -386.8039) (xy 156.398214 -386.729224) (xy 156.397628 -386.718688)
			(xy 156.389102 -386.69941) (xy 156.381704 -386.691886) (xy 156.362046 -386.672955) (xy 156.328597 -386.629836)
			(xy 156.302683 -386.58181) (xy 156.285009 -386.53018) (xy 156.276053 -386.476348) (xy 156.275532 -386.449062)
			(xy 156.275786 -386.43687) (xy 156.27604 -386.427218) (xy 156.269944 -386.409184) (xy 156.21127 -386.341874)
			(xy 156.194506 -386.333238) (xy 156.1846 -386.332222) (xy 156.157685 -386.328874) (xy 156.10538 -386.314534)
			(xy 156.056117 -386.291849) (xy 156.011218 -386.261427) (xy 155.971886 -386.224085) (xy 155.939177 -386.180824)
			(xy 155.913967 -386.132804) (xy 155.896934 -386.081314) (xy 155.892246 -386.0546) (xy 155.890722 -386.045202)
			(xy 155.617672 -385.572762) (xy 155.61056 -385.56692) (xy 155.591827 -385.55114) (xy 155.558774 -385.514996)
			(xy 155.531416 -385.47437) (xy 155.510353 -385.430152) (xy 155.496045 -385.38331) (xy 155.488806 -385.334869)
			(xy 155.488386 -385.31038) (xy 155.488818 -385.285969) (xy 155.495988 -385.237676) (xy 155.510185 -385.190963)
			(xy 155.531099 -385.146848) (xy 155.558275 -385.106288) (xy 155.591122 -385.070168) (xy 155.628926 -385.039273)
			(xy 155.649676 -385.026408) (xy 155.66136 -385.019296) (xy 155.674568 -384.996436) (xy 155.674568 -384.98272)
			(xy 155.674151 -384.972698) (xy 155.666484 -384.95418) (xy 155.65231 -384.940009) (xy 155.63379 -384.932346)
			(xy 155.623768 -384.93192) (xy 155.593542 -384.93192) (xy 155.58643 -384.934206) (xy 155.562926 -384.940881)
			(xy 155.514594 -384.948024) (xy 155.490164 -384.94843) (xy 155.465736 -384.948007) (xy 155.417406 -384.940861)
			(xy 155.393898 -384.934206) (xy 155.386786 -384.93192) (xy 154.950922 -384.93192) (xy 154.941302 -384.932329)
			(xy 154.923413 -384.939412) (xy 154.909394 -384.95259) (xy 154.904948 -384.96113) (xy 154.859482 -385.058158)
			(xy 154.863292 -385.087114) (xy 154.872944 -385.098544) (xy 154.891502 -385.121804) (xy 154.920803 -385.173589)
			(xy 154.940382 -385.229775) (xy 154.945588 -385.259072) (xy 154.947112 -385.26847) (xy 155.219908 -385.740402)
			(xy 155.227274 -385.746244) (xy 155.246053 -385.762047) (xy 155.279189 -385.798254) (xy 155.306611 -385.838958)
			(xy 155.327719 -385.883267) (xy 155.342049 -385.930208) (xy 155.349287 -385.978752) (xy 155.349702 -386.003292)
			(xy 155.349448 -386.015484) (xy 155.349194 -386.025136) (xy 155.35529 -386.04317) (xy 155.413964 -386.11048)
			(xy 155.430728 -386.119116) (xy 155.440634 -386.120132) (xy 155.4674 -386.123461) (xy 155.519424 -386.137689)
			(xy 155.56845 -386.160168) (xy 155.613179 -386.190305) (xy 155.652427 -386.227299) (xy 155.685152 -386.27017)
			(xy 155.710488 -386.317783) (xy 155.727763 -386.368876) (xy 155.736519 -386.422095) (xy 155.737052 -386.449062)
			(xy 155.736489 -386.476344) (xy 155.727526 -386.530168) (xy 155.709853 -386.581791) (xy 155.683949 -386.629815)
			(xy 155.650517 -386.672937) (xy 155.63088 -386.691886) (xy 155.623438 -386.699381) (xy 155.614907 -386.718675)
			(xy 155.61437 -386.729224) (xy 155.61437 -386.8039) (xy 155.61496 -386.814434) (xy 155.62349 -386.833707)
			(xy 155.63088 -386.841238) (xy 155.650532 -386.860172) (xy 155.68397 -386.903294) (xy 155.709873 -386.951321)
			(xy 155.727539 -387.00295) (xy 155.736489 -387.056778) (xy 155.737052 -387.084062) (xy 155.736619 -387.108179)
			(xy 155.729622 -387.155904) (xy 155.715772 -387.202107) (xy 155.695361 -387.245811) (xy 155.682442 -387.26618)
			(xy 155.6766 -387.27507) (xy 155.673044 -387.295136) (xy 155.694126 -387.387338) (xy 155.706318 -387.404102)
			(xy 155.715208 -387.409436) (xy 155.736011 -387.42229) (xy 155.77393 -387.453167) (xy 155.806882 -387.489297)
			(xy 155.834147 -387.529891) (xy 155.855128 -387.574061) (xy 155.869367 -387.620842) (xy 155.876554 -387.669212)
			(xy 155.877006 -387.693662) (xy 155.876568 -387.718032) (xy 155.869412 -387.766245) (xy 155.855262 -387.812886)
			(xy 155.834426 -387.856949) (xy 155.807353 -387.897479) (xy 155.77463 -387.933601) (xy 155.756102 -387.94944)
			(xy 155.747212 -387.956552) (xy 155.737814 -387.97611) (xy 155.73502 -388.075424) (xy 155.743656 -388.09549)
			(xy 155.752038 -388.10311) (xy 155.770458 -388.120599) (xy 155.801796 -388.160568) (xy 155.82609 -388.205171)
			(xy 155.842669 -388.253178) (xy 155.851078 -388.303267) (xy 155.851606 -388.328662) (xy 155.851534 -388.33802)
			(xy 155.850388 -388.356702) (xy 155.84932 -388.366) (xy 155.848304 -388.37489) (xy 155.852114 -388.391654)
			(xy 155.896056 -388.461504) (xy 155.909772 -388.471918) (xy 155.918154 -388.474712) (xy 155.942252 -388.483193)
			(xy 155.987544 -388.506819) (xy 156.028442 -388.537429) (xy 156.063878 -388.574224) (xy 156.092928 -388.616244)
			(xy 156.114834 -388.662393) (xy 156.12237 -388.686802) (xy 156.123894 -388.692644) (xy 156.44368 -389.245602)
			(xy 156.447744 -389.24992) (xy 156.463963 -389.267617) (xy 156.491401 -389.307004) (xy 156.512552 -389.350095)
			(xy 156.526928 -389.395894) (xy 156.534196 -389.443343) (xy 156.534612 -389.467344) (xy 156.534147 -389.492147)
			(xy 156.526377 -389.541142) (xy 156.511036 -389.588317) (xy 156.488502 -389.63251) (xy 156.45933 -389.672632)
			(xy 156.424239 -389.707695) (xy 156.384093 -389.736835) (xy 156.339882 -389.759334) (xy 156.292694 -389.774636)
			(xy 156.243694 -389.782367) (xy 156.21889 -389.782812) (xy 156.193497 -389.782303) (xy 156.143365 -389.774172)
			(xy 156.095182 -389.75812) (xy 156.05019 -389.734561) (xy 156.00955 -389.704104) (xy 155.974309 -389.667534)
			(xy 155.945377 -389.625794) (xy 155.9235 -389.579961) (xy 155.915868 -389.555736) (xy 155.914344 -389.549894)
			(xy 155.593796 -388.995412) (xy 155.589732 -388.991094) (xy 155.573628 -388.973425) (xy 155.546389 -388.93414)
			(xy 155.525379 -388.891199) (xy 155.511077 -388.845584) (xy 155.503811 -388.798334) (xy 155.503372 -388.774432)
			(xy 155.50353 -388.76238) (xy 155.505439 -388.738352) (xy 155.507182 -388.726426) (xy 155.508452 -388.717536)
			(xy 155.505404 -388.700518) (xy 155.46324 -388.629652) (xy 155.450032 -388.618476) (xy 155.44165 -388.615428)
			(xy 155.419911 -388.607021) (xy 155.37907 -388.584566) (xy 155.342116 -388.556165) (xy 155.309907 -388.522478)
			(xy 155.283191 -388.484288) (xy 155.262589 -388.442481) (xy 155.248579 -388.39803) (xy 155.241487 -388.351965)
			(xy 155.24099 -388.328662) (xy 155.24149 -388.303264) (xy 155.249889 -388.253167) (xy 155.266467 -388.205152)
			(xy 155.290764 -388.160544) (xy 155.322112 -388.120575) (xy 155.340558 -388.10311) (xy 155.34894 -388.09549)
			(xy 155.357576 -388.075424) (xy 155.354782 -387.97611) (xy 155.345384 -387.956552) (xy 155.336494 -387.94944)
			(xy 155.317933 -387.933637) (xy 155.285207 -387.897511) (xy 155.258135 -387.856974) (xy 155.237302 -387.812904)
			(xy 155.22316 -387.766254) (xy 155.216015 -387.718035) (xy 155.21559 -387.693662) (xy 155.216029 -387.669546)
			(xy 155.223034 -387.621826) (xy 155.236891 -387.575627) (xy 155.257306 -387.531929) (xy 155.2702 -387.511544)
			(xy 155.276042 -387.502654) (xy 155.279598 -387.482588) (xy 155.258516 -387.390386) (xy 155.246324 -387.373622)
			(xy 155.237434 -387.368288) (xy 155.216633 -387.355432) (xy 155.178718 -387.324553) (xy 155.145769 -387.288421)
			(xy 155.118506 -387.247828) (xy 155.097526 -387.203659) (xy 155.083286 -387.156879) (xy 155.076098 -387.108512)
			(xy 155.075636 -387.084062) (xy 155.076197 -387.056779) (xy 155.085156 -387.002953) (xy 155.102826 -386.951327)
			(xy 155.128727 -386.9033) (xy 155.162158 -386.860173) (xy 155.181808 -386.841238) (xy 155.189256 -386.833745)
			(xy 155.197797 -386.814451) (xy 155.198318 -386.8039) (xy 155.198318 -386.729224) (xy 155.197732 -386.718688)
			(xy 155.189206 -386.69941) (xy 155.181808 -386.691886) (xy 155.162155 -386.672952) (xy 155.128715 -386.62983)
			(xy 155.10281 -386.581803) (xy 155.08514 -386.530175) (xy 155.076187 -386.476346) (xy 155.075636 -386.449062)
			(xy 155.07589 -386.43687) (xy 155.076144 -386.427218) (xy 155.070048 -386.409184) (xy 155.011374 -386.341874)
			(xy 154.99461 -386.333238) (xy 154.984704 -386.332222) (xy 154.957788 -386.328874) (xy 154.905483 -386.314535)
			(xy 154.85622 -386.29185) (xy 154.81132 -386.261429) (xy 154.771988 -386.224086) (xy 154.739278 -386.180825)
			(xy 154.714068 -386.132805) (xy 154.697034 -386.081314) (xy 154.69235 -386.0546) (xy 154.690826 -386.045202)
			(xy 154.41803 -385.57327) (xy 154.410664 -385.567428) (xy 154.391884 -385.551625) (xy 154.358748 -385.51542)
			(xy 154.331326 -385.474715) (xy 154.310219 -385.430406) (xy 154.295891 -385.383464) (xy 154.288657 -385.33492)
			(xy 154.288236 -385.31038) (xy 154.288668 -385.285968) (xy 154.295838 -385.237674) (xy 154.310033 -385.19096)
			(xy 154.330945 -385.146842) (xy 154.358119 -385.106279) (xy 154.390963 -385.070155) (xy 154.428764 -385.039255)
			(xy 154.449526 -385.026408) (xy 154.46121 -385.019296) (xy 154.474418 -384.996436) (xy 154.474418 -384.98272)
			(xy 154.474002 -384.972695) (xy 154.466336 -384.954168) (xy 154.452164 -384.939985) (xy 154.433643 -384.932305)
			(xy 154.423618 -384.93192) (xy 154.393392 -384.93192) (xy 154.38628 -384.934206) (xy 154.362776 -384.940877)
			(xy 154.314443 -384.948013) (xy 154.290014 -384.94843) (xy 154.265585 -384.948011) (xy 154.217253 -384.940872)
			(xy 154.193748 -384.934206) (xy 154.186636 -384.93192) (xy 153.751026 -384.93192) (xy 153.741405 -384.932328)
			(xy 153.723515 -384.939411) (xy 153.709495 -384.952588) (xy 153.705052 -384.96113) (xy 153.659586 -385.058158)
			(xy 153.663396 -385.087114) (xy 153.673048 -385.098544) (xy 153.691606 -385.121805) (xy 153.720906 -385.173589)
			(xy 153.740485 -385.229775) (xy 153.745692 -385.259072) (xy 153.747216 -385.26847) (xy 154.020012 -385.740402)
			(xy 154.027378 -385.746244) (xy 154.046157 -385.762047) (xy 154.079292 -385.798254) (xy 154.106715 -385.838958)
			(xy 154.127822 -385.883267) (xy 154.142152 -385.930209) (xy 154.14939 -385.978752) (xy 154.149806 -386.003292)
			(xy 154.149552 -386.015484) (xy 154.149298 -386.025136) (xy 154.155394 -386.04317) (xy 154.214068 -386.11048)
			(xy 154.230832 -386.119116) (xy 154.240484 -386.120132) (xy 154.267253 -386.123457) (xy 154.319283 -386.137679)
			(xy 154.368316 -386.160155) (xy 154.413052 -386.19029) (xy 154.452306 -386.227284) (xy 154.485037 -386.270157)
			(xy 154.510377 -386.317773) (xy 154.527656 -386.368869) (xy 154.536414 -386.422093) (xy 154.536902 -386.449062)
			(xy 154.536339 -386.476344) (xy 154.527375 -386.530166) (xy 154.5097 -386.581788) (xy 154.483793 -386.629809)
			(xy 154.450357 -386.672928) (xy 154.43073 -386.691886) (xy 154.423282 -386.699378) (xy 154.414743 -386.718673)
			(xy 154.41422 -386.729224) (xy 154.41422 -386.8039) (xy 154.414811 -386.814433) (xy 154.423347 -386.8337)
			(xy 154.43073 -386.841238) (xy 154.450385 -386.860171) (xy 154.483827 -386.903291) (xy 154.509735 -386.951318)
			(xy 154.527404 -387.002947) (xy 154.536355 -387.056777) (xy 154.536902 -387.084062) (xy 154.536469 -387.10818)
			(xy 154.529473 -387.155905) (xy 154.515625 -387.202109) (xy 154.495217 -387.245814) (xy 154.482292 -387.26618)
			(xy 154.47645 -387.27507) (xy 154.472894 -387.295136) (xy 154.493976 -387.387338) (xy 154.506168 -387.404102)
			(xy 154.515058 -387.409436) (xy 154.535858 -387.422292) (xy 154.573772 -387.453172) (xy 154.606719 -387.489303)
			(xy 154.633979 -387.529897) (xy 154.654957 -387.574067) (xy 154.669194 -387.620846) (xy 154.676379 -387.669213)
			(xy 154.676856 -387.693662) (xy 154.676418 -387.718033) (xy 154.669263 -387.766246) (xy 154.655115 -387.812889)
			(xy 154.634281 -387.856954) (xy 154.607211 -387.897487) (xy 154.57449 -387.933613) (xy 154.555952 -387.94944)
			(xy 154.547062 -387.956552) (xy 154.537664 -387.97611) (xy 154.53487 -388.075424) (xy 154.543506 -388.09549)
			(xy 154.551888 -388.10311) (xy 154.57031 -388.120598) (xy 154.601653 -388.160565) (xy 154.625951 -388.205168)
			(xy 154.642534 -388.253176) (xy 154.650944 -388.303266) (xy 154.651456 -388.328662) (xy 154.651384 -388.33802)
			(xy 154.650238 -388.356702) (xy 154.64917 -388.366) (xy 154.648154 -388.37489) (xy 154.651964 -388.391654)
			(xy 154.695906 -388.461504) (xy 154.709622 -388.471918) (xy 154.718004 -388.474712) (xy 154.74204 -388.483165)
			(xy 154.787222 -388.50671) (xy 154.828036 -388.537207) (xy 154.863421 -388.573863) (xy 154.892458 -388.615728)
			(xy 154.914395 -388.661712) (xy 154.921966 -388.68604) (xy 154.92349 -388.691882) (xy 155.243784 -389.245602)
			(xy 155.247848 -389.24992) (xy 155.264067 -389.267617) (xy 155.291504 -389.307005) (xy 155.312655 -389.350096)
			(xy 155.327031 -389.395894) (xy 155.334299 -389.443343) (xy 155.334716 -389.467344) (xy 155.334251 -389.492147)
			(xy 155.326481 -389.541142) (xy 155.31114 -389.588317) (xy 155.288606 -389.632511) (xy 155.259434 -389.672633)
			(xy 155.224343 -389.707697) (xy 155.184197 -389.736837) (xy 155.139986 -389.759336) (xy 155.092799 -389.77464)
			(xy 155.043798 -389.78237) (xy 155.018994 -389.782812) (xy 154.993601 -389.782304) (xy 154.943469 -389.774173)
			(xy 154.895285 -389.758121) (xy 154.850292 -389.734563) (xy 154.809651 -389.704106) (xy 154.77441 -389.667536)
			(xy 154.745478 -389.625796) (xy 154.723601 -389.579962) (xy 154.715972 -389.555736) (xy 154.714448 -389.549894)
			(xy 154.394154 -388.996174) (xy 154.39009 -388.991856) (xy 154.373901 -388.974147) (xy 154.346527 -388.934744)
			(xy 154.325439 -388.891648) (xy 154.311122 -388.845855) (xy 154.303909 -388.798422) (xy 154.303476 -388.774432)
			(xy 154.303562 -388.762384) (xy 154.305345 -388.738355) (xy 154.307032 -388.726426) (xy 154.308302 -388.717536)
			(xy 154.305254 -388.700518) (xy 154.26309 -388.629652) (xy 154.249882 -388.618476) (xy 154.2415 -388.615428)
			(xy 154.219759 -388.607024) (xy 154.178912 -388.584572) (xy 154.141952 -388.556174) (xy 154.109737 -388.522488)
			(xy 154.083016 -388.484297) (xy 154.062411 -388.442489) (xy 154.048398 -388.398035) (xy 154.041305 -388.351967)
			(xy 154.04084 -388.328662) (xy 154.04134 -388.303264) (xy 154.049741 -388.253169) (xy 154.06632 -388.205156)
			(xy 154.09062 -388.16055) (xy 154.121971 -388.120584) (xy 154.140408 -388.10311) (xy 154.14879 -388.09549)
			(xy 154.157426 -388.075424) (xy 154.154632 -387.97611) (xy 154.145234 -387.956552) (xy 154.136344 -387.94944)
			(xy 154.117781 -387.933639) (xy 154.08505 -387.897514) (xy 154.057973 -387.856978) (xy 154.037138 -387.812907)
			(xy 154.022993 -387.766257) (xy 154.015847 -387.718036) (xy 154.01544 -387.693662) (xy 154.015879 -387.669546)
			(xy 154.022885 -387.621826) (xy 154.036744 -387.575629) (xy 154.057162 -387.531932) (xy 154.07005 -387.511544)
			(xy 154.075892 -387.502654) (xy 154.079448 -387.482588) (xy 154.058366 -387.390386) (xy 154.046174 -387.373622)
			(xy 154.037284 -387.368288) (xy 154.01648 -387.355434) (xy 153.97856 -387.324557) (xy 153.945606 -387.288427)
			(xy 153.918339 -387.247834) (xy 153.897355 -387.203664) (xy 153.883113 -387.156882) (xy 153.875923 -387.108513)
			(xy 153.875486 -387.084062) (xy 153.876047 -387.056779) (xy 153.885008 -387.002955) (xy 153.902679 -386.95133)
			(xy 153.928583 -386.903305) (xy 153.962017 -386.860182) (xy 153.981658 -386.841238) (xy 153.989112 -386.833748)
			(xy 153.997662 -386.814453) (xy 153.998168 -386.8039) (xy 153.998168 -386.729224) (xy 153.997581 -386.71869)
			(xy 153.989049 -386.699417) (xy 153.981658 -386.691886) (xy 153.962002 -386.672954) (xy 153.928558 -386.629833)
			(xy 153.902648 -386.581807) (xy 153.884976 -386.530177) (xy 153.876022 -386.476347) (xy 153.875486 -386.449062)
			(xy 153.87574 -386.43687) (xy 153.875994 -386.427218) (xy 153.869898 -386.409184) (xy 153.811224 -386.341874)
			(xy 153.79446 -386.333238) (xy 153.784808 -386.332222) (xy 153.757892 -386.328875) (xy 153.705586 -386.314535)
			(xy 153.656323 -386.291851) (xy 153.611422 -386.26143) (xy 153.572089 -386.224088) (xy 153.539379 -386.180826)
			(xy 153.514169 -386.132806) (xy 153.497135 -386.081315) (xy 153.492454 -386.0546) (xy 153.49093 -386.045202)
			(xy 153.218134 -385.57327) (xy 153.210768 -385.567428) (xy 153.191993 -385.551622) (xy 153.158866 -385.515413)
			(xy 153.131452 -385.474707) (xy 153.110351 -385.430399) (xy 153.096028 -385.383459) (xy 153.088796 -385.334918)
			(xy 153.08834 -385.31038) (xy 153.088772 -385.285968) (xy 153.095942 -385.237674) (xy 153.110137 -385.19096)
			(xy 153.131049 -385.146842) (xy 153.158223 -385.10628) (xy 153.191068 -385.070156) (xy 153.228869 -385.039256)
			(xy 153.24963 -385.026408) (xy 153.261314 -385.019296) (xy 153.274522 -384.996436) (xy 153.274522 -384.98272)
			(xy 153.274038 -384.972708) (xy 153.266383 -384.954206) (xy 153.25223 -384.940041) (xy 153.233734 -384.93237)
			(xy 153.223722 -384.93192) (xy 153.193496 -384.93192) (xy 153.186384 -384.934206) (xy 153.16288 -384.940877)
			(xy 153.114547 -384.948014) (xy 153.090118 -384.94843) (xy 153.065689 -384.948011) (xy 153.017357 -384.940873)
			(xy 152.993852 -384.934206) (xy 152.98674 -384.93192) (xy 152.550876 -384.93192) (xy 152.541261 -384.932337)
			(xy 152.523385 -384.93943) (xy 152.50938 -384.952609) (xy 152.504902 -384.96113) (xy 152.459436 -385.058158)
			(xy 152.463246 -385.087114) (xy 152.472898 -385.098544) (xy 152.491453 -385.121806) (xy 152.520749 -385.173592)
			(xy 152.540325 -385.229777) (xy 152.545542 -385.259072) (xy 152.547066 -385.26847) (xy 152.819862 -385.740402)
			(xy 152.827228 -385.746244) (xy 152.846005 -385.762049) (xy 152.879135 -385.798257) (xy 152.906553 -385.838962)
			(xy 152.927657 -385.883271) (xy 152.941985 -385.930211) (xy 152.949221 -385.978753) (xy 152.949656 -386.003292)
			(xy 152.949402 -386.015484) (xy 152.949148 -386.025136) (xy 152.955244 -386.04317) (xy 153.013918 -386.11048)
			(xy 153.030682 -386.119116) (xy 153.040588 -386.120132) (xy 153.067357 -386.123457) (xy 153.119386 -386.13768)
			(xy 153.168419 -386.160156) (xy 153.213155 -386.190291) (xy 153.252408 -386.227285) (xy 153.285138 -386.270158)
			(xy 153.310478 -386.317774) (xy 153.327756 -386.36887) (xy 153.336514 -386.422093) (xy 153.337006 -386.449062)
			(xy 153.336539 -386.473259) (xy 153.329443 -386.521132) (xy 153.315455 -386.567463) (xy 153.294874 -386.611265)
			(xy 153.281888 -386.631688) (xy 153.277137 -386.639658) (xy 153.273116 -386.657757) (xy 153.274014 -386.666994)
			(xy 153.278332 -386.697982) (xy 153.280138 -386.707234) (xy 153.289399 -386.723634) (xy 153.296366 -386.729986)
			(xy 153.318464 -386.748659) (xy 153.358243 -386.790667) (xy 153.39241 -386.837354) (xy 153.420419 -386.887976)
			(xy 153.441825 -386.941724) (xy 153.456285 -386.997741) (xy 153.46357 -387.055135) (xy 153.464006 -387.084062)
			(xy 153.463402 -387.117382) (xy 153.453733 -387.183317) (xy 153.434609 -387.247154) (xy 153.42108 -387.27761)
			(xy 153.416817 -387.288079) (xy 153.416891 -387.310653) (xy 153.426648 -387.331009) (xy 153.43505 -387.33857)
			(xy 153.457296 -387.357245) (xy 153.497359 -387.399301) (xy 153.531779 -387.446088) (xy 153.560004 -387.496852)
			(xy 153.581581 -387.55078) (xy 153.596163 -387.607003) (xy 153.603515 -387.66462) (xy 153.60396 -387.693662)
			(xy 153.603509 -387.722666) (xy 153.596178 -387.780208) (xy 153.58164 -387.836364) (xy 153.560129 -387.890235)
			(xy 153.531989 -387.94096) (xy 153.497669 -387.987725) (xy 153.45772 -388.029784) (xy 153.435558 -388.0485)
			(xy 153.428446 -388.054088) (xy 153.419302 -388.069328) (xy 153.404062 -388.152132) (xy 153.406856 -388.169404)
			(xy 153.411428 -388.177532) (xy 153.424024 -388.20071) (xy 153.441915 -388.25033) (xy 153.450999 -388.302289)
			(xy 153.45156 -388.328662) (xy 153.451488 -388.33802) (xy 153.450342 -388.356702) (xy 153.449274 -388.366)
			(xy 153.448258 -388.37489) (xy 153.452068 -388.391654) (xy 153.49601 -388.461504) (xy 153.509726 -388.471918)
			(xy 153.518108 -388.474712) (xy 153.542144 -388.483166) (xy 153.587325 -388.506711) (xy 153.628139 -388.537208)
			(xy 153.663523 -388.573864) (xy 153.69256 -388.615729) (xy 153.714496 -388.661713) (xy 153.72207 -388.68604)
			(xy 153.723594 -388.691882) (xy 154.043888 -389.245602) (xy 154.047952 -389.24992) (xy 154.064171 -389.267617)
			(xy 154.091608 -389.307005) (xy 154.112758 -389.350096) (xy 154.127134 -389.395895) (xy 154.134402 -389.443343)
			(xy 154.13482 -389.467344) (xy 154.134355 -389.492145) (xy 154.126584 -389.541134) (xy 154.111242 -389.588303)
			(xy 154.088707 -389.632489) (xy 154.059533 -389.672604) (xy 154.02444 -389.707658) (xy 153.984294 -389.736788)
			(xy 153.940083 -389.759275) (xy 153.892897 -389.774565) (xy 153.843899 -389.782282) (xy 153.819098 -389.782812)
			(xy 153.793704 -389.782304) (xy 153.743572 -389.774173) (xy 153.695388 -389.758122) (xy 153.650395 -389.734564)
			(xy 153.609753 -389.704107) (xy 153.574512 -389.667537) (xy 153.545579 -389.625797) (xy 153.523701 -389.579963)
			(xy 153.516076 -389.555736) (xy 153.514552 -389.549894) (xy 153.194258 -388.996174) (xy 153.190194 -388.991856)
			(xy 153.174005 -388.974147) (xy 153.146631 -388.934744) (xy 153.125542 -388.891648) (xy 153.111225 -388.845855)
			(xy 153.104012 -388.798422) (xy 153.10358 -388.774432) (xy 153.103666 -388.762384) (xy 153.105449 -388.738355)
			(xy 153.107136 -388.726426) (xy 153.108406 -388.717536) (xy 153.105358 -388.700518) (xy 153.063194 -388.629652)
			(xy 153.049986 -388.618476) (xy 153.041604 -388.615428) (xy 153.019862 -388.607024) (xy 152.979015 -388.584573)
			(xy 152.942055 -388.556174) (xy 152.90984 -388.522488) (xy 152.883118 -388.484298) (xy 152.862512 -388.442489)
			(xy 152.8485 -388.398035) (xy 152.841406 -388.351967) (xy 152.840944 -388.328662) (xy 152.841526 -388.302291)
			(xy 152.850627 -388.25034) (xy 152.868502 -388.200719) (xy 152.881076 -388.177532) (xy 152.885648 -388.169404)
			(xy 152.888442 -388.152132) (xy 152.873202 -388.069328) (xy 152.864058 -388.054088) (xy 152.856946 -388.0485)
			(xy 152.834757 -388.029815) (xy 152.794806 -387.987755) (xy 152.760489 -387.940985) (xy 152.732355 -387.890255)
			(xy 152.710855 -387.836376) (xy 152.696333 -387.780214) (xy 152.689022 -387.722667) (xy 152.688544 -387.693662)
			(xy 152.689147 -387.660342) (xy 152.698813 -387.594406) (xy 152.717936 -387.530568) (xy 152.73147 -387.500114)
			(xy 152.735736 -387.489643) (xy 152.735669 -387.467062) (xy 152.725924 -387.446692) (xy 152.7175 -387.439154)
			(xy 152.695255 -387.420479) (xy 152.655196 -387.378423) (xy 152.620779 -387.331636) (xy 152.592559 -387.28087)
			(xy 152.570988 -387.226942) (xy 152.556414 -387.170719) (xy 152.54907 -387.113103) (xy 152.54859 -387.084062)
			(xy 152.549035 -387.055136) (xy 152.556328 -386.997746) (xy 152.570793 -386.941732) (xy 152.5922 -386.887987)
			(xy 152.620207 -386.837367) (xy 152.654369 -386.790679) (xy 152.69414 -386.748666) (xy 152.71623 -386.729986)
			(xy 152.723305 -386.723722) (xy 152.732593 -386.707281) (xy 152.734264 -386.697982) (xy 152.738582 -386.666994)
			(xy 152.73953 -386.657756) (xy 152.735495 -386.639646) (xy 152.730708 -386.631688) (xy 152.717675 -386.61129)
			(xy 152.697076 -386.567488) (xy 152.68309 -386.521149) (xy 152.676017 -386.473264) (xy 152.67559 -386.449062)
			(xy 152.675844 -386.43687) (xy 152.676098 -386.427218) (xy 152.670002 -386.409184) (xy 152.611328 -386.341874)
			(xy 152.594564 -386.333238) (xy 152.584658 -386.332222) (xy 152.557745 -386.328871) (xy 152.505445 -386.314526)
			(xy 152.456188 -386.291837) (xy 152.411295 -386.261414) (xy 152.371968 -386.224072) (xy 152.339264 -386.180812)
			(xy 152.314058 -386.132794) (xy 152.297027 -386.081306) (xy 152.292304 -386.0546) (xy 152.29078 -386.045202)
			(xy 152.017984 -385.57327) (xy 152.010618 -385.567428) (xy 151.99184 -385.551624) (xy 151.958709 -385.515417)
			(xy 151.93129 -385.474712) (xy 151.910187 -385.430402) (xy 151.895861 -385.383462) (xy 151.888628 -385.334919)
			(xy 151.88819 -385.31038) (xy 151.888622 -385.285968) (xy 151.895791 -385.237672) (xy 151.909985 -385.190956)
			(xy 151.930895 -385.146836) (xy 151.958067 -385.106271) (xy 151.990909 -385.070143) (xy 152.028708 -385.039238)
			(xy 152.04948 -385.026408) (xy 152.061164 -385.019296) (xy 152.074372 -384.996436) (xy 152.074372 -384.98272)
			(xy 152.073955 -384.972698) (xy 152.066288 -384.954179) (xy 152.052114 -384.940008) (xy 152.033594 -384.932343)
			(xy 152.023572 -384.93192) (xy 151.9936 -384.93192) (xy 151.986488 -384.934206) (xy 151.962984 -384.940878)
			(xy 151.914651 -384.948015) (xy 151.890222 -384.94843) (xy 151.865793 -384.948011) (xy 151.817461 -384.940873)
			(xy 151.793956 -384.934206) (xy 151.786844 -384.93192) (xy 151.35098 -384.93192) (xy 151.341364 -384.932336)
			(xy 151.323487 -384.939428) (xy 151.309481 -384.952608) (xy 151.305006 -384.96113) (xy 151.25954 -385.058158)
			(xy 151.26335 -385.087114) (xy 151.273002 -385.098544) (xy 151.291557 -385.121806) (xy 151.320853 -385.173592)
			(xy 151.340428 -385.229778) (xy 151.345646 -385.259072) (xy 151.34717 -385.26847) (xy 151.619966 -385.740402)
			(xy 151.627332 -385.746244) (xy 151.646109 -385.762049) (xy 151.679238 -385.798258) (xy 151.706656 -385.838963)
			(xy 151.72776 -385.883271) (xy 151.742088 -385.930211) (xy 151.749324 -385.978753) (xy 151.74976 -386.003292)
			(xy 151.749506 -386.015484) (xy 151.749252 -386.025136) (xy 151.755348 -386.04317) (xy 151.814022 -386.11048)
			(xy 151.830786 -386.119116) (xy 151.840438 -386.120132) (xy 151.86721 -386.123454) (xy 151.919246 -386.137671)
			(xy 151.968285 -386.160143) (xy 152.013028 -386.190276) (xy 152.052287 -386.22727) (xy 152.085023 -386.270144)
			(xy 152.110368 -386.317763) (xy 152.127649 -386.368863) (xy 152.136409 -386.42209) (xy 152.136856 -386.449062)
			(xy 152.136346 -386.475049) (xy 152.128216 -386.526384) (xy 152.112155 -386.575814) (xy 152.088559 -386.622124)
			(xy 152.058009 -386.664172) (xy 152.021258 -386.700923) (xy 151.97921 -386.731473) (xy 151.9329 -386.755069)
			(xy 151.88347 -386.77113) (xy 151.832135 -386.77926) (xy 151.780161 -386.77926) (xy 151.728826 -386.77113)
			(xy 151.679396 -386.755069) (xy 151.633086 -386.731473) (xy 151.591038 -386.700923) (xy 151.554287 -386.664172)
			(xy 151.523737 -386.622124) (xy 151.500141 -386.575814) (xy 151.48408 -386.526384) (xy 151.47595 -386.475049)
			(xy 151.47544 -386.449062) (xy 151.475694 -386.43687) (xy 151.475948 -386.427218) (xy 151.469852 -386.409184)
			(xy 151.411178 -386.341874) (xy 151.394414 -386.333238) (xy 151.384762 -386.332222) (xy 151.357849 -386.328871)
			(xy 151.305549 -386.314527) (xy 151.256291 -386.291839) (xy 151.211397 -386.261415) (xy 151.17207 -386.224073)
			(xy 151.139365 -386.180813) (xy 151.114159 -386.132795) (xy 151.097128 -386.081307) (xy 151.092408 -386.0546)
			(xy 151.090884 -386.045202) (xy 150.818088 -385.57327) (xy 150.810722 -385.567428) (xy 150.791944 -385.551624)
			(xy 150.758812 -385.515417) (xy 150.731393 -385.474712) (xy 150.710289 -385.430403) (xy 150.695964 -385.383462)
			(xy 150.68873 -385.334919) (xy 150.688294 -385.31038) (xy 150.688726 -385.285968) (xy 150.695895 -385.237672)
			(xy 150.710089 -385.190957) (xy 150.730999 -385.146837) (xy 150.758171 -385.106272) (xy 150.791014 -385.070144)
			(xy 150.828813 -385.03924) (xy 150.849584 -385.026408) (xy 150.861268 -385.019296) (xy 150.874476 -384.996436)
			(xy 150.874476 -384.98272) (xy 150.874059 -384.972698) (xy 150.866392 -384.954178) (xy 150.852218 -384.940006)
			(xy 150.833698 -384.93234) (xy 150.823676 -384.93192) (xy 150.79345 -384.93192) (xy 150.786338 -384.934206)
			(xy 150.762834 -384.940881) (xy 150.714502 -384.948026) (xy 150.690072 -384.94843) (xy 150.665644 -384.948008)
			(xy 150.617313 -384.940863) (xy 150.593806 -384.934206) (xy 150.586694 -384.93192) (xy 150.151084 -384.93192)
			(xy 150.141468 -384.932335) (xy 150.12359 -384.939427) (xy 150.109582 -384.952606) (xy 150.10511 -384.96113)
			(xy 150.059644 -385.058158) (xy 150.063454 -385.087114) (xy 150.073106 -385.098544) (xy 150.09173 -385.121875)
			(xy 150.121134 -385.173822) (xy 150.140778 -385.230189) (xy 150.146004 -385.25958) (xy 150.147274 -385.268978)
			(xy 150.419816 -385.740402) (xy 150.427182 -385.746244) (xy 150.445961 -385.762048) (xy 150.479096 -385.798254)
			(xy 150.506518 -385.838959) (xy 150.527625 -385.883268) (xy 150.541955 -385.930209) (xy 150.549192 -385.978752)
			(xy 150.54961 -386.003292) (xy 150.549356 -386.015484) (xy 150.549102 -386.025136) (xy 150.555198 -386.04317)
			(xy 150.613872 -386.11048) (xy 150.630636 -386.119116) (xy 150.640542 -386.120132) (xy 150.667313 -386.123454)
			(xy 150.719349 -386.137671) (xy 150.768388 -386.160144) (xy 150.81313 -386.190277) (xy 150.852389 -386.227271)
			(xy 150.885125 -386.270145) (xy 150.910469 -386.317764) (xy 150.92775 -386.368864) (xy 150.93651 -386.422091)
			(xy 150.93696 -386.449062) (xy 150.936397 -386.476344) (xy 150.927434 -386.530168) (xy 150.909762 -386.581791)
			(xy 150.883858 -386.629816) (xy 150.850426 -386.672939) (xy 150.830788 -386.691886) (xy 150.823345 -386.69938)
			(xy 150.814813 -386.718675) (xy 150.814278 -386.729224) (xy 150.814278 -386.8039) (xy 150.814868 -386.814434)
			(xy 150.823399 -386.833706) (xy 150.830788 -386.841238) (xy 150.85044 -386.860172) (xy 150.883877 -386.903295)
			(xy 150.909779 -386.951322) (xy 150.927445 -387.00295) (xy 150.936394 -387.056778) (xy 150.93696 -387.084062)
			(xy 150.936527 -387.108179) (xy 150.92953 -387.155904) (xy 150.91568 -387.202107) (xy 150.89527 -387.245811)
			(xy 150.88235 -387.26618) (xy 150.876508 -387.27507) (xy 150.872952 -387.295136) (xy 150.894034 -387.387338)
			(xy 150.906226 -387.404102) (xy 150.915116 -387.409436) (xy 150.935919 -387.422291) (xy 150.973837 -387.453168)
			(xy 151.006788 -387.489298) (xy 151.034052 -387.529892) (xy 151.055033 -387.574062) (xy 151.069272 -387.620843)
			(xy 151.076458 -387.669212) (xy 151.076914 -387.693662) (xy 151.076476 -387.718032) (xy 151.06932 -387.766245)
			(xy 151.055171 -387.812887) (xy 151.034335 -387.856949) (xy 151.007263 -387.89748) (xy 150.97454 -387.933603)
			(xy 150.95601 -387.94944) (xy 150.94712 -387.956552) (xy 150.937722 -387.97611) (xy 150.934928 -388.075424)
			(xy 150.943564 -388.09549) (xy 150.951946 -388.10311) (xy 150.970365 -388.120599) (xy 151.001703 -388.160569)
			(xy 151.025996 -388.205171) (xy 151.042575 -388.253179) (xy 151.050984 -388.303267) (xy 151.051514 -388.328662)
			(xy 151.640794 -388.328662) (xy 151.641316 -388.303407) (xy 151.649629 -388.253585) (xy 151.66603 -388.205811)
			(xy 151.690071 -388.161388) (xy 151.721095 -388.121528) (xy 151.758257 -388.087318) (xy 151.800543 -388.059692)
			(xy 151.846799 -388.039402) (xy 151.895764 -388.027002) (xy 151.946102 -388.022831) (xy 151.99644 -388.027002)
			(xy 152.045405 -388.039402) (xy 152.091661 -388.059692) (xy 152.133947 -388.087318) (xy 152.171109 -388.121528)
			(xy 152.202133 -388.161388) (xy 152.226174 -388.205811) (xy 152.242575 -388.253585) (xy 152.250888 -388.303407)
			(xy 152.25141 -388.328662) (xy 152.251341 -388.338021) (xy 152.250198 -388.356703) (xy 152.249124 -388.366)
			(xy 152.248108 -388.37489) (xy 152.251918 -388.391654) (xy 152.29586 -388.461504) (xy 152.309576 -388.471918)
			(xy 152.317958 -388.474712) (xy 152.34199 -388.48317) (xy 152.387162 -388.506725) (xy 152.427966 -388.537227)
			(xy 152.463345 -388.573884) (xy 152.492379 -388.615745) (xy 152.514317 -388.661724) (xy 152.52192 -388.68604)
			(xy 152.523444 -388.691882) (xy 152.843738 -389.245602) (xy 152.847802 -389.24992) (xy 152.86399 -389.267629)
			(xy 152.891356 -389.307037) (xy 152.912442 -389.350133) (xy 152.926762 -389.395924) (xy 152.933987 -389.443355)
			(xy 152.934416 -389.467344) (xy 152.933923 -389.492132) (xy 152.926162 -389.541098) (xy 152.910838 -389.588247)
			(xy 152.888328 -389.63242) (xy 152.859187 -389.672528) (xy 152.824131 -389.707584) (xy 152.784023 -389.736726)
			(xy 152.739851 -389.759236) (xy 152.692702 -389.774561) (xy 152.643736 -389.782322) (xy 152.618948 -389.782812)
			(xy 152.593555 -389.782269) (xy 152.543423 -389.774146) (xy 152.495239 -389.758102) (xy 152.450245 -389.73455)
			(xy 152.409601 -389.704098) (xy 152.374358 -389.667532) (xy 152.345423 -389.625796) (xy 152.323543 -389.579965)
			(xy 152.315926 -389.555736) (xy 152.314402 -389.549894) (xy 151.994108 -388.996174) (xy 151.990044 -388.991856)
			(xy 151.973831 -388.974156) (xy 151.946411 -388.934762) (xy 151.92527 -388.89167) (xy 151.910899 -388.845875)
			(xy 151.903626 -388.798431) (xy 151.903176 -388.774432) (xy 151.903318 -388.76238) (xy 151.905224 -388.73835)
			(xy 151.906986 -388.726426) (xy 151.908256 -388.717536) (xy 151.905208 -388.700518) (xy 151.863044 -388.629652)
			(xy 151.849836 -388.618476) (xy 151.841454 -388.615428) (xy 151.819703 -388.607042) (xy 151.778845 -388.584599)
			(xy 151.741875 -388.556203) (xy 151.709653 -388.522517) (xy 151.682928 -388.484322) (xy 151.662322 -388.442507)
			(xy 151.648315 -388.398045) (xy 151.641232 -388.35197) (xy 151.640794 -388.328662) (xy 151.051514 -388.328662)
			(xy 151.051442 -388.33802) (xy 151.050296 -388.356702) (xy 151.049228 -388.366) (xy 151.048212 -388.37489)
			(xy 151.052022 -388.391654) (xy 151.095964 -388.461504) (xy 151.10968 -388.471918) (xy 151.118062 -388.474712)
			(xy 151.142095 -388.483169) (xy 151.18727 -388.506719) (xy 151.228077 -388.537219) (xy 151.263456 -388.573877)
			(xy 151.292487 -388.615741) (xy 151.314419 -388.661724) (xy 151.322024 -388.68604) (xy 151.323548 -388.691882)
			(xy 151.643842 -389.245602) (xy 151.647906 -389.24992) (xy 151.664096 -389.267629) (xy 151.691474 -389.307031)
			(xy 151.712566 -389.350126) (xy 151.726886 -389.395919) (xy 151.734103 -389.443354) (xy 151.73452 -389.467344)
			(xy 151.734056 -389.492132) (xy 151.726293 -389.541097) (xy 151.710967 -389.588244) (xy 151.688453 -389.632413)
			(xy 151.659308 -389.672517) (xy 151.624247 -389.707567) (xy 151.584135 -389.736702) (xy 151.539959 -389.759202)
			(xy 151.492807 -389.774515) (xy 151.44384 -389.782263) (xy 151.419052 -389.782812) (xy 151.39366 -389.782301)
			(xy 151.343533 -389.774164) (xy 151.295355 -389.758108) (xy 151.250368 -389.734547) (xy 151.209733 -389.704089)
			(xy 151.174497 -389.667519) (xy 151.145569 -389.62578) (xy 151.123696 -389.579949) (xy 151.11603 -389.555736)
			(xy 151.114506 -389.549894) (xy 150.794212 -388.996174) (xy 150.790148 -388.991856) (xy 150.77393 -388.974158)
			(xy 150.746497 -388.93477) (xy 150.725349 -388.891679) (xy 150.710977 -388.84588) (xy 150.703713 -388.798432)
			(xy 150.70328 -388.774432) (xy 150.703438 -388.76238) (xy 150.705347 -388.738352) (xy 150.70709 -388.726426)
			(xy 150.70836 -388.717536) (xy 150.705312 -388.700518) (xy 150.663148 -388.629652) (xy 150.64994 -388.618476)
			(xy 150.641558 -388.615428) (xy 150.619819 -388.607021) (xy 150.578977 -388.584567) (xy 150.542022 -388.556166)
			(xy 150.509812 -388.52248) (xy 150.483095 -388.484289) (xy 150.462493 -388.442483) (xy 150.448482 -388.398031)
			(xy 150.44139 -388.351966) (xy 150.440898 -388.328662) (xy 150.441398 -388.303264) (xy 150.449798 -388.253167)
			(xy 150.466375 -388.205153) (xy 150.490673 -388.160545) (xy 150.522021 -388.120576) (xy 150.540466 -388.10311)
			(xy 150.548848 -388.09549) (xy 150.557484 -388.075424) (xy 150.55469 -387.97611) (xy 150.545292 -387.956552)
			(xy 150.536402 -387.94944) (xy 150.517841 -387.933638) (xy 150.485114 -387.897511) (xy 150.458041 -387.856974)
			(xy 150.437208 -387.812904) (xy 150.423065 -387.766255) (xy 150.41592 -387.718035) (xy 150.415498 -387.693662)
			(xy 150.415937 -387.669546) (xy 150.422942 -387.621826) (xy 150.4368 -387.575627) (xy 150.457215 -387.531929)
			(xy 150.470108 -387.511544) (xy 150.47595 -387.502654) (xy 150.479506 -387.482588) (xy 150.458424 -387.390386)
			(xy 150.446232 -387.373622) (xy 150.437342 -387.368288) (xy 150.41654 -387.355432) (xy 150.378624 -387.324553)
			(xy 150.345675 -387.288422) (xy 150.318412 -387.247829) (xy 150.297431 -387.203659) (xy 150.28319 -387.15688)
			(xy 150.276002 -387.108512) (xy 150.275544 -387.084062) (xy 150.276105 -387.056779) (xy 150.285065 -387.002953)
			(xy 150.302735 -386.951327) (xy 150.328636 -386.903301) (xy 150.362067 -386.860175) (xy 150.381716 -386.841238)
			(xy 150.389163 -386.833745) (xy 150.397703 -386.81445) (xy 150.398226 -386.8039) (xy 150.398226 -386.729224)
			(xy 150.397641 -386.718688) (xy 150.389116 -386.699409) (xy 150.381716 -386.691886) (xy 150.362062 -386.672952)
			(xy 150.328622 -386.629831) (xy 150.302716 -386.581804) (xy 150.285046 -386.530175) (xy 150.276093 -386.476346)
			(xy 150.275544 -386.449062) (xy 150.275798 -386.43687) (xy 150.276052 -386.427218) (xy 150.269956 -386.409184)
			(xy 150.211282 -386.341874) (xy 150.194518 -386.333238) (xy 150.184612 -386.332222) (xy 150.157696 -386.328875)
			(xy 150.10539 -386.314536) (xy 150.056125 -386.291852) (xy 150.011224 -386.261431) (xy 149.971891 -386.224089)
			(xy 149.939181 -386.180828) (xy 149.91397 -386.132807) (xy 149.896936 -386.081316) (xy 149.892258 -386.0546)
			(xy 149.890734 -386.045202) (xy 149.617684 -385.572762) (xy 149.610572 -385.56692) (xy 149.591839 -385.55114)
			(xy 149.558784 -385.514997) (xy 149.531425 -385.474371) (xy 149.510361 -385.430153) (xy 149.496053 -385.383311)
			(xy 149.488813 -385.334869) (xy 149.488398 -385.31038) (xy 149.48883 -385.285968) (xy 149.495999 -385.237673)
			(xy 149.510193 -385.190957) (xy 149.531104 -385.146837) (xy 149.558276 -385.106272) (xy 149.591119 -385.070145)
			(xy 149.628917 -385.039241) (xy 149.649688 -385.026408) (xy 149.661372 -385.019296) (xy 149.67458 -384.996436)
			(xy 149.67458 -384.98272) (xy 149.674163 -384.972698) (xy 149.666496 -384.954177) (xy 149.652323 -384.940004)
			(xy 149.633802 -384.932337) (xy 149.62378 -384.93192) (xy 149.593554 -384.93192) (xy 149.586442 -384.934206)
			(xy 149.562938 -384.940881) (xy 149.514606 -384.948027) (xy 149.490176 -384.94843) (xy 149.465748 -384.948008)
			(xy 149.417417 -384.940864) (xy 149.39391 -384.934206) (xy 149.386798 -384.93192) (xy 148.950934 -384.93192)
			(xy 148.941313 -384.932327) (xy 148.92342 -384.939407) (xy 148.909398 -384.952585) (xy 148.90496 -384.96113)
			(xy 148.859494 -385.058158) (xy 148.863304 -385.087114) (xy 148.872956 -385.098544) (xy 148.891513 -385.121805)
			(xy 148.920813 -385.17359) (xy 148.940391 -385.229776) (xy 148.9456 -385.259072) (xy 148.947124 -385.26847)
			(xy 149.21992 -385.740402) (xy 149.227286 -385.746244) (xy 149.246065 -385.762048) (xy 149.279199 -385.798254)
			(xy 149.306621 -385.838959) (xy 149.327728 -385.883268) (xy 149.342057 -385.930209) (xy 149.349295 -385.978752)
			(xy 149.349714 -386.003292) (xy 149.34946 -386.015484) (xy 149.349206 -386.025136) (xy 149.355302 -386.04317)
			(xy 149.413976 -386.11048) (xy 149.43074 -386.119116) (xy 149.440646 -386.120132) (xy 149.467417 -386.123454)
			(xy 149.519452 -386.137672) (xy 149.56849 -386.160145) (xy 149.613232 -386.190278) (xy 149.652491 -386.227272)
			(xy 149.685226 -386.270147) (xy 149.71057 -386.317765) (xy 149.72785 -386.368864) (xy 149.73661 -386.422091)
			(xy 149.737064 -386.449062) (xy 149.736501 -386.476344) (xy 149.727538 -386.530168) (xy 149.709866 -386.581792)
			(xy 149.683963 -386.629816) (xy 149.650531 -386.67294) (xy 149.630892 -386.691886) (xy 149.623448 -386.69938)
			(xy 149.614916 -386.718675) (xy 149.614382 -386.729224) (xy 149.614382 -386.8039) (xy 149.614972 -386.814434)
			(xy 149.623504 -386.833705) (xy 149.630892 -386.841238) (xy 149.650544 -386.860172) (xy 149.68398 -386.903295)
			(xy 149.709882 -386.951322) (xy 149.727548 -387.00295) (xy 149.736497 -387.056778) (xy 149.737064 -387.084062)
			(xy 149.736631 -387.108179) (xy 149.729634 -387.155904) (xy 149.715784 -387.202108) (xy 149.695374 -387.245811)
			(xy 149.682454 -387.26618) (xy 149.676612 -387.27507) (xy 149.673056 -387.295136) (xy 149.694138 -387.387338)
			(xy 149.70633 -387.404102) (xy 149.71522 -387.409436) (xy 149.736022 -387.422291) (xy 149.77394 -387.453168)
			(xy 149.806891 -387.489299) (xy 149.834154 -387.529893) (xy 149.855135 -387.574063) (xy 149.869374 -387.620843)
			(xy 149.87656 -387.669212) (xy 149.877018 -387.693662) (xy 149.87658 -387.718032) (xy 149.869424 -387.766245)
			(xy 149.855275 -387.812887) (xy 149.834439 -387.85695) (xy 149.807367 -387.897481) (xy 149.774644 -387.933604)
			(xy 149.756114 -387.94944) (xy 149.747224 -387.956552) (xy 149.737826 -387.97611) (xy 149.735032 -388.075424)
			(xy 149.743668 -388.09549) (xy 149.75205 -388.10311) (xy 149.770469 -388.120599) (xy 149.801806 -388.160569)
			(xy 149.826099 -388.205172) (xy 149.842678 -388.253179) (xy 149.851086 -388.303267) (xy 149.851618 -388.328662)
			(xy 149.851546 -388.33802) (xy 149.8504 -388.356702) (xy 149.849332 -388.366) (xy 149.848316 -388.37489)
			(xy 149.852126 -388.391654) (xy 149.896068 -388.461504) (xy 149.909784 -388.471918) (xy 149.918166 -388.474712)
			(xy 149.942263 -388.483193) (xy 149.987554 -388.506821) (xy 150.02845 -388.537432) (xy 150.063885 -388.574227)
			(xy 150.092933 -388.616247) (xy 150.114839 -388.662395) (xy 150.122382 -388.686802) (xy 150.123906 -388.692644)
			(xy 150.443692 -389.245602) (xy 150.447756 -389.24992) (xy 150.463975 -389.267617) (xy 150.491411 -389.307005)
			(xy 150.512562 -389.350096) (xy 150.526937 -389.395895) (xy 150.534205 -389.443343) (xy 150.534624 -389.467344)
			(xy 150.534159 -389.492145) (xy 150.526388 -389.541134) (xy 150.511047 -389.588303) (xy 150.488511 -389.63249)
			(xy 150.459337 -389.672605) (xy 150.424245 -389.70766) (xy 150.384098 -389.73679) (xy 150.339887 -389.759278)
			(xy 150.292701 -389.774568) (xy 150.243703 -389.782285) (xy 150.218902 -389.782812) (xy 150.193508 -389.782304)
			(xy 150.143375 -389.774174) (xy 150.095191 -389.758123) (xy 150.050197 -389.734566) (xy 150.009555 -389.704109)
			(xy 149.974313 -389.667539) (xy 149.94538 -389.625798) (xy 149.923502 -389.579965) (xy 149.91588 -389.555736)
			(xy 149.914356 -389.549894) (xy 149.593808 -388.995412) (xy 149.589744 -388.991094) (xy 149.573639 -388.973426)
			(xy 149.546399 -388.93414) (xy 149.525388 -388.8912) (xy 149.511087 -388.845584) (xy 149.50382 -388.798334)
			(xy 149.503384 -388.774432) (xy 149.503542 -388.76238) (xy 149.505451 -388.738352) (xy 149.507194 -388.726426)
			(xy 149.508464 -388.717536) (xy 149.505416 -388.700518) (xy 149.463252 -388.629652) (xy 149.450044 -388.618476)
			(xy 149.441662 -388.615428) (xy 149.419923 -388.607022) (xy 149.37908 -388.584567) (xy 149.342125 -388.556167)
			(xy 149.309914 -388.52248) (xy 149.283197 -388.48429) (xy 149.262594 -388.442483) (xy 149.248584 -388.398031)
			(xy 149.241492 -388.351966) (xy 149.241002 -388.328662) (xy 149.241502 -388.303264) (xy 149.249902 -388.253168)
			(xy 149.266479 -388.205153) (xy 149.290778 -388.160546) (xy 149.322126 -388.120577) (xy 149.34057 -388.10311)
			(xy 149.348952 -388.09549) (xy 149.357588 -388.075424) (xy 149.354794 -387.97611) (xy 149.345396 -387.956552)
			(xy 149.336506 -387.94944) (xy 149.317945 -387.933638) (xy 149.285217 -387.897511) (xy 149.258144 -387.856974)
			(xy 149.237311 -387.812904) (xy 149.223168 -387.766255) (xy 149.216022 -387.718035) (xy 149.215602 -387.693662)
			(xy 149.216041 -387.669546) (xy 149.223046 -387.621826) (xy 149.236904 -387.575627) (xy 149.25732 -387.53193)
			(xy 149.270212 -387.511544) (xy 149.276054 -387.502654) (xy 149.27961 -387.482588) (xy 149.258528 -387.390386)
			(xy 149.246336 -387.373622) (xy 149.237446 -387.368288) (xy 149.216644 -387.355432) (xy 149.178728 -387.324554)
			(xy 149.145778 -387.288423) (xy 149.118514 -387.247829) (xy 149.097533 -387.20366) (xy 149.083292 -387.15688)
			(xy 149.076104 -387.108512) (xy 149.075648 -387.084062) (xy 149.076209 -387.056779) (xy 149.085169 -387.002953)
			(xy 149.102839 -386.951328) (xy 149.128741 -386.903301) (xy 149.162172 -386.860175) (xy 149.18182 -386.841238)
			(xy 149.189266 -386.833745) (xy 149.197806 -386.81445) (xy 149.19833 -386.8039) (xy 149.19833 -386.729224)
			(xy 149.197745 -386.718688) (xy 149.18922 -386.699408) (xy 149.18182 -386.691886) (xy 149.162166 -386.672953)
			(xy 149.128726 -386.629831) (xy 149.102819 -386.581804) (xy 149.085149 -386.530176) (xy 149.076196 -386.476346)
			(xy 149.075648 -386.449062) (xy 149.075902 -386.43687) (xy 149.076156 -386.427218) (xy 149.07006 -386.409184)
			(xy 149.011386 -386.341874) (xy 148.994622 -386.333238) (xy 148.984716 -386.332222) (xy 148.9578 -386.328875)
			(xy 148.905493 -386.314537) (xy 148.856228 -386.291853) (xy 148.811327 -386.261432) (xy 148.771993 -386.22409)
			(xy 148.739282 -386.180829) (xy 148.714071 -386.132808) (xy 148.697036 -386.081317) (xy 148.692362 -386.0546)
			(xy 148.690838 -386.045202) (xy 148.418042 -385.57327) (xy 148.410676 -385.567428) (xy 148.3919 -385.551623)
			(xy 148.358773 -385.515414) (xy 148.331358 -385.474708) (xy 148.310257 -385.430399) (xy 148.295933 -385.383459)
			(xy 148.288701 -385.334919) (xy 148.288248 -385.31038) (xy 148.28868 -385.285968) (xy 148.29585 -385.237675)
			(xy 148.310045 -385.190961) (xy 148.330958 -385.146843) (xy 148.358132 -385.106281) (xy 148.390977 -385.070158)
			(xy 148.428779 -385.039259) (xy 148.449538 -385.026408) (xy 148.461222 -385.019296) (xy 148.47443 -384.996436)
			(xy 148.47443 -384.98272) (xy 148.473946 -384.972707) (xy 148.466291 -384.954204) (xy 148.452138 -384.940037)
			(xy 148.433642 -384.932364) (xy 148.42363 -384.93192) (xy 148.393404 -384.93192) (xy 148.386292 -384.934206)
			(xy 148.362788 -384.940878) (xy 148.314455 -384.948016) (xy 148.290026 -384.94843) (xy 148.265597 -384.948012)
			(xy 148.217265 -384.940874) (xy 148.19376 -384.934206) (xy 148.186648 -384.93192) (xy 147.751038 -384.93192)
			(xy 147.741416 -384.932326) (xy 147.723523 -384.939406) (xy 147.709499 -384.952583) (xy 147.705064 -384.96113)
			(xy 147.659598 -385.058158) (xy 147.663408 -385.087114) (xy 147.67306 -385.098544) (xy 147.691617 -385.121805)
			(xy 147.720917 -385.17359) (xy 147.740494 -385.229776) (xy 147.745704 -385.259072) (xy 147.747228 -385.26847)
			(xy 148.020024 -385.740402) (xy 148.02739 -385.746244) (xy 148.046169 -385.762048) (xy 148.079303 -385.798255)
			(xy 148.106724 -385.838959) (xy 148.127831 -385.883268) (xy 148.14216 -385.930209) (xy 148.149397 -385.978752)
			(xy 148.149818 -386.003292) (xy 148.149564 -386.015484) (xy 148.14931 -386.025136) (xy 148.155406 -386.04317)
			(xy 148.21408 -386.11048) (xy 148.230844 -386.119116) (xy 148.240496 -386.120132) (xy 148.267264 -386.123458)
			(xy 148.319293 -386.137681) (xy 148.368324 -386.160158) (xy 148.413059 -386.190293) (xy 148.452311 -386.227287)
			(xy 148.485041 -386.27016) (xy 148.51038 -386.317775) (xy 148.527657 -386.368871) (xy 148.536415 -386.422093)
			(xy 148.536914 -386.449062) (xy 148.536351 -386.476344) (xy 148.527387 -386.530166) (xy 148.509713 -386.581788)
			(xy 148.483807 -386.62981) (xy 148.450372 -386.67293) (xy 148.430742 -386.691886) (xy 148.423292 -386.699377)
			(xy 148.414751 -386.718673) (xy 148.414232 -386.729224) (xy 148.414232 -386.8039) (xy 148.414824 -386.814432)
			(xy 148.423361 -386.833698) (xy 148.430742 -386.841238) (xy 148.450396 -386.860171) (xy 148.483838 -386.903292)
			(xy 148.509744 -386.951319) (xy 148.527412 -387.002948) (xy 148.536363 -387.056778) (xy 148.536914 -387.084062)
			(xy 148.536481 -387.10818) (xy 148.529485 -387.155905) (xy 148.515637 -387.202109) (xy 148.49523 -387.245815)
			(xy 148.482304 -387.26618) (xy 148.476462 -387.27507) (xy 148.472906 -387.295136) (xy 148.493988 -387.387338)
			(xy 148.50618 -387.404102) (xy 148.51507 -387.409436) (xy 148.53587 -387.422293) (xy 148.573782 -387.453173)
			(xy 148.606728 -387.489305) (xy 148.633987 -387.529899) (xy 148.654964 -387.574068) (xy 148.669201 -387.620847)
			(xy 148.676385 -387.669213) (xy 148.676868 -387.693662) (xy 148.67643 -387.718033) (xy 148.669275 -387.766246)
			(xy 148.655127 -387.81289) (xy 148.634294 -387.856955) (xy 148.607224 -387.897489) (xy 148.574505 -387.933616)
			(xy 148.555964 -387.94944) (xy 148.547074 -387.956552) (xy 148.537676 -387.97611) (xy 148.534882 -388.075424)
			(xy 148.543518 -388.09549) (xy 148.5519 -388.10311) (xy 148.570322 -388.120598) (xy 148.601664 -388.160566)
			(xy 148.62596 -388.205168) (xy 148.642542 -388.253177) (xy 148.650953 -388.303267) (xy 148.651468 -388.328662)
			(xy 148.651396 -388.33802) (xy 148.65025 -388.356702) (xy 148.649182 -388.366) (xy 148.648166 -388.37489)
			(xy 148.651976 -388.391654) (xy 148.695918 -388.461504) (xy 148.709634 -388.471918) (xy 148.718016 -388.474712)
			(xy 148.742051 -388.483166) (xy 148.787232 -388.506712) (xy 148.828044 -388.537209) (xy 148.863428 -388.573866)
			(xy 148.892464 -388.61573) (xy 148.9144 -388.661715) (xy 148.921978 -388.68604) (xy 148.923502 -388.691882)
			(xy 149.243796 -389.245602) (xy 149.24786 -389.24992) (xy 149.264079 -389.267617) (xy 149.291515 -389.307005)
			(xy 149.312665 -389.350096) (xy 149.32704 -389.395895) (xy 149.334308 -389.443343) (xy 149.334728 -389.467344)
			(xy 149.334263 -389.492145) (xy 149.326492 -389.541134) (xy 149.311151 -389.588304) (xy 149.288615 -389.632491)
			(xy 149.259442 -389.672606) (xy 149.224349 -389.707661) (xy 149.184202 -389.736792) (xy 149.139991 -389.75928)
			(xy 149.092805 -389.774571) (xy 149.043807 -389.782289) (xy 149.019006 -389.782812) (xy 148.993612 -389.782305)
			(xy 148.943479 -389.774175) (xy 148.895294 -389.758125) (xy 148.850299 -389.734567) (xy 148.809657 -389.704111)
			(xy 148.774414 -389.66754) (xy 148.74548 -389.6258) (xy 148.723602 -389.579966) (xy 148.715984 -389.555736)
			(xy 148.71446 -389.549894) (xy 148.394166 -388.996174) (xy 148.390102 -388.991856) (xy 148.373913 -388.974147)
			(xy 148.346538 -388.934744) (xy 148.325448 -388.891649) (xy 148.311131 -388.845856) (xy 148.303918 -388.798422)
			(xy 148.303488 -388.774432) (xy 148.303574 -388.762384) (xy 148.305356 -388.738355) (xy 148.307044 -388.726426)
			(xy 148.308314 -388.717536) (xy 148.305266 -388.700518) (xy 148.263102 -388.629652) (xy 148.249894 -388.618476)
			(xy 148.241512 -388.615428) (xy 148.21977 -388.607024) (xy 148.178922 -388.584574) (xy 148.14196 -388.556176)
			(xy 148.109744 -388.52249) (xy 148.083023 -388.484299) (xy 148.062416 -388.44249) (xy 148.048403 -388.398036)
			(xy 148.041309 -388.351967) (xy 148.040852 -388.328662) (xy 148.041351 -388.303263) (xy 148.04975 -388.253166)
			(xy 148.066326 -388.20515) (xy 148.090621 -388.16054) (xy 148.121966 -388.120567) (xy 148.14042 -388.10311)
			(xy 148.148802 -388.09549) (xy 148.157438 -388.075424) (xy 148.154644 -387.97611) (xy 148.145246 -387.956552)
			(xy 148.136356 -387.94944) (xy 148.117792 -387.933639) (xy 148.08506 -387.897515) (xy 148.057983 -387.856978)
			(xy 148.037146 -387.812908) (xy 148.023001 -387.766257) (xy 148.015854 -387.718036) (xy 148.015452 -387.693662)
			(xy 148.015891 -387.669546) (xy 148.022897 -387.621827) (xy 148.036757 -387.575629) (xy 148.057175 -387.531933)
			(xy 148.070062 -387.511544) (xy 148.075904 -387.502654) (xy 148.07946 -387.482588) (xy 148.058378 -387.390386)
			(xy 148.046186 -387.373622) (xy 148.037296 -387.368288) (xy 148.016492 -387.355434) (xy 147.97857 -387.324558)
			(xy 147.945615 -387.288429) (xy 147.918347 -387.247835) (xy 147.897362 -387.203665) (xy 147.883119 -387.156883)
			(xy 147.87593 -387.108513) (xy 147.875498 -387.084062) (xy 147.876059 -387.056779) (xy 147.88502 -387.002955)
			(xy 147.902692 -386.951331) (xy 147.928597 -386.903307) (xy 147.962031 -386.860185) (xy 147.98167 -386.841238)
			(xy 147.989122 -386.833748) (xy 147.99767 -386.814452) (xy 147.99818 -386.8039) (xy 147.99818 -386.729224)
			(xy 147.997593 -386.718689) (xy 147.989063 -386.699415) (xy 147.98167 -386.691886) (xy 147.962014 -386.672954)
			(xy 147.928568 -386.629834) (xy 147.902657 -386.581807) (xy 147.884985 -386.530178) (xy 147.87603 -386.476347)
			(xy 147.875498 -386.449062) (xy 147.875752 -386.43687) (xy 147.876006 -386.427218) (xy 147.86991 -386.409184)
			(xy 147.811236 -386.341874) (xy 147.794472 -386.333238) (xy 147.78482 -386.332222) (xy 147.757903 -386.328875)
			(xy 147.705596 -386.314538) (xy 147.656331 -386.291854) (xy 147.611429 -386.261434) (xy 147.572095 -386.224092)
			(xy 147.539383 -386.18083) (xy 147.514172 -386.132809) (xy 147.497137 -386.081317) (xy 147.492466 -386.0546)
			(xy 147.490942 -386.045202) (xy 147.218146 -385.57327) (xy 147.21078 -385.567428) (xy 147.192004 -385.551623)
			(xy 147.158876 -385.515414) (xy 147.131461 -385.474708) (xy 147.11036 -385.4304) (xy 147.096036 -385.38346)
			(xy 147.088803 -385.334919) (xy 147.088352 -385.31038) (xy 147.088784 -385.285968) (xy 147.095954 -385.237675)
			(xy 147.11015 -385.190961) (xy 147.131062 -385.146844) (xy 147.158237 -385.106282) (xy 147.191082 -385.070159)
			(xy 147.228884 -385.03926) (xy 147.249642 -385.026408) (xy 147.261326 -385.019296) (xy 147.274534 -384.996436)
			(xy 147.274534 -384.98272) (xy 147.27405 -384.972707) (xy 147.266395 -384.954203) (xy 147.252243 -384.940035)
			(xy 147.233746 -384.932361) (xy 147.223734 -384.93192) (xy 147.193508 -384.93192) (xy 147.186396 -384.934206)
			(xy 147.162892 -384.940878) (xy 147.114559 -384.948017) (xy 147.09013 -384.94843) (xy 147.065701 -384.948012)
			(xy 147.017368 -384.940875) (xy 146.993864 -384.934206) (xy 146.986752 -384.93192) (xy 146.805142 -384.93192)
			(xy 146.795077 -384.932354) (xy 146.77649 -384.940086) (xy 146.769074 -384.946906) (xy 145.84045 -385.87553)
			(xy 146.461734 -385.87553) (xy 146.462244 -385.849543) (xy 146.470374 -385.798208) (xy 146.486435 -385.748778)
			(xy 146.510031 -385.702468) (xy 146.540581 -385.66042) (xy 146.577332 -385.623669) (xy 146.61938 -385.593119)
			(xy 146.66569 -385.569523) (xy 146.71512 -385.553462) (xy 146.766455 -385.545332) (xy 146.818429 -385.545332)
			(xy 146.869764 -385.553462) (xy 146.919194 -385.569523) (xy 146.965504 -385.593119) (xy 147.007552 -385.623669)
			(xy 147.044303 -385.66042) (xy 147.074853 -385.702468) (xy 147.098449 -385.748778) (xy 147.11451 -385.798208)
			(xy 147.12264 -385.849543) (xy 147.12315 -385.87553) (xy 147.122767 -385.899206) (xy 147.116034 -385.946077)
			(xy 147.102668 -385.991504) (xy 147.093178 -386.013198) (xy 147.08886 -386.022596) (xy 147.088098 -386.042662)
			(xy 147.120356 -386.129022) (xy 147.134072 -386.143754) (xy 147.14347 -386.148072) (xy 147.167843 -386.159753)
			(xy 147.212712 -386.189883) (xy 147.252089 -386.226903) (xy 147.284927 -386.269829) (xy 147.310352 -386.317522)
			(xy 147.32769 -386.368712) (xy 147.336479 -386.422039) (xy 147.337018 -386.449062) (xy 147.336481 -386.476347)
			(xy 147.327527 -386.530177) (xy 147.309855 -386.581806) (xy 147.283946 -386.629833) (xy 147.250502 -386.672954)
			(xy 147.230846 -386.691886) (xy 147.223455 -386.699417) (xy 147.214923 -386.71869) (xy 147.214336 -386.729224)
			(xy 147.214336 -386.8039) (xy 147.214841 -386.814453) (xy 147.223392 -386.833749) (xy 147.230846 -386.841238)
			(xy 147.250488 -386.860182) (xy 147.283921 -386.903305) (xy 147.309825 -386.95133) (xy 147.327496 -387.002955)
			(xy 147.336457 -387.056779) (xy 147.337018 -387.084062) (xy 147.336573 -387.108178) (xy 147.329576 -387.155901)
			(xy 147.315725 -387.202102) (xy 147.295314 -387.245803) (xy 147.282408 -387.26618) (xy 147.276566 -387.27507)
			(xy 147.27301 -387.295136) (xy 147.294092 -387.387338) (xy 147.306284 -387.404102) (xy 147.315174 -387.409436)
			(xy 147.335984 -387.422277) (xy 147.373888 -387.45317) (xy 147.406828 -387.489309) (xy 147.434088 -387.529904)
			(xy 147.455071 -387.574072) (xy 147.469322 -387.620848) (xy 147.476529 -387.669213) (xy 147.476972 -387.693662)
			(xy 147.476561 -387.718036) (xy 147.469415 -387.766256) (xy 147.455271 -387.812906) (xy 147.434436 -387.856977)
			(xy 147.40736 -387.897513) (xy 147.374631 -387.933639) (xy 147.356068 -387.94944) (xy 147.347178 -387.956552)
			(xy 147.33778 -387.97611) (xy 147.334986 -388.075424) (xy 147.343622 -388.09549) (xy 147.352004 -388.10311)
			(xy 147.370443 -388.120582) (xy 147.401793 -388.160549) (xy 147.426093 -388.205155) (xy 147.442672 -388.253168)
			(xy 147.451072 -388.303264) (xy 147.451572 -388.328662) (xy 147.451503 -388.338021) (xy 147.45036 -388.356703)
			(xy 147.449286 -388.366) (xy 147.44827 -388.37489) (xy 147.45208 -388.391654) (xy 147.496022 -388.461504)
			(xy 147.509738 -388.471918) (xy 147.51812 -388.474712) (xy 147.542144 -388.48319) (xy 147.587317 -388.506741)
			(xy 147.628123 -388.537238) (xy 147.663503 -388.573891) (xy 147.692539 -388.615748) (xy 147.714479 -388.661725)
			(xy 147.722082 -388.68604) (xy 147.723606 -388.691882) (xy 148.0439 -389.245602) (xy 148.047964 -389.24992)
			(xy 148.064166 -389.267629) (xy 148.091588 -389.307021) (xy 148.11273 -389.35011) (xy 148.127105 -389.395904)
			(xy 148.13438 -389.443346) (xy 148.134832 -389.467344) (xy 148.134447 -389.492151) (xy 148.126674 -389.541153)
			(xy 148.111329 -389.588335) (xy 148.088788 -389.632534) (xy 148.059607 -389.67266) (xy 148.024505 -389.707724)
			(xy 147.984349 -389.736862) (xy 147.940126 -389.759357) (xy 147.892928 -389.774652) (xy 147.843918 -389.782373)
			(xy 147.81911 -389.782812) (xy 147.793716 -389.782303) (xy 147.743583 -389.774174) (xy 147.695397 -389.758124)
			(xy 147.650403 -389.734567) (xy 147.60976 -389.70411) (xy 147.574517 -389.66754) (xy 147.545583 -389.6258)
			(xy 147.523705 -389.579966) (xy 147.516088 -389.555736) (xy 147.514564 -389.549894) (xy 147.19427 -388.996174)
			(xy 147.190206 -388.991856) (xy 147.174039 -388.974129) (xy 147.146673 -388.934724) (xy 147.125585 -388.891633)
			(xy 147.111259 -388.845846) (xy 147.104026 -388.79842) (xy 147.103592 -388.774432) (xy 147.103673 -388.762384)
			(xy 147.105456 -388.738355) (xy 147.107148 -388.726426) (xy 147.108418 -388.717536) (xy 147.10537 -388.700518)
			(xy 147.063206 -388.629652) (xy 147.049998 -388.618476) (xy 147.041616 -388.615428) (xy 147.019878 -388.607008)
			(xy 146.979018 -388.584573) (xy 146.942046 -388.556184) (xy 146.909821 -388.522503) (xy 146.883094 -388.484312)
			(xy 146.862487 -388.442501) (xy 146.848478 -388.398042) (xy 146.841394 -388.351969) (xy 146.840956 -388.328662)
			(xy 146.841464 -388.303266) (xy 146.849875 -388.253175) (xy 146.866458 -388.205167) (xy 146.890757 -388.160564)
			(xy 146.922101 -388.120597) (xy 146.940524 -388.10311) (xy 146.948906 -388.09549) (xy 146.957542 -388.075424)
			(xy 146.954748 -387.97611) (xy 146.94535 -387.956552) (xy 146.93646 -387.94944) (xy 146.917924 -387.93361)
			(xy 146.885203 -387.897485) (xy 146.858132 -387.856952) (xy 146.837298 -387.812888) (xy 146.82315 -387.766246)
			(xy 146.815994 -387.718033) (xy 146.815556 -387.693662) (xy 146.815969 -387.669544) (xy 146.822976 -387.621821)
			(xy 146.836836 -387.57562) (xy 146.857257 -387.53192) (xy 146.870166 -387.511544) (xy 146.876008 -387.502654)
			(xy 146.879564 -387.482588) (xy 146.858482 -387.390386) (xy 146.84629 -387.373622) (xy 146.8374 -387.368288)
			(xy 146.816618 -387.355404) (xy 146.77871 -387.324521) (xy 146.745765 -387.288391) (xy 146.718501 -387.247802)
			(xy 146.697513 -387.203641) (xy 146.683258 -387.15687) (xy 146.676047 -387.10851) (xy 146.675602 -387.084062)
			(xy 146.676148 -387.056777) (xy 146.685099 -387.002947) (xy 146.702768 -386.951318) (xy 146.728676 -386.903291)
			(xy 146.762119 -386.86017) (xy 146.781774 -386.841238) (xy 146.789157 -386.833701) (xy 146.797693 -386.814433)
			(xy 146.798284 -386.8039) (xy 146.798284 -386.729224) (xy 146.79776 -386.718674) (xy 146.789222 -386.699378)
			(xy 146.781774 -386.691886) (xy 146.762147 -386.672927) (xy 146.728711 -386.629808) (xy 146.702804 -386.581787)
			(xy 146.685129 -386.530166) (xy 146.676165 -386.476344) (xy 146.675602 -386.449062) (xy 146.675987 -386.425386)
			(xy 146.68272 -386.378515) (xy 146.696084 -386.333089) (xy 146.705574 -386.311394) (xy 146.709892 -386.301996)
			(xy 146.710654 -386.28193) (xy 146.678396 -386.19557) (xy 146.66468 -386.180838) (xy 146.655282 -386.17652)
			(xy 146.630917 -386.164821) (xy 146.586046 -386.134697) (xy 146.546666 -386.097681) (xy 146.513827 -386.054758)
			(xy 146.4884 -386.007067) (xy 146.471061 -385.955879) (xy 146.462273 -385.902553) (xy 146.461734 -385.87553)
			(xy 145.84045 -385.87553) (xy 144.955514 -386.760466) (xy 144.95526 -386.802122) (xy 144.969738 -386.817108)
			(xy 144.987205 -386.835742) (xy 145.016768 -386.877388) (xy 145.039581 -386.923082) (xy 145.055101 -386.97174)
			(xy 145.062959 -387.022204) (xy 145.063464 -387.04774) (xy 145.062978 -387.073726) (xy 145.054841 -387.125057)
			(xy 145.038775 -387.174483) (xy 145.015174 -387.220788) (xy 144.984621 -387.26283) (xy 144.947866 -387.299575)
			(xy 144.905816 -387.330118) (xy 144.859506 -387.353707) (xy 144.810075 -387.369761) (xy 144.758742 -387.377884)
			(xy 144.732756 -387.378448) (xy 144.707217 -387.377977) (xy 144.656745 -387.370128) (xy 144.608082 -387.354609)
			(xy 144.562384 -387.331788) (xy 144.520742 -387.30221) (xy 144.502124 -387.284722) (xy 144.487138 -387.270244)
			(xy 144.445482 -387.270498) (xy 143.934942 -387.781038) (xy 143.926605 -387.790315) (xy 143.919409 -387.814165)
			(xy 143.921226 -387.826504) (xy 143.939768 -387.921754) (xy 143.955516 -387.941312) (xy 143.9672 -387.946392)
			(xy 143.992738 -387.957702) (xy 144.040474 -387.986699) (xy 144.083466 -388.022354) (xy 144.120793 -388.063901)
			(xy 144.151657 -388.110452) (xy 144.175396 -388.161009) (xy 144.191501 -388.214489) (xy 144.199628 -388.269747)
			(xy 144.200118 -388.297674) (xy 144.199704 -388.322137) (xy 144.402558 -388.322137) (xy 144.402558 -388.270163)
			(xy 144.410688 -388.218828) (xy 144.426749 -388.169398) (xy 144.450345 -388.123088) (xy 144.480895 -388.08104)
			(xy 144.517646 -388.044289) (xy 144.559694 -388.013739) (xy 144.606004 -387.990143) (xy 144.655434 -387.974082)
			(xy 144.706769 -387.965952) (xy 144.758743 -387.965952) (xy 144.810078 -387.974082) (xy 144.859508 -387.990143)
			(xy 144.905818 -388.013739) (xy 144.947866 -388.044289) (xy 144.984617 -388.08104) (xy 145.015167 -388.123088)
			(xy 145.038763 -388.169398) (xy 145.054824 -388.218828) (xy 145.062954 -388.270163) (xy 145.063464 -388.29615)
			(xy 145.062954 -388.322137) (xy 145.054824 -388.373472) (xy 145.038763 -388.422902) (xy 145.015167 -388.469212)
			(xy 144.984617 -388.51126) (xy 144.947866 -388.548011) (xy 144.905818 -388.578561) (xy 144.859508 -388.602157)
			(xy 144.810078 -388.618218) (xy 144.758743 -388.626348) (xy 144.706769 -388.626348) (xy 144.655434 -388.618218)
			(xy 144.606004 -388.602157) (xy 144.559694 -388.578561) (xy 144.517646 -388.548011) (xy 144.480895 -388.51126)
			(xy 144.450345 -388.469212) (xy 144.426749 -388.422902) (xy 144.410688 -388.373472) (xy 144.402558 -388.322137)
			(xy 144.199704 -388.322137) (xy 144.199657 -388.324928) (xy 144.191903 -388.378883) (xy 144.176549 -388.431184)
			(xy 144.153908 -388.480768) (xy 144.124441 -388.526626) (xy 144.088748 -388.567822) (xy 144.047554 -388.60352)
			(xy 144.0017 -388.632991) (xy 143.952118 -388.655637) (xy 143.899818 -388.670995) (xy 143.845864 -388.678754)
			(xy 143.81861 -388.679182) (xy 143.790687 -388.678689) (xy 143.73544 -388.670533) (xy 143.681971 -388.65441)
			(xy 143.631425 -388.630664) (xy 143.584881 -388.599802) (xy 143.543334 -388.562484) (xy 143.507672 -388.519507)
			(xy 143.478657 -388.471791) (xy 143.467328 -388.446264) (xy 143.462248 -388.43458) (xy 143.44269 -388.418832)
			(xy 143.34744 -388.40029) (xy 143.335113 -388.398678) (xy 143.311348 -388.40584) (xy 143.301974 -388.414006)
			(xy 142.153386 -389.562594) (xy 142.145987 -389.569439) (xy 142.127389 -389.577169) (xy 142.117318 -389.57758)
			(xy 140.696442 -389.57758) (xy 140.686376 -389.578013) (xy 140.667785 -389.58574) (xy 140.660374 -389.592566)
			(xy 140.321284 -389.931656) (xy 140.319506 -389.970772) (xy 140.331952 -389.985758) (xy 140.353618 -390.013149)
			(xy 140.390035 -390.07274) (xy 140.417961 -390.136752) (xy 140.436871 -390.203981) (xy 140.44641 -390.273165)
			(xy 140.447014 -390.308084) (xy 140.44652 -390.340247) (xy 140.438405 -390.40406) (xy 140.422302 -390.466339)
			(xy 140.398468 -390.526088) (xy 140.367285 -390.582351) (xy 140.329252 -390.63423) (xy 140.284976 -390.680894)
			(xy 140.235165 -390.721599) (xy 140.180616 -390.755692) (xy 140.151612 -390.769602) (xy 140.142249 -390.774603)
			(xy 140.128322 -390.79059) (xy 140.121992 -390.810825) (xy 140.122656 -390.821418) (xy 140.124112 -390.835533)
			(xy 140.125639 -390.86387) (xy 140.125704 -390.87806) (xy 140.125433 -390.901115) (xy 140.121234 -390.947032)
			(xy 140.117322 -390.969754) (xy 140.11656 -390.974072) (xy 140.11656 -391.096246) (xy 140.13688 -391.12317)
			(xy 140.153136 -391.127996) (xy 140.184335 -391.137721) (xy 140.244135 -391.164077) (xy 140.300069 -391.197872)
			(xy 140.351216 -391.23855) (xy 140.396735 -391.285441) (xy 140.435877 -391.337773) (xy 140.467997 -391.394685)
			(xy 140.492567 -391.455241) (xy 140.509183 -391.518445) (xy 140.51757 -391.583255) (xy 140.518134 -391.61593)
			(xy 140.517653 -391.646624) (xy 140.510229 -391.707563) (xy 140.495528 -391.767167) (xy 140.473764 -391.824569)
			(xy 140.445253 -391.878936) (xy 140.428218 -391.904474) (xy 140.42275 -391.913225) (xy 140.418631 -391.933425)
			(xy 140.42277 -391.953621) (xy 140.428218 -391.962386) (xy 140.445272 -391.987913) (xy 140.4738 -392.042276)
			(xy 140.495571 -392.09968) (xy 140.510266 -392.159288) (xy 140.517671 -392.220233) (xy 140.518134 -392.25093)
			(xy 140.517668 -392.28166) (xy 140.510257 -392.342673) (xy 140.495546 -392.402347) (xy 140.47375 -392.459813)
			(xy 140.445186 -392.514233) (xy 140.410271 -392.564814) (xy 140.369515 -392.610818) (xy 140.323511 -392.651574)
			(xy 140.27293 -392.686488) (xy 140.218509 -392.715051) (xy 140.161043 -392.736847) (xy 140.101369 -392.751558)
			(xy 140.040356 -392.758968) (xy 140.009626 -392.759438) (xy 139.988544 -392.75893) (xy 139.977622 -392.758422)
			(xy 139.958064 -392.766042) (xy 139.889738 -392.834368) (xy 139.882118 -392.853926) (xy 139.882626 -392.864848)
			(xy 139.883134 -392.88593) (xy 139.882653 -392.916624) (xy 139.875229 -392.977563) (xy 139.860528 -393.037167)
			(xy 139.838764 -393.094569) (xy 139.810253 -393.148936) (xy 139.793218 -393.174474) (xy 139.78775 -393.183225)
			(xy 139.783631 -393.203425) (xy 139.78777 -393.223621) (xy 139.793218 -393.232386) (xy 139.810272 -393.257913)
			(xy 139.8388 -393.312276) (xy 139.860571 -393.36968) (xy 139.875266 -393.429288) (xy 139.882671 -393.490233)
			(xy 139.883134 -393.52093) (xy 140.738098 -393.52093) (xy 140.738582 -393.49356) (xy 140.746396 -393.439382)
			(xy 140.761881 -393.386879) (xy 140.784718 -393.337132) (xy 140.814439 -393.291164) (xy 140.832078 -393.270232)
			(xy 140.838174 -393.26312) (xy 140.844524 -393.246102) (xy 140.844524 -393.160758) (xy 140.838174 -393.14374)
			(xy 140.832078 -393.136628) (xy 140.814469 -393.11567) (xy 140.784746 -393.069706) (xy 140.761902 -393.019963)
			(xy 140.746406 -392.967465) (xy 140.738576 -392.913291) (xy 140.738572 -392.858554) (xy 140.746396 -392.804379)
			(xy 140.761886 -392.751879) (xy 140.784725 -392.702134) (xy 140.814441 -392.656166) (xy 140.832078 -392.635232)
			(xy 140.838174 -392.62812) (xy 140.844524 -392.611102) (xy 140.844524 -392.525758) (xy 140.838174 -392.50874)
			(xy 140.832078 -392.501628) (xy 140.814469 -392.48067) (xy 140.784746 -392.434706) (xy 140.761902 -392.384963)
			(xy 140.746406 -392.332465) (xy 140.738576 -392.278291) (xy 140.738572 -392.223554) (xy 140.746396 -392.169379)
			(xy 140.761886 -392.116879) (xy 140.784725 -392.067134) (xy 140.814441 -392.021166) (xy 140.832078 -392.000232)
			(xy 140.838174 -391.99312) (xy 140.844524 -391.976102) (xy 140.844524 -391.890758) (xy 140.838174 -391.87374)
			(xy 140.832078 -391.866628) (xy 140.814435 -391.845699) (xy 140.784725 -391.799725) (xy 140.76189 -391.749977)
			(xy 140.7464 -391.697475) (xy 140.738572 -391.643299) (xy 140.738098 -391.61593) (xy 140.738601 -391.588394)
			(xy 140.746503 -391.533894) (xy 140.762163 -391.481096) (xy 140.785253 -391.4311) (xy 140.815294 -391.384945)
			(xy 140.851662 -391.34359) (xy 140.8936 -391.307897) (xy 140.91666 -391.292842) (xy 140.925296 -391.287508)
			(xy 140.936726 -391.271252) (xy 140.957808 -391.181844) (xy 140.954506 -391.162286) (xy 140.949172 -391.15365)
			(xy 140.935741 -391.130982) (xy 140.91457 -391.082732) (xy 140.900225 -391.032032) (xy 140.892977 -390.979843)
			(xy 140.89253 -390.953498) (xy 140.892988 -390.926127) (xy 140.900806 -390.871948) (xy 140.916297 -390.819444)
			(xy 140.939141 -390.769697) (xy 140.968868 -390.723731) (xy 140.98651 -390.7028) (xy 140.992606 -390.695688)
			(xy 140.998956 -390.67867) (xy 140.998956 -390.593326) (xy 140.992606 -390.576308) (xy 140.98651 -390.569196)
			(xy 140.968857 -390.548275) (xy 140.939147 -390.502299) (xy 140.916314 -390.452549) (xy 140.900826 -390.400046)
			(xy 140.893002 -390.345868) (xy 140.89253 -390.318498) (xy 140.893016 -390.291247) (xy 140.900772 -390.237299)
			(xy 140.916127 -390.185004) (xy 140.938769 -390.135427) (xy 140.968235 -390.089577) (xy 141.003926 -390.048386)
			(xy 141.045117 -390.012695) (xy 141.090967 -389.983229) (xy 141.140544 -389.960587) (xy 141.192839 -389.945232)
			(xy 141.246787 -389.937476) (xy 141.301289 -389.937476) (xy 141.355237 -389.945232) (xy 141.407532 -389.960587)
			(xy 141.457109 -389.983229) (xy 141.502959 -390.012695) (xy 141.54415 -390.048386) (xy 141.579841 -390.089577)
			(xy 141.609307 -390.135427) (xy 141.631949 -390.185004) (xy 141.647304 -390.237299) (xy 141.65506 -390.291247)
			(xy 141.655546 -390.318498) (xy 141.655092 -390.345869) (xy 141.647273 -390.400049) (xy 141.631782 -390.452553)
			(xy 141.608937 -390.502299) (xy 141.579209 -390.548265) (xy 141.561566 -390.569196) (xy 141.55547 -390.576308)
			(xy 141.54912 -390.593326) (xy 141.54912 -390.626092) (xy 144.390364 -390.626092) (xy 144.390783 -390.602859)
			(xy 144.397277 -390.556849) (xy 144.410148 -390.512202) (xy 144.429145 -390.469797) (xy 144.453892 -390.43047)
			(xy 144.468596 -390.412478) (xy 144.474692 -390.405366) (xy 144.480788 -390.388856) (xy 144.480788 -390.304528)
			(xy 144.474692 -390.288018) (xy 144.468596 -390.280906) (xy 144.453875 -390.262926) (xy 144.429131 -390.223594)
			(xy 144.410134 -390.181186) (xy 144.397258 -390.136538) (xy 144.390757 -390.090526) (xy 144.390364 -390.067292)
			(xy 144.390874 -390.041305) (xy 144.399004 -389.98997) (xy 144.415065 -389.94054) (xy 144.438661 -389.89423)
			(xy 144.469211 -389.852182) (xy 144.505962 -389.815431) (xy 144.54801 -389.784881) (xy 144.59432 -389.761285)
			(xy 144.64375 -389.745224) (xy 144.695085 -389.737094) (xy 144.747059 -389.737094) (xy 144.798394 -389.745224)
			(xy 144.847824 -389.761285) (xy 144.894134 -389.784881) (xy 144.936182 -389.815431) (xy 144.972933 -389.852182)
			(xy 145.003483 -389.89423) (xy 145.027079 -389.94054) (xy 145.04314 -389.98997) (xy 145.05127 -390.041305)
			(xy 145.05178 -390.067292) (xy 145.051423 -390.090527) (xy 145.044917 -390.13654) (xy 145.038146 -390.160002)
			(xy 146.712952 -390.160002) (xy 146.716912 -390.110948) (xy 146.728689 -390.063164) (xy 146.74798 -390.017888)
			(xy 146.774283 -389.976292) (xy 146.806918 -389.939455) (xy 146.845039 -389.90833) (xy 146.88766 -389.883723)
			(xy 146.933676 -389.866271) (xy 146.981895 -389.856427) (xy 147.03107 -389.854446) (xy 147.079925 -389.860378)
			(xy 147.127196 -389.87407) (xy 147.171658 -389.895168) (xy 147.212161 -389.923124) (xy 147.247654 -389.957216)
			(xy 147.277219 -389.99656) (xy 147.30009 -390.040137) (xy 147.315674 -390.086818) (xy 147.323569 -390.135395)
			(xy 147.324064 -390.160002) (xy 147.913102 -390.160002) (xy 147.917062 -390.110948) (xy 147.928839 -390.063164)
			(xy 147.94813 -390.017888) (xy 147.974433 -389.976292) (xy 148.007068 -389.939455) (xy 148.045189 -389.90833)
			(xy 148.08781 -389.883723) (xy 148.133826 -389.866271) (xy 148.182045 -389.856427) (xy 148.23122 -389.854446)
			(xy 148.280075 -389.860378) (xy 148.327346 -389.87407) (xy 148.371808 -389.895168) (xy 148.412311 -389.923124)
			(xy 148.447804 -389.957216) (xy 148.477369 -389.99656) (xy 148.50024 -390.040137) (xy 148.515824 -390.086818)
			(xy 148.523719 -390.135395) (xy 148.524214 -390.160002) (xy 149.113252 -390.160002) (xy 149.117212 -390.110948)
			(xy 149.128989 -390.063164) (xy 149.14828 -390.017888) (xy 149.174583 -389.976292) (xy 149.207218 -389.939455)
			(xy 149.245339 -389.90833) (xy 149.28796 -389.883723) (xy 149.333976 -389.866271) (xy 149.382195 -389.856427)
			(xy 149.43137 -389.854446) (xy 149.480225 -389.860378) (xy 149.527496 -389.87407) (xy 149.571958 -389.895168)
			(xy 149.612461 -389.923124) (xy 149.647954 -389.957216) (xy 149.677519 -389.99656) (xy 149.70039 -390.040137)
			(xy 149.715974 -390.086818) (xy 149.723869 -390.135395) (xy 149.724364 -390.160002) (xy 150.313148 -390.160002)
			(xy 150.317108 -390.110948) (xy 150.328885 -390.063164) (xy 150.348176 -390.017888) (xy 150.374479 -389.976292)
			(xy 150.407114 -389.939455) (xy 150.445235 -389.90833) (xy 150.487856 -389.883723) (xy 150.533872 -389.866271)
			(xy 150.582091 -389.856427) (xy 150.631266 -389.854446) (xy 150.680121 -389.860378) (xy 150.727392 -389.87407)
			(xy 150.771854 -389.895168) (xy 150.812357 -389.923124) (xy 150.84785 -389.957216) (xy 150.877415 -389.99656)
			(xy 150.900286 -390.040137) (xy 150.91587 -390.086818) (xy 150.923765 -390.135395) (xy 150.92426 -390.160002)
			(xy 151.513298 -390.160002) (xy 151.517258 -390.110948) (xy 151.529035 -390.063164) (xy 151.548326 -390.017888)
			(xy 151.574629 -389.976292) (xy 151.607264 -389.939455) (xy 151.645385 -389.90833) (xy 151.688006 -389.883723)
			(xy 151.734022 -389.866271) (xy 151.782241 -389.856427) (xy 151.831416 -389.854446) (xy 151.880271 -389.860378)
			(xy 151.927542 -389.87407) (xy 151.972004 -389.895168) (xy 152.012507 -389.923124) (xy 152.048 -389.957216)
			(xy 152.077565 -389.99656) (xy 152.100436 -390.040137) (xy 152.11602 -390.086818) (xy 152.123915 -390.135395)
			(xy 152.12441 -390.160002) (xy 152.713194 -390.160002) (xy 152.717154 -390.110948) (xy 152.728931 -390.063164)
			(xy 152.748222 -390.017888) (xy 152.774525 -389.976292) (xy 152.80716 -389.939455) (xy 152.845281 -389.90833)
			(xy 152.887902 -389.883723) (xy 152.933918 -389.866271) (xy 152.982137 -389.856427) (xy 153.031312 -389.854446)
			(xy 153.080167 -389.860378) (xy 153.127438 -389.87407) (xy 153.1719 -389.895168) (xy 153.212403 -389.923124)
			(xy 153.247896 -389.957216) (xy 153.277461 -389.99656) (xy 153.300332 -390.040137) (xy 153.315916 -390.086818)
			(xy 153.323811 -390.135395) (xy 153.324306 -390.160002) (xy 153.91309 -390.160002) (xy 153.91705 -390.110948)
			(xy 153.928827 -390.063164) (xy 153.948118 -390.017888) (xy 153.974421 -389.976292) (xy 154.007056 -389.939455)
			(xy 154.045177 -389.90833) (xy 154.087798 -389.883723) (xy 154.133814 -389.866271) (xy 154.182033 -389.856427)
			(xy 154.231208 -389.854446) (xy 154.280063 -389.860378) (xy 154.327334 -389.87407) (xy 154.371796 -389.895168)
			(xy 154.412299 -389.923124) (xy 154.447792 -389.957216) (xy 154.477357 -389.99656) (xy 154.500228 -390.040137)
			(xy 154.515812 -390.086818) (xy 154.523707 -390.135395) (xy 154.524202 -390.160002) (xy 155.11324 -390.160002)
			(xy 155.1172 -390.110948) (xy 155.128977 -390.063164) (xy 155.148268 -390.017888) (xy 155.174571 -389.976292)
			(xy 155.207206 -389.939455) (xy 155.245327 -389.90833) (xy 155.287948 -389.883723) (xy 155.333964 -389.866271)
			(xy 155.382183 -389.856427) (xy 155.431358 -389.854446) (xy 155.480213 -389.860378) (xy 155.527484 -389.87407)
			(xy 155.571946 -389.895168) (xy 155.612449 -389.923124) (xy 155.647942 -389.957216) (xy 155.677507 -389.99656)
			(xy 155.700378 -390.040137) (xy 155.715962 -390.086818) (xy 155.723857 -390.135395) (xy 155.724352 -390.160002)
			(xy 156.313136 -390.160002) (xy 156.317096 -390.110948) (xy 156.328873 -390.063164) (xy 156.348164 -390.017888)
			(xy 156.374467 -389.976292) (xy 156.407102 -389.939455) (xy 156.445223 -389.90833) (xy 156.487844 -389.883723)
			(xy 156.53386 -389.866271) (xy 156.582079 -389.856427) (xy 156.631254 -389.854446) (xy 156.680109 -389.860378)
			(xy 156.72738 -389.87407) (xy 156.771842 -389.895168) (xy 156.812345 -389.923124) (xy 156.847838 -389.957216)
			(xy 156.877403 -389.99656) (xy 156.900274 -390.040137) (xy 156.915858 -390.086818) (xy 156.923753 -390.135395)
			(xy 156.924248 -390.160002) (xy 157.513286 -390.160002) (xy 157.517246 -390.110948) (xy 157.529023 -390.063164)
			(xy 157.548314 -390.017888) (xy 157.574617 -389.976292) (xy 157.607252 -389.939455) (xy 157.645373 -389.90833)
			(xy 157.687994 -389.883723) (xy 157.73401 -389.866271) (xy 157.782229 -389.856427) (xy 157.831404 -389.854446)
			(xy 157.880259 -389.860378) (xy 157.92753 -389.87407) (xy 157.971992 -389.895168) (xy 158.012495 -389.923124)
			(xy 158.047988 -389.957216) (xy 158.077553 -389.99656) (xy 158.100424 -390.040137) (xy 158.116008 -390.086818)
			(xy 158.123903 -390.135395) (xy 158.124398 -390.160002) (xy 158.713182 -390.160002) (xy 158.717142 -390.110948)
			(xy 158.728919 -390.063164) (xy 158.74821 -390.017888) (xy 158.774513 -389.976292) (xy 158.807148 -389.939455)
			(xy 158.845269 -389.90833) (xy 158.88789 -389.883723) (xy 158.933906 -389.866271) (xy 158.982125 -389.856427)
			(xy 159.0313 -389.854446) (xy 159.080155 -389.860378) (xy 159.127426 -389.87407) (xy 159.171888 -389.895168)
			(xy 159.212391 -389.923124) (xy 159.247884 -389.957216) (xy 159.277449 -389.99656) (xy 159.30032 -390.040137)
			(xy 159.315904 -390.086818) (xy 159.323799 -390.135395) (xy 159.324294 -390.160002) (xy 159.913078 -390.160002)
			(xy 159.917038 -390.110948) (xy 159.928815 -390.063164) (xy 159.948106 -390.017888) (xy 159.974409 -389.976292)
			(xy 160.007044 -389.939455) (xy 160.045165 -389.90833) (xy 160.087786 -389.883723) (xy 160.133802 -389.866271)
			(xy 160.182021 -389.856427) (xy 160.231196 -389.854446) (xy 160.280051 -389.860378) (xy 160.327322 -389.87407)
			(xy 160.371784 -389.895168) (xy 160.412287 -389.923124) (xy 160.44778 -389.957216) (xy 160.477345 -389.99656)
			(xy 160.500216 -390.040137) (xy 160.5158 -390.086818) (xy 160.523695 -390.135395) (xy 160.52419 -390.160002)
			(xy 161.113228 -390.160002) (xy 161.117188 -390.110948) (xy 161.128965 -390.063164) (xy 161.148256 -390.017888)
			(xy 161.174559 -389.976292) (xy 161.207194 -389.939455) (xy 161.245315 -389.90833) (xy 161.287936 -389.883723)
			(xy 161.333952 -389.866271) (xy 161.382171 -389.856427) (xy 161.431346 -389.854446) (xy 161.480201 -389.860378)
			(xy 161.527472 -389.87407) (xy 161.571934 -389.895168) (xy 161.612437 -389.923124) (xy 161.64793 -389.957216)
			(xy 161.677495 -389.99656) (xy 161.700366 -390.040137) (xy 161.71595 -390.086818) (xy 161.723845 -390.135395)
			(xy 161.72434 -390.160002) (xy 162.313124 -390.160002) (xy 162.317084 -390.110948) (xy 162.328861 -390.063164)
			(xy 162.348152 -390.017888) (xy 162.374455 -389.976292) (xy 162.40709 -389.939455) (xy 162.445211 -389.90833)
			(xy 162.487832 -389.883723) (xy 162.533848 -389.866271) (xy 162.582067 -389.856427) (xy 162.631242 -389.854446)
			(xy 162.680097 -389.860378) (xy 162.727368 -389.87407) (xy 162.77183 -389.895168) (xy 162.812333 -389.923124)
			(xy 162.847826 -389.957216) (xy 162.877391 -389.99656) (xy 162.900262 -390.040137) (xy 162.915846 -390.086818)
			(xy 162.923741 -390.135395) (xy 162.924236 -390.160002) (xy 163.513274 -390.160002) (xy 163.517234 -390.110948)
			(xy 163.529011 -390.063164) (xy 163.548302 -390.017888) (xy 163.574605 -389.976292) (xy 163.60724 -389.939455)
			(xy 163.645361 -389.90833) (xy 163.687982 -389.883723) (xy 163.733998 -389.866271) (xy 163.782217 -389.856427)
			(xy 163.831392 -389.854446) (xy 163.880247 -389.860378) (xy 163.927518 -389.87407) (xy 163.97198 -389.895168)
			(xy 164.012483 -389.923124) (xy 164.047976 -389.957216) (xy 164.077541 -389.99656) (xy 164.100412 -390.040137)
			(xy 164.115996 -390.086818) (xy 164.123891 -390.135395) (xy 164.124386 -390.160002) (xy 164.123891 -390.184609)
			(xy 164.115996 -390.233186) (xy 164.100412 -390.279867) (xy 164.077541 -390.323444) (xy 164.047976 -390.362788)
			(xy 164.012483 -390.39688) (xy 163.97198 -390.424836) (xy 163.927518 -390.445934) (xy 163.880247 -390.459626)
			(xy 163.831392 -390.465558) (xy 163.782217 -390.463577) (xy 163.733998 -390.453733) (xy 163.687982 -390.436281)
			(xy 163.645361 -390.411674) (xy 163.60724 -390.380549) (xy 163.574605 -390.343712) (xy 163.548302 -390.302116)
			(xy 163.529011 -390.25684) (xy 163.517234 -390.209056) (xy 163.513274 -390.160002) (xy 162.924236 -390.160002)
			(xy 162.923741 -390.184609) (xy 162.915846 -390.233186) (xy 162.900262 -390.279867) (xy 162.877391 -390.323444)
			(xy 162.847826 -390.362788) (xy 162.812333 -390.39688) (xy 162.77183 -390.424836) (xy 162.727368 -390.445934)
			(xy 162.680097 -390.459626) (xy 162.631242 -390.465558) (xy 162.582067 -390.463577) (xy 162.533848 -390.453733)
			(xy 162.487832 -390.436281) (xy 162.445211 -390.411674) (xy 162.40709 -390.380549) (xy 162.374455 -390.343712)
			(xy 162.348152 -390.302116) (xy 162.328861 -390.25684) (xy 162.317084 -390.209056) (xy 162.313124 -390.160002)
			(xy 161.72434 -390.160002) (xy 161.723845 -390.184609) (xy 161.71595 -390.233186) (xy 161.700366 -390.279867)
			(xy 161.677495 -390.323444) (xy 161.64793 -390.362788) (xy 161.612437 -390.39688) (xy 161.571934 -390.424836)
			(xy 161.527472 -390.445934) (xy 161.480201 -390.459626) (xy 161.431346 -390.465558) (xy 161.382171 -390.463577)
			(xy 161.333952 -390.453733) (xy 161.287936 -390.436281) (xy 161.245315 -390.411674) (xy 161.207194 -390.380549)
			(xy 161.174559 -390.343712) (xy 161.148256 -390.302116) (xy 161.128965 -390.25684) (xy 161.117188 -390.209056)
			(xy 161.113228 -390.160002) (xy 160.52419 -390.160002) (xy 160.523695 -390.184609) (xy 160.5158 -390.233186)
			(xy 160.500216 -390.279867) (xy 160.477345 -390.323444) (xy 160.44778 -390.362788) (xy 160.412287 -390.39688)
			(xy 160.371784 -390.424836) (xy 160.327322 -390.445934) (xy 160.280051 -390.459626) (xy 160.231196 -390.465558)
			(xy 160.182021 -390.463577) (xy 160.133802 -390.453733) (xy 160.087786 -390.436281) (xy 160.045165 -390.411674)
			(xy 160.007044 -390.380549) (xy 159.974409 -390.343712) (xy 159.948106 -390.302116) (xy 159.928815 -390.25684)
			(xy 159.917038 -390.209056) (xy 159.913078 -390.160002) (xy 159.324294 -390.160002) (xy 159.323799 -390.184609)
			(xy 159.315904 -390.233186) (xy 159.30032 -390.279867) (xy 159.277449 -390.323444) (xy 159.247884 -390.362788)
			(xy 159.212391 -390.39688) (xy 159.171888 -390.424836) (xy 159.127426 -390.445934) (xy 159.080155 -390.459626)
			(xy 159.0313 -390.465558) (xy 158.982125 -390.463577) (xy 158.933906 -390.453733) (xy 158.88789 -390.436281)
			(xy 158.845269 -390.411674) (xy 158.807148 -390.380549) (xy 158.774513 -390.343712) (xy 158.74821 -390.302116)
			(xy 158.728919 -390.25684) (xy 158.717142 -390.209056) (xy 158.713182 -390.160002) (xy 158.124398 -390.160002)
			(xy 158.123903 -390.184609) (xy 158.116008 -390.233186) (xy 158.100424 -390.279867) (xy 158.077553 -390.323444)
			(xy 158.047988 -390.362788) (xy 158.012495 -390.39688) (xy 157.971992 -390.424836) (xy 157.92753 -390.445934)
			(xy 157.880259 -390.459626) (xy 157.831404 -390.465558) (xy 157.782229 -390.463577) (xy 157.73401 -390.453733)
			(xy 157.687994 -390.436281) (xy 157.645373 -390.411674) (xy 157.607252 -390.380549) (xy 157.574617 -390.343712)
			(xy 157.548314 -390.302116) (xy 157.529023 -390.25684) (xy 157.517246 -390.209056) (xy 157.513286 -390.160002)
			(xy 156.924248 -390.160002) (xy 156.923753 -390.184609) (xy 156.915858 -390.233186) (xy 156.900274 -390.279867)
			(xy 156.877403 -390.323444) (xy 156.847838 -390.362788) (xy 156.812345 -390.39688) (xy 156.771842 -390.424836)
			(xy 156.72738 -390.445934) (xy 156.680109 -390.459626) (xy 156.631254 -390.465558) (xy 156.582079 -390.463577)
			(xy 156.53386 -390.453733) (xy 156.487844 -390.436281) (xy 156.445223 -390.411674) (xy 156.407102 -390.380549)
			(xy 156.374467 -390.343712) (xy 156.348164 -390.302116) (xy 156.328873 -390.25684) (xy 156.317096 -390.209056)
			(xy 156.313136 -390.160002) (xy 155.724352 -390.160002) (xy 155.723857 -390.184609) (xy 155.715962 -390.233186)
			(xy 155.700378 -390.279867) (xy 155.677507 -390.323444) (xy 155.647942 -390.362788) (xy 155.612449 -390.39688)
			(xy 155.571946 -390.424836) (xy 155.527484 -390.445934) (xy 155.480213 -390.459626) (xy 155.431358 -390.465558)
			(xy 155.382183 -390.463577) (xy 155.333964 -390.453733) (xy 155.287948 -390.436281) (xy 155.245327 -390.411674)
			(xy 155.207206 -390.380549) (xy 155.174571 -390.343712) (xy 155.148268 -390.302116) (xy 155.128977 -390.25684)
			(xy 155.1172 -390.209056) (xy 155.11324 -390.160002) (xy 154.524202 -390.160002) (xy 154.523707 -390.184609)
			(xy 154.515812 -390.233186) (xy 154.500228 -390.279867) (xy 154.477357 -390.323444) (xy 154.447792 -390.362788)
			(xy 154.412299 -390.39688) (xy 154.371796 -390.424836) (xy 154.327334 -390.445934) (xy 154.280063 -390.459626)
			(xy 154.231208 -390.465558) (xy 154.182033 -390.463577) (xy 154.133814 -390.453733) (xy 154.087798 -390.436281)
			(xy 154.045177 -390.411674) (xy 154.007056 -390.380549) (xy 153.974421 -390.343712) (xy 153.948118 -390.302116)
			(xy 153.928827 -390.25684) (xy 153.91705 -390.209056) (xy 153.91309 -390.160002) (xy 153.324306 -390.160002)
			(xy 153.323811 -390.184609) (xy 153.315916 -390.233186) (xy 153.300332 -390.279867) (xy 153.277461 -390.323444)
			(xy 153.247896 -390.362788) (xy 153.212403 -390.39688) (xy 153.1719 -390.424836) (xy 153.127438 -390.445934)
			(xy 153.080167 -390.459626) (xy 153.031312 -390.465558) (xy 152.982137 -390.463577) (xy 152.933918 -390.453733)
			(xy 152.887902 -390.436281) (xy 152.845281 -390.411674) (xy 152.80716 -390.380549) (xy 152.774525 -390.343712)
			(xy 152.748222 -390.302116) (xy 152.728931 -390.25684) (xy 152.717154 -390.209056) (xy 152.713194 -390.160002)
			(xy 152.12441 -390.160002) (xy 152.123915 -390.184609) (xy 152.11602 -390.233186) (xy 152.100436 -390.279867)
			(xy 152.077565 -390.323444) (xy 152.048 -390.362788) (xy 152.012507 -390.39688) (xy 151.972004 -390.424836)
			(xy 151.927542 -390.445934) (xy 151.880271 -390.459626) (xy 151.831416 -390.465558) (xy 151.782241 -390.463577)
			(xy 151.734022 -390.453733) (xy 151.688006 -390.436281) (xy 151.645385 -390.411674) (xy 151.607264 -390.380549)
			(xy 151.574629 -390.343712) (xy 151.548326 -390.302116) (xy 151.529035 -390.25684) (xy 151.517258 -390.209056)
			(xy 151.513298 -390.160002) (xy 150.92426 -390.160002) (xy 150.923765 -390.184609) (xy 150.91587 -390.233186)
			(xy 150.900286 -390.279867) (xy 150.877415 -390.323444) (xy 150.84785 -390.362788) (xy 150.812357 -390.39688)
			(xy 150.771854 -390.424836) (xy 150.727392 -390.445934) (xy 150.680121 -390.459626) (xy 150.631266 -390.465558)
			(xy 150.582091 -390.463577) (xy 150.533872 -390.453733) (xy 150.487856 -390.436281) (xy 150.445235 -390.411674)
			(xy 150.407114 -390.380549) (xy 150.374479 -390.343712) (xy 150.348176 -390.302116) (xy 150.328885 -390.25684)
			(xy 150.317108 -390.209056) (xy 150.313148 -390.160002) (xy 149.724364 -390.160002) (xy 149.723869 -390.184609)
			(xy 149.715974 -390.233186) (xy 149.70039 -390.279867) (xy 149.677519 -390.323444) (xy 149.647954 -390.362788)
			(xy 149.612461 -390.39688) (xy 149.571958 -390.424836) (xy 149.527496 -390.445934) (xy 149.480225 -390.459626)
			(xy 149.43137 -390.465558) (xy 149.382195 -390.463577) (xy 149.333976 -390.453733) (xy 149.28796 -390.436281)
			(xy 149.245339 -390.411674) (xy 149.207218 -390.380549) (xy 149.174583 -390.343712) (xy 149.14828 -390.302116)
			(xy 149.128989 -390.25684) (xy 149.117212 -390.209056) (xy 149.113252 -390.160002) (xy 148.524214 -390.160002)
			(xy 148.523719 -390.184609) (xy 148.515824 -390.233186) (xy 148.50024 -390.279867) (xy 148.477369 -390.323444)
			(xy 148.447804 -390.362788) (xy 148.412311 -390.39688) (xy 148.371808 -390.424836) (xy 148.327346 -390.445934)
			(xy 148.280075 -390.459626) (xy 148.23122 -390.465558) (xy 148.182045 -390.463577) (xy 148.133826 -390.453733)
			(xy 148.08781 -390.436281) (xy 148.045189 -390.411674) (xy 148.007068 -390.380549) (xy 147.974433 -390.343712)
			(xy 147.94813 -390.302116) (xy 147.928839 -390.25684) (xy 147.917062 -390.209056) (xy 147.913102 -390.160002)
			(xy 147.324064 -390.160002) (xy 147.323569 -390.184609) (xy 147.315674 -390.233186) (xy 147.30009 -390.279867)
			(xy 147.277219 -390.323444) (xy 147.247654 -390.362788) (xy 147.212161 -390.39688) (xy 147.171658 -390.424836)
			(xy 147.127196 -390.445934) (xy 147.079925 -390.459626) (xy 147.03107 -390.465558) (xy 146.981895 -390.463577)
			(xy 146.933676 -390.453733) (xy 146.88766 -390.436281) (xy 146.845039 -390.411674) (xy 146.806918 -390.380549)
			(xy 146.774283 -390.343712) (xy 146.74798 -390.302116) (xy 146.728689 -390.25684) (xy 146.716912 -390.209056)
			(xy 146.712952 -390.160002) (xy 145.038146 -390.160002) (xy 145.032031 -390.181188) (xy 145.013021 -390.223593)
			(xy 144.988259 -390.262917) (xy 144.973548 -390.280906) (xy 144.967452 -390.288018) (xy 144.961356 -390.304528)
			(xy 144.961356 -390.388856) (xy 144.967452 -390.405366) (xy 144.973548 -390.412478) (xy 144.988253 -390.43047)
			(xy 145.013001 -390.469798) (xy 145.032002 -390.512203) (xy 145.044882 -390.556849) (xy 145.051386 -390.602859)
			(xy 145.05178 -390.626092) (xy 145.051368 -390.650185) (xy 145.044389 -390.697862) (xy 145.030577 -390.744025)
			(xy 145.020792 -390.766046) (xy 145.015458 -390.777476) (xy 145.016728 -390.802622) (xy 145.072862 -390.896602)
			(xy 145.094452 -390.909556) (xy 145.107152 -390.910318) (xy 145.132148 -390.912171) (xy 145.181192 -390.922501)
			(xy 145.228116 -390.940114) (xy 145.271845 -390.964605) (xy 145.311377 -390.995415) (xy 145.345808 -391.031837)
			(xy 145.374349 -391.073037) (xy 145.396346 -391.118072) (xy 145.411296 -391.165911) (xy 145.418856 -391.215458)
			(xy 145.419318 -391.240518) (xy 145.418808 -391.266505) (xy 145.410678 -391.31784) (xy 145.394617 -391.36727)
			(xy 145.371021 -391.41358) (xy 145.340471 -391.455628) (xy 145.30372 -391.492379) (xy 145.261672 -391.522929)
			(xy 145.215362 -391.546525) (xy 145.165932 -391.562586) (xy 145.114597 -391.570716) (xy 145.062623 -391.570716)
			(xy 145.011288 -391.562586) (xy 144.961858 -391.546525) (xy 144.915548 -391.522929) (xy 144.8735 -391.492379)
			(xy 144.836749 -391.455628) (xy 144.806199 -391.41358) (xy 144.782603 -391.36727) (xy 144.766542 -391.31784)
			(xy 144.758412 -391.266505) (xy 144.757902 -391.240518) (xy 144.758319 -391.216425) (xy 144.765296 -391.168748)
			(xy 144.779107 -391.122585) (xy 144.78889 -391.100564) (xy 144.794224 -391.089134) (xy 144.792954 -391.063988)
			(xy 144.73682 -390.970008) (xy 144.71523 -390.957054) (xy 144.70253 -390.956292) (xy 144.677534 -390.954445)
			(xy 144.62849 -390.944112) (xy 144.581567 -390.926498) (xy 144.537839 -390.902005) (xy 144.498307 -390.871195)
			(xy 144.463876 -390.834773) (xy 144.435336 -390.793573) (xy 144.413338 -390.748537) (xy 144.398388 -390.700699)
			(xy 144.390826 -390.651152) (xy 144.390364 -390.626092) (xy 141.54912 -390.626092) (xy 141.54912 -390.67867)
			(xy 141.55547 -390.695688) (xy 141.561566 -390.7028) (xy 141.579213 -390.723726) (xy 141.608925 -390.7697)
			(xy 141.63176 -390.819449) (xy 141.647249 -390.871951) (xy 141.655074 -390.926128) (xy 141.655546 -390.953498)
			(xy 141.655167 -390.977849) (xy 141.648946 -391.026152) (xy 141.636619 -391.073267) (xy 141.62786 -391.095992)
			(xy 141.623034 -391.108438) (xy 141.626082 -391.133838) (xy 141.692376 -391.225278) (xy 141.715744 -391.2362)
			(xy 141.728952 -391.235184) (xy 141.754606 -391.234422) (xy 141.781977 -391.234879) (xy 141.836156 -391.242698)
			(xy 141.88866 -391.258189) (xy 141.938406 -391.281033) (xy 141.984373 -391.31076) (xy 142.005304 -391.328402)
			(xy 142.012416 -391.334498) (xy 142.029434 -391.340848) (xy 142.114778 -391.340848) (xy 142.131796 -391.334498)
			(xy 142.138908 -391.328402) (xy 142.159841 -391.310761) (xy 142.205809 -391.281037) (xy 142.255555 -391.258191)
			(xy 142.308057 -391.242695) (xy 142.362235 -391.234866) (xy 142.416977 -391.234866) (xy 142.471155 -391.242695)
			(xy 142.523657 -391.258191) (xy 142.573403 -391.281037) (xy 142.619371 -391.310761) (xy 142.640304 -391.328402)
			(xy 142.647416 -391.334498) (xy 142.664434 -391.340848) (xy 142.749778 -391.340848) (xy 142.766796 -391.334498)
			(xy 142.773908 -391.328402) (xy 142.794826 -391.310746) (xy 142.840803 -391.281037) (xy 142.890554 -391.258204)
			(xy 142.943058 -391.242717) (xy 142.997236 -391.234893) (xy 143.024606 -391.234422) (xy 143.05186 -391.23485)
			(xy 143.105814 -391.242608) (xy 143.158114 -391.257967) (xy 143.207697 -391.280612) (xy 143.253551 -391.310084)
			(xy 143.294745 -391.345781) (xy 143.330438 -391.386978) (xy 143.359905 -391.432835) (xy 143.382546 -391.482419)
			(xy 143.397899 -391.534721) (xy 143.405653 -391.588676) (xy 143.406114 -391.61593) (xy 143.405662 -391.643301)
			(xy 143.39784 -391.69748) (xy 143.382348 -391.749983) (xy 143.359503 -391.79973) (xy 143.329776 -391.845696)
			(xy 143.312134 -391.866628) (xy 143.306038 -391.87374) (xy 143.299688 -391.890758) (xy 143.299688 -391.976102)
			(xy 143.306038 -391.99312) (xy 143.312134 -392.000232) (xy 143.329806 -392.02114) (xy 143.359532 -392.067111)
			(xy 143.382378 -392.116861) (xy 143.397874 -392.169367) (xy 143.405701 -392.22355) (xy 143.405699 -392.251946)
			(xy 143.690848 -392.251946) (xy 143.691334 -392.224695) (xy 143.69909 -392.170747) (xy 143.714445 -392.118452)
			(xy 143.737087 -392.068875) (xy 143.766553 -392.023025) (xy 143.802244 -391.981834) (xy 143.843435 -391.946143)
			(xy 143.889285 -391.916677) (xy 143.938862 -391.894035) (xy 143.991157 -391.87868) (xy 144.045105 -391.870924)
			(xy 144.099607 -391.870924) (xy 144.153555 -391.87868) (xy 144.20585 -391.894035) (xy 144.255427 -391.916677)
			(xy 144.301277 -391.946143) (xy 144.342468 -391.981834) (xy 144.378159 -392.023025) (xy 144.407625 -392.068875)
			(xy 144.430267 -392.118452) (xy 144.445622 -392.170747) (xy 144.453378 -392.224695) (xy 144.453864 -392.251946)
			(xy 144.452594 -392.284204) (xy 144.451578 -392.293856) (xy 144.456912 -392.31189) (xy 144.474516 -392.33475)
			(xy 145.791936 -392.33475) (xy 145.792337 -392.311516) (xy 145.798836 -392.265506) (xy 145.811712 -392.220859)
			(xy 145.830712 -392.178454) (xy 145.855462 -392.139128) (xy 145.870168 -392.121136) (xy 145.876264 -392.114024)
			(xy 145.88236 -392.097514) (xy 145.88236 -392.013186) (xy 145.876264 -391.996676) (xy 145.870168 -391.989564)
			(xy 145.855485 -391.971555) (xy 145.830733 -391.932232) (xy 145.811727 -391.889832) (xy 145.798843 -391.845189)
			(xy 145.792333 -391.799182) (xy 145.791936 -391.77595) (xy 145.792446 -391.749963) (xy 145.800576 -391.698628)
			(xy 145.816637 -391.649198) (xy 145.840233 -391.602888) (xy 145.870783 -391.56084) (xy 145.907534 -391.524089)
			(xy 145.949582 -391.493539) (xy 145.995892 -391.469943) (xy 146.045322 -391.453882) (xy 146.096657 -391.445752)
			(xy 146.148631 -391.445752) (xy 146.199966 -391.453882) (xy 146.249396 -391.469943) (xy 146.295706 -391.493539)
			(xy 146.337754 -391.524089) (xy 146.374505 -391.56084) (xy 146.405055 -391.602888) (xy 146.428651 -391.649198)
			(xy 146.444712 -391.698628) (xy 146.452842 -391.749963) (xy 146.453352 -391.77595) (xy 146.452954 -391.799184)
			(xy 146.446455 -391.845194) (xy 146.433578 -391.889841) (xy 146.414577 -391.932246) (xy 146.389826 -391.971573)
			(xy 146.37512 -391.989564) (xy 146.369024 -391.996676) (xy 146.362928 -392.013186) (xy 146.362928 -392.097514)
			(xy 146.369024 -392.114024) (xy 146.37512 -392.121136) (xy 146.389816 -392.139135) (xy 146.414564 -392.178462)
			(xy 146.433565 -392.220865) (xy 146.446447 -392.265509) (xy 146.452955 -392.311517) (xy 146.453352 -392.33475)
			(xy 146.452842 -392.360737) (xy 146.444712 -392.412072) (xy 146.428651 -392.461502) (xy 146.405055 -392.507812)
			(xy 146.374505 -392.54986) (xy 146.337754 -392.586611) (xy 146.295706 -392.617161) (xy 146.249396 -392.640757)
			(xy 146.199966 -392.656818) (xy 146.148631 -392.664948) (xy 146.096657 -392.664948) (xy 146.045322 -392.656818)
			(xy 145.995892 -392.640757) (xy 145.949582 -392.617161) (xy 145.907534 -392.586611) (xy 145.870783 -392.54986)
			(xy 145.840233 -392.507812) (xy 145.816637 -392.461502) (xy 145.800576 -392.412072) (xy 145.792446 -392.360737)
			(xy 145.791936 -392.33475) (xy 144.474516 -392.33475) (xy 144.510506 -392.381486) (xy 144.526762 -392.391138)
			(xy 144.53616 -392.392916) (xy 144.562314 -392.398009) (xy 144.612988 -392.414476) (xy 144.660877 -392.437834)
			(xy 144.705049 -392.46763) (xy 144.744645 -392.503283) (xy 144.778894 -392.544099) (xy 144.80713 -392.589285)
			(xy 144.828803 -392.63796) (xy 144.843491 -392.689178) (xy 144.850908 -392.741941) (xy 144.851374 -392.768582)
			(xy 144.850888 -392.795833) (xy 144.843132 -392.849781) (xy 144.827777 -392.902076) (xy 144.805135 -392.951653)
			(xy 144.775669 -392.997503) (xy 144.739978 -393.038694) (xy 144.698787 -393.074385) (xy 144.652937 -393.103851)
			(xy 144.60336 -393.126493) (xy 144.551065 -393.141848) (xy 144.497117 -393.149604) (xy 144.442615 -393.149604)
			(xy 144.388667 -393.141848) (xy 144.336372 -393.126493) (xy 144.286795 -393.103851) (xy 144.240945 -393.074385)
			(xy 144.199754 -393.038694) (xy 144.164063 -392.997503) (xy 144.134597 -392.951653) (xy 144.111955 -392.902076)
			(xy 144.0966 -392.849781) (xy 144.088844 -392.795833) (xy 144.088358 -392.768582) (xy 144.089628 -392.736324)
			(xy 144.090644 -392.726672) (xy 144.08531 -392.708638) (xy 144.031716 -392.639042) (xy 144.01546 -392.62939)
			(xy 144.006062 -392.627612) (xy 143.979891 -392.622591) (xy 143.92921 -392.606122) (xy 143.881314 -392.582759)
			(xy 143.837136 -392.552957) (xy 143.797536 -392.517297) (xy 143.763285 -392.476471) (xy 143.73505 -392.431276)
			(xy 143.71338 -392.382591) (xy 143.698697 -392.331364) (xy 143.691288 -392.278591) (xy 143.690848 -392.251946)
			(xy 143.405699 -392.251946) (xy 143.405697 -392.278295) (xy 143.397864 -392.332477) (xy 143.382362 -392.384981)
			(xy 143.35951 -392.434728) (xy 143.329778 -392.480696) (xy 143.312134 -392.501628) (xy 143.306038 -392.50874)
			(xy 143.299688 -392.525758) (xy 143.299688 -392.611102) (xy 143.306038 -392.62812) (xy 143.312134 -392.635232)
			(xy 143.329806 -392.65614) (xy 143.359532 -392.702111) (xy 143.382378 -392.751861) (xy 143.397874 -392.804367)
			(xy 143.405701 -392.85855) (xy 143.405697 -392.913295) (xy 143.397864 -392.967477) (xy 143.382362 -393.019981)
			(xy 143.35951 -393.069728) (xy 143.329778 -393.115696) (xy 143.312134 -393.136628) (xy 143.306038 -393.14374)
			(xy 143.299688 -393.160758) (xy 143.299688 -393.246102) (xy 143.306038 -393.26312) (xy 143.312134 -393.270232)
			(xy 143.32976 -393.291175) (xy 143.330835 -393.292838) (xy 147.062444 -393.292838) (xy 147.062444 -392.429238)
			(xy 147.062923 -392.402882) (xy 147.070186 -392.350674) (xy 147.084565 -392.299961) (xy 147.105786 -392.25171)
			(xy 147.133447 -392.206839) (xy 147.167019 -392.166202) (xy 147.186142 -392.14806) (xy 147.193254 -392.14171)
			(xy 147.201382 -392.124946) (xy 147.209764 -392.038332) (xy 147.204684 -392.020552) (xy 147.199096 -392.012678)
			(xy 147.184951 -391.992827) (xy 147.162491 -391.949571) (xy 147.147177 -391.903299) (xy 147.139397 -391.855184)
			(xy 147.138898 -391.830814) (xy 147.13942 -391.805559) (xy 147.147733 -391.755737) (xy 147.164134 -391.707963)
			(xy 147.188175 -391.66354) (xy 147.219199 -391.62368) (xy 147.256361 -391.58947) (xy 147.298647 -391.561844)
			(xy 147.344903 -391.541554) (xy 147.393868 -391.529154) (xy 147.444206 -391.524983) (xy 147.494544 -391.529154)
			(xy 147.543509 -391.541554) (xy 147.589765 -391.561844) (xy 147.632051 -391.58947) (xy 147.669213 -391.62368)
			(xy 147.700237 -391.66354) (xy 147.724278 -391.707963) (xy 147.740679 -391.755737) (xy 147.748992 -391.805559)
			(xy 147.749514 -391.830814) (xy 147.749043 -391.855187) (xy 147.741283 -391.90331) (xy 147.725963 -391.949586)
			(xy 147.703475 -391.992834) (xy 147.689316 -392.012678) (xy 147.683728 -392.020552) (xy 147.678648 -392.038332)
			(xy 147.68703 -392.124946) (xy 147.695158 -392.14171) (xy 147.70227 -392.14806) (xy 147.721408 -392.16619)
			(xy 147.754995 -392.206822) (xy 147.782665 -392.251693) (xy 147.803892 -392.299947) (xy 147.81827 -392.350665)
			(xy 147.825525 -392.40288) (xy 147.825968 -392.429238) (xy 147.825968 -393.292838) (xy 148.26234 -393.292838)
			(xy 148.26234 -392.429238) (xy 148.26282 -392.402882) (xy 148.270083 -392.350674) (xy 148.284462 -392.299962)
			(xy 148.305683 -392.251711) (xy 148.333343 -392.20684) (xy 148.366915 -392.166202) (xy 148.386038 -392.14806)
			(xy 148.39315 -392.141456) (xy 148.401532 -392.124946) (xy 148.40966 -392.038078) (xy 148.404834 -392.020298)
			(xy 148.398992 -392.012678) (xy 148.384887 -391.992809) (xy 148.362464 -391.949554) (xy 148.347207 -391.903284)
			(xy 148.339502 -391.855175) (xy 148.339048 -391.830814) (xy 148.33957 -391.805559) (xy 148.347883 -391.755737)
			(xy 148.364284 -391.707963) (xy 148.388325 -391.66354) (xy 148.419349 -391.62368) (xy 148.456511 -391.58947)
			(xy 148.498797 -391.561844) (xy 148.545053 -391.541554) (xy 148.594018 -391.529154) (xy 148.644356 -391.524983)
			(xy 148.694694 -391.529154) (xy 148.743659 -391.541554) (xy 148.789915 -391.561844) (xy 148.832201 -391.58947)
			(xy 148.869363 -391.62368) (xy 148.900387 -391.66354) (xy 148.924428 -391.707963) (xy 148.940829 -391.755737)
			(xy 148.949142 -391.805559) (xy 148.949664 -391.830814) (xy 148.949197 -391.855217) (xy 148.941438 -391.903401)
			(xy 148.926118 -391.949739) (xy 148.903627 -391.993053) (xy 148.889466 -392.012932) (xy 148.883878 -392.020552)
			(xy 148.878798 -392.038332) (xy 148.886926 -392.1252) (xy 148.895308 -392.14171) (xy 148.90242 -392.148314)
			(xy 148.921489 -392.166466) (xy 148.95498 -392.207089) (xy 148.982577 -392.251924) (xy 149.003758 -392.300122)
			(xy 149.018123 -392.350772) (xy 149.025399 -392.402915) (xy 149.025864 -392.429238) (xy 149.025864 -393.292838)
			(xy 149.462744 -393.292838) (xy 149.462744 -392.429238) (xy 149.463216 -392.402892) (xy 149.470444 -392.350699)
			(xy 149.484783 -392.299996) (xy 149.505959 -392.251746) (xy 149.53357 -392.206868) (xy 149.567091 -392.166215)
			(xy 149.586188 -392.14806) (xy 149.5933 -392.14171) (xy 149.601428 -392.124946) (xy 149.60981 -392.038332)
			(xy 149.60473 -392.020552) (xy 149.599142 -392.012678) (xy 149.584991 -391.992832) (xy 149.562534 -391.949573)
			(xy 149.547222 -391.9033) (xy 149.539442 -391.855184) (xy 149.538944 -391.830814) (xy 149.539466 -391.805559)
			(xy 149.547779 -391.755737) (xy 149.56418 -391.707963) (xy 149.588221 -391.66354) (xy 149.619245 -391.62368)
			(xy 149.656407 -391.58947) (xy 149.698693 -391.561844) (xy 149.744949 -391.541554) (xy 149.793914 -391.529154)
			(xy 149.844252 -391.524983) (xy 149.89459 -391.529154) (xy 149.943555 -391.541554) (xy 149.989811 -391.561844)
			(xy 150.032097 -391.58947) (xy 150.069259 -391.62368) (xy 150.100283 -391.66354) (xy 150.124324 -391.707963)
			(xy 150.140725 -391.755737) (xy 150.149038 -391.805559) (xy 150.14956 -391.830814) (xy 150.14908 -391.855186)
			(xy 150.141321 -391.903309) (xy 150.126004 -391.949585) (xy 150.103519 -391.992833) (xy 150.089362 -392.012678)
			(xy 150.083774 -392.020552) (xy 150.078694 -392.038332) (xy 150.087076 -392.124946) (xy 150.095204 -392.14171)
			(xy 150.102316 -392.14806) (xy 150.121443 -392.166189) (xy 150.154986 -392.206835) (xy 150.182612 -392.251714)
			(xy 150.203793 -392.29997) (xy 150.218126 -392.350683) (xy 150.225338 -392.402888) (xy 150.22576 -392.429238)
			(xy 150.22576 -393.292838) (xy 150.66264 -393.292838) (xy 150.66264 -392.429238) (xy 150.663113 -392.402892)
			(xy 150.670341 -392.350699) (xy 150.68468 -392.299996) (xy 150.705855 -392.251747) (xy 150.733466 -392.206869)
			(xy 150.766987 -392.166215) (xy 150.786084 -392.14806) (xy 150.793196 -392.14171) (xy 150.801324 -392.124946)
			(xy 150.809706 -392.038332) (xy 150.804626 -392.020552) (xy 150.799038 -392.012678) (xy 150.784886 -391.992832)
			(xy 150.76243 -391.949573) (xy 150.747118 -391.9033) (xy 150.739338 -391.855184) (xy 150.73884 -391.830814)
			(xy 150.739362 -391.805559) (xy 150.747675 -391.755737) (xy 150.764076 -391.707963) (xy 150.788117 -391.66354)
			(xy 150.819141 -391.62368) (xy 150.856303 -391.58947) (xy 150.898589 -391.561844) (xy 150.944845 -391.541554)
			(xy 150.99381 -391.529154) (xy 151.044148 -391.524983) (xy 151.094486 -391.529154) (xy 151.143451 -391.541554)
			(xy 151.189707 -391.561844) (xy 151.231993 -391.58947) (xy 151.269155 -391.62368) (xy 151.300179 -391.66354)
			(xy 151.32422 -391.707963) (xy 151.340621 -391.755737) (xy 151.348934 -391.805559) (xy 151.349456 -391.830814)
			(xy 151.348977 -391.855186) (xy 151.341218 -391.903309) (xy 151.325901 -391.949585) (xy 151.303415 -391.992833)
			(xy 151.289258 -392.012678) (xy 151.28367 -392.020552) (xy 151.27859 -392.038332) (xy 151.286972 -392.124946)
			(xy 151.2951 -392.14171) (xy 151.302212 -392.14806) (xy 151.321338 -392.16619) (xy 151.354882 -392.206836)
			(xy 151.382508 -392.251714) (xy 151.403689 -392.29997) (xy 151.418022 -392.350684) (xy 151.425234 -392.402888)
			(xy 151.425656 -392.429238) (xy 151.425656 -393.292838) (xy 151.862536 -393.292838) (xy 151.862536 -392.429238)
			(xy 151.863017 -392.402882) (xy 151.87028 -392.350674) (xy 151.884659 -392.299962) (xy 151.90588 -392.251711)
			(xy 151.93354 -392.20684) (xy 151.967112 -392.166202) (xy 151.986234 -392.14806) (xy 151.993346 -392.14171)
			(xy 152.001474 -392.124946) (xy 152.009856 -392.038332) (xy 152.004776 -392.020552) (xy 151.999188 -392.012678)
			(xy 151.985042 -391.992828) (xy 151.962583 -391.949571) (xy 151.947269 -391.903299) (xy 151.939489 -391.855184)
			(xy 151.93899 -391.830814) (xy 151.939512 -391.805559) (xy 151.947825 -391.755737) (xy 151.964226 -391.707963)
			(xy 151.988267 -391.66354) (xy 152.019291 -391.62368) (xy 152.056453 -391.58947) (xy 152.098739 -391.561844)
			(xy 152.144995 -391.541554) (xy 152.19396 -391.529154) (xy 152.244298 -391.524983) (xy 152.294636 -391.529154)
			(xy 152.343601 -391.541554) (xy 152.389857 -391.561844) (xy 152.432143 -391.58947) (xy 152.469305 -391.62368)
			(xy 152.500329 -391.66354) (xy 152.52437 -391.707963) (xy 152.540771 -391.755737) (xy 152.549084 -391.805559)
			(xy 152.549606 -391.830814) (xy 152.549136 -391.855187) (xy 152.541376 -391.903311) (xy 152.526056 -391.949586)
			(xy 152.503567 -391.992834) (xy 152.489408 -392.012678) (xy 152.48382 -392.020552) (xy 152.47874 -392.038332)
			(xy 152.487122 -392.124946) (xy 152.49525 -392.14171) (xy 152.502362 -392.14806) (xy 152.521498 -392.166192)
			(xy 152.555086 -392.206823) (xy 152.582756 -392.251693) (xy 152.603983 -392.299947) (xy 152.618362 -392.350665)
			(xy 152.625617 -392.40288) (xy 152.62606 -392.429238) (xy 152.62606 -393.292838) (xy 153.062432 -393.292838)
			(xy 153.062432 -392.429238) (xy 153.062914 -392.402883) (xy 153.070177 -392.350674) (xy 153.084556 -392.299962)
			(xy 153.105777 -392.251711) (xy 153.133436 -392.20684) (xy 153.167008 -392.166203) (xy 153.18613 -392.14806)
			(xy 153.193242 -392.14171) (xy 153.20137 -392.124946) (xy 153.209752 -392.038332) (xy 153.204672 -392.020552)
			(xy 153.199084 -392.012678) (xy 153.184938 -391.992828) (xy 153.162479 -391.949571) (xy 153.147165 -391.903299)
			(xy 153.139385 -391.855184) (xy 153.138886 -391.830814) (xy 153.139408 -391.805559) (xy 153.147721 -391.755737)
			(xy 153.164122 -391.707963) (xy 153.188163 -391.66354) (xy 153.219187 -391.62368) (xy 153.256349 -391.58947)
			(xy 153.298635 -391.561844) (xy 153.344891 -391.541554) (xy 153.393856 -391.529154) (xy 153.444194 -391.524983)
			(xy 153.494532 -391.529154) (xy 153.543497 -391.541554) (xy 153.589753 -391.561844) (xy 153.632039 -391.58947)
			(xy 153.669201 -391.62368) (xy 153.700225 -391.66354) (xy 153.724266 -391.707963) (xy 153.740667 -391.755737)
			(xy 153.74898 -391.805559) (xy 153.749502 -391.830814) (xy 153.749033 -391.855187) (xy 153.741273 -391.903311)
			(xy 153.725953 -391.949586) (xy 153.703463 -391.992834) (xy 153.689304 -392.012678) (xy 153.683716 -392.020552)
			(xy 153.678636 -392.038332) (xy 153.687018 -392.124946) (xy 153.695146 -392.14171) (xy 153.702258 -392.14806)
			(xy 153.721393 -392.166192) (xy 153.754981 -392.206824) (xy 153.782652 -392.251694) (xy 153.803879 -392.299947)
			(xy 153.818258 -392.350665) (xy 153.825513 -392.40288) (xy 153.825956 -392.429238) (xy 153.825956 -393.292838)
			(xy 154.262836 -393.292838) (xy 154.262836 -392.429238) (xy 154.26331 -392.402892) (xy 154.270539 -392.350699)
			(xy 154.284877 -392.299996) (xy 154.306052 -392.251747) (xy 154.333663 -392.206869) (xy 154.367183 -392.166215)
			(xy 154.38628 -392.14806) (xy 154.393392 -392.14171) (xy 154.40152 -392.124946) (xy 154.409902 -392.038332)
			(xy 154.404822 -392.020552) (xy 154.399234 -392.012678) (xy 154.385082 -391.992833) (xy 154.362625 -391.949573)
			(xy 154.347314 -391.9033) (xy 154.339534 -391.855184) (xy 154.339036 -391.830814) (xy 154.339558 -391.805559)
			(xy 154.347871 -391.755737) (xy 154.364272 -391.707963) (xy 154.388313 -391.66354) (xy 154.419337 -391.62368)
			(xy 154.456499 -391.58947) (xy 154.498785 -391.561844) (xy 154.545041 -391.541554) (xy 154.594006 -391.529154)
			(xy 154.644344 -391.524983) (xy 154.694682 -391.529154) (xy 154.743647 -391.541554) (xy 154.789903 -391.561844)
			(xy 154.832189 -391.58947) (xy 154.869351 -391.62368) (xy 154.900375 -391.66354) (xy 154.924416 -391.707963)
			(xy 154.940817 -391.755737) (xy 154.94913 -391.805559) (xy 154.949652 -391.830814) (xy 154.949173 -391.855186)
			(xy 154.941415 -391.903309) (xy 154.926097 -391.949585) (xy 154.903611 -391.992833) (xy 154.889454 -392.012678)
			(xy 154.883866 -392.020552) (xy 154.878786 -392.038332) (xy 154.887168 -392.124946) (xy 154.895296 -392.14171)
			(xy 154.902408 -392.14806) (xy 154.921533 -392.166191) (xy 154.955077 -392.206836) (xy 154.982703 -392.251715)
			(xy 155.003885 -392.299971) (xy 155.018218 -392.350684) (xy 155.02543 -392.402888) (xy 155.025852 -392.429238)
			(xy 155.025852 -393.292838) (xy 155.462732 -393.292838) (xy 155.462732 -392.429238) (xy 155.463176 -392.402891)
			(xy 155.470406 -392.350695) (xy 155.484748 -392.29999) (xy 155.505929 -392.251741) (xy 155.533546 -392.206864)
			(xy 155.567075 -392.166212) (xy 155.586176 -392.14806) (xy 155.593288 -392.14171) (xy 155.601416 -392.124946)
			(xy 155.609798 -392.038332) (xy 155.604718 -392.020552) (xy 155.59913 -392.012678) (xy 155.584977 -391.992833)
			(xy 155.562521 -391.949573) (xy 155.54721 -391.9033) (xy 155.53943 -391.855184) (xy 155.538932 -391.830814)
			(xy 155.539454 -391.805559) (xy 155.547767 -391.755737) (xy 155.564168 -391.707963) (xy 155.588209 -391.66354)
			(xy 155.619233 -391.62368) (xy 155.656395 -391.58947) (xy 155.698681 -391.561844) (xy 155.744937 -391.541554)
			(xy 155.793902 -391.529154) (xy 155.84424 -391.524983) (xy 155.894578 -391.529154) (xy 155.943543 -391.541554)
			(xy 155.989799 -391.561844) (xy 156.032085 -391.58947) (xy 156.069247 -391.62368) (xy 156.100271 -391.66354)
			(xy 156.124312 -391.707963) (xy 156.140713 -391.755737) (xy 156.149026 -391.805559) (xy 156.149548 -391.830814)
			(xy 156.14907 -391.855186) (xy 156.141311 -391.90331) (xy 156.125993 -391.949585) (xy 156.103507 -391.992833)
			(xy 156.08935 -392.012678) (xy 156.083762 -392.020552) (xy 156.078682 -392.038332) (xy 156.087064 -392.124946)
			(xy 156.095192 -392.14171) (xy 156.102304 -392.14806) (xy 156.121429 -392.166191) (xy 156.154973 -392.206837)
			(xy 156.182599 -392.251715) (xy 156.203781 -392.299971) (xy 156.218114 -392.350684) (xy 156.225326 -392.402888)
			(xy 156.225748 -392.429238) (xy 156.225748 -393.292838) (xy 156.662628 -393.292838) (xy 156.662628 -392.429238)
			(xy 156.663061 -392.402911) (xy 156.670311 -392.350757) (xy 156.684665 -392.300096) (xy 156.70585 -392.251891)
			(xy 156.733463 -392.207057) (xy 156.76698 -392.166447) (xy 156.786072 -392.148314) (xy 156.793184 -392.14171)
			(xy 156.801566 -392.1252) (xy 156.809694 -392.038332) (xy 156.804614 -392.020552) (xy 156.799026 -392.012932)
			(xy 156.784874 -391.993048) (xy 156.762385 -391.949735) (xy 156.747066 -391.903398) (xy 156.739306 -391.855216)
			(xy 156.738828 -391.830814) (xy 156.73935 -391.805559) (xy 156.747663 -391.755737) (xy 156.764064 -391.707963)
			(xy 156.788105 -391.66354) (xy 156.819129 -391.62368) (xy 156.856291 -391.58947) (xy 156.898577 -391.561844)
			(xy 156.944833 -391.541554) (xy 156.993798 -391.529154) (xy 157.044136 -391.524983) (xy 157.094474 -391.529154)
			(xy 157.143439 -391.541554) (xy 157.189695 -391.561844) (xy 157.231981 -391.58947) (xy 157.269143 -391.62368)
			(xy 157.300167 -391.66354) (xy 157.324208 -391.707963) (xy 157.340609 -391.755737) (xy 157.348922 -391.805559)
			(xy 157.349444 -391.830814) (xy 157.348948 -391.855172) (xy 157.341235 -391.903275) (xy 157.325992 -391.949545)
			(xy 157.303603 -391.992812) (xy 157.2895 -392.012678) (xy 157.283658 -392.020298) (xy 157.278832 -392.038078)
			(xy 157.28696 -392.124946) (xy 157.295342 -392.141456) (xy 157.302454 -392.14806) (xy 157.321589 -392.166193)
			(xy 157.355176 -392.206824) (xy 157.382848 -392.251694) (xy 157.404075 -392.299948) (xy 157.418453 -392.350665)
			(xy 157.425709 -392.40288) (xy 157.426152 -392.429238) (xy 157.426152 -393.292838) (xy 157.862524 -393.292838)
			(xy 157.862524 -392.429238) (xy 157.863009 -392.402883) (xy 157.870272 -392.350674) (xy 157.88465 -392.299963)
			(xy 157.90587 -392.251712) (xy 157.933529 -392.206841) (xy 157.9671 -392.166203) (xy 157.986222 -392.14806)
			(xy 157.993334 -392.14171) (xy 158.001462 -392.124946) (xy 158.009844 -392.038332) (xy 158.004764 -392.020552)
			(xy 157.999176 -392.012678) (xy 157.985029 -391.992829) (xy 157.96257 -391.949571) (xy 157.947257 -391.903299)
			(xy 157.939476 -391.855184) (xy 157.938978 -391.830814) (xy 157.9395 -391.805559) (xy 157.947813 -391.755737)
			(xy 157.964214 -391.707963) (xy 157.988255 -391.66354) (xy 158.019279 -391.62368) (xy 158.056441 -391.58947)
			(xy 158.098727 -391.561844) (xy 158.144983 -391.541554) (xy 158.193948 -391.529154) (xy 158.244286 -391.524983)
			(xy 158.294624 -391.529154) (xy 158.343589 -391.541554) (xy 158.389845 -391.561844) (xy 158.432131 -391.58947)
			(xy 158.469293 -391.62368) (xy 158.500317 -391.66354) (xy 158.524358 -391.707963) (xy 158.540759 -391.755737)
			(xy 158.549072 -391.805559) (xy 158.549594 -391.830814) (xy 158.549127 -391.855187) (xy 158.541366 -391.903311)
			(xy 158.526046 -391.949587) (xy 158.503555 -391.992834) (xy 158.489396 -392.012678) (xy 158.483808 -392.020552)
			(xy 158.478728 -392.038332) (xy 158.48711 -392.124946) (xy 158.495238 -392.14171) (xy 158.50235 -392.14806)
			(xy 158.521484 -392.166194) (xy 158.555072 -392.206825) (xy 158.582743 -392.251694) (xy 158.603971 -392.299948)
			(xy 158.618349 -392.350665) (xy 158.625605 -392.40288) (xy 158.626048 -392.429238) (xy 158.626048 -393.292838)
			(xy 159.062928 -393.292838) (xy 159.062928 -392.429238) (xy 159.063351 -392.402921) (xy 159.070576 -392.350785)
			(xy 159.084894 -392.300136) (xy 159.106034 -392.251934) (xy 159.133595 -392.207093) (xy 159.167055 -392.166463)
			(xy 159.186118 -392.148314) (xy 159.19323 -392.14171) (xy 159.201612 -392.1252) (xy 159.20974 -392.038332)
			(xy 159.20466 -392.020552) (xy 159.199072 -392.012932) (xy 159.184913 -391.993052) (xy 159.162427 -391.949737)
			(xy 159.14711 -391.903399) (xy 159.139352 -391.855216) (xy 159.138874 -391.830814) (xy 159.139396 -391.805559)
			(xy 159.147709 -391.755737) (xy 159.16411 -391.707963) (xy 159.188151 -391.66354) (xy 159.219175 -391.62368)
			(xy 159.256337 -391.58947) (xy 159.298623 -391.561844) (xy 159.344879 -391.541554) (xy 159.393844 -391.529154)
			(xy 159.444182 -391.524983) (xy 159.49452 -391.529154) (xy 159.543485 -391.541554) (xy 159.589741 -391.561844)
			(xy 159.632027 -391.58947) (xy 159.669189 -391.62368) (xy 159.700213 -391.66354) (xy 159.724254 -391.707963)
			(xy 159.740655 -391.755737) (xy 159.748968 -391.805559) (xy 159.74949 -391.830814) (xy 159.749004 -391.855173)
			(xy 159.74129 -391.903276) (xy 159.726044 -391.949546) (xy 159.703651 -391.992813) (xy 159.689546 -392.012678)
			(xy 159.683704 -392.020298) (xy 159.678878 -392.038078) (xy 159.687006 -392.124946) (xy 159.695388 -392.141456)
			(xy 159.7025 -392.14806) (xy 159.721624 -392.166192) (xy 159.755168 -392.206837) (xy 159.782795 -392.251715)
			(xy 159.803976 -392.299971) (xy 159.81831 -392.350684) (xy 159.825522 -392.402888) (xy 159.825944 -392.429238)
			(xy 159.825944 -393.292838) (xy 160.262824 -393.292838) (xy 160.262824 -392.429238) (xy 160.26327 -392.402891)
			(xy 160.2705 -392.350695) (xy 160.284842 -392.299991) (xy 160.306023 -392.251741) (xy 160.333639 -392.206864)
			(xy 160.367167 -392.166213) (xy 160.386268 -392.14806) (xy 160.39338 -392.14171) (xy 160.401508 -392.124946)
			(xy 160.40989 -392.038332) (xy 160.40481 -392.020552) (xy 160.399222 -392.012678) (xy 160.385068 -391.992834)
			(xy 160.362612 -391.949574) (xy 160.347301 -391.9033) (xy 160.339522 -391.855184) (xy 160.339024 -391.830814)
			(xy 160.339546 -391.805559) (xy 160.347859 -391.755737) (xy 160.36426 -391.707963) (xy 160.388301 -391.66354)
			(xy 160.419325 -391.62368) (xy 160.456487 -391.58947) (xy 160.498773 -391.561844) (xy 160.545029 -391.541554)
			(xy 160.593994 -391.529154) (xy 160.644332 -391.524983) (xy 160.69467 -391.529154) (xy 160.743635 -391.541554)
			(xy 160.789891 -391.561844) (xy 160.832177 -391.58947) (xy 160.869339 -391.62368) (xy 160.900363 -391.66354)
			(xy 160.924404 -391.707963) (xy 160.940805 -391.755737) (xy 160.949118 -391.805559) (xy 160.94964 -391.830814)
			(xy 160.949164 -391.855186) (xy 160.941405 -391.90331) (xy 160.926086 -391.949585) (xy 160.903599 -391.992833)
			(xy 160.889442 -392.012678) (xy 160.883854 -392.020552) (xy 160.878774 -392.038332) (xy 160.887156 -392.124946)
			(xy 160.895284 -392.14171) (xy 160.902396 -392.14806) (xy 160.921519 -392.166193) (xy 160.955064 -392.206838)
			(xy 160.98269 -392.251716) (xy 161.003872 -392.299971) (xy 161.018206 -392.350684) (xy 161.025418 -392.402888)
			(xy 161.02584 -392.429238) (xy 161.02584 -393.292838) (xy 161.46272 -393.292838) (xy 161.46272 -392.429238)
			(xy 161.463167 -392.402891) (xy 161.470397 -392.350696) (xy 161.484739 -392.299991) (xy 161.505919 -392.251741)
			(xy 161.533536 -392.206864) (xy 161.567063 -392.166213) (xy 161.586164 -392.14806) (xy 161.593276 -392.14171)
			(xy 161.601404 -392.124946) (xy 161.609786 -392.038332) (xy 161.604706 -392.020552) (xy 161.599118 -392.012678)
			(xy 161.584964 -391.992834) (xy 161.562508 -391.949574) (xy 161.547197 -391.9033) (xy 161.539418 -391.855184)
			(xy 161.53892 -391.830814) (xy 161.539442 -391.805559) (xy 161.547755 -391.755737) (xy 161.564156 -391.707963)
			(xy 161.588197 -391.66354) (xy 161.619221 -391.62368) (xy 161.656383 -391.58947) (xy 161.698669 -391.561844)
			(xy 161.744925 -391.541554) (xy 161.79389 -391.529154) (xy 161.844228 -391.524983) (xy 161.894566 -391.529154)
			(xy 161.943531 -391.541554) (xy 161.989787 -391.561844) (xy 162.032073 -391.58947) (xy 162.069235 -391.62368)
			(xy 162.100259 -391.66354) (xy 162.1243 -391.707963) (xy 162.140701 -391.755737) (xy 162.149014 -391.805559)
			(xy 162.149536 -391.830814) (xy 162.14906 -391.855186) (xy 162.141301 -391.90331) (xy 162.125983 -391.949585)
			(xy 162.103496 -391.992833) (xy 162.089338 -392.012678) (xy 162.08375 -392.020552) (xy 162.07867 -392.038332)
			(xy 162.087052 -392.124946) (xy 162.09518 -392.14171) (xy 162.102292 -392.14806) (xy 162.121414 -392.166194)
			(xy 162.154959 -392.206838) (xy 162.182586 -392.251716) (xy 162.203768 -392.299971) (xy 162.218102 -392.350684)
			(xy 162.225314 -392.402888) (xy 162.225736 -392.429238) (xy 162.225736 -393.292838) (xy 162.662616 -393.292838)
			(xy 162.662616 -392.429238) (xy 162.663065 -392.402891) (xy 162.670295 -392.350696) (xy 162.684636 -392.299991)
			(xy 162.705816 -392.251742) (xy 162.733432 -392.206864) (xy 162.76696 -392.166213) (xy 162.78606 -392.14806)
			(xy 162.793172 -392.14171) (xy 162.8013 -392.124946) (xy 162.809682 -392.038332) (xy 162.804602 -392.020552)
			(xy 162.799014 -392.012678) (xy 162.784859 -391.992834) (xy 162.762404 -391.949574) (xy 162.747093 -391.9033)
			(xy 162.739314 -391.855184) (xy 162.738816 -391.830814) (xy 162.739338 -391.805559) (xy 162.747651 -391.755737)
			(xy 162.764052 -391.707963) (xy 162.788093 -391.66354) (xy 162.819117 -391.62368) (xy 162.856279 -391.58947)
			(xy 162.898565 -391.561844) (xy 162.944821 -391.541554) (xy 162.993786 -391.529154) (xy 163.044124 -391.524983)
			(xy 163.094462 -391.529154) (xy 163.143427 -391.541554) (xy 163.189683 -391.561844) (xy 163.231969 -391.58947)
			(xy 163.269131 -391.62368) (xy 163.300155 -391.66354) (xy 163.324196 -391.707963) (xy 163.340597 -391.755737)
			(xy 163.34891 -391.805559) (xy 163.349432 -391.830814) (xy 163.348957 -391.855186) (xy 163.341198 -391.90331)
			(xy 163.325879 -391.949585) (xy 163.303392 -391.992833) (xy 163.289234 -392.012678) (xy 163.283646 -392.020552)
			(xy 163.278566 -392.038332) (xy 163.286948 -392.124946) (xy 163.295076 -392.14171) (xy 163.302188 -392.14806)
			(xy 163.32131 -392.166194) (xy 163.354855 -392.206839) (xy 163.382482 -392.251716) (xy 163.403664 -392.299972)
			(xy 163.417998 -392.350684) (xy 163.42521 -392.402888) (xy 163.425632 -392.429238) (xy 163.425632 -393.292838)
			(xy 163.862512 -393.292838) (xy 163.862512 -392.429238) (xy 163.863001 -392.402883) (xy 163.870263 -392.350675)
			(xy 163.884641 -392.299963) (xy 163.905861 -392.251713) (xy 163.933519 -392.206841) (xy 163.967089 -392.166203)
			(xy 163.98621 -392.14806) (xy 163.993322 -392.14171) (xy 164.00145 -392.124946) (xy 164.009832 -392.038332)
			(xy 164.004752 -392.020552) (xy 163.999164 -392.012678) (xy 163.985015 -391.99283) (xy 163.962557 -391.949572)
			(xy 163.947244 -391.903299) (xy 163.939464 -391.855184) (xy 163.938966 -391.830814) (xy 163.939488 -391.805559)
			(xy 163.947801 -391.755737) (xy 163.964202 -391.707963) (xy 163.988243 -391.66354) (xy 164.019267 -391.62368)
			(xy 164.056429 -391.58947) (xy 164.098715 -391.561844) (xy 164.144971 -391.541554) (xy 164.193936 -391.529154)
			(xy 164.244274 -391.524983) (xy 164.294612 -391.529154) (xy 164.343577 -391.541554) (xy 164.389833 -391.561844)
			(xy 164.432119 -391.58947) (xy 164.469281 -391.62368) (xy 164.500305 -391.66354) (xy 164.524346 -391.707963)
			(xy 164.540747 -391.755737) (xy 164.54906 -391.805559) (xy 164.549582 -391.830814) (xy 164.549117 -391.855187)
			(xy 164.541356 -391.903311) (xy 164.526035 -391.949587) (xy 164.503544 -391.992834) (xy 164.489384 -392.012678)
			(xy 164.483796 -392.020552) (xy 164.478716 -392.038332) (xy 164.487098 -392.124946) (xy 164.495226 -392.14171)
			(xy 164.502338 -392.14806) (xy 164.52147 -392.166196) (xy 164.555058 -392.206826) (xy 164.58273 -392.251695)
			(xy 164.603958 -392.299948) (xy 164.618337 -392.350666) (xy 164.625593 -392.40288) (xy 164.626036 -392.429238)
			(xy 164.626036 -393.292838) (xy 164.625609 -393.319012) (xy 164.618413 -393.370864) (xy 164.6042 -393.421247)
			(xy 164.583239 -393.469216) (xy 164.555922 -393.513872) (xy 164.522761 -393.554378) (xy 164.503862 -393.572492)
			(xy 164.496496 -393.57935) (xy 164.488368 -393.596876) (xy 164.483034 -393.687046) (xy 164.48913 -393.705334)
			(xy 164.495734 -393.712954) (xy 164.510639 -393.730994) (xy 164.535702 -393.770513) (xy 164.554948 -393.813169)
			(xy 164.567994 -393.858109) (xy 164.57458 -393.90444) (xy 164.574982 -393.927838) (xy 164.574472 -393.953825)
			(xy 164.566342 -394.00516) (xy 164.550281 -394.05459) (xy 164.526685 -394.1009) (xy 164.496135 -394.142948)
			(xy 164.459384 -394.179699) (xy 164.417336 -394.210249) (xy 164.371026 -394.233845) (xy 164.321596 -394.249906)
			(xy 164.270261 -394.258036) (xy 164.218287 -394.258036) (xy 164.166952 -394.249906) (xy 164.117522 -394.233845)
			(xy 164.071212 -394.210249) (xy 164.029164 -394.179699) (xy 163.992413 -394.142948) (xy 163.961863 -394.1009)
			(xy 163.938267 -394.05459) (xy 163.922206 -394.00516) (xy 163.914076 -393.953825) (xy 163.913566 -393.927838)
			(xy 163.913987 -393.904441) (xy 163.920574 -393.858114) (xy 163.933621 -393.813177) (xy 163.952868 -393.770526)
			(xy 163.977932 -393.731011) (xy 163.992814 -393.712954) (xy 163.999418 -393.705334) (xy 164.005514 -393.687046)
			(xy 164.00018 -393.596876) (xy 163.992052 -393.57935) (xy 163.984686 -393.572492) (xy 163.965787 -393.554378)
			(xy 163.932624 -393.513874) (xy 163.905308 -393.469218) (xy 163.884351 -393.421248) (xy 163.870146 -393.370864)
			(xy 163.86296 -393.319012) (xy 163.862512 -393.292838) (xy 163.425632 -393.292838) (xy 163.425181 -393.319002)
			(xy 163.41803 -393.370838) (xy 163.403867 -393.421213) (xy 163.382957 -393.469181) (xy 163.355693 -393.513844)
			(xy 163.322585 -393.554366) (xy 163.303712 -393.572492) (xy 163.296346 -393.57935) (xy 163.288218 -393.596876)
			(xy 163.282884 -393.687046) (xy 163.28898 -393.705334) (xy 163.295584 -393.712954) (xy 163.310482 -393.731)
			(xy 163.335547 -393.770517) (xy 163.354795 -393.813171) (xy 163.367843 -393.85811) (xy 163.37443 -393.90444)
			(xy 163.374832 -393.927838) (xy 163.374322 -393.953825) (xy 163.366192 -394.00516) (xy 163.350131 -394.05459)
			(xy 163.326535 -394.1009) (xy 163.295985 -394.142948) (xy 163.259234 -394.179699) (xy 163.217186 -394.210249)
			(xy 163.170876 -394.233845) (xy 163.121446 -394.249906) (xy 163.070111 -394.258036) (xy 163.018137 -394.258036)
			(xy 162.966802 -394.249906) (xy 162.917372 -394.233845) (xy 162.871062 -394.210249) (xy 162.829014 -394.179699)
			(xy 162.792263 -394.142948) (xy 162.761713 -394.1009) (xy 162.738117 -394.05459) (xy 162.722056 -394.00516)
			(xy 162.713926 -393.953825) (xy 162.713416 -393.927838) (xy 162.713849 -393.904442) (xy 162.720434 -393.858116)
			(xy 162.733479 -393.813179) (xy 162.752724 -393.770528) (xy 162.777784 -393.731012) (xy 162.792664 -393.712954)
			(xy 162.799268 -393.705334) (xy 162.805364 -393.687046) (xy 162.80003 -393.596876) (xy 162.791902 -393.57935)
			(xy 162.784536 -393.572492) (xy 162.765648 -393.554379) (xy 162.732529 -393.513861) (xy 162.705258 -393.469197)
			(xy 162.684346 -393.421225) (xy 162.670186 -393.370846) (xy 162.663043 -393.319004) (xy 162.662616 -393.292838)
			(xy 162.225736 -393.292838) (xy 162.225202 -393.321743) (xy 162.216497 -393.378893) (xy 162.199276 -393.434077)
			(xy 162.173933 -393.486035) (xy 162.141048 -393.533579) (xy 162.121596 -393.554966) (xy 162.1155 -393.56157)
			(xy 162.108388 -393.577572) (xy 162.1028 -393.659868) (xy 162.107626 -393.676886) (xy 162.112706 -393.683998)
			(xy 162.127349 -393.705223) (xy 162.150599 -393.751246) (xy 162.166423 -393.800321) (xy 162.174437 -393.851257)
			(xy 162.174936 -393.877038) (xy 162.174426 -393.903025) (xy 162.166296 -393.95436) (xy 162.150235 -394.00379)
			(xy 162.126639 -394.0501) (xy 162.096089 -394.092148) (xy 162.059338 -394.128899) (xy 162.01729 -394.159449)
			(xy 161.97098 -394.183045) (xy 161.92155 -394.199106) (xy 161.870215 -394.207236) (xy 161.818241 -394.207236)
			(xy 161.766906 -394.199106) (xy 161.717476 -394.183045) (xy 161.671166 -394.159449) (xy 161.629118 -394.128899)
			(xy 161.592367 -394.092148) (xy 161.561817 -394.0501) (xy 161.538221 -394.00379) (xy 161.52216 -393.95436)
			(xy 161.51403 -393.903025) (xy 161.51352 -393.877038) (xy 161.513989 -393.851254) (xy 161.521997 -393.800313)
			(xy 161.537824 -393.751234) (xy 161.561087 -393.705212) (xy 161.57575 -393.683998) (xy 161.58083 -393.676886)
			(xy 161.585656 -393.659868) (xy 161.580068 -393.577572) (xy 161.572956 -393.56157) (xy 161.56686 -393.554966)
			(xy 161.54737 -393.533609) (xy 161.514465 -393.486069) (xy 161.489116 -393.434106) (xy 161.471905 -393.378909)
			(xy 161.463228 -393.321747) (xy 161.46272 -393.292838) (xy 161.02584 -393.292838) (xy 161.025386 -393.319002)
			(xy 161.018235 -393.370838) (xy 161.004073 -393.421212) (xy 160.983164 -393.46918) (xy 160.9559 -393.513844)
			(xy 160.922793 -393.554366) (xy 160.90392 -393.572492) (xy 160.896554 -393.57935) (xy 160.888426 -393.596876)
			(xy 160.883092 -393.687046) (xy 160.889188 -393.705334) (xy 160.895792 -393.712954) (xy 160.910691 -393.730999)
			(xy 160.935756 -393.770516) (xy 160.955004 -393.81317) (xy 160.968051 -393.85811) (xy 160.974638 -393.90444)
			(xy 160.97504 -393.927838) (xy 160.97453 -393.953825) (xy 160.9664 -394.00516) (xy 160.950339 -394.05459)
			(xy 160.926743 -394.1009) (xy 160.896193 -394.142948) (xy 160.859442 -394.179699) (xy 160.817394 -394.210249)
			(xy 160.771084 -394.233845) (xy 160.721654 -394.249906) (xy 160.670319 -394.258036) (xy 160.618345 -394.258036)
			(xy 160.56701 -394.249906) (xy 160.51758 -394.233845) (xy 160.47127 -394.210249) (xy 160.429222 -394.179699)
			(xy 160.392471 -394.142948) (xy 160.361921 -394.1009) (xy 160.338325 -394.05459) (xy 160.322264 -394.00516)
			(xy 160.314134 -393.953825) (xy 160.313624 -393.927838) (xy 160.314055 -393.904442) (xy 160.320641 -393.858116)
			(xy 160.333686 -393.813179) (xy 160.352931 -393.770528) (xy 160.377991 -393.731012) (xy 160.392872 -393.712954)
			(xy 160.399476 -393.705334) (xy 160.405572 -393.687046) (xy 160.400238 -393.596876) (xy 160.39211 -393.57935)
			(xy 160.384744 -393.572492) (xy 160.365858 -393.554377) (xy 160.332738 -393.51386) (xy 160.305467 -393.469196)
			(xy 160.284554 -393.421225) (xy 160.270394 -393.370845) (xy 160.263251 -393.319004) (xy 160.262824 -393.292838)
			(xy 159.825944 -393.292838) (xy 159.825489 -393.319002) (xy 159.818338 -393.370838) (xy 159.804176 -393.421212)
			(xy 159.783267 -393.46918) (xy 159.756004 -393.513844) (xy 159.722896 -393.554366) (xy 159.704024 -393.572492)
			(xy 159.696658 -393.57935) (xy 159.68853 -393.596876) (xy 159.683196 -393.687046) (xy 159.689292 -393.705334)
			(xy 159.695896 -393.712954) (xy 159.710795 -393.730999) (xy 159.73586 -393.770516) (xy 159.755108 -393.81317)
			(xy 159.768155 -393.85811) (xy 159.774742 -393.90444) (xy 159.775144 -393.927838) (xy 159.774634 -393.953825)
			(xy 159.766504 -394.00516) (xy 159.750443 -394.05459) (xy 159.726847 -394.1009) (xy 159.696297 -394.142948)
			(xy 159.659546 -394.179699) (xy 159.617498 -394.210249) (xy 159.571188 -394.233845) (xy 159.521758 -394.249906)
			(xy 159.470423 -394.258036) (xy 159.418449 -394.258036) (xy 159.367114 -394.249906) (xy 159.317684 -394.233845)
			(xy 159.271374 -394.210249) (xy 159.229326 -394.179699) (xy 159.192575 -394.142948) (xy 159.162025 -394.1009)
			(xy 159.138429 -394.05459) (xy 159.122368 -394.00516) (xy 159.114238 -393.953825) (xy 159.113728 -393.927838)
			(xy 159.114158 -393.904442) (xy 159.120744 -393.858116) (xy 159.133789 -393.813179) (xy 159.153034 -393.770527)
			(xy 159.178095 -393.731012) (xy 159.192976 -393.712954) (xy 159.19958 -393.705334) (xy 159.205676 -393.687046)
			(xy 159.200342 -393.596876) (xy 159.192214 -393.57935) (xy 159.184848 -393.572492) (xy 159.165963 -393.554377)
			(xy 159.132843 -393.513859) (xy 159.105571 -393.469196) (xy 159.084659 -393.421224) (xy 159.070498 -393.370845)
			(xy 159.063355 -393.319004) (xy 159.062928 -393.292838) (xy 158.626048 -393.292838) (xy 158.625618 -393.319012)
			(xy 158.618421 -393.370863) (xy 158.604209 -393.421246) (xy 158.583249 -393.469215) (xy 158.555932 -393.513871)
			(xy 158.522772 -393.554377) (xy 158.503874 -393.572492) (xy 158.496508 -393.57935) (xy 158.48838 -393.596876)
			(xy 158.483046 -393.687046) (xy 158.489142 -393.705334) (xy 158.495746 -393.712954) (xy 158.510653 -393.730993)
			(xy 158.535715 -393.770512) (xy 158.55496 -393.813168) (xy 158.568006 -393.858109) (xy 158.574592 -393.90444)
			(xy 158.574994 -393.927838) (xy 158.574484 -393.953825) (xy 158.566354 -394.00516) (xy 158.550293 -394.05459)
			(xy 158.526697 -394.1009) (xy 158.496147 -394.142948) (xy 158.459396 -394.179699) (xy 158.417348 -394.210249)
			(xy 158.371038 -394.233845) (xy 158.321608 -394.249906) (xy 158.270273 -394.258036) (xy 158.218299 -394.258036)
			(xy 158.166964 -394.249906) (xy 158.117534 -394.233845) (xy 158.071224 -394.210249) (xy 158.029176 -394.179699)
			(xy 157.992425 -394.142948) (xy 157.961875 -394.1009) (xy 157.938279 -394.05459) (xy 157.922218 -394.00516)
			(xy 157.914088 -393.953825) (xy 157.913578 -393.927838) (xy 157.913996 -393.904441) (xy 157.920583 -393.858114)
			(xy 157.93363 -393.813177) (xy 157.952878 -393.770525) (xy 157.977943 -393.731011) (xy 157.992826 -393.712954)
			(xy 157.99943 -393.705334) (xy 158.005526 -393.687046) (xy 158.000192 -393.596876) (xy 157.992064 -393.57935)
			(xy 157.984698 -393.572492) (xy 157.965801 -393.554376) (xy 157.932638 -393.513873) (xy 157.905321 -393.469218)
			(xy 157.884364 -393.421248) (xy 157.870158 -393.370864) (xy 157.862972 -393.319012) (xy 157.862524 -393.292838)
			(xy 157.426152 -393.292838) (xy 157.42572 -393.319012) (xy 157.418524 -393.370863) (xy 157.404312 -393.421246)
			(xy 157.383352 -393.469215) (xy 157.356036 -393.513871) (xy 157.322876 -393.554377) (xy 157.303978 -393.572492)
			(xy 157.296612 -393.57935) (xy 157.288484 -393.596876) (xy 157.28315 -393.687046) (xy 157.289246 -393.705334)
			(xy 157.29585 -393.712954) (xy 157.310758 -393.730992) (xy 157.335819 -393.770512) (xy 157.355065 -393.813168)
			(xy 157.36811 -393.858109) (xy 157.374696 -393.90444) (xy 157.375098 -393.927838) (xy 157.374588 -393.953825)
			(xy 157.366458 -394.00516) (xy 157.350397 -394.05459) (xy 157.326801 -394.1009) (xy 157.296251 -394.142948)
			(xy 157.2595 -394.179699) (xy 157.217452 -394.210249) (xy 157.171142 -394.233845) (xy 157.121712 -394.249906)
			(xy 157.070377 -394.258036) (xy 157.018403 -394.258036) (xy 156.967068 -394.249906) (xy 156.917638 -394.233845)
			(xy 156.871328 -394.210249) (xy 156.82928 -394.179699) (xy 156.792529 -394.142948) (xy 156.761979 -394.1009)
			(xy 156.738383 -394.05459) (xy 156.722322 -394.00516) (xy 156.714192 -393.953825) (xy 156.713682 -393.927838)
			(xy 156.714123 -393.904442) (xy 156.720708 -393.858117) (xy 156.733751 -393.813181) (xy 156.752993 -393.770529)
			(xy 156.778051 -393.731013) (xy 156.79293 -393.712954) (xy 156.799534 -393.705334) (xy 156.80563 -393.687046)
			(xy 156.800296 -393.596876) (xy 156.792168 -393.57935) (xy 156.784802 -393.572492) (xy 156.765906 -393.554375)
			(xy 156.732743 -393.513872) (xy 156.705426 -393.469217) (xy 156.684468 -393.421248) (xy 156.670262 -393.370864)
			(xy 156.663076 -393.319012) (xy 156.662628 -393.292838) (xy 156.225748 -393.292838) (xy 156.225191 -393.322987)
			(xy 156.215735 -393.382538) (xy 156.197032 -393.439862) (xy 156.169548 -393.493532) (xy 156.133967 -393.542212)
			(xy 156.112972 -393.563856) (xy 156.106368 -393.57046) (xy 156.098748 -393.587224) (xy 156.093414 -393.67333)
			(xy 156.098748 -393.69111) (xy 156.10459 -393.698476) (xy 156.121101 -393.720461) (xy 156.147374 -393.768756)
			(xy 156.165304 -393.820728) (xy 156.1744 -393.874949) (xy 156.174948 -393.902438) (xy 156.174438 -393.928425)
			(xy 156.166308 -393.97976) (xy 156.150247 -394.02919) (xy 156.126651 -394.0755) (xy 156.096101 -394.117548)
			(xy 156.05935 -394.154299) (xy 156.017302 -394.184849) (xy 155.970992 -394.208445) (xy 155.921562 -394.224506)
			(xy 155.870227 -394.232636) (xy 155.818253 -394.232636) (xy 155.766918 -394.224506) (xy 155.717488 -394.208445)
			(xy 155.671178 -394.184849) (xy 155.62913 -394.154299) (xy 155.592379 -394.117548) (xy 155.561829 -394.0755)
			(xy 155.538233 -394.02919) (xy 155.522172 -393.97976) (xy 155.514042 -393.928425) (xy 155.513532 -393.902438)
			(xy 155.514078 -393.874947) (xy 155.523155 -393.82072) (xy 155.541082 -393.768744) (xy 155.567364 -393.720451)
			(xy 155.58389 -393.698476) (xy 155.589732 -393.69111) (xy 155.595066 -393.67333) (xy 155.589732 -393.587224)
			(xy 155.582112 -393.57046) (xy 155.575508 -393.563856) (xy 155.554514 -393.542209) (xy 155.518922 -393.493535)
			(xy 155.491432 -393.439867) (xy 155.47273 -393.382542) (xy 155.463282 -393.322988) (xy 155.462732 -393.292838)
			(xy 155.025852 -393.292838) (xy 155.025314 -393.321742) (xy 155.016609 -393.378892) (xy 154.999389 -393.434076)
			(xy 154.974047 -393.486034) (xy 154.941163 -393.533579) (xy 154.921712 -393.554966) (xy 154.915616 -393.56157)
			(xy 154.908504 -393.577572) (xy 154.902916 -393.659868) (xy 154.907742 -393.676886) (xy 154.912822 -393.683998)
			(xy 154.927455 -393.70523) (xy 154.95071 -393.75125) (xy 154.966537 -393.800322) (xy 154.974553 -393.851257)
			(xy 154.975052 -393.877038) (xy 154.974542 -393.903025) (xy 154.966412 -393.95436) (xy 154.950351 -394.00379)
			(xy 154.926755 -394.0501) (xy 154.896205 -394.092148) (xy 154.859454 -394.128899) (xy 154.817406 -394.159449)
			(xy 154.771096 -394.183045) (xy 154.721666 -394.199106) (xy 154.670331 -394.207236) (xy 154.618357 -394.207236)
			(xy 154.567022 -394.199106) (xy 154.517592 -394.183045) (xy 154.471282 -394.159449) (xy 154.429234 -394.128899)
			(xy 154.392483 -394.092148) (xy 154.361933 -394.0501) (xy 154.338337 -394.00379) (xy 154.322276 -393.95436)
			(xy 154.314146 -393.903025) (xy 154.313636 -393.877038) (xy 154.31412 -393.851255) (xy 154.322126 -393.800315)
			(xy 154.337949 -393.751237) (xy 154.361206 -393.705213) (xy 154.375866 -393.683998) (xy 154.380946 -393.676886)
			(xy 154.385772 -393.659868) (xy 154.380184 -393.577572) (xy 154.373072 -393.56157) (xy 154.366976 -393.554966)
			(xy 154.347489 -393.533607) (xy 154.314582 -393.486068) (xy 154.289233 -393.434105) (xy 154.272021 -393.378909)
			(xy 154.263344 -393.321747) (xy 154.262836 -393.292838) (xy 153.825956 -393.292838) (xy 153.825524 -393.319012)
			(xy 153.818327 -393.370863) (xy 153.804116 -393.421246) (xy 153.783156 -393.469215) (xy 153.75584 -393.513871)
			(xy 153.72268 -393.554378) (xy 153.703782 -393.572492) (xy 153.696416 -393.57935) (xy 153.688288 -393.596876)
			(xy 153.682954 -393.687046) (xy 153.68905 -393.705334) (xy 153.695654 -393.712954) (xy 153.710547 -393.731004)
			(xy 153.735614 -393.770519) (xy 153.754864 -393.813172) (xy 153.767913 -393.858111) (xy 153.7745 -393.90444)
			(xy 153.774902 -393.927838) (xy 153.774392 -393.953825) (xy 153.766262 -394.00516) (xy 153.750201 -394.05459)
			(xy 153.726605 -394.1009) (xy 153.696055 -394.142948) (xy 153.659304 -394.179699) (xy 153.617256 -394.210249)
			(xy 153.570946 -394.233845) (xy 153.521516 -394.249906) (xy 153.470181 -394.258036) (xy 153.418207 -394.258036)
			(xy 153.366872 -394.249906) (xy 153.317442 -394.233845) (xy 153.271132 -394.210249) (xy 153.229084 -394.179699)
			(xy 153.192333 -394.142948) (xy 153.161783 -394.1009) (xy 153.138187 -394.05459) (xy 153.122126 -394.00516)
			(xy 153.113996 -393.953825) (xy 153.113486 -393.927838) (xy 153.113926 -393.904442) (xy 153.120511 -393.858117)
			(xy 153.133554 -393.81318) (xy 153.152797 -393.770529) (xy 153.177855 -393.731013) (xy 153.192734 -393.712954)
			(xy 153.199338 -393.705334) (xy 153.205434 -393.687046) (xy 153.2001 -393.596876) (xy 153.191972 -393.57935)
			(xy 153.184606 -393.572492) (xy 153.165711 -393.554375) (xy 153.132547 -393.513872) (xy 153.10523 -393.469217)
			(xy 153.084272 -393.421247) (xy 153.070066 -393.370864) (xy 153.06288 -393.319012) (xy 153.062432 -393.292838)
			(xy 152.62606 -393.292838) (xy 152.625657 -393.319013) (xy 152.618459 -393.370867) (xy 152.604244 -393.421251)
			(xy 152.583278 -393.469221) (xy 152.555956 -393.513876) (xy 152.522788 -393.55438) (xy 152.503886 -393.572492)
			(xy 152.49652 -393.57935) (xy 152.488392 -393.596876) (xy 152.483058 -393.687046) (xy 152.489154 -393.705334)
			(xy 152.495758 -393.712954) (xy 152.510652 -393.731004) (xy 152.535718 -393.770519) (xy 152.554968 -393.813172)
			(xy 152.568017 -393.858111) (xy 152.574604 -393.90444) (xy 152.575006 -393.927838) (xy 152.574496 -393.953825)
			(xy 152.566366 -394.00516) (xy 152.550305 -394.05459) (xy 152.526709 -394.1009) (xy 152.496159 -394.142948)
			(xy 152.459408 -394.179699) (xy 152.41736 -394.210249) (xy 152.37105 -394.233845) (xy 152.32162 -394.249906)
			(xy 152.270285 -394.258036) (xy 152.218311 -394.258036) (xy 152.166976 -394.249906) (xy 152.117546 -394.233845)
			(xy 152.071236 -394.210249) (xy 152.029188 -394.179699) (xy 151.992437 -394.142948) (xy 151.961887 -394.1009)
			(xy 151.938291 -394.05459) (xy 151.92223 -394.00516) (xy 151.9141 -393.953825) (xy 151.91359 -393.927838)
			(xy 151.914029 -393.904442) (xy 151.920614 -393.858117) (xy 151.933658 -393.81318) (xy 151.952901 -393.770529)
			(xy 151.977959 -393.731013) (xy 151.992838 -393.712954) (xy 151.999442 -393.705334) (xy 152.005538 -393.687046)
			(xy 152.000204 -393.596876) (xy 151.992076 -393.57935) (xy 151.98471 -393.572492) (xy 151.965816 -393.554374)
			(xy 151.932652 -393.513871) (xy 151.905334 -393.469217) (xy 151.884376 -393.421247) (xy 151.87017 -393.370864)
			(xy 151.862984 -393.319012) (xy 151.862536 -393.292838) (xy 151.425656 -393.292838) (xy 151.425117 -393.321742)
			(xy 151.416412 -393.378892) (xy 151.399192 -393.434076) (xy 151.373851 -393.486034) (xy 151.340967 -393.533579)
			(xy 151.321516 -393.554966) (xy 151.31542 -393.56157) (xy 151.308308 -393.577572) (xy 151.30272 -393.659868)
			(xy 151.307546 -393.676886) (xy 151.312626 -393.683998) (xy 151.327259 -393.70523) (xy 151.350514 -393.75125)
			(xy 151.366341 -393.800322) (xy 151.374357 -393.851257) (xy 151.374856 -393.877038) (xy 151.374346 -393.903025)
			(xy 151.366216 -393.95436) (xy 151.350155 -394.00379) (xy 151.326559 -394.0501) (xy 151.296009 -394.092148)
			(xy 151.259258 -394.128899) (xy 151.21721 -394.159449) (xy 151.1709 -394.183045) (xy 151.12147 -394.199106)
			(xy 151.070135 -394.207236) (xy 151.018161 -394.207236) (xy 150.966826 -394.199106) (xy 150.917396 -394.183045)
			(xy 150.871086 -394.159449) (xy 150.829038 -394.128899) (xy 150.792287 -394.092148) (xy 150.761737 -394.0501)
			(xy 150.738141 -394.00379) (xy 150.72208 -393.95436) (xy 150.71395 -393.903025) (xy 150.71344 -393.877038)
			(xy 150.713923 -393.851255) (xy 150.721929 -393.800314) (xy 150.737753 -393.751236) (xy 150.761009 -393.705213)
			(xy 150.77567 -393.683998) (xy 150.78075 -393.676886) (xy 150.785576 -393.659868) (xy 150.779988 -393.577572)
			(xy 150.772876 -393.56157) (xy 150.76678 -393.554966) (xy 150.747294 -393.533606) (xy 150.714387 -393.486068)
			(xy 150.689037 -393.434105) (xy 150.671825 -393.378909) (xy 150.663148 -393.321747) (xy 150.66264 -393.292838)
			(xy 150.22576 -393.292838) (xy 150.2253 -393.319001) (xy 150.21815 -393.370837) (xy 150.203988 -393.421211)
			(xy 150.18308 -393.469179) (xy 150.155818 -393.513843) (xy 150.122712 -393.554366) (xy 150.10384 -393.572492)
			(xy 150.096474 -393.57935) (xy 150.088346 -393.596876) (xy 150.083012 -393.687046) (xy 150.089108 -393.705334)
			(xy 150.095712 -393.712954) (xy 150.110614 -393.730997) (xy 150.135678 -393.770515) (xy 150.154925 -393.813169)
			(xy 150.167972 -393.85811) (xy 150.174558 -393.90444) (xy 150.17496 -393.927838) (xy 150.17445 -393.953825)
			(xy 150.16632 -394.00516) (xy 150.150259 -394.05459) (xy 150.126663 -394.1009) (xy 150.096113 -394.142948)
			(xy 150.059362 -394.179699) (xy 150.017314 -394.210249) (xy 149.971004 -394.233845) (xy 149.921574 -394.249906)
			(xy 149.870239 -394.258036) (xy 149.818265 -394.258036) (xy 149.76693 -394.249906) (xy 149.7175 -394.233845)
			(xy 149.67119 -394.210249) (xy 149.629142 -394.179699) (xy 149.592391 -394.142948) (xy 149.561841 -394.1009)
			(xy 149.538245 -394.05459) (xy 149.522184 -394.00516) (xy 149.514054 -393.953825) (xy 149.513544 -393.927838)
			(xy 149.51397 -393.904442) (xy 149.520556 -393.858115) (xy 149.533602 -393.813178) (xy 149.552848 -393.770527)
			(xy 149.57791 -393.731012) (xy 149.592792 -393.712954) (xy 149.599396 -393.705334) (xy 149.605492 -393.687046)
			(xy 149.600158 -393.596876) (xy 149.59203 -393.57935) (xy 149.584664 -393.572492) (xy 149.565763 -393.554393)
			(xy 149.532648 -393.51387) (xy 149.50538 -393.469203) (xy 149.484471 -393.421229) (xy 149.470313 -393.370847)
			(xy 149.463171 -393.319004) (xy 149.462744 -393.292838) (xy 149.025864 -393.292838) (xy 149.025249 -393.322996)
			(xy 149.015755 -393.382559) (xy 148.99701 -393.439888) (xy 148.969481 -393.493554) (xy 148.933853 -393.542222)
			(xy 148.912834 -393.563856) (xy 148.90623 -393.57046) (xy 148.89861 -393.587224) (xy 148.893276 -393.67333)
			(xy 148.89861 -393.69111) (xy 148.904452 -393.698476) (xy 148.920958 -393.720465) (xy 148.947233 -393.768758)
			(xy 148.965165 -393.820729) (xy 148.974261 -393.874949) (xy 148.97481 -393.902438) (xy 148.9743 -393.928425)
			(xy 148.96617 -393.97976) (xy 148.950109 -394.02919) (xy 148.926513 -394.0755) (xy 148.895963 -394.117548)
			(xy 148.859212 -394.154299) (xy 148.817164 -394.184849) (xy 148.770854 -394.208445) (xy 148.721424 -394.224506)
			(xy 148.670089 -394.232636) (xy 148.618115 -394.232636) (xy 148.56678 -394.224506) (xy 148.51735 -394.208445)
			(xy 148.47104 -394.184849) (xy 148.428992 -394.154299) (xy 148.392241 -394.117548) (xy 148.361691 -394.0755)
			(xy 148.338095 -394.02919) (xy 148.322034 -393.97976) (xy 148.313904 -393.928425) (xy 148.313394 -393.902438)
			(xy 148.313948 -393.874948) (xy 148.323024 -393.820722) (xy 148.340948 -393.768745) (xy 148.367227 -393.720452)
			(xy 148.383752 -393.698476) (xy 148.389594 -393.69111) (xy 148.394928 -393.67333) (xy 148.389594 -393.587224)
			(xy 148.381974 -393.57046) (xy 148.37537 -393.563856) (xy 148.354326 -393.542242) (xy 148.31868 -393.493577)
			(xy 148.291141 -393.439908) (xy 148.272394 -393.382572) (xy 148.262907 -393.323) (xy 148.26234 -393.292838)
			(xy 147.825968 -393.292838) (xy 147.825352 -393.322996) (xy 147.815858 -393.382559) (xy 147.797113 -393.439888)
			(xy 147.769584 -393.493554) (xy 147.733956 -393.542222) (xy 147.712938 -393.563856) (xy 147.706334 -393.57046)
			(xy 147.698714 -393.587224) (xy 147.69338 -393.67333) (xy 147.698714 -393.69111) (xy 147.704556 -393.698476)
			(xy 147.721062 -393.720465) (xy 147.747337 -393.768758) (xy 147.765269 -393.820729) (xy 147.774365 -393.874949)
			(xy 147.774914 -393.902438) (xy 147.774404 -393.928425) (xy 147.766274 -393.97976) (xy 147.750213 -394.02919)
			(xy 147.726617 -394.0755) (xy 147.696067 -394.117548) (xy 147.659316 -394.154299) (xy 147.617268 -394.184849)
			(xy 147.570958 -394.208445) (xy 147.521528 -394.224506) (xy 147.470193 -394.232636) (xy 147.418219 -394.232636)
			(xy 147.366884 -394.224506) (xy 147.317454 -394.208445) (xy 147.271144 -394.184849) (xy 147.229096 -394.154299)
			(xy 147.192345 -394.117548) (xy 147.161795 -394.0755) (xy 147.138199 -394.02919) (xy 147.122138 -393.97976)
			(xy 147.114008 -393.928425) (xy 147.113498 -393.902438) (xy 147.114051 -393.874948) (xy 147.123127 -393.820722)
			(xy 147.141052 -393.768745) (xy 147.167331 -393.720452) (xy 147.183856 -393.698476) (xy 147.189698 -393.69111)
			(xy 147.195032 -393.67333) (xy 147.189698 -393.587224) (xy 147.182078 -393.57046) (xy 147.175474 -393.563856)
			(xy 147.15443 -393.542242) (xy 147.118785 -393.493577) (xy 147.091245 -393.439908) (xy 147.072498 -393.382572)
			(xy 147.063011 -393.323) (xy 147.062444 -393.292838) (xy 143.330835 -393.292838) (xy 143.359473 -393.337145)
			(xy 143.382311 -393.38689) (xy 143.397805 -393.439388) (xy 143.405637 -393.493562) (xy 143.406114 -393.52093)
			(xy 143.40565 -393.548182) (xy 143.39789 -393.60213) (xy 143.382531 -393.654425) (xy 143.359887 -393.704002)
			(xy 143.330418 -393.749852) (xy 143.294724 -393.791041) (xy 143.253532 -393.826732) (xy 143.207681 -393.856198)
			(xy 143.158102 -393.878839) (xy 143.105806 -393.894195) (xy 143.051858 -393.901952) (xy 143.024606 -393.902438)
			(xy 142.997235 -393.901984) (xy 142.943055 -393.894165) (xy 142.890551 -393.878674) (xy 142.840804 -393.85583)
			(xy 142.794839 -393.826101) (xy 142.773908 -393.808458) (xy 142.766796 -393.802362) (xy 142.749778 -393.796012)
			(xy 142.664434 -393.796012) (xy 142.647416 -393.802362) (xy 142.640304 -393.808458) (xy 142.619371 -393.826099)
			(xy 142.573403 -393.855823) (xy 142.523657 -393.878669) (xy 142.471155 -393.894165) (xy 142.416977 -393.901994)
			(xy 142.362235 -393.901994) (xy 142.308057 -393.894165) (xy 142.255555 -393.878669) (xy 142.205809 -393.855823)
			(xy 142.159841 -393.826099) (xy 142.138908 -393.808458) (xy 142.131796 -393.802362) (xy 142.114778 -393.796012)
			(xy 142.029434 -393.796012) (xy 142.012416 -393.802362) (xy 142.005304 -393.808458) (xy 141.984371 -393.826099)
			(xy 141.938403 -393.855823) (xy 141.888657 -393.878669) (xy 141.836155 -393.894165) (xy 141.781977 -393.901994)
			(xy 141.727235 -393.901994) (xy 141.673057 -393.894165) (xy 141.620555 -393.878669) (xy 141.570809 -393.855823)
			(xy 141.524841 -393.826099) (xy 141.503908 -393.808458) (xy 141.496796 -393.802362) (xy 141.479778 -393.796012)
			(xy 141.394434 -393.796012) (xy 141.377416 -393.802362) (xy 141.370304 -393.808458) (xy 141.349376 -393.826102)
			(xy 141.303403 -393.855815) (xy 141.253654 -393.87865) (xy 141.201152 -393.89414) (xy 141.146976 -393.901966)
			(xy 141.119606 -393.902438) (xy 141.092356 -393.901917) (xy 141.038411 -393.894162) (xy 140.986119 -393.878809)
			(xy 140.936544 -393.856171) (xy 140.890695 -393.826708) (xy 140.849505 -393.79102) (xy 140.813814 -393.749834)
			(xy 140.784347 -393.703988) (xy 140.761704 -393.654415) (xy 140.746346 -393.602124) (xy 140.738586 -393.54818)
			(xy 140.738098 -393.52093) (xy 139.883134 -393.52093) (xy 139.882668 -393.55166) (xy 139.875257 -393.612673)
			(xy 139.860546 -393.672347) (xy 139.83875 -393.729813) (xy 139.810186 -393.784233) (xy 139.775271 -393.834814)
			(xy 139.734515 -393.880818) (xy 139.688511 -393.921574) (xy 139.63793 -393.956488) (xy 139.583509 -393.985051)
			(xy 139.526043 -394.006847) (xy 139.466369 -394.021558) (xy 139.405356 -394.028968) (xy 139.374626 -394.029438)
			(xy 139.343932 -394.028955) (xy 139.282996 -394.021526) (xy 139.223395 -394.00682) (xy 139.165996 -393.985052)
			(xy 139.111632 -393.956538) (xy 139.086082 -393.939522) (xy 139.07733 -393.934051) (xy 139.057126 -393.929923)
			(xy 139.036922 -393.934051) (xy 139.02817 -393.939522) (xy 139.001783 -393.957124) (xy 138.945481 -393.986341)
			(xy 138.885975 -394.008308) (xy 138.855196 -394.015976) (xy 138.837924 -394.020294) (xy 138.81608 -394.047726)
			(xy 138.81608 -394.352018) (xy 145.832828 -394.352018) (xy 145.836899 -394.296396) (xy 145.849025 -394.241959)
			(xy 145.868948 -394.189868) (xy 145.896244 -394.141233) (xy 145.93033 -394.09709) (xy 145.970479 -394.058381)
			(xy 146.015837 -394.02593) (xy 146.065437 -394.000429) (xy 146.118221 -393.982422) (xy 146.173064 -393.972292)
			(xy 146.228798 -393.970255) (xy 146.284235 -393.976355) (xy 146.338192 -393.990461) (xy 146.389521 -394.012273)
			(xy 146.437127 -394.041327) (xy 146.479995 -394.077002) (xy 146.517212 -394.118539) (xy 146.547985 -394.165052)
			(xy 146.571657 -394.215549) (xy 146.587725 -394.268956) (xy 146.595845 -394.324132) (xy 146.596354 -394.352018)
			(xy 146.595845 -394.379904) (xy 146.587725 -394.43508) (xy 146.571657 -394.488487) (xy 146.547985 -394.538984)
			(xy 146.517212 -394.585497) (xy 146.479995 -394.627034) (xy 146.437127 -394.662709) (xy 146.389521 -394.691763)
			(xy 146.338192 -394.713575) (xy 146.284235 -394.727681) (xy 146.228798 -394.733781) (xy 146.173064 -394.731744)
			(xy 146.118221 -394.721614) (xy 146.065437 -394.703607) (xy 146.015837 -394.678106) (xy 145.970479 -394.645655)
			(xy 145.93033 -394.606946) (xy 145.896244 -394.562803) (xy 145.868948 -394.514168) (xy 145.849025 -394.462077)
			(xy 145.836899 -394.40764) (xy 145.832828 -394.352018) (xy 138.81608 -394.352018) (xy 138.81608 -394.559536)
			(xy 138.816509 -394.568899) (xy 138.823248 -394.586372) (xy 138.835813 -394.600258) (xy 138.852528 -394.608704)
			(xy 138.8618 -394.610082) (xy 139.145264 -394.638276) (xy 139.177547 -394.641905) (xy 139.241085 -394.655448)
			(xy 139.302713 -394.676007) (xy 139.361657 -394.703323) (xy 139.417179 -394.737055) (xy 139.468584 -394.776779)
			(xy 139.492228 -394.799058) (xy 139.498578 -394.805408) (xy 139.513818 -394.81252) (xy 139.678918 -394.828522)
			(xy 139.695174 -394.824712) (xy 139.70254 -394.819886) (xy 139.730749 -394.802162) (xy 139.790446 -394.772579)
			(xy 139.853141 -394.750035) (xy 139.918007 -394.734827) (xy 139.984188 -394.727155) (xy 140.0175 -394.726668)
			(xy 140.03175 -394.726819) (xy 140.060211 -394.728344) (xy 140.074396 -394.729716) (xy 140.499338 -394.771626)
			(xy 140.531621 -394.775254) (xy 140.59516 -394.788796) (xy 140.656788 -394.809353) (xy 140.715733 -394.836669)
			(xy 140.771255 -394.870402) (xy 140.82266 -394.910127) (xy 140.846302 -394.932408) (xy 140.852652 -394.938758)
			(xy 140.867892 -394.94587) (xy 142.728442 -395.12875) (xy 142.744698 -395.12494) (xy 142.752064 -395.120114)
			(xy 142.780274 -395.102392) (xy 142.839972 -395.072816) (xy 142.902667 -395.050278) (xy 142.967532 -395.035074)
			(xy 143.033713 -395.027406) (xy 143.067024 -395.026896) (xy 143.081274 -395.027048) (xy 143.109735 -395.028574)
			(xy 143.12392 -395.029944) (xy 143.548862 -395.071854) (xy 143.581153 -395.075501) (xy 143.644705 -395.089079)
			(xy 143.706341 -395.109675) (xy 143.76529 -395.13703) (xy 143.820812 -395.170801) (xy 143.872213 -395.210565)
			(xy 143.895826 -395.23289) (xy 143.902176 -395.238986) (xy 143.917416 -395.246098) (xy 144.837912 -395.336522)
			(xy 144.854168 -395.332712) (xy 144.861534 -395.327886) (xy 144.889743 -395.310161) (xy 144.94944 -395.280578)
			(xy 145.012135 -395.258034) (xy 145.077 -395.242825) (xy 145.143182 -395.235152) (xy 145.176494 -395.234668)
			(xy 145.190744 -395.234819) (xy 145.219205 -395.236344) (xy 145.23339 -395.237716) (xy 145.658332 -395.279626)
			(xy 145.690615 -395.283254) (xy 145.754155 -395.296795) (xy 145.815783 -395.317352) (xy 145.874728 -395.344667)
			(xy 145.930251 -395.378399) (xy 145.981656 -395.418125) (xy 146.005296 -395.440408) (xy 146.011646 -395.446758)
			(xy 146.026886 -395.453616) (xy 146.651472 -395.515084) (xy 146.665653 -395.51657) (xy 146.69386 -395.520763)
			(xy 146.70786 -395.523466) (xy 147.812506 -395.743176) (xy 147.82927 -395.74089) (xy 147.837144 -395.736826)
			(xy 147.868021 -395.721491) (xy 147.932633 -395.697435) (xy 147.999642 -395.681213) (xy 148.068102 -395.673055)
			(xy 148.102574 -395.672564) (xy 148.130951 -395.672872) (xy 148.187441 -395.678342) (xy 148.21535 -395.683486)
			(xy 148.633942 -395.766544) (xy 148.665767 -395.773292) (xy 148.727772 -395.792995) (xy 148.787178 -395.819522)
			(xy 148.843236 -395.85254) (xy 148.895242 -395.891632) (xy 148.942539 -395.936305) (xy 148.963888 -395.960854)
			(xy 148.969476 -395.967712) (xy 148.983954 -395.976348) (xy 150.002494 -396.178786) (xy 150.030336 -396.184676)
			(xy 150.084793 -396.201212) (xy 150.111206 -396.211806) (xy 151.077422 -396.61211) (xy 151.082051 -396.61388)
			(xy 151.091772 -396.615793) (xy 151.096726 -396.61592) (xy 152.287478 -396.61592) (xy 152.297541 -396.616358)
			(xy 152.316123 -396.624094) (xy 152.323546 -396.630906) (xy 153.76779 -398.07515) (xy 153.77541 -398.081246)
			(xy 154.095958 -398.295622) (xy 154.12271 -398.31404) (xy 154.172346 -398.355932) (xy 154.21699 -398.403107)
			(xy 154.256083 -398.454976) (xy 154.289135 -398.510889) (xy 154.315732 -398.570144) (xy 154.326082 -398.60093)
			(xy 154.328876 -398.609312) (xy 154.339036 -398.622774) (xy 155.215082 -399.208244) (xy 155.221444 -399.212216)
			(xy 155.23578 -399.2166) (xy 155.243276 -399.21688) (xy 162.20567 -399.21688)
		)
		(stroke
			(width 0)
			(type solid)
		)
		(fill yes)
		(layer "In13.Cu")
		(net "P0V9_CPU1_RT2_2A_2D")
	)
	(gr_poly
		(pts
			(xy 181.418738 -412.165038) (xy 181.421532 -412.146242) (xy 181.425971 -412.119418) (xy 181.441455 -412.067299)
			(xy 181.46418 -412.017906) (xy 181.493687 -411.972239) (xy 181.529379 -411.931224) (xy 181.570532 -411.895692)
			(xy 181.616312 -411.866362) (xy 181.665793 -411.843828) (xy 181.717972 -411.828547) (xy 181.771791 -411.820828)
			(xy 181.826161 -411.820828) (xy 181.87998 -411.828547) (xy 181.932159 -411.843828) (xy 181.98164 -411.866362)
			(xy 182.02742 -411.895692) (xy 182.068573 -411.931224) (xy 182.104265 -411.972239) (xy 182.133772 -412.017906)
			(xy 182.156497 -412.067299) (xy 182.171981 -412.119418) (xy 182.17642 -412.146242) (xy 182.179214 -412.165038)
			(xy 182.207662 -412.189676) (xy 183.131206 -412.189676) (xy 183.1409 -412.189237) (xy 183.158904 -412.18204)
			(xy 183.166258 -412.175706) (xy 183.217058 -412.127446) (xy 183.223795 -412.120452) (xy 183.231904 -412.102824)
			(xy 183.232806 -412.093156) (xy 183.234711 -412.0656) (xy 183.245468 -412.011423) (xy 183.263925 -411.959364)
			(xy 183.289697 -411.91051) (xy 183.322245 -411.865884) (xy 183.360888 -411.826418) (xy 183.404819 -411.792937)
			(xy 183.453119 -411.766142) (xy 183.504778 -411.746591) (xy 183.558716 -411.734695) (xy 183.613806 -411.730702)
			(xy 183.668896 -411.734695) (xy 183.722834 -411.746591) (xy 183.774493 -411.766142) (xy 183.822793 -411.792937)
			(xy 183.866724 -411.826418) (xy 183.905367 -411.865884) (xy 183.937915 -411.91051) (xy 183.963687 -411.959364)
			(xy 183.982144 -412.011423) (xy 183.992901 -412.0656) (xy 183.994806 -412.093156) (xy 183.995723 -412.102821)
			(xy 184.003829 -412.120443) (xy 184.010554 -412.127446) (xy 184.061354 -412.175706) (xy 184.068679 -412.182078)
			(xy 184.086705 -412.189243) (xy 184.096406 -412.189676) (xy 184.41035 -412.189676) (xy 184.421363 -412.189125)
			(xy 184.44136 -412.17989) (xy 184.448958 -412.171896) (xy 184.46716 -412.151258) (xy 184.508483 -412.114919)
			(xy 184.554601 -412.084899) (xy 184.604556 -412.06182) (xy 184.657309 -412.046163) (xy 184.711766 -412.038252)
			(xy 184.766794 -412.038252) (xy 184.821251 -412.046163) (xy 184.874004 -412.06182) (xy 184.923959 -412.084899)
			(xy 184.970077 -412.114919) (xy 185.0114 -412.151258) (xy 185.029602 -412.171896) (xy 185.037174 -412.17992)
			(xy 185.057191 -412.18914) (xy 185.06821 -412.189676) (xy 185.24093 -412.189676) (xy 185.252664 -412.189153)
			(xy 185.273731 -412.17883) (xy 185.281316 -412.169864) (xy 185.298068 -412.14876) (xy 185.336525 -412.111022)
			(xy 185.379906 -412.079067) (xy 185.42735 -412.053529) (xy 185.477913 -412.034917) (xy 185.530592 -412.023599)
			(xy 185.584338 -412.019802) (xy 185.638084 -412.023599) (xy 185.690763 -412.034917) (xy 185.741326 -412.053529)
			(xy 185.78877 -412.079067) (xy 185.832151 -412.111022) (xy 185.870608 -412.14876) (xy 185.88736 -412.169864)
			(xy 185.894993 -412.178771) (xy 185.91603 -412.189092) (xy 185.927746 -412.189676) (xy 186.862466 -412.189676)
			(xy 186.87089 -412.18933) (xy 186.886838 -412.183895) (xy 186.893708 -412.179008) (xy 186.916118 -412.162216)
			(xy 186.964883 -412.13469) (xy 187.01715 -412.114595) (xy 187.071795 -412.102362) (xy 187.127642 -412.098255)
			(xy 187.183489 -412.102362) (xy 187.238134 -412.114595) (xy 187.290401 -412.13469) (xy 187.339166 -412.162216)
			(xy 187.361576 -412.179008) (xy 187.368415 -412.18396) (xy 187.384379 -412.189429) (xy 187.392818 -412.189676)
			(xy 226.977702 -412.189676) (xy 226.987772 -412.189252) (xy 227.006373 -412.181534) (xy 227.01377 -412.17469)
			(xy 229.436422 -409.752038) (xy 229.44382 -409.745191) (xy 229.462418 -409.737458) (xy 229.47249 -409.737052)
			(xy 234.227624 -409.737052) (xy 234.237691 -409.736623) (xy 234.256285 -409.728897) (xy 234.263692 -409.722066)
			(xy 238.940594 -405.045164) (xy 238.947435 -405.037764) (xy 238.955158 -405.019166) (xy 238.95558 -405.009096)
			(xy 238.95558 -398.856962) (xy 238.955414 -398.850952) (xy 238.952592 -398.839269) (xy 238.949992 -398.833848)
			(xy 238.94815 -398.830375) (xy 238.943553 -398.824) (xy 238.940848 -398.821148) (xy 238.466884 -398.347184)
			(xy 238.464031 -398.344481) (xy 238.45765 -398.339894) (xy 238.454184 -398.33804) (xy 238.448758 -398.335452)
			(xy 238.437079 -398.33262) (xy 238.43107 -398.332452) (xy 235.574332 -398.332452) (xy 235.564268 -398.332889)
			(xy 235.545687 -398.340627) (xy 235.538264 -398.347438) (xy 234.327446 -399.55851) (xy 234.320049 -399.565358)
			(xy 234.30145 -399.573087) (xy 234.291378 -399.573496) (xy 234.248706 -399.573496) (xy 234.238635 -399.573918)
			(xy 234.220029 -399.58163) (xy 234.212638 -399.588482) (xy 234.124246 -399.676874) (xy 234.116846 -399.683715)
			(xy 234.098247 -399.691433) (xy 234.088178 -399.69186) (xy 229.311962 -399.69186) (xy 229.301896 -399.691429)
			(xy 229.283305 -399.6837) (xy 229.275894 -399.676874) (xy 228.429312 -398.830292) (xy 228.424486 -398.826228)
			(xy 228.422708 -398.824704) (xy 228.412207 -398.818224) (xy 228.38778 -398.815031) (xy 228.375972 -398.818608)
			(xy 228.372162 -398.820132) (xy 228.285802 -398.860264) (xy 228.276589 -398.865001) (xy 228.262704 -398.880346)
			(xy 228.256055 -398.899943) (xy 228.256338 -398.910302) (xy 228.257608 -398.940782) (xy 228.257122 -398.968033)
			(xy 228.249366 -399.021981) (xy 228.234011 -399.074276) (xy 228.211369 -399.123853) (xy 228.181903 -399.169703)
			(xy 228.146212 -399.210894) (xy 228.105021 -399.246585) (xy 228.059171 -399.276051) (xy 228.009594 -399.298693)
			(xy 227.957299 -399.314048) (xy 227.903351 -399.321804) (xy 227.848849 -399.321804) (xy 227.794901 -399.314048)
			(xy 227.742606 -399.298693) (xy 227.693029 -399.276051) (xy 227.647179 -399.246585) (xy 227.605988 -399.210894)
			(xy 227.570297 -399.169703) (xy 227.540831 -399.123853) (xy 227.518189 -399.074276) (xy 227.502834 -399.021981)
			(xy 227.495078 -398.968033) (xy 227.494592 -398.940782) (xy 227.495149 -398.912195) (xy 227.503713 -398.855664)
			(xy 227.520603 -398.80104) (xy 227.545442 -398.749541) (xy 227.56114 -398.725644) (xy 227.561394 -398.72539)
			(xy 227.566014 -398.717872) (xy 227.570342 -398.700778) (xy 227.568636 -398.683228) (xy 227.565204 -398.675098)
			(xy 227.520754 -398.591532) (xy 227.515952 -398.584159) (xy 227.502398 -398.57296) (xy 227.485857 -398.566998)
			(xy 227.477066 -398.56664) (xy 224.343722 -398.56664) (xy 224.337713 -398.56681) (xy 224.326032 -398.569636)
			(xy 224.320608 -398.572228) (xy 224.317133 -398.574067) (xy 224.310754 -398.57866) (xy 224.307908 -398.581372)
			(xy 223.735392 -399.153888) (xy 223.730312 -399.159984) (xy 223.72574 -399.16608) (xy 223.722184 -399.171668)
			(xy 223.71151 -399.190664) (xy 223.685628 -399.225718) (xy 223.670622 -399.241518) (xy 223.668082 -399.244058)
			(xy 223.423226 -399.489168) (xy 223.407247 -399.504508) (xy 223.371674 -399.5309) (xy 223.35236 -399.541746)
			(xy 223.349312 -399.54327) (xy 223.340422 -399.549874) (xy 223.334326 -399.554954) (xy 223.237806 -399.651474)
			(xy 223.230409 -399.658324) (xy 223.211811 -399.666065) (xy 223.201738 -399.66646) (xy 218.641422 -399.66646)
			(xy 218.631359 -399.666021) (xy 218.612779 -399.658283) (xy 218.605354 -399.651474) (xy 217.484452 -398.530572)
			(xy 217.481601 -398.527867) (xy 217.475221 -398.523276) (xy 217.471752 -398.521428) (xy 217.466325 -398.518844)
			(xy 217.454646 -398.51602) (xy 217.448638 -398.51584) (xy 217.424762 -398.51584) (xy 217.414749 -398.516267)
			(xy 217.396252 -398.523945) (xy 217.382101 -398.538117) (xy 217.374451 -398.556626) (xy 217.373962 -398.56664)
			(xy 217.373962 -398.566894) (xy 217.374647 -398.579338) (xy 217.386359 -398.601306) (xy 217.396314 -398.608804)
			(xy 217.399362 -398.610582) (xy 217.423758 -398.625349) (xy 217.468276 -398.660983) (xy 217.507001 -398.702841)
			(xy 217.539072 -398.749991) (xy 217.563775 -398.801386) (xy 217.580562 -398.855883) (xy 217.589058 -398.91227)
			(xy 217.589608 -398.940782) (xy 217.589122 -398.968033) (xy 217.581366 -399.021981) (xy 217.566011 -399.074276)
			(xy 217.543369 -399.123853) (xy 217.513903 -399.169703) (xy 217.478212 -399.210894) (xy 217.437021 -399.246585)
			(xy 217.391171 -399.276051) (xy 217.341594 -399.298693) (xy 217.289299 -399.314048) (xy 217.235351 -399.321804)
			(xy 217.180849 -399.321804) (xy 217.126901 -399.314048) (xy 217.074606 -399.298693) (xy 217.025029 -399.276051)
			(xy 216.979179 -399.246585) (xy 216.937988 -399.210894) (xy 216.902297 -399.169703) (xy 216.872831 -399.123853)
			(xy 216.850189 -399.074276) (xy 216.834834 -399.021981) (xy 216.827078 -398.968033) (xy 216.826592 -398.940782)
			(xy 216.827085 -398.9128) (xy 216.835266 -398.857438) (xy 216.851449 -398.803865) (xy 216.875286 -398.753232)
			(xy 216.906267 -398.706626) (xy 216.924636 -398.685512) (xy 216.924636 -398.685258) (xy 216.930787 -398.67771)
			(xy 216.93742 -398.65942) (xy 216.936804 -398.639974) (xy 216.933272 -398.630902) (xy 216.914476 -398.588484)
			(xy 216.894918 -398.544288) (xy 216.890701 -398.536563) (xy 216.878046 -398.52435) (xy 216.862001 -398.517149)
			(xy 216.853262 -398.516094) (xy 216.849198 -398.51584) (xy 213.723982 -398.51584) (xy 213.717971 -398.516003)
			(xy 213.706284 -398.518817) (xy 213.700868 -398.521428) (xy 213.697395 -398.523269) (xy 213.691019 -398.527866)
			(xy 213.688168 -398.530572) (xy 213.062312 -399.156428) (xy 213.055454 -399.16481) (xy 213.05266 -399.169636)
			(xy 213.041569 -399.190669) (xy 213.013884 -399.229326) (xy 212.997542 -399.246598) (xy 212.995002 -399.249138)
			(xy 212.755226 -399.489168) (xy 212.737779 -399.50585) (xy 212.698607 -399.534055) (xy 212.677248 -399.545302)
			(xy 212.669628 -399.549874) (xy 212.663786 -399.554954) (xy 212.615526 -399.603214) (xy 212.608128 -399.610058)
			(xy 212.589528 -399.617779) (xy 212.579458 -399.6182) (xy 208.169002 -399.6182) (xy 208.158932 -399.617777)
			(xy 208.140327 -399.610063) (xy 208.132934 -399.603214) (xy 206.915512 -398.385792) (xy 206.91266 -398.383087)
			(xy 206.906281 -398.378497) (xy 206.902812 -398.376648) (xy 206.897385 -398.374068) (xy 206.885705 -398.371252)
			(xy 206.879698 -398.37106) (xy 203.322682 -398.37106) (xy 203.316671 -398.371223) (xy 203.304985 -398.374038)
			(xy 203.299568 -398.376648) (xy 203.296096 -398.37849) (xy 203.289721 -398.383088) (xy 203.286868 -398.385792)
			(xy 202.731878 -398.940782) (xy 206.158082 -398.940782) (xy 206.162153 -398.88516) (xy 206.174279 -398.830723)
			(xy 206.194202 -398.778632) (xy 206.221498 -398.729997) (xy 206.255584 -398.685854) (xy 206.295733 -398.647145)
			(xy 206.341091 -398.614694) (xy 206.390691 -398.589193) (xy 206.443475 -398.571186) (xy 206.498318 -398.561056)
			(xy 206.554052 -398.559019) (xy 206.609489 -398.565119) (xy 206.663446 -398.579225) (xy 206.714775 -398.601037)
			(xy 206.762381 -398.630091) (xy 206.805249 -398.665766) (xy 206.842466 -398.707303) (xy 206.873239 -398.753816)
			(xy 206.896911 -398.804313) (xy 206.912979 -398.85772) (xy 206.921099 -398.912896) (xy 206.921608 -398.940782)
			(xy 206.921099 -398.968668) (xy 206.912979 -399.023844) (xy 206.896911 -399.077251) (xy 206.873239 -399.127748)
			(xy 206.842466 -399.174261) (xy 206.805249 -399.215798) (xy 206.762381 -399.251473) (xy 206.714775 -399.280527)
			(xy 206.663446 -399.302339) (xy 206.609489 -399.316445) (xy 206.554052 -399.322545) (xy 206.498318 -399.320508)
			(xy 206.443475 -399.310378) (xy 206.390691 -399.292371) (xy 206.341091 -399.26687) (xy 206.295733 -399.234419)
			(xy 206.255584 -399.19571) (xy 206.221498 -399.151567) (xy 206.194202 -399.102932) (xy 206.174279 -399.050841)
			(xy 206.162153 -398.996404) (xy 206.158082 -398.940782) (xy 202.731878 -398.940782) (xy 201.968354 -399.704306)
			(xy 201.964064 -399.70882) (xy 201.957648 -399.719488) (xy 201.955654 -399.725388) (xy 201.953742 -399.732632)
			(xy 201.953748 -399.747606) (xy 201.955654 -399.754852) (xy 201.957678 -399.760737) (xy 201.964096 -399.771395)
			(xy 201.968354 -399.775934) (xy 201.983594 -399.791174) (xy 201.987404 -399.79473) (xy 203.128118 -400.935444)
			(xy 203.14192 -400.949943) (xy 203.164157 -400.983223) (xy 203.179483 -401.020197) (xy 203.187309 -401.05945)
			(xy 203.187808 -401.079462) (xy 203.187808 -401.226528) (xy 203.188301 -401.236531) (xy 203.195966 -401.255012)
			(xy 203.210118 -401.269154) (xy 203.228604 -401.276806) (xy 203.238608 -401.277328) (xy 204.924914 -401.277328)
			(xy 204.930925 -401.277165) (xy 204.942612 -401.27435) (xy 204.948028 -401.27174) (xy 204.951503 -401.269901)
			(xy 204.957883 -401.265309) (xy 204.960728 -401.262596) (xy 205.730348 -400.492722) (xy 205.73746 -400.481292)
			(xy 205.740827 -400.473149) (xy 205.742389 -400.45561) (xy 205.740508 -400.447002) (xy 205.736952 -400.43354)
			(xy 205.736952 -400.433032) (xy 205.717394 -400.361404) (xy 205.715435 -400.355066) (xy 205.708747 -400.343615)
			(xy 205.704186 -400.338798) (xy 205.699614 -400.334226) (xy 205.688184 -400.327622) (xy 205.681326 -400.325844)
			(xy 205.654494 -400.318283) (xy 205.603206 -400.296447) (xy 205.55564 -400.26738) (xy 205.512811 -400.231701)
			(xy 205.475631 -400.190168) (xy 205.44489 -400.143667) (xy 205.421243 -400.093188) (xy 205.405194 -400.039804)
			(xy 205.397085 -399.984654) (xy 205.396592 -399.956782) (xy 205.397079 -399.929532) (xy 205.404838 -399.875586)
			(xy 205.420194 -399.823293) (xy 205.442836 -399.773718) (xy 205.472303 -399.72787) (xy 205.507995 -399.686682)
			(xy 205.549185 -399.650992) (xy 205.595034 -399.621528) (xy 205.64461 -399.598888) (xy 205.696903 -399.583534)
			(xy 205.75085 -399.575778) (xy 205.7781 -399.575274) (xy 205.805972 -399.575781) (xy 205.861124 -399.583892)
			(xy 205.914509 -399.599939) (xy 205.964991 -399.623583) (xy 206.011496 -399.65432) (xy 206.053034 -399.691496)
			(xy 206.088722 -399.734319) (xy 206.1178 -399.781879) (xy 206.139649 -399.833164) (xy 206.147162 -399.860008)
			(xy 206.148686 -399.866358) (xy 206.155544 -399.878296) (xy 206.159862 -399.882614) (xy 206.164685 -399.887167)
			(xy 206.176134 -399.893855) (xy 206.182468 -399.895822) (xy 206.270098 -399.919698) (xy 206.281904 -399.921706)
			(xy 206.305101 -399.915881) (xy 206.314548 -399.908522) (xy 206.342234 -399.88109) (xy 206.342742 -399.880582)
			(xy 206.378048 -399.845022) (xy 206.392547 -399.831218) (xy 206.425825 -399.808977) (xy 206.4628 -399.79365)
			(xy 206.502053 -399.785822) (xy 206.522066 -399.785332) (xy 211.970874 -399.785332) (xy 211.990891 -399.785789)
			(xy 212.030155 -399.793603) (xy 212.067136 -399.808935) (xy 212.100412 -399.831194) (xy 212.114892 -399.845022)
			(xy 213.548976 -401.279106) (xy 213.55333 -401.283273) (xy 213.563607 -401.289562) (xy 213.569296 -401.291552)
			(xy 213.580726 -401.295108) (xy 213.592664 -401.29333) (xy 213.607427 -401.291166) (xy 213.63718 -401.288875)
			(xy 213.6521 -401.288758) (xy 213.668761 -401.288952) (xy 213.701955 -401.291878) (xy 213.718394 -401.2946)
			(xy 213.726525 -401.295391) (xy 213.742577 -401.292401) (xy 213.74989 -401.288758) (xy 213.759034 -401.282662)
			(xy 213.775315 -401.272983) (xy 213.810585 -401.25919) (xy 213.847795 -401.252139) (xy 213.86673 -401.251674)
			(xy 214.660988 -401.251928) (xy 215.621362 -401.251928) (xy 215.627371 -401.25176) (xy 215.639053 -401.248935)
			(xy 215.644476 -401.24634) (xy 215.647953 -401.244504) (xy 215.654338 -401.239917) (xy 215.657176 -401.237196)
			(xy 216.400634 -400.493484) (xy 216.407685 -400.484257) (xy 216.41339 -400.46177) (xy 216.411556 -400.450304)
			(xy 216.38768 -400.36242) (xy 216.38514 -400.3548) (xy 216.379921 -400.344476) (xy 216.36219 -400.329656)
			(xy 216.351104 -400.326352) (xy 216.324126 -400.318915) (xy 216.272541 -400.297224) (xy 216.224679 -400.268228)
			(xy 216.181566 -400.232551) (xy 216.14413 -400.190957) (xy 216.113172 -400.14434) (xy 216.089357 -400.0937)
			(xy 216.073197 -400.040124) (xy 216.065038 -399.984762) (xy 216.064592 -399.956782) (xy 216.065079 -399.929532)
			(xy 216.072838 -399.875586) (xy 216.088194 -399.823293) (xy 216.110836 -399.773718) (xy 216.140303 -399.72787)
			(xy 216.175995 -399.686682) (xy 216.217185 -399.650992) (xy 216.263034 -399.621528) (xy 216.31261 -399.598888)
			(xy 216.364903 -399.583534) (xy 216.41885 -399.575778) (xy 216.4461 -399.575274) (xy 216.472832 -399.575717)
			(xy 216.525774 -399.583171) (xy 216.577156 -399.597947) (xy 216.62597 -399.619756) (xy 216.671259 -399.648169)
			(xy 216.712135 -399.68263) (xy 216.747797 -399.722462) (xy 216.777545 -399.766886) (xy 216.800797 -399.815029)
			(xy 216.817095 -399.865948) (xy 216.826122 -399.918645) (xy 216.827354 -399.945352) (xy 216.827354 -399.947384)
			(xy 216.828216 -399.955592) (xy 216.834448 -399.970864) (xy 216.839546 -399.977356) (xy 216.84488 -399.982436)
			(xy 216.852346 -399.988386) (xy 216.870328 -399.99476) (xy 216.889396 -399.994132) (xy 216.906919 -399.986588)
			(xy 216.913968 -399.98015) (xy 216.954354 -399.939764) (xy 216.968806 -399.926018) (xy 217.001971 -399.903873)
			(xy 217.038815 -399.888612) (xy 217.077925 -399.880819) (xy 217.097864 -399.880328) (xy 222.734124 -399.880328)
			(xy 222.754059 -399.880843) (xy 222.793158 -399.888654) (xy 222.829993 -399.903916) (xy 222.863159 -399.926046)
			(xy 222.877634 -399.939764) (xy 224.216976 -401.279106) (xy 224.22133 -401.283273) (xy 224.231607 -401.289562)
			(xy 224.237296 -401.291552) (xy 224.248726 -401.295108) (xy 224.260664 -401.29333) (xy 224.275427 -401.291166)
			(xy 224.30518 -401.288875) (xy 224.3201 -401.288758) (xy 224.339218 -401.288994) (xy 224.377262 -401.292812)
			(xy 224.396046 -401.296378) (xy 224.401126 -401.297394) (xy 224.408492 -401.297902) (xy 224.428558 -401.293838)
			(xy 224.432876 -401.29206) (xy 224.447354 -401.286726) (xy 224.447862 -401.286726) (xy 224.462902 -401.282285)
			(xy 224.493904 -401.277568) (xy 224.509584 -401.277328) (xy 226.208082 -401.277328) (xy 226.21621 -401.276566)
			(xy 226.22396 -401.275035) (xy 226.238047 -401.267908) (xy 226.243896 -401.262596) (xy 227.022914 -400.483324)
			(xy 227.031405 -400.473973) (xy 227.038748 -400.449841) (xy 227.036884 -400.43735) (xy 227.020628 -400.365468)
			(xy 227.01906 -400.359307) (xy 227.013282 -400.347987) (xy 227.009198 -400.343116) (xy 226.989894 -400.321018)
			(xy 226.979734 -400.313906) (xy 226.974146 -400.311874) (xy 226.947811 -400.300909) (xy 226.898459 -400.272303)
			(xy 226.853913 -400.236671) (xy 226.815165 -400.194807) (xy 226.783078 -400.147644) (xy 226.758367 -400.096231)
			(xy 226.741581 -400.041713) (xy 226.733095 -399.985304) (xy 226.732592 -399.956782) (xy 226.733079 -399.929532)
			(xy 226.740838 -399.875586) (xy 226.756194 -399.823293) (xy 226.778836 -399.773718) (xy 226.808303 -399.72787)
			(xy 226.843995 -399.686682) (xy 226.885185 -399.650992) (xy 226.931034 -399.621528) (xy 226.98061 -399.598888)
			(xy 227.032903 -399.583534) (xy 227.08685 -399.575778) (xy 227.1141 -399.575274) (xy 227.141238 -399.57576)
			(xy 227.194965 -399.583468) (xy 227.247057 -399.598715) (xy 227.296461 -399.621192) (xy 227.34218 -399.650446)
			(xy 227.38329 -399.685886) (xy 227.418961 -399.726795) (xy 227.448473 -399.772348) (xy 227.471229 -399.821625)
			(xy 227.486769 -399.87363) (xy 227.49129 -399.900394) (xy 227.49256 -399.908522) (xy 227.499672 -399.922746)
			(xy 227.505768 -399.928842) (xy 227.51318 -399.935526) (xy 227.531613 -399.943123) (xy 227.551551 -399.943123)
			(xy 227.569984 -399.935526) (xy 227.577396 -399.928842) (xy 227.617274 -399.888964) (xy 227.631727 -399.875219)
			(xy 227.664893 -399.853078) (xy 227.701736 -399.83782) (xy 227.740845 -399.830031) (xy 227.760784 -399.829528)
			(xy 233.478324 -399.829528) (xy 233.498259 -399.830043) (xy 233.537358 -399.837854) (xy 233.574193 -399.853116)
			(xy 233.607359 -399.875246) (xy 233.621834 -399.888964) (xy 234.604052 -400.871182) (xy 237.400082 -400.871182)
			(xy 237.404153 -400.81556) (xy 237.416279 -400.761123) (xy 237.436202 -400.709032) (xy 237.463498 -400.660397)
			(xy 237.497584 -400.616254) (xy 237.537733 -400.577545) (xy 237.583091 -400.545094) (xy 237.632691 -400.519593)
			(xy 237.685475 -400.501586) (xy 237.740318 -400.491456) (xy 237.796052 -400.489419) (xy 237.851489 -400.495519)
			(xy 237.905446 -400.509625) (xy 237.956775 -400.531437) (xy 238.004381 -400.560491) (xy 238.047249 -400.596166)
			(xy 238.084466 -400.637703) (xy 238.115239 -400.684216) (xy 238.138911 -400.734713) (xy 238.154979 -400.78812)
			(xy 238.163099 -400.843296) (xy 238.163608 -400.871182) (xy 238.163099 -400.899068) (xy 238.154979 -400.954244)
			(xy 238.138911 -401.007651) (xy 238.115239 -401.058148) (xy 238.084466 -401.104661) (xy 238.047249 -401.146198)
			(xy 238.004381 -401.181873) (xy 237.956775 -401.210927) (xy 237.905446 -401.232739) (xy 237.851489 -401.246845)
			(xy 237.796052 -401.252945) (xy 237.740318 -401.250908) (xy 237.685475 -401.240778) (xy 237.632691 -401.222771)
			(xy 237.583091 -401.19727) (xy 237.537733 -401.164819) (xy 237.497584 -401.12611) (xy 237.463498 -401.081967)
			(xy 237.436202 -401.033332) (xy 237.416279 -400.981241) (xy 237.404153 -400.926804) (xy 237.400082 -400.871182)
			(xy 234.604052 -400.871182) (xy 235.011976 -401.279106) (xy 235.01633 -401.283273) (xy 235.026607 -401.289562)
			(xy 235.032296 -401.291552) (xy 235.043726 -401.295108) (xy 235.055664 -401.29333) (xy 235.070427 -401.291166)
			(xy 235.10018 -401.288875) (xy 235.1151 -401.288758) (xy 235.142356 -401.289221) (xy 235.196313 -401.296979)
			(xy 235.248616 -401.312337) (xy 235.298201 -401.334982) (xy 235.344059 -401.364454) (xy 235.385256 -401.400152)
			(xy 235.420953 -401.44135) (xy 235.450423 -401.487209) (xy 235.473067 -401.536795) (xy 235.488423 -401.589098)
			(xy 235.49618 -401.643055) (xy 235.496178 -401.697567) (xy 235.488419 -401.751524) (xy 235.473059 -401.803827)
			(xy 235.450412 -401.853411) (xy 235.420939 -401.899268) (xy 235.38524 -401.940464) (xy 235.344041 -401.97616)
			(xy 235.298182 -402.005629) (xy 235.248595 -402.028271) (xy 235.19629 -402.043626) (xy 235.142333 -402.051381)
			(xy 235.087822 -402.051377) (xy 235.033865 -402.043616) (xy 234.981563 -402.028255) (xy 234.931979 -402.005607)
			(xy 234.886123 -401.976132) (xy 234.844928 -401.940432) (xy 234.809234 -401.899232) (xy 234.779766 -401.853372)
			(xy 234.757125 -401.803784) (xy 234.741772 -401.751479) (xy 234.734019 -401.697522) (xy 234.733592 -401.670266)
			(xy 234.733717 -401.655346) (xy 234.736007 -401.625594) (xy 234.738164 -401.61083) (xy 234.740196 -401.598384)
			(xy 234.73664 -401.587462) (xy 234.734605 -401.581852) (xy 234.72831 -401.571717) (xy 234.724194 -401.567396)
			(xy 234.060238 -400.90344) (xy 233.407966 -400.250914) (xy 233.402069 -400.245568) (xy 233.387842 -400.238451)
			(xy 233.380026 -400.236944) (xy 233.372406 -400.236436) (xy 233.331766 -400.236436) (xy 233.329226 -400.236436)
			(xy 233.316538 -400.237827) (xy 233.294805 -400.251151) (xy 233.287824 -400.261836) (xy 233.245406 -400.344132)
			(xy 233.242386 -400.350423) (xy 233.239554 -400.364082) (xy 233.239818 -400.371056) (xy 233.24058 -400.381724)
			(xy 233.247184 -400.39417) (xy 233.248962 -400.39671) (xy 233.265498 -400.421021) (xy 233.291695 -400.473657)
			(xy 233.309512 -400.529686) (xy 233.318528 -400.587785) (xy 233.319066 -400.617182) (xy 233.31858 -400.644433)
			(xy 233.310824 -400.698381) (xy 233.295469 -400.750676) (xy 233.272827 -400.800253) (xy 233.243361 -400.846103)
			(xy 233.20767 -400.887294) (xy 233.166479 -400.922985) (xy 233.120629 -400.952451) (xy 233.071052 -400.975093)
			(xy 233.018757 -400.990448) (xy 232.964809 -400.998204) (xy 232.910307 -400.998204) (xy 232.856359 -400.990448)
			(xy 232.804064 -400.975093) (xy 232.754487 -400.952451) (xy 232.708637 -400.922985) (xy 232.667446 -400.887294)
			(xy 232.631755 -400.846103) (xy 232.602289 -400.800253) (xy 232.579647 -400.750676) (xy 232.564292 -400.698381)
			(xy 232.556536 -400.644433) (xy 232.55605 -400.617182) (xy 232.556593 -400.587785) (xy 232.56561 -400.529688)
			(xy 232.583427 -400.473659) (xy 232.609624 -400.421025) (xy 232.626154 -400.39671) (xy 232.627932 -400.39417)
			(xy 232.629456 -400.391122) (xy 232.631817 -400.386412) (xy 232.634758 -400.376297) (xy 232.635298 -400.371056)
			(xy 232.636314 -400.356832) (xy 232.587292 -400.261836) (xy 232.582805 -400.254649) (xy 232.570036 -400.243527)
			(xy 232.554329 -400.237201) (xy 232.54589 -400.236436) (xy 231.934766 -400.236436) (xy 231.932226 -400.236436)
			(xy 231.919538 -400.237827) (xy 231.897805 -400.251151) (xy 231.890824 -400.261836) (xy 231.848406 -400.344132)
			(xy 231.845386 -400.350423) (xy 231.842554 -400.364082) (xy 231.842818 -400.371056) (xy 231.84358 -400.381724)
			(xy 231.850184 -400.39417) (xy 231.851962 -400.39671) (xy 231.868498 -400.421021) (xy 231.894695 -400.473657)
			(xy 231.912512 -400.529686) (xy 231.921528 -400.587785) (xy 231.922066 -400.617182) (xy 231.92158 -400.644433)
			(xy 231.913824 -400.698381) (xy 231.898469 -400.750676) (xy 231.875827 -400.800253) (xy 231.846361 -400.846103)
			(xy 231.81067 -400.887294) (xy 231.769479 -400.922985) (xy 231.723629 -400.952451) (xy 231.674052 -400.975093)
			(xy 231.621757 -400.990448) (xy 231.567809 -400.998204) (xy 231.513307 -400.998204) (xy 231.459359 -400.990448)
			(xy 231.407064 -400.975093) (xy 231.357487 -400.952451) (xy 231.311637 -400.922985) (xy 231.270446 -400.887294)
			(xy 231.234755 -400.846103) (xy 231.205289 -400.800253) (xy 231.182647 -400.750676) (xy 231.167292 -400.698381)
			(xy 231.159536 -400.644433) (xy 231.15905 -400.617182) (xy 231.159593 -400.587785) (xy 231.16861 -400.529688)
			(xy 231.186427 -400.473659) (xy 231.212624 -400.421025) (xy 231.229154 -400.39671) (xy 231.230932 -400.39417)
			(xy 231.232456 -400.391122) (xy 231.234817 -400.386412) (xy 231.237758 -400.376297) (xy 231.238298 -400.371056)
			(xy 231.239314 -400.356832) (xy 231.190292 -400.261836) (xy 231.185805 -400.254649) (xy 231.173036 -400.243527)
			(xy 231.157329 -400.237201) (xy 231.14889 -400.236436) (xy 230.512366 -400.236436) (xy 230.509826 -400.236436)
			(xy 230.497138 -400.237827) (xy 230.475405 -400.251151) (xy 230.468424 -400.261836) (xy 230.426006 -400.344132)
			(xy 230.422986 -400.350423) (xy 230.420154 -400.364082) (xy 230.420418 -400.371056) (xy 230.42118 -400.381724)
			(xy 230.427784 -400.39417) (xy 230.429562 -400.39671) (xy 230.446098 -400.421021) (xy 230.472295 -400.473657)
			(xy 230.490112 -400.529686) (xy 230.499128 -400.587785) (xy 230.499666 -400.617182) (xy 230.49918 -400.644433)
			(xy 230.491424 -400.698381) (xy 230.476069 -400.750676) (xy 230.453427 -400.800253) (xy 230.423961 -400.846103)
			(xy 230.38827 -400.887294) (xy 230.347079 -400.922985) (xy 230.301229 -400.952451) (xy 230.251652 -400.975093)
			(xy 230.199357 -400.990448) (xy 230.145409 -400.998204) (xy 230.090907 -400.998204) (xy 230.036959 -400.990448)
			(xy 229.984664 -400.975093) (xy 229.935087 -400.952451) (xy 229.889237 -400.922985) (xy 229.848046 -400.887294)
			(xy 229.812355 -400.846103) (xy 229.782889 -400.800253) (xy 229.760247 -400.750676) (xy 229.744892 -400.698381)
			(xy 229.737136 -400.644433) (xy 229.73665 -400.617182) (xy 229.737193 -400.587785) (xy 229.74621 -400.529688)
			(xy 229.764027 -400.473659) (xy 229.790224 -400.421025) (xy 229.806754 -400.39671) (xy 229.808532 -400.39417)
			(xy 229.810056 -400.391122) (xy 229.812417 -400.386412) (xy 229.815358 -400.376297) (xy 229.815898 -400.371056)
			(xy 229.816914 -400.356832) (xy 229.767892 -400.261836) (xy 229.763405 -400.254649) (xy 229.750636 -400.243527)
			(xy 229.734929 -400.237201) (xy 229.72649 -400.236436) (xy 227.866702 -400.236436) (xy 227.85705 -400.237452)
			(xy 227.849721 -400.23911) (xy 227.83642 -400.246082) (xy 227.830888 -400.251168) (xy 226.912107 -401.17014)
			(xy 227.494082 -401.17014) (xy 227.498153 -401.114518) (xy 227.510279 -401.060081) (xy 227.530202 -401.00799)
			(xy 227.557498 -400.959355) (xy 227.591584 -400.915212) (xy 227.631733 -400.876503) (xy 227.677091 -400.844052)
			(xy 227.726691 -400.818551) (xy 227.779475 -400.800544) (xy 227.834318 -400.790414) (xy 227.890052 -400.788377)
			(xy 227.945489 -400.794477) (xy 227.999446 -400.808583) (xy 228.050775 -400.830395) (xy 228.098381 -400.859449)
			(xy 228.141249 -400.895124) (xy 228.178466 -400.936661) (xy 228.209239 -400.983174) (xy 228.232911 -401.033671)
			(xy 228.248979 -401.087078) (xy 228.257099 -401.142254) (xy 228.257608 -401.17014) (xy 228.257099 -401.198026)
			(xy 228.248979 -401.253202) (xy 228.232911 -401.306609) (xy 228.209239 -401.357106) (xy 228.178466 -401.403619)
			(xy 228.141249 -401.445156) (xy 228.098381 -401.480831) (xy 228.050775 -401.509885) (xy 227.999446 -401.531697)
			(xy 227.945489 -401.545803) (xy 227.890052 -401.551903) (xy 227.834318 -401.549866) (xy 227.779475 -401.539736)
			(xy 227.726691 -401.521729) (xy 227.677091 -401.496228) (xy 227.631733 -401.463777) (xy 227.591584 -401.425068)
			(xy 227.557498 -401.380925) (xy 227.530202 -401.33229) (xy 227.510279 -401.280199) (xy 227.498153 -401.225762)
			(xy 227.494082 -401.17014) (xy 226.912107 -401.17014) (xy 226.612196 -401.470114) (xy 226.605794 -401.4772)
			(xy 226.598299 -401.494749) (xy 226.597692 -401.513823) (xy 226.600512 -401.522946) (xy 226.601528 -401.525232)
			(xy 226.604679 -401.532225) (xy 226.614358 -401.544113) (xy 226.620578 -401.5486) (xy 226.62642 -401.55241)
			(xy 226.64039 -401.556728) (xy 227.386642 -401.556728) (xy 227.406576 -401.557245) (xy 227.445673 -401.565059)
			(xy 227.482506 -401.580323) (xy 227.51567 -401.602455) (xy 227.530152 -401.616164) (xy 227.834124 -401.920202)
			(xy 229.73614 -401.920202) (xy 229.740211 -401.86458) (xy 229.752337 -401.810143) (xy 229.77226 -401.758052)
			(xy 229.799556 -401.709417) (xy 229.833642 -401.665274) (xy 229.873791 -401.626565) (xy 229.919149 -401.594114)
			(xy 229.968749 -401.568613) (xy 230.021533 -401.550606) (xy 230.076376 -401.540476) (xy 230.13211 -401.538439)
			(xy 230.187547 -401.544539) (xy 230.241504 -401.558645) (xy 230.292833 -401.580457) (xy 230.340439 -401.609511)
			(xy 230.383307 -401.645186) (xy 230.420524 -401.686723) (xy 230.451297 -401.733236) (xy 230.474969 -401.783733)
			(xy 230.491037 -401.83714) (xy 230.499157 -401.892316) (xy 230.499666 -401.920202) (xy 232.55554 -401.920202)
			(xy 232.559611 -401.86458) (xy 232.571737 -401.810143) (xy 232.59166 -401.758052) (xy 232.618956 -401.709417)
			(xy 232.653042 -401.665274) (xy 232.693191 -401.626565) (xy 232.738549 -401.594114) (xy 232.788149 -401.568613)
			(xy 232.840933 -401.550606) (xy 232.895776 -401.540476) (xy 232.95151 -401.538439) (xy 233.006947 -401.544539)
			(xy 233.060904 -401.558645) (xy 233.112233 -401.580457) (xy 233.159839 -401.609511) (xy 233.202707 -401.645186)
			(xy 233.239924 -401.686723) (xy 233.270697 -401.733236) (xy 233.294369 -401.783733) (xy 233.310437 -401.83714)
			(xy 233.318557 -401.892316) (xy 233.319066 -401.920202) (xy 233.318557 -401.948088) (xy 233.310437 -402.003264)
			(xy 233.294369 -402.056671) (xy 233.270697 -402.107168) (xy 233.239924 -402.153681) (xy 233.225179 -402.170138)
			(xy 233.971082 -402.170138) (xy 233.975153 -402.114516) (xy 233.987279 -402.060079) (xy 234.007202 -402.007988)
			(xy 234.034498 -401.959353) (xy 234.068584 -401.91521) (xy 234.108733 -401.876501) (xy 234.154091 -401.84405)
			(xy 234.203691 -401.818549) (xy 234.256475 -401.800542) (xy 234.311318 -401.790412) (xy 234.367052 -401.788375)
			(xy 234.422489 -401.794475) (xy 234.476446 -401.808581) (xy 234.527775 -401.830393) (xy 234.575381 -401.859447)
			(xy 234.618249 -401.895122) (xy 234.655466 -401.936659) (xy 234.686239 -401.983172) (xy 234.709911 -402.033669)
			(xy 234.725979 -402.087076) (xy 234.734099 -402.142252) (xy 234.734608 -402.170138) (xy 234.734099 -402.198024)
			(xy 234.725979 -402.2532) (xy 234.709911 -402.306607) (xy 234.686239 -402.357104) (xy 234.655466 -402.403617)
			(xy 234.618249 -402.445154) (xy 234.575381 -402.480829) (xy 234.527775 -402.509883) (xy 234.476446 -402.531695)
			(xy 234.422489 -402.545801) (xy 234.367052 -402.551901) (xy 234.311318 -402.549864) (xy 234.256475 -402.539734)
			(xy 234.203691 -402.521727) (xy 234.154091 -402.496226) (xy 234.108733 -402.463775) (xy 234.068584 -402.425066)
			(xy 234.034498 -402.380923) (xy 234.007202 -402.332288) (xy 233.987279 -402.280197) (xy 233.975153 -402.22576)
			(xy 233.971082 -402.170138) (xy 233.225179 -402.170138) (xy 233.202707 -402.195218) (xy 233.159839 -402.230893)
			(xy 233.112233 -402.259947) (xy 233.060904 -402.281759) (xy 233.006947 -402.295865) (xy 232.95151 -402.301965)
			(xy 232.895776 -402.299928) (xy 232.840933 -402.289798) (xy 232.788149 -402.271791) (xy 232.738549 -402.24629)
			(xy 232.693191 -402.213839) (xy 232.653042 -402.17513) (xy 232.618956 -402.130987) (xy 232.59166 -402.082352)
			(xy 232.571737 -402.030261) (xy 232.559611 -401.975824) (xy 232.55554 -401.920202) (xy 230.499666 -401.920202)
			(xy 230.499157 -401.948088) (xy 230.491037 -402.003264) (xy 230.474969 -402.056671) (xy 230.451297 -402.107168)
			(xy 230.420524 -402.153681) (xy 230.383307 -402.195218) (xy 230.340439 -402.230893) (xy 230.292833 -402.259947)
			(xy 230.241504 -402.281759) (xy 230.187547 -402.295865) (xy 230.13211 -402.301965) (xy 230.076376 -402.299928)
			(xy 230.021533 -402.289798) (xy 229.968749 -402.271791) (xy 229.919149 -402.24629) (xy 229.873791 -402.213839)
			(xy 229.833642 -402.17513) (xy 229.799556 -402.130987) (xy 229.77226 -402.082352) (xy 229.752337 -402.030261)
			(xy 229.740211 -401.975824) (xy 229.73614 -401.920202) (xy 227.834124 -401.920202) (xy 228.698552 -402.784818)
			(xy 228.70922 -402.792946) (xy 228.72065 -402.797772) (xy 228.72319 -402.79828) (xy 228.750884 -402.805169)
			(xy 228.803993 -402.826054) (xy 228.853398 -402.854615) (xy 228.897999 -402.890216) (xy 228.936799 -402.932063)
			(xy 228.968935 -402.979222) (xy 228.993688 -403.030641) (xy 229.010506 -403.085173) (xy 229.019015 -403.141603)
			(xy 229.019608 -403.170136) (xy 229.019122 -403.197387) (xy 229.015408 -403.223222) (xy 229.73614 -403.223222)
			(xy 229.740211 -403.1676) (xy 229.752337 -403.113163) (xy 229.77226 -403.061072) (xy 229.799556 -403.012437)
			(xy 229.833642 -402.968294) (xy 229.873791 -402.929585) (xy 229.919149 -402.897134) (xy 229.968749 -402.871633)
			(xy 230.021533 -402.853626) (xy 230.076376 -402.843496) (xy 230.13211 -402.841459) (xy 230.187547 -402.847559)
			(xy 230.241504 -402.861665) (xy 230.292833 -402.883477) (xy 230.340439 -402.912531) (xy 230.383307 -402.948206)
			(xy 230.420524 -402.989743) (xy 230.451297 -403.036256) (xy 230.474969 -403.086753) (xy 230.491037 -403.14016)
			(xy 230.499157 -403.195336) (xy 230.499666 -403.223222) (xy 231.15854 -403.223222) (xy 231.162611 -403.1676)
			(xy 231.174737 -403.113163) (xy 231.19466 -403.061072) (xy 231.221956 -403.012437) (xy 231.256042 -402.968294)
			(xy 231.296191 -402.929585) (xy 231.341549 -402.897134) (xy 231.391149 -402.871633) (xy 231.443933 -402.853626)
			(xy 231.498776 -402.843496) (xy 231.55451 -402.841459) (xy 231.609947 -402.847559) (xy 231.663904 -402.861665)
			(xy 231.715233 -402.883477) (xy 231.762839 -402.912531) (xy 231.805707 -402.948206) (xy 231.842924 -402.989743)
			(xy 231.873697 -403.036256) (xy 231.897369 -403.086753) (xy 231.913437 -403.14016) (xy 231.921557 -403.195336)
			(xy 231.922066 -403.223222) (xy 232.55554 -403.223222) (xy 232.559611 -403.1676) (xy 232.571737 -403.113163)
			(xy 232.59166 -403.061072) (xy 232.618956 -403.012437) (xy 232.653042 -402.968294) (xy 232.693191 -402.929585)
			(xy 232.738549 -402.897134) (xy 232.788149 -402.871633) (xy 232.840933 -402.853626) (xy 232.895776 -402.843496)
			(xy 232.95151 -402.841459) (xy 233.006947 -402.847559) (xy 233.060904 -402.861665) (xy 233.112233 -402.883477)
			(xy 233.14452 -402.903182) (xy 237.400082 -402.903182) (xy 237.404153 -402.84756) (xy 237.416279 -402.793123)
			(xy 237.436202 -402.741032) (xy 237.463498 -402.692397) (xy 237.497584 -402.648254) (xy 237.537733 -402.609545)
			(xy 237.583091 -402.577094) (xy 237.632691 -402.551593) (xy 237.685475 -402.533586) (xy 237.740318 -402.523456)
			(xy 237.796052 -402.521419) (xy 237.851489 -402.527519) (xy 237.905446 -402.541625) (xy 237.956775 -402.563437)
			(xy 238.004381 -402.592491) (xy 238.047249 -402.628166) (xy 238.084466 -402.669703) (xy 238.115239 -402.716216)
			(xy 238.138911 -402.766713) (xy 238.154979 -402.82012) (xy 238.163099 -402.875296) (xy 238.163608 -402.903182)
			(xy 238.163099 -402.931068) (xy 238.154979 -402.986244) (xy 238.138911 -403.039651) (xy 238.115239 -403.090148)
			(xy 238.084466 -403.136661) (xy 238.047249 -403.178198) (xy 238.004381 -403.213873) (xy 237.956775 -403.242927)
			(xy 237.905446 -403.264739) (xy 237.851489 -403.278845) (xy 237.796052 -403.284945) (xy 237.740318 -403.282908)
			(xy 237.685475 -403.272778) (xy 237.632691 -403.254771) (xy 237.583091 -403.22927) (xy 237.537733 -403.196819)
			(xy 237.497584 -403.15811) (xy 237.463498 -403.113967) (xy 237.436202 -403.065332) (xy 237.416279 -403.013241)
			(xy 237.404153 -402.958804) (xy 237.400082 -402.903182) (xy 233.14452 -402.903182) (xy 233.159839 -402.912531)
			(xy 233.202707 -402.948206) (xy 233.239924 -402.989743) (xy 233.270697 -403.036256) (xy 233.294369 -403.086753)
			(xy 233.310437 -403.14016) (xy 233.318557 -403.195336) (xy 233.319066 -403.223222) (xy 233.318557 -403.251108)
			(xy 233.310437 -403.306284) (xy 233.294369 -403.359691) (xy 233.270697 -403.410188) (xy 233.239924 -403.456701)
			(xy 233.202707 -403.498238) (xy 233.159839 -403.533913) (xy 233.112233 -403.562967) (xy 233.060904 -403.584779)
			(xy 233.006947 -403.598885) (xy 232.95151 -403.604985) (xy 232.895776 -403.602948) (xy 232.840933 -403.592818)
			(xy 232.788149 -403.574811) (xy 232.738549 -403.54931) (xy 232.693191 -403.516859) (xy 232.653042 -403.47815)
			(xy 232.618956 -403.434007) (xy 232.59166 -403.385372) (xy 232.571737 -403.333281) (xy 232.559611 -403.278844)
			(xy 232.55554 -403.223222) (xy 231.922066 -403.223222) (xy 231.921557 -403.251108) (xy 231.913437 -403.306284)
			(xy 231.897369 -403.359691) (xy 231.873697 -403.410188) (xy 231.842924 -403.456701) (xy 231.805707 -403.498238)
			(xy 231.762839 -403.533913) (xy 231.715233 -403.562967) (xy 231.663904 -403.584779) (xy 231.609947 -403.598885)
			(xy 231.55451 -403.604985) (xy 231.498776 -403.602948) (xy 231.443933 -403.592818) (xy 231.391149 -403.574811)
			(xy 231.341549 -403.54931) (xy 231.296191 -403.516859) (xy 231.256042 -403.47815) (xy 231.221956 -403.434007)
			(xy 231.19466 -403.385372) (xy 231.174737 -403.333281) (xy 231.162611 -403.278844) (xy 231.15854 -403.223222)
			(xy 230.499666 -403.223222) (xy 230.499157 -403.251108) (xy 230.491037 -403.306284) (xy 230.474969 -403.359691)
			(xy 230.451297 -403.410188) (xy 230.420524 -403.456701) (xy 230.383307 -403.498238) (xy 230.340439 -403.533913)
			(xy 230.292833 -403.562967) (xy 230.241504 -403.584779) (xy 230.187547 -403.598885) (xy 230.13211 -403.604985)
			(xy 230.076376 -403.602948) (xy 230.021533 -403.592818) (xy 229.968749 -403.574811) (xy 229.919149 -403.54931)
			(xy 229.873791 -403.516859) (xy 229.833642 -403.47815) (xy 229.799556 -403.434007) (xy 229.77226 -403.385372)
			(xy 229.752337 -403.333281) (xy 229.740211 -403.278844) (xy 229.73614 -403.223222) (xy 229.015408 -403.223222)
			(xy 229.011366 -403.251335) (xy 228.996011 -403.30363) (xy 228.973369 -403.353207) (xy 228.943903 -403.399057)
			(xy 228.908212 -403.440248) (xy 228.867021 -403.475939) (xy 228.821171 -403.505405) (xy 228.771594 -403.528047)
			(xy 228.719299 -403.543402) (xy 228.665351 -403.551158) (xy 228.610849 -403.551158) (xy 228.556901 -403.543402)
			(xy 228.504606 -403.528047) (xy 228.455029 -403.505405) (xy 228.409179 -403.475939) (xy 228.367988 -403.440248)
			(xy 228.332297 -403.399057) (xy 228.302831 -403.353207) (xy 228.280189 -403.30363) (xy 228.264834 -403.251335)
			(xy 228.257078 -403.197387) (xy 228.256592 -403.170136) (xy 228.257098 -403.141567) (xy 228.265618 -403.085069)
			(xy 228.282473 -403.030475) (xy 228.294438 -403.004528) (xy 228.294438 -403.004274) (xy 228.297596 -402.997092)
			(xy 228.299801 -402.981569) (xy 228.298756 -402.973794) (xy 228.297486 -402.966174) (xy 228.290374 -402.952204)
			(xy 227.974398 -402.636482) (xy 227.64242 -402.304504) (xy 227.635621 -402.298218) (xy 227.618775 -402.290569)
			(xy 227.60031 -402.289413) (xy 227.591366 -402.291804) (xy 227.588572 -402.29282) (xy 227.502212 -402.325332)
			(xy 227.495475 -402.32819) (xy 227.483874 -402.337102) (xy 227.479352 -402.342858) (xy 227.475254 -402.348807)
			(xy 227.470236 -402.362347) (xy 227.469446 -402.369528) (xy 227.469446 -402.369782) (xy 227.467024 -402.398398)
			(xy 227.454669 -402.454481) (xy 227.434045 -402.508078) (xy 227.405618 -402.557977) (xy 227.370031 -402.60305)
			(xy 227.328089 -402.642277) (xy 227.280739 -402.674773) (xy 227.229053 -402.699803) (xy 227.174198 -402.7168)
			(xy 227.117414 -402.72538) (xy 227.0887 -402.72589) (xy 227.061448 -402.725427) (xy 227.007498 -402.71767)
			(xy 226.955201 -402.702313) (xy 226.905622 -402.679671) (xy 226.85977 -402.650202) (xy 226.818579 -402.614508)
			(xy 226.782887 -402.573316) (xy 226.753421 -402.527462) (xy 226.73078 -402.477882) (xy 226.715427 -402.425585)
			(xy 226.707672 -402.371634) (xy 226.707192 -402.344382) (xy 226.707681 -402.316777) (xy 226.71564 -402.262144)
			(xy 226.731388 -402.209228) (xy 226.754598 -402.159133) (xy 226.784785 -402.112907) (xy 226.821318 -402.071512)
			(xy 226.842066 -402.053298) (xy 226.850204 -402.045708) (xy 226.859568 -402.02555) (xy 226.8601 -402.014436)
			(xy 226.859687 -402.00441) (xy 226.852023 -401.985881) (xy 226.83785 -401.971697) (xy 226.819326 -401.96402)
			(xy 226.8093 -401.963636) (xy 226.73691 -401.963636) (xy 226.72929 -401.964144) (xy 226.721372 -401.965629)
			(xy 226.706994 -401.97288) (xy 226.701096 -401.978368) (xy 226.013518 -402.6662) (xy 225.999066 -402.679946)
			(xy 225.965901 -402.70209) (xy 225.929057 -402.717349) (xy 225.889947 -402.725138) (xy 225.870008 -402.725636)
			(xy 225.58629 -402.725636) (xy 225.576576 -402.726067) (xy 225.558539 -402.733287) (xy 225.544474 -402.74669)
			(xy 225.540062 -402.755354) (xy 225.501708 -402.839682) (xy 225.500946 -402.84146) (xy 225.497649 -402.850318)
			(xy 225.497181 -402.869201) (xy 225.50362 -402.886958) (xy 225.509582 -402.894292) (xy 225.527157 -402.915199)
			(xy 225.556769 -402.961092) (xy 225.579537 -403.010737) (xy 225.594994 -403.063121) (xy 225.602826 -403.117174)
			(xy 225.603308 -403.144482) (xy 225.602822 -403.171733) (xy 225.595066 -403.225681) (xy 225.579711 -403.277976)
			(xy 225.557069 -403.327553) (xy 225.527603 -403.373403) (xy 225.491912 -403.414594) (xy 225.450721 -403.450285)
			(xy 225.404871 -403.479751) (xy 225.355294 -403.502393) (xy 225.302999 -403.517748) (xy 225.249051 -403.525504)
			(xy 225.194549 -403.525504) (xy 225.140601 -403.517748) (xy 225.088306 -403.502393) (xy 225.038729 -403.479751)
			(xy 224.992879 -403.450285) (xy 224.951688 -403.414594) (xy 224.915997 -403.373403) (xy 224.886531 -403.327553)
			(xy 224.863889 -403.277976) (xy 224.848534 -403.225681) (xy 224.840778 -403.171733) (xy 224.840292 -403.144482)
			(xy 224.840763 -403.117149) (xy 224.84857 -403.063043) (xy 224.864022 -403.010605) (xy 224.886802 -402.960911)
			(xy 224.916444 -402.914979) (xy 224.934018 -402.894038) (xy 224.938653 -402.88831) (xy 224.944709 -402.874885)
			(xy 224.945956 -402.867622) (xy 224.946972 -402.860764) (xy 224.94494 -402.846794) (xy 224.938336 -402.832062)
			(xy 224.903538 -402.755354) (xy 224.89912 -402.746688) (xy 224.885066 -402.733264) (xy 224.867027 -402.726031)
			(xy 224.85731 -402.725636) (xy 224.630742 -402.725636) (xy 224.625916 -402.72589) (xy 224.617337 -402.727064)
			(xy 224.601637 -402.734341) (xy 224.595182 -402.740114) (xy 224.468436 -402.867114) (xy 224.33788 -402.99767)
			(xy 224.331193 -403.005079) (xy 224.323603 -403.023515) (xy 224.323148 -403.033484) (xy 224.323148 -408.084782)
			(xy 224.700082 -408.084782) (xy 224.704153 -408.02916) (xy 224.716279 -407.974723) (xy 224.736202 -407.922632)
			(xy 224.763498 -407.873997) (xy 224.797584 -407.829854) (xy 224.837733 -407.791145) (xy 224.883091 -407.758694)
			(xy 224.932691 -407.733193) (xy 224.985475 -407.715186) (xy 225.040318 -407.705056) (xy 225.096052 -407.703019)
			(xy 225.151489 -407.709119) (xy 225.205446 -407.723225) (xy 225.256775 -407.745037) (xy 225.304381 -407.774091)
			(xy 225.347249 -407.809766) (xy 225.384466 -407.851303) (xy 225.415239 -407.897816) (xy 225.438911 -407.948313)
			(xy 225.454979 -408.00172) (xy 225.463099 -408.056896) (xy 225.463608 -408.084782) (xy 225.463099 -408.112668)
			(xy 225.454979 -408.167844) (xy 225.438911 -408.221251) (xy 225.415239 -408.271748) (xy 225.384466 -408.318261)
			(xy 225.347249 -408.359798) (xy 225.304381 -408.395473) (xy 225.256775 -408.424527) (xy 225.205446 -408.446339)
			(xy 225.151489 -408.460445) (xy 225.096052 -408.466545) (xy 225.040318 -408.464508) (xy 224.985475 -408.454378)
			(xy 224.932691 -408.436371) (xy 224.883091 -408.41087) (xy 224.837733 -408.378419) (xy 224.797584 -408.33971)
			(xy 224.763498 -408.295567) (xy 224.736202 -408.246932) (xy 224.716279 -408.194841) (xy 224.704153 -408.140404)
			(xy 224.700082 -408.084782) (xy 224.323148 -408.084782) (xy 224.323148 -408.94508) (xy 224.32269 -408.965097)
			(xy 224.314875 -409.004359) (xy 224.299541 -409.041339) (xy 224.27728 -409.074612) (xy 224.263458 -409.089098)
			(xy 223.675956 -409.6766) (xy 223.661505 -409.690349) (xy 223.628341 -409.712499) (xy 223.591497 -409.727765)
			(xy 223.552386 -409.735561) (xy 223.532446 -409.736036) (xy 217.490294 -409.736036) (xy 217.470358 -409.735524)
			(xy 217.431255 -409.727717) (xy 217.394415 -409.712461) (xy 217.361241 -409.690337) (xy 217.346784 -409.6766)
			(xy 216.708482 -409.038298) (xy 216.694677 -409.0238) (xy 216.672433 -408.990522) (xy 216.6571 -408.953547)
			(xy 216.649265 -408.914293) (xy 216.648792 -408.89428) (xy 216.648792 -407.38806) (xy 216.649246 -407.368041)
			(xy 216.657052 -407.328773) (xy 216.672378 -407.291785) (xy 216.694631 -407.258502) (xy 216.708482 -407.244042)
			(xy 217.751914 -406.20061) (xy 217.756905 -406.195112) (xy 217.763756 -406.181947) (xy 217.765376 -406.174702)
			(xy 217.766392 -406.16505) (xy 217.766392 -403.519386) (xy 217.766138 -403.51583) (xy 217.764902 -403.505484)
			(xy 217.75533 -403.486999) (xy 217.747596 -403.480016) (xy 217.726856 -403.464591) (xy 217.68933 -403.429047)
			(xy 217.656946 -403.388762) (xy 217.630296 -403.344475) (xy 217.609869 -403.296995) (xy 217.596037 -403.247193)
			(xy 217.589055 -403.19598) (xy 217.588592 -403.170136) (xy 217.589098 -403.141567) (xy 217.597618 -403.085069)
			(xy 217.614473 -403.030475) (xy 217.626438 -403.004528) (xy 217.626438 -403.004274) (xy 217.629596 -402.997092)
			(xy 217.631801 -402.981569) (xy 217.630756 -402.973794) (xy 217.629486 -402.966174) (xy 217.622374 -402.952204)
			(xy 217.306398 -402.636482) (xy 216.97442 -402.304504) (xy 216.967621 -402.298218) (xy 216.950775 -402.290569)
			(xy 216.93231 -402.289413) (xy 216.923366 -402.291804) (xy 216.920572 -402.29282) (xy 216.834212 -402.325332)
			(xy 216.827475 -402.32819) (xy 216.815874 -402.337102) (xy 216.811352 -402.342858) (xy 216.807254 -402.348807)
			(xy 216.802236 -402.362347) (xy 216.801446 -402.369528) (xy 216.801446 -402.369782) (xy 216.799024 -402.398398)
			(xy 216.786669 -402.454481) (xy 216.766045 -402.508078) (xy 216.737618 -402.557977) (xy 216.702031 -402.60305)
			(xy 216.660089 -402.642277) (xy 216.612739 -402.674773) (xy 216.561053 -402.699803) (xy 216.506198 -402.7168)
			(xy 216.449414 -402.72538) (xy 216.4207 -402.72589) (xy 216.393448 -402.725427) (xy 216.339498 -402.71767)
			(xy 216.287201 -402.702313) (xy 216.237622 -402.679671) (xy 216.19177 -402.650202) (xy 216.150579 -402.614508)
			(xy 216.114887 -402.573316) (xy 216.085421 -402.527462) (xy 216.06278 -402.477882) (xy 216.047427 -402.425585)
			(xy 216.039672 -402.371634) (xy 216.039192 -402.344382) (xy 216.039681 -402.316777) (xy 216.04764 -402.262144)
			(xy 216.063388 -402.209228) (xy 216.086598 -402.159133) (xy 216.116785 -402.112907) (xy 216.153318 -402.071512)
			(xy 216.174066 -402.053298) (xy 216.182204 -402.045708) (xy 216.191568 -402.02555) (xy 216.1921 -402.014436)
			(xy 216.191687 -402.00441) (xy 216.184023 -401.985881) (xy 216.16985 -401.971697) (xy 216.151326 -401.96402)
			(xy 216.1413 -401.963636) (xy 216.06891 -401.963636) (xy 216.06129 -401.964144) (xy 216.053372 -401.965629)
			(xy 216.038994 -401.97288) (xy 216.033096 -401.978368) (xy 215.345518 -402.6662) (xy 215.331066 -402.679946)
			(xy 215.297901 -402.70209) (xy 215.261057 -402.717349) (xy 215.221947 -402.725138) (xy 215.202008 -402.725636)
			(xy 214.91829 -402.725636) (xy 214.908576 -402.726067) (xy 214.890539 -402.733287) (xy 214.876474 -402.74669)
			(xy 214.872062 -402.755354) (xy 214.833708 -402.839682) (xy 214.832946 -402.84146) (xy 214.829649 -402.850318)
			(xy 214.829181 -402.869201) (xy 214.83562 -402.886958) (xy 214.841582 -402.894292) (xy 214.859157 -402.915199)
			(xy 214.888769 -402.961092) (xy 214.911537 -403.010737) (xy 214.926994 -403.063121) (xy 214.934826 -403.117174)
			(xy 214.935308 -403.144482) (xy 214.934822 -403.171733) (xy 214.927066 -403.225681) (xy 214.911711 -403.277976)
			(xy 214.889069 -403.327553) (xy 214.859603 -403.373403) (xy 214.823912 -403.414594) (xy 214.782721 -403.450285)
			(xy 214.736871 -403.479751) (xy 214.687294 -403.502393) (xy 214.634999 -403.517748) (xy 214.581051 -403.525504)
			(xy 214.526549 -403.525504) (xy 214.472601 -403.517748) (xy 214.420306 -403.502393) (xy 214.370729 -403.479751)
			(xy 214.324879 -403.450285) (xy 214.283688 -403.414594) (xy 214.247997 -403.373403) (xy 214.218531 -403.327553)
			(xy 214.195889 -403.277976) (xy 214.180534 -403.225681) (xy 214.172778 -403.171733) (xy 214.172292 -403.144482)
			(xy 214.172763 -403.117149) (xy 214.18057 -403.063043) (xy 214.196022 -403.010605) (xy 214.218802 -402.960911)
			(xy 214.248444 -402.914979) (xy 214.266018 -402.894038) (xy 214.270653 -402.88831) (xy 214.276709 -402.874885)
			(xy 214.277956 -402.867622) (xy 214.278972 -402.860764) (xy 214.27694 -402.846794) (xy 214.270336 -402.832062)
			(xy 214.235538 -402.755354) (xy 214.23112 -402.746688) (xy 214.217066 -402.733264) (xy 214.199027 -402.726031)
			(xy 214.18931 -402.725636) (xy 213.962742 -402.725636) (xy 213.957916 -402.72589) (xy 213.949337 -402.727064)
			(xy 213.933637 -402.734341) (xy 213.927182 -402.740114) (xy 213.800436 -402.867114) (xy 213.66988 -402.99767)
			(xy 213.663193 -403.005079) (xy 213.655603 -403.023515) (xy 213.655148 -403.033484) (xy 213.655148 -408.084782)
			(xy 214.032082 -408.084782) (xy 214.036153 -408.02916) (xy 214.048279 -407.974723) (xy 214.068202 -407.922632)
			(xy 214.095498 -407.873997) (xy 214.129584 -407.829854) (xy 214.169733 -407.791145) (xy 214.215091 -407.758694)
			(xy 214.264691 -407.733193) (xy 214.317475 -407.715186) (xy 214.372318 -407.705056) (xy 214.428052 -407.703019)
			(xy 214.483489 -407.709119) (xy 214.537446 -407.723225) (xy 214.588775 -407.745037) (xy 214.636381 -407.774091)
			(xy 214.679249 -407.809766) (xy 214.716466 -407.851303) (xy 214.747239 -407.897816) (xy 214.770911 -407.948313)
			(xy 214.786979 -408.00172) (xy 214.795099 -408.056896) (xy 214.795608 -408.084782) (xy 214.795099 -408.112668)
			(xy 214.786979 -408.167844) (xy 214.770911 -408.221251) (xy 214.747239 -408.271748) (xy 214.716466 -408.318261)
			(xy 214.679249 -408.359798) (xy 214.636381 -408.395473) (xy 214.588775 -408.424527) (xy 214.537446 -408.446339)
			(xy 214.483489 -408.460445) (xy 214.428052 -408.466545) (xy 214.372318 -408.464508) (xy 214.317475 -408.454378)
			(xy 214.264691 -408.436371) (xy 214.215091 -408.41087) (xy 214.169733 -408.378419) (xy 214.129584 -408.33971)
			(xy 214.095498 -408.295567) (xy 214.068202 -408.246932) (xy 214.048279 -408.194841) (xy 214.036153 -408.140404)
			(xy 214.032082 -408.084782) (xy 213.655148 -408.084782) (xy 213.655148 -408.94508) (xy 213.65469 -408.965097)
			(xy 213.646875 -409.004359) (xy 213.631541 -409.041339) (xy 213.60928 -409.074612) (xy 213.595458 -409.089098)
			(xy 213.007956 -409.6766) (xy 212.993505 -409.690349) (xy 212.960341 -409.712499) (xy 212.923497 -409.727765)
			(xy 212.884386 -409.735561) (xy 212.864446 -409.736036) (xy 206.822294 -409.736036) (xy 206.802358 -409.735524)
			(xy 206.763255 -409.727717) (xy 206.726415 -409.712461) (xy 206.693241 -409.690337) (xy 206.678784 -409.6766)
			(xy 206.040482 -409.038298) (xy 206.03464 -409.032202) (xy 205.852522 -408.850338) (xy 205.838719 -408.835839)
			(xy 205.816481 -408.80256) (xy 205.801155 -408.765585) (xy 205.793331 -408.726332) (xy 205.792832 -408.70632)
			(xy 205.792832 -407.57602) (xy 205.79329 -407.556003) (xy 205.801105 -407.51674) (xy 205.816437 -407.479759)
			(xy 205.838697 -407.446485) (xy 205.852522 -407.432002) (xy 206.03464 -407.250138) (xy 206.040482 -407.244042)
			(xy 207.083914 -406.20061) (xy 207.088905 -406.195112) (xy 207.095756 -406.181947) (xy 207.097376 -406.174702)
			(xy 207.098392 -406.16505) (xy 207.098392 -403.519386) (xy 207.098138 -403.51583) (xy 207.096902 -403.505484)
			(xy 207.08733 -403.486999) (xy 207.079596 -403.480016) (xy 207.058856 -403.464591) (xy 207.02133 -403.429047)
			(xy 206.988946 -403.388762) (xy 206.962296 -403.344475) (xy 206.941869 -403.296995) (xy 206.928037 -403.247193)
			(xy 206.921055 -403.19598) (xy 206.920592 -403.170136) (xy 206.921098 -403.141567) (xy 206.929618 -403.085069)
			(xy 206.946473 -403.030475) (xy 206.958438 -403.004528) (xy 206.958438 -403.004274) (xy 206.961596 -402.997092)
			(xy 206.963801 -402.981569) (xy 206.962756 -402.973794) (xy 206.961486 -402.966174) (xy 206.954374 -402.952204)
			(xy 206.638398 -402.636482) (xy 206.30642 -402.304504) (xy 206.299621 -402.298218) (xy 206.282775 -402.290569)
			(xy 206.26431 -402.289413) (xy 206.255366 -402.291804) (xy 206.252572 -402.29282) (xy 206.166212 -402.325332)
			(xy 206.159475 -402.32819) (xy 206.147874 -402.337102) (xy 206.143352 -402.342858) (xy 206.139254 -402.348807)
			(xy 206.134236 -402.362347) (xy 206.133446 -402.369528) (xy 206.133446 -402.369782) (xy 206.131024 -402.398398)
			(xy 206.118669 -402.454481) (xy 206.098045 -402.508078) (xy 206.069618 -402.557977) (xy 206.034031 -402.60305)
			(xy 205.992089 -402.642277) (xy 205.944739 -402.674773) (xy 205.893053 -402.699803) (xy 205.838198 -402.7168)
			(xy 205.781414 -402.72538) (xy 205.7527 -402.72589) (xy 205.725448 -402.725427) (xy 205.671498 -402.71767)
			(xy 205.619201 -402.702313) (xy 205.569622 -402.679671) (xy 205.52377 -402.650202) (xy 205.482579 -402.614508)
			(xy 205.446887 -402.573316) (xy 205.417421 -402.527462) (xy 205.39478 -402.477882) (xy 205.379427 -402.425585)
			(xy 205.371672 -402.371634) (xy 205.371192 -402.344382) (xy 205.371681 -402.316777) (xy 205.37964 -402.262144)
			(xy 205.395388 -402.209228) (xy 205.418598 -402.159133) (xy 205.448785 -402.112907) (xy 205.485318 -402.071512)
			(xy 205.506066 -402.053298) (xy 205.514204 -402.045708) (xy 205.523568 -402.02555) (xy 205.5241 -402.014436)
			(xy 205.523687 -402.00441) (xy 205.516023 -401.985881) (xy 205.50185 -401.971697) (xy 205.483326 -401.96402)
			(xy 205.4733 -401.963636) (xy 205.40091 -401.963636) (xy 205.39329 -401.964144) (xy 205.385372 -401.965629)
			(xy 205.370994 -401.97288) (xy 205.365096 -401.978368) (xy 204.677518 -402.6662) (xy 204.663066 -402.679946)
			(xy 204.629901 -402.70209) (xy 204.593057 -402.717349) (xy 204.553947 -402.725138) (xy 204.534008 -402.725636)
			(xy 204.25029 -402.725636) (xy 204.240576 -402.726067) (xy 204.222539 -402.733287) (xy 204.208474 -402.74669)
			(xy 204.204062 -402.755354) (xy 204.165708 -402.839682) (xy 204.164946 -402.84146) (xy 204.161649 -402.850318)
			(xy 204.161181 -402.869201) (xy 204.16762 -402.886958) (xy 204.173582 -402.894292) (xy 204.191157 -402.915199)
			(xy 204.220769 -402.961092) (xy 204.243537 -403.010737) (xy 204.258994 -403.063121) (xy 204.266826 -403.117174)
			(xy 204.267308 -403.144482) (xy 204.266822 -403.171733) (xy 204.259066 -403.225681) (xy 204.243711 -403.277976)
			(xy 204.221069 -403.327553) (xy 204.191603 -403.373403) (xy 204.155912 -403.414594) (xy 204.114721 -403.450285)
			(xy 204.068871 -403.479751) (xy 204.019294 -403.502393) (xy 203.966999 -403.517748) (xy 203.913051 -403.525504)
			(xy 203.858549 -403.525504) (xy 203.804601 -403.517748) (xy 203.752306 -403.502393) (xy 203.702729 -403.479751)
			(xy 203.656879 -403.450285) (xy 203.615688 -403.414594) (xy 203.579997 -403.373403) (xy 203.550531 -403.327553)
			(xy 203.527889 -403.277976) (xy 203.512534 -403.225681) (xy 203.504778 -403.171733) (xy 203.504292 -403.144482)
			(xy 203.504763 -403.117149) (xy 203.51257 -403.063043) (xy 203.528022 -403.010605) (xy 203.550802 -402.960911)
			(xy 203.580444 -402.914979) (xy 203.598018 -402.894038) (xy 203.602653 -402.88831) (xy 203.608709 -402.874885)
			(xy 203.609956 -402.867622) (xy 203.610972 -402.860764) (xy 203.60894 -402.846794) (xy 203.602336 -402.832062)
			(xy 203.567538 -402.755354) (xy 203.56312 -402.746688) (xy 203.549066 -402.733264) (xy 203.531027 -402.726031)
			(xy 203.52131 -402.725636) (xy 203.294742 -402.725636) (xy 203.289916 -402.72589) (xy 203.281337 -402.727064)
			(xy 203.265637 -402.734341) (xy 203.259182 -402.740114) (xy 203.132436 -402.867114) (xy 203.00188 -402.99767)
			(xy 202.995193 -403.005079) (xy 202.987603 -403.023515) (xy 202.987148 -403.033484) (xy 202.987148 -408.084782)
			(xy 203.364082 -408.084782) (xy 203.368153 -408.02916) (xy 203.380279 -407.974723) (xy 203.400202 -407.922632)
			(xy 203.427498 -407.873997) (xy 203.461584 -407.829854) (xy 203.501733 -407.791145) (xy 203.547091 -407.758694)
			(xy 203.596691 -407.733193) (xy 203.649475 -407.715186) (xy 203.704318 -407.705056) (xy 203.760052 -407.703019)
			(xy 203.815489 -407.709119) (xy 203.869446 -407.723225) (xy 203.920775 -407.745037) (xy 203.968381 -407.774091)
			(xy 204.011249 -407.809766) (xy 204.048466 -407.851303) (xy 204.079239 -407.897816) (xy 204.102911 -407.948313)
			(xy 204.118979 -408.00172) (xy 204.127099 -408.056896) (xy 204.127608 -408.084782) (xy 204.127099 -408.112668)
			(xy 204.118979 -408.167844) (xy 204.102911 -408.221251) (xy 204.079239 -408.271748) (xy 204.048466 -408.318261)
			(xy 204.011249 -408.359798) (xy 203.968381 -408.395473) (xy 203.920775 -408.424527) (xy 203.869446 -408.446339)
			(xy 203.815489 -408.460445) (xy 203.760052 -408.466545) (xy 203.704318 -408.464508) (xy 203.649475 -408.454378)
			(xy 203.596691 -408.436371) (xy 203.547091 -408.41087) (xy 203.501733 -408.378419) (xy 203.461584 -408.33971)
			(xy 203.427498 -408.295567) (xy 203.400202 -408.246932) (xy 203.380279 -408.194841) (xy 203.368153 -408.140404)
			(xy 203.364082 -408.084782) (xy 202.987148 -408.084782) (xy 202.987148 -408.94508) (xy 202.98669 -408.965097)
			(xy 202.978875 -409.004359) (xy 202.963541 -409.041339) (xy 202.94128 -409.074612) (xy 202.927458 -409.089098)
			(xy 202.339956 -409.6766) (xy 202.325505 -409.690349) (xy 202.292341 -409.712499) (xy 202.255497 -409.727765)
			(xy 202.216386 -409.735561) (xy 202.196446 -409.736036) (xy 196.154294 -409.736036) (xy 196.134358 -409.735524)
			(xy 196.095255 -409.727717) (xy 196.058415 -409.712461) (xy 196.025241 -409.690337) (xy 196.010784 -409.6766)
			(xy 195.372482 -409.038298) (xy 195.358677 -409.0238) (xy 195.336433 -408.990522) (xy 195.3211 -408.953547)
			(xy 195.313265 -408.914293) (xy 195.312792 -408.89428) (xy 195.312792 -405.02586) (xy 195.313246 -405.005841)
			(xy 195.321052 -404.966573) (xy 195.336378 -404.929585) (xy 195.358631 -404.896302) (xy 195.372482 -404.881842)
			(xy 196.484494 -403.76983) (xy 196.489477 -403.764329) (xy 196.496311 -403.751161) (xy 196.497956 -403.743922)
			(xy 196.498972 -403.73427) (xy 196.498972 -403.519386) (xy 196.498718 -403.51583) (xy 196.497481 -403.505485)
			(xy 196.487906 -403.487002) (xy 196.480176 -403.480016) (xy 196.458272 -403.463682) (xy 196.418877 -403.425819)
			(xy 196.40169 -403.404578) (xy 196.401436 -403.404324) (xy 196.397935 -403.400077) (xy 196.389477 -403.393038)
			(xy 196.384672 -403.390354) (xy 196.375782 -403.385782) (xy 196.325998 -403.382988) (xy 196.287644 -403.380956)
			(xy 196.282124 -403.380788) (xy 196.271228 -403.382579) (xy 196.266054 -403.384512) (xy 196.256148 -403.388576)
			(xy 196.248528 -403.39645) (xy 196.230477 -403.414576) (xy 196.190369 -403.446328) (xy 196.146381 -403.472442)
			(xy 196.099302 -403.492451) (xy 196.049973 -403.505998) (xy 195.999277 -403.512839) (xy 195.9737 -403.51329)
			(xy 195.95878 -403.513166) (xy 195.929027 -403.510879) (xy 195.914264 -403.508718) (xy 195.901818 -403.506686)
			(xy 195.890896 -403.510242) (xy 195.885284 -403.512274) (xy 195.875142 -403.518561) (xy 195.87083 -403.522688)
			(xy 194.61734 -404.775924) (xy 194.612268 -404.781392) (xy 194.60529 -404.794563) (xy 194.603624 -404.801832)
			(xy 194.602608 -404.811738) (xy 194.602608 -409.80995) (xy 194.602862 -409.814776) (xy 194.604024 -409.823173)
			(xy 194.611023 -409.838599) (xy 194.616578 -409.845002) (xy 194.758056 -409.986226) (xy 194.90309 -410.13126)
			(xy 194.910497 -410.13795) (xy 194.928934 -410.145542) (xy 194.938904 -410.145992) (xy 204.69479 -410.145992)
			(xy 204.703307 -410.145674) (xy 204.719404 -410.140097) (xy 204.726286 -410.13507) (xy 204.728572 -410.132784)
			(xy 204.736192 -410.114242) (xy 204.736192 -405.595328) (xy 204.736649 -405.575311) (xy 204.744461 -405.536045)
			(xy 204.75979 -405.499062) (xy 204.782046 -405.465783) (xy 204.795882 -405.45131) (xy 206.123286 -404.123906)
			(xy 206.127461 -404.119557) (xy 206.133768 -404.109285) (xy 206.135732 -404.103586) (xy 206.139288 -404.092156)
			(xy 206.13751 -404.080218) (xy 206.135347 -404.065455) (xy 206.133057 -404.035702) (xy 206.132938 -404.020782)
			(xy 206.133425 -403.993535) (xy 206.141183 -403.939596) (xy 206.156538 -403.88731) (xy 206.179177 -403.837741)
			(xy 206.20864 -403.791899) (xy 206.244326 -403.750716) (xy 206.285511 -403.715031) (xy 206.331354 -403.68557)
			(xy 206.380924 -403.662932) (xy 206.43321 -403.64758) (xy 206.48715 -403.639824) (xy 206.541644 -403.639824)
			(xy 206.595583 -403.647578) (xy 206.64787 -403.66293) (xy 206.69744 -403.685567) (xy 206.743284 -403.715027)
			(xy 206.784469 -403.750711) (xy 206.820156 -403.791894) (xy 206.84962 -403.837736) (xy 206.87226 -403.887304)
			(xy 206.887616 -403.93959) (xy 206.895374 -403.993528) (xy 206.895378 -404.048022) (xy 206.887626 -404.101962)
			(xy 206.872277 -404.15425) (xy 206.849644 -404.203821) (xy 206.820186 -404.249667) (xy 206.784504 -404.290854)
			(xy 206.743323 -404.326544) (xy 206.697483 -404.35601) (xy 206.647916 -404.378653) (xy 206.595631 -404.394011)
			(xy 206.541693 -404.401773) (xy 206.514446 -404.40229) (xy 206.499526 -404.402164) (xy 206.469774 -404.399873)
			(xy 206.45501 -404.397718) (xy 206.443072 -404.39594) (xy 206.431642 -404.399496) (xy 206.425982 -404.401544)
			(xy 206.415723 -404.407834) (xy 206.411322 -404.411942) (xy 205.15834 -405.664924) (xy 205.155635 -405.667776)
			(xy 205.151044 -405.674155) (xy 205.149196 -405.677624) (xy 205.146611 -405.68305) (xy 205.143783 -405.69473)
			(xy 205.143608 -405.700738) (xy 205.143608 -406.052782) (xy 205.396082 -406.052782) (xy 205.400153 -405.99716)
			(xy 205.412279 -405.942723) (xy 205.432202 -405.890632) (xy 205.459498 -405.841997) (xy 205.493584 -405.797854)
			(xy 205.533733 -405.759145) (xy 205.579091 -405.726694) (xy 205.628691 -405.701193) (xy 205.681475 -405.683186)
			(xy 205.736318 -405.673056) (xy 205.792052 -405.671019) (xy 205.847489 -405.677119) (xy 205.901446 -405.691225)
			(xy 205.952775 -405.713037) (xy 206.000381 -405.742091) (xy 206.043249 -405.777766) (xy 206.080466 -405.819303)
			(xy 206.111239 -405.865816) (xy 206.134911 -405.916313) (xy 206.150979 -405.96972) (xy 206.159099 -406.024896)
			(xy 206.159608 -406.052782) (xy 206.159099 -406.080668) (xy 206.150979 -406.135844) (xy 206.134911 -406.189251)
			(xy 206.111239 -406.239748) (xy 206.080466 -406.286261) (xy 206.043249 -406.327798) (xy 206.000381 -406.363473)
			(xy 205.952775 -406.392527) (xy 205.901446 -406.414339) (xy 205.847489 -406.428445) (xy 205.792052 -406.434545)
			(xy 205.736318 -406.432508) (xy 205.681475 -406.422378) (xy 205.628691 -406.404371) (xy 205.579091 -406.37887)
			(xy 205.533733 -406.346419) (xy 205.493584 -406.30771) (xy 205.459498 -406.263567) (xy 205.432202 -406.214932)
			(xy 205.412279 -406.162841) (xy 205.400153 -406.108404) (xy 205.396082 -406.052782) (xy 205.143608 -406.052782)
			(xy 205.143608 -410.10459) (xy 205.143926 -410.113107) (xy 205.149503 -410.129204) (xy 205.15453 -410.136086)
			(xy 205.156816 -410.138372) (xy 205.175358 -410.145992) (xy 215.36279 -410.145992) (xy 215.371307 -410.145674)
			(xy 215.387404 -410.140097) (xy 215.394286 -410.13507) (xy 215.396572 -410.132784) (xy 215.404192 -410.114242)
			(xy 215.404192 -405.595328) (xy 215.404649 -405.575311) (xy 215.412461 -405.536045) (xy 215.42779 -405.499062)
			(xy 215.450046 -405.465783) (xy 215.463882 -405.45131) (xy 216.791286 -404.123906) (xy 216.795461 -404.119557)
			(xy 216.801768 -404.109285) (xy 216.803732 -404.103586) (xy 216.807288 -404.092156) (xy 216.80551 -404.080218)
			(xy 216.803347 -404.065455) (xy 216.801057 -404.035702) (xy 216.800938 -404.020782) (xy 216.801425 -403.993535)
			(xy 216.809183 -403.939596) (xy 216.824538 -403.88731) (xy 216.847177 -403.837741) (xy 216.87664 -403.791899)
			(xy 216.912326 -403.750716) (xy 216.953511 -403.715031) (xy 216.999354 -403.68557) (xy 217.048924 -403.662932)
			(xy 217.10121 -403.64758) (xy 217.15515 -403.639824) (xy 217.209644 -403.639824) (xy 217.263583 -403.647578)
			(xy 217.31587 -403.66293) (xy 217.36544 -403.685567) (xy 217.411284 -403.715027) (xy 217.452469 -403.750711)
			(xy 217.488156 -403.791894) (xy 217.51762 -403.837736) (xy 217.54026 -403.887304) (xy 217.555616 -403.93959)
			(xy 217.563374 -403.993528) (xy 217.563378 -404.048022) (xy 217.555626 -404.101962) (xy 217.540277 -404.15425)
			(xy 217.517644 -404.203821) (xy 217.488186 -404.249667) (xy 217.452504 -404.290854) (xy 217.411323 -404.326544)
			(xy 217.365483 -404.35601) (xy 217.315916 -404.378653) (xy 217.263631 -404.394011) (xy 217.209693 -404.401773)
			(xy 217.182446 -404.40229) (xy 217.167526 -404.402164) (xy 217.137774 -404.399873) (xy 217.12301 -404.397718)
			(xy 217.111072 -404.39594) (xy 217.099642 -404.399496) (xy 217.093982 -404.401544) (xy 217.083723 -404.407834)
			(xy 217.079322 -404.411942) (xy 215.82634 -405.664924) (xy 215.823635 -405.667776) (xy 215.819044 -405.674155)
			(xy 215.817196 -405.677624) (xy 215.814611 -405.68305) (xy 215.811783 -405.69473) (xy 215.811608 -405.700738)
			(xy 215.811608 -406.052782) (xy 216.064082 -406.052782) (xy 216.068153 -405.99716) (xy 216.080279 -405.942723)
			(xy 216.100202 -405.890632) (xy 216.127498 -405.841997) (xy 216.161584 -405.797854) (xy 216.201733 -405.759145)
			(xy 216.247091 -405.726694) (xy 216.296691 -405.701193) (xy 216.349475 -405.683186) (xy 216.404318 -405.673056)
			(xy 216.460052 -405.671019) (xy 216.515489 -405.677119) (xy 216.569446 -405.691225) (xy 216.620775 -405.713037)
			(xy 216.668381 -405.742091) (xy 216.711249 -405.777766) (xy 216.748466 -405.819303) (xy 216.779239 -405.865816)
			(xy 216.802911 -405.916313) (xy 216.818979 -405.96972) (xy 216.827099 -406.024896) (xy 216.827608 -406.052782)
			(xy 216.827099 -406.080668) (xy 216.818979 -406.135844) (xy 216.802911 -406.189251) (xy 216.779239 -406.239748)
			(xy 216.748466 -406.286261) (xy 216.711249 -406.327798) (xy 216.668381 -406.363473) (xy 216.620775 -406.392527)
			(xy 216.569446 -406.414339) (xy 216.515489 -406.428445) (xy 216.460052 -406.434545) (xy 216.404318 -406.432508)
			(xy 216.349475 -406.422378) (xy 216.296691 -406.404371) (xy 216.247091 -406.37887) (xy 216.201733 -406.346419)
			(xy 216.161584 -406.30771) (xy 216.127498 -406.263567) (xy 216.100202 -406.214932) (xy 216.080279 -406.162841)
			(xy 216.068153 -406.108404) (xy 216.064082 -406.052782) (xy 215.811608 -406.052782) (xy 215.811608 -410.10459)
			(xy 215.811926 -410.113107) (xy 215.817503 -410.129204) (xy 215.82253 -410.136086) (xy 215.824816 -410.138372)
			(xy 215.843358 -410.145992) (xy 226.03079 -410.145992) (xy 226.039307 -410.145674) (xy 226.055404 -410.140097)
			(xy 226.062286 -410.13507) (xy 226.064572 -410.132784) (xy 226.072192 -410.114242) (xy 226.072192 -405.595328)
			(xy 226.072649 -405.575311) (xy 226.080461 -405.536045) (xy 226.09579 -405.499062) (xy 226.118046 -405.465783)
			(xy 226.131882 -405.45131) (xy 227.459286 -404.123906) (xy 227.463461 -404.119557) (xy 227.469768 -404.109285)
			(xy 227.471732 -404.103586) (xy 227.475288 -404.092156) (xy 227.47351 -404.080218) (xy 227.471347 -404.065455)
			(xy 227.469057 -404.035702) (xy 227.468938 -404.020782) (xy 227.469425 -403.993535) (xy 227.477183 -403.939596)
			(xy 227.492538 -403.88731) (xy 227.515177 -403.837741) (xy 227.54464 -403.791899) (xy 227.580326 -403.750716)
			(xy 227.621511 -403.715031) (xy 227.667354 -403.68557) (xy 227.716924 -403.662932) (xy 227.76921 -403.64758)
			(xy 227.82315 -403.639824) (xy 227.877644 -403.639824) (xy 227.931583 -403.647578) (xy 227.98387 -403.66293)
			(xy 228.03344 -403.685567) (xy 228.079284 -403.715027) (xy 228.120469 -403.750711) (xy 228.156156 -403.791894)
			(xy 228.18562 -403.837736) (xy 228.20826 -403.887304) (xy 228.223616 -403.93959) (xy 228.231374 -403.993528)
			(xy 228.231378 -404.048022) (xy 228.223626 -404.101962) (xy 228.208277 -404.15425) (xy 228.185644 -404.203821)
			(xy 228.156186 -404.249667) (xy 228.120504 -404.290854) (xy 228.079323 -404.326544) (xy 228.033483 -404.35601)
			(xy 227.983916 -404.378653) (xy 227.931631 -404.394011) (xy 227.877693 -404.401773) (xy 227.850446 -404.40229)
			(xy 227.835526 -404.402164) (xy 227.805774 -404.399873) (xy 227.79101 -404.397718) (xy 227.779072 -404.39594)
			(xy 227.767642 -404.399496) (xy 227.761982 -404.401544) (xy 227.751723 -404.407834) (xy 227.747322 -404.411942)
			(xy 226.49434 -405.664924) (xy 226.491635 -405.667776) (xy 226.487044 -405.674155) (xy 226.485196 -405.677624)
			(xy 226.482611 -405.68305) (xy 226.479783 -405.69473) (xy 226.479608 -405.700738) (xy 226.479608 -406.052782)
			(xy 226.732082 -406.052782) (xy 226.736153 -405.99716) (xy 226.748279 -405.942723) (xy 226.768202 -405.890632)
			(xy 226.795498 -405.841997) (xy 226.829584 -405.797854) (xy 226.869733 -405.759145) (xy 226.915091 -405.726694)
			(xy 226.964691 -405.701193) (xy 227.017475 -405.683186) (xy 227.072318 -405.673056) (xy 227.128052 -405.671019)
			(xy 227.183489 -405.677119) (xy 227.237446 -405.691225) (xy 227.288775 -405.713037) (xy 227.336381 -405.742091)
			(xy 227.379249 -405.777766) (xy 227.416466 -405.819303) (xy 227.447239 -405.865816) (xy 227.470911 -405.916313)
			(xy 227.486979 -405.96972) (xy 227.495099 -406.024896) (xy 227.495608 -406.052782) (xy 227.495099 -406.080668)
			(xy 227.486979 -406.135844) (xy 227.470911 -406.189251) (xy 227.447239 -406.239748) (xy 227.416466 -406.286261)
			(xy 227.379249 -406.327798) (xy 227.336381 -406.363473) (xy 227.288775 -406.392527) (xy 227.237446 -406.414339)
			(xy 227.183489 -406.428445) (xy 227.128052 -406.434545) (xy 227.072318 -406.432508) (xy 227.017475 -406.422378)
			(xy 226.964691 -406.404371) (xy 226.915091 -406.37887) (xy 226.869733 -406.346419) (xy 226.829584 -406.30771)
			(xy 226.795498 -406.263567) (xy 226.768202 -406.214932) (xy 226.748279 -406.162841) (xy 226.736153 -406.108404)
			(xy 226.732082 -406.052782) (xy 226.479608 -406.052782) (xy 226.479608 -408.086653) (xy 228.10466 -408.086653)
			(xy 228.10466 -408.032147) (xy 228.112417 -407.978197) (xy 228.127773 -407.9259) (xy 228.150415 -407.87632)
			(xy 228.179882 -407.830468) (xy 228.215576 -407.789276) (xy 228.256768 -407.753582) (xy 228.30262 -407.724115)
			(xy 228.3522 -407.701473) (xy 228.404497 -407.686117) (xy 228.458447 -407.67836) (xy 228.4857 -407.677874)
			(xy 228.514618 -407.678364) (xy 228.571792 -407.687095) (xy 228.626993 -407.704357) (xy 228.678955 -407.729754)
			(xy 228.726488 -407.762703) (xy 228.768502 -407.802451) (xy 228.78669 -407.82494) (xy 228.794305 -407.833739)
			(xy 228.8152 -407.843926) (xy 228.826822 -407.844498) (xy 228.906578 -407.844498) (xy 228.918207 -407.843932)
			(xy 228.939116 -407.833762) (xy 228.94671 -407.82494) (xy 228.961486 -407.806539) (xy 228.994858 -407.77317)
			(xy 229.013258 -407.758392) (xy 229.022069 -407.750789) (xy 229.032248 -407.729885) (xy 229.032816 -407.71826)
			(xy 229.032816 -407.638504) (xy 229.032255 -407.626875) (xy 229.022081 -407.605966) (xy 229.013258 -407.598372)
			(xy 228.990752 -407.580207) (xy 228.95102 -407.538181) (xy 228.918085 -407.49064) (xy 228.892701 -407.438674)
			(xy 228.875449 -407.383472) (xy 228.866725 -407.326299) (xy 228.866192 -407.297382) (xy 228.866661 -407.27013)
			(xy 228.87442 -407.216182) (xy 228.889777 -407.163887) (xy 228.912421 -407.11431) (xy 228.941889 -407.068459)
			(xy 228.977582 -407.027269) (xy 229.018774 -406.991578) (xy 229.064625 -406.962112) (xy 229.114204 -406.939471)
			(xy 229.1665 -406.924116) (xy 229.220448 -406.91636) (xy 229.2477 -406.915874) (xy 229.276618 -406.916364)
			(xy 229.333792 -406.925095) (xy 229.388993 -406.942357) (xy 229.440955 -406.967754) (xy 229.488488 -407.000703)
			(xy 229.530502 -407.040451) (xy 229.54869 -407.06294) (xy 229.556305 -407.071739) (xy 229.5772 -407.081926)
			(xy 229.588822 -407.082498) (xy 229.668578 -407.082498) (xy 229.680207 -407.081932) (xy 229.701116 -407.071762)
			(xy 229.70871 -407.06294) (xy 229.723486 -407.044539) (xy 229.756858 -407.01117) (xy 229.775258 -406.996392)
			(xy 229.784069 -406.988789) (xy 229.794248 -406.967885) (xy 229.794816 -406.95626) (xy 229.794816 -406.876504)
			(xy 229.794255 -406.864875) (xy 229.784081 -406.843966) (xy 229.775258 -406.836372) (xy 229.754457 -406.81964)
			(xy 229.717327 -406.781284) (xy 229.685905 -406.738127) (xy 229.660807 -406.691011) (xy 229.642521 -406.640856)
			(xy 229.631406 -406.588642) (xy 229.627678 -406.535389) (xy 229.631409 -406.482136) (xy 229.642528 -406.429922)
			(xy 229.660816 -406.379769) (xy 229.685917 -406.332654) (xy 229.717341 -406.289499) (xy 229.754474 -406.251145)
			(xy 229.775258 -406.234392) (xy 229.784069 -406.226789) (xy 229.794248 -406.205885) (xy 229.794816 -406.19426)
			(xy 229.794816 -406.114504) (xy 229.794255 -406.102875) (xy 229.784081 -406.081966) (xy 229.775258 -406.074372)
			(xy 229.754457 -406.05764) (xy 229.717327 -406.019284) (xy 229.685905 -405.976127) (xy 229.660807 -405.929011)
			(xy 229.642521 -405.878856) (xy 229.631406 -405.826642) (xy 229.627678 -405.773389) (xy 229.631409 -405.720136)
			(xy 229.642528 -405.667922) (xy 229.660816 -405.617769) (xy 229.685917 -405.570654) (xy 229.717341 -405.527499)
			(xy 229.754474 -405.489145) (xy 229.775258 -405.472392) (xy 229.784069 -405.464789) (xy 229.794248 -405.443885)
			(xy 229.794816 -405.43226) (xy 229.794816 -405.352504) (xy 229.794255 -405.340875) (xy 229.784081 -405.319966)
			(xy 229.775258 -405.312372) (xy 229.752752 -405.294207) (xy 229.71302 -405.252181) (xy 229.680085 -405.20464)
			(xy 229.654701 -405.152674) (xy 229.637449 -405.097472) (xy 229.628725 -405.040299) (xy 229.628192 -405.011382)
			(xy 229.628661 -404.98413) (xy 229.63642 -404.930182) (xy 229.651777 -404.877887) (xy 229.674421 -404.82831)
			(xy 229.703889 -404.782459) (xy 229.739582 -404.741269) (xy 229.780774 -404.705578) (xy 229.826625 -404.676112)
			(xy 229.876204 -404.653471) (xy 229.9285 -404.638116) (xy 229.982448 -404.63036) (xy 230.0097 -404.629874)
			(xy 230.038618 -404.630364) (xy 230.095792 -404.639095) (xy 230.150993 -404.656357) (xy 230.202955 -404.681754)
			(xy 230.250488 -404.714703) (xy 230.292502 -404.754451) (xy 230.31069 -404.77694) (xy 230.318305 -404.785739)
			(xy 230.3392 -404.795926) (xy 230.350822 -404.796498) (xy 230.430578 -404.796498) (xy 230.442207 -404.795932)
			(xy 230.463116 -404.785762) (xy 230.47071 -404.77694) (xy 230.487463 -404.756157) (xy 230.525817 -404.719027)
			(xy 230.568971 -404.687605) (xy 230.616085 -404.662506) (xy 230.666237 -404.64422) (xy 230.718448 -404.633103)
			(xy 230.7717 -404.629373) (xy 230.824952 -404.633103) (xy 230.877163 -404.64422) (xy 230.927315 -404.662506)
			(xy 230.974429 -404.687605) (xy 231.017583 -404.719027) (xy 231.055937 -404.756157) (xy 231.07269 -404.77694)
			(xy 231.080305 -404.785739) (xy 231.1012 -404.795926) (xy 231.112822 -404.796498) (xy 231.192578 -404.796498)
			(xy 231.204207 -404.795932) (xy 231.225116 -404.785762) (xy 231.23271 -404.77694) (xy 231.249463 -404.756157)
			(xy 231.287817 -404.719027) (xy 231.330971 -404.687605) (xy 231.378085 -404.662506) (xy 231.428237 -404.64422)
			(xy 231.480448 -404.633103) (xy 231.5337 -404.629373) (xy 231.586952 -404.633103) (xy 231.639163 -404.64422)
			(xy 231.689315 -404.662506) (xy 231.736429 -404.687605) (xy 231.779583 -404.719027) (xy 231.817937 -404.756157)
			(xy 231.83469 -404.77694) (xy 231.842305 -404.785739) (xy 231.8632 -404.795926) (xy 231.874822 -404.796498)
			(xy 231.954578 -404.796498) (xy 231.966207 -404.795932) (xy 231.987116 -404.785762) (xy 231.99471 -404.77694)
			(xy 232.011463 -404.756157) (xy 232.049817 -404.719027) (xy 232.092971 -404.687605) (xy 232.140085 -404.662506)
			(xy 232.190237 -404.64422) (xy 232.242448 -404.633103) (xy 232.2957 -404.629373) (xy 232.348952 -404.633103)
			(xy 232.401163 -404.64422) (xy 232.451315 -404.662506) (xy 232.498429 -404.687605) (xy 232.541583 -404.719027)
			(xy 232.579937 -404.756157) (xy 232.59669 -404.77694) (xy 232.604305 -404.785739) (xy 232.6252 -404.795926)
			(xy 232.636822 -404.796498) (xy 232.716578 -404.796498) (xy 232.728207 -404.795932) (xy 232.749116 -404.785762)
			(xy 232.75671 -404.77694) (xy 232.774905 -404.75446) (xy 232.816923 -404.714723) (xy 232.864457 -404.681782)
			(xy 232.916417 -404.656393) (xy 232.971615 -404.639136) (xy 233.028784 -404.630408) (xy 233.0577 -404.629874)
			(xy 233.08495 -404.630378) (xy 233.138897 -404.638134) (xy 233.19119 -404.653488) (xy 233.240766 -404.676128)
			(xy 233.286615 -404.705592) (xy 233.327805 -404.741282) (xy 233.363497 -404.78247) (xy 233.392964 -404.828318)
			(xy 233.415606 -404.877893) (xy 233.430962 -404.930186) (xy 233.438721 -404.984132) (xy 233.439208 -405.011382)
			(xy 233.438712 -405.0403) (xy 233.429983 -405.097474) (xy 233.412723 -405.152675) (xy 233.387327 -405.204637)
			(xy 233.354378 -405.25217) (xy 233.314631 -405.294184) (xy 233.292142 -405.312372) (xy 233.283348 -405.319991)
			(xy 233.273159 -405.340883) (xy 233.272584 -405.352504) (xy 233.272584 -405.43226) (xy 233.273109 -405.443893)
			(xy 233.283308 -405.464802) (xy 233.292142 -405.472392) (xy 233.312907 -405.489167) (xy 233.350037 -405.527517)
			(xy 233.381459 -405.570669) (xy 233.406558 -405.61778) (xy 233.424845 -405.66793) (xy 233.435963 -405.72014)
			(xy 233.439694 -405.773389) (xy 233.435966 -405.826639) (xy 233.424851 -405.878849) (xy 233.406567 -405.928999)
			(xy 233.38147 -405.976112) (xy 233.350052 -406.019266) (xy 233.312924 -406.057619) (xy 233.292142 -406.074372)
			(xy 233.283348 -406.081991) (xy 233.273159 -406.102883) (xy 233.272584 -406.114504) (xy 233.272584 -406.19426)
			(xy 233.273109 -406.205893) (xy 233.283308 -406.226802) (xy 233.292142 -406.234392) (xy 233.312907 -406.251167)
			(xy 233.350037 -406.289517) (xy 233.381459 -406.332669) (xy 233.406558 -406.37978) (xy 233.424845 -406.42993)
			(xy 233.435963 -406.48214) (xy 233.439694 -406.535389) (xy 233.435966 -406.588639) (xy 233.424851 -406.640849)
			(xy 233.406567 -406.690999) (xy 233.38147 -406.738112) (xy 233.350052 -406.781266) (xy 233.312924 -406.819619)
			(xy 233.292142 -406.836372) (xy 233.283348 -406.843991) (xy 233.273159 -406.864883) (xy 233.272584 -406.876504)
			(xy 233.272584 -406.95626) (xy 233.273109 -406.967893) (xy 233.283308 -406.988802) (xy 233.292142 -406.996392)
			(xy 233.31054 -407.011172) (xy 233.343911 -407.044541) (xy 233.35869 -407.06294) (xy 233.366305 -407.071739)
			(xy 233.3872 -407.081926) (xy 233.398822 -407.082498) (xy 233.478578 -407.082498) (xy 233.490207 -407.081932)
			(xy 233.511116 -407.071762) (xy 233.51871 -407.06294) (xy 233.536905 -407.04046) (xy 233.578923 -407.000723)
			(xy 233.626457 -406.967782) (xy 233.678417 -406.942393) (xy 233.733615 -406.925136) (xy 233.790784 -406.916408)
			(xy 233.8197 -406.915874) (xy 233.84695 -406.916378) (xy 233.900897 -406.924134) (xy 233.95319 -406.939488)
			(xy 234.002766 -406.962128) (xy 234.048615 -406.991592) (xy 234.089805 -407.027282) (xy 234.125497 -407.06847)
			(xy 234.154964 -407.114318) (xy 234.177606 -407.163893) (xy 234.192962 -407.216186) (xy 234.200721 -407.270132)
			(xy 234.201208 -407.297382) (xy 234.200712 -407.3263) (xy 234.191983 -407.383474) (xy 234.174723 -407.438675)
			(xy 234.149327 -407.490637) (xy 234.116378 -407.53817) (xy 234.076631 -407.580184) (xy 234.054142 -407.598372)
			(xy 234.045348 -407.605991) (xy 234.035159 -407.626883) (xy 234.034584 -407.638504) (xy 234.034584 -407.71826)
			(xy 234.035109 -407.729893) (xy 234.045308 -407.750802) (xy 234.054142 -407.758392) (xy 234.07663 -407.776577)
			(xy 234.116363 -407.818599) (xy 234.149301 -407.866136) (xy 234.174688 -407.918098) (xy 234.191943 -407.973296)
			(xy 234.200673 -408.030466) (xy 234.201208 -408.059382) (xy 234.200728 -408.086634) (xy 234.192973 -408.140585)
			(xy 234.17762 -408.192882) (xy 234.154979 -408.242462) (xy 234.125513 -408.288316) (xy 234.089821 -408.329508)
			(xy 234.04863 -408.365202) (xy 234.002778 -408.394671) (xy 233.953199 -408.417313) (xy 233.900902 -408.43267)
			(xy 233.846952 -408.440427) (xy 233.8197 -408.44089) (xy 233.790783 -408.440375) (xy 233.733611 -408.431646)
			(xy 233.678412 -408.414388) (xy 233.626451 -408.388995) (xy 233.578917 -408.356051) (xy 233.5369 -408.31631)
			(xy 233.51871 -408.293824) (xy 233.511102 -408.285019) (xy 233.490201 -408.274837) (xy 233.478578 -408.274266)
			(xy 233.398822 -408.274266) (xy 233.38719 -408.274809) (xy 233.366279 -408.284993) (xy 233.35869 -408.293824)
			(xy 233.341937 -408.314607) (xy 233.303583 -408.351737) (xy 233.260429 -408.383159) (xy 233.213315 -408.408258)
			(xy 233.163163 -408.426544) (xy 233.110952 -408.437661) (xy 233.0577 -408.441391) (xy 233.004448 -408.437661)
			(xy 232.952237 -408.426544) (xy 232.902085 -408.408258) (xy 232.854971 -408.383159) (xy 232.811817 -408.351737)
			(xy 232.773463 -408.314607) (xy 232.75671 -408.293824) (xy 232.749102 -408.285019) (xy 232.728201 -408.274837)
			(xy 232.716578 -408.274266) (xy 232.636822 -408.274266) (xy 232.62519 -408.274809) (xy 232.604279 -408.284993)
			(xy 232.59669 -408.293824) (xy 232.579937 -408.314607) (xy 232.541583 -408.351737) (xy 232.498429 -408.383159)
			(xy 232.451315 -408.408258) (xy 232.401163 -408.426544) (xy 232.348952 -408.437661) (xy 232.2957 -408.441391)
			(xy 232.242448 -408.437661) (xy 232.190237 -408.426544) (xy 232.140085 -408.408258) (xy 232.092971 -408.383159)
			(xy 232.049817 -408.351737) (xy 232.011463 -408.314607) (xy 231.99471 -408.293824) (xy 231.987102 -408.285019)
			(xy 231.966201 -408.274837) (xy 231.954578 -408.274266) (xy 231.874822 -408.274266) (xy 231.86319 -408.274809)
			(xy 231.842279 -408.284993) (xy 231.83469 -408.293824) (xy 231.817937 -408.314607) (xy 231.779583 -408.351737)
			(xy 231.736429 -408.383159) (xy 231.689315 -408.408258) (xy 231.639163 -408.426544) (xy 231.586952 -408.437661)
			(xy 231.5337 -408.441391) (xy 231.480448 -408.437661) (xy 231.428237 -408.426544) (xy 231.378085 -408.408258)
			(xy 231.330971 -408.383159) (xy 231.287817 -408.351737) (xy 231.249463 -408.314607) (xy 231.23271 -408.293824)
			(xy 231.225102 -408.285019) (xy 231.204201 -408.274837) (xy 231.192578 -408.274266) (xy 231.112822 -408.274266)
			(xy 231.10119 -408.274809) (xy 231.080279 -408.284993) (xy 231.07269 -408.293824) (xy 231.055937 -408.314607)
			(xy 231.017583 -408.351737) (xy 230.974429 -408.383159) (xy 230.927315 -408.408258) (xy 230.877163 -408.426544)
			(xy 230.824952 -408.437661) (xy 230.7717 -408.441391) (xy 230.718448 -408.437661) (xy 230.666237 -408.426544)
			(xy 230.616085 -408.408258) (xy 230.568971 -408.383159) (xy 230.525817 -408.351737) (xy 230.487463 -408.314607)
			(xy 230.47071 -408.293824) (xy 230.463102 -408.285019) (xy 230.442201 -408.274837) (xy 230.430578 -408.274266)
			(xy 230.350822 -408.274266) (xy 230.33919 -408.274809) (xy 230.318279 -408.284993) (xy 230.31069 -408.293824)
			(xy 230.293937 -408.314607) (xy 230.255583 -408.351737) (xy 230.212429 -408.383159) (xy 230.165315 -408.408258)
			(xy 230.115163 -408.426544) (xy 230.062952 -408.437661) (xy 230.0097 -408.441391) (xy 229.956448 -408.437661)
			(xy 229.904237 -408.426544) (xy 229.854085 -408.408258) (xy 229.806971 -408.383159) (xy 229.763817 -408.351737)
			(xy 229.725463 -408.314607) (xy 229.70871 -408.293824) (xy 229.701102 -408.285019) (xy 229.680201 -408.274837)
			(xy 229.668578 -408.274266) (xy 229.588822 -408.274266) (xy 229.57719 -408.274809) (xy 229.556279 -408.284993)
			(xy 229.54869 -408.293824) (xy 229.531937 -408.314607) (xy 229.493583 -408.351737) (xy 229.450429 -408.383159)
			(xy 229.403315 -408.408258) (xy 229.353163 -408.426544) (xy 229.300952 -408.437661) (xy 229.2477 -408.441391)
			(xy 229.194448 -408.437661) (xy 229.142237 -408.426544) (xy 229.092085 -408.408258) (xy 229.044971 -408.383159)
			(xy 229.001817 -408.351737) (xy 228.963463 -408.314607) (xy 228.94671 -408.293824) (xy 228.939102 -408.285019)
			(xy 228.918201 -408.274837) (xy 228.906578 -408.274266) (xy 228.826822 -408.274266) (xy 228.81519 -408.274809)
			(xy 228.794279 -408.284993) (xy 228.78669 -408.293824) (xy 228.768511 -408.316317) (xy 228.726488 -408.356051)
			(xy 228.67895 -408.388988) (xy 228.626987 -408.414374) (xy 228.571787 -408.431629) (xy 228.514617 -408.440356)
			(xy 228.4857 -408.44089) (xy 228.458447 -408.44044) (xy 228.404497 -408.432683) (xy 228.3522 -408.417327)
			(xy 228.30262 -408.394685) (xy 228.256768 -408.365218) (xy 228.215576 -408.329524) (xy 228.179882 -408.288332)
			(xy 228.150415 -408.24248) (xy 228.127773 -408.1929) (xy 228.112417 -408.140603) (xy 228.10466 -408.086653)
			(xy 226.479608 -408.086653) (xy 226.479608 -410.200094) (xy 226.479862 -410.21) (xy 226.479372 -410.230042)
			(xy 226.471559 -410.269358) (xy 226.456232 -410.306396) (xy 226.43398 -410.339736) (xy 226.420172 -410.354272)
			(xy 226.280472 -410.493972) (xy 226.26594 -410.507782) (xy 226.232595 -410.530025) (xy 226.195556 -410.545345)
			(xy 226.156241 -410.553154) (xy 226.1362 -410.553662) (xy 226.126294 -410.553408) (xy 215.757506 -410.553408)
			(xy 215.7476 -410.553662) (xy 215.726944 -410.553114) (xy 215.686482 -410.544762) (xy 215.64852 -410.528459)
			(xy 215.631268 -410.517086) (xy 215.620104 -410.512105) (xy 215.595696 -410.512105) (xy 215.584532 -410.517086)
			(xy 215.567282 -410.528463) (xy 215.529322 -410.544769) (xy 215.488857 -410.553102) (xy 215.4682 -410.553662)
			(xy 215.458294 -410.553408) (xy 205.089506 -410.553408) (xy 205.0796 -410.553662) (xy 205.058944 -410.553114)
			(xy 205.018482 -410.544762) (xy 204.98052 -410.528459) (xy 204.963268 -410.517086) (xy 204.952104 -410.512105)
			(xy 204.927696 -410.512105) (xy 204.916532 -410.517086) (xy 204.899282 -410.528463) (xy 204.861322 -410.544769)
			(xy 204.820857 -410.553102) (xy 204.8002 -410.553662) (xy 204.790294 -410.553408) (xy 194.833494 -410.553408)
			(xy 194.813474 -410.552958) (xy 194.774202 -410.545156) (xy 194.737209 -410.529836) (xy 194.703921 -410.507585)
			(xy 194.689476 -410.493718) (xy 194.432174 -410.236416) (xy 194.4247 -410.230526) (xy 194.406736 -410.224289)
			(xy 194.387737 -410.225073) (xy 194.370348 -410.232768) (xy 194.36334 -410.23921) (xy 194.212972 -410.389578)
			(xy 194.198474 -410.403384) (xy 194.165196 -410.425628) (xy 194.128221 -410.440959) (xy 194.088967 -410.44879)
			(xy 194.068954 -410.449268) (xy 179.49926 -410.449268) (xy 179.479242 -410.448814) (xy 179.439974 -410.441006)
			(xy 179.402988 -410.425678) (xy 179.369708 -410.403422) (xy 179.355242 -410.389578) (xy 178.865022 -409.899358)
			(xy 178.851217 -409.88486) (xy 178.828975 -409.851582) (xy 178.813647 -409.814607) (xy 178.805818 -409.775353)
			(xy 178.805332 -409.75534) (xy 178.805332 -408.835606) (xy 178.805078 -408.8257) (xy 178.805568 -408.805657)
			(xy 178.813379 -408.76634) (xy 178.828702 -408.729299) (xy 178.85095 -408.695954) (xy 178.864768 -408.681428)
			(xy 179.275994 -408.270456) (xy 179.280322 -408.264945) (xy 179.286123 -408.252195) (xy 179.287424 -408.24531)
			(xy 179.287932 -408.23769) (xy 179.287932 -403.588728) (xy 179.288479 -403.567795) (xy 179.297062 -403.526817)
			(xy 179.313795 -403.488439) (xy 179.337977 -403.454262) (xy 179.352956 -403.43963) (xy 179.354226 -403.43836)
			(xy 180.05552 -402.737066) (xy 180.05969 -402.732713) (xy 180.065985 -402.722438) (xy 180.067966 -402.716746)
			(xy 180.071522 -402.705316) (xy 180.069744 -402.693378) (xy 180.067583 -402.678615) (xy 180.065296 -402.648862)
			(xy 180.065172 -402.633942) (xy 180.065632 -402.606687) (xy 180.073384 -402.55273) (xy 180.088736 -402.500426)
			(xy 180.111376 -402.45084) (xy 180.140842 -402.40498) (xy 180.176536 -402.36378) (xy 180.217729 -402.32808)
			(xy 180.263584 -402.298606) (xy 180.313167 -402.275958) (xy 180.365468 -402.260597) (xy 180.419423 -402.252836)
			(xy 180.473934 -402.252833) (xy 180.52789 -402.260588) (xy 180.580193 -402.275943) (xy 180.629779 -402.298586)
			(xy 180.675637 -402.328055) (xy 180.716834 -402.36375) (xy 180.752532 -402.404946) (xy 180.782004 -402.450802)
			(xy 180.804649 -402.500386) (xy 180.820007 -402.552688) (xy 180.827765 -402.606644) (xy 180.827765 -402.661155)
			(xy 180.820007 -402.71511) (xy 180.804649 -402.767413) (xy 180.782004 -402.816997) (xy 180.752533 -402.862853)
			(xy 180.716835 -402.904049) (xy 180.675638 -402.939745) (xy 180.62978 -402.969214) (xy 180.580194 -402.991856)
			(xy 180.527891 -403.007211) (xy 180.473935 -403.014966) (xy 180.44668 -403.01545) (xy 180.43176 -403.015325)
			(xy 180.402008 -403.013036) (xy 180.387244 -403.010878) (xy 180.375306 -403.0091) (xy 180.363876 -403.012656)
			(xy 180.358212 -403.014699) (xy 180.347945 -403.020981) (xy 180.343556 -403.025102) (xy 180.145944 -403.222714)
			(xy 184.474102 -403.222714) (xy 184.478173 -403.167092) (xy 184.490299 -403.112655) (xy 184.510222 -403.060564)
			(xy 184.537518 -403.011929) (xy 184.571604 -402.967786) (xy 184.611753 -402.929077) (xy 184.657111 -402.896626)
			(xy 184.706711 -402.871125) (xy 184.759495 -402.853118) (xy 184.814338 -402.842988) (xy 184.870072 -402.840951)
			(xy 184.925509 -402.847051) (xy 184.979466 -402.861157) (xy 185.030795 -402.882969) (xy 185.078401 -402.912023)
			(xy 185.121269 -402.947698) (xy 185.158486 -402.989235) (xy 185.189259 -403.035748) (xy 185.212931 -403.086245)
			(xy 185.228999 -403.139652) (xy 185.237119 -403.194828) (xy 185.237628 -403.222714) (xy 185.896502 -403.222714)
			(xy 185.900573 -403.167092) (xy 185.912699 -403.112655) (xy 185.932622 -403.060564) (xy 185.959918 -403.011929)
			(xy 185.994004 -402.967786) (xy 186.034153 -402.929077) (xy 186.079511 -402.896626) (xy 186.129111 -402.871125)
			(xy 186.181895 -402.853118) (xy 186.236738 -402.842988) (xy 186.292472 -402.840951) (xy 186.347909 -402.847051)
			(xy 186.401866 -402.861157) (xy 186.453195 -402.882969) (xy 186.500801 -402.912023) (xy 186.543669 -402.947698)
			(xy 186.580886 -402.989235) (xy 186.611659 -403.035748) (xy 186.635331 -403.086245) (xy 186.651399 -403.139652)
			(xy 186.659519 -403.194828) (xy 186.660028 -403.222714) (xy 187.293502 -403.222714) (xy 187.297573 -403.167092)
			(xy 187.309699 -403.112655) (xy 187.329622 -403.060564) (xy 187.356918 -403.011929) (xy 187.391004 -402.967786)
			(xy 187.431153 -402.929077) (xy 187.476511 -402.896626) (xy 187.526111 -402.871125) (xy 187.578895 -402.853118)
			(xy 187.633738 -402.842988) (xy 187.689472 -402.840951) (xy 187.744909 -402.847051) (xy 187.798866 -402.861157)
			(xy 187.850195 -402.882969) (xy 187.897801 -402.912023) (xy 187.940669 -402.947698) (xy 187.977886 -402.989235)
			(xy 188.008659 -403.035748) (xy 188.032331 -403.086245) (xy 188.048399 -403.139652) (xy 188.056519 -403.194828)
			(xy 188.057028 -403.222714) (xy 188.056519 -403.2506) (xy 188.050082 -403.294342) (xy 189.396622 -403.294342)
			(xy 189.400693 -403.23872) (xy 189.412819 -403.184283) (xy 189.432742 -403.132192) (xy 189.460038 -403.083557)
			(xy 189.494124 -403.039414) (xy 189.534273 -403.000705) (xy 189.579631 -402.968254) (xy 189.629231 -402.942753)
			(xy 189.682015 -402.924746) (xy 189.736858 -402.914616) (xy 189.792592 -402.912579) (xy 189.848029 -402.918679)
			(xy 189.901986 -402.932785) (xy 189.953315 -402.954597) (xy 190.000921 -402.983651) (xy 190.043789 -403.019326)
			(xy 190.081006 -403.060863) (xy 190.111779 -403.107376) (xy 190.135451 -403.157873) (xy 190.151519 -403.21128)
			(xy 190.159639 -403.266456) (xy 190.160148 -403.294342) (xy 190.159639 -403.322228) (xy 190.151519 -403.377404)
			(xy 190.135451 -403.430811) (xy 190.111779 -403.481308) (xy 190.081006 -403.527821) (xy 190.043789 -403.569358)
			(xy 190.000921 -403.605033) (xy 189.953315 -403.634087) (xy 189.901986 -403.655899) (xy 189.848029 -403.670005)
			(xy 189.792592 -403.676105) (xy 189.736858 -403.674068) (xy 189.682015 -403.663938) (xy 189.629231 -403.645931)
			(xy 189.579631 -403.62043) (xy 189.534273 -403.587979) (xy 189.494124 -403.54927) (xy 189.460038 -403.505127)
			(xy 189.432742 -403.456492) (xy 189.412819 -403.404401) (xy 189.400693 -403.349964) (xy 189.396622 -403.294342)
			(xy 188.050082 -403.294342) (xy 188.048399 -403.305776) (xy 188.032331 -403.359183) (xy 188.008659 -403.40968)
			(xy 187.977886 -403.456193) (xy 187.940669 -403.49773) (xy 187.897801 -403.533405) (xy 187.850195 -403.562459)
			(xy 187.798866 -403.584271) (xy 187.744909 -403.598377) (xy 187.689472 -403.604477) (xy 187.633738 -403.60244)
			(xy 187.578895 -403.59231) (xy 187.526111 -403.574303) (xy 187.476511 -403.548802) (xy 187.431153 -403.516351)
			(xy 187.391004 -403.477642) (xy 187.356918 -403.433499) (xy 187.329622 -403.384864) (xy 187.309699 -403.332773)
			(xy 187.297573 -403.278336) (xy 187.293502 -403.222714) (xy 186.660028 -403.222714) (xy 186.659519 -403.2506)
			(xy 186.651399 -403.305776) (xy 186.635331 -403.359183) (xy 186.611659 -403.40968) (xy 186.580886 -403.456193)
			(xy 186.543669 -403.49773) (xy 186.500801 -403.533405) (xy 186.453195 -403.562459) (xy 186.401866 -403.584271)
			(xy 186.347909 -403.598377) (xy 186.292472 -403.604477) (xy 186.236738 -403.60244) (xy 186.181895 -403.59231)
			(xy 186.129111 -403.574303) (xy 186.079511 -403.548802) (xy 186.034153 -403.516351) (xy 185.994004 -403.477642)
			(xy 185.959918 -403.433499) (xy 185.932622 -403.384864) (xy 185.912699 -403.332773) (xy 185.900573 -403.278336)
			(xy 185.896502 -403.222714) (xy 185.237628 -403.222714) (xy 185.237119 -403.2506) (xy 185.228999 -403.305776)
			(xy 185.212931 -403.359183) (xy 185.189259 -403.40968) (xy 185.158486 -403.456193) (xy 185.121269 -403.49773)
			(xy 185.078401 -403.533405) (xy 185.030795 -403.562459) (xy 184.979466 -403.584271) (xy 184.925509 -403.598377)
			(xy 184.870072 -403.604477) (xy 184.814338 -403.60244) (xy 184.759495 -403.59231) (xy 184.706711 -403.574303)
			(xy 184.657111 -403.548802) (xy 184.611753 -403.516351) (xy 184.571604 -403.477642) (xy 184.537518 -403.433499)
			(xy 184.510222 -403.384864) (xy 184.490299 -403.332773) (xy 184.478173 -403.278336) (xy 184.474102 -403.222714)
			(xy 180.145944 -403.222714) (xy 179.710334 -403.658324) (xy 179.705508 -403.663912) (xy 179.700842 -403.670654)
			(xy 179.695663 -403.686199) (xy 179.695348 -403.694392) (xy 179.695348 -406.70734) (xy 179.80101 -406.70734)
			(xy 179.805081 -406.651718) (xy 179.817207 -406.597281) (xy 179.83713 -406.54519) (xy 179.864426 -406.496555)
			(xy 179.898512 -406.452412) (xy 179.938661 -406.413703) (xy 179.984019 -406.381252) (xy 180.033619 -406.355751)
			(xy 180.086403 -406.337744) (xy 180.141246 -406.327614) (xy 180.19698 -406.325577) (xy 180.252417 -406.331677)
			(xy 180.306374 -406.345783) (xy 180.357703 -406.367595) (xy 180.405309 -406.396649) (xy 180.448177 -406.432324)
			(xy 180.485394 -406.473861) (xy 180.516167 -406.520374) (xy 180.539839 -406.570871) (xy 180.555907 -406.624278)
			(xy 180.564027 -406.679454) (xy 180.564536 -406.70734) (xy 180.564027 -406.735226) (xy 180.555907 -406.790402)
			(xy 180.539839 -406.843809) (xy 180.516167 -406.894306) (xy 180.485394 -406.940819) (xy 180.448177 -406.982356)
			(xy 180.405309 -407.018031) (xy 180.357703 -407.047085) (xy 180.306374 -407.068897) (xy 180.252417 -407.083003)
			(xy 180.19698 -407.089103) (xy 180.141246 -407.087066) (xy 180.086403 -407.076936) (xy 180.033619 -407.058929)
			(xy 179.984019 -407.033428) (xy 179.938661 -407.000977) (xy 179.898512 -406.962268) (xy 179.864426 -406.918125)
			(xy 179.83713 -406.86949) (xy 179.817207 -406.817399) (xy 179.805081 -406.762962) (xy 179.80101 -406.70734)
			(xy 179.695348 -406.70734) (xy 179.695348 -408.26309) (xy 181.939184 -408.26309) (xy 181.93967 -408.235839)
			(xy 181.947426 -408.181891) (xy 181.962781 -408.129596) (xy 181.985423 -408.080019) (xy 182.014889 -408.034169)
			(xy 182.05058 -407.992978) (xy 182.091771 -407.957287) (xy 182.137621 -407.927821) (xy 182.187198 -407.905179)
			(xy 182.239493 -407.889824) (xy 182.293441 -407.882068) (xy 182.347943 -407.882068) (xy 182.401891 -407.889824)
			(xy 182.454186 -407.905179) (xy 182.503763 -407.927821) (xy 182.549613 -407.957287) (xy 182.590804 -407.992978)
			(xy 182.626495 -408.034169) (xy 182.655961 -408.080019) (xy 182.678603 -408.129596) (xy 182.693958 -408.181891)
			(xy 182.701714 -408.235839) (xy 182.7022 -408.26309) (xy 182.701974 -408.281109) (xy 182.698543 -408.316984)
			(xy 182.695342 -408.334718) (xy 182.693056 -408.347418) (xy 182.700676 -408.371548) (xy 182.77205 -408.439874)
			(xy 182.778361 -408.445488) (xy 182.7937 -408.452542) (xy 182.8105 -408.454216) (xy 182.818786 -408.452574)
			(xy 182.840498 -408.447729) (xy 182.88468 -408.442514) (xy 182.906924 -408.44216) (xy 182.907178 -408.44216)
			(xy 182.934405 -408.442672) (xy 182.988301 -408.450454) (xy 183.040543 -408.465819) (xy 183.090069 -408.488457)
			(xy 183.135874 -408.517906) (xy 183.177026 -408.553569) (xy 183.212689 -408.59472) (xy 183.242139 -408.640524)
			(xy 183.264778 -408.69005) (xy 183.280145 -408.742291) (xy 183.287928 -408.796187) (xy 183.288432 -408.823414)
			(xy 183.288432 -408.823922) (xy 183.28767 -408.845766) (xy 183.28767 -408.84602) (xy 183.287649 -408.85491)
			(xy 183.292857 -408.871889) (xy 183.303548 -408.886071) (xy 183.310784 -408.891232) (xy 183.396382 -408.946858)
			(xy 183.42356 -408.948382) (xy 183.435752 -408.942032) (xy 183.462926 -408.928675) (xy 183.520445 -408.909769)
			(xy 183.580231 -408.900196) (xy 183.610504 -408.899614) (xy 183.637757 -408.900056) (xy 183.691707 -408.907814)
			(xy 183.744004 -408.92317) (xy 183.793584 -408.945813) (xy 183.839436 -408.975281) (xy 183.880629 -409.010974)
			(xy 183.916322 -409.052167) (xy 183.945789 -409.09802) (xy 183.968432 -409.147599) (xy 183.983787 -409.199897)
			(xy 183.991544 -409.253847) (xy 183.991544 -409.308353) (xy 183.983787 -409.362303) (xy 183.968432 -409.414601)
			(xy 183.945789 -409.46418) (xy 183.916322 -409.510033) (xy 183.880629 -409.551226) (xy 183.839436 -409.586919)
			(xy 183.793584 -409.616387) (xy 183.744004 -409.63903) (xy 183.691707 -409.654386) (xy 183.637757 -409.662144)
			(xy 183.610504 -409.66263) (xy 183.583265 -409.662119) (xy 183.529342 -409.654371) (xy 183.477069 -409.63903)
			(xy 183.42751 -409.616409) (xy 183.381673 -409.586969) (xy 183.34049 -409.551308) (xy 183.304799 -409.510151)
			(xy 183.275325 -409.464336) (xy 183.252668 -409.414793) (xy 183.237289 -409.362532) (xy 183.229501 -409.308614)
			(xy 183.228996 -409.281376) (xy 183.228996 -409.280868) (xy 183.229758 -409.259024) (xy 183.229758 -409.25877)
			(xy 183.229819 -409.249877) (xy 183.224599 -409.232892) (xy 183.21389 -409.218714) (xy 183.206644 -409.213558)
			(xy 183.121046 -409.157932) (xy 183.093868 -409.156408) (xy 183.081676 -409.162758) (xy 183.054497 -409.176104)
			(xy 182.99698 -409.195014) (xy 182.937197 -409.204592) (xy 182.906924 -409.205176) (xy 182.87967 -409.204722)
			(xy 182.825717 -409.196968) (xy 182.773417 -409.181613) (xy 182.723835 -409.158971) (xy 182.67798 -409.129503)
			(xy 182.636787 -409.093808) (xy 182.601093 -409.052613) (xy 182.571625 -409.006758) (xy 182.548984 -408.957175)
			(xy 182.533631 -408.904875) (xy 182.525877 -408.850922) (xy 182.525416 -408.823668) (xy 182.525638 -408.805649)
			(xy 182.529072 -408.769774) (xy 182.532274 -408.75204) (xy 182.53456 -408.73934) (xy 182.52694 -408.71521)
			(xy 182.455566 -408.646884) (xy 182.449241 -408.641286) (xy 182.43391 -408.634223) (xy 182.417115 -408.632543)
			(xy 182.40883 -408.634184) (xy 182.387117 -408.639026) (xy 182.342936 -408.644243) (xy 182.320692 -408.644598)
			(xy 182.320438 -408.644598) (xy 182.293198 -408.644112) (xy 182.239277 -408.636325) (xy 182.187011 -408.620946)
			(xy 182.137465 -408.598289) (xy 182.091646 -408.568814) (xy 182.050486 -408.533121) (xy 182.014823 -408.491936)
			(xy 181.98538 -408.446096) (xy 181.962758 -408.396533) (xy 181.947417 -408.344257) (xy 181.939668 -408.29033)
			(xy 181.939184 -408.26309) (xy 179.695348 -408.26309) (xy 179.695348 -408.336242) (xy 179.695602 -408.342338)
			(xy 179.695602 -408.343862) (xy 179.694078 -408.366976) (xy 179.693824 -408.372818) (xy 179.693824 -408.438604)
			(xy 179.687728 -408.439874) (xy 179.680405 -408.441893) (xy 179.667354 -408.449652) (xy 179.662074 -408.455114)
			(xy 179.656267 -408.463747) (xy 179.643161 -408.479908) (xy 179.635912 -408.487372) (xy 179.41163 -408.711654)
			(xy 179.709572 -408.711654) (xy 179.710039 -408.685258) (xy 179.717373 -408.632976) (xy 179.731852 -408.582207)
			(xy 179.7532 -408.533922) (xy 179.766722 -408.511248) (xy 179.766722 -408.51074) (xy 179.774088 -408.498802)
			(xy 179.776882 -408.494738) (xy 179.785264 -408.483562) (xy 179.803397 -408.460183) (xy 179.845667 -408.418789)
			(xy 179.89382 -408.384416) (xy 179.946702 -408.357887) (xy 180.003045 -408.339839) (xy 180.061499 -408.330704)
			(xy 180.09108 -408.330146) (xy 180.118335 -408.330634) (xy 180.172291 -408.338389) (xy 180.224595 -408.353744)
			(xy 180.27418 -408.376387) (xy 180.320038 -408.405856) (xy 180.361236 -408.441552) (xy 180.396933 -408.482747)
			(xy 180.426405 -408.528604) (xy 180.44905 -408.578188) (xy 180.464408 -408.630491) (xy 180.472165 -408.684447)
			(xy 180.472165 -408.738957) (xy 180.464407 -408.792913) (xy 180.449048 -408.845215) (xy 180.426403 -408.894799)
			(xy 180.396931 -408.940656) (xy 180.361233 -408.981851) (xy 180.340644 -408.99969) (xy 180.902354 -408.99969)
			(xy 180.906425 -408.944068) (xy 180.918551 -408.889631) (xy 180.938474 -408.83754) (xy 180.96577 -408.788905)
			(xy 180.999856 -408.744762) (xy 181.040005 -408.706053) (xy 181.085363 -408.673602) (xy 181.134963 -408.648101)
			(xy 181.187747 -408.630094) (xy 181.24259 -408.619964) (xy 181.298324 -408.617927) (xy 181.353761 -408.624027)
			(xy 181.407718 -408.638133) (xy 181.459047 -408.659945) (xy 181.506653 -408.688999) (xy 181.549521 -408.724674)
			(xy 181.586738 -408.766211) (xy 181.617511 -408.812724) (xy 181.641183 -408.863221) (xy 181.657251 -408.916628)
			(xy 181.665371 -408.971804) (xy 181.66588 -408.99969) (xy 181.665371 -409.027576) (xy 181.657251 -409.082752)
			(xy 181.641183 -409.136159) (xy 181.617511 -409.186656) (xy 181.586738 -409.233169) (xy 181.549521 -409.274706)
			(xy 181.506653 -409.310381) (xy 181.459047 -409.339435) (xy 181.407718 -409.361247) (xy 181.353761 -409.375353)
			(xy 181.298324 -409.381453) (xy 181.24259 -409.379416) (xy 181.187747 -409.369286) (xy 181.134963 -409.351279)
			(xy 181.085363 -409.325778) (xy 181.040005 -409.293327) (xy 180.999856 -409.254618) (xy 180.96577 -409.210475)
			(xy 180.938474 -409.16184) (xy 180.918551 -409.109749) (xy 180.906425 -409.055312) (xy 180.902354 -408.99969)
			(xy 180.340644 -408.99969) (xy 180.320035 -409.017547) (xy 180.274177 -409.047015) (xy 180.224591 -409.069658)
			(xy 180.172288 -409.085012) (xy 180.118331 -409.092767) (xy 180.063821 -409.092763) (xy 180.009865 -409.085002)
			(xy 179.957564 -409.069641) (xy 179.907981 -409.046992) (xy 179.862126 -409.017518) (xy 179.820933 -408.981817)
			(xy 179.78524 -408.940617) (xy 179.755774 -408.894757) (xy 179.733135 -408.84517) (xy 179.717783 -408.792866)
			(xy 179.710032 -408.738909) (xy 179.709572 -408.711654) (xy 179.41163 -408.711654) (xy 179.22367 -408.899614)
			(xy 179.218646 -408.906498) (xy 179.213075 -408.922593) (xy 179.212748 -408.93111) (xy 179.212748 -409.543504)
			(xy 181.794148 -409.543504) (xy 181.798219 -409.487882) (xy 181.810345 -409.433445) (xy 181.830268 -409.381354)
			(xy 181.857564 -409.332719) (xy 181.89165 -409.288576) (xy 181.931799 -409.249867) (xy 181.977157 -409.217416)
			(xy 182.026757 -409.191915) (xy 182.079541 -409.173908) (xy 182.134384 -409.163778) (xy 182.190118 -409.161741)
			(xy 182.245555 -409.167841) (xy 182.299512 -409.181947) (xy 182.350841 -409.203759) (xy 182.398447 -409.232813)
			(xy 182.441315 -409.268488) (xy 182.478532 -409.310025) (xy 182.509305 -409.356538) (xy 182.532977 -409.407035)
			(xy 182.549045 -409.460442) (xy 182.557165 -409.515618) (xy 182.557674 -409.543504) (xy 182.557165 -409.57139)
			(xy 182.549045 -409.626566) (xy 182.532977 -409.679973) (xy 182.509305 -409.73047) (xy 182.478532 -409.776983)
			(xy 182.441315 -409.81852) (xy 182.398447 -409.854195) (xy 182.350841 -409.883249) (xy 182.299512 -409.905061)
			(xy 182.245555 -409.919167) (xy 182.190118 -409.925267) (xy 182.134384 -409.92323) (xy 182.079541 -409.9131)
			(xy 182.026757 -409.895093) (xy 181.977157 -409.869592) (xy 181.931799 -409.837141) (xy 181.89165 -409.798432)
			(xy 181.857564 -409.754289) (xy 181.830268 -409.705654) (xy 181.810345 -409.653563) (xy 181.798219 -409.599126)
			(xy 181.794148 -409.543504) (xy 179.212748 -409.543504) (xy 179.212748 -409.64993) (xy 179.213764 -409.659582)
			(xy 179.215396 -409.666823) (xy 179.222247 -409.679984) (xy 179.227226 -409.68549) (xy 179.56911 -410.027374)
			(xy 179.574611 -410.032357) (xy 179.587778 -410.039195) (xy 179.595018 -410.040836) (xy 179.60467 -410.041852)
			(xy 193.963798 -410.041852) (xy 193.97091 -410.041344) (xy 193.977306 -410.040249) (xy 193.989271 -410.035236)
			(xy 193.994532 -410.031438) (xy 193.999866 -410.026866) (xy 194.180714 -409.846018) (xy 194.184696 -409.841848)
			(xy 194.190852 -409.832102) (xy 194.192906 -409.826714) (xy 194.195446 -409.814268) (xy 194.1957 -409.80995)
			(xy 194.1957 -404.70582) (xy 194.19621 -404.685883) (xy 194.204014 -404.646779) (xy 194.219268 -404.609936)
			(xy 194.241392 -404.576761) (xy 194.255136 -404.56231) (xy 195.58254 -403.234906) (xy 195.586711 -403.230554)
			(xy 195.593012 -403.220281) (xy 195.594986 -403.214586) (xy 195.598542 -403.203156) (xy 195.596764 -403.191218)
			(xy 195.594601 -403.176455) (xy 195.592311 -403.146702) (xy 195.592192 -403.131782) (xy 195.592679 -403.104532)
			(xy 195.600438 -403.050586) (xy 195.615794 -402.998293) (xy 195.638436 -402.948718) (xy 195.667903 -402.90287)
			(xy 195.703595 -402.861682) (xy 195.744785 -402.825992) (xy 195.790634 -402.796528) (xy 195.84021 -402.773888)
			(xy 195.892503 -402.758534) (xy 195.94645 -402.750778) (xy 195.9737 -402.750274) (xy 196.002616 -402.750808)
			(xy 196.059785 -402.759536) (xy 196.114983 -402.776793) (xy 196.166943 -402.802182) (xy 196.214477 -402.835123)
			(xy 196.256495 -402.87486) (xy 196.27469 -402.89734) (xy 196.274944 -402.897594) (xy 196.278445 -402.901841)
			(xy 196.286902 -402.90888) (xy 196.291708 -402.911564) (xy 196.300598 -402.916136) (xy 196.350128 -402.918676)
			(xy 196.350636 -402.918676) (xy 196.388736 -402.920708) (xy 196.394242 -402.920924) (xy 196.405132 -402.919249)
			(xy 196.410326 -402.917406) (xy 196.420232 -402.913342) (xy 196.427852 -402.905468) (xy 196.437833 -402.895388)
			(xy 196.459064 -402.876572) (xy 196.47027 -402.867876) (xy 196.470778 -402.867368) (xy 196.479414 -402.860764)
			(xy 196.485944 -402.85523) (xy 196.495161 -402.840819) (xy 196.497448 -402.83257) (xy 196.498972 -402.820632)
			(xy 196.498972 -402.45411) (xy 196.498499 -402.444142) (xy 196.490928 -402.425701) (xy 196.48424 -402.418296)
			(xy 196.118988 -402.053044) (xy 195.764658 -401.69846) (xy 195.758444 -401.692923) (xy 195.743414 -401.685796)
			(xy 195.735194 -401.68449) (xy 195.729352 -401.684236) (xy 195.600574 -401.684236) (xy 195.580638 -401.683722)
			(xy 195.541538 -401.675912) (xy 195.5047 -401.660653) (xy 195.471529 -401.638528) (xy 195.457064 -401.6248)
			(xy 195.355972 -401.523708) (xy 195.348553 -401.517987) (xy 195.330866 -401.511861) (xy 195.31216 -401.512529)
			(xy 195.303394 -401.515834) (xy 195.258944 -401.5359) (xy 195.258436 -401.5359) (xy 195.21551 -401.555712)
			(xy 195.21168 -401.557518) (xy 195.20465 -401.562237) (xy 195.20154 -401.56511) (xy 195.193974 -401.573015)
			(xy 195.185795 -401.593286) (xy 195.185792 -401.604226) (xy 195.185792 -401.605496) (xy 195.186808 -401.633182)
			(xy 195.186346 -401.660436) (xy 195.178591 -401.714389) (xy 195.163237 -401.766689) (xy 195.140595 -401.816271)
			(xy 195.111128 -401.862126) (xy 195.075434 -401.903321) (xy 195.034241 -401.939017) (xy 194.988387 -401.968486)
			(xy 194.938805 -401.99113) (xy 194.886506 -402.006487) (xy 194.832554 -402.014245) (xy 194.8053 -402.01469)
			(xy 194.777127 -402.014191) (xy 194.721393 -402.005916) (xy 194.667483 -401.989531) (xy 194.61657 -401.965392)
			(xy 194.569762 -401.934025) (xy 194.528079 -401.896113) (xy 194.492428 -401.85248) (xy 194.463584 -401.804078)
			(xy 194.442176 -401.751958) (xy 194.428668 -401.697255) (xy 194.42557 -401.66925) (xy 194.42557 -401.668488)
			(xy 194.424574 -401.661532) (xy 194.419285 -401.64852) (xy 194.415156 -401.642834) (xy 194.410838 -401.636992)
			(xy 194.399408 -401.62861) (xy 194.305682 -401.594828) (xy 194.297139 -401.592112) (xy 194.279224 -401.59219)
			(xy 194.262426 -401.598418) (xy 194.25539 -401.603972) (xy 194.046094 -401.813268) (xy 194.039259 -401.82067)
			(xy 194.03155 -401.839269) (xy 194.031108 -401.849336) (xy 194.031108 -408.87396) (xy 194.030653 -408.893978)
			(xy 194.022842 -408.933244) (xy 194.007515 -408.97023) (xy 193.98526 -409.00351) (xy 193.971418 -409.017978)
			(xy 193.387218 -409.602178) (xy 193.372719 -409.61598) (xy 193.339439 -409.638215) (xy 193.302464 -409.653536)
			(xy 193.263212 -409.661357) (xy 193.2432 -409.661868) (xy 185.5216 -409.661868) (xy 185.501584 -409.661408)
			(xy 185.462323 -409.65359) (xy 185.425345 -409.638255) (xy 185.392073 -409.615994) (xy 185.377582 -409.602178)
			(xy 182.894224 -407.11882) (xy 182.891373 -407.116114) (xy 182.884996 -407.111519) (xy 182.881524 -407.109676)
			(xy 182.876096 -407.107097) (xy 182.864417 -407.104283) (xy 182.85841 -407.104088) (xy 181.26964 -407.104088)
			(xy 181.249622 -407.103632) (xy 181.210356 -407.095821) (xy 181.173372 -407.080492) (xy 181.140093 -407.058236)
			(xy 181.125622 -407.044398) (xy 180.730398 -406.649174) (xy 180.716593 -406.634676) (xy 180.694352 -406.601397)
			(xy 180.679022 -406.564422) (xy 180.671191 -406.525169) (xy 180.670708 -406.505156) (xy 180.670708 -405.459184)
			(xy 180.670376 -405.450543) (xy 180.664631 -405.434244) (xy 180.653773 -405.420799) (xy 180.646578 -405.416004)
			(xy 180.561488 -405.370538) (xy 180.556649 -405.368531) (xy 180.546405 -405.366345) (xy 180.541168 -405.36622)
			(xy 180.512466 -405.37511) (xy 180.508402 -405.37765) (xy 180.484898 -405.392536) (xy 180.434493 -405.416081)
			(xy 180.381204 -405.432063) (xy 180.326161 -405.440142) (xy 180.298344 -405.440642) (xy 180.271087 -405.440182)
			(xy 180.217126 -405.432429) (xy 180.164818 -405.417076) (xy 180.115228 -405.394434) (xy 180.069365 -405.364964)
			(xy 180.028164 -405.329267) (xy 179.992462 -405.28807) (xy 179.962987 -405.242211) (xy 179.94034 -405.192623)
			(xy 179.92498 -405.140317) (xy 179.917221 -405.086357) (xy 179.917221 -405.031843) (xy 179.92498 -404.977883)
			(xy 179.94034 -404.925577) (xy 179.962987 -404.875989) (xy 179.992462 -404.83013) (xy 180.028164 -404.788933)
			(xy 180.069365 -404.753236) (xy 180.115228 -404.723766) (xy 180.164818 -404.701124) (xy 180.217126 -404.685771)
			(xy 180.271087 -404.678018) (xy 180.298344 -404.677626) (xy 180.326162 -404.678125) (xy 180.381209 -404.686194)
			(xy 180.434501 -404.70217) (xy 180.484909 -404.725714) (xy 180.508402 -404.740618) (xy 180.512466 -404.743158)
			(xy 180.541168 -404.752048) (xy 180.546401 -404.751887) (xy 180.556639 -404.749705) (xy 180.561488 -404.74773)
			(xy 180.646578 -404.702264) (xy 180.653739 -404.697433) (xy 180.664571 -404.68399) (xy 180.670327 -404.667715)
			(xy 180.670708 -404.659084) (xy 180.670708 -404.22957) (xy 180.670543 -404.22356) (xy 180.667724 -404.211875)
			(xy 180.66512 -404.206456) (xy 180.66328 -404.202982) (xy 180.658685 -404.196605) (xy 180.655976 -404.193756)
			(xy 180.534564 -404.072344) (xy 180.53021 -404.068177) (xy 180.519933 -404.061887) (xy 180.514244 -404.059898)
			(xy 180.502814 -404.056342) (xy 180.490876 -404.05812) (xy 180.476113 -404.060281) (xy 180.44636 -404.062568)
			(xy 180.43144 -404.062692) (xy 180.404188 -404.062232) (xy 180.350238 -404.05448) (xy 180.29794 -404.03913)
			(xy 180.248359 -404.016493) (xy 180.202504 -403.98703) (xy 180.161309 -403.951342) (xy 180.125613 -403.910154)
			(xy 180.096141 -403.864304) (xy 180.073495 -403.814728) (xy 180.058135 -403.762433) (xy 180.050374 -403.708484)
			(xy 180.050369 -403.65398) (xy 180.058121 -403.60003) (xy 180.073473 -403.547732) (xy 180.096111 -403.498152)
			(xy 180.125574 -403.452298) (xy 180.161264 -403.411104) (xy 180.202453 -403.375408) (xy 180.248303 -403.345938)
			(xy 180.29788 -403.323292) (xy 180.350175 -403.307933) (xy 180.404124 -403.300173) (xy 180.458628 -403.30017)
			(xy 180.512578 -403.307923) (xy 180.564875 -403.323276) (xy 180.614455 -403.345915) (xy 180.660309 -403.375379)
			(xy 180.701502 -403.41107) (xy 180.737197 -403.452259) (xy 180.766666 -403.49811) (xy 180.78931 -403.547687)
			(xy 180.804668 -403.599983) (xy 180.812428 -403.653932) (xy 180.812948 -403.681184) (xy 180.812825 -403.696104)
			(xy 180.810538 -403.725857) (xy 180.808376 -403.74062) (xy 180.806598 -403.752558) (xy 180.810154 -403.763988)
			(xy 180.812203 -403.769648) (xy 180.818494 -403.779906) (xy 180.8226 -403.784308) (xy 181.018434 -403.980142)
			(xy 181.032236 -403.994642) (xy 181.054471 -404.027922) (xy 181.069796 -404.064896) (xy 181.077622 -404.104148)
			(xy 181.078124 -404.12416) (xy 181.078124 -404.359618) (xy 189.9064 -404.359618) (xy 189.910471 -404.303996)
			(xy 189.922597 -404.249559) (xy 189.94252 -404.197468) (xy 189.969816 -404.148833) (xy 190.003902 -404.10469)
			(xy 190.044051 -404.065981) (xy 190.089409 -404.03353) (xy 190.139009 -404.008029) (xy 190.191793 -403.990022)
			(xy 190.246636 -403.979892) (xy 190.30237 -403.977855) (xy 190.357807 -403.983955) (xy 190.411764 -403.998061)
			(xy 190.463093 -404.019873) (xy 190.510699 -404.048927) (xy 190.553567 -404.084602) (xy 190.590784 -404.126139)
			(xy 190.621557 -404.172652) (xy 190.645229 -404.223149) (xy 190.661297 -404.276556) (xy 190.669417 -404.331732)
			(xy 190.669926 -404.359618) (xy 190.669417 -404.387504) (xy 190.661297 -404.44268) (xy 190.645229 -404.496087)
			(xy 190.637285 -404.513034) (xy 191.295272 -404.513034) (xy 191.299343 -404.457412) (xy 191.311469 -404.402975)
			(xy 191.331392 -404.350884) (xy 191.358688 -404.302249) (xy 191.392774 -404.258106) (xy 191.432923 -404.219397)
			(xy 191.478281 -404.186946) (xy 191.527881 -404.161445) (xy 191.580665 -404.143438) (xy 191.635508 -404.133308)
			(xy 191.691242 -404.131271) (xy 191.746679 -404.137371) (xy 191.800636 -404.151477) (xy 191.851965 -404.173289)
			(xy 191.899571 -404.202343) (xy 191.942439 -404.238018) (xy 191.979656 -404.279555) (xy 192.010429 -404.326068)
			(xy 192.034101 -404.376565) (xy 192.050169 -404.429972) (xy 192.058289 -404.485148) (xy 192.058798 -404.513034)
			(xy 192.058289 -404.54092) (xy 192.050169 -404.596096) (xy 192.034101 -404.649503) (xy 192.010429 -404.7)
			(xy 191.979656 -404.746513) (xy 191.942439 -404.78805) (xy 191.899571 -404.823725) (xy 191.851965 -404.852779)
			(xy 191.800636 -404.874591) (xy 191.746679 -404.888697) (xy 191.691242 -404.894797) (xy 191.635508 -404.89276)
			(xy 191.580665 -404.88263) (xy 191.527881 -404.864623) (xy 191.478281 -404.839122) (xy 191.432923 -404.806671)
			(xy 191.392774 -404.767962) (xy 191.358688 -404.723819) (xy 191.331392 -404.675184) (xy 191.311469 -404.623093)
			(xy 191.299343 -404.568656) (xy 191.295272 -404.513034) (xy 190.637285 -404.513034) (xy 190.621557 -404.546584)
			(xy 190.590784 -404.593097) (xy 190.553567 -404.634634) (xy 190.510699 -404.670309) (xy 190.463093 -404.699363)
			(xy 190.411764 -404.721175) (xy 190.357807 -404.735281) (xy 190.30237 -404.741381) (xy 190.246636 -404.739344)
			(xy 190.191793 -404.729214) (xy 190.139009 -404.711207) (xy 190.089409 -404.685706) (xy 190.044051 -404.653255)
			(xy 190.003902 -404.614546) (xy 189.969816 -404.570403) (xy 189.94252 -404.521768) (xy 189.922597 -404.469677)
			(xy 189.910471 -404.41524) (xy 189.9064 -404.359618) (xy 181.078124 -404.359618) (xy 181.078124 -404.648416)
			(xy 181.078457 -404.657056) (xy 181.084204 -404.673352) (xy 181.095065 -404.686792) (xy 181.102254 -404.691596)
			(xy 181.187344 -404.737062) (xy 181.192184 -404.739066) (xy 181.202428 -404.741246) (xy 181.207664 -404.74138)
			(xy 181.236366 -404.73249) (xy 181.24043 -404.72995) (xy 181.263935 -404.715066) (xy 181.31434 -404.691525)
			(xy 181.367629 -404.675548) (xy 181.422672 -404.667473) (xy 181.450488 -404.666958) (xy 181.477744 -404.66742)
			(xy 181.531701 -404.675176) (xy 181.584005 -404.690533) (xy 181.633591 -404.713177) (xy 181.67945 -404.742647)
			(xy 181.720648 -404.778344) (xy 181.756346 -404.819541) (xy 181.785818 -404.865398) (xy 181.808463 -404.914984)
			(xy 181.823821 -404.967287) (xy 181.831579 -405.021244) (xy 181.831579 -405.075756) (xy 181.823821 -405.129713)
			(xy 181.808463 -405.182016) (xy 181.794751 -405.212042) (xy 183.409842 -405.212042) (xy 183.413913 -405.15642)
			(xy 183.426039 -405.101983) (xy 183.445962 -405.049892) (xy 183.473258 -405.001257) (xy 183.507344 -404.957114)
			(xy 183.547493 -404.918405) (xy 183.592851 -404.885954) (xy 183.642451 -404.860453) (xy 183.695235 -404.842446)
			(xy 183.750078 -404.832316) (xy 183.805812 -404.830279) (xy 183.861249 -404.836379) (xy 183.915206 -404.850485)
			(xy 183.966535 -404.872297) (xy 184.014141 -404.901351) (xy 184.057009 -404.937026) (xy 184.094226 -404.978563)
			(xy 184.124999 -405.025076) (xy 184.148671 -405.075573) (xy 184.164739 -405.12898) (xy 184.172859 -405.184156)
			(xy 184.173368 -405.212042) (xy 184.172859 -405.239928) (xy 184.164739 -405.295104) (xy 184.148671 -405.348511)
			(xy 184.124999 -405.399008) (xy 184.094226 -405.445521) (xy 184.057009 -405.487058) (xy 184.014141 -405.522733)
			(xy 183.966535 -405.551787) (xy 183.915206 -405.573599) (xy 183.861249 -405.587705) (xy 183.805812 -405.593805)
			(xy 183.750078 -405.591768) (xy 183.695235 -405.581638) (xy 183.642451 -405.563631) (xy 183.592851 -405.53813)
			(xy 183.547493 -405.505679) (xy 183.507344 -405.46697) (xy 183.473258 -405.422827) (xy 183.445962 -405.374192)
			(xy 183.426039 -405.322101) (xy 183.413913 -405.267664) (xy 183.409842 -405.212042) (xy 181.794751 -405.212042)
			(xy 181.785818 -405.231602) (xy 181.756346 -405.277459) (xy 181.720648 -405.318656) (xy 181.67945 -405.354353)
			(xy 181.633591 -405.383823) (xy 181.584005 -405.406467) (xy 181.531701 -405.421824) (xy 181.477744 -405.42958)
			(xy 181.450488 -405.429974) (xy 181.422672 -405.42947) (xy 181.367629 -405.421392) (xy 181.314342 -405.405408)
			(xy 181.26394 -405.381857) (xy 181.24043 -405.366982) (xy 181.236366 -405.364442) (xy 181.207664 -405.355552)
			(xy 181.20243 -405.35571) (xy 181.19219 -405.357886) (xy 181.187344 -405.35987) (xy 181.102254 -405.405336)
			(xy 181.095101 -405.410173) (xy 181.084284 -405.423618) (xy 181.078536 -405.439889) (xy 181.078124 -405.448516)
			(xy 181.078124 -405.676608) (xy 182.21655 -405.676608) (xy 182.220621 -405.620986) (xy 182.232747 -405.566549)
			(xy 182.25267 -405.514458) (xy 182.279966 -405.465823) (xy 182.314052 -405.42168) (xy 182.354201 -405.382971)
			(xy 182.399559 -405.35052) (xy 182.449159 -405.325019) (xy 182.501943 -405.307012) (xy 182.556786 -405.296882)
			(xy 182.61252 -405.294845) (xy 182.667957 -405.300945) (xy 182.721914 -405.315051) (xy 182.773243 -405.336863)
			(xy 182.820849 -405.365917) (xy 182.863717 -405.401592) (xy 182.900934 -405.443129) (xy 182.931707 -405.489642)
			(xy 182.955379 -405.540139) (xy 182.971447 -405.593546) (xy 182.979567 -405.648722) (xy 182.980076 -405.676608)
			(xy 182.979567 -405.704494) (xy 182.972046 -405.755601) (xy 185.291488 -405.755601) (xy 185.295218 -405.70235)
			(xy 185.306334 -405.650139) (xy 185.32462 -405.599987) (xy 185.349718 -405.552874) (xy 185.381138 -405.509719)
			(xy 185.418268 -405.471366) (xy 185.43905 -405.454612) (xy 185.44785 -405.446999) (xy 185.458036 -405.426102)
			(xy 185.458608 -405.41448) (xy 185.458608 -405.334724) (xy 185.458038 -405.323096) (xy 185.447871 -405.302187)
			(xy 185.43905 -405.294592) (xy 185.416552 -405.276418) (xy 185.37682 -405.234393) (xy 185.343884 -405.186854)
			(xy 185.318499 -405.13489) (xy 185.301245 -405.07969) (xy 185.292518 -405.022519) (xy 185.291984 -404.993602)
			(xy 185.29248 -404.966351) (xy 185.300236 -404.912404) (xy 185.31559 -404.86011) (xy 185.33823 -404.810533)
			(xy 185.367696 -404.764683) (xy 185.403386 -404.723493) (xy 185.444575 -404.687802) (xy 185.490425 -404.658335)
			(xy 185.540001 -404.635694) (xy 185.592294 -404.620338) (xy 185.646241 -404.61258) (xy 185.673492 -404.612094)
			(xy 185.70241 -404.612582) (xy 185.759585 -404.621313) (xy 185.814786 -404.638574) (xy 185.866748 -404.663971)
			(xy 185.914281 -404.696922) (xy 185.956294 -404.736671) (xy 185.974482 -404.75916) (xy 185.982096 -404.767959)
			(xy 186.002992 -404.778145) (xy 186.014614 -404.778718) (xy 186.09437 -404.778718) (xy 186.105997 -404.778141)
			(xy 186.126906 -404.767978) (xy 186.134502 -404.75916) (xy 186.151255 -404.738377) (xy 186.189609 -404.701247)
			(xy 186.232763 -404.669825) (xy 186.279877 -404.644726) (xy 186.330029 -404.62644) (xy 186.38224 -404.615323)
			(xy 186.435492 -404.611593) (xy 186.488744 -404.615323) (xy 186.540955 -404.62644) (xy 186.591107 -404.644726)
			(xy 186.638221 -404.669825) (xy 186.681375 -404.701247) (xy 186.719729 -404.738377) (xy 186.736482 -404.75916)
			(xy 186.744096 -404.767959) (xy 186.764992 -404.778145) (xy 186.776614 -404.778718) (xy 186.85637 -404.778718)
			(xy 186.867997 -404.778141) (xy 186.888906 -404.767978) (xy 186.896502 -404.75916) (xy 186.913255 -404.738377)
			(xy 186.951609 -404.701247) (xy 186.994763 -404.669825) (xy 187.041877 -404.644726) (xy 187.092029 -404.62644)
			(xy 187.14424 -404.615323) (xy 187.197492 -404.611593) (xy 187.250744 -404.615323) (xy 187.302955 -404.62644)
			(xy 187.353107 -404.644726) (xy 187.400221 -404.669825) (xy 187.443375 -404.701247) (xy 187.481729 -404.738377)
			(xy 187.498482 -404.75916) (xy 187.506096 -404.767959) (xy 187.526992 -404.778145) (xy 187.538614 -404.778718)
			(xy 187.61837 -404.778718) (xy 187.629997 -404.778141) (xy 187.650906 -404.767978) (xy 187.658502 -404.75916)
			(xy 187.675255 -404.738377) (xy 187.713609 -404.701247) (xy 187.756763 -404.669825) (xy 187.803877 -404.644726)
			(xy 187.854029 -404.62644) (xy 187.90624 -404.615323) (xy 187.959492 -404.611593) (xy 188.012744 -404.615323)
			(xy 188.064955 -404.62644) (xy 188.115107 -404.644726) (xy 188.162221 -404.669825) (xy 188.205375 -404.701247)
			(xy 188.243729 -404.738377) (xy 188.260482 -404.75916) (xy 188.268096 -404.767959) (xy 188.288992 -404.778145)
			(xy 188.300614 -404.778718) (xy 188.38037 -404.778718) (xy 188.391997 -404.778141) (xy 188.412906 -404.767978)
			(xy 188.420502 -404.75916) (xy 188.437255 -404.738377) (xy 188.475609 -404.701247) (xy 188.518763 -404.669825)
			(xy 188.565877 -404.644726) (xy 188.616029 -404.62644) (xy 188.66824 -404.615323) (xy 188.721492 -404.611593)
			(xy 188.774744 -404.615323) (xy 188.826955 -404.62644) (xy 188.877107 -404.644726) (xy 188.924221 -404.669825)
			(xy 188.967375 -404.701247) (xy 189.005729 -404.738377) (xy 189.022482 -404.75916) (xy 189.030096 -404.767959)
			(xy 189.050992 -404.778145) (xy 189.062614 -404.778718) (xy 189.14237 -404.778718) (xy 189.153997 -404.778141)
			(xy 189.174906 -404.767978) (xy 189.182502 -404.75916) (xy 189.200682 -404.736667) (xy 189.242705 -404.696934)
			(xy 189.290243 -404.663998) (xy 189.342206 -404.638611) (xy 189.397405 -404.621357) (xy 189.454576 -404.612629)
			(xy 189.483492 -404.612094) (xy 189.510745 -404.612563) (xy 189.564696 -404.620319) (xy 189.616993 -404.635674)
			(xy 189.666574 -404.658316) (xy 189.712427 -404.687783) (xy 189.75362 -404.723476) (xy 189.789314 -404.764668)
			(xy 189.818782 -404.810521) (xy 189.841424 -404.860101) (xy 189.85678 -404.912399) (xy 189.864537 -404.966349)
			(xy 189.865 -404.993602) (xy 189.864483 -405.022519) (xy 189.855754 -405.07969) (xy 189.838495 -405.134889)
			(xy 189.813103 -405.186851) (xy 189.78016 -405.234385) (xy 189.740419 -405.276402) (xy 189.717934 -405.294592)
			(xy 189.709129 -405.302201) (xy 189.698947 -405.323101) (xy 189.698376 -405.334724) (xy 189.698376 -405.41448)
			(xy 189.698914 -405.426113) (xy 189.709101 -405.447024) (xy 189.717934 -405.454612) (xy 189.738719 -405.471363)
			(xy 189.77585 -405.509716) (xy 189.807272 -405.552871) (xy 189.832372 -405.599985) (xy 189.850658 -405.650137)
			(xy 189.861775 -405.702349) (xy 189.865505 -405.755601) (xy 189.861775 -405.808853) (xy 189.850658 -405.861065)
			(xy 189.832371 -405.911218) (xy 189.807271 -405.958331) (xy 189.775849 -406.001486) (xy 189.738717 -406.039839)
			(xy 189.717934 -406.056592) (xy 189.709129 -406.064201) (xy 189.698947 -406.085101) (xy 189.698376 -406.096724)
			(xy 189.698376 -406.17648) (xy 189.698914 -406.188113) (xy 189.709101 -406.209024) (xy 189.717934 -406.216612)
			(xy 189.74043 -406.234788) (xy 189.780163 -406.276812) (xy 189.8131 -406.32435) (xy 189.838486 -406.376314)
			(xy 189.855739 -406.431514) (xy 189.864466 -406.488685) (xy 189.865 -406.517602) (xy 189.864508 -406.544846)
			(xy 189.856751 -406.598778) (xy 189.841396 -406.651056) (xy 189.818755 -406.700617) (xy 189.78929 -406.746449)
			(xy 189.7536 -406.78762) (xy 189.712413 -406.823292) (xy 189.68974 -406.838404) (xy 189.68272 -406.843258)
			(xy 189.672174 -406.856663) (xy 189.666646 -406.8728) (xy 189.666372 -406.88133) (xy 189.666372 -406.966674)
			(xy 189.666669 -406.975196) (xy 189.67223 -406.991306) (xy 189.68275 -407.004716) (xy 189.68974 -407.0096)
			(xy 189.712409 -407.02472) (xy 189.753604 -407.060385) (xy 189.789302 -407.101552) (xy 189.818774 -407.147383)
			(xy 189.84142 -407.196944) (xy 189.856778 -407.249223) (xy 189.864537 -407.303157) (xy 189.865 -407.330402)
			(xy 189.864483 -407.359319) (xy 189.855754 -407.41649) (xy 189.838495 -407.471689) (xy 189.813103 -407.523651)
			(xy 189.78016 -407.571185) (xy 189.740419 -407.613202) (xy 189.717934 -407.631392) (xy 189.709129 -407.639001)
			(xy 189.698947 -407.659901) (xy 189.698376 -407.671524) (xy 189.698376 -407.75128) (xy 189.698914 -407.762913)
			(xy 189.709101 -407.783824) (xy 189.717934 -407.791412) (xy 189.74043 -407.809588) (xy 189.780163 -407.851612)
			(xy 189.8131 -407.89915) (xy 189.838486 -407.951114) (xy 189.855739 -408.006314) (xy 189.864466 -408.063485)
			(xy 189.865 -408.092402) (xy 189.864546 -408.119655) (xy 189.856789 -408.173607) (xy 189.841432 -408.225905)
			(xy 189.818789 -408.275486) (xy 189.78932 -408.32134) (xy 189.753625 -408.362532) (xy 189.712432 -408.398226)
			(xy 189.666577 -408.427694) (xy 189.616996 -408.450336) (xy 189.564697 -408.465691) (xy 189.510745 -408.473447)
			(xy 189.483492 -408.47391) (xy 189.454576 -408.47336) (xy 189.397405 -408.464642) (xy 189.342205 -408.447393)
			(xy 189.290242 -408.422007) (xy 189.242708 -408.389067) (xy 189.200692 -408.349329) (xy 189.182502 -408.326844)
			(xy 189.174894 -408.318038) (xy 189.153994 -408.307856) (xy 189.14237 -408.307286) (xy 189.062614 -408.307286)
			(xy 189.050986 -408.307852) (xy 189.030076 -408.318022) (xy 189.022482 -408.326844) (xy 189.005729 -408.347627)
			(xy 188.967375 -408.384757) (xy 188.924221 -408.416179) (xy 188.877107 -408.441278) (xy 188.826955 -408.459564)
			(xy 188.774744 -408.470681) (xy 188.721492 -408.474411) (xy 188.66824 -408.470681) (xy 188.616029 -408.459564)
			(xy 188.565877 -408.441278) (xy 188.518763 -408.416179) (xy 188.475609 -408.384757) (xy 188.437255 -408.347627)
			(xy 188.420502 -408.326844) (xy 188.412894 -408.318038) (xy 188.391994 -408.307856) (xy 188.38037 -408.307286)
			(xy 188.300614 -408.307286) (xy 188.288986 -408.307852) (xy 188.268076 -408.318022) (xy 188.260482 -408.326844)
			(xy 188.243729 -408.347627) (xy 188.205375 -408.384757) (xy 188.162221 -408.416179) (xy 188.115107 -408.441278)
			(xy 188.064955 -408.459564) (xy 188.012744 -408.470681) (xy 187.959492 -408.474411) (xy 187.90624 -408.470681)
			(xy 187.854029 -408.459564) (xy 187.803877 -408.441278) (xy 187.756763 -408.416179) (xy 187.713609 -408.384757)
			(xy 187.675255 -408.347627) (xy 187.658502 -408.326844) (xy 187.650894 -408.318038) (xy 187.629994 -408.307856)
			(xy 187.61837 -408.307286) (xy 187.538614 -408.307286) (xy 187.526986 -408.307852) (xy 187.506076 -408.318022)
			(xy 187.498482 -408.326844) (xy 187.481729 -408.347627) (xy 187.443375 -408.384757) (xy 187.400221 -408.416179)
			(xy 187.353107 -408.441278) (xy 187.302955 -408.459564) (xy 187.250744 -408.470681) (xy 187.197492 -408.474411)
			(xy 187.14424 -408.470681) (xy 187.092029 -408.459564) (xy 187.041877 -408.441278) (xy 186.994763 -408.416179)
			(xy 186.951609 -408.384757) (xy 186.913255 -408.347627) (xy 186.896502 -408.326844) (xy 186.888894 -408.318038)
			(xy 186.867994 -408.307856) (xy 186.85637 -408.307286) (xy 186.776614 -408.307286) (xy 186.764986 -408.307852)
			(xy 186.744076 -408.318022) (xy 186.736482 -408.326844) (xy 186.719729 -408.347627) (xy 186.681375 -408.384757)
			(xy 186.638221 -408.416179) (xy 186.591107 -408.441278) (xy 186.540955 -408.459564) (xy 186.488744 -408.470681)
			(xy 186.435492 -408.474411) (xy 186.38224 -408.470681) (xy 186.330029 -408.459564) (xy 186.279877 -408.441278)
			(xy 186.232763 -408.416179) (xy 186.189609 -408.384757) (xy 186.151255 -408.347627) (xy 186.134502 -408.326844)
			(xy 186.126894 -408.318038) (xy 186.105994 -408.307856) (xy 186.09437 -408.307286) (xy 186.014614 -408.307286)
			(xy 186.002986 -408.307852) (xy 185.982076 -408.318022) (xy 185.974482 -408.326844) (xy 185.956312 -408.349345)
			(xy 185.914287 -408.389077) (xy 185.866747 -408.422013) (xy 185.814782 -408.447398) (xy 185.759581 -408.464651)
			(xy 185.702409 -408.473377) (xy 185.673492 -408.47391) (xy 185.646241 -408.47343) (xy 185.592293 -408.465672)
			(xy 185.539998 -408.450316) (xy 185.490421 -408.427674) (xy 185.444571 -408.398207) (xy 185.403381 -408.362515)
			(xy 185.367689 -408.321324) (xy 185.338223 -408.275474) (xy 185.315582 -408.225896) (xy 185.300227 -408.173601)
			(xy 185.29247 -408.119653) (xy 185.291984 -408.092402) (xy 185.292472 -408.063484) (xy 185.301203 -408.00631)
			(xy 185.318465 -407.951109) (xy 185.343862 -407.899146) (xy 185.376812 -407.851614) (xy 185.416561 -407.8096)
			(xy 185.43905 -407.791412) (xy 185.44785 -407.783799) (xy 185.458036 -407.762902) (xy 185.458608 -407.75128)
			(xy 185.458608 -407.671524) (xy 185.458038 -407.659896) (xy 185.447871 -407.638987) (xy 185.43905 -407.631392)
			(xy 185.416552 -407.613218) (xy 185.37682 -407.571193) (xy 185.343884 -407.523654) (xy 185.318499 -407.47169)
			(xy 185.301245 -407.41649) (xy 185.292518 -407.359319) (xy 185.291984 -407.330402) (xy 185.292487 -407.303159)
			(xy 185.300242 -407.249228) (xy 185.315596 -407.19695) (xy 185.338236 -407.14739) (xy 185.367699 -407.101557)
			(xy 185.403387 -407.060385) (xy 185.444572 -407.024713) (xy 185.467244 -407.0096) (xy 185.474259 -407.004739)
			(xy 185.484807 -406.991338) (xy 185.490337 -406.975204) (xy 185.490612 -406.966674) (xy 185.490612 -406.88133)
			(xy 185.490319 -406.872808) (xy 185.484758 -406.856696) (xy 185.474235 -406.843287) (xy 185.467244 -406.838404)
			(xy 185.444573 -406.823287) (xy 185.403379 -406.787621) (xy 185.367682 -406.746452) (xy 185.33821 -406.700621)
			(xy 185.315565 -406.651061) (xy 185.300206 -406.598781) (xy 185.292448 -406.544847) (xy 185.291984 -406.517602)
			(xy 185.292472 -406.488684) (xy 185.301203 -406.43151) (xy 185.318465 -406.376309) (xy 185.343862 -406.324346)
			(xy 185.376812 -406.276814) (xy 185.416561 -406.2348) (xy 185.43905 -406.216612) (xy 185.44785 -406.208999)
			(xy 185.458036 -406.188102) (xy 185.458608 -406.17648) (xy 185.458608 -406.096724) (xy 185.458038 -406.085096)
			(xy 185.447871 -406.064187) (xy 185.43905 -406.056592) (xy 185.418269 -406.039836) (xy 185.38114 -406.001483)
			(xy 185.349719 -405.958328) (xy 185.324621 -405.911215) (xy 185.306335 -405.861063) (xy 185.295218 -405.808852)
			(xy 185.291488 -405.755601) (xy 182.972046 -405.755601) (xy 182.971447 -405.75967) (xy 182.955379 -405.813077)
			(xy 182.931707 -405.863574) (xy 182.900934 -405.910087) (xy 182.863717 -405.951624) (xy 182.820849 -405.987299)
			(xy 182.773243 -406.016353) (xy 182.721914 -406.038165) (xy 182.667957 -406.052271) (xy 182.61252 -406.058371)
			(xy 182.556786 -406.056334) (xy 182.501943 -406.046204) (xy 182.449159 -406.028197) (xy 182.399559 -406.002696)
			(xy 182.354201 -405.970245) (xy 182.314052 -405.931536) (xy 182.279966 -405.887393) (xy 182.25267 -405.838758)
			(xy 182.232747 -405.786667) (xy 182.220621 -405.73223) (xy 182.21655 -405.676608) (xy 181.078124 -405.676608)
			(xy 181.078124 -406.236932) (xy 184.161682 -406.236932) (xy 184.165753 -406.18131) (xy 184.177879 -406.126873)
			(xy 184.197802 -406.074782) (xy 184.225098 -406.026147) (xy 184.259184 -405.982004) (xy 184.299333 -405.943295)
			(xy 184.344691 -405.910844) (xy 184.394291 -405.885343) (xy 184.447075 -405.867336) (xy 184.501918 -405.857206)
			(xy 184.557652 -405.855169) (xy 184.613089 -405.861269) (xy 184.667046 -405.875375) (xy 184.718375 -405.897187)
			(xy 184.765981 -405.926241) (xy 184.808849 -405.961916) (xy 184.846066 -406.003453) (xy 184.876839 -406.049966)
			(xy 184.900511 -406.100463) (xy 184.916579 -406.15387) (xy 184.924699 -406.209046) (xy 184.925208 -406.236932)
			(xy 184.924699 -406.264818) (xy 184.916579 -406.319994) (xy 184.900511 -406.373401) (xy 184.876839 -406.423898)
			(xy 184.846066 -406.470411) (xy 184.808849 -406.511948) (xy 184.765981 -406.547623) (xy 184.718375 -406.576677)
			(xy 184.667046 -406.598489) (xy 184.613089 -406.612595) (xy 184.557652 -406.618695) (xy 184.501918 -406.616658)
			(xy 184.447075 -406.606528) (xy 184.394291 -406.588521) (xy 184.344691 -406.56302) (xy 184.299333 -406.530569)
			(xy 184.259184 -406.49186) (xy 184.225098 -406.447717) (xy 184.197802 -406.399082) (xy 184.177879 -406.346991)
			(xy 184.165753 -406.292554) (xy 184.161682 -406.236932) (xy 181.078124 -406.236932) (xy 181.078124 -406.399746)
			(xy 181.07914 -406.409398) (xy 181.080774 -406.416639) (xy 181.087624 -406.429799) (xy 181.092602 -406.435306)
			(xy 181.33949 -406.682194) (xy 181.344987 -406.687186) (xy 181.358151 -406.69404) (xy 181.365398 -406.695656)
			(xy 181.37505 -406.696672) (xy 182.96382 -406.696672) (xy 182.983839 -406.697124) (xy 183.023107 -406.70493)
			(xy 183.060094 -406.720258) (xy 183.093374 -406.742515) (xy 183.107838 -406.756362) (xy 185.59145 -409.239974)
			(xy 185.596953 -409.244953) (xy 185.610122 -409.251781) (xy 185.617358 -409.253436) (xy 185.62701 -409.254452)
			(xy 193.13779 -409.254452) (xy 193.147442 -409.253436) (xy 193.154686 -409.251808) (xy 193.167854 -409.244965)
			(xy 193.17335 -409.239974) (xy 193.609214 -408.80411) (xy 193.614205 -408.798612) (xy 193.621056 -408.785447)
			(xy 193.622676 -408.778202) (xy 193.623692 -408.76855) (xy 193.623692 -405.589994) (xy 193.623248 -405.580415)
			(xy 193.616143 -405.562618) (xy 193.603001 -405.548672) (xy 193.594482 -405.544274) (xy 193.504566 -405.507952)
			(xy 193.4973 -405.505346) (xy 193.481915 -405.50418) (xy 193.47434 -405.505666) (xy 193.467228 -405.50719)
			(xy 193.454274 -405.514302) (xy 193.448686 -405.520144) (xy 193.430607 -405.538499) (xy 193.390367 -405.570671)
			(xy 193.346165 -405.597139) (xy 193.298805 -405.61742) (xy 193.249147 -405.631146) (xy 193.198094 -405.638067)
			(xy 193.172334 -405.638508) (xy 193.14508 -405.638047) (xy 193.091125 -405.630294) (xy 193.038823 -405.614941)
			(xy 192.989239 -405.5923) (xy 192.943381 -405.562833) (xy 192.902185 -405.52714) (xy 192.866487 -405.485946)
			(xy 192.837016 -405.440091) (xy 192.814371 -405.390509) (xy 192.799013 -405.338208) (xy 192.791255 -405.284254)
			(xy 192.791255 -405.229746) (xy 192.799013 -405.175792) (xy 192.814371 -405.123491) (xy 192.837016 -405.073909)
			(xy 192.866487 -405.028054) (xy 192.902185 -404.98686) (xy 192.943381 -404.951167) (xy 192.989239 -404.9217)
			(xy 193.038823 -404.899059) (xy 193.091125 -404.883706) (xy 193.14508 -404.875953) (xy 193.172334 -404.875492)
			(xy 193.198094 -404.875917) (xy 193.249144 -404.88285) (xy 193.298799 -404.896584) (xy 193.346156 -404.916871)
			(xy 193.390355 -404.943341) (xy 193.430593 -404.975515) (xy 193.448686 -404.993856) (xy 193.454274 -404.999698)
			(xy 193.460878 -405.003254) (xy 193.464075 -405.004932) (xy 193.470831 -405.007484) (xy 193.47434 -405.008334)
			(xy 193.481916 -405.009808) (xy 193.4973 -405.008651) (xy 193.504566 -405.006048) (xy 193.594482 -404.969726)
			(xy 193.602984 -404.965293) (xy 193.61614 -404.951365) (xy 193.623272 -404.933583) (xy 193.623692 -404.924006)
			(xy 193.623692 -401.743926) (xy 193.624149 -401.723909) (xy 193.631961 -401.684644) (xy 193.647291 -401.64766)
			(xy 193.669547 -401.614382) (xy 193.683382 -401.599908) (xy 194.378326 -400.904964) (xy 194.39278 -400.891223)
			(xy 194.425948 -400.869091) (xy 194.462791 -400.853842) (xy 194.501899 -400.846063) (xy 194.521836 -400.845528)
			(xy 195.16979 -400.845528) (xy 195.189726 -400.84604) (xy 195.228829 -400.853846) (xy 195.265668 -400.869103)
			(xy 195.29884 -400.89123) (xy 195.3133 -400.904964) (xy 195.671186 -401.263104) (xy 195.677529 -401.268784)
			(xy 195.692976 -401.275922) (xy 195.701412 -401.277074) (xy 195.706492 -401.277328) (xy 195.83527 -401.277328)
			(xy 195.855207 -401.277838) (xy 195.894312 -401.285641) (xy 195.931154 -401.300895) (xy 195.964328 -401.323021)
			(xy 195.97878 -401.336764) (xy 196.562218 -401.920202) (xy 197.73214 -401.920202) (xy 197.736211 -401.86458)
			(xy 197.748337 -401.810143) (xy 197.76826 -401.758052) (xy 197.795556 -401.709417) (xy 197.829642 -401.665274)
			(xy 197.869791 -401.626565) (xy 197.915149 -401.594114) (xy 197.964749 -401.568613) (xy 198.017533 -401.550606)
			(xy 198.072376 -401.540476) (xy 198.12811 -401.538439) (xy 198.183547 -401.544539) (xy 198.237504 -401.558645)
			(xy 198.288833 -401.580457) (xy 198.336439 -401.609511) (xy 198.379307 -401.645186) (xy 198.416524 -401.686723)
			(xy 198.447297 -401.733236) (xy 198.470969 -401.783733) (xy 198.487037 -401.83714) (xy 198.495157 -401.892316)
			(xy 198.495666 -401.920202) (xy 200.55154 -401.920202) (xy 200.555611 -401.86458) (xy 200.567737 -401.810143)
			(xy 200.58766 -401.758052) (xy 200.614956 -401.709417) (xy 200.649042 -401.665274) (xy 200.689191 -401.626565)
			(xy 200.734549 -401.594114) (xy 200.784149 -401.568613) (xy 200.836933 -401.550606) (xy 200.891776 -401.540476)
			(xy 200.94751 -401.538439) (xy 201.002947 -401.544539) (xy 201.056904 -401.558645) (xy 201.108233 -401.580457)
			(xy 201.155839 -401.609511) (xy 201.198707 -401.645186) (xy 201.235924 -401.686723) (xy 201.266697 -401.733236)
			(xy 201.290369 -401.783733) (xy 201.306437 -401.83714) (xy 201.314557 -401.892316) (xy 201.315066 -401.920202)
			(xy 201.314557 -401.948088) (xy 201.306437 -402.003264) (xy 201.290369 -402.056671) (xy 201.266697 -402.107168)
			(xy 201.235924 -402.153681) (xy 201.198707 -402.195218) (xy 201.155839 -402.230893) (xy 201.108233 -402.259947)
			(xy 201.056904 -402.281759) (xy 201.002947 -402.295865) (xy 200.94751 -402.301965) (xy 200.891776 -402.299928)
			(xy 200.836933 -402.289798) (xy 200.784149 -402.271791) (xy 200.734549 -402.24629) (xy 200.689191 -402.213839)
			(xy 200.649042 -402.17513) (xy 200.614956 -402.130987) (xy 200.58766 -402.082352) (xy 200.567737 -402.030261)
			(xy 200.555611 -401.975824) (xy 200.55154 -401.920202) (xy 198.495666 -401.920202) (xy 198.495157 -401.948088)
			(xy 198.487037 -402.003264) (xy 198.470969 -402.056671) (xy 198.447297 -402.107168) (xy 198.416524 -402.153681)
			(xy 198.379307 -402.195218) (xy 198.336439 -402.230893) (xy 198.288833 -402.259947) (xy 198.237504 -402.281759)
			(xy 198.183547 -402.295865) (xy 198.12811 -402.301965) (xy 198.072376 -402.299928) (xy 198.017533 -402.289798)
			(xy 197.964749 -402.271791) (xy 197.915149 -402.24629) (xy 197.869791 -402.213839) (xy 197.829642 -402.17513)
			(xy 197.795556 -402.130987) (xy 197.76826 -402.082352) (xy 197.748337 -402.030261) (xy 197.736211 -401.975824)
			(xy 197.73214 -401.920202) (xy 196.562218 -401.920202) (xy 196.846698 -402.204682) (xy 196.860498 -402.219182)
			(xy 196.882731 -402.252462) (xy 196.898051 -402.289437) (xy 196.905871 -402.328689) (xy 196.906388 -402.3487)
			(xy 196.906388 -402.820632) (xy 196.906642 -402.826982) (xy 196.908173 -402.836066) (xy 196.916766 -402.852346)
			(xy 196.923406 -402.858732) (xy 196.927216 -402.86178) (xy 196.949276 -402.878437) (xy 196.988809 -402.91707)
			(xy 197.02235 -402.961007) (xy 197.049194 -403.009326) (xy 197.06878 -403.061015) (xy 197.080698 -403.11499)
			(xy 197.084696 -403.170121) (xy 197.080838 -403.223222) (xy 197.73214 -403.223222) (xy 197.736211 -403.1676)
			(xy 197.748337 -403.113163) (xy 197.76826 -403.061072) (xy 197.795556 -403.012437) (xy 197.829642 -402.968294)
			(xy 197.869791 -402.929585) (xy 197.915149 -402.897134) (xy 197.964749 -402.871633) (xy 198.017533 -402.853626)
			(xy 198.072376 -402.843496) (xy 198.12811 -402.841459) (xy 198.183547 -402.847559) (xy 198.237504 -402.861665)
			(xy 198.288833 -402.883477) (xy 198.336439 -402.912531) (xy 198.379307 -402.948206) (xy 198.416524 -402.989743)
			(xy 198.447297 -403.036256) (xy 198.470969 -403.086753) (xy 198.487037 -403.14016) (xy 198.495157 -403.195336)
			(xy 198.495666 -403.223222) (xy 199.15454 -403.223222) (xy 199.158611 -403.1676) (xy 199.170737 -403.113163)
			(xy 199.19066 -403.061072) (xy 199.217956 -403.012437) (xy 199.252042 -402.968294) (xy 199.292191 -402.929585)
			(xy 199.337549 -402.897134) (xy 199.387149 -402.871633) (xy 199.439933 -402.853626) (xy 199.494776 -402.843496)
			(xy 199.55051 -402.841459) (xy 199.605947 -402.847559) (xy 199.659904 -402.861665) (xy 199.711233 -402.883477)
			(xy 199.758839 -402.912531) (xy 199.801707 -402.948206) (xy 199.838924 -402.989743) (xy 199.869697 -403.036256)
			(xy 199.893369 -403.086753) (xy 199.909437 -403.14016) (xy 199.917557 -403.195336) (xy 199.918066 -403.223222)
			(xy 200.55154 -403.223222) (xy 200.555611 -403.1676) (xy 200.567737 -403.113163) (xy 200.58766 -403.061072)
			(xy 200.614956 -403.012437) (xy 200.649042 -402.968294) (xy 200.689191 -402.929585) (xy 200.734549 -402.897134)
			(xy 200.784149 -402.871633) (xy 200.836933 -402.853626) (xy 200.891776 -402.843496) (xy 200.94751 -402.841459)
			(xy 201.002947 -402.847559) (xy 201.056904 -402.861665) (xy 201.108233 -402.883477) (xy 201.155839 -402.912531)
			(xy 201.198707 -402.948206) (xy 201.235924 -402.989743) (xy 201.266697 -403.036256) (xy 201.290369 -403.086753)
			(xy 201.306437 -403.14016) (xy 201.314557 -403.195336) (xy 201.315066 -403.223222) (xy 201.314557 -403.251108)
			(xy 201.306437 -403.306284) (xy 201.290369 -403.359691) (xy 201.266697 -403.410188) (xy 201.235924 -403.456701)
			(xy 201.198707 -403.498238) (xy 201.155839 -403.533913) (xy 201.108233 -403.562967) (xy 201.056904 -403.584779)
			(xy 201.002947 -403.598885) (xy 200.94751 -403.604985) (xy 200.891776 -403.602948) (xy 200.836933 -403.592818)
			(xy 200.784149 -403.574811) (xy 200.734549 -403.54931) (xy 200.689191 -403.516859) (xy 200.649042 -403.47815)
			(xy 200.614956 -403.434007) (xy 200.58766 -403.385372) (xy 200.567737 -403.333281) (xy 200.555611 -403.278844)
			(xy 200.55154 -403.223222) (xy 199.918066 -403.223222) (xy 199.917557 -403.251108) (xy 199.909437 -403.306284)
			(xy 199.893369 -403.359691) (xy 199.869697 -403.410188) (xy 199.838924 -403.456701) (xy 199.801707 -403.498238)
			(xy 199.758839 -403.533913) (xy 199.711233 -403.562967) (xy 199.659904 -403.584779) (xy 199.605947 -403.598885)
			(xy 199.55051 -403.604985) (xy 199.494776 -403.602948) (xy 199.439933 -403.592818) (xy 199.387149 -403.574811)
			(xy 199.337549 -403.54931) (xy 199.292191 -403.516859) (xy 199.252042 -403.47815) (xy 199.217956 -403.434007)
			(xy 199.19066 -403.385372) (xy 199.170737 -403.333281) (xy 199.158611 -403.278844) (xy 199.15454 -403.223222)
			(xy 198.495666 -403.223222) (xy 198.495157 -403.251108) (xy 198.487037 -403.306284) (xy 198.470969 -403.359691)
			(xy 198.447297 -403.410188) (xy 198.416524 -403.456701) (xy 198.379307 -403.498238) (xy 198.336439 -403.533913)
			(xy 198.288833 -403.562967) (xy 198.237504 -403.584779) (xy 198.183547 -403.598885) (xy 198.12811 -403.604985)
			(xy 198.072376 -403.602948) (xy 198.017533 -403.592818) (xy 197.964749 -403.574811) (xy 197.915149 -403.54931)
			(xy 197.869791 -403.516859) (xy 197.829642 -403.47815) (xy 197.795556 -403.434007) (xy 197.76826 -403.385372)
			(xy 197.748337 -403.333281) (xy 197.736211 -403.278844) (xy 197.73214 -403.223222) (xy 197.080838 -403.223222)
			(xy 197.080691 -403.225251) (xy 197.068768 -403.279226) (xy 197.049176 -403.330913) (xy 197.022326 -403.379229)
			(xy 196.988781 -403.423162) (xy 196.949243 -403.46179) (xy 196.927216 -403.478492) (xy 196.923406 -403.48154)
			(xy 196.916772 -403.487933) (xy 196.908159 -403.504204) (xy 196.906642 -403.51329) (xy 196.906388 -403.51964)
			(xy 196.906388 -403.83968) (xy 196.90593 -403.859697) (xy 196.898116 -403.898961) (xy 196.882785 -403.935942)
			(xy 196.860527 -403.969218) (xy 196.846698 -403.983698) (xy 195.73494 -405.095456) (xy 195.732232 -405.098305)
			(xy 195.727634 -405.104681) (xy 195.725796 -405.108156) (xy 195.723214 -405.113583) (xy 195.720394 -405.125263)
			(xy 195.720208 -405.13127) (xy 195.720208 -407.297389) (xy 196.861678 -407.297389) (xy 196.865409 -407.244136)
			(xy 196.876528 -407.191922) (xy 196.894816 -407.141769) (xy 196.919917 -407.094654) (xy 196.951341 -407.051499)
			(xy 196.988474 -407.013145) (xy 197.009258 -406.996392) (xy 197.018069 -406.988789) (xy 197.028248 -406.967885)
			(xy 197.028816 -406.95626) (xy 197.028816 -406.876504) (xy 197.028255 -406.864875) (xy 197.018081 -406.843966)
			(xy 197.009258 -406.836372) (xy 196.988457 -406.81964) (xy 196.951327 -406.781284) (xy 196.919905 -406.738127)
			(xy 196.894807 -406.691011) (xy 196.876521 -406.640856) (xy 196.865406 -406.588642) (xy 196.861678 -406.535389)
			(xy 196.865409 -406.482136) (xy 196.876528 -406.429922) (xy 196.894816 -406.379769) (xy 196.919917 -406.332654)
			(xy 196.951341 -406.289499) (xy 196.988474 -406.251145) (xy 197.009258 -406.234392) (xy 197.018069 -406.226789)
			(xy 197.028248 -406.205885) (xy 197.028816 -406.19426) (xy 197.028816 -406.114504) (xy 197.028255 -406.102875)
			(xy 197.018081 -406.081966) (xy 197.009258 -406.074372) (xy 196.988457 -406.05764) (xy 196.951327 -406.019284)
			(xy 196.919905 -405.976127) (xy 196.894807 -405.929011) (xy 196.876521 -405.878856) (xy 196.865406 -405.826642)
			(xy 196.861678 -405.773389) (xy 196.865409 -405.720136) (xy 196.876528 -405.667922) (xy 196.894816 -405.617769)
			(xy 196.919917 -405.570654) (xy 196.951341 -405.527499) (xy 196.988474 -405.489145) (xy 197.009258 -405.472392)
			(xy 197.018069 -405.464789) (xy 197.028248 -405.443885) (xy 197.028816 -405.43226) (xy 197.028816 -405.352504)
			(xy 197.028255 -405.340875) (xy 197.018081 -405.319966) (xy 197.009258 -405.312372) (xy 196.986752 -405.294207)
			(xy 196.94702 -405.252181) (xy 196.914085 -405.20464) (xy 196.888701 -405.152674) (xy 196.871449 -405.097472)
			(xy 196.862725 -405.040299) (xy 196.862192 -405.011382) (xy 196.862661 -404.98413) (xy 196.87042 -404.930182)
			(xy 196.885777 -404.877887) (xy 196.908421 -404.82831) (xy 196.937889 -404.782459) (xy 196.973582 -404.741269)
			(xy 197.014774 -404.705578) (xy 197.060625 -404.676112) (xy 197.110204 -404.653471) (xy 197.1625 -404.638116)
			(xy 197.216448 -404.63036) (xy 197.2437 -404.629874) (xy 197.272618 -404.630364) (xy 197.329792 -404.639095)
			(xy 197.384993 -404.656357) (xy 197.436955 -404.681754) (xy 197.484488 -404.714703) (xy 197.526502 -404.754451)
			(xy 197.54469 -404.77694) (xy 197.552305 -404.785739) (xy 197.5732 -404.795926) (xy 197.584822 -404.796498)
			(xy 197.664578 -404.796498) (xy 197.676207 -404.795932) (xy 197.697116 -404.785762) (xy 197.70471 -404.77694)
			(xy 197.721463 -404.756157) (xy 197.759817 -404.719027) (xy 197.802971 -404.687605) (xy 197.850085 -404.662506)
			(xy 197.900237 -404.64422) (xy 197.952448 -404.633103) (xy 198.0057 -404.629373) (xy 198.058952 -404.633103)
			(xy 198.111163 -404.64422) (xy 198.161315 -404.662506) (xy 198.208429 -404.687605) (xy 198.251583 -404.719027)
			(xy 198.289937 -404.756157) (xy 198.30669 -404.77694) (xy 198.314305 -404.785739) (xy 198.3352 -404.795926)
			(xy 198.346822 -404.796498) (xy 198.426578 -404.796498) (xy 198.438207 -404.795932) (xy 198.459116 -404.785762)
			(xy 198.46671 -404.77694) (xy 198.483463 -404.756157) (xy 198.521817 -404.719027) (xy 198.564971 -404.687605)
			(xy 198.612085 -404.662506) (xy 198.662237 -404.64422) (xy 198.714448 -404.633103) (xy 198.7677 -404.629373)
			(xy 198.820952 -404.633103) (xy 198.873163 -404.64422) (xy 198.923315 -404.662506) (xy 198.970429 -404.687605)
			(xy 199.013583 -404.719027) (xy 199.051937 -404.756157) (xy 199.06869 -404.77694) (xy 199.076305 -404.785739)
			(xy 199.0972 -404.795926) (xy 199.108822 -404.796498) (xy 199.188578 -404.796498) (xy 199.200207 -404.795932)
			(xy 199.221116 -404.785762) (xy 199.22871 -404.77694) (xy 199.245463 -404.756157) (xy 199.283817 -404.719027)
			(xy 199.326971 -404.687605) (xy 199.374085 -404.662506) (xy 199.424237 -404.64422) (xy 199.476448 -404.633103)
			(xy 199.5297 -404.629373) (xy 199.582952 -404.633103) (xy 199.635163 -404.64422) (xy 199.685315 -404.662506)
			(xy 199.732429 -404.687605) (xy 199.775583 -404.719027) (xy 199.813937 -404.756157) (xy 199.83069 -404.77694)
			(xy 199.838305 -404.785739) (xy 199.8592 -404.795926) (xy 199.870822 -404.796498) (xy 199.950578 -404.796498)
			(xy 199.962207 -404.795932) (xy 199.983116 -404.785762) (xy 199.99071 -404.77694) (xy 200.007463 -404.756157)
			(xy 200.045817 -404.719027) (xy 200.088971 -404.687605) (xy 200.136085 -404.662506) (xy 200.186237 -404.64422)
			(xy 200.238448 -404.633103) (xy 200.2917 -404.629373) (xy 200.344952 -404.633103) (xy 200.397163 -404.64422)
			(xy 200.447315 -404.662506) (xy 200.494429 -404.687605) (xy 200.537583 -404.719027) (xy 200.575937 -404.756157)
			(xy 200.59269 -404.77694) (xy 200.600305 -404.785739) (xy 200.6212 -404.795926) (xy 200.632822 -404.796498)
			(xy 200.712578 -404.796498) (xy 200.724207 -404.795932) (xy 200.745116 -404.785762) (xy 200.75271 -404.77694)
			(xy 200.770905 -404.75446) (xy 200.812923 -404.714723) (xy 200.860457 -404.681782) (xy 200.912417 -404.656393)
			(xy 200.967615 -404.639136) (xy 201.024784 -404.630408) (xy 201.0537 -404.629874) (xy 201.08095 -404.630378)
			(xy 201.134897 -404.638134) (xy 201.18719 -404.653488) (xy 201.236766 -404.676128) (xy 201.282615 -404.705592)
			(xy 201.323805 -404.741282) (xy 201.359497 -404.78247) (xy 201.388964 -404.828318) (xy 201.411606 -404.877893)
			(xy 201.426962 -404.930186) (xy 201.434721 -404.984132) (xy 201.435208 -405.011382) (xy 201.434712 -405.0403)
			(xy 201.425983 -405.097474) (xy 201.408723 -405.152675) (xy 201.383327 -405.204637) (xy 201.350378 -405.25217)
			(xy 201.310631 -405.294184) (xy 201.288142 -405.312372) (xy 201.279348 -405.319991) (xy 201.269159 -405.340883)
			(xy 201.268584 -405.352504) (xy 201.268584 -405.43226) (xy 201.269109 -405.443893) (xy 201.279308 -405.464802)
			(xy 201.288142 -405.472392) (xy 201.308907 -405.489167) (xy 201.346037 -405.527517) (xy 201.377459 -405.570669)
			(xy 201.402558 -405.61778) (xy 201.420845 -405.66793) (xy 201.431963 -405.72014) (xy 201.435694 -405.773389)
			(xy 201.431966 -405.826639) (xy 201.420851 -405.878849) (xy 201.402567 -405.928999) (xy 201.37747 -405.976112)
			(xy 201.346052 -406.019266) (xy 201.308924 -406.057619) (xy 201.288142 -406.074372) (xy 201.279348 -406.081991)
			(xy 201.269159 -406.102883) (xy 201.268584 -406.114504) (xy 201.268584 -406.19426) (xy 201.269109 -406.205893)
			(xy 201.279308 -406.226802) (xy 201.288142 -406.234392) (xy 201.308907 -406.251167) (xy 201.346037 -406.289517)
			(xy 201.377459 -406.332669) (xy 201.402558 -406.37978) (xy 201.420845 -406.42993) (xy 201.431963 -406.48214)
			(xy 201.435694 -406.535389) (xy 201.431966 -406.588639) (xy 201.420851 -406.640849) (xy 201.402567 -406.690999)
			(xy 201.37747 -406.738112) (xy 201.346052 -406.781266) (xy 201.308924 -406.819619) (xy 201.288142 -406.836372)
			(xy 201.279348 -406.843991) (xy 201.269159 -406.864883) (xy 201.268584 -406.876504) (xy 201.268584 -406.95626)
			(xy 201.269109 -406.967893) (xy 201.279308 -406.988802) (xy 201.288142 -406.996392) (xy 201.308907 -407.013167)
			(xy 201.346037 -407.051517) (xy 201.377459 -407.094669) (xy 201.402558 -407.14178) (xy 201.420845 -407.19193)
			(xy 201.431963 -407.24414) (xy 201.435694 -407.297389) (xy 201.431966 -407.350639) (xy 201.420851 -407.402849)
			(xy 201.402567 -407.452999) (xy 201.37747 -407.500112) (xy 201.346052 -407.543266) (xy 201.308924 -407.581619)
			(xy 201.288142 -407.598372) (xy 201.279348 -407.605991) (xy 201.269159 -407.626883) (xy 201.268584 -407.638504)
			(xy 201.268584 -407.71826) (xy 201.269109 -407.729893) (xy 201.279308 -407.750802) (xy 201.288142 -407.758392)
			(xy 201.31063 -407.776577) (xy 201.350363 -407.818599) (xy 201.383301 -407.866136) (xy 201.408688 -407.918098)
			(xy 201.425943 -407.973296) (xy 201.434673 -408.030466) (xy 201.435208 -408.059382) (xy 201.434728 -408.086634)
			(xy 201.426973 -408.140585) (xy 201.41162 -408.192882) (xy 201.388979 -408.242462) (xy 201.359513 -408.288316)
			(xy 201.323821 -408.329508) (xy 201.28263 -408.365202) (xy 201.236778 -408.394671) (xy 201.187199 -408.417313)
			(xy 201.134902 -408.43267) (xy 201.080952 -408.440427) (xy 201.0537 -408.44089) (xy 201.024783 -408.440375)
			(xy 200.967611 -408.431646) (xy 200.912412 -408.414388) (xy 200.860451 -408.388995) (xy 200.812917 -408.356051)
			(xy 200.7709 -408.31631) (xy 200.75271 -408.293824) (xy 200.745102 -408.285019) (xy 200.724201 -408.274837)
			(xy 200.712578 -408.274266) (xy 200.632822 -408.274266) (xy 200.62119 -408.274809) (xy 200.600279 -408.284993)
			(xy 200.59269 -408.293824) (xy 200.575937 -408.314607) (xy 200.537583 -408.351737) (xy 200.494429 -408.383159)
			(xy 200.447315 -408.408258) (xy 200.397163 -408.426544) (xy 200.344952 -408.437661) (xy 200.2917 -408.441391)
			(xy 200.238448 -408.437661) (xy 200.186237 -408.426544) (xy 200.136085 -408.408258) (xy 200.088971 -408.383159)
			(xy 200.045817 -408.351737) (xy 200.007463 -408.314607) (xy 199.99071 -408.293824) (xy 199.983102 -408.285019)
			(xy 199.962201 -408.274837) (xy 199.950578 -408.274266) (xy 199.870822 -408.274266) (xy 199.85919 -408.274809)
			(xy 199.838279 -408.284993) (xy 199.83069 -408.293824) (xy 199.813937 -408.314607) (xy 199.775583 -408.351737)
			(xy 199.732429 -408.383159) (xy 199.685315 -408.408258) (xy 199.635163 -408.426544) (xy 199.582952 -408.437661)
			(xy 199.5297 -408.441391) (xy 199.476448 -408.437661) (xy 199.424237 -408.426544) (xy 199.374085 -408.408258)
			(xy 199.326971 -408.383159) (xy 199.283817 -408.351737) (xy 199.245463 -408.314607) (xy 199.22871 -408.293824)
			(xy 199.221102 -408.285019) (xy 199.200201 -408.274837) (xy 199.188578 -408.274266) (xy 199.108822 -408.274266)
			(xy 199.09719 -408.274809) (xy 199.076279 -408.284993) (xy 199.06869 -408.293824) (xy 199.051937 -408.314607)
			(xy 199.013583 -408.351737) (xy 198.970429 -408.383159) (xy 198.923315 -408.408258) (xy 198.873163 -408.426544)
			(xy 198.820952 -408.437661) (xy 198.7677 -408.441391) (xy 198.714448 -408.437661) (xy 198.662237 -408.426544)
			(xy 198.612085 -408.408258) (xy 198.564971 -408.383159) (xy 198.521817 -408.351737) (xy 198.483463 -408.314607)
			(xy 198.46671 -408.293824) (xy 198.459102 -408.285019) (xy 198.438201 -408.274837) (xy 198.426578 -408.274266)
			(xy 198.346822 -408.274266) (xy 198.33519 -408.274809) (xy 198.314279 -408.284993) (xy 198.30669 -408.293824)
			(xy 198.289937 -408.314607) (xy 198.251583 -408.351737) (xy 198.208429 -408.383159) (xy 198.161315 -408.408258)
			(xy 198.111163 -408.426544) (xy 198.058952 -408.437661) (xy 198.0057 -408.441391) (xy 197.952448 -408.437661)
			(xy 197.900237 -408.426544) (xy 197.850085 -408.408258) (xy 197.802971 -408.383159) (xy 197.759817 -408.351737)
			(xy 197.721463 -408.314607) (xy 197.70471 -408.293824) (xy 197.697102 -408.285019) (xy 197.676201 -408.274837)
			(xy 197.664578 -408.274266) (xy 197.584822 -408.274266) (xy 197.57319 -408.274809) (xy 197.552279 -408.284993)
			(xy 197.54469 -408.293824) (xy 197.526511 -408.316317) (xy 197.484488 -408.356051) (xy 197.43695 -408.388988)
			(xy 197.384987 -408.414374) (xy 197.329787 -408.431629) (xy 197.272617 -408.440356) (xy 197.2437 -408.44089)
			(xy 197.216446 -408.440445) (xy 197.162494 -408.432687) (xy 197.110195 -408.41733) (xy 197.060613 -408.394686)
			(xy 197.014759 -408.365217) (xy 196.973566 -408.329521) (xy 196.937872 -408.288326) (xy 196.908405 -408.242471)
			(xy 196.885763 -408.192889) (xy 196.870409 -408.140589) (xy 196.862654 -408.086636) (xy 196.862192 -408.059382)
			(xy 196.862734 -408.030466) (xy 196.871454 -407.973294) (xy 196.888704 -407.918094) (xy 196.914091 -407.866131)
			(xy 196.947033 -407.818597) (xy 196.986773 -407.776581) (xy 197.009258 -407.758392) (xy 197.018069 -407.750789)
			(xy 197.028248 -407.729885) (xy 197.028816 -407.71826) (xy 197.028816 -407.638504) (xy 197.028255 -407.626875)
			(xy 197.018081 -407.605966) (xy 197.009258 -407.598372) (xy 196.988457 -407.58164) (xy 196.951327 -407.543284)
			(xy 196.919905 -407.500127) (xy 196.894807 -407.453011) (xy 196.876521 -407.402856) (xy 196.865406 -407.350642)
			(xy 196.861678 -407.297389) (xy 195.720208 -407.297389) (xy 195.720208 -408.78887) (xy 195.720678 -408.798743)
			(xy 195.728135 -408.817027) (xy 195.734686 -408.82443) (xy 195.983606 -409.07335) (xy 196.224906 -409.314904)
			(xy 196.231196 -409.320553) (xy 196.246506 -409.327701) (xy 196.254878 -409.328874) (xy 196.260212 -409.329128)
			(xy 202.090528 -409.329128) (xy 202.096878 -409.32862) (xy 202.105126 -409.32728) (xy 202.120163 -409.320021)
			(xy 202.126342 -409.314396) (xy 202.564746 -408.875738) (xy 202.565254 -408.87523) (xy 202.571834 -408.867848)
			(xy 202.579278 -408.849549) (xy 202.579732 -408.83967) (xy 202.579732 -402.928074) (xy 202.580185 -402.908055)
			(xy 202.587991 -402.868786) (xy 202.603316 -402.831798) (xy 202.625571 -402.798516) (xy 202.639422 -402.784056)
			(xy 203.045314 -402.378164) (xy 203.059768 -402.364423) (xy 203.092935 -402.342288) (xy 203.129778 -402.327037)
			(xy 203.168887 -402.319256) (xy 203.188824 -402.318728) (xy 204.42809 -402.318728) (xy 204.434186 -402.318474)
			(xy 204.442448 -402.317185) (xy 204.457497 -402.309913) (xy 204.46365 -402.30425) (xy 204.726286 -402.04136)
			(xy 204.996796 -401.77085) (xy 205.003193 -401.763764) (xy 205.010677 -401.746216) (xy 205.011272 -401.727148)
			(xy 205.00848 -401.718018) (xy 205.007464 -401.715732) (xy 205.004309 -401.708743) (xy 204.994624 -401.696863)
			(xy 204.988414 -401.692364) (xy 204.982572 -401.688554) (xy 204.968602 -401.684236) (xy 203.411328 -401.684236)
			(xy 203.402304 -401.684641) (xy 203.385399 -401.690972) (xy 203.371725 -401.702757) (xy 203.362968 -401.718542)
			(xy 203.36129 -401.727416) (xy 203.356761 -401.754147) (xy 203.341137 -401.806061) (xy 203.31832 -401.855241)
			(xy 203.288771 -401.900695) (xy 203.253084 -401.941508) (xy 203.211979 -401.976857) (xy 203.166283 -402.006031)
			(xy 203.116917 -402.028442) (xy 203.064876 -402.043638) (xy 203.011207 -402.051314) (xy 202.9841 -402.051774)
			(xy 202.983846 -402.051774) (xy 202.953003 -402.051156) (xy 202.892124 -402.041194) (xy 202.862688 -402.031962)
			(xy 202.856636 -402.03016) (xy 202.844045 -402.029272) (xy 202.837796 -402.030184) (xy 202.825604 -402.032216)
			(xy 202.74661 -402.094192) (xy 202.737897 -402.102527) (xy 202.728769 -402.124807) (xy 202.729084 -402.136864)
			(xy 202.729084 -402.137118) (xy 202.730608 -402.170138) (xy 202.73012 -402.197389) (xy 202.722358 -402.251334)
			(xy 202.706998 -402.303627) (xy 202.684353 -402.353201) (xy 202.654883 -402.399048) (xy 202.619189 -402.440234)
			(xy 202.577997 -402.475921) (xy 202.532145 -402.505384) (xy 202.482567 -402.52802) (xy 202.430273 -402.543371)
			(xy 202.376325 -402.551124) (xy 202.321824 -402.55112) (xy 202.267878 -402.543361) (xy 202.215585 -402.528003)
			(xy 202.16601 -402.505359) (xy 202.120162 -402.475891) (xy 202.078975 -402.440198) (xy 202.043286 -402.399007)
			(xy 202.013823 -402.353156) (xy 201.991184 -402.303579) (xy 201.975831 -402.251285) (xy 201.968077 -402.197338)
			(xy 201.968079 -402.142837) (xy 201.975837 -402.08889) (xy 201.991193 -402.036597) (xy 202.013835 -401.987021)
			(xy 202.043301 -401.941173) (xy 202.078993 -401.899984) (xy 202.120183 -401.864294) (xy 202.166033 -401.834829)
			(xy 202.215609 -401.812188) (xy 202.267903 -401.796834) (xy 202.321849 -401.789078) (xy 202.3491 -401.78863)
			(xy 202.349354 -401.78863) (xy 202.380197 -401.789248) (xy 202.441076 -401.79921) (xy 202.470512 -401.808442)
			(xy 202.476564 -401.810243) (xy 202.489155 -401.811132) (xy 202.495404 -401.81022) (xy 202.507596 -401.808188)
			(xy 202.58659 -401.746212) (xy 202.595304 -401.737877) (xy 202.604434 -401.715597) (xy 202.604116 -401.70354)
			(xy 202.604116 -401.703286) (xy 202.602592 -401.670266) (xy 202.603018 -401.644419) (xy 202.609991 -401.593198)
			(xy 202.623818 -401.543388) (xy 202.644247 -401.495902) (xy 202.670902 -401.45161) (xy 202.703295 -401.411324)
			(xy 202.740832 -401.375783) (xy 202.761596 -401.360386) (xy 202.76936 -401.353427) (xy 202.778926 -401.334928)
			(xy 202.780138 -401.324572) (xy 202.780392 -401.321016) (xy 202.780392 -401.184872) (xy 202.779913 -401.174907)
			(xy 202.772334 -401.156473) (xy 202.76566 -401.149058) (xy 201.774044 -400.157442) (xy 201.766644 -400.1506)
			(xy 201.748046 -400.142879) (xy 201.737976 -400.142456) (xy 201.24039 -400.142456) (xy 201.22994 -400.142904)
			(xy 201.21073 -400.151125) (xy 201.19639 -400.166323) (xy 201.192384 -400.175984) (xy 201.154792 -400.281394)
			(xy 201.163428 -400.312128) (xy 201.175874 -400.322288) (xy 201.197239 -400.340503) (xy 201.234907 -400.382133)
			(xy 201.266069 -400.428832) (xy 201.290051 -400.479594) (xy 201.306336 -400.533323) (xy 201.314573 -400.588857)
			(xy 201.315066 -400.616928) (xy 201.315066 -400.617182) (xy 201.31458 -400.644433) (xy 201.306824 -400.698381)
			(xy 201.291469 -400.750676) (xy 201.268827 -400.800253) (xy 201.239361 -400.846103) (xy 201.20367 -400.887294)
			(xy 201.162479 -400.922985) (xy 201.116629 -400.952451) (xy 201.067052 -400.975093) (xy 201.014757 -400.990448)
			(xy 200.960809 -400.998204) (xy 200.906307 -400.998204) (xy 200.852359 -400.990448) (xy 200.800064 -400.975093)
			(xy 200.750487 -400.952451) (xy 200.704637 -400.922985) (xy 200.663446 -400.887294) (xy 200.627755 -400.846103)
			(xy 200.598289 -400.800253) (xy 200.575647 -400.750676) (xy 200.560292 -400.698381) (xy 200.552536 -400.644433)
			(xy 200.55205 -400.617182) (xy 200.55205 -400.616928) (xy 200.552547 -400.588857) (xy 200.560774 -400.53332)
			(xy 200.577055 -400.47959) (xy 200.601038 -400.428828) (xy 200.632204 -400.38213) (xy 200.66988 -400.340507)
			(xy 200.691242 -400.322288) (xy 200.703688 -400.312128) (xy 200.712324 -400.281394) (xy 200.674732 -400.175984)
			(xy 200.670703 -400.166334) (xy 200.656368 -400.15114) (xy 200.637172 -400.142898) (xy 200.626726 -400.142456)
			(xy 199.84339 -400.142456) (xy 199.83294 -400.142904) (xy 199.81373 -400.151125) (xy 199.79939 -400.166323)
			(xy 199.795384 -400.175984) (xy 199.757792 -400.281394) (xy 199.766428 -400.312128) (xy 199.778874 -400.322288)
			(xy 199.800239 -400.340503) (xy 199.837907 -400.382133) (xy 199.869069 -400.428832) (xy 199.893051 -400.479594)
			(xy 199.909336 -400.533323) (xy 199.917573 -400.588857) (xy 199.918066 -400.616928) (xy 199.918066 -400.617182)
			(xy 199.91758 -400.644433) (xy 199.909824 -400.698381) (xy 199.894469 -400.750676) (xy 199.871827 -400.800253)
			(xy 199.842361 -400.846103) (xy 199.80667 -400.887294) (xy 199.765479 -400.922985) (xy 199.719629 -400.952451)
			(xy 199.670052 -400.975093) (xy 199.617757 -400.990448) (xy 199.563809 -400.998204) (xy 199.509307 -400.998204)
			(xy 199.455359 -400.990448) (xy 199.403064 -400.975093) (xy 199.353487 -400.952451) (xy 199.307637 -400.922985)
			(xy 199.266446 -400.887294) (xy 199.230755 -400.846103) (xy 199.201289 -400.800253) (xy 199.178647 -400.750676)
			(xy 199.163292 -400.698381) (xy 199.155536 -400.644433) (xy 199.15505 -400.617182) (xy 199.15505 -400.616928)
			(xy 199.155547 -400.588857) (xy 199.163774 -400.53332) (xy 199.180055 -400.47959) (xy 199.204038 -400.428828)
			(xy 199.235204 -400.38213) (xy 199.27288 -400.340507) (xy 199.294242 -400.322288) (xy 199.306688 -400.312128)
			(xy 199.315324 -400.281394) (xy 199.277732 -400.175984) (xy 199.273703 -400.166334) (xy 199.259368 -400.15114)
			(xy 199.240172 -400.142898) (xy 199.229726 -400.142456) (xy 198.42099 -400.142456) (xy 198.41054 -400.142904)
			(xy 198.39133 -400.151125) (xy 198.37699 -400.166323) (xy 198.372984 -400.175984) (xy 198.335392 -400.281394)
			(xy 198.344028 -400.312128) (xy 198.356474 -400.322288) (xy 198.377839 -400.340503) (xy 198.415507 -400.382133)
			(xy 198.446669 -400.428832) (xy 198.470651 -400.479594) (xy 198.486936 -400.533323) (xy 198.495173 -400.588857)
			(xy 198.495666 -400.616928) (xy 198.495666 -400.617182) (xy 198.49518 -400.644433) (xy 198.487424 -400.698381)
			(xy 198.472069 -400.750676) (xy 198.449427 -400.800253) (xy 198.419961 -400.846103) (xy 198.38427 -400.887294)
			(xy 198.343079 -400.922985) (xy 198.297229 -400.952451) (xy 198.247652 -400.975093) (xy 198.195357 -400.990448)
			(xy 198.141409 -400.998204) (xy 198.086907 -400.998204) (xy 198.032959 -400.990448) (xy 197.980664 -400.975093)
			(xy 197.931087 -400.952451) (xy 197.885237 -400.922985) (xy 197.844046 -400.887294) (xy 197.808355 -400.846103)
			(xy 197.778889 -400.800253) (xy 197.756247 -400.750676) (xy 197.740892 -400.698381) (xy 197.733136 -400.644433)
			(xy 197.73265 -400.617182) (xy 197.73265 -400.616928) (xy 197.733147 -400.588857) (xy 197.741374 -400.53332)
			(xy 197.757655 -400.47959) (xy 197.781638 -400.428828) (xy 197.812804 -400.38213) (xy 197.85048 -400.340507)
			(xy 197.871842 -400.322288) (xy 197.884288 -400.312128) (xy 197.892924 -400.281394) (xy 197.855332 -400.175984)
			(xy 197.851303 -400.166334) (xy 197.836968 -400.15114) (xy 197.817772 -400.142898) (xy 197.807326 -400.142456)
			(xy 197.474586 -400.142456) (xy 197.454567 -400.142004) (xy 197.415297 -400.1342) (xy 197.378308 -400.118875)
			(xy 197.345025 -400.096621) (xy 197.330568 -400.082766) (xy 197.227444 -399.979388) (xy 197.221602 -399.9738)
			(xy 197.114414 -399.866612) (xy 197.111563 -399.863906) (xy 197.105184 -399.859314) (xy 197.101714 -399.857468)
			(xy 197.096286 -399.854891) (xy 197.084606 -399.852079) (xy 197.0786 -399.85188) (xy 195.307458 -399.85188)
			(xy 195.301448 -399.852046) (xy 195.289764 -399.854867) (xy 195.284344 -399.857468) (xy 195.280871 -399.859309)
			(xy 195.274493 -399.863903) (xy 195.271644 -399.866612) (xy 194.495674 -400.642582) (xy 195.566282 -400.642582)
			(xy 195.570353 -400.58696) (xy 195.582479 -400.532523) (xy 195.602402 -400.480432) (xy 195.629698 -400.431797)
			(xy 195.663784 -400.387654) (xy 195.703933 -400.348945) (xy 195.749291 -400.316494) (xy 195.798891 -400.290993)
			(xy 195.851675 -400.272986) (xy 195.906518 -400.262856) (xy 195.962252 -400.260819) (xy 196.017689 -400.266919)
			(xy 196.071646 -400.281025) (xy 196.122975 -400.302837) (xy 196.170581 -400.331891) (xy 196.213449 -400.367566)
			(xy 196.250666 -400.409103) (xy 196.281439 -400.455616) (xy 196.305111 -400.506113) (xy 196.321179 -400.55952)
			(xy 196.329299 -400.614696) (xy 196.329808 -400.642582) (xy 196.329299 -400.670468) (xy 196.321179 -400.725644)
			(xy 196.305111 -400.779051) (xy 196.281439 -400.829548) (xy 196.250666 -400.876061) (xy 196.213449 -400.917598)
			(xy 196.170581 -400.953273) (xy 196.122975 -400.982327) (xy 196.071646 -401.004139) (xy 196.017689 -401.018245)
			(xy 195.962252 -401.024345) (xy 195.906518 -401.022308) (xy 195.851675 -401.012178) (xy 195.798891 -400.994171)
			(xy 195.749291 -400.96867) (xy 195.703933 -400.936219) (xy 195.663784 -400.89751) (xy 195.629698 -400.853367)
			(xy 195.602402 -400.804732) (xy 195.582479 -400.752641) (xy 195.570353 -400.698204) (xy 195.566282 -400.642582)
			(xy 194.495674 -400.642582) (xy 193.538856 -401.5994) (xy 193.524405 -401.613149) (xy 193.491241 -401.635299)
			(xy 193.454397 -401.650565) (xy 193.415286 -401.658361) (xy 193.395346 -401.658836) (xy 192.641982 -401.658836)
			(xy 192.635895 -401.659043) (xy 192.624082 -401.661994) (xy 192.618614 -401.664678) (xy 192.61836 -401.664678)
			(xy 192.59112 -401.678115) (xy 192.533437 -401.69713) (xy 192.473468 -401.70676) (xy 192.4431 -401.70735)
			(xy 192.415846 -401.706864) (xy 192.361892 -401.699107) (xy 192.309592 -401.68375) (xy 192.260009 -401.661106)
			(xy 192.214153 -401.631637) (xy 192.172959 -401.595941) (xy 192.137263 -401.554747) (xy 192.107794 -401.508891)
			(xy 192.08515 -401.459308) (xy 192.069793 -401.407008) (xy 192.062036 -401.353054) (xy 192.062036 -401.298546)
			(xy 192.069793 -401.244592) (xy 192.08515 -401.192292) (xy 192.107794 -401.142709) (xy 192.137263 -401.096853)
			(xy 192.172959 -401.055659) (xy 192.214153 -401.019963) (xy 192.260009 -400.990494) (xy 192.309592 -400.96785)
			(xy 192.361892 -400.952493) (xy 192.415846 -400.944736) (xy 192.4431 -400.944334) (xy 192.470193 -400.944808)
			(xy 192.523835 -400.952474) (xy 192.575852 -400.967652) (xy 192.625199 -400.990036) (xy 192.670883 -401.019176)
			(xy 192.711985 -401.054486) (xy 192.747678 -401.095255) (xy 192.777245 -401.140664) (xy 192.80009 -401.1898)
			(xy 192.808352 -401.215606) (xy 192.809114 -401.2184) (xy 192.812972 -401.227751) (xy 192.826653 -401.242631)
			(xy 192.845005 -401.251102) (xy 192.855088 -401.251928) (xy 193.289428 -401.251928) (xy 193.300604 -401.250658)
			(xy 193.307499 -401.248856) (xy 193.320002 -401.242026) (xy 193.325242 -401.237196) (xy 195.05803 -399.504154)
			(xy 195.07253 -399.490352) (xy 195.10581 -399.468116) (xy 195.142784 -399.45279) (xy 195.182036 -399.444962)
			(xy 195.202048 -399.444464) (xy 197.18147 -399.444464) (xy 197.190562 -399.444041) (xy 197.207568 -399.437593)
			(xy 197.221248 -399.425607) (xy 197.22592 -399.417794) (xy 197.227952 -399.412714) (xy 197.230681 -399.405683)
			(xy 197.232246 -399.390688) (xy 197.231 -399.38325) (xy 197.22973 -399.376646) (xy 197.222618 -399.363438)
			(xy 196.379592 -398.520412) (xy 196.37674 -398.517707) (xy 196.37036 -398.513117) (xy 196.366892 -398.511268)
			(xy 196.361466 -398.508683) (xy 196.349786 -398.505853) (xy 196.343778 -398.50568) (xy 194.952366 -398.50568)
			(xy 194.951858 -398.50568) (xy 194.940973 -398.506308) (xy 194.921239 -398.515527) (xy 194.913758 -398.52346)
			(xy 194.895555 -398.545064) (xy 194.853863 -398.583182) (xy 194.807001 -398.61473) (xy 194.755996 -398.639015)
			(xy 194.701966 -398.655508) (xy 194.646094 -398.663845) (xy 194.589602 -398.663845) (xy 194.53373 -398.655508)
			(xy 194.4797 -398.639015) (xy 194.428695 -398.61473) (xy 194.381833 -398.583182) (xy 194.340141 -398.545064)
			(xy 194.321938 -398.52346) (xy 194.314468 -398.515513) (xy 194.294727 -398.506292) (xy 194.283838 -398.50568)
			(xy 191.110362 -398.50568) (xy 191.104352 -398.505846) (xy 191.092668 -398.508666) (xy 191.087248 -398.511268)
			(xy 191.083774 -398.513108) (xy 191.077397 -398.517703) (xy 191.074548 -398.520412) (xy 189.85357 -399.74139)
			(xy 189.847762 -399.747702) (xy 189.84037 -399.763169) (xy 189.838498 -399.780209) (xy 189.840108 -399.788634)
			(xy 189.859158 -399.872454) (xy 189.860815 -399.878619) (xy 189.866723 -399.889929) (xy 189.870842 -399.894806)
			(xy 189.875414 -399.899886) (xy 189.886082 -399.906998) (xy 189.892178 -399.90903) (xy 189.916718 -399.918108)
			(xy 189.963253 -399.94203) (xy 190.006086 -399.972081) (xy 190.044415 -400.0077) (xy 190.077522 -400.048217)
			(xy 190.104786 -400.092876) (xy 190.125698 -400.140839) (xy 190.139865 -400.191209) (xy 190.147022 -400.24304)
			(xy 190.147448 -400.269202) (xy 190.146962 -400.296454) (xy 190.145037 -400.309842) (xy 192.050922 -400.309842)
			(xy 192.054993 -400.25422) (xy 192.067119 -400.199783) (xy 192.087042 -400.147692) (xy 192.114338 -400.099057)
			(xy 192.148424 -400.054914) (xy 192.188573 -400.016205) (xy 192.233931 -399.983754) (xy 192.283531 -399.958253)
			(xy 192.336315 -399.940246) (xy 192.391158 -399.930116) (xy 192.446892 -399.928079) (xy 192.502329 -399.934179)
			(xy 192.556286 -399.948285) (xy 192.607615 -399.970097) (xy 192.655221 -399.999151) (xy 192.698089 -400.034826)
			(xy 192.735306 -400.076363) (xy 192.766079 -400.122876) (xy 192.789751 -400.173373) (xy 192.805819 -400.22678)
			(xy 192.813939 -400.281956) (xy 192.814448 -400.309842) (xy 192.813939 -400.337728) (xy 192.805819 -400.392904)
			(xy 192.789751 -400.446311) (xy 192.766079 -400.496808) (xy 192.735306 -400.543321) (xy 192.698089 -400.584858)
			(xy 192.655221 -400.620533) (xy 192.607615 -400.649587) (xy 192.556286 -400.671399) (xy 192.502329 -400.685505)
			(xy 192.446892 -400.691605) (xy 192.391158 -400.689568) (xy 192.336315 -400.679438) (xy 192.283531 -400.661431)
			(xy 192.233931 -400.63593) (xy 192.188573 -400.603479) (xy 192.148424 -400.56477) (xy 192.114338 -400.520627)
			(xy 192.087042 -400.471992) (xy 192.067119 -400.419901) (xy 192.054993 -400.365464) (xy 192.050922 -400.309842)
			(xy 190.145037 -400.309842) (xy 190.139206 -400.350404) (xy 190.123851 -400.402701) (xy 190.10121 -400.45228)
			(xy 190.071744 -400.498133) (xy 190.036053 -400.539326) (xy 189.994864 -400.575021) (xy 189.949014 -400.604492)
			(xy 189.899436 -400.627137) (xy 189.847141 -400.642497) (xy 189.793192 -400.650259) (xy 189.76594 -400.65071)
			(xy 189.739046 -400.650246) (xy 189.685793 -400.642684) (xy 189.634129 -400.62772) (xy 189.585078 -400.60565)
			(xy 189.539613 -400.57691) (xy 189.498633 -400.542071) (xy 189.462951 -400.501823) (xy 189.433275 -400.456963)
			(xy 189.410192 -400.408381) (xy 189.39416 -400.357038) (xy 189.385495 -400.303953) (xy 189.384432 -400.277076)
			(xy 189.384432 -400.268948) (xy 189.384934 -400.241782) (xy 189.392677 -400.188004) (xy 189.407956 -400.135864)
			(xy 189.430464 -400.086412) (xy 189.459748 -400.040646) (xy 189.477142 -400.019774) (xy 189.481787 -400.014051)
			(xy 189.487862 -400.000627) (xy 189.48908 -399.993358) (xy 189.490096 -399.9865) (xy 189.488064 -399.97253)
			(xy 189.481968 -399.959322) (xy 189.445138 -399.879312) (xy 189.44053 -399.871327) (xy 189.426807 -399.859036)
			(xy 189.40964 -399.852351) (xy 189.400434 -399.85188) (xy 186.307222 -399.85188) (xy 186.297159 -399.851442)
			(xy 186.278577 -399.843706) (xy 186.271154 -399.836894) (xy 186.02706 -399.5928) (xy 186.024207 -399.590097)
			(xy 186.017825 -399.585512) (xy 186.01436 -399.583656) (xy 186.008934 -399.58107) (xy 185.997254 -399.578242)
			(xy 185.991246 -399.578068) (xy 185.509154 -399.578068) (xy 185.483273 -399.577544) (xy 185.432241 -399.568885)
			(xy 185.383385 -399.551788) (xy 185.33809 -399.526735) (xy 185.29764 -399.494439) (xy 185.280046 -399.475452)
			(xy 185.230516 -399.419572) (xy 185.230008 -399.419064) (xy 185.162952 -399.344642) (xy 185.156759 -399.337252)
			(xy 185.149957 -399.319229) (xy 185.149744 -399.30959) (xy 185.151014 -399.245328) (xy 185.150762 -399.235087)
			(xy 185.143171 -399.216079) (xy 185.136282 -399.208498) (xy 185.12155 -399.193766) (xy 185.114704 -399.186368)
			(xy 185.106974 -399.167769) (xy 185.106564 -399.157698) (xy 185.106564 -398.869916) (xy 185.106411 -398.864681)
			(xy 185.104245 -398.854436) (xy 185.102246 -398.849596) (xy 185.097674 -398.838928) (xy 185.094626 -398.82953)
			(xy 185.094626 -398.829276) (xy 185.086498 -398.792954) (xy 185.083248 -398.776768) (xy 185.079815 -398.743931)
			(xy 185.07964 -398.727422) (xy 185.07964 -398.666462) (xy 185.079474 -398.660452) (xy 185.076655 -398.648767)
			(xy 185.074052 -398.643348) (xy 185.072209 -398.639876) (xy 185.067609 -398.633503) (xy 185.064908 -398.630648)
			(xy 181.954932 -395.520672) (xy 181.952083 -395.517963) (xy 181.945708 -395.513364) (xy 181.942232 -395.511528)
			(xy 181.936805 -395.508946) (xy 181.925125 -395.506127) (xy 181.919118 -395.50594) (xy 177.973228 -395.50594)
			(xy 177.962731 -395.506466) (xy 177.943491 -395.514868) (xy 177.929199 -395.530247) (xy 177.925222 -395.539976)
			(xy 177.888392 -395.645894) (xy 177.897282 -395.676882) (xy 177.909982 -395.687042) (xy 177.93211 -395.705239)
			(xy 177.971179 -395.74714) (xy 178.003547 -395.79441) (xy 178.028485 -395.845987) (xy 178.045434 -395.900712)
			(xy 178.054012 -395.957355) (xy 178.054508 -395.986) (xy 178.054022 -396.013251) (xy 178.046266 -396.067199)
			(xy 178.030911 -396.119494) (xy 178.008269 -396.169071) (xy 177.978803 -396.214921) (xy 177.943112 -396.256112)
			(xy 177.901921 -396.291803) (xy 177.856071 -396.321269) (xy 177.806494 -396.343911) (xy 177.754199 -396.359266)
			(xy 177.700404 -396.367) (xy 179.576982 -396.367) (xy 179.581053 -396.311378) (xy 179.593179 -396.256941)
			(xy 179.613102 -396.20485) (xy 179.640398 -396.156215) (xy 179.674484 -396.112072) (xy 179.714633 -396.073363)
			(xy 179.759991 -396.040912) (xy 179.809591 -396.015411) (xy 179.862375 -395.997404) (xy 179.917218 -395.987274)
			(xy 179.972952 -395.985237) (xy 180.028389 -395.991337) (xy 180.082346 -396.005443) (xy 180.133675 -396.027255)
			(xy 180.181281 -396.056309) (xy 180.224149 -396.091984) (xy 180.261366 -396.133521) (xy 180.292139 -396.180034)
			(xy 180.315811 -396.230531) (xy 180.331879 -396.283938) (xy 180.339999 -396.339114) (xy 180.340508 -396.367)
			(xy 180.339999 -396.394886) (xy 180.331879 -396.450062) (xy 180.315811 -396.503469) (xy 180.292139 -396.553966)
			(xy 180.261366 -396.600479) (xy 180.224149 -396.642016) (xy 180.181281 -396.677691) (xy 180.133675 -396.706745)
			(xy 180.082346 -396.728557) (xy 180.028389 -396.742663) (xy 179.972952 -396.748763) (xy 179.917218 -396.746726)
			(xy 179.862375 -396.736596) (xy 179.809591 -396.718589) (xy 179.759991 -396.693088) (xy 179.714633 -396.660637)
			(xy 179.674484 -396.621928) (xy 179.640398 -396.577785) (xy 179.613102 -396.52915) (xy 179.593179 -396.477059)
			(xy 179.581053 -396.422622) (xy 179.576982 -396.367) (xy 177.700404 -396.367) (xy 177.700251 -396.367022)
			(xy 177.645749 -396.367022) (xy 177.591801 -396.359266) (xy 177.539506 -396.343911) (xy 177.489929 -396.321269)
			(xy 177.444079 -396.291803) (xy 177.402888 -396.256112) (xy 177.367197 -396.214921) (xy 177.337731 -396.169071)
			(xy 177.315089 -396.119494) (xy 177.299734 -396.067199) (xy 177.291978 -396.013251) (xy 177.291492 -395.986)
			(xy 177.291982 -395.95829) (xy 177.29999 -395.903453) (xy 177.315852 -395.850353) (xy 177.339234 -395.800108)
			(xy 177.369643 -395.753777) (xy 177.406439 -395.712336) (xy 177.448847 -395.676659) (xy 177.495972 -395.647496)
			(xy 177.546823 -395.625463) (xy 177.600328 -395.611023) (xy 177.627788 -395.607286) (xy 177.647092 -395.605)
			(xy 177.672492 -395.576298) (xy 177.672492 -395.55674) (xy 177.672079 -395.546714) (xy 177.664416 -395.528185)
			(xy 177.650242 -395.514002) (xy 177.631718 -395.506327) (xy 177.621692 -395.50594) (xy 177.409602 -395.50594)
			(xy 177.403594 -395.506112) (xy 177.391915 -395.508943) (xy 177.386488 -395.511528) (xy 177.383014 -395.513368)
			(xy 177.376637 -395.517963) (xy 177.373788 -395.520672) (xy 176.62017 -396.27429) (xy 176.613314 -396.281685)
			(xy 176.605565 -396.300283) (xy 176.605184 -396.310358) (xy 176.605184 -397.938244) (xy 176.612804 -397.956786)
			(xy 176.614836 -397.958818) (xy 176.614836 -398.400778) (xy 179.702458 -398.400778) (xy 179.706529 -398.345156)
			(xy 179.718655 -398.290719) (xy 179.738578 -398.238628) (xy 179.765874 -398.189993) (xy 179.79996 -398.14585)
			(xy 179.840109 -398.107141) (xy 179.885467 -398.07469) (xy 179.935067 -398.049189) (xy 179.987851 -398.031182)
			(xy 180.042694 -398.021052) (xy 180.098428 -398.019015) (xy 180.153865 -398.025115) (xy 180.207822 -398.039221)
			(xy 180.259151 -398.061033) (xy 180.306757 -398.090087) (xy 180.349625 -398.125762) (xy 180.386842 -398.167299)
			(xy 180.417615 -398.213812) (xy 180.441287 -398.264309) (xy 180.457355 -398.317716) (xy 180.465475 -398.372892)
			(xy 180.465984 -398.400778) (xy 180.465475 -398.428664) (xy 180.457355 -398.48384) (xy 180.441287 -398.537247)
			(xy 180.417615 -398.587744) (xy 180.386842 -398.634257) (xy 180.349625 -398.675794) (xy 180.306757 -398.711469)
			(xy 180.259151 -398.740523) (xy 180.207822 -398.762335) (xy 180.153865 -398.776441) (xy 180.098428 -398.782541)
			(xy 180.042694 -398.780504) (xy 179.987851 -398.770374) (xy 179.935067 -398.752367) (xy 179.885467 -398.726866)
			(xy 179.840109 -398.694415) (xy 179.79996 -398.655706) (xy 179.765874 -398.611563) (xy 179.738578 -398.562928)
			(xy 179.718655 -398.510837) (xy 179.706529 -398.4564) (xy 179.702458 -398.400778) (xy 176.614836 -398.400778)
			(xy 176.614836 -398.476724) (xy 176.605184 -398.481296) (xy 176.605184 -399.420842) (xy 179.602382 -399.420842)
			(xy 179.606453 -399.36522) (xy 179.618579 -399.310783) (xy 179.638502 -399.258692) (xy 179.665798 -399.210057)
			(xy 179.699884 -399.165914) (xy 179.740033 -399.127205) (xy 179.785391 -399.094754) (xy 179.834991 -399.069253)
			(xy 179.887775 -399.051246) (xy 179.942618 -399.041116) (xy 179.998352 -399.039079) (xy 180.053789 -399.045179)
			(xy 180.107746 -399.059285) (xy 180.159075 -399.081097) (xy 180.195524 -399.103342) (xy 181.202582 -399.103342)
			(xy 181.206653 -399.04772) (xy 181.218779 -398.993283) (xy 181.238702 -398.941192) (xy 181.265998 -398.892557)
			(xy 181.300084 -398.848414) (xy 181.340233 -398.809705) (xy 181.385591 -398.777254) (xy 181.435191 -398.751753)
			(xy 181.487975 -398.733746) (xy 181.542818 -398.723616) (xy 181.598552 -398.721579) (xy 181.653989 -398.727679)
			(xy 181.707946 -398.741785) (xy 181.759275 -398.763597) (xy 181.806881 -398.792651) (xy 181.849749 -398.828326)
			(xy 181.886966 -398.869863) (xy 181.917739 -398.916376) (xy 181.941411 -398.966873) (xy 181.957479 -399.02028)
			(xy 181.958115 -399.024602) (xy 182.863742 -399.024602) (xy 182.867813 -398.96898) (xy 182.879939 -398.914543)
			(xy 182.899862 -398.862452) (xy 182.927158 -398.813817) (xy 182.961244 -398.769674) (xy 183.001393 -398.730965)
			(xy 183.046751 -398.698514) (xy 183.096351 -398.673013) (xy 183.149135 -398.655006) (xy 183.203978 -398.644876)
			(xy 183.259712 -398.642839) (xy 183.315149 -398.648939) (xy 183.369106 -398.663045) (xy 183.420435 -398.684857)
			(xy 183.468041 -398.713911) (xy 183.510909 -398.749586) (xy 183.548126 -398.791123) (xy 183.578899 -398.837636)
			(xy 183.602571 -398.888133) (xy 183.618639 -398.94154) (xy 183.626759 -398.996716) (xy 183.627268 -399.024602)
			(xy 183.626759 -399.052488) (xy 183.618639 -399.107664) (xy 183.618411 -399.108422) (xy 184.142632 -399.108422)
			(xy 184.146703 -399.0528) (xy 184.158829 -398.998363) (xy 184.178752 -398.946272) (xy 184.206048 -398.897637)
			(xy 184.240134 -398.853494) (xy 184.280283 -398.814785) (xy 184.325641 -398.782334) (xy 184.375241 -398.756833)
			(xy 184.428025 -398.738826) (xy 184.482868 -398.728696) (xy 184.538602 -398.726659) (xy 184.594039 -398.732759)
			(xy 184.647996 -398.746865) (xy 184.699325 -398.768677) (xy 184.746931 -398.797731) (xy 184.789799 -398.833406)
			(xy 184.827016 -398.874943) (xy 184.857789 -398.921456) (xy 184.881461 -398.971953) (xy 184.897529 -399.02536)
			(xy 184.905649 -399.080536) (xy 184.906158 -399.108422) (xy 184.905649 -399.136308) (xy 184.897529 -399.191484)
			(xy 184.881461 -399.244891) (xy 184.857789 -399.295388) (xy 184.827016 -399.341901) (xy 184.789799 -399.383438)
			(xy 184.746931 -399.419113) (xy 184.699325 -399.448167) (xy 184.647996 -399.469979) (xy 184.594039 -399.484085)
			(xy 184.538602 -399.490185) (xy 184.482868 -399.488148) (xy 184.428025 -399.478018) (xy 184.375241 -399.460011)
			(xy 184.325641 -399.43451) (xy 184.280283 -399.402059) (xy 184.240134 -399.36335) (xy 184.206048 -399.319207)
			(xy 184.178752 -399.270572) (xy 184.158829 -399.218481) (xy 184.146703 -399.164044) (xy 184.142632 -399.108422)
			(xy 183.618411 -399.108422) (xy 183.602571 -399.161071) (xy 183.578899 -399.211568) (xy 183.548126 -399.258081)
			(xy 183.510909 -399.299618) (xy 183.468041 -399.335293) (xy 183.420435 -399.364347) (xy 183.369106 -399.386159)
			(xy 183.315149 -399.400265) (xy 183.259712 -399.406365) (xy 183.203978 -399.404328) (xy 183.149135 -399.394198)
			(xy 183.096351 -399.376191) (xy 183.046751 -399.35069) (xy 183.001393 -399.318239) (xy 182.961244 -399.27953)
			(xy 182.927158 -399.235387) (xy 182.899862 -399.186752) (xy 182.879939 -399.134661) (xy 182.867813 -399.080224)
			(xy 182.863742 -399.024602) (xy 181.958115 -399.024602) (xy 181.965599 -399.075456) (xy 181.966108 -399.103342)
			(xy 181.965599 -399.131228) (xy 181.957479 -399.186404) (xy 181.941411 -399.239811) (xy 181.917739 -399.290308)
			(xy 181.886966 -399.336821) (xy 181.849749 -399.378358) (xy 181.806881 -399.414033) (xy 181.759275 -399.443087)
			(xy 181.707946 -399.464899) (xy 181.653989 -399.479005) (xy 181.598552 -399.485105) (xy 181.542818 -399.483068)
			(xy 181.487975 -399.472938) (xy 181.435191 -399.454931) (xy 181.385591 -399.42943) (xy 181.340233 -399.396979)
			(xy 181.300084 -399.35827) (xy 181.265998 -399.314127) (xy 181.238702 -399.265492) (xy 181.218779 -399.213401)
			(xy 181.206653 -399.158964) (xy 181.202582 -399.103342) (xy 180.195524 -399.103342) (xy 180.206681 -399.110151)
			(xy 180.249549 -399.145826) (xy 180.286766 -399.187363) (xy 180.317539 -399.233876) (xy 180.341211 -399.284373)
			(xy 180.357279 -399.33778) (xy 180.365399 -399.392956) (xy 180.365908 -399.420842) (xy 180.365399 -399.448728)
			(xy 180.357279 -399.503904) (xy 180.341211 -399.557311) (xy 180.317539 -399.607808) (xy 180.286766 -399.654321)
			(xy 180.249549 -399.695858) (xy 180.206681 -399.731533) (xy 180.159075 -399.760587) (xy 180.107746 -399.782399)
			(xy 180.053789 -399.796505) (xy 179.998352 -399.802605) (xy 179.942618 -399.800568) (xy 179.887775 -399.790438)
			(xy 179.834991 -399.772431) (xy 179.785391 -399.74693) (xy 179.740033 -399.714479) (xy 179.699884 -399.67577)
			(xy 179.665798 -399.631627) (xy 179.638502 -399.582992) (xy 179.618579 -399.530901) (xy 179.606453 -399.476464)
			(xy 179.602382 -399.420842) (xy 176.605184 -399.420842) (xy 176.605184 -400.436842) (xy 180.097682 -400.436842)
			(xy 180.101753 -400.38122) (xy 180.113879 -400.326783) (xy 180.133802 -400.274692) (xy 180.161098 -400.226057)
			(xy 180.195184 -400.181914) (xy 180.235333 -400.143205) (xy 180.280691 -400.110754) (xy 180.330291 -400.085253)
			(xy 180.383075 -400.067246) (xy 180.437918 -400.057116) (xy 180.493652 -400.055079) (xy 180.549089 -400.061179)
			(xy 180.603046 -400.075285) (xy 180.654375 -400.097097) (xy 180.701981 -400.126151) (xy 180.744849 -400.161826)
			(xy 180.782066 -400.203363) (xy 180.812839 -400.249876) (xy 180.836511 -400.300373) (xy 180.852579 -400.35378)
			(xy 180.860699 -400.408956) (xy 180.861208 -400.436842) (xy 180.860699 -400.464728) (xy 180.852579 -400.519904)
			(xy 180.836511 -400.573311) (xy 180.812839 -400.623808) (xy 180.782066 -400.670321) (xy 180.744849 -400.711858)
			(xy 180.701981 -400.747533) (xy 180.654375 -400.776587) (xy 180.603046 -400.798399) (xy 180.549089 -400.812505)
			(xy 180.493652 -400.818605) (xy 180.437918 -400.816568) (xy 180.383075 -400.806438) (xy 180.330291 -400.788431)
			(xy 180.280691 -400.76293) (xy 180.235333 -400.730479) (xy 180.195184 -400.69177) (xy 180.161098 -400.647627)
			(xy 180.133802 -400.598992) (xy 180.113879 -400.546901) (xy 180.101753 -400.492464) (xy 180.097682 -400.436842)
			(xy 176.605184 -400.436842) (xy 176.605184 -401.452842) (xy 177.318922 -401.452842) (xy 177.322993 -401.39722)
			(xy 177.335119 -401.342783) (xy 177.355042 -401.290692) (xy 177.382338 -401.242057) (xy 177.416424 -401.197914)
			(xy 177.456573 -401.159205) (xy 177.501931 -401.126754) (xy 177.551531 -401.101253) (xy 177.604315 -401.083246)
			(xy 177.659158 -401.073116) (xy 177.714892 -401.071079) (xy 177.759051 -401.075938) (xy 182.489605 -401.075938)
			(xy 182.489607 -401.021441) (xy 182.497364 -400.967498) (xy 182.512719 -400.915208) (xy 182.535359 -400.865636)
			(xy 182.564824 -400.81979) (xy 182.600513 -400.778604) (xy 182.6417 -400.742916) (xy 182.687547 -400.713453)
			(xy 182.73712 -400.690815) (xy 182.78941 -400.675461) (xy 182.843353 -400.667706) (xy 182.870602 -400.66722)
			(xy 182.890922 -400.667728) (xy 182.901844 -400.668236) (xy 182.92191 -400.660616) (xy 182.99049 -400.592036)
			(xy 182.99811 -400.57197) (xy 182.997602 -400.561048) (xy 182.997094 -400.540728) (xy 182.99758 -400.513477)
			(xy 183.005336 -400.459529) (xy 183.020691 -400.407234) (xy 183.043333 -400.357657) (xy 183.072799 -400.311807)
			(xy 183.10849 -400.270616) (xy 183.149681 -400.234925) (xy 183.195531 -400.205459) (xy 183.245108 -400.182817)
			(xy 183.297403 -400.167462) (xy 183.351351 -400.159706) (xy 183.405853 -400.159706) (xy 183.459801 -400.167462)
			(xy 183.512096 -400.182817) (xy 183.561673 -400.205459) (xy 183.607523 -400.234925) (xy 183.648714 -400.270616)
			(xy 183.684405 -400.311807) (xy 183.713871 -400.357657) (xy 183.736513 -400.407234) (xy 183.751868 -400.459529)
			(xy 183.759624 -400.513477) (xy 183.76011 -400.540728) (xy 183.759602 -400.561048) (xy 183.759094 -400.57197)
			(xy 183.766714 -400.592036) (xy 183.791352 -400.616674) (xy 184.474102 -400.616674) (xy 184.478173 -400.561052)
			(xy 184.490299 -400.506615) (xy 184.510222 -400.454524) (xy 184.537518 -400.405889) (xy 184.571604 -400.361746)
			(xy 184.611753 -400.323037) (xy 184.657111 -400.290586) (xy 184.706711 -400.265085) (xy 184.759495 -400.247078)
			(xy 184.814338 -400.236948) (xy 184.870072 -400.234911) (xy 184.925509 -400.241011) (xy 184.979466 -400.255117)
			(xy 185.030795 -400.276929) (xy 185.078401 -400.305983) (xy 185.121269 -400.341658) (xy 185.158486 -400.383195)
			(xy 185.189259 -400.429708) (xy 185.212931 -400.480205) (xy 185.228999 -400.533612) (xy 185.237119 -400.588788)
			(xy 185.237628 -400.616674) (xy 185.896502 -400.616674) (xy 185.900573 -400.561052) (xy 185.912699 -400.506615)
			(xy 185.932622 -400.454524) (xy 185.959918 -400.405889) (xy 185.994004 -400.361746) (xy 186.034153 -400.323037)
			(xy 186.079511 -400.290586) (xy 186.129111 -400.265085) (xy 186.181895 -400.247078) (xy 186.236738 -400.236948)
			(xy 186.292472 -400.234911) (xy 186.347909 -400.241011) (xy 186.401866 -400.255117) (xy 186.453195 -400.276929)
			(xy 186.500801 -400.305983) (xy 186.543669 -400.341658) (xy 186.580886 -400.383195) (xy 186.611659 -400.429708)
			(xy 186.635331 -400.480205) (xy 186.651399 -400.533612) (xy 186.659519 -400.588788) (xy 186.660028 -400.616674)
			(xy 187.293502 -400.616674) (xy 187.297573 -400.561052) (xy 187.309699 -400.506615) (xy 187.329622 -400.454524)
			(xy 187.356918 -400.405889) (xy 187.391004 -400.361746) (xy 187.431153 -400.323037) (xy 187.476511 -400.290586)
			(xy 187.526111 -400.265085) (xy 187.578895 -400.247078) (xy 187.633738 -400.236948) (xy 187.689472 -400.234911)
			(xy 187.744909 -400.241011) (xy 187.798866 -400.255117) (xy 187.850195 -400.276929) (xy 187.897801 -400.305983)
			(xy 187.940669 -400.341658) (xy 187.977886 -400.383195) (xy 188.008659 -400.429708) (xy 188.032331 -400.480205)
			(xy 188.048399 -400.533612) (xy 188.056519 -400.588788) (xy 188.057028 -400.616674) (xy 188.056519 -400.64456)
			(xy 188.048399 -400.699736) (xy 188.032331 -400.753143) (xy 188.008659 -400.80364) (xy 187.977886 -400.850153)
			(xy 187.940669 -400.89169) (xy 187.897801 -400.927365) (xy 187.850195 -400.956419) (xy 187.798866 -400.978231)
			(xy 187.744909 -400.992337) (xy 187.689472 -400.998437) (xy 187.633738 -400.9964) (xy 187.578895 -400.98627)
			(xy 187.526111 -400.968263) (xy 187.476511 -400.942762) (xy 187.431153 -400.910311) (xy 187.391004 -400.871602)
			(xy 187.356918 -400.827459) (xy 187.329622 -400.778824) (xy 187.309699 -400.726733) (xy 187.297573 -400.672296)
			(xy 187.293502 -400.616674) (xy 186.660028 -400.616674) (xy 186.659519 -400.64456) (xy 186.651399 -400.699736)
			(xy 186.635331 -400.753143) (xy 186.611659 -400.80364) (xy 186.580886 -400.850153) (xy 186.543669 -400.89169)
			(xy 186.500801 -400.927365) (xy 186.453195 -400.956419) (xy 186.401866 -400.978231) (xy 186.347909 -400.992337)
			(xy 186.292472 -400.998437) (xy 186.236738 -400.9964) (xy 186.181895 -400.98627) (xy 186.129111 -400.968263)
			(xy 186.079511 -400.942762) (xy 186.034153 -400.910311) (xy 185.994004 -400.871602) (xy 185.959918 -400.827459)
			(xy 185.932622 -400.778824) (xy 185.912699 -400.726733) (xy 185.900573 -400.672296) (xy 185.896502 -400.616674)
			(xy 185.237628 -400.616674) (xy 185.237119 -400.64456) (xy 185.228999 -400.699736) (xy 185.212931 -400.753143)
			(xy 185.189259 -400.80364) (xy 185.158486 -400.850153) (xy 185.121269 -400.89169) (xy 185.078401 -400.927365)
			(xy 185.030795 -400.956419) (xy 184.979466 -400.978231) (xy 184.925509 -400.992337) (xy 184.870072 -400.998437)
			(xy 184.814338 -400.9964) (xy 184.759495 -400.98627) (xy 184.706711 -400.968263) (xy 184.657111 -400.942762)
			(xy 184.611753 -400.910311) (xy 184.571604 -400.871602) (xy 184.537518 -400.827459) (xy 184.510222 -400.778824)
			(xy 184.490299 -400.726733) (xy 184.478173 -400.672296) (xy 184.474102 -400.616674) (xy 183.791352 -400.616674)
			(xy 183.835294 -400.660616) (xy 183.85536 -400.668236) (xy 183.866282 -400.667728) (xy 183.886602 -400.66722)
			(xy 183.913853 -400.66768) (xy 183.967799 -400.675436) (xy 184.020093 -400.690791) (xy 184.069669 -400.713432)
			(xy 184.115518 -400.742897) (xy 184.156708 -400.778588) (xy 184.192399 -400.819777) (xy 184.221865 -400.865626)
			(xy 184.244507 -400.915202) (xy 184.259862 -400.967495) (xy 184.26762 -401.021441) (xy 184.267621 -401.075943)
			(xy 184.259866 -401.129889) (xy 184.244512 -401.182183) (xy 184.221873 -401.23176) (xy 184.192409 -401.27761)
			(xy 184.185831 -401.285202) (xy 189.384432 -401.285202) (xy 189.384918 -401.257951) (xy 189.392674 -401.204003)
			(xy 189.408029 -401.151708) (xy 189.430671 -401.102131) (xy 189.460137 -401.056281) (xy 189.495828 -401.01509)
			(xy 189.537019 -400.979399) (xy 189.582869 -400.949933) (xy 189.632446 -400.927291) (xy 189.684741 -400.911936)
			(xy 189.738689 -400.90418) (xy 189.793191 -400.90418) (xy 189.847139 -400.911936) (xy 189.899434 -400.927291)
			(xy 189.949011 -400.949933) (xy 189.994861 -400.979399) (xy 190.036052 -401.01509) (xy 190.071743 -401.056281)
			(xy 190.101209 -401.102131) (xy 190.123851 -401.151708) (xy 190.139206 -401.204003) (xy 190.146962 -401.257951)
			(xy 190.147448 -401.285202) (xy 190.146877 -401.314773) (xy 190.137763 -401.373209) (xy 190.119739 -401.429537)
			(xy 190.093237 -401.482409) (xy 190.058891 -401.530556) (xy 190.017525 -401.572825) (xy 189.970131 -401.608203)
			(xy 189.944248 -401.622514) (xy 189.93207 -401.629374) (xy 189.911787 -401.648594) (xy 189.897474 -401.672593)
			(xy 189.890204 -401.699574) (xy 189.89052 -401.727515) (xy 189.8984 -401.754325) (xy 189.913252 -401.777994)
			(xy 189.933964 -401.79675) (xy 189.94628 -401.803362) (xy 189.969739 -401.815561) (xy 190.013359 -401.845444)
			(xy 190.052432 -401.881068) (xy 190.086208 -401.921748) (xy 190.11404 -401.966704) (xy 190.135394 -402.015075)
			(xy 190.149859 -402.065933) (xy 190.15716 -402.118301) (xy 190.157608 -402.144738) (xy 190.157122 -402.171989)
			(xy 190.149366 -402.225937) (xy 190.134011 -402.278232) (xy 190.111369 -402.327809) (xy 190.102351 -402.341842)
			(xy 192.050922 -402.341842) (xy 192.054993 -402.28622) (xy 192.067119 -402.231783) (xy 192.087042 -402.179692)
			(xy 192.114338 -402.131057) (xy 192.148424 -402.086914) (xy 192.188573 -402.048205) (xy 192.233931 -402.015754)
			(xy 192.283531 -401.990253) (xy 192.336315 -401.972246) (xy 192.391158 -401.962116) (xy 192.446892 -401.960079)
			(xy 192.502329 -401.966179) (xy 192.556286 -401.980285) (xy 192.607615 -402.002097) (xy 192.655221 -402.031151)
			(xy 192.698089 -402.066826) (xy 192.735306 -402.108363) (xy 192.766079 -402.154876) (xy 192.789751 -402.205373)
			(xy 192.805819 -402.25878) (xy 192.813939 -402.313956) (xy 192.814448 -402.341842) (xy 192.813939 -402.369728)
			(xy 192.805819 -402.424904) (xy 192.789751 -402.478311) (xy 192.766079 -402.528808) (xy 192.735306 -402.575321)
			(xy 192.698089 -402.616858) (xy 192.655221 -402.652533) (xy 192.607615 -402.681587) (xy 192.556286 -402.703399)
			(xy 192.502329 -402.717505) (xy 192.446892 -402.723605) (xy 192.391158 -402.721568) (xy 192.336315 -402.711438)
			(xy 192.283531 -402.693431) (xy 192.233931 -402.66793) (xy 192.188573 -402.635479) (xy 192.148424 -402.59677)
			(xy 192.114338 -402.552627) (xy 192.087042 -402.503992) (xy 192.067119 -402.451901) (xy 192.054993 -402.397464)
			(xy 192.050922 -402.341842) (xy 190.102351 -402.341842) (xy 190.081903 -402.373659) (xy 190.046212 -402.41485)
			(xy 190.005021 -402.450541) (xy 189.959171 -402.480007) (xy 189.909594 -402.502649) (xy 189.857299 -402.518004)
			(xy 189.803351 -402.52576) (xy 189.748849 -402.52576) (xy 189.694901 -402.518004) (xy 189.642606 -402.502649)
			(xy 189.593029 -402.480007) (xy 189.547179 -402.450541) (xy 189.505988 -402.41485) (xy 189.470297 -402.373659)
			(xy 189.440831 -402.327809) (xy 189.418189 -402.278232) (xy 189.402834 -402.225937) (xy 189.395078 -402.171989)
			(xy 189.394592 -402.144738) (xy 189.395093 -402.115164) (xy 189.404217 -402.056724) (xy 189.422252 -402.000393)
			(xy 189.448765 -401.94752) (xy 189.483122 -401.899374) (xy 189.524499 -401.857107) (xy 189.571904 -401.821734)
			(xy 189.597792 -401.807426) (xy 189.60993 -401.800504) (xy 189.630201 -401.781291) (xy 189.644506 -401.757304)
			(xy 189.651776 -401.730338) (xy 189.651465 -401.70241) (xy 189.643597 -401.675612) (xy 189.62876 -401.651949)
			(xy 189.608066 -401.633193) (xy 189.59576 -401.626578) (xy 189.572285 -401.614407) (xy 189.528663 -401.584522)
			(xy 189.489588 -401.548896) (xy 189.455812 -401.508212) (xy 189.427981 -401.463251) (xy 189.406631 -401.414875)
			(xy 189.39217 -401.364013) (xy 189.384876 -401.311641) (xy 189.384432 -401.285202) (xy 184.185831 -401.285202)
			(xy 184.156719 -401.318801) (xy 184.115531 -401.354493) (xy 184.069683 -401.383961) (xy 184.020108 -401.406603)
			(xy 183.967815 -401.42196) (xy 183.913869 -401.429719) (xy 183.859367 -401.429722) (xy 183.80542 -401.421968)
			(xy 183.753126 -401.406616) (xy 183.703549 -401.383978) (xy 183.657698 -401.354515) (xy 183.616506 -401.318826)
			(xy 183.580813 -401.277639) (xy 183.551344 -401.231792) (xy 183.5287 -401.182217) (xy 183.513342 -401.129925)
			(xy 183.505582 -401.075979) (xy 183.505094 -401.048728) (xy 183.505602 -401.028408) (xy 183.50611 -401.017486)
			(xy 183.49849 -400.99742) (xy 183.42991 -400.92884) (xy 183.409844 -400.92122) (xy 183.398922 -400.921728)
			(xy 183.378602 -400.922236) (xy 183.358282 -400.921728) (xy 183.34736 -400.92122) (xy 183.327294 -400.92884)
			(xy 183.258714 -400.99742) (xy 183.251094 -401.017486) (xy 183.251602 -401.028408) (xy 183.25211 -401.048728)
			(xy 183.251592 -401.075977) (xy 183.243832 -401.129919) (xy 183.228475 -401.182208) (xy 183.205832 -401.231779)
			(xy 183.176366 -401.277624) (xy 183.140675 -401.318808) (xy 183.099486 -401.354494) (xy 183.053638 -401.383955)
			(xy 183.004064 -401.406591) (xy 182.951773 -401.421942) (xy 182.89783 -401.429695) (xy 182.843332 -401.429692)
			(xy 182.789389 -401.421934) (xy 182.7371 -401.406578) (xy 182.687528 -401.383936) (xy 182.641683 -401.354471)
			(xy 182.600498 -401.318781) (xy 182.564811 -401.277593) (xy 182.535349 -401.231746) (xy 182.512712 -401.182172)
			(xy 182.49736 -401.129881) (xy 182.489605 -401.075938) (xy 177.759051 -401.075938) (xy 177.770329 -401.077179)
			(xy 177.824286 -401.091285) (xy 177.875615 -401.113097) (xy 177.923221 -401.142151) (xy 177.966089 -401.177826)
			(xy 178.003306 -401.219363) (xy 178.034079 -401.265876) (xy 178.057751 -401.316373) (xy 178.073819 -401.36978)
			(xy 178.081939 -401.424956) (xy 178.082448 -401.452842) (xy 178.081939 -401.480728) (xy 178.073819 -401.535904)
			(xy 178.057751 -401.589311) (xy 178.034079 -401.639808) (xy 178.003306 -401.686321) (xy 177.966089 -401.727858)
			(xy 177.942508 -401.747482) (xy 179.978302 -401.747482) (xy 179.982373 -401.69186) (xy 179.994499 -401.637423)
			(xy 180.014422 -401.585332) (xy 180.041718 -401.536697) (xy 180.075804 -401.492554) (xy 180.115953 -401.453845)
			(xy 180.161311 -401.421394) (xy 180.210911 -401.395893) (xy 180.263695 -401.377886) (xy 180.318538 -401.367756)
			(xy 180.374272 -401.365719) (xy 180.429709 -401.371819) (xy 180.483666 -401.385925) (xy 180.534995 -401.407737)
			(xy 180.582601 -401.436791) (xy 180.625469 -401.472466) (xy 180.662686 -401.514003) (xy 180.693459 -401.560516)
			(xy 180.717131 -401.611013) (xy 180.733199 -401.66442) (xy 180.741319 -401.719596) (xy 180.741828 -401.747482)
			(xy 180.741319 -401.775368) (xy 180.733199 -401.830544) (xy 180.717131 -401.883951) (xy 180.700375 -401.919694)
			(xy 184.474102 -401.919694) (xy 184.478173 -401.864072) (xy 184.490299 -401.809635) (xy 184.510222 -401.757544)
			(xy 184.537518 -401.708909) (xy 184.571604 -401.664766) (xy 184.611753 -401.626057) (xy 184.657111 -401.593606)
			(xy 184.706711 -401.568105) (xy 184.759495 -401.550098) (xy 184.814338 -401.539968) (xy 184.870072 -401.537931)
			(xy 184.925509 -401.544031) (xy 184.979466 -401.558137) (xy 185.030795 -401.579949) (xy 185.078401 -401.609003)
			(xy 185.121269 -401.644678) (xy 185.158486 -401.686215) (xy 185.189259 -401.732728) (xy 185.212931 -401.783225)
			(xy 185.228999 -401.836632) (xy 185.237119 -401.891808) (xy 185.237628 -401.919694) (xy 187.293502 -401.919694)
			(xy 187.297573 -401.864072) (xy 187.309699 -401.809635) (xy 187.329622 -401.757544) (xy 187.356918 -401.708909)
			(xy 187.391004 -401.664766) (xy 187.431153 -401.626057) (xy 187.476511 -401.593606) (xy 187.526111 -401.568105)
			(xy 187.578895 -401.550098) (xy 187.633738 -401.539968) (xy 187.689472 -401.537931) (xy 187.744909 -401.544031)
			(xy 187.798866 -401.558137) (xy 187.850195 -401.579949) (xy 187.897801 -401.609003) (xy 187.940669 -401.644678)
			(xy 187.977886 -401.686215) (xy 188.008659 -401.732728) (xy 188.032331 -401.783225) (xy 188.048399 -401.836632)
			(xy 188.056519 -401.891808) (xy 188.057028 -401.919694) (xy 188.056519 -401.94758) (xy 188.048399 -402.002756)
			(xy 188.032331 -402.056163) (xy 188.008659 -402.10666) (xy 187.977886 -402.153173) (xy 187.940669 -402.19471)
			(xy 187.897801 -402.230385) (xy 187.850195 -402.259439) (xy 187.798866 -402.281251) (xy 187.744909 -402.295357)
			(xy 187.689472 -402.301457) (xy 187.633738 -402.29942) (xy 187.578895 -402.28929) (xy 187.526111 -402.271283)
			(xy 187.476511 -402.245782) (xy 187.431153 -402.213331) (xy 187.391004 -402.174622) (xy 187.356918 -402.130479)
			(xy 187.329622 -402.081844) (xy 187.309699 -402.029753) (xy 187.297573 -401.975316) (xy 187.293502 -401.919694)
			(xy 185.237628 -401.919694) (xy 185.237119 -401.94758) (xy 185.228999 -402.002756) (xy 185.212931 -402.056163)
			(xy 185.189259 -402.10666) (xy 185.158486 -402.153173) (xy 185.121269 -402.19471) (xy 185.078401 -402.230385)
			(xy 185.030795 -402.259439) (xy 184.979466 -402.281251) (xy 184.925509 -402.295357) (xy 184.870072 -402.301457)
			(xy 184.814338 -402.29942) (xy 184.759495 -402.28929) (xy 184.706711 -402.271283) (xy 184.657111 -402.245782)
			(xy 184.611753 -402.213331) (xy 184.571604 -402.174622) (xy 184.537518 -402.130479) (xy 184.510222 -402.081844)
			(xy 184.490299 -402.029753) (xy 184.478173 -401.975316) (xy 184.474102 -401.919694) (xy 180.700375 -401.919694)
			(xy 180.693459 -401.934448) (xy 180.662686 -401.980961) (xy 180.625469 -402.022498) (xy 180.582601 -402.058173)
			(xy 180.534995 -402.087227) (xy 180.483666 -402.109039) (xy 180.429709 -402.123145) (xy 180.374272 -402.129245)
			(xy 180.318538 -402.127208) (xy 180.263695 -402.117078) (xy 180.210911 -402.099071) (xy 180.161311 -402.07357)
			(xy 180.115953 -402.041119) (xy 180.075804 -402.00241) (xy 180.041718 -401.958267) (xy 180.014422 -401.909632)
			(xy 179.994499 -401.857541) (xy 179.982373 -401.803104) (xy 179.978302 -401.747482) (xy 177.942508 -401.747482)
			(xy 177.923221 -401.763533) (xy 177.875615 -401.792587) (xy 177.824286 -401.814399) (xy 177.770329 -401.828505)
			(xy 177.714892 -401.834605) (xy 177.659158 -401.832568) (xy 177.604315 -401.822438) (xy 177.551531 -401.804431)
			(xy 177.501931 -401.77893) (xy 177.456573 -401.746479) (xy 177.416424 -401.70777) (xy 177.382338 -401.663627)
			(xy 177.355042 -401.614992) (xy 177.335119 -401.562901) (xy 177.322993 -401.508464) (xy 177.318922 -401.452842)
			(xy 176.605184 -401.452842) (xy 176.605184 -403.479) (xy 177.290982 -403.479) (xy 177.295053 -403.423378)
			(xy 177.307179 -403.368941) (xy 177.327102 -403.31685) (xy 177.354398 -403.268215) (xy 177.388484 -403.224072)
			(xy 177.428633 -403.185363) (xy 177.473991 -403.152912) (xy 177.523591 -403.127411) (xy 177.576375 -403.109404)
			(xy 177.631218 -403.099274) (xy 177.686952 -403.097237) (xy 177.742389 -403.103337) (xy 177.796346 -403.117443)
			(xy 177.847675 -403.139255) (xy 177.895281 -403.168309) (xy 177.938149 -403.203984) (xy 177.975366 -403.245521)
			(xy 178.006139 -403.292034) (xy 178.029811 -403.342531) (xy 178.045879 -403.395938) (xy 178.053999 -403.451114)
			(xy 178.054508 -403.479) (xy 178.053999 -403.506886) (xy 178.045879 -403.562062) (xy 178.029811 -403.615469)
			(xy 178.006139 -403.665966) (xy 177.975366 -403.712479) (xy 177.938149 -403.754016) (xy 177.895281 -403.789691)
			(xy 177.847675 -403.818745) (xy 177.796346 -403.840557) (xy 177.742389 -403.854663) (xy 177.686952 -403.860763)
			(xy 177.631218 -403.858726) (xy 177.576375 -403.848596) (xy 177.523591 -403.830589) (xy 177.473991 -403.805088)
			(xy 177.428633 -403.772637) (xy 177.388484 -403.733928) (xy 177.354398 -403.689785) (xy 177.327102 -403.64115)
			(xy 177.307179 -403.589059) (xy 177.295053 -403.534622) (xy 177.290982 -403.479) (xy 176.605184 -403.479)
			(xy 176.605184 -406.273) (xy 177.290982 -406.273) (xy 177.295053 -406.217378) (xy 177.307179 -406.162941)
			(xy 177.327102 -406.11085) (xy 177.354398 -406.062215) (xy 177.388484 -406.018072) (xy 177.428633 -405.979363)
			(xy 177.473991 -405.946912) (xy 177.523591 -405.921411) (xy 177.576375 -405.903404) (xy 177.631218 -405.893274)
			(xy 177.686952 -405.891237) (xy 177.742389 -405.897337) (xy 177.796346 -405.911443) (xy 177.847675 -405.933255)
			(xy 177.895281 -405.962309) (xy 177.938149 -405.997984) (xy 177.975366 -406.039521) (xy 178.006139 -406.086034)
			(xy 178.029811 -406.136531) (xy 178.045879 -406.189938) (xy 178.053999 -406.245114) (xy 178.054508 -406.273)
			(xy 178.053999 -406.300886) (xy 178.045879 -406.356062) (xy 178.029811 -406.409469) (xy 178.006139 -406.459966)
			(xy 177.975366 -406.506479) (xy 177.938149 -406.548016) (xy 177.895281 -406.583691) (xy 177.847675 -406.612745)
			(xy 177.796346 -406.634557) (xy 177.742389 -406.648663) (xy 177.686952 -406.654763) (xy 177.631218 -406.652726)
			(xy 177.576375 -406.642596) (xy 177.523591 -406.624589) (xy 177.473991 -406.599088) (xy 177.428633 -406.566637)
			(xy 177.388484 -406.527928) (xy 177.354398 -406.483785) (xy 177.327102 -406.43515) (xy 177.307179 -406.383059)
			(xy 177.295053 -406.328622) (xy 177.290982 -406.273) (xy 176.605184 -406.273) (xy 176.605184 -408.559)
			(xy 177.290982 -408.559) (xy 177.295053 -408.503378) (xy 177.307179 -408.448941) (xy 177.327102 -408.39685)
			(xy 177.354398 -408.348215) (xy 177.388484 -408.304072) (xy 177.428633 -408.265363) (xy 177.473991 -408.232912)
			(xy 177.523591 -408.207411) (xy 177.576375 -408.189404) (xy 177.631218 -408.179274) (xy 177.686952 -408.177237)
			(xy 177.742389 -408.183337) (xy 177.796346 -408.197443) (xy 177.847675 -408.219255) (xy 177.895281 -408.248309)
			(xy 177.938149 -408.283984) (xy 177.975366 -408.325521) (xy 178.006139 -408.372034) (xy 178.029811 -408.422531)
			(xy 178.045879 -408.475938) (xy 178.053999 -408.531114) (xy 178.054508 -408.559) (xy 178.053999 -408.586886)
			(xy 178.045879 -408.642062) (xy 178.029811 -408.695469) (xy 178.006139 -408.745966) (xy 177.975366 -408.792479)
			(xy 177.938149 -408.834016) (xy 177.895281 -408.869691) (xy 177.847675 -408.898745) (xy 177.796346 -408.920557)
			(xy 177.742389 -408.934663) (xy 177.686952 -408.940763) (xy 177.631218 -408.938726) (xy 177.576375 -408.928596)
			(xy 177.523591 -408.910589) (xy 177.473991 -408.885088) (xy 177.428633 -408.852637) (xy 177.388484 -408.813928)
			(xy 177.354398 -408.769785) (xy 177.327102 -408.72115) (xy 177.307179 -408.669059) (xy 177.295053 -408.614622)
			(xy 177.290982 -408.559) (xy 176.605184 -408.559) (xy 176.605184 -409.05176) (xy 176.605946 -409.052268)
			(xy 176.605946 -409.91282) (xy 176.605184 -409.913328) (xy 176.605184 -410.623258) (xy 177.271678 -410.623258)
			(xy 177.275749 -410.567636) (xy 177.287875 -410.513199) (xy 177.307798 -410.461108) (xy 177.335094 -410.412473)
			(xy 177.36918 -410.36833) (xy 177.409329 -410.329621) (xy 177.454687 -410.29717) (xy 177.504287 -410.271669)
			(xy 177.557071 -410.253662) (xy 177.611914 -410.243532) (xy 177.667648 -410.241495) (xy 177.723085 -410.247595)
			(xy 177.777042 -410.261701) (xy 177.828371 -410.283513) (xy 177.875977 -410.312567) (xy 177.918845 -410.348242)
			(xy 177.956062 -410.389779) (xy 177.986835 -410.436292) (xy 178.010507 -410.486789) (xy 178.026575 -410.540196)
			(xy 178.034695 -410.595372) (xy 178.035204 -410.623258) (xy 178.034695 -410.651144) (xy 178.026575 -410.70632)
			(xy 178.010507 -410.759727) (xy 177.986835 -410.810224) (xy 177.956062 -410.856737) (xy 177.918845 -410.898274)
			(xy 177.875977 -410.933949) (xy 177.853999 -410.947362) (xy 179.770022 -410.947362) (xy 179.774093 -410.89174)
			(xy 179.786219 -410.837303) (xy 179.806142 -410.785212) (xy 179.833438 -410.736577) (xy 179.867524 -410.692434)
			(xy 179.907673 -410.653725) (xy 179.953031 -410.621274) (xy 180.002631 -410.595773) (xy 180.055415 -410.577766)
			(xy 180.110258 -410.567636) (xy 180.165992 -410.565599) (xy 180.221429 -410.571699) (xy 180.275386 -410.585805)
			(xy 180.326715 -410.607617) (xy 180.374321 -410.636671) (xy 180.417189 -410.672346) (xy 180.454406 -410.713883)
			(xy 180.485179 -410.760396) (xy 180.508851 -410.810893) (xy 180.524919 -410.8643) (xy 180.533039 -410.919476)
			(xy 180.533548 -410.947362) (xy 180.533039 -410.975248) (xy 180.524919 -411.030424) (xy 180.508851 -411.083831)
			(xy 180.485179 -411.134328) (xy 180.454406 -411.180841) (xy 180.417189 -411.222378) (xy 180.374321 -411.258053)
			(xy 180.326715 -411.287107) (xy 180.275386 -411.308919) (xy 180.221429 -411.323025) (xy 180.165992 -411.329125)
			(xy 180.110258 -411.327088) (xy 180.055415 -411.316958) (xy 180.002631 -411.298951) (xy 179.953031 -411.27345)
			(xy 179.907673 -411.240999) (xy 179.867524 -411.20229) (xy 179.833438 -411.158147) (xy 179.806142 -411.109512)
			(xy 179.786219 -411.057421) (xy 179.774093 -411.002984) (xy 179.770022 -410.947362) (xy 177.853999 -410.947362)
			(xy 177.828371 -410.963003) (xy 177.777042 -410.984815) (xy 177.723085 -410.998921) (xy 177.667648 -411.005021)
			(xy 177.611914 -411.002984) (xy 177.557071 -410.992854) (xy 177.504287 -410.974847) (xy 177.454687 -410.949346)
			(xy 177.409329 -410.916895) (xy 177.36918 -410.878186) (xy 177.335094 -410.834043) (xy 177.307798 -410.785408)
			(xy 177.287875 -410.733317) (xy 177.275749 -410.67888) (xy 177.271678 -410.623258) (xy 176.605184 -410.623258)
			(xy 176.605184 -411.587188) (xy 176.595786 -411.596586) (xy 176.588944 -411.603985) (xy 176.581227 -411.622584)
			(xy 176.5808 -411.632654) (xy 176.5808 -411.883352) (xy 176.581364 -411.89446) (xy 176.590716 -411.914612)
			(xy 176.598834 -411.922214) (xy 176.66716 -411.979618) (xy 176.689004 -411.985206) (xy 176.70018 -411.983174)
			(xy 176.716617 -411.980442) (xy 176.749812 -411.977517) (xy 176.766474 -411.977332) (xy 176.766982 -411.977332)
			(xy 176.795257 -411.977844) (xy 176.851186 -411.986192) (xy 176.90527 -412.002707) (xy 176.956322 -412.027027)
			(xy 177.003223 -412.05862) (xy 177.044945 -412.096791) (xy 177.080573 -412.140706) (xy 177.095404 -412.164784)
			(xy 177.100203 -412.17216) (xy 177.113756 -412.183362) (xy 177.1303 -412.189316) (xy 177.139092 -412.189676)
			(xy 181.39029 -412.189676)
		)
		(stroke
			(width 0)
			(type solid)
		)
		(fill yes)
		(layer "In13.Cu")
		(net "AGND_HSC")
	)
	(gr_poly
		(pts
			(xy 326.079104 -403.85238) (xy 326.083515 -403.852296) (xy 326.092205 -403.850771) (xy 326.096376 -403.849332)
			(xy 327.482454 -403.347936) (xy 327.509295 -403.338585) (xy 327.564386 -403.324585) (xy 327.592436 -403.319996)
			(xy 328.920094 -403.11832) (xy 328.929746 -403.11578) (xy 331.008228 -402.364194) (xy 331.016423 -402.360821)
			(xy 331.030033 -402.349492) (xy 331.038996 -402.33422) (xy 331.040994 -402.325586) (xy 331.059282 -402.226018)
			(xy 331.050392 -402.200618) (xy 331.040232 -402.191728) (xy 331.038708 -402.190458) (xy 331.031596 -402.184362)
			(xy 331.014578 -402.178012) (xy 330.929234 -402.178012) (xy 330.912216 -402.184362) (xy 330.905104 -402.190458)
			(xy 330.884171 -402.208099) (xy 330.838203 -402.237823) (xy 330.788457 -402.260669) (xy 330.735955 -402.276165)
			(xy 330.681777 -402.283994) (xy 330.627035 -402.283994) (xy 330.572857 -402.276165) (xy 330.520355 -402.260669)
			(xy 330.470609 -402.237823) (xy 330.424641 -402.208099) (xy 330.403708 -402.190458) (xy 330.396596 -402.184362)
			(xy 330.379578 -402.178012) (xy 330.294234 -402.178012) (xy 330.277216 -402.184362) (xy 330.270104 -402.190458)
			(xy 330.249174 -402.208102) (xy 330.203208 -402.237832) (xy 330.153461 -402.260678) (xy 330.100958 -402.276171)
			(xy 330.046777 -402.283991) (xy 330.019406 -402.284438) (xy 329.992154 -402.283953) (xy 329.938204 -402.276197)
			(xy 329.885907 -402.260843) (xy 329.836327 -402.238202) (xy 329.790473 -402.208737) (xy 329.74928 -402.173046)
			(xy 329.713585 -402.131856) (xy 329.684115 -402.086005) (xy 329.66147 -402.036427) (xy 329.646111 -401.984132)
			(xy 329.63835 -401.930182) (xy 329.637898 -401.90293) (xy 329.638375 -401.875562) (xy 329.646207 -401.821388)
			(xy 329.661702 -401.76889) (xy 329.684541 -401.719146) (xy 329.714254 -401.673176) (xy 329.731878 -401.652232)
			(xy 329.737974 -401.64512) (xy 329.744324 -401.628102) (xy 329.744324 -401.542758) (xy 329.737974 -401.52574)
			(xy 329.731878 -401.518628) (xy 329.714237 -401.497694) (xy 329.684512 -401.451725) (xy 329.661665 -401.401977)
			(xy 329.646167 -401.349474) (xy 329.638336 -401.295294) (xy 329.638333 -401.240551) (xy 329.646158 -401.18637)
			(xy 329.66165 -401.133865) (xy 329.68449 -401.084115) (xy 329.71421 -401.038142) (xy 329.731878 -401.017232)
			(xy 329.737974 -401.01012) (xy 329.744324 -400.993102) (xy 329.744324 -400.907758) (xy 329.737974 -400.89074)
			(xy 329.731878 -400.883628) (xy 329.714237 -400.862694) (xy 329.684512 -400.816725) (xy 329.661665 -400.766977)
			(xy 329.646167 -400.714474) (xy 329.638336 -400.660294) (xy 329.638333 -400.605551) (xy 329.646158 -400.55137)
			(xy 329.66165 -400.498865) (xy 329.68449 -400.449115) (xy 329.71421 -400.403142) (xy 329.731878 -400.382232)
			(xy 329.737974 -400.37512) (xy 329.744324 -400.358102) (xy 329.744324 -400.272758) (xy 329.737974 -400.25574)
			(xy 329.731878 -400.248628) (xy 329.714235 -400.227697) (xy 329.684508 -400.18173) (xy 329.661662 -400.131984)
			(xy 329.646169 -400.079481) (xy 329.638347 -400.025301) (xy 329.637898 -399.99793) (xy 329.638374 -399.970459)
			(xy 329.646249 -399.916084) (xy 329.661841 -399.863401) (xy 329.684827 -399.813498) (xy 329.714732 -399.767408)
			(xy 329.750938 -399.726083) (xy 329.771502 -399.707862) (xy 329.779122 -399.701258) (xy 329.788266 -399.683478)
			(xy 329.795378 -399.591276) (xy 329.789028 -399.571972) (xy 329.78217 -399.564352) (xy 329.764752 -399.543461)
			(xy 329.7354 -399.49767) (xy 329.712861 -399.448169) (xy 329.697594 -399.395965) (xy 329.689909 -399.34212)
			(xy 329.68946 -399.314924) (xy 329.689937 -399.287556) (xy 329.697772 -399.233384) (xy 329.713269 -399.180888)
			(xy 329.736111 -399.131146) (xy 329.765828 -399.08518) (xy 329.78344 -399.064226) (xy 329.789536 -399.057114)
			(xy 329.795886 -399.040096) (xy 329.795886 -398.954752) (xy 329.789536 -398.937734) (xy 329.78344 -398.930622)
			(xy 329.765795 -398.909692) (xy 329.736063 -398.863727) (xy 329.713215 -398.81398) (xy 329.69772 -398.761476)
			(xy 329.689897 -398.707295) (xy 329.68946 -398.679924) (xy 329.689946 -398.652673) (xy 329.697702 -398.598725)
			(xy 329.713057 -398.54643) (xy 329.735699 -398.496853) (xy 329.765165 -398.451003) (xy 329.800856 -398.409812)
			(xy 329.842047 -398.374121) (xy 329.887897 -398.344655) (xy 329.937474 -398.322013) (xy 329.989769 -398.306658)
			(xy 330.043717 -398.298902) (xy 330.098219 -398.298902) (xy 330.152167 -398.306658) (xy 330.204462 -398.322013)
			(xy 330.254039 -398.344655) (xy 330.299889 -398.374121) (xy 330.34108 -398.409812) (xy 330.376771 -398.451003)
			(xy 330.406237 -398.496853) (xy 330.428879 -398.54643) (xy 330.444234 -398.598725) (xy 330.45199 -398.652673)
			(xy 330.452476 -398.679924) (xy 330.452003 -398.707293) (xy 330.444175 -398.761469) (xy 330.428685 -398.813971)
			(xy 330.405849 -398.863719) (xy 330.376138 -398.909692) (xy 330.358496 -398.930622) (xy 330.3524 -398.937734)
			(xy 330.34605 -398.954752) (xy 330.34605 -399.040096) (xy 330.3524 -399.057114) (xy 330.358496 -399.064226)
			(xy 330.376137 -399.085158) (xy 330.40586 -399.131125) (xy 330.4287 -399.180872) (xy 330.444187 -399.233375)
			(xy 330.452002 -399.287554) (xy 330.452476 -399.314924) (xy 330.451923 -399.344539) (xy 330.442783 -399.403058)
			(xy 330.42471 -399.459462) (xy 330.398139 -399.512397) (xy 330.363708 -399.56059) (xy 330.322244 -399.602884)
			(xy 330.298806 -399.620994) (xy 330.290371 -399.627915) (xy 330.279836 -399.646998) (xy 330.278486 -399.657824)
			(xy 330.2762 -399.690082) (xy 330.275843 -399.701026) (xy 330.283348 -399.721571) (xy 330.290678 -399.729706)
			(xy 330.299568 -399.739104) (xy 330.352908 -399.739104) (xy 330.362717 -399.738601) (xy 330.380872 -399.731151)
			(xy 330.388214 -399.724626) (xy 330.409713 -399.704451) (xy 330.45777 -399.670301) (xy 330.51051 -399.643951)
			(xy 330.566675 -399.626028) (xy 330.624928 -399.61696) (xy 330.654406 -399.616422) (xy 330.681776 -399.616894)
			(xy 330.735953 -399.624719) (xy 330.788456 -399.640208) (xy 330.838206 -399.663041) (xy 330.884181 -399.692752)
			(xy 330.905104 -399.710402) (xy 330.912216 -399.716498) (xy 330.929234 -399.722848) (xy 331.014578 -399.722848)
			(xy 331.031596 -399.716498) (xy 331.038708 -399.710402) (xy 331.059641 -399.692761) (xy 331.105609 -399.663037)
			(xy 331.155355 -399.640191) (xy 331.207857 -399.624695) (xy 331.262035 -399.616866) (xy 331.316777 -399.616866)
			(xy 331.370955 -399.624695) (xy 331.423457 -399.640191) (xy 331.473203 -399.663037) (xy 331.519171 -399.692761)
			(xy 331.540104 -399.710402) (xy 331.547216 -399.716498) (xy 331.564234 -399.722848) (xy 331.649578 -399.722848)
			(xy 331.666596 -399.716498) (xy 331.673708 -399.710402) (xy 331.694639 -399.69276) (xy 331.740606 -399.663035)
			(xy 331.790353 -399.640193) (xy 331.842856 -399.624704) (xy 331.897036 -399.616886) (xy 331.924406 -399.616422)
			(xy 331.951658 -399.616886) (xy 332.005606 -399.624644) (xy 332.057902 -399.64) (xy 332.107479 -399.662644)
			(xy 332.15333 -399.692112) (xy 332.194519 -399.727806) (xy 332.230209 -399.768999) (xy 332.259674 -399.814852)
			(xy 332.282312 -399.864432) (xy 332.297664 -399.916729) (xy 332.305417 -399.970678) (xy 332.305914 -399.99793)
			(xy 332.30544 -400.025299) (xy 332.297613 -400.079476) (xy 332.282123 -400.131977) (xy 332.259289 -400.181726)
			(xy 332.229579 -400.227701) (xy 332.211934 -400.248628) (xy 332.205838 -400.25574) (xy 332.199488 -400.272758)
			(xy 332.199488 -400.358102) (xy 332.205838 -400.37512) (xy 332.211934 -400.382232) (xy 332.229574 -400.403164)
			(xy 332.259298 -400.44913) (xy 332.282141 -400.498875) (xy 332.297635 -400.551376) (xy 332.305461 -400.605553)
			(xy 332.305458 -400.660292) (xy 332.297626 -400.714468) (xy 332.282125 -400.766967) (xy 332.259276 -400.816709)
			(xy 332.229547 -400.862672) (xy 332.211934 -400.883628) (xy 332.205838 -400.89074) (xy 332.199488 -400.907758)
			(xy 332.199488 -400.993102) (xy 332.205838 -401.01012) (xy 332.211934 -401.017232) (xy 332.229302 -401.03782)
			(xy 332.258672 -401.082969) (xy 332.281391 -401.131805) (xy 332.289658 -401.15744) (xy 332.293468 -401.170648)
			(xy 332.312772 -401.188936) (xy 332.410308 -401.21332) (xy 332.418875 -401.21512) (xy 332.436291 -401.213463)
			(xy 332.452136 -401.206048) (xy 332.458568 -401.200112) (xy 332.707488 -400.951192) (xy 332.70825 -400.910298)
			(xy 332.694026 -400.895058) (xy 332.674717 -400.873719) (xy 332.642084 -400.826321) (xy 332.616936 -400.774561)
			(xy 332.599846 -400.719611) (xy 332.591199 -400.662719) (xy 332.590648 -400.633946) (xy 332.591108 -400.60669)
			(xy 332.598859 -400.552732) (xy 332.614211 -400.500426) (xy 332.63685 -400.450837) (xy 332.666316 -400.404975)
			(xy 332.702009 -400.363773) (xy 332.743203 -400.32807) (xy 332.789058 -400.298593) (xy 332.838641 -400.275942)
			(xy 332.890943 -400.260578) (xy 332.9449 -400.252814) (xy 332.972156 -400.252438) (xy 332.999054 -400.252904)
			(xy 333.052316 -400.260472) (xy 333.103986 -400.27545) (xy 333.153038 -400.297541) (xy 333.198499 -400.326307)
			(xy 333.219298 -400.34337) (xy 333.226553 -400.349046) (xy 333.243871 -400.355281) (xy 333.25308 -400.355562)
			(xy 333.283306 -400.355054) (xy 333.293162 -400.354443) (xy 333.311322 -400.34673) (xy 333.318612 -400.340068)
			(xy 333.641954 -400.016726) (xy 333.649354 -400.009885) (xy 333.667953 -400.002167) (xy 333.678022 -400.00174)
			(xy 333.689452 -400.00174) (xy 333.74838 -399.875502) (xy 333.744316 -399.846292) (xy 333.734918 -399.834862)
			(xy 333.716829 -399.812381) (xy 333.687985 -399.762411) (xy 333.668258 -399.70819) (xy 333.65825 -399.651367)
			(xy 333.657702 -399.622518) (xy 333.658117 -399.598424) (xy 333.665077 -399.550743) (xy 333.678895 -399.504581)
			(xy 333.68869 -399.482564) (xy 333.694024 -399.471134) (xy 333.692754 -399.445988) (xy 333.63662 -399.352008)
			(xy 333.61503 -399.339054) (xy 333.60233 -399.338292) (xy 333.577337 -399.336423) (xy 333.528297 -399.326091)
			(xy 333.481377 -399.308478) (xy 333.437651 -399.283987) (xy 333.398122 -399.253179) (xy 333.363694 -399.216759)
			(xy 333.335155 -399.175561) (xy 333.313159 -399.130529) (xy 333.298209 -399.082694) (xy 333.290648 -399.03315)
			(xy 333.290164 -399.008092) (xy 333.290558 -398.984858) (xy 333.297061 -398.938848) (xy 333.309939 -398.8942)
			(xy 333.328937 -398.851794) (xy 333.353683 -398.812463) (xy 333.368396 -398.794478) (xy 333.374492 -398.787366)
			(xy 333.380588 -398.770856) (xy 333.380588 -398.686528) (xy 333.374492 -398.670018) (xy 333.368396 -398.662906)
			(xy 333.353687 -398.644916) (xy 333.32893 -398.60559) (xy 333.309922 -398.563186) (xy 333.297039 -398.518538)
			(xy 333.290534 -398.472527) (xy 333.290164 -398.449292) (xy 333.290674 -398.423305) (xy 333.298804 -398.37197)
			(xy 333.314865 -398.32254) (xy 333.338461 -398.27623) (xy 333.369011 -398.234182) (xy 333.405762 -398.197431)
			(xy 333.44781 -398.166881) (xy 333.49412 -398.143285) (xy 333.54355 -398.127224) (xy 333.594885 -398.119094)
			(xy 333.646859 -398.119094) (xy 333.698194 -398.127224) (xy 333.747624 -398.143285) (xy 333.793934 -398.166881)
			(xy 333.835982 -398.197431) (xy 333.872733 -398.234182) (xy 333.903283 -398.27623) (xy 333.926879 -398.32254)
			(xy 333.94294 -398.37197) (xy 333.95107 -398.423305) (xy 333.95158 -398.449292) (xy 333.951187 -398.472526)
			(xy 333.944685 -398.518536) (xy 333.937917 -398.542002) (xy 335.612752 -398.542002) (xy 335.616712 -398.492948)
			(xy 335.628489 -398.445164) (xy 335.64778 -398.399888) (xy 335.674083 -398.358292) (xy 335.706718 -398.321455)
			(xy 335.744839 -398.29033) (xy 335.78746 -398.265723) (xy 335.833476 -398.248271) (xy 335.881695 -398.238427)
			(xy 335.93087 -398.236446) (xy 335.979725 -398.242378) (xy 336.026996 -398.25607) (xy 336.071458 -398.277168)
			(xy 336.111961 -398.305124) (xy 336.147454 -398.339216) (xy 336.177019 -398.37856) (xy 336.19989 -398.422137)
			(xy 336.215474 -398.468818) (xy 336.223369 -398.517395) (xy 336.223864 -398.542002) (xy 336.812902 -398.542002)
			(xy 336.816862 -398.492948) (xy 336.828639 -398.445164) (xy 336.84793 -398.399888) (xy 336.874233 -398.358292)
			(xy 336.906868 -398.321455) (xy 336.944989 -398.29033) (xy 336.98761 -398.265723) (xy 337.033626 -398.248271)
			(xy 337.081845 -398.238427) (xy 337.13102 -398.236446) (xy 337.179875 -398.242378) (xy 337.227146 -398.25607)
			(xy 337.271608 -398.277168) (xy 337.312111 -398.305124) (xy 337.347604 -398.339216) (xy 337.377169 -398.37856)
			(xy 337.40004 -398.422137) (xy 337.415624 -398.468818) (xy 337.423519 -398.517395) (xy 337.424014 -398.542002)
			(xy 338.013052 -398.542002) (xy 338.017012 -398.492948) (xy 338.028789 -398.445164) (xy 338.04808 -398.399888)
			(xy 338.074383 -398.358292) (xy 338.107018 -398.321455) (xy 338.145139 -398.29033) (xy 338.18776 -398.265723)
			(xy 338.233776 -398.248271) (xy 338.281995 -398.238427) (xy 338.33117 -398.236446) (xy 338.380025 -398.242378)
			(xy 338.427296 -398.25607) (xy 338.471758 -398.277168) (xy 338.512261 -398.305124) (xy 338.547754 -398.339216)
			(xy 338.577319 -398.37856) (xy 338.60019 -398.422137) (xy 338.615774 -398.468818) (xy 338.623669 -398.517395)
			(xy 338.624164 -398.542002) (xy 339.212948 -398.542002) (xy 339.216908 -398.492948) (xy 339.228685 -398.445164)
			(xy 339.247976 -398.399888) (xy 339.274279 -398.358292) (xy 339.306914 -398.321455) (xy 339.345035 -398.29033)
			(xy 339.387656 -398.265723) (xy 339.433672 -398.248271) (xy 339.481891 -398.238427) (xy 339.531066 -398.236446)
			(xy 339.579921 -398.242378) (xy 339.627192 -398.25607) (xy 339.671654 -398.277168) (xy 339.712157 -398.305124)
			(xy 339.74765 -398.339216) (xy 339.777215 -398.37856) (xy 339.800086 -398.422137) (xy 339.81567 -398.468818)
			(xy 339.823565 -398.517395) (xy 339.82406 -398.542002) (xy 340.413098 -398.542002) (xy 340.417058 -398.492948)
			(xy 340.428835 -398.445164) (xy 340.448126 -398.399888) (xy 340.474429 -398.358292) (xy 340.507064 -398.321455)
			(xy 340.545185 -398.29033) (xy 340.587806 -398.265723) (xy 340.633822 -398.248271) (xy 340.682041 -398.238427)
			(xy 340.731216 -398.236446) (xy 340.780071 -398.242378) (xy 340.827342 -398.25607) (xy 340.871804 -398.277168)
			(xy 340.912307 -398.305124) (xy 340.9478 -398.339216) (xy 340.977365 -398.37856) (xy 341.000236 -398.422137)
			(xy 341.01582 -398.468818) (xy 341.023715 -398.517395) (xy 341.02421 -398.542002) (xy 341.612994 -398.542002)
			(xy 341.616954 -398.492948) (xy 341.628731 -398.445164) (xy 341.648022 -398.399888) (xy 341.674325 -398.358292)
			(xy 341.70696 -398.321455) (xy 341.745081 -398.29033) (xy 341.787702 -398.265723) (xy 341.833718 -398.248271)
			(xy 341.881937 -398.238427) (xy 341.931112 -398.236446) (xy 341.979967 -398.242378) (xy 342.027238 -398.25607)
			(xy 342.0717 -398.277168) (xy 342.112203 -398.305124) (xy 342.147696 -398.339216) (xy 342.177261 -398.37856)
			(xy 342.200132 -398.422137) (xy 342.215716 -398.468818) (xy 342.223611 -398.517395) (xy 342.224106 -398.542002)
			(xy 342.81289 -398.542002) (xy 342.81685 -398.492948) (xy 342.828627 -398.445164) (xy 342.847918 -398.399888)
			(xy 342.874221 -398.358292) (xy 342.906856 -398.321455) (xy 342.944977 -398.29033) (xy 342.987598 -398.265723)
			(xy 343.033614 -398.248271) (xy 343.081833 -398.238427) (xy 343.131008 -398.236446) (xy 343.179863 -398.242378)
			(xy 343.227134 -398.25607) (xy 343.271596 -398.277168) (xy 343.312099 -398.305124) (xy 343.347592 -398.339216)
			(xy 343.377157 -398.37856) (xy 343.400028 -398.422137) (xy 343.415612 -398.468818) (xy 343.423507 -398.517395)
			(xy 343.424002 -398.542002) (xy 344.01304 -398.542002) (xy 344.017 -398.492948) (xy 344.028777 -398.445164)
			(xy 344.048068 -398.399888) (xy 344.074371 -398.358292) (xy 344.107006 -398.321455) (xy 344.145127 -398.29033)
			(xy 344.187748 -398.265723) (xy 344.233764 -398.248271) (xy 344.281983 -398.238427) (xy 344.331158 -398.236446)
			(xy 344.380013 -398.242378) (xy 344.427284 -398.25607) (xy 344.471746 -398.277168) (xy 344.512249 -398.305124)
			(xy 344.547742 -398.339216) (xy 344.577307 -398.37856) (xy 344.600178 -398.422137) (xy 344.615762 -398.468818)
			(xy 344.623657 -398.517395) (xy 344.624152 -398.542002) (xy 345.212936 -398.542002) (xy 345.216896 -398.492948)
			(xy 345.228673 -398.445164) (xy 345.247964 -398.399888) (xy 345.274267 -398.358292) (xy 345.306902 -398.321455)
			(xy 345.345023 -398.29033) (xy 345.387644 -398.265723) (xy 345.43366 -398.248271) (xy 345.481879 -398.238427)
			(xy 345.531054 -398.236446) (xy 345.579909 -398.242378) (xy 345.62718 -398.25607) (xy 345.671642 -398.277168)
			(xy 345.712145 -398.305124) (xy 345.747638 -398.339216) (xy 345.777203 -398.37856) (xy 345.800074 -398.422137)
			(xy 345.815658 -398.468818) (xy 345.823553 -398.517395) (xy 345.824048 -398.542002) (xy 346.413086 -398.542002)
			(xy 346.417046 -398.492948) (xy 346.428823 -398.445164) (xy 346.448114 -398.399888) (xy 346.474417 -398.358292)
			(xy 346.507052 -398.321455) (xy 346.545173 -398.29033) (xy 346.587794 -398.265723) (xy 346.63381 -398.248271)
			(xy 346.682029 -398.238427) (xy 346.731204 -398.236446) (xy 346.780059 -398.242378) (xy 346.82733 -398.25607)
			(xy 346.871792 -398.277168) (xy 346.912295 -398.305124) (xy 346.947788 -398.339216) (xy 346.977353 -398.37856)
			(xy 347.000224 -398.422137) (xy 347.015808 -398.468818) (xy 347.023703 -398.517395) (xy 347.024198 -398.542002)
			(xy 347.612982 -398.542002) (xy 347.616942 -398.492948) (xy 347.628719 -398.445164) (xy 347.64801 -398.399888)
			(xy 347.674313 -398.358292) (xy 347.706948 -398.321455) (xy 347.745069 -398.29033) (xy 347.78769 -398.265723)
			(xy 347.833706 -398.248271) (xy 347.881925 -398.238427) (xy 347.9311 -398.236446) (xy 347.979955 -398.242378)
			(xy 348.027226 -398.25607) (xy 348.071688 -398.277168) (xy 348.112191 -398.305124) (xy 348.147684 -398.339216)
			(xy 348.177249 -398.37856) (xy 348.20012 -398.422137) (xy 348.215704 -398.468818) (xy 348.223599 -398.517395)
			(xy 348.224094 -398.542002) (xy 348.812878 -398.542002) (xy 348.816838 -398.492948) (xy 348.828615 -398.445164)
			(xy 348.847906 -398.399888) (xy 348.874209 -398.358292) (xy 348.906844 -398.321455) (xy 348.944965 -398.29033)
			(xy 348.987586 -398.265723) (xy 349.033602 -398.248271) (xy 349.081821 -398.238427) (xy 349.130996 -398.236446)
			(xy 349.179851 -398.242378) (xy 349.227122 -398.25607) (xy 349.271584 -398.277168) (xy 349.312087 -398.305124)
			(xy 349.34758 -398.339216) (xy 349.377145 -398.37856) (xy 349.400016 -398.422137) (xy 349.4156 -398.468818)
			(xy 349.423495 -398.517395) (xy 349.42399 -398.542002) (xy 350.013028 -398.542002) (xy 350.016988 -398.492948)
			(xy 350.028765 -398.445164) (xy 350.048056 -398.399888) (xy 350.074359 -398.358292) (xy 350.106994 -398.321455)
			(xy 350.145115 -398.29033) (xy 350.187736 -398.265723) (xy 350.233752 -398.248271) (xy 350.281971 -398.238427)
			(xy 350.331146 -398.236446) (xy 350.380001 -398.242378) (xy 350.427272 -398.25607) (xy 350.471734 -398.277168)
			(xy 350.512237 -398.305124) (xy 350.54773 -398.339216) (xy 350.577295 -398.37856) (xy 350.600166 -398.422137)
			(xy 350.61575 -398.468818) (xy 350.623645 -398.517395) (xy 350.62414 -398.542002) (xy 351.212924 -398.542002)
			(xy 351.216884 -398.492948) (xy 351.228661 -398.445164) (xy 351.247952 -398.399888) (xy 351.274255 -398.358292)
			(xy 351.30689 -398.321455) (xy 351.345011 -398.29033) (xy 351.387632 -398.265723) (xy 351.433648 -398.248271)
			(xy 351.481867 -398.238427) (xy 351.531042 -398.236446) (xy 351.579897 -398.242378) (xy 351.627168 -398.25607)
			(xy 351.67163 -398.277168) (xy 351.712133 -398.305124) (xy 351.747626 -398.339216) (xy 351.777191 -398.37856)
			(xy 351.800062 -398.422137) (xy 351.815646 -398.468818) (xy 351.823541 -398.517395) (xy 351.824036 -398.542002)
			(xy 352.413074 -398.542002) (xy 352.417034 -398.492948) (xy 352.428811 -398.445164) (xy 352.448102 -398.399888)
			(xy 352.474405 -398.358292) (xy 352.50704 -398.321455) (xy 352.545161 -398.29033) (xy 352.587782 -398.265723)
			(xy 352.633798 -398.248271) (xy 352.682017 -398.238427) (xy 352.731192 -398.236446) (xy 352.780047 -398.242378)
			(xy 352.827318 -398.25607) (xy 352.87178 -398.277168) (xy 352.912283 -398.305124) (xy 352.947776 -398.339216)
			(xy 352.977341 -398.37856) (xy 353.000212 -398.422137) (xy 353.015796 -398.468818) (xy 353.023691 -398.517395)
			(xy 353.024186 -398.542002) (xy 353.61297 -398.542002) (xy 353.61693 -398.492948) (xy 353.628707 -398.445164)
			(xy 353.647998 -398.399888) (xy 353.674301 -398.358292) (xy 353.706936 -398.321455) (xy 353.745057 -398.29033)
			(xy 353.787678 -398.265723) (xy 353.833694 -398.248271) (xy 353.881913 -398.238427) (xy 353.931088 -398.236446)
			(xy 353.979943 -398.242378) (xy 354.027214 -398.25607) (xy 354.071676 -398.277168) (xy 354.112179 -398.305124)
			(xy 354.147672 -398.339216) (xy 354.177237 -398.37856) (xy 354.200108 -398.422137) (xy 354.215692 -398.468818)
			(xy 354.223587 -398.517395) (xy 354.224082 -398.542002) (xy 354.223587 -398.566609) (xy 354.215692 -398.615186)
			(xy 354.200108 -398.661867) (xy 354.177237 -398.705444) (xy 354.147672 -398.744788) (xy 354.112179 -398.77888)
			(xy 354.071676 -398.806836) (xy 354.027214 -398.827934) (xy 353.979943 -398.841626) (xy 353.931088 -398.847558)
			(xy 353.881913 -398.845577) (xy 353.833694 -398.835733) (xy 353.787678 -398.818281) (xy 353.745057 -398.793674)
			(xy 353.706936 -398.762549) (xy 353.674301 -398.725712) (xy 353.647998 -398.684116) (xy 353.628707 -398.63884)
			(xy 353.61693 -398.591056) (xy 353.61297 -398.542002) (xy 353.024186 -398.542002) (xy 353.023691 -398.566609)
			(xy 353.015796 -398.615186) (xy 353.000212 -398.661867) (xy 352.977341 -398.705444) (xy 352.947776 -398.744788)
			(xy 352.912283 -398.77888) (xy 352.87178 -398.806836) (xy 352.827318 -398.827934) (xy 352.780047 -398.841626)
			(xy 352.731192 -398.847558) (xy 352.682017 -398.845577) (xy 352.633798 -398.835733) (xy 352.587782 -398.818281)
			(xy 352.545161 -398.793674) (xy 352.50704 -398.762549) (xy 352.474405 -398.725712) (xy 352.448102 -398.684116)
			(xy 352.428811 -398.63884) (xy 352.417034 -398.591056) (xy 352.413074 -398.542002) (xy 351.824036 -398.542002)
			(xy 351.823541 -398.566609) (xy 351.815646 -398.615186) (xy 351.800062 -398.661867) (xy 351.777191 -398.705444)
			(xy 351.747626 -398.744788) (xy 351.712133 -398.77888) (xy 351.67163 -398.806836) (xy 351.627168 -398.827934)
			(xy 351.579897 -398.841626) (xy 351.531042 -398.847558) (xy 351.481867 -398.845577) (xy 351.433648 -398.835733)
			(xy 351.387632 -398.818281) (xy 351.345011 -398.793674) (xy 351.30689 -398.762549) (xy 351.274255 -398.725712)
			(xy 351.247952 -398.684116) (xy 351.228661 -398.63884) (xy 351.216884 -398.591056) (xy 351.212924 -398.542002)
			(xy 350.62414 -398.542002) (xy 350.623645 -398.566609) (xy 350.61575 -398.615186) (xy 350.600166 -398.661867)
			(xy 350.577295 -398.705444) (xy 350.54773 -398.744788) (xy 350.512237 -398.77888) (xy 350.471734 -398.806836)
			(xy 350.427272 -398.827934) (xy 350.380001 -398.841626) (xy 350.331146 -398.847558) (xy 350.281971 -398.845577)
			(xy 350.233752 -398.835733) (xy 350.187736 -398.818281) (xy 350.145115 -398.793674) (xy 350.106994 -398.762549)
			(xy 350.074359 -398.725712) (xy 350.048056 -398.684116) (xy 350.028765 -398.63884) (xy 350.016988 -398.591056)
			(xy 350.013028 -398.542002) (xy 349.42399 -398.542002) (xy 349.423495 -398.566609) (xy 349.4156 -398.615186)
			(xy 349.400016 -398.661867) (xy 349.377145 -398.705444) (xy 349.34758 -398.744788) (xy 349.312087 -398.77888)
			(xy 349.271584 -398.806836) (xy 349.227122 -398.827934) (xy 349.179851 -398.841626) (xy 349.130996 -398.847558)
			(xy 349.081821 -398.845577) (xy 349.033602 -398.835733) (xy 348.987586 -398.818281) (xy 348.944965 -398.793674)
			(xy 348.906844 -398.762549) (xy 348.874209 -398.725712) (xy 348.847906 -398.684116) (xy 348.828615 -398.63884)
			(xy 348.816838 -398.591056) (xy 348.812878 -398.542002) (xy 348.224094 -398.542002) (xy 348.223599 -398.566609)
			(xy 348.215704 -398.615186) (xy 348.20012 -398.661867) (xy 348.177249 -398.705444) (xy 348.147684 -398.744788)
			(xy 348.112191 -398.77888) (xy 348.071688 -398.806836) (xy 348.027226 -398.827934) (xy 347.979955 -398.841626)
			(xy 347.9311 -398.847558) (xy 347.881925 -398.845577) (xy 347.833706 -398.835733) (xy 347.78769 -398.818281)
			(xy 347.745069 -398.793674) (xy 347.706948 -398.762549) (xy 347.674313 -398.725712) (xy 347.64801 -398.684116)
			(xy 347.628719 -398.63884) (xy 347.616942 -398.591056) (xy 347.612982 -398.542002) (xy 347.024198 -398.542002)
			(xy 347.023703 -398.566609) (xy 347.015808 -398.615186) (xy 347.000224 -398.661867) (xy 346.977353 -398.705444)
			(xy 346.947788 -398.744788) (xy 346.912295 -398.77888) (xy 346.871792 -398.806836) (xy 346.82733 -398.827934)
			(xy 346.780059 -398.841626) (xy 346.731204 -398.847558) (xy 346.682029 -398.845577) (xy 346.63381 -398.835733)
			(xy 346.587794 -398.818281) (xy 346.545173 -398.793674) (xy 346.507052 -398.762549) (xy 346.474417 -398.725712)
			(xy 346.448114 -398.684116) (xy 346.428823 -398.63884) (xy 346.417046 -398.591056) (xy 346.413086 -398.542002)
			(xy 345.824048 -398.542002) (xy 345.823553 -398.566609) (xy 345.815658 -398.615186) (xy 345.800074 -398.661867)
			(xy 345.777203 -398.705444) (xy 345.747638 -398.744788) (xy 345.712145 -398.77888) (xy 345.671642 -398.806836)
			(xy 345.62718 -398.827934) (xy 345.579909 -398.841626) (xy 345.531054 -398.847558) (xy 345.481879 -398.845577)
			(xy 345.43366 -398.835733) (xy 345.387644 -398.818281) (xy 345.345023 -398.793674) (xy 345.306902 -398.762549)
			(xy 345.274267 -398.725712) (xy 345.247964 -398.684116) (xy 345.228673 -398.63884) (xy 345.216896 -398.591056)
			(xy 345.212936 -398.542002) (xy 344.624152 -398.542002) (xy 344.623657 -398.566609) (xy 344.615762 -398.615186)
			(xy 344.600178 -398.661867) (xy 344.577307 -398.705444) (xy 344.547742 -398.744788) (xy 344.512249 -398.77888)
			(xy 344.471746 -398.806836) (xy 344.427284 -398.827934) (xy 344.380013 -398.841626) (xy 344.331158 -398.847558)
			(xy 344.281983 -398.845577) (xy 344.233764 -398.835733) (xy 344.187748 -398.818281) (xy 344.145127 -398.793674)
			(xy 344.107006 -398.762549) (xy 344.074371 -398.725712) (xy 344.048068 -398.684116) (xy 344.028777 -398.63884)
			(xy 344.017 -398.591056) (xy 344.01304 -398.542002) (xy 343.424002 -398.542002) (xy 343.423507 -398.566609)
			(xy 343.415612 -398.615186) (xy 343.400028 -398.661867) (xy 343.377157 -398.705444) (xy 343.347592 -398.744788)
			(xy 343.312099 -398.77888) (xy 343.271596 -398.806836) (xy 343.227134 -398.827934) (xy 343.179863 -398.841626)
			(xy 343.131008 -398.847558) (xy 343.081833 -398.845577) (xy 343.033614 -398.835733) (xy 342.987598 -398.818281)
			(xy 342.944977 -398.793674) (xy 342.906856 -398.762549) (xy 342.874221 -398.725712) (xy 342.847918 -398.684116)
			(xy 342.828627 -398.63884) (xy 342.81685 -398.591056) (xy 342.81289 -398.542002) (xy 342.224106 -398.542002)
			(xy 342.223611 -398.566609) (xy 342.215716 -398.615186) (xy 342.200132 -398.661867) (xy 342.177261 -398.705444)
			(xy 342.147696 -398.744788) (xy 342.112203 -398.77888) (xy 342.0717 -398.806836) (xy 342.027238 -398.827934)
			(xy 341.979967 -398.841626) (xy 341.931112 -398.847558) (xy 341.881937 -398.845577) (xy 341.833718 -398.835733)
			(xy 341.787702 -398.818281) (xy 341.745081 -398.793674) (xy 341.70696 -398.762549) (xy 341.674325 -398.725712)
			(xy 341.648022 -398.684116) (xy 341.628731 -398.63884) (xy 341.616954 -398.591056) (xy 341.612994 -398.542002)
			(xy 341.02421 -398.542002) (xy 341.023715 -398.566609) (xy 341.01582 -398.615186) (xy 341.000236 -398.661867)
			(xy 340.977365 -398.705444) (xy 340.9478 -398.744788) (xy 340.912307 -398.77888) (xy 340.871804 -398.806836)
			(xy 340.827342 -398.827934) (xy 340.780071 -398.841626) (xy 340.731216 -398.847558) (xy 340.682041 -398.845577)
			(xy 340.633822 -398.835733) (xy 340.587806 -398.818281) (xy 340.545185 -398.793674) (xy 340.507064 -398.762549)
			(xy 340.474429 -398.725712) (xy 340.448126 -398.684116) (xy 340.428835 -398.63884) (xy 340.417058 -398.591056)
			(xy 340.413098 -398.542002) (xy 339.82406 -398.542002) (xy 339.823565 -398.566609) (xy 339.81567 -398.615186)
			(xy 339.800086 -398.661867) (xy 339.777215 -398.705444) (xy 339.74765 -398.744788) (xy 339.712157 -398.77888)
			(xy 339.671654 -398.806836) (xy 339.627192 -398.827934) (xy 339.579921 -398.841626) (xy 339.531066 -398.847558)
			(xy 339.481891 -398.845577) (xy 339.433672 -398.835733) (xy 339.387656 -398.818281) (xy 339.345035 -398.793674)
			(xy 339.306914 -398.762549) (xy 339.274279 -398.725712) (xy 339.247976 -398.684116) (xy 339.228685 -398.63884)
			(xy 339.216908 -398.591056) (xy 339.212948 -398.542002) (xy 338.624164 -398.542002) (xy 338.623669 -398.566609)
			(xy 338.615774 -398.615186) (xy 338.60019 -398.661867) (xy 338.577319 -398.705444) (xy 338.547754 -398.744788)
			(xy 338.512261 -398.77888) (xy 338.471758 -398.806836) (xy 338.427296 -398.827934) (xy 338.380025 -398.841626)
			(xy 338.33117 -398.847558) (xy 338.281995 -398.845577) (xy 338.233776 -398.835733) (xy 338.18776 -398.818281)
			(xy 338.145139 -398.793674) (xy 338.107018 -398.762549) (xy 338.074383 -398.725712) (xy 338.04808 -398.684116)
			(xy 338.028789 -398.63884) (xy 338.017012 -398.591056) (xy 338.013052 -398.542002) (xy 337.424014 -398.542002)
			(xy 337.423519 -398.566609) (xy 337.415624 -398.615186) (xy 337.40004 -398.661867) (xy 337.377169 -398.705444)
			(xy 337.347604 -398.744788) (xy 337.312111 -398.77888) (xy 337.271608 -398.806836) (xy 337.227146 -398.827934)
			(xy 337.179875 -398.841626) (xy 337.13102 -398.847558) (xy 337.081845 -398.845577) (xy 337.033626 -398.835733)
			(xy 336.98761 -398.818281) (xy 336.944989 -398.793674) (xy 336.906868 -398.762549) (xy 336.874233 -398.725712)
			(xy 336.84793 -398.684116) (xy 336.828639 -398.63884) (xy 336.816862 -398.591056) (xy 336.812902 -398.542002)
			(xy 336.223864 -398.542002) (xy 336.223369 -398.566609) (xy 336.215474 -398.615186) (xy 336.19989 -398.661867)
			(xy 336.177019 -398.705444) (xy 336.147454 -398.744788) (xy 336.111961 -398.77888) (xy 336.071458 -398.806836)
			(xy 336.026996 -398.827934) (xy 335.979725 -398.841626) (xy 335.93087 -398.847558) (xy 335.881695 -398.845577)
			(xy 335.833476 -398.835733) (xy 335.78746 -398.818281) (xy 335.744839 -398.793674) (xy 335.706718 -398.762549)
			(xy 335.674083 -398.725712) (xy 335.64778 -398.684116) (xy 335.628489 -398.63884) (xy 335.616712 -398.591056)
			(xy 335.612752 -398.542002) (xy 333.937917 -398.542002) (xy 333.931807 -398.563184) (xy 333.912808 -398.60559)
			(xy 333.88806 -398.64492) (xy 333.873348 -398.662906) (xy 333.867252 -398.670018) (xy 333.861156 -398.686528)
			(xy 333.861156 -398.770856) (xy 333.867252 -398.787366) (xy 333.873348 -398.794478) (xy 333.888054 -398.812469)
			(xy 333.912805 -398.851795) (xy 333.931805 -398.8942) (xy 333.944679 -398.938848) (xy 333.951174 -398.984858)
			(xy 333.95158 -399.008092) (xy 333.951165 -399.032185) (xy 333.944203 -399.079866) (xy 333.930382 -399.126027)
			(xy 333.920592 -399.148046) (xy 333.915258 -399.159476) (xy 333.916528 -399.184622) (xy 333.972662 -399.278602)
			(xy 333.994252 -399.291556) (xy 334.006952 -399.292318) (xy 334.031946 -399.294186) (xy 334.080988 -399.304516)
			(xy 334.127909 -399.322128) (xy 334.171636 -399.346618) (xy 334.211167 -399.377426) (xy 334.245596 -399.413846)
			(xy 334.274136 -399.455045) (xy 334.296132 -399.500078) (xy 334.311081 -399.547914) (xy 334.318641 -399.597459)
			(xy 334.319118 -399.622518) (xy 334.31849 -399.651361) (xy 334.308482 -399.708173) (xy 334.288773 -399.762388)
			(xy 334.25996 -399.812363) (xy 334.241902 -399.834862) (xy 334.232504 -399.846292) (xy 334.22844 -399.875502)
			(xy 334.273652 -399.97253) (xy 334.278143 -399.981086) (xy 334.292244 -399.994276) (xy 334.310223 -400.001318)
			(xy 334.31988 -400.00174) (xy 334.701896 -400.00174) (xy 334.714625 -400.001032) (xy 334.737003 -399.98889)
			(xy 334.744568 -399.978626) (xy 334.758728 -399.957539) (xy 334.792469 -399.919575) (xy 334.831618 -399.887217)
			(xy 334.875254 -399.861224) (xy 334.922352 -399.842209) (xy 334.971802 -399.830618) (xy 335.022444 -399.826723)
			(xy 335.073086 -399.830618) (xy 335.122536 -399.842209) (xy 335.169634 -399.861224) (xy 335.21327 -399.887217)
			(xy 335.252419 -399.919575) (xy 335.28616 -399.957539) (xy 335.30032 -399.978626) (xy 335.305185 -399.985553)
			(xy 335.318523 -399.995961) (xy 335.334532 -400.001434) (xy 335.342992 -400.00174) (xy 336.102706 -400.00174)
			(xy 336.112155 -400.001258) (xy 336.129758 -399.994369) (xy 336.136996 -399.988278) (xy 336.155932 -399.971511)
			(xy 336.198267 -399.943844) (xy 336.244579 -399.923524) (xy 336.293605 -399.911106) (xy 336.344006 -399.906929)
			(xy 336.394407 -399.911106) (xy 336.443433 -399.923524) (xy 336.489745 -399.943844) (xy 336.53208 -399.971511)
			(xy 336.551016 -399.988278) (xy 336.558219 -399.994433) (xy 336.57584 -400.001358) (xy 336.585306 -400.00174)
			(xy 337.302856 -400.00174) (xy 337.312301 -400.00125) (xy 337.329893 -399.994348) (xy 337.337146 -399.988278)
			(xy 337.356082 -399.971511) (xy 337.398417 -399.943844) (xy 337.444729 -399.923524) (xy 337.493755 -399.911106)
			(xy 337.544156 -399.906929) (xy 337.594557 -399.911106) (xy 337.643583 -399.923524) (xy 337.689895 -399.943844)
			(xy 337.73223 -399.971511) (xy 337.751166 -399.988278) (xy 337.758366 -399.994441) (xy 337.775987 -400.001383)
			(xy 337.785456 -400.00174) (xy 338.502752 -400.00174) (xy 338.512198 -400.00125) (xy 338.52979 -399.994349)
			(xy 338.537042 -399.988278) (xy 338.555978 -399.971511) (xy 338.598313 -399.943844) (xy 338.644625 -399.923524)
			(xy 338.693651 -399.911106) (xy 338.744052 -399.906929) (xy 338.794453 -399.911106) (xy 338.843479 -399.923524)
			(xy 338.889791 -399.943844) (xy 338.932126 -399.971511) (xy 338.951062 -399.988278) (xy 338.958267 -399.994427)
			(xy 338.975888 -400.001335) (xy 338.985352 -400.00174) (xy 339.702648 -400.00174) (xy 339.712094 -400.001251)
			(xy 339.729687 -399.994351) (xy 339.736938 -399.988278) (xy 339.755874 -399.971511) (xy 339.798209 -399.943844)
			(xy 339.844521 -399.923524) (xy 339.893547 -399.911106) (xy 339.943948 -399.906929) (xy 339.994349 -399.911106)
			(xy 340.043375 -399.923524) (xy 340.089687 -399.943844) (xy 340.132022 -399.971511) (xy 340.150958 -399.988278)
			(xy 340.158163 -399.994427) (xy 340.175784 -400.001337) (xy 340.185248 -400.00174) (xy 340.902798 -400.00174)
			(xy 340.91224 -400.001243) (xy 340.929822 -399.99433) (xy 340.937088 -399.988278) (xy 340.956024 -399.971511)
			(xy 340.998359 -399.943844) (xy 341.044671 -399.923524) (xy 341.093697 -399.911106) (xy 341.144098 -399.906929)
			(xy 341.194499 -399.911106) (xy 341.243525 -399.923524) (xy 341.289837 -399.943844) (xy 341.332172 -399.971511)
			(xy 341.351108 -399.988278) (xy 341.35831 -399.994435) (xy 341.375931 -400.001362) (xy 341.385398 -400.00174)
			(xy 342.102694 -400.00174) (xy 342.112137 -400.001243) (xy 342.129719 -399.994332) (xy 342.136984 -399.988278)
			(xy 342.15592 -399.971511) (xy 342.198255 -399.943844) (xy 342.244567 -399.923524) (xy 342.293593 -399.911106)
			(xy 342.343994 -399.906929) (xy 342.394395 -399.911106) (xy 342.443421 -399.923524) (xy 342.489733 -399.943844)
			(xy 342.532068 -399.971511) (xy 342.551004 -399.988278) (xy 342.558206 -399.994436) (xy 342.575827 -400.001364)
			(xy 342.585294 -400.00174) (xy 343.302844 -400.00174) (xy 343.31229 -400.001252) (xy 343.329885 -399.994353)
			(xy 343.337134 -399.988278) (xy 343.35607 -399.971511) (xy 343.398405 -399.943844) (xy 343.444717 -399.923524)
			(xy 343.493743 -399.911106) (xy 343.544144 -399.906929) (xy 343.594545 -399.911106) (xy 343.643571 -399.923524)
			(xy 343.689883 -399.943844) (xy 343.732218 -399.971511) (xy 343.751154 -399.988278) (xy 343.758358 -399.994428)
			(xy 343.77598 -400.001339) (xy 343.785444 -400.00174) (xy 344.50274 -400.00174) (xy 344.512187 -400.001252)
			(xy 344.529782 -399.994354) (xy 344.53703 -399.988278) (xy 344.555966 -399.971511) (xy 344.598301 -399.943844)
			(xy 344.644613 -399.923524) (xy 344.693639 -399.911106) (xy 344.74404 -399.906929) (xy 344.794441 -399.911106)
			(xy 344.843467 -399.923524) (xy 344.889779 -399.943844) (xy 344.932114 -399.971511) (xy 344.95105 -399.988278)
			(xy 344.958254 -399.994428) (xy 344.975875 -400.001341) (xy 344.98534 -400.00174) (xy 345.702636 -400.00174)
			(xy 345.712083 -400.001253) (xy 345.729679 -399.994356) (xy 345.736926 -399.988278) (xy 345.755862 -399.971511)
			(xy 345.798197 -399.943844) (xy 345.844509 -399.923524) (xy 345.893535 -399.911106) (xy 345.943936 -399.906929)
			(xy 345.994337 -399.911106) (xy 346.043363 -399.923524) (xy 346.089675 -399.943844) (xy 346.13201 -399.971511)
			(xy 346.150946 -399.988278) (xy 346.15815 -399.994429) (xy 346.175771 -400.001343) (xy 346.185236 -400.00174)
			(xy 346.902786 -400.00174) (xy 346.912229 -400.001245) (xy 346.929814 -399.994335) (xy 346.937076 -399.988278)
			(xy 346.956012 -399.971511) (xy 346.998347 -399.943844) (xy 347.044659 -399.923524) (xy 347.093685 -399.911106)
			(xy 347.144086 -399.906929) (xy 347.194487 -399.911106) (xy 347.243513 -399.923524) (xy 347.289825 -399.943844)
			(xy 347.33216 -399.971511) (xy 347.351096 -399.988278) (xy 347.358298 -399.994437) (xy 347.375918 -400.001368)
			(xy 347.385386 -400.00174) (xy 348.102682 -400.00174) (xy 348.112125 -400.001245) (xy 348.129711 -399.994337)
			(xy 348.136972 -399.988278) (xy 348.155908 -399.971511) (xy 348.198243 -399.943844) (xy 348.244555 -399.923524)
			(xy 348.293581 -399.911106) (xy 348.343982 -399.906929) (xy 348.394383 -399.911106) (xy 348.443409 -399.923524)
			(xy 348.489721 -399.943844) (xy 348.532056 -399.971511) (xy 348.550992 -399.988278) (xy 348.558193 -399.994437)
			(xy 348.575814 -400.00137) (xy 348.585282 -400.00174) (xy 349.302832 -400.00174) (xy 349.312279 -400.001254)
			(xy 349.329876 -399.994358) (xy 349.337122 -399.988278) (xy 349.356058 -399.971511) (xy 349.398393 -399.943844)
			(xy 349.444705 -399.923524) (xy 349.493731 -399.911106) (xy 349.544132 -399.906929) (xy 349.594533 -399.911106)
			(xy 349.643559 -399.923524) (xy 349.689871 -399.943844) (xy 349.732206 -399.971511) (xy 349.751142 -399.988278)
			(xy 349.758346 -399.99443) (xy 349.775967 -400.001345) (xy 349.785432 -400.00174) (xy 350.502728 -400.00174)
			(xy 350.512175 -400.001255) (xy 350.529773 -399.994359) (xy 350.537018 -399.988278) (xy 350.555954 -399.971511)
			(xy 350.598289 -399.943844) (xy 350.644601 -399.923524) (xy 350.693627 -399.911106) (xy 350.744028 -399.906929)
			(xy 350.794429 -399.911106) (xy 350.843455 -399.923524) (xy 350.889767 -399.943844) (xy 350.932102 -399.971511)
			(xy 350.951038 -399.988278) (xy 350.958242 -399.99443) (xy 350.975863 -400.001347) (xy 350.985328 -400.00174)
			(xy 351.702624 -400.00174) (xy 351.712072 -400.001255) (xy 351.729671 -399.994361) (xy 351.736914 -399.988278)
			(xy 351.75585 -399.971511) (xy 351.798185 -399.943844) (xy 351.844497 -399.923524) (xy 351.893523 -399.911106)
			(xy 351.943924 -399.906929) (xy 351.994325 -399.911106) (xy 352.043351 -399.923524) (xy 352.089663 -399.943844)
			(xy 352.131998 -399.971511) (xy 352.150934 -399.988278) (xy 352.158138 -399.994431) (xy 352.175759 -400.001349)
			(xy 352.185224 -400.00174) (xy 352.902774 -400.00174) (xy 352.912218 -400.001247) (xy 352.929805 -399.99434)
			(xy 352.937064 -399.988278) (xy 352.956 -399.971511) (xy 352.998335 -399.943844) (xy 353.044647 -399.923524)
			(xy 353.093673 -399.911106) (xy 353.144074 -399.906929) (xy 353.194475 -399.911106) (xy 353.243501 -399.923524)
			(xy 353.289813 -399.943844) (xy 353.332148 -399.971511) (xy 353.351084 -399.988278) (xy 353.358285 -399.994439)
			(xy 353.375906 -400.001374) (xy 353.385374 -400.00174) (xy 354.10267 -400.00174) (xy 354.112114 -400.001247)
			(xy 354.129703 -399.994342) (xy 354.13696 -399.988278) (xy 354.153979 -399.973169) (xy 354.191655 -399.947641)
			(xy 354.232701 -399.927987) (xy 354.276209 -399.914641) (xy 354.321215 -399.907898) (xy 354.34397 -399.907506)
			(xy 354.36662 -399.907896) (xy 354.411426 -399.914554) (xy 354.454753 -399.927772) (xy 354.495646 -399.94726)
			(xy 354.514658 -399.959576) (xy 354.524709 -399.965655) (xy 354.547958 -399.968818) (xy 354.5702 -399.961349)
			(xy 354.57892 -399.95348) (xy 355.099874 -399.432526) (xy 355.106712 -399.425125) (xy 355.114423 -399.406526)
			(xy 355.11486 -399.396458) (xy 355.11486 -398.86128) (xy 355.114112 -398.848613) (xy 355.101984 -398.826359)
			(xy 355.091746 -398.818862) (xy 355.070893 -398.804634) (xy 355.033356 -398.770882) (xy 355.001379 -398.731822)
			(xy 354.975705 -398.688358) (xy 354.956929 -398.6415) (xy 354.945486 -398.592334) (xy 354.941642 -398.542001)
			(xy 354.945486 -398.491668) (xy 354.956928 -398.442502) (xy 354.975704 -398.395644) (xy 355.001378 -398.35218)
			(xy 355.033354 -398.313119) (xy 355.070891 -398.279367) (xy 355.091746 -398.265142) (xy 355.098647 -398.26031)
			(xy 355.109032 -398.247057) (xy 355.114529 -398.231142) (xy 355.11486 -398.222724) (xy 355.11486 -398.145)
			(xy 355.114362 -398.135006) (xy 355.106724 -398.116534) (xy 355.092633 -398.102355) (xy 355.083618 -398.09801)
			(xy 354.982526 -398.0561) (xy 354.952554 -398.061942) (xy 354.941632 -398.072864) (xy 354.923759 -398.089975)
			(xy 354.883676 -398.118979) (xy 354.839558 -398.141372) (xy 354.792485 -398.156606) (xy 354.743612 -398.164308)
			(xy 354.718874 -398.164812) (xy 354.693481 -398.164302) (xy 354.643352 -398.156168) (xy 354.595171 -398.140115)
			(xy 354.550181 -398.116555) (xy 354.509543 -398.086098) (xy 354.474304 -398.049528) (xy 354.445374 -398.007788)
			(xy 354.423498 -397.961956) (xy 354.415852 -397.937736) (xy 354.414328 -397.931894) (xy 354.094034 -397.378174)
			(xy 354.08997 -397.373856) (xy 354.073782 -397.356146) (xy 354.04641 -397.316743) (xy 354.025323 -397.273647)
			(xy 354.011007 -397.227854) (xy 354.003794 -397.180422) (xy 354.003356 -397.156432) (xy 354.003442 -397.144384)
			(xy 354.005225 -397.120355) (xy 354.006912 -397.108426) (xy 354.008182 -397.099536) (xy 354.005134 -397.082518)
			(xy 353.96297 -397.011652) (xy 353.949762 -397.000476) (xy 353.94138 -396.997428) (xy 353.91964 -396.989022)
			(xy 353.878795 -396.96657) (xy 353.841838 -396.93817) (xy 353.809625 -396.904484) (xy 353.782906 -396.866293)
			(xy 353.762302 -396.824486) (xy 353.748291 -396.780033) (xy 353.741198 -396.733966) (xy 353.74072 -396.710662)
			(xy 353.74122 -396.685264) (xy 353.74962 -396.635168) (xy 353.766199 -396.587154) (xy 353.790498 -396.542548)
			(xy 353.821847 -396.50258) (xy 353.840288 -396.48511) (xy 353.84867 -396.47749) (xy 353.857306 -396.457424)
			(xy 353.854512 -396.35811) (xy 353.845114 -396.338552) (xy 353.836224 -396.33144) (xy 353.817662 -396.315638)
			(xy 353.784933 -396.279513) (xy 353.757858 -396.238976) (xy 353.737023 -396.194906) (xy 353.72288 -396.148256)
			(xy 353.715734 -396.100035) (xy 353.71532 -396.075662) (xy 353.715759 -396.051546) (xy 353.722765 -396.003826)
			(xy 353.736623 -395.957628) (xy 353.75704 -395.913931) (xy 353.76993 -395.893544) (xy 353.775772 -395.884654)
			(xy 353.779328 -395.864588) (xy 353.758246 -395.772386) (xy 353.746054 -395.755622) (xy 353.737164 -395.750288)
			(xy 353.716361 -395.737433) (xy 353.678443 -395.706555) (xy 353.645491 -395.670425) (xy 353.618226 -395.629831)
			(xy 353.597244 -395.585662) (xy 353.583002 -395.538881) (xy 353.575813 -395.490512) (xy 353.575366 -395.466062)
			(xy 353.575927 -395.438779) (xy 353.584887 -395.384954) (xy 353.602558 -395.333329) (xy 353.628461 -395.285303)
			(xy 353.661893 -395.242179) (xy 353.681538 -395.223238) (xy 353.688982 -395.215744) (xy 353.697518 -395.196449)
			(xy 353.698048 -395.1859) (xy 353.698048 -395.111224) (xy 353.69746 -395.10069) (xy 353.688926 -395.081419)
			(xy 353.681538 -395.073886) (xy 353.661883 -395.054953) (xy 353.628441 -395.011832) (xy 353.602533 -394.963805)
			(xy 353.584862 -394.912176) (xy 353.575908 -394.858347) (xy 353.575366 -394.831062) (xy 353.57562 -394.81887)
			(xy 353.575874 -394.809218) (xy 353.569778 -394.791184) (xy 353.511104 -394.723874) (xy 353.49434 -394.715238)
			(xy 353.484434 -394.714222) (xy 353.457483 -394.710859) (xy 353.405113 -394.696479) (xy 353.355792 -394.673742)
			(xy 353.310844 -394.64326) (xy 353.271476 -394.605849) (xy 353.238742 -394.562514) (xy 353.213521 -394.514417)
			(xy 353.19649 -394.462847) (xy 353.191826 -394.436092) (xy 353.190556 -394.426694) (xy 352.918014 -393.95527)
			(xy 352.910648 -393.949428) (xy 352.891869 -393.933625) (xy 352.858735 -393.897419) (xy 352.831314 -393.856714)
			(xy 352.810208 -393.812405) (xy 352.795881 -393.765463) (xy 352.788647 -393.71692) (xy 352.78822 -393.69238)
			(xy 352.788705 -393.666393) (xy 352.796839 -393.615058) (xy 352.812903 -393.565628) (xy 352.836502 -393.51932)
			(xy 352.867055 -393.477273) (xy 352.90381 -393.440524) (xy 352.945861 -393.409977) (xy 352.992172 -393.386385)
			(xy 353.041605 -393.370327) (xy 353.09294 -393.362201) (xy 353.118928 -393.361672) (xy 353.144942 -393.362152)
			(xy 353.19633 -393.370289) (xy 353.24581 -393.386375) (xy 353.292159 -393.410011) (xy 353.334234 -393.440615)
			(xy 353.370997 -393.477432) (xy 353.40154 -393.519551) (xy 353.425109 -393.565935) (xy 353.441123 -393.615438)
			(xy 353.445572 -393.641072) (xy 353.447096 -393.65047) (xy 353.720146 -394.12291) (xy 353.727258 -394.128752)
			(xy 353.745986 -394.144534) (xy 353.77903 -394.180681) (xy 353.806377 -394.221308) (xy 353.82743 -394.265526)
			(xy 353.841727 -394.312367) (xy 353.848955 -394.360805) (xy 353.849432 -394.385292) (xy 353.849178 -394.397484)
			(xy 353.848924 -394.407136) (xy 353.85502 -394.42517) (xy 353.913694 -394.49248) (xy 353.930458 -394.501116)
			(xy 353.940364 -394.502132) (xy 353.967134 -394.505456) (xy 354.019167 -394.519675) (xy 354.068203 -394.54215)
			(xy 354.112942 -394.572284) (xy 354.152198 -394.609278) (xy 354.184931 -394.652151) (xy 354.210273 -394.699768)
			(xy 354.227553 -394.750867) (xy 354.236312 -394.804092) (xy 354.236782 -394.831062) (xy 354.236219 -394.858344)
			(xy 354.227254 -394.912165) (xy 354.209579 -394.963786) (xy 354.183671 -395.011807) (xy 354.150234 -395.054924)
			(xy 354.13061 -395.073886) (xy 354.123164 -395.081379) (xy 354.114629 -395.100674) (xy 354.1141 -395.111224)
			(xy 354.1141 -395.1859) (xy 354.114691 -395.196433) (xy 354.123225 -395.215703) (xy 354.13061 -395.223238)
			(xy 354.150266 -395.24217) (xy 354.18371 -395.28529) (xy 354.209619 -395.333317) (xy 354.227289 -395.384946)
			(xy 354.236241 -395.438777) (xy 354.236782 -395.466062) (xy 354.236349 -395.490179) (xy 354.229353 -395.537904)
			(xy 354.215504 -395.584108) (xy 354.195094 -395.627813) (xy 354.182172 -395.64818) (xy 354.17633 -395.65707)
			(xy 354.172774 -395.677136) (xy 354.193856 -395.769338) (xy 354.206048 -395.786102) (xy 354.214938 -395.791436)
			(xy 354.235739 -395.804292) (xy 354.273655 -395.83517) (xy 354.306604 -395.871301) (xy 354.333866 -395.911895)
			(xy 354.354846 -395.956065) (xy 354.369084 -396.002845) (xy 354.376269 -396.051212) (xy 354.376736 -396.075662)
			(xy 354.376298 -396.100033) (xy 354.369142 -396.148245) (xy 354.354994 -396.194888) (xy 354.334159 -396.238952)
			(xy 354.307088 -396.279484) (xy 354.274366 -396.315609) (xy 354.255832 -396.33144) (xy 354.246942 -396.338552)
			(xy 354.237544 -396.35811) (xy 354.23475 -396.457424) (xy 354.243386 -396.47749) (xy 354.251768 -396.48511)
			(xy 354.270186 -396.5026) (xy 354.301521 -396.54257) (xy 354.325813 -396.587173) (xy 354.342391 -396.63518)
			(xy 354.350799 -396.685268) (xy 354.351336 -396.710662) (xy 354.351264 -396.72002) (xy 354.350118 -396.738702)
			(xy 354.34905 -396.748) (xy 354.348034 -396.75689) (xy 354.351844 -396.773654) (xy 354.395786 -396.843504)
			(xy 354.409502 -396.853918) (xy 354.417884 -396.856712) (xy 354.441921 -396.865164) (xy 354.487106 -396.888707)
			(xy 354.527922 -396.919203) (xy 354.563309 -396.955859) (xy 354.592349 -396.997723) (xy 354.614286 -397.043708)
			(xy 354.621846 -397.06804) (xy 354.62337 -397.073882) (xy 354.943664 -397.627602) (xy 354.947728 -397.63192)
			(xy 354.962593 -397.648123) (xy 354.988169 -397.68389) (xy 355.008558 -397.722849) (xy 355.016308 -397.743426)
			(xy 355.021642 -397.75892) (xy 355.047804 -397.777208) (xy 355.06406 -397.777208) (xy 355.074087 -397.776795)
			(xy 355.092619 -397.769133) (xy 355.106806 -397.75496) (xy 355.114486 -397.736435) (xy 355.11486 -397.726408)
			(xy 355.11486 -395.190218) (xy 355.089714 -395.161516) (xy 355.07041 -395.15923) (xy 355.044084 -395.155414)
			(xy 354.993035 -395.140472) (xy 354.945037 -395.11755) (xy 354.901326 -395.087241) (xy 354.863031 -395.050326)
			(xy 354.831139 -395.007756) (xy 354.806473 -394.96063) (xy 354.789669 -394.910163) (xy 354.781161 -394.857657)
			(xy 354.780596 -394.831062) (xy 354.78085 -394.819378) (xy 354.781104 -394.809472) (xy 354.774754 -394.791438)
			(xy 354.715572 -394.724382) (xy 354.6983 -394.715492) (xy 354.688648 -394.71473) (xy 354.664454 -394.712085)
			(xy 354.617162 -394.700597) (xy 354.572066 -394.682295) (xy 354.530143 -394.657575) (xy 354.4923 -394.626973)
			(xy 354.459355 -394.591151) (xy 354.432022 -394.550883) (xy 354.410891 -394.507042) (xy 354.396421 -394.460575)
			(xy 354.39223 -394.4366) (xy 354.390706 -394.427202) (xy 354.11791 -393.95527) (xy 354.110544 -393.949428)
			(xy 354.091765 -393.933625) (xy 354.058631 -393.897418) (xy 354.03121 -393.856714) (xy 354.010105 -393.812404)
			(xy 353.995778 -393.765463) (xy 353.988544 -393.71692) (xy 353.988116 -393.69238) (xy 353.988601 -393.666392)
			(xy 353.996735 -393.615058) (xy 354.012799 -393.565627) (xy 354.036398 -393.519319) (xy 354.066951 -393.477272)
			(xy 354.103705 -393.440522) (xy 354.145756 -393.409975) (xy 354.192068 -393.386382) (xy 354.241501 -393.370324)
			(xy 354.292836 -393.362197) (xy 354.318824 -393.361672) (xy 354.344838 -393.362151) (xy 354.396227 -393.370288)
			(xy 354.445707 -393.386374) (xy 354.492057 -393.41001) (xy 354.534132 -393.440614) (xy 354.570896 -393.47743)
			(xy 354.601439 -393.51955) (xy 354.625009 -393.565934) (xy 354.641023 -393.615437) (xy 354.645468 -393.641072)
			(xy 354.646992 -393.65047) (xy 354.919788 -394.122402) (xy 354.927154 -394.128244) (xy 354.944172 -394.14323)
			(xy 354.955348 -394.15339) (xy 354.985066 -394.15847) (xy 355.08438 -394.11529) (xy 355.093207 -394.110928)
			(xy 355.106943 -394.096847) (xy 355.114395 -394.078642) (xy 355.11486 -394.068808) (xy 355.11486 -391.397744)
			(xy 355.110288 -391.387584) (xy 355.100814 -391.365929) (xy 355.087464 -391.320587) (xy 355.080722 -391.273803)
			(xy 355.080316 -391.25017) (xy 355.080758 -391.22654) (xy 355.087515 -391.179764) (xy 355.100845 -391.134422)
			(xy 355.110288 -391.112756) (xy 355.11486 -391.102596) (xy 355.11486 -390.464802) (xy 355.114436 -390.454733)
			(xy 355.106718 -390.436131) (xy 355.099874 -390.428734) (xy 354.278946 -389.607806) (xy 354.271545 -389.600967)
			(xy 354.252947 -389.593252) (xy 354.242878 -389.59282) (xy 332.689708 -389.59282) (xy 332.664054 -389.609838)
			(xy 332.658212 -389.624316) (xy 332.647002 -389.650106) (xy 332.618112 -389.698351) (xy 332.582452 -389.741832)
			(xy 332.540796 -389.779607) (xy 332.494045 -389.810858) (xy 332.443213 -389.834906) (xy 332.389402 -389.851232)
			(xy 332.333777 -389.859482) (xy 332.30566 -389.860028) (xy 332.278387 -389.859567) (xy 332.224396 -389.851804)
			(xy 332.172063 -389.836426) (xy 332.122454 -389.813749) (xy 332.076583 -389.784235) (xy 332.035385 -389.748486)
			(xy 331.999702 -389.707231) (xy 331.984604 -389.684514) (xy 331.978254 -389.674608) (xy 331.958696 -389.66267)
			(xy 331.868526 -389.652764) (xy 331.857113 -389.652192) (xy 331.835615 -389.659847) (xy 331.827124 -389.667496)
			(xy 330.884276 -390.610344) (xy 330.883768 -390.651238) (xy 330.897738 -390.666224) (xy 330.916885 -390.687521)
			(xy 330.949226 -390.734782) (xy 330.974136 -390.786348) (xy 330.991054 -390.84106) (xy 330.999601 -390.897686)
			(xy 331.0001 -390.92632) (xy 330.999613 -390.95357) (xy 330.991854 -391.007515) (xy 330.976497 -391.059807)
			(xy 330.953855 -391.109381) (xy 330.924388 -391.155229) (xy 330.888696 -391.196416) (xy 330.847506 -391.232104)
			(xy 330.801657 -391.261568) (xy 330.752081 -391.284207) (xy 330.699788 -391.29956) (xy 330.645842 -391.307315)
			(xy 330.618592 -391.307828) (xy 330.59452 -391.307478) (xy 330.546755 -391.301446) (xy 330.500132 -391.289443)
			(xy 330.477622 -391.280904) (xy 330.465176 -391.275824) (xy 330.439268 -391.279126) (xy 330.390177 -391.315291)
			(xy 333.556561 -391.315291) (xy 333.556561 -391.263309) (xy 333.564693 -391.211967) (xy 333.580757 -391.16253)
			(xy 333.604356 -391.116214) (xy 333.634911 -391.07416) (xy 333.671668 -391.037404) (xy 333.713723 -391.006851)
			(xy 333.760039 -390.983253) (xy 333.809477 -390.967191) (xy 333.860819 -390.95906) (xy 333.88681 -390.958578)
			(xy 333.910008 -390.958961) (xy 333.955948 -390.965453) (xy 334.000533 -390.978294) (xy 334.042888 -390.997233)
			(xy 334.082184 -391.021899) (xy 334.10017 -391.036556) (xy 334.107282 -391.042652) (xy 334.124808 -391.048748)
			(xy 334.210406 -391.04697) (xy 334.227678 -391.039858) (xy 334.234536 -391.033508) (xy 334.252953 -391.01716)
			(xy 334.293734 -390.989556) (xy 334.338157 -390.968303) (xy 334.38524 -390.953872) (xy 334.433942 -390.94658)
			(xy 334.458564 -390.946132) (xy 334.483401 -390.946579) (xy 334.532518 -390.953998) (xy 334.57997 -390.968689)
			(xy 334.624686 -390.990322) (xy 334.665658 -391.018407) (xy 334.684116 -391.035032) (xy 334.691192 -391.041057)
			(xy 334.708374 -391.0481) (xy 334.717644 -391.048748) (xy 334.748886 -391.04951) (xy 334.758141 -391.049354)
			(xy 334.775594 -391.043229) (xy 334.782922 -391.037572) (xy 334.805455 -391.019365) (xy 334.855596 -390.990358)
			(xy 334.910019 -390.970516) (xy 334.967064 -390.960443) (xy 334.996028 -390.959848) (xy 335.02201 -390.960448)
			(xy 335.073334 -390.968581) (xy 335.122755 -390.984642) (xy 335.169054 -391.008236) (xy 335.211093 -391.038783)
			(xy 335.247836 -391.075529) (xy 335.278378 -391.11757) (xy 335.301968 -391.163871) (xy 335.318026 -391.213293)
			(xy 335.325568 -391.260917) (xy 336.013808 -391.260917) (xy 336.013808 -391.208943) (xy 336.021938 -391.157608)
			(xy 336.037999 -391.108178) (xy 336.061595 -391.061868) (xy 336.092145 -391.01982) (xy 336.128896 -390.983069)
			(xy 336.170944 -390.952519) (xy 336.217254 -390.928923) (xy 336.266684 -390.912862) (xy 336.318019 -390.904732)
			(xy 336.369993 -390.904732) (xy 336.421328 -390.912862) (xy 336.470758 -390.928923) (xy 336.517068 -390.952519)
			(xy 336.559116 -390.983069) (xy 336.595867 -391.01982) (xy 336.626417 -391.061868) (xy 336.650013 -391.108178)
			(xy 336.666074 -391.157608) (xy 336.674204 -391.208943) (xy 336.674714 -391.23493) (xy 336.674204 -391.260917)
			(xy 337.213958 -391.260917) (xy 337.213958 -391.208943) (xy 337.222088 -391.157608) (xy 337.238149 -391.108178)
			(xy 337.261745 -391.061868) (xy 337.292295 -391.01982) (xy 337.329046 -390.983069) (xy 337.371094 -390.952519)
			(xy 337.417404 -390.928923) (xy 337.466834 -390.912862) (xy 337.518169 -390.904732) (xy 337.570143 -390.904732)
			(xy 337.621478 -390.912862) (xy 337.670908 -390.928923) (xy 337.717218 -390.952519) (xy 337.759266 -390.983069)
			(xy 337.796017 -391.01982) (xy 337.826567 -391.061868) (xy 337.850163 -391.108178) (xy 337.866224 -391.157608)
			(xy 337.874354 -391.208943) (xy 337.874864 -391.23493) (xy 337.874354 -391.260917) (xy 338.413854 -391.260917)
			(xy 338.413854 -391.208943) (xy 338.421984 -391.157608) (xy 338.438045 -391.108178) (xy 338.461641 -391.061868)
			(xy 338.492191 -391.01982) (xy 338.528942 -390.983069) (xy 338.57099 -390.952519) (xy 338.6173 -390.928923)
			(xy 338.66673 -390.912862) (xy 338.718065 -390.904732) (xy 338.770039 -390.904732) (xy 338.821374 -390.912862)
			(xy 338.870804 -390.928923) (xy 338.917114 -390.952519) (xy 338.959162 -390.983069) (xy 338.995913 -391.01982)
			(xy 339.026463 -391.061868) (xy 339.050059 -391.108178) (xy 339.06612 -391.157608) (xy 339.07425 -391.208943)
			(xy 339.07476 -391.23493) (xy 339.07425 -391.260917) (xy 339.61375 -391.260917) (xy 339.61375 -391.208943)
			(xy 339.62188 -391.157608) (xy 339.637941 -391.108178) (xy 339.661537 -391.061868) (xy 339.692087 -391.01982)
			(xy 339.728838 -390.983069) (xy 339.770886 -390.952519) (xy 339.817196 -390.928923) (xy 339.866626 -390.912862)
			(xy 339.917961 -390.904732) (xy 339.969935 -390.904732) (xy 340.02127 -390.912862) (xy 340.0707 -390.928923)
			(xy 340.11701 -390.952519) (xy 340.159058 -390.983069) (xy 340.195809 -391.01982) (xy 340.226359 -391.061868)
			(xy 340.249955 -391.108178) (xy 340.266016 -391.157608) (xy 340.274146 -391.208943) (xy 340.274656 -391.23493)
			(xy 340.274146 -391.260917) (xy 340.8139 -391.260917) (xy 340.8139 -391.208943) (xy 340.82203 -391.157608)
			(xy 340.838091 -391.108178) (xy 340.861687 -391.061868) (xy 340.892237 -391.01982) (xy 340.928988 -390.983069)
			(xy 340.971036 -390.952519) (xy 341.017346 -390.928923) (xy 341.066776 -390.912862) (xy 341.118111 -390.904732)
			(xy 341.170085 -390.904732) (xy 341.22142 -390.912862) (xy 341.27085 -390.928923) (xy 341.31716 -390.952519)
			(xy 341.359208 -390.983069) (xy 341.395959 -391.01982) (xy 341.426509 -391.061868) (xy 341.450105 -391.108178)
			(xy 341.466166 -391.157608) (xy 341.474296 -391.208943) (xy 341.474806 -391.23493) (xy 341.474296 -391.260917)
			(xy 342.013796 -391.260917) (xy 342.013796 -391.208943) (xy 342.021926 -391.157608) (xy 342.037987 -391.108178)
			(xy 342.061583 -391.061868) (xy 342.092133 -391.01982) (xy 342.128884 -390.983069) (xy 342.170932 -390.952519)
			(xy 342.217242 -390.928923) (xy 342.266672 -390.912862) (xy 342.318007 -390.904732) (xy 342.369981 -390.904732)
			(xy 342.421316 -390.912862) (xy 342.470746 -390.928923) (xy 342.517056 -390.952519) (xy 342.559104 -390.983069)
			(xy 342.595855 -391.01982) (xy 342.626405 -391.061868) (xy 342.650001 -391.108178) (xy 342.666062 -391.157608)
			(xy 342.674192 -391.208943) (xy 342.674702 -391.23493) (xy 342.674192 -391.260917) (xy 343.213946 -391.260917)
			(xy 343.213946 -391.208943) (xy 343.222076 -391.157608) (xy 343.238137 -391.108178) (xy 343.261733 -391.061868)
			(xy 343.292283 -391.01982) (xy 343.329034 -390.983069) (xy 343.371082 -390.952519) (xy 343.417392 -390.928923)
			(xy 343.466822 -390.912862) (xy 343.518157 -390.904732) (xy 343.570131 -390.904732) (xy 343.621466 -390.912862)
			(xy 343.670896 -390.928923) (xy 343.717206 -390.952519) (xy 343.759254 -390.983069) (xy 343.796005 -391.01982)
			(xy 343.826555 -391.061868) (xy 343.850151 -391.108178) (xy 343.866212 -391.157608) (xy 343.874342 -391.208943)
			(xy 343.874852 -391.23493) (xy 343.874342 -391.260917) (xy 344.413842 -391.260917) (xy 344.413842 -391.208943)
			(xy 344.421972 -391.157608) (xy 344.438033 -391.108178) (xy 344.461629 -391.061868) (xy 344.492179 -391.01982)
			(xy 344.52893 -390.983069) (xy 344.570978 -390.952519) (xy 344.617288 -390.928923) (xy 344.666718 -390.912862)
			(xy 344.718053 -390.904732) (xy 344.770027 -390.904732) (xy 344.821362 -390.912862) (xy 344.870792 -390.928923)
			(xy 344.917102 -390.952519) (xy 344.95915 -390.983069) (xy 344.995901 -391.01982) (xy 345.026451 -391.061868)
			(xy 345.050047 -391.108178) (xy 345.066108 -391.157608) (xy 345.074238 -391.208943) (xy 345.074748 -391.23493)
			(xy 345.074238 -391.260917) (xy 345.613738 -391.260917) (xy 345.613738 -391.208943) (xy 345.621868 -391.157608)
			(xy 345.637929 -391.108178) (xy 345.661525 -391.061868) (xy 345.692075 -391.01982) (xy 345.728826 -390.983069)
			(xy 345.770874 -390.952519) (xy 345.817184 -390.928923) (xy 345.866614 -390.912862) (xy 345.917949 -390.904732)
			(xy 345.969923 -390.904732) (xy 346.021258 -390.912862) (xy 346.070688 -390.928923) (xy 346.116998 -390.952519)
			(xy 346.159046 -390.983069) (xy 346.195797 -391.01982) (xy 346.226347 -391.061868) (xy 346.249943 -391.108178)
			(xy 346.266004 -391.157608) (xy 346.274134 -391.208943) (xy 346.274644 -391.23493) (xy 346.274134 -391.260917)
			(xy 346.813888 -391.260917) (xy 346.813888 -391.208943) (xy 346.822018 -391.157608) (xy 346.838079 -391.108178)
			(xy 346.861675 -391.061868) (xy 346.892225 -391.01982) (xy 346.928976 -390.983069) (xy 346.971024 -390.952519)
			(xy 347.017334 -390.928923) (xy 347.066764 -390.912862) (xy 347.118099 -390.904732) (xy 347.170073 -390.904732)
			(xy 347.221408 -390.912862) (xy 347.270838 -390.928923) (xy 347.317148 -390.952519) (xy 347.359196 -390.983069)
			(xy 347.395947 -391.01982) (xy 347.426497 -391.061868) (xy 347.450093 -391.108178) (xy 347.466154 -391.157608)
			(xy 347.474284 -391.208943) (xy 347.474794 -391.23493) (xy 347.474284 -391.260917) (xy 348.013784 -391.260917)
			(xy 348.013784 -391.208943) (xy 348.021914 -391.157608) (xy 348.037975 -391.108178) (xy 348.061571 -391.061868)
			(xy 348.092121 -391.01982) (xy 348.128872 -390.983069) (xy 348.17092 -390.952519) (xy 348.21723 -390.928923)
			(xy 348.26666 -390.912862) (xy 348.317995 -390.904732) (xy 348.369969 -390.904732) (xy 348.421304 -390.912862)
			(xy 348.470734 -390.928923) (xy 348.517044 -390.952519) (xy 348.559092 -390.983069) (xy 348.595843 -391.01982)
			(xy 348.626393 -391.061868) (xy 348.649989 -391.108178) (xy 348.66605 -391.157608) (xy 348.67418 -391.208943)
			(xy 348.67469 -391.23493) (xy 348.67418 -391.260917) (xy 349.213934 -391.260917) (xy 349.213934 -391.208943)
			(xy 349.222064 -391.157608) (xy 349.238125 -391.108178) (xy 349.261721 -391.061868) (xy 349.292271 -391.01982)
			(xy 349.329022 -390.983069) (xy 349.37107 -390.952519) (xy 349.41738 -390.928923) (xy 349.46681 -390.912862)
			(xy 349.518145 -390.904732) (xy 349.570119 -390.904732) (xy 349.621454 -390.912862) (xy 349.670884 -390.928923)
			(xy 349.717194 -390.952519) (xy 349.759242 -390.983069) (xy 349.795993 -391.01982) (xy 349.826543 -391.061868)
			(xy 349.850139 -391.108178) (xy 349.8662 -391.157608) (xy 349.87433 -391.208943) (xy 349.87484 -391.23493)
			(xy 349.87433 -391.260917) (xy 350.41383 -391.260917) (xy 350.41383 -391.208943) (xy 350.42196 -391.157608)
			(xy 350.438021 -391.108178) (xy 350.461617 -391.061868) (xy 350.492167 -391.01982) (xy 350.528918 -390.983069)
			(xy 350.570966 -390.952519) (xy 350.617276 -390.928923) (xy 350.666706 -390.912862) (xy 350.718041 -390.904732)
			(xy 350.770015 -390.904732) (xy 350.82135 -390.912862) (xy 350.87078 -390.928923) (xy 350.91709 -390.952519)
			(xy 350.959138 -390.983069) (xy 350.995889 -391.01982) (xy 351.026439 -391.061868) (xy 351.050035 -391.108178)
			(xy 351.066096 -391.157608) (xy 351.074226 -391.208943) (xy 351.074736 -391.23493) (xy 351.074226 -391.260917)
			(xy 351.613726 -391.260917) (xy 351.613726 -391.208943) (xy 351.621856 -391.157608) (xy 351.637917 -391.108178)
			(xy 351.661513 -391.061868) (xy 351.692063 -391.01982) (xy 351.728814 -390.983069) (xy 351.770862 -390.952519)
			(xy 351.817172 -390.928923) (xy 351.866602 -390.912862) (xy 351.917937 -390.904732) (xy 351.969911 -390.904732)
			(xy 352.021246 -390.912862) (xy 352.070676 -390.928923) (xy 352.116986 -390.952519) (xy 352.159034 -390.983069)
			(xy 352.195785 -391.01982) (xy 352.226335 -391.061868) (xy 352.249931 -391.108178) (xy 352.265992 -391.157608)
			(xy 352.274122 -391.208943) (xy 352.274632 -391.23493) (xy 352.274122 -391.260917) (xy 352.813876 -391.260917)
			(xy 352.813876 -391.208943) (xy 352.822006 -391.157608) (xy 352.838067 -391.108178) (xy 352.861663 -391.061868)
			(xy 352.892213 -391.01982) (xy 352.928964 -390.983069) (xy 352.971012 -390.952519) (xy 353.017322 -390.928923)
			(xy 353.066752 -390.912862) (xy 353.118087 -390.904732) (xy 353.170061 -390.904732) (xy 353.221396 -390.912862)
			(xy 353.270826 -390.928923) (xy 353.317136 -390.952519) (xy 353.359184 -390.983069) (xy 353.395935 -391.01982)
			(xy 353.426485 -391.061868) (xy 353.450081 -391.108178) (xy 353.466142 -391.157608) (xy 353.474272 -391.208943)
			(xy 353.474782 -391.23493) (xy 353.474272 -391.260917) (xy 354.013772 -391.260917) (xy 354.013772 -391.208943)
			(xy 354.021902 -391.157608) (xy 354.037963 -391.108178) (xy 354.061559 -391.061868) (xy 354.092109 -391.01982)
			(xy 354.12886 -390.983069) (xy 354.170908 -390.952519) (xy 354.217218 -390.928923) (xy 354.266648 -390.912862)
			(xy 354.317983 -390.904732) (xy 354.369957 -390.904732) (xy 354.421292 -390.912862) (xy 354.470722 -390.928923)
			(xy 354.517032 -390.952519) (xy 354.55908 -390.983069) (xy 354.595831 -391.01982) (xy 354.626381 -391.061868)
			(xy 354.649977 -391.108178) (xy 354.666038 -391.157608) (xy 354.674168 -391.208943) (xy 354.674678 -391.23493)
			(xy 354.674168 -391.260917) (xy 354.666038 -391.312252) (xy 354.649977 -391.361682) (xy 354.626381 -391.407992)
			(xy 354.595831 -391.45004) (xy 354.55908 -391.486791) (xy 354.517032 -391.517341) (xy 354.470722 -391.540937)
			(xy 354.421292 -391.556998) (xy 354.369957 -391.565128) (xy 354.317983 -391.565128) (xy 354.266648 -391.556998)
			(xy 354.217218 -391.540937) (xy 354.170908 -391.517341) (xy 354.12886 -391.486791) (xy 354.092109 -391.45004)
			(xy 354.061559 -391.407992) (xy 354.037963 -391.361682) (xy 354.021902 -391.312252) (xy 354.013772 -391.260917)
			(xy 353.474272 -391.260917) (xy 353.466142 -391.312252) (xy 353.450081 -391.361682) (xy 353.426485 -391.407992)
			(xy 353.395935 -391.45004) (xy 353.359184 -391.486791) (xy 353.317136 -391.517341) (xy 353.270826 -391.540937)
			(xy 353.221396 -391.556998) (xy 353.170061 -391.565128) (xy 353.118087 -391.565128) (xy 353.066752 -391.556998)
			(xy 353.017322 -391.540937) (xy 352.971012 -391.517341) (xy 352.928964 -391.486791) (xy 352.892213 -391.45004)
			(xy 352.861663 -391.407992) (xy 352.838067 -391.361682) (xy 352.822006 -391.312252) (xy 352.813876 -391.260917)
			(xy 352.274122 -391.260917) (xy 352.265992 -391.312252) (xy 352.249931 -391.361682) (xy 352.226335 -391.407992)
			(xy 352.195785 -391.45004) (xy 352.159034 -391.486791) (xy 352.116986 -391.517341) (xy 352.070676 -391.540937)
			(xy 352.021246 -391.556998) (xy 351.969911 -391.565128) (xy 351.917937 -391.565128) (xy 351.866602 -391.556998)
			(xy 351.817172 -391.540937) (xy 351.770862 -391.517341) (xy 351.728814 -391.486791) (xy 351.692063 -391.45004)
			(xy 351.661513 -391.407992) (xy 351.637917 -391.361682) (xy 351.621856 -391.312252) (xy 351.613726 -391.260917)
			(xy 351.074226 -391.260917) (xy 351.066096 -391.312252) (xy 351.050035 -391.361682) (xy 351.026439 -391.407992)
			(xy 350.995889 -391.45004) (xy 350.959138 -391.486791) (xy 350.91709 -391.517341) (xy 350.87078 -391.540937)
			(xy 350.82135 -391.556998) (xy 350.770015 -391.565128) (xy 350.718041 -391.565128) (xy 350.666706 -391.556998)
			(xy 350.617276 -391.540937) (xy 350.570966 -391.517341) (xy 350.528918 -391.486791) (xy 350.492167 -391.45004)
			(xy 350.461617 -391.407992) (xy 350.438021 -391.361682) (xy 350.42196 -391.312252) (xy 350.41383 -391.260917)
			(xy 349.87433 -391.260917) (xy 349.8662 -391.312252) (xy 349.850139 -391.361682) (xy 349.826543 -391.407992)
			(xy 349.795993 -391.45004) (xy 349.759242 -391.486791) (xy 349.717194 -391.517341) (xy 349.670884 -391.540937)
			(xy 349.621454 -391.556998) (xy 349.570119 -391.565128) (xy 349.518145 -391.565128) (xy 349.46681 -391.556998)
			(xy 349.41738 -391.540937) (xy 349.37107 -391.517341) (xy 349.329022 -391.486791) (xy 349.292271 -391.45004)
			(xy 349.261721 -391.407992) (xy 349.238125 -391.361682) (xy 349.222064 -391.312252) (xy 349.213934 -391.260917)
			(xy 348.67418 -391.260917) (xy 348.66605 -391.312252) (xy 348.649989 -391.361682) (xy 348.626393 -391.407992)
			(xy 348.595843 -391.45004) (xy 348.559092 -391.486791) (xy 348.517044 -391.517341) (xy 348.470734 -391.540937)
			(xy 348.421304 -391.556998) (xy 348.369969 -391.565128) (xy 348.317995 -391.565128) (xy 348.26666 -391.556998)
			(xy 348.21723 -391.540937) (xy 348.17092 -391.517341) (xy 348.128872 -391.486791) (xy 348.092121 -391.45004)
			(xy 348.061571 -391.407992) (xy 348.037975 -391.361682) (xy 348.021914 -391.312252) (xy 348.013784 -391.260917)
			(xy 347.474284 -391.260917) (xy 347.466154 -391.312252) (xy 347.450093 -391.361682) (xy 347.426497 -391.407992)
			(xy 347.395947 -391.45004) (xy 347.359196 -391.486791) (xy 347.317148 -391.517341) (xy 347.270838 -391.540937)
			(xy 347.221408 -391.556998) (xy 347.170073 -391.565128) (xy 347.118099 -391.565128) (xy 347.066764 -391.556998)
			(xy 347.017334 -391.540937) (xy 346.971024 -391.517341) (xy 346.928976 -391.486791) (xy 346.892225 -391.45004)
			(xy 346.861675 -391.407992) (xy 346.838079 -391.361682) (xy 346.822018 -391.312252) (xy 346.813888 -391.260917)
			(xy 346.274134 -391.260917) (xy 346.266004 -391.312252) (xy 346.249943 -391.361682) (xy 346.226347 -391.407992)
			(xy 346.195797 -391.45004) (xy 346.159046 -391.486791) (xy 346.116998 -391.517341) (xy 346.070688 -391.540937)
			(xy 346.021258 -391.556998) (xy 345.969923 -391.565128) (xy 345.917949 -391.565128) (xy 345.866614 -391.556998)
			(xy 345.817184 -391.540937) (xy 345.770874 -391.517341) (xy 345.728826 -391.486791) (xy 345.692075 -391.45004)
			(xy 345.661525 -391.407992) (xy 345.637929 -391.361682) (xy 345.621868 -391.312252) (xy 345.613738 -391.260917)
			(xy 345.074238 -391.260917) (xy 345.066108 -391.312252) (xy 345.050047 -391.361682) (xy 345.026451 -391.407992)
			(xy 344.995901 -391.45004) (xy 344.95915 -391.486791) (xy 344.917102 -391.517341) (xy 344.870792 -391.540937)
			(xy 344.821362 -391.556998) (xy 344.770027 -391.565128) (xy 344.718053 -391.565128) (xy 344.666718 -391.556998)
			(xy 344.617288 -391.540937) (xy 344.570978 -391.517341) (xy 344.52893 -391.486791) (xy 344.492179 -391.45004)
			(xy 344.461629 -391.407992) (xy 344.438033 -391.361682) (xy 344.421972 -391.312252) (xy 344.413842 -391.260917)
			(xy 343.874342 -391.260917) (xy 343.866212 -391.312252) (xy 343.850151 -391.361682) (xy 343.826555 -391.407992)
			(xy 343.796005 -391.45004) (xy 343.759254 -391.486791) (xy 343.717206 -391.517341) (xy 343.670896 -391.540937)
			(xy 343.621466 -391.556998) (xy 343.570131 -391.565128) (xy 343.518157 -391.565128) (xy 343.466822 -391.556998)
			(xy 343.417392 -391.540937) (xy 343.371082 -391.517341) (xy 343.329034 -391.486791) (xy 343.292283 -391.45004)
			(xy 343.261733 -391.407992) (xy 343.238137 -391.361682) (xy 343.222076 -391.312252) (xy 343.213946 -391.260917)
			(xy 342.674192 -391.260917) (xy 342.666062 -391.312252) (xy 342.650001 -391.361682) (xy 342.626405 -391.407992)
			(xy 342.595855 -391.45004) (xy 342.559104 -391.486791) (xy 342.517056 -391.517341) (xy 342.470746 -391.540937)
			(xy 342.421316 -391.556998) (xy 342.369981 -391.565128) (xy 342.318007 -391.565128) (xy 342.266672 -391.556998)
			(xy 342.217242 -391.540937) (xy 342.170932 -391.517341) (xy 342.128884 -391.486791) (xy 342.092133 -391.45004)
			(xy 342.061583 -391.407992) (xy 342.037987 -391.361682) (xy 342.021926 -391.312252) (xy 342.013796 -391.260917)
			(xy 341.474296 -391.260917) (xy 341.466166 -391.312252) (xy 341.450105 -391.361682) (xy 341.426509 -391.407992)
			(xy 341.395959 -391.45004) (xy 341.359208 -391.486791) (xy 341.31716 -391.517341) (xy 341.27085 -391.540937)
			(xy 341.22142 -391.556998) (xy 341.170085 -391.565128) (xy 341.118111 -391.565128) (xy 341.066776 -391.556998)
			(xy 341.017346 -391.540937) (xy 340.971036 -391.517341) (xy 340.928988 -391.486791) (xy 340.892237 -391.45004)
			(xy 340.861687 -391.407992) (xy 340.838091 -391.361682) (xy 340.82203 -391.312252) (xy 340.8139 -391.260917)
			(xy 340.274146 -391.260917) (xy 340.266016 -391.312252) (xy 340.249955 -391.361682) (xy 340.226359 -391.407992)
			(xy 340.195809 -391.45004) (xy 340.159058 -391.486791) (xy 340.11701 -391.517341) (xy 340.0707 -391.540937)
			(xy 340.02127 -391.556998) (xy 339.969935 -391.565128) (xy 339.917961 -391.565128) (xy 339.866626 -391.556998)
			(xy 339.817196 -391.540937) (xy 339.770886 -391.517341) (xy 339.728838 -391.486791) (xy 339.692087 -391.45004)
			(xy 339.661537 -391.407992) (xy 339.637941 -391.361682) (xy 339.62188 -391.312252) (xy 339.61375 -391.260917)
			(xy 339.07425 -391.260917) (xy 339.06612 -391.312252) (xy 339.050059 -391.361682) (xy 339.026463 -391.407992)
			(xy 338.995913 -391.45004) (xy 338.959162 -391.486791) (xy 338.917114 -391.517341) (xy 338.870804 -391.540937)
			(xy 338.821374 -391.556998) (xy 338.770039 -391.565128) (xy 338.718065 -391.565128) (xy 338.66673 -391.556998)
			(xy 338.6173 -391.540937) (xy 338.57099 -391.517341) (xy 338.528942 -391.486791) (xy 338.492191 -391.45004)
			(xy 338.461641 -391.407992) (xy 338.438045 -391.361682) (xy 338.421984 -391.312252) (xy 338.413854 -391.260917)
			(xy 337.874354 -391.260917) (xy 337.866224 -391.312252) (xy 337.850163 -391.361682) (xy 337.826567 -391.407992)
			(xy 337.796017 -391.45004) (xy 337.759266 -391.486791) (xy 337.717218 -391.517341) (xy 337.670908 -391.540937)
			(xy 337.621478 -391.556998) (xy 337.570143 -391.565128) (xy 337.518169 -391.565128) (xy 337.466834 -391.556998)
			(xy 337.417404 -391.540937) (xy 337.371094 -391.517341) (xy 337.329046 -391.486791) (xy 337.292295 -391.45004)
			(xy 337.261745 -391.407992) (xy 337.238149 -391.361682) (xy 337.222088 -391.312252) (xy 337.213958 -391.260917)
			(xy 336.674204 -391.260917) (xy 336.666074 -391.312252) (xy 336.650013 -391.361682) (xy 336.626417 -391.407992)
			(xy 336.595867 -391.45004) (xy 336.559116 -391.486791) (xy 336.517068 -391.517341) (xy 336.470758 -391.540937)
			(xy 336.421328 -391.556998) (xy 336.369993 -391.565128) (xy 336.318019 -391.565128) (xy 336.266684 -391.556998)
			(xy 336.217254 -391.540937) (xy 336.170944 -391.517341) (xy 336.128896 -391.486791) (xy 336.092145 -391.45004)
			(xy 336.061595 -391.407992) (xy 336.037999 -391.361682) (xy 336.021938 -391.312252) (xy 336.013808 -391.260917)
			(xy 335.325568 -391.260917) (xy 335.326154 -391.264618) (xy 335.326154 -391.316582) (xy 335.318026 -391.367907)
			(xy 335.301968 -391.417329) (xy 335.278378 -391.46363) (xy 335.247836 -391.505671) (xy 335.211093 -391.542417)
			(xy 335.169054 -391.572964) (xy 335.122755 -391.596558) (xy 335.073334 -391.612619) (xy 335.02201 -391.620752)
			(xy 334.996028 -391.621264) (xy 334.971191 -391.620823) (xy 334.922073 -391.613403) (xy 334.874622 -391.59871)
			(xy 334.829905 -391.577076) (xy 334.788933 -391.54899) (xy 334.770476 -391.532364) (xy 334.763402 -391.526335)
			(xy 334.746219 -391.519294) (xy 334.736948 -391.518648) (xy 334.705706 -391.517886) (xy 334.69645 -391.518039)
			(xy 334.678997 -391.524166) (xy 334.67167 -391.529824) (xy 334.649105 -391.547988) (xy 334.598975 -391.577005)
			(xy 334.544562 -391.596858) (xy 334.487525 -391.606945) (xy 334.458564 -391.607548) (xy 334.435368 -391.607117)
			(xy 334.38943 -391.600636) (xy 334.344846 -391.587805) (xy 334.30249 -391.568877) (xy 334.263191 -391.544222)
			(xy 334.245204 -391.52957) (xy 334.238092 -391.523474) (xy 334.220566 -391.517378) (xy 334.134968 -391.519156)
			(xy 334.117696 -391.526268) (xy 334.110838 -391.532618) (xy 334.092395 -391.548936) (xy 334.051621 -391.576543)
			(xy 334.007204 -391.597801) (xy 333.960128 -391.61224) (xy 333.911431 -391.619541) (xy 333.88681 -391.619994)
			(xy 333.860819 -391.61954) (xy 333.809477 -391.611409) (xy 333.760039 -391.595347) (xy 333.713723 -391.571749)
			(xy 333.671668 -391.541196) (xy 333.634911 -391.50444) (xy 333.604356 -391.462386) (xy 333.580757 -391.41607)
			(xy 333.564693 -391.366633) (xy 333.556561 -391.315291) (xy 330.390177 -391.315291) (xy 330.34859 -391.345928)
			(xy 330.337668 -391.36955) (xy 330.338684 -391.382758) (xy 330.3397 -391.41146) (xy 330.339239 -391.438715)
			(xy 330.331487 -391.492669) (xy 330.316134 -391.544972) (xy 330.293494 -391.594556) (xy 330.264027 -391.640414)
			(xy 330.228333 -391.681611) (xy 330.187139 -391.717308) (xy 330.141284 -391.746779) (xy 330.091702 -391.769423)
			(xy 330.039401 -391.78478) (xy 329.985446 -391.792537) (xy 329.958192 -391.792968) (xy 329.929058 -391.792419)
			(xy 329.871469 -391.783546) (xy 329.815908 -391.765994) (xy 329.789536 -391.753598) (xy 329.775058 -391.746486)
			(xy 329.7428 -391.75182) (xy 329.36942 -392.1252) (xy 332.211424 -392.1252) (xy 332.215495 -392.069578)
			(xy 332.227621 -392.015141) (xy 332.247544 -391.96305) (xy 332.27484 -391.914415) (xy 332.308926 -391.870272)
			(xy 332.349075 -391.831563) (xy 332.394433 -391.799112) (xy 332.444033 -391.773611) (xy 332.496817 -391.755604)
			(xy 332.55166 -391.745474) (xy 332.607394 -391.743437) (xy 332.662831 -391.749537) (xy 332.716788 -391.763643)
			(xy 332.768117 -391.785455) (xy 332.815723 -391.814509) (xy 332.858591 -391.850184) (xy 332.895808 -391.891721)
			(xy 332.926581 -391.938234) (xy 332.950253 -391.988731) (xy 332.966321 -392.042138) (xy 332.974441 -392.097314)
			(xy 332.97495 -392.1252) (xy 332.974441 -392.153086) (xy 332.966321 -392.208262) (xy 332.950253 -392.261669)
			(xy 332.926581 -392.312166) (xy 332.895808 -392.358679) (xy 332.858591 -392.400216) (xy 332.815723 -392.435891)
			(xy 332.768117 -392.464945) (xy 332.716788 -392.486757) (xy 332.662831 -392.500863) (xy 332.607394 -392.506963)
			(xy 332.55166 -392.504926) (xy 332.496817 -392.494796) (xy 332.444033 -392.476789) (xy 332.394433 -392.451288)
			(xy 332.349075 -392.418837) (xy 332.308926 -392.380128) (xy 332.27484 -392.335985) (xy 332.247544 -392.28735)
			(xy 332.227621 -392.235259) (xy 332.215495 -392.180822) (xy 332.211424 -392.1252) (xy 329.36942 -392.1252)
			(xy 328.62266 -392.87196) (xy 328.61631 -392.900408) (xy 328.621136 -392.914378) (xy 328.630406 -392.941737)
			(xy 328.643409 -392.998022) (xy 328.64872 -393.04468) (xy 332.211424 -393.04468) (xy 332.215495 -392.989058)
			(xy 332.227621 -392.934621) (xy 332.247544 -392.88253) (xy 332.27484 -392.833895) (xy 332.308926 -392.789752)
			(xy 332.349075 -392.751043) (xy 332.394433 -392.718592) (xy 332.444033 -392.693091) (xy 332.496817 -392.675084)
			(xy 332.55166 -392.664954) (xy 332.607394 -392.662917) (xy 332.662831 -392.669017) (xy 332.716788 -392.683123)
			(xy 332.768117 -392.704935) (xy 332.815723 -392.733989) (xy 332.853418 -392.765359) (xy 333.598522 -392.765359)
			(xy 333.598522 -392.713385) (xy 333.606652 -392.66205) (xy 333.622713 -392.61262) (xy 333.646309 -392.56631)
			(xy 333.676859 -392.524262) (xy 333.71361 -392.487511) (xy 333.755658 -392.456961) (xy 333.801968 -392.433365)
			(xy 333.851398 -392.417304) (xy 333.902733 -392.409174) (xy 333.954707 -392.409174) (xy 334.006042 -392.417304)
			(xy 334.055472 -392.433365) (xy 334.101782 -392.456961) (xy 334.14383 -392.487511) (xy 334.180581 -392.524262)
			(xy 334.211131 -392.56631) (xy 334.234727 -392.61262) (xy 334.250788 -392.66205) (xy 334.258918 -392.713385)
			(xy 334.259428 -392.739372) (xy 334.258918 -392.765359) (xy 334.250788 -392.816694) (xy 334.234727 -392.866124)
			(xy 334.211131 -392.912434) (xy 334.180581 -392.954482) (xy 334.14383 -392.991233) (xy 334.101782 -393.021783)
			(xy 334.094077 -393.025709) (xy 335.659732 -393.025709) (xy 335.659732 -392.973735) (xy 335.667862 -392.9224)
			(xy 335.683923 -392.87297) (xy 335.707519 -392.82666) (xy 335.738069 -392.784612) (xy 335.77482 -392.747861)
			(xy 335.816868 -392.717311) (xy 335.863178 -392.693715) (xy 335.912608 -392.677654) (xy 335.963943 -392.669524)
			(xy 336.015917 -392.669524) (xy 336.067252 -392.677654) (xy 336.116682 -392.693715) (xy 336.162992 -392.717311)
			(xy 336.20504 -392.747861) (xy 336.241791 -392.784612) (xy 336.272341 -392.82666) (xy 336.295937 -392.87297)
			(xy 336.311998 -392.9224) (xy 336.320128 -392.973735) (xy 336.320638 -392.999722) (xy 336.320128 -393.025709)
			(xy 336.859628 -393.025709) (xy 336.859628 -392.973735) (xy 336.867758 -392.9224) (xy 336.883819 -392.87297)
			(xy 336.907415 -392.82666) (xy 336.937965 -392.784612) (xy 336.974716 -392.747861) (xy 337.016764 -392.717311)
			(xy 337.063074 -392.693715) (xy 337.112504 -392.677654) (xy 337.163839 -392.669524) (xy 337.215813 -392.669524)
			(xy 337.267148 -392.677654) (xy 337.316578 -392.693715) (xy 337.362888 -392.717311) (xy 337.404936 -392.747861)
			(xy 337.441687 -392.784612) (xy 337.472237 -392.82666) (xy 337.495833 -392.87297) (xy 337.511894 -392.9224)
			(xy 337.520024 -392.973735) (xy 337.520534 -392.999722) (xy 337.520024 -393.025709) (xy 338.059778 -393.025709)
			(xy 338.059778 -392.973735) (xy 338.067908 -392.9224) (xy 338.083969 -392.87297) (xy 338.107565 -392.82666)
			(xy 338.138115 -392.784612) (xy 338.174866 -392.747861) (xy 338.216914 -392.717311) (xy 338.263224 -392.693715)
			(xy 338.312654 -392.677654) (xy 338.363989 -392.669524) (xy 338.415963 -392.669524) (xy 338.467298 -392.677654)
			(xy 338.516728 -392.693715) (xy 338.563038 -392.717311) (xy 338.605086 -392.747861) (xy 338.641837 -392.784612)
			(xy 338.672387 -392.82666) (xy 338.695983 -392.87297) (xy 338.712044 -392.9224) (xy 338.720174 -392.973735)
			(xy 338.720684 -392.999722) (xy 338.720174 -393.025709) (xy 339.259674 -393.025709) (xy 339.259674 -392.973735)
			(xy 339.267804 -392.9224) (xy 339.283865 -392.87297) (xy 339.307461 -392.82666) (xy 339.338011 -392.784612)
			(xy 339.374762 -392.747861) (xy 339.41681 -392.717311) (xy 339.46312 -392.693715) (xy 339.51255 -392.677654)
			(xy 339.563885 -392.669524) (xy 339.615859 -392.669524) (xy 339.667194 -392.677654) (xy 339.716624 -392.693715)
			(xy 339.762934 -392.717311) (xy 339.804982 -392.747861) (xy 339.841733 -392.784612) (xy 339.872283 -392.82666)
			(xy 339.895879 -392.87297) (xy 339.91194 -392.9224) (xy 339.92007 -392.973735) (xy 339.92058 -392.999722)
			(xy 339.92007 -393.025709) (xy 340.459824 -393.025709) (xy 340.459824 -392.973735) (xy 340.467954 -392.9224)
			(xy 340.484015 -392.87297) (xy 340.507611 -392.82666) (xy 340.538161 -392.784612) (xy 340.574912 -392.747861)
			(xy 340.61696 -392.717311) (xy 340.66327 -392.693715) (xy 340.7127 -392.677654) (xy 340.764035 -392.669524)
			(xy 340.816009 -392.669524) (xy 340.867344 -392.677654) (xy 340.916774 -392.693715) (xy 340.963084 -392.717311)
			(xy 341.005132 -392.747861) (xy 341.041883 -392.784612) (xy 341.072433 -392.82666) (xy 341.096029 -392.87297)
			(xy 341.11209 -392.9224) (xy 341.12022 -392.973735) (xy 341.12073 -392.999722) (xy 341.12022 -393.025709)
			(xy 341.65972 -393.025709) (xy 341.65972 -392.973735) (xy 341.66785 -392.9224) (xy 341.683911 -392.87297)
			(xy 341.707507 -392.82666) (xy 341.738057 -392.784612) (xy 341.774808 -392.747861) (xy 341.816856 -392.717311)
			(xy 341.863166 -392.693715) (xy 341.912596 -392.677654) (xy 341.963931 -392.669524) (xy 342.015905 -392.669524)
			(xy 342.06724 -392.677654) (xy 342.11667 -392.693715) (xy 342.16298 -392.717311) (xy 342.205028 -392.747861)
			(xy 342.241779 -392.784612) (xy 342.272329 -392.82666) (xy 342.295925 -392.87297) (xy 342.311986 -392.9224)
			(xy 342.320116 -392.973735) (xy 342.320626 -392.999722) (xy 342.320116 -393.025709) (xy 342.859616 -393.025709)
			(xy 342.859616 -392.973735) (xy 342.867746 -392.9224) (xy 342.883807 -392.87297) (xy 342.907403 -392.82666)
			(xy 342.937953 -392.784612) (xy 342.974704 -392.747861) (xy 343.016752 -392.717311) (xy 343.063062 -392.693715)
			(xy 343.112492 -392.677654) (xy 343.163827 -392.669524) (xy 343.215801 -392.669524) (xy 343.267136 -392.677654)
			(xy 343.316566 -392.693715) (xy 343.362876 -392.717311) (xy 343.404924 -392.747861) (xy 343.441675 -392.784612)
			(xy 343.472225 -392.82666) (xy 343.495821 -392.87297) (xy 343.511882 -392.9224) (xy 343.520012 -392.973735)
			(xy 343.520522 -392.999722) (xy 343.520012 -393.025709) (xy 344.059766 -393.025709) (xy 344.059766 -392.973735)
			(xy 344.067896 -392.9224) (xy 344.083957 -392.87297) (xy 344.107553 -392.82666) (xy 344.138103 -392.784612)
			(xy 344.174854 -392.747861) (xy 344.216902 -392.717311) (xy 344.263212 -392.693715) (xy 344.312642 -392.677654)
			(xy 344.363977 -392.669524) (xy 344.415951 -392.669524) (xy 344.467286 -392.677654) (xy 344.516716 -392.693715)
			(xy 344.563026 -392.717311) (xy 344.605074 -392.747861) (xy 344.641825 -392.784612) (xy 344.672375 -392.82666)
			(xy 344.695971 -392.87297) (xy 344.712032 -392.9224) (xy 344.720162 -392.973735) (xy 344.720672 -392.999722)
			(xy 344.720162 -393.025709) (xy 345.259662 -393.025709) (xy 345.259662 -392.973735) (xy 345.267792 -392.9224)
			(xy 345.283853 -392.87297) (xy 345.307449 -392.82666) (xy 345.337999 -392.784612) (xy 345.37475 -392.747861)
			(xy 345.416798 -392.717311) (xy 345.463108 -392.693715) (xy 345.512538 -392.677654) (xy 345.563873 -392.669524)
			(xy 345.615847 -392.669524) (xy 345.667182 -392.677654) (xy 345.716612 -392.693715) (xy 345.762922 -392.717311)
			(xy 345.80497 -392.747861) (xy 345.841721 -392.784612) (xy 345.872271 -392.82666) (xy 345.895867 -392.87297)
			(xy 345.911928 -392.9224) (xy 345.920058 -392.973735) (xy 345.920568 -392.999722) (xy 345.920058 -393.025709)
			(xy 346.459812 -393.025709) (xy 346.459812 -392.973735) (xy 346.467942 -392.9224) (xy 346.484003 -392.87297)
			(xy 346.507599 -392.82666) (xy 346.538149 -392.784612) (xy 346.5749 -392.747861) (xy 346.616948 -392.717311)
			(xy 346.663258 -392.693715) (xy 346.712688 -392.677654) (xy 346.764023 -392.669524) (xy 346.815997 -392.669524)
			(xy 346.867332 -392.677654) (xy 346.916762 -392.693715) (xy 346.963072 -392.717311) (xy 347.00512 -392.747861)
			(xy 347.041871 -392.784612) (xy 347.072421 -392.82666) (xy 347.096017 -392.87297) (xy 347.112078 -392.9224)
			(xy 347.120208 -392.973735) (xy 347.120718 -392.999722) (xy 347.120208 -393.025709) (xy 347.659708 -393.025709)
			(xy 347.659708 -392.973735) (xy 347.667838 -392.9224) (xy 347.683899 -392.87297) (xy 347.707495 -392.82666)
			(xy 347.738045 -392.784612) (xy 347.774796 -392.747861) (xy 347.816844 -392.717311) (xy 347.863154 -392.693715)
			(xy 347.912584 -392.677654) (xy 347.963919 -392.669524) (xy 348.015893 -392.669524) (xy 348.067228 -392.677654)
			(xy 348.116658 -392.693715) (xy 348.162968 -392.717311) (xy 348.205016 -392.747861) (xy 348.241767 -392.784612)
			(xy 348.272317 -392.82666) (xy 348.295913 -392.87297) (xy 348.311974 -392.9224) (xy 348.320104 -392.973735)
			(xy 348.320614 -392.999722) (xy 348.320104 -393.025709) (xy 348.859604 -393.025709) (xy 348.859604 -392.973735)
			(xy 348.867734 -392.9224) (xy 348.883795 -392.87297) (xy 348.907391 -392.82666) (xy 348.937941 -392.784612)
			(xy 348.974692 -392.747861) (xy 349.01674 -392.717311) (xy 349.06305 -392.693715) (xy 349.11248 -392.677654)
			(xy 349.163815 -392.669524) (xy 349.215789 -392.669524) (xy 349.267124 -392.677654) (xy 349.316554 -392.693715)
			(xy 349.362864 -392.717311) (xy 349.404912 -392.747861) (xy 349.441663 -392.784612) (xy 349.472213 -392.82666)
			(xy 349.495809 -392.87297) (xy 349.51187 -392.9224) (xy 349.52 -392.973735) (xy 349.52051 -392.999722)
			(xy 349.52 -393.025709) (xy 350.059754 -393.025709) (xy 350.059754 -392.973735) (xy 350.067884 -392.9224)
			(xy 350.083945 -392.87297) (xy 350.107541 -392.82666) (xy 350.138091 -392.784612) (xy 350.174842 -392.747861)
			(xy 350.21689 -392.717311) (xy 350.2632 -392.693715) (xy 350.31263 -392.677654) (xy 350.363965 -392.669524)
			(xy 350.415939 -392.669524) (xy 350.467274 -392.677654) (xy 350.516704 -392.693715) (xy 350.563014 -392.717311)
			(xy 350.605062 -392.747861) (xy 350.641813 -392.784612) (xy 350.672363 -392.82666) (xy 350.695959 -392.87297)
			(xy 350.71202 -392.9224) (xy 350.72015 -392.973735) (xy 350.72066 -392.999722) (xy 350.72015 -393.025709)
			(xy 351.25965 -393.025709) (xy 351.25965 -392.973735) (xy 351.26778 -392.9224) (xy 351.283841 -392.87297)
			(xy 351.307437 -392.82666) (xy 351.337987 -392.784612) (xy 351.374738 -392.747861) (xy 351.416786 -392.717311)
			(xy 351.463096 -392.693715) (xy 351.512526 -392.677654) (xy 351.563861 -392.669524) (xy 351.615835 -392.669524)
			(xy 351.66717 -392.677654) (xy 351.7166 -392.693715) (xy 351.76291 -392.717311) (xy 351.804958 -392.747861)
			(xy 351.841709 -392.784612) (xy 351.872259 -392.82666) (xy 351.895855 -392.87297) (xy 351.911916 -392.9224)
			(xy 351.920046 -392.973735) (xy 351.920556 -392.999722) (xy 351.920046 -393.025709) (xy 352.4598 -393.025709)
			(xy 352.4598 -392.973735) (xy 352.46793 -392.9224) (xy 352.483991 -392.87297) (xy 352.507587 -392.82666)
			(xy 352.538137 -392.784612) (xy 352.574888 -392.747861) (xy 352.616936 -392.717311) (xy 352.663246 -392.693715)
			(xy 352.712676 -392.677654) (xy 352.764011 -392.669524) (xy 352.815985 -392.669524) (xy 352.86732 -392.677654)
			(xy 352.91675 -392.693715) (xy 352.96306 -392.717311) (xy 353.005108 -392.747861) (xy 353.041859 -392.784612)
			(xy 353.072409 -392.82666) (xy 353.096005 -392.87297) (xy 353.112066 -392.9224) (xy 353.120196 -392.973735)
			(xy 353.120706 -392.999722) (xy 353.120196 -393.025709) (xy 353.659696 -393.025709) (xy 353.659696 -392.973735)
			(xy 353.667826 -392.9224) (xy 353.683887 -392.87297) (xy 353.707483 -392.82666) (xy 353.738033 -392.784612)
			(xy 353.774784 -392.747861) (xy 353.816832 -392.717311) (xy 353.863142 -392.693715) (xy 353.912572 -392.677654)
			(xy 353.963907 -392.669524) (xy 354.015881 -392.669524) (xy 354.067216 -392.677654) (xy 354.116646 -392.693715)
			(xy 354.162956 -392.717311) (xy 354.205004 -392.747861) (xy 354.241755 -392.784612) (xy 354.272305 -392.82666)
			(xy 354.295901 -392.87297) (xy 354.311962 -392.9224) (xy 354.320092 -392.973735) (xy 354.320602 -392.999722)
			(xy 354.320092 -393.025709) (xy 354.311962 -393.077044) (xy 354.295901 -393.126474) (xy 354.272305 -393.172784)
			(xy 354.241755 -393.214832) (xy 354.205004 -393.251583) (xy 354.162956 -393.282133) (xy 354.116646 -393.305729)
			(xy 354.067216 -393.32179) (xy 354.015881 -393.32992) (xy 353.963907 -393.32992) (xy 353.912572 -393.32179)
			(xy 353.863142 -393.305729) (xy 353.816832 -393.282133) (xy 353.774784 -393.251583) (xy 353.738033 -393.214832)
			(xy 353.707483 -393.172784) (xy 353.683887 -393.126474) (xy 353.667826 -393.077044) (xy 353.659696 -393.025709)
			(xy 353.120196 -393.025709) (xy 353.112066 -393.077044) (xy 353.096005 -393.126474) (xy 353.072409 -393.172784)
			(xy 353.041859 -393.214832) (xy 353.005108 -393.251583) (xy 352.96306 -393.282133) (xy 352.91675 -393.305729)
			(xy 352.86732 -393.32179) (xy 352.815985 -393.32992) (xy 352.764011 -393.32992) (xy 352.712676 -393.32179)
			(xy 352.663246 -393.305729) (xy 352.616936 -393.282133) (xy 352.574888 -393.251583) (xy 352.538137 -393.214832)
			(xy 352.507587 -393.172784) (xy 352.483991 -393.126474) (xy 352.46793 -393.077044) (xy 352.4598 -393.025709)
			(xy 351.920046 -393.025709) (xy 351.911916 -393.077044) (xy 351.895855 -393.126474) (xy 351.872259 -393.172784)
			(xy 351.841709 -393.214832) (xy 351.804958 -393.251583) (xy 351.76291 -393.282133) (xy 351.7166 -393.305729)
			(xy 351.66717 -393.32179) (xy 351.615835 -393.32992) (xy 351.563861 -393.32992) (xy 351.512526 -393.32179)
			(xy 351.463096 -393.305729) (xy 351.416786 -393.282133) (xy 351.374738 -393.251583) (xy 351.337987 -393.214832)
			(xy 351.307437 -393.172784) (xy 351.283841 -393.126474) (xy 351.26778 -393.077044) (xy 351.25965 -393.025709)
			(xy 350.72015 -393.025709) (xy 350.71202 -393.077044) (xy 350.695959 -393.126474) (xy 350.672363 -393.172784)
			(xy 350.641813 -393.214832) (xy 350.605062 -393.251583) (xy 350.563014 -393.282133) (xy 350.516704 -393.305729)
			(xy 350.467274 -393.32179) (xy 350.415939 -393.32992) (xy 350.363965 -393.32992) (xy 350.31263 -393.32179)
			(xy 350.2632 -393.305729) (xy 350.21689 -393.282133) (xy 350.174842 -393.251583) (xy 350.138091 -393.214832)
			(xy 350.107541 -393.172784) (xy 350.083945 -393.126474) (xy 350.067884 -393.077044) (xy 350.059754 -393.025709)
			(xy 349.52 -393.025709) (xy 349.51187 -393.077044) (xy 349.495809 -393.126474) (xy 349.472213 -393.172784)
			(xy 349.441663 -393.214832) (xy 349.404912 -393.251583) (xy 349.362864 -393.282133) (xy 349.316554 -393.305729)
			(xy 349.267124 -393.32179) (xy 349.215789 -393.32992) (xy 349.163815 -393.32992) (xy 349.11248 -393.32179)
			(xy 349.06305 -393.305729) (xy 349.01674 -393.282133) (xy 348.974692 -393.251583) (xy 348.937941 -393.214832)
			(xy 348.907391 -393.172784) (xy 348.883795 -393.126474) (xy 348.867734 -393.077044) (xy 348.859604 -393.025709)
			(xy 348.320104 -393.025709) (xy 348.311974 -393.077044) (xy 348.295913 -393.126474) (xy 348.272317 -393.172784)
			(xy 348.241767 -393.214832) (xy 348.205016 -393.251583) (xy 348.162968 -393.282133) (xy 348.116658 -393.305729)
			(xy 348.067228 -393.32179) (xy 348.015893 -393.32992) (xy 347.963919 -393.32992) (xy 347.912584 -393.32179)
			(xy 347.863154 -393.305729) (xy 347.816844 -393.282133) (xy 347.774796 -393.251583) (xy 347.738045 -393.214832)
			(xy 347.707495 -393.172784) (xy 347.683899 -393.126474) (xy 347.667838 -393.077044) (xy 347.659708 -393.025709)
			(xy 347.120208 -393.025709) (xy 347.112078 -393.077044) (xy 347.096017 -393.126474) (xy 347.072421 -393.172784)
			(xy 347.041871 -393.214832) (xy 347.00512 -393.251583) (xy 346.963072 -393.282133) (xy 346.916762 -393.305729)
			(xy 346.867332 -393.32179) (xy 346.815997 -393.32992) (xy 346.764023 -393.32992) (xy 346.712688 -393.32179)
			(xy 346.663258 -393.305729) (xy 346.616948 -393.282133) (xy 346.5749 -393.251583) (xy 346.538149 -393.214832)
			(xy 346.507599 -393.172784) (xy 346.484003 -393.126474) (xy 346.467942 -393.077044) (xy 346.459812 -393.025709)
			(xy 345.920058 -393.025709) (xy 345.911928 -393.077044) (xy 345.895867 -393.126474) (xy 345.872271 -393.172784)
			(xy 345.841721 -393.214832) (xy 345.80497 -393.251583) (xy 345.762922 -393.282133) (xy 345.716612 -393.305729)
			(xy 345.667182 -393.32179) (xy 345.615847 -393.32992) (xy 345.563873 -393.32992) (xy 345.512538 -393.32179)
			(xy 345.463108 -393.305729) (xy 345.416798 -393.282133) (xy 345.37475 -393.251583) (xy 345.337999 -393.214832)
			(xy 345.307449 -393.172784) (xy 345.283853 -393.126474) (xy 345.267792 -393.077044) (xy 345.259662 -393.025709)
			(xy 344.720162 -393.025709) (xy 344.712032 -393.077044) (xy 344.695971 -393.126474) (xy 344.672375 -393.172784)
			(xy 344.641825 -393.214832) (xy 344.605074 -393.251583) (xy 344.563026 -393.282133) (xy 344.516716 -393.305729)
			(xy 344.467286 -393.32179) (xy 344.415951 -393.32992) (xy 344.363977 -393.32992) (xy 344.312642 -393.32179)
			(xy 344.263212 -393.305729) (xy 344.216902 -393.282133) (xy 344.174854 -393.251583) (xy 344.138103 -393.214832)
			(xy 344.107553 -393.172784) (xy 344.083957 -393.126474) (xy 344.067896 -393.077044) (xy 344.059766 -393.025709)
			(xy 343.520012 -393.025709) (xy 343.511882 -393.077044) (xy 343.495821 -393.126474) (xy 343.472225 -393.172784)
			(xy 343.441675 -393.214832) (xy 343.404924 -393.251583) (xy 343.362876 -393.282133) (xy 343.316566 -393.305729)
			(xy 343.267136 -393.32179) (xy 343.215801 -393.32992) (xy 343.163827 -393.32992) (xy 343.112492 -393.32179)
			(xy 343.063062 -393.305729) (xy 343.016752 -393.282133) (xy 342.974704 -393.251583) (xy 342.937953 -393.214832)
			(xy 342.907403 -393.172784) (xy 342.883807 -393.126474) (xy 342.867746 -393.077044) (xy 342.859616 -393.025709)
			(xy 342.320116 -393.025709) (xy 342.311986 -393.077044) (xy 342.295925 -393.126474) (xy 342.272329 -393.172784)
			(xy 342.241779 -393.214832) (xy 342.205028 -393.251583) (xy 342.16298 -393.282133) (xy 342.11667 -393.305729)
			(xy 342.06724 -393.32179) (xy 342.015905 -393.32992) (xy 341.963931 -393.32992) (xy 341.912596 -393.32179)
			(xy 341.863166 -393.305729) (xy 341.816856 -393.282133) (xy 341.774808 -393.251583) (xy 341.738057 -393.214832)
			(xy 341.707507 -393.172784) (xy 341.683911 -393.126474) (xy 341.66785 -393.077044) (xy 341.65972 -393.025709)
			(xy 341.12022 -393.025709) (xy 341.11209 -393.077044) (xy 341.096029 -393.126474) (xy 341.072433 -393.172784)
			(xy 341.041883 -393.214832) (xy 341.005132 -393.251583) (xy 340.963084 -393.282133) (xy 340.916774 -393.305729)
			(xy 340.867344 -393.32179) (xy 340.816009 -393.32992) (xy 340.764035 -393.32992) (xy 340.7127 -393.32179)
			(xy 340.66327 -393.305729) (xy 340.61696 -393.282133) (xy 340.574912 -393.251583) (xy 340.538161 -393.214832)
			(xy 340.507611 -393.172784) (xy 340.484015 -393.126474) (xy 340.467954 -393.077044) (xy 340.459824 -393.025709)
			(xy 339.92007 -393.025709) (xy 339.91194 -393.077044) (xy 339.895879 -393.126474) (xy 339.872283 -393.172784)
			(xy 339.841733 -393.214832) (xy 339.804982 -393.251583) (xy 339.762934 -393.282133) (xy 339.716624 -393.305729)
			(xy 339.667194 -393.32179) (xy 339.615859 -393.32992) (xy 339.563885 -393.32992) (xy 339.51255 -393.32179)
			(xy 339.46312 -393.305729) (xy 339.41681 -393.282133) (xy 339.374762 -393.251583) (xy 339.338011 -393.214832)
			(xy 339.307461 -393.172784) (xy 339.283865 -393.126474) (xy 339.267804 -393.077044) (xy 339.259674 -393.025709)
			(xy 338.720174 -393.025709) (xy 338.712044 -393.077044) (xy 338.695983 -393.126474) (xy 338.672387 -393.172784)
			(xy 338.641837 -393.214832) (xy 338.605086 -393.251583) (xy 338.563038 -393.282133) (xy 338.516728 -393.305729)
			(xy 338.467298 -393.32179) (xy 338.415963 -393.32992) (xy 338.363989 -393.32992) (xy 338.312654 -393.32179)
			(xy 338.263224 -393.305729) (xy 338.216914 -393.282133) (xy 338.174866 -393.251583) (xy 338.138115 -393.214832)
			(xy 338.107565 -393.172784) (xy 338.083969 -393.126474) (xy 338.067908 -393.077044) (xy 338.059778 -393.025709)
			(xy 337.520024 -393.025709) (xy 337.511894 -393.077044) (xy 337.495833 -393.126474) (xy 337.472237 -393.172784)
			(xy 337.441687 -393.214832) (xy 337.404936 -393.251583) (xy 337.362888 -393.282133) (xy 337.316578 -393.305729)
			(xy 337.267148 -393.32179) (xy 337.215813 -393.32992) (xy 337.163839 -393.32992) (xy 337.112504 -393.32179)
			(xy 337.063074 -393.305729) (xy 337.016764 -393.282133) (xy 336.974716 -393.251583) (xy 336.937965 -393.214832)
			(xy 336.907415 -393.172784) (xy 336.883819 -393.126474) (xy 336.867758 -393.077044) (xy 336.859628 -393.025709)
			(xy 336.320128 -393.025709) (xy 336.311998 -393.077044) (xy 336.295937 -393.126474) (xy 336.272341 -393.172784)
			(xy 336.241791 -393.214832) (xy 336.20504 -393.251583) (xy 336.162992 -393.282133) (xy 336.116682 -393.305729)
			(xy 336.067252 -393.32179) (xy 336.015917 -393.32992) (xy 335.963943 -393.32992) (xy 335.912608 -393.32179)
			(xy 335.863178 -393.305729) (xy 335.816868 -393.282133) (xy 335.77482 -393.251583) (xy 335.738069 -393.214832)
			(xy 335.707519 -393.172784) (xy 335.683923 -393.126474) (xy 335.667862 -393.077044) (xy 335.659732 -393.025709)
			(xy 334.094077 -393.025709) (xy 334.055472 -393.045379) (xy 334.006042 -393.06144) (xy 333.954707 -393.06957)
			(xy 333.902733 -393.06957) (xy 333.851398 -393.06144) (xy 333.801968 -393.045379) (xy 333.755658 -393.021783)
			(xy 333.71361 -392.991233) (xy 333.676859 -392.954482) (xy 333.646309 -392.912434) (xy 333.622713 -392.866124)
			(xy 333.606652 -392.816694) (xy 333.598522 -392.765359) (xy 332.853418 -392.765359) (xy 332.858591 -392.769664)
			(xy 332.895808 -392.811201) (xy 332.926581 -392.857714) (xy 332.950253 -392.908211) (xy 332.966321 -392.961618)
			(xy 332.974441 -393.016794) (xy 332.97495 -393.04468) (xy 332.974441 -393.072566) (xy 332.966321 -393.127742)
			(xy 332.950253 -393.181149) (xy 332.926581 -393.231646) (xy 332.895808 -393.278159) (xy 332.858591 -393.319696)
			(xy 332.815723 -393.355371) (xy 332.768117 -393.384425) (xy 332.716788 -393.406237) (xy 332.662831 -393.420343)
			(xy 332.607394 -393.426443) (xy 332.55166 -393.424406) (xy 332.496817 -393.414276) (xy 332.444033 -393.396269)
			(xy 332.394433 -393.370768) (xy 332.349075 -393.338317) (xy 332.308926 -393.299608) (xy 332.27484 -393.255465)
			(xy 332.247544 -393.20683) (xy 332.227621 -393.154739) (xy 332.215495 -393.100302) (xy 332.211424 -393.04468)
			(xy 328.64872 -393.04468) (xy 328.649942 -393.05542) (xy 328.650346 -393.084304) (xy 328.649882 -393.115036)
			(xy 328.642474 -393.176051) (xy 328.627765 -393.235728) (xy 328.60597 -393.293198) (xy 328.577408 -393.347622)
			(xy 328.542494 -393.398206) (xy 328.501737 -393.444213) (xy 328.455733 -393.484973) (xy 328.405151 -393.51989)
			(xy 328.350729 -393.548456) (xy 328.293261 -393.570255) (xy 328.233584 -393.584967) (xy 328.17257 -393.59238)
			(xy 328.141838 -393.592812) (xy 328.112955 -393.592405) (xy 328.055559 -393.585861) (xy 327.999274 -393.572863)
			(xy 327.971912 -393.563602) (xy 327.957942 -393.558776) (xy 327.929494 -393.565126) (xy 327.53046 -393.96416)
			(xy 332.211424 -393.96416) (xy 332.215495 -393.908538) (xy 332.227621 -393.854101) (xy 332.247544 -393.80201)
			(xy 332.27484 -393.753375) (xy 332.308926 -393.709232) (xy 332.349075 -393.670523) (xy 332.394433 -393.638072)
			(xy 332.444033 -393.612571) (xy 332.496817 -393.594564) (xy 332.55166 -393.584434) (xy 332.607394 -393.582397)
			(xy 332.662831 -393.588497) (xy 332.716788 -393.602603) (xy 332.768117 -393.624415) (xy 332.815723 -393.653469)
			(xy 332.858591 -393.689144) (xy 332.895808 -393.730681) (xy 332.926581 -393.777194) (xy 332.950253 -393.827691)
			(xy 332.966321 -393.881098) (xy 332.974441 -393.936274) (xy 332.97495 -393.96416) (xy 332.974441 -393.992046)
			(xy 332.971693 -394.010721) (xy 333.177136 -394.010721) (xy 333.177136 -393.958747) (xy 333.185266 -393.907412)
			(xy 333.201327 -393.857982) (xy 333.224923 -393.811672) (xy 333.255473 -393.769624) (xy 333.292224 -393.732873)
			(xy 333.334272 -393.702323) (xy 333.380582 -393.678727) (xy 333.430012 -393.662666) (xy 333.481347 -393.654536)
			(xy 333.533321 -393.654536) (xy 333.584656 -393.662666) (xy 333.634086 -393.678727) (xy 333.660882 -393.69238)
			(xy 335.988152 -393.69238) (xy 335.988683 -393.666394) (xy 335.996815 -393.615063) (xy 336.012877 -393.565636)
			(xy 336.036471 -393.519329) (xy 336.067019 -393.477282) (xy 336.103767 -393.440532) (xy 336.145812 -393.409982)
			(xy 336.192117 -393.386384) (xy 336.241543 -393.37032) (xy 336.292874 -393.362185) (xy 336.31886 -393.361672)
			(xy 336.344872 -393.362087) (xy 336.396251 -393.370255) (xy 336.445718 -393.386364) (xy 336.492054 -393.410017)
			(xy 336.534117 -393.440632) (xy 336.570869 -393.477453) (xy 336.601405 -393.519573) (xy 336.624972 -393.565953)
			(xy 336.640989 -393.61545) (xy 336.645504 -393.641072) (xy 336.647028 -393.65047) (xy 336.671254 -393.69238)
			(xy 337.188048 -393.69238) (xy 337.188583 -393.666394) (xy 337.196715 -393.615064) (xy 337.212776 -393.565636)
			(xy 337.236371 -393.51933) (xy 337.266918 -393.477284) (xy 337.303666 -393.440533) (xy 337.345709 -393.409983)
			(xy 337.392014 -393.386385) (xy 337.44144 -393.370321) (xy 337.492771 -393.362185) (xy 337.518756 -393.361672)
			(xy 337.544768 -393.362091) (xy 337.596147 -393.370258) (xy 337.645614 -393.386366) (xy 337.69195 -393.410019)
			(xy 337.734013 -393.440633) (xy 337.770765 -393.477454) (xy 337.801301 -393.519573) (xy 337.824868 -393.565953)
			(xy 337.840885 -393.61545) (xy 337.8454 -393.641072) (xy 337.846924 -393.65047) (xy 337.87115 -393.69238)
			(xy 338.388198 -393.69238) (xy 338.388683 -393.666392) (xy 338.396817 -393.615056) (xy 338.412881 -393.565625)
			(xy 338.43648 -393.519315) (xy 338.467032 -393.477267) (xy 338.503787 -393.440516) (xy 338.545837 -393.409966)
			(xy 338.592149 -393.386371) (xy 338.641582 -393.370311) (xy 338.692918 -393.362181) (xy 338.718906 -393.361672)
			(xy 338.744916 -393.362136) (xy 338.796293 -393.370296) (xy 338.84576 -393.386397) (xy 338.892096 -393.410044)
			(xy 338.934159 -393.440652) (xy 338.970912 -393.477468) (xy 339.001449 -393.519582) (xy 339.025017 -393.565958)
			(xy 339.041035 -393.615452) (xy 339.04555 -393.641072) (xy 339.047074 -393.65047) (xy 339.071296 -393.69238)
			(xy 339.588094 -393.69238) (xy 339.588583 -393.666392) (xy 339.596717 -393.615057) (xy 339.612781 -393.565626)
			(xy 339.636379 -393.519316) (xy 339.666931 -393.477268) (xy 339.703685 -393.440517) (xy 339.745735 -393.409968)
			(xy 339.792046 -393.386372) (xy 339.841478 -393.370312) (xy 339.892814 -393.362181) (xy 339.918802 -393.361672)
			(xy 339.944812 -393.36214) (xy 339.996189 -393.370299) (xy 340.045655 -393.3864) (xy 340.091991 -393.410046)
			(xy 340.134054 -393.440654) (xy 340.170808 -393.477469) (xy 340.201345 -393.519583) (xy 340.224913 -393.565959)
			(xy 340.240931 -393.615452) (xy 340.245446 -393.641072) (xy 340.24697 -393.65047) (xy 340.271196 -393.69238)
			(xy 340.78799 -393.69238) (xy 340.788483 -393.666392) (xy 340.796617 -393.615057) (xy 340.81268 -393.565627)
			(xy 340.836278 -393.519317) (xy 340.86683 -393.477269) (xy 340.903583 -393.440518) (xy 340.945633 -393.409969)
			(xy 340.991943 -393.386373) (xy 341.041375 -393.370312) (xy 341.09271 -393.362182) (xy 341.118698 -393.361672)
			(xy 341.144708 -393.362143) (xy 341.196085 -393.370302) (xy 341.245551 -393.386402) (xy 341.291887 -393.410048)
			(xy 341.33395 -393.440655) (xy 341.370703 -393.47747) (xy 341.401241 -393.519584) (xy 341.424809 -393.565959)
			(xy 341.440827 -393.615452) (xy 341.445342 -393.641072) (xy 341.446866 -393.65047) (xy 341.471092 -393.69238)
			(xy 341.98814 -393.69238) (xy 341.988557 -393.666388) (xy 341.996693 -393.615044) (xy 342.01276 -393.565605)
			(xy 342.036365 -393.519289) (xy 342.066925 -393.477235) (xy 342.103687 -393.44048) (xy 342.145747 -393.409929)
			(xy 342.192068 -393.386334) (xy 342.24151 -393.370277) (xy 342.292856 -393.362152) (xy 342.318848 -393.361672)
			(xy 342.34486 -393.362098) (xy 342.396238 -393.370264) (xy 342.445705 -393.386371) (xy 342.492041 -393.410023)
			(xy 342.534104 -393.440636) (xy 342.570857 -393.477456) (xy 342.601393 -393.519575) (xy 342.62496 -393.565954)
			(xy 342.640977 -393.61545) (xy 342.645492 -393.641072) (xy 342.647016 -393.65047) (xy 342.671242 -393.69238)
			(xy 343.188036 -393.69238) (xy 343.188457 -393.666388) (xy 343.196592 -393.615044) (xy 343.21266 -393.565606)
			(xy 343.236264 -393.51929) (xy 343.266823 -393.477236) (xy 343.303585 -393.440482) (xy 343.345644 -393.409931)
			(xy 343.391965 -393.386336) (xy 343.441407 -393.370277) (xy 343.492752 -393.362152) (xy 343.518744 -393.361672)
			(xy 343.544755 -393.362102) (xy 343.596134 -393.370267) (xy 343.645601 -393.386374) (xy 343.691937 -393.410025)
			(xy 343.734 -393.440638) (xy 343.770752 -393.477457) (xy 343.801289 -393.519576) (xy 343.824856 -393.565954)
			(xy 343.840873 -393.615451) (xy 343.845388 -393.641072) (xy 343.846912 -393.65047) (xy 343.871138 -393.69238)
			(xy 344.388186 -393.69238) (xy 344.388683 -393.666393) (xy 344.396816 -393.615058) (xy 344.41288 -393.565628)
			(xy 344.436478 -393.519319) (xy 344.467029 -393.477271) (xy 344.503781 -393.44052) (xy 344.54583 -393.40997)
			(xy 344.592141 -393.386374) (xy 344.641572 -393.370313) (xy 344.692907 -393.362182) (xy 344.718894 -393.361672)
			(xy 344.744904 -393.362147) (xy 344.79628 -393.370305) (xy 344.845747 -393.386405) (xy 344.892082 -393.41005)
			(xy 344.934146 -393.440657) (xy 344.970899 -393.477471) (xy 345.001436 -393.519585) (xy 345.025005 -393.56596)
			(xy 345.041023 -393.615452) (xy 345.045538 -393.641072) (xy 345.047062 -393.65047) (xy 345.071284 -393.69238)
			(xy 345.588082 -393.69238) (xy 345.588583 -393.666393) (xy 345.596716 -393.615059) (xy 345.612779 -393.565629)
			(xy 345.636377 -393.51932) (xy 345.666928 -393.477272) (xy 345.70368 -393.440521) (xy 345.745728 -393.409972)
			(xy 345.792038 -393.386376) (xy 345.841468 -393.370314) (xy 345.892803 -393.362182) (xy 345.91879 -393.361672)
			(xy 345.9448 -393.362151) (xy 345.996176 -393.370308) (xy 346.045642 -393.386407) (xy 346.091978 -393.410052)
			(xy 346.134041 -393.440658) (xy 346.170795 -393.477472) (xy 346.201332 -393.519585) (xy 346.224901 -393.56596)
			(xy 346.240919 -393.615452) (xy 346.245434 -393.641072) (xy 346.246958 -393.65047) (xy 346.271184 -393.69238)
			(xy 346.787978 -393.69238) (xy 346.788483 -393.666393) (xy 346.796616 -393.615059) (xy 346.812679 -393.565629)
			(xy 346.836276 -393.519321) (xy 346.866827 -393.477274) (xy 346.903578 -393.440523) (xy 346.945626 -393.409973)
			(xy 346.991935 -393.386377) (xy 347.041365 -393.370315) (xy 347.092699 -393.362183) (xy 347.118686 -393.361672)
			(xy 347.144696 -393.362154) (xy 347.196072 -393.370311) (xy 347.245538 -393.38641) (xy 347.291874 -393.410054)
			(xy 347.333937 -393.44066) (xy 347.370691 -393.477473) (xy 347.401228 -393.519586) (xy 347.424796 -393.56596)
			(xy 347.440815 -393.615453) (xy 347.44533 -393.641072) (xy 347.446854 -393.65047) (xy 347.47108 -393.69238)
			(xy 347.988128 -393.69238) (xy 347.988557 -393.666388) (xy 347.996692 -393.615046) (xy 348.012759 -393.565608)
			(xy 348.036363 -393.519292) (xy 348.066921 -393.477239) (xy 348.103682 -393.440485) (xy 348.14574 -393.409933)
			(xy 348.19206 -393.386338) (xy 348.2415 -393.370279) (xy 348.292844 -393.362152) (xy 348.318836 -393.361672)
			(xy 348.344847 -393.362109) (xy 348.396225 -393.370273) (xy 348.445692 -393.386379) (xy 348.492028 -393.410029)
			(xy 348.534091 -393.440641) (xy 348.570844 -393.477459) (xy 348.60138 -393.519577) (xy 348.624948 -393.565955)
			(xy 348.640965 -393.615451) (xy 348.64548 -393.641072) (xy 348.647004 -393.65047) (xy 348.67123 -393.69238)
			(xy 349.188024 -393.69238) (xy 349.188457 -393.666389) (xy 349.196592 -393.615046) (xy 349.212659 -393.565609)
			(xy 349.236262 -393.519293) (xy 349.26682 -393.477241) (xy 349.30358 -393.440486) (xy 349.345638 -393.409935)
			(xy 349.391957 -393.386339) (xy 349.441397 -393.37028) (xy 349.492741 -393.362153) (xy 349.518732 -393.361672)
			(xy 349.544743 -393.362112) (xy 349.596121 -393.370276) (xy 349.645588 -393.386381) (xy 349.691924 -393.410031)
			(xy 349.733987 -393.440642) (xy 349.77074 -393.477461) (xy 349.801276 -393.519578) (xy 349.824844 -393.565956)
			(xy 349.840861 -393.615451) (xy 349.845376 -393.641072) (xy 349.8469 -393.65047) (xy 349.871126 -393.69238)
			(xy 350.388174 -393.69238) (xy 350.388683 -393.666393) (xy 350.396816 -393.61506) (xy 350.412879 -393.56563)
			(xy 350.436475 -393.519322) (xy 350.467025 -393.477275) (xy 350.503776 -393.440524) (xy 350.545824 -393.409974)
			(xy 350.592132 -393.386378) (xy 350.641562 -393.370316) (xy 350.692895 -393.362183) (xy 350.718882 -393.361672)
			(xy 350.744892 -393.362158) (xy 350.796268 -393.370314) (xy 350.845733 -393.386412) (xy 350.892069 -393.410056)
			(xy 350.934133 -393.440661) (xy 350.970886 -393.477474) (xy 351.001424 -393.519587) (xy 351.024992 -393.565961)
			(xy 351.041011 -393.615453) (xy 351.045526 -393.641072) (xy 351.04705 -393.65047) (xy 351.071272 -393.69238)
			(xy 351.58807 -393.69238) (xy 351.588583 -393.666393) (xy 351.596716 -393.61506) (xy 351.612778 -393.565631)
			(xy 351.636375 -393.519323) (xy 351.666924 -393.477276) (xy 351.703675 -393.440526) (xy 351.745722 -393.409976)
			(xy 351.792029 -393.386379) (xy 351.841458 -393.370316) (xy 351.892791 -393.362183) (xy 351.918778 -393.361672)
			(xy 351.944787 -393.362162) (xy 351.996163 -393.370317) (xy 352.045629 -393.386415) (xy 352.091965 -393.410058)
			(xy 352.134028 -393.440663) (xy 352.170782 -393.477475) (xy 352.20132 -393.519588) (xy 352.224888 -393.565961)
			(xy 352.240907 -393.615453) (xy 352.245422 -393.641072) (xy 352.246946 -393.65047) (xy 352.519742 -394.122402)
			(xy 352.527108 -394.128244) (xy 352.545891 -394.144039) (xy 352.579008 -394.180258) (xy 352.606417 -394.220968)
			(xy 352.627517 -394.265277) (xy 352.641846 -394.312215) (xy 352.649091 -394.360754) (xy 352.649536 -394.385292)
			(xy 352.649282 -394.397484) (xy 352.649028 -394.407136) (xy 352.655124 -394.42517) (xy 352.713798 -394.49248)
			(xy 352.730562 -394.501116) (xy 352.740468 -394.502132) (xy 352.767226 -394.505517) (xy 352.819249 -394.519735)
			(xy 352.868275 -394.542206) (xy 352.913005 -394.572334) (xy 352.952253 -394.609321) (xy 352.98498 -394.652186)
			(xy 353.010317 -394.699794) (xy 353.027593 -394.750882) (xy 353.03635 -394.804097) (xy 353.036886 -394.831062)
			(xy 353.036359 -394.858348) (xy 353.027404 -394.912179) (xy 353.00973 -394.963808) (xy 352.983818 -395.011835)
			(xy 352.950371 -395.054954) (xy 352.930714 -395.073886) (xy 352.923319 -395.081413) (xy 352.91479 -395.100689)
			(xy 352.914204 -395.111224) (xy 352.914204 -395.1859) (xy 352.914719 -395.196451) (xy 352.923264 -395.215747)
			(xy 352.930714 -395.223238) (xy 352.95035 -395.242188) (xy 352.983786 -395.285309) (xy 353.009691 -395.333332)
			(xy 353.027364 -395.384956) (xy 353.036325 -395.43878) (xy 353.036886 -395.466062) (xy 353.03643 -395.490178)
			(xy 353.029435 -395.537899) (xy 353.015587 -395.5841) (xy 352.995179 -395.627802) (xy 352.982276 -395.64818)
			(xy 352.976434 -395.65707) (xy 352.972878 -395.677136) (xy 352.99396 -395.769338) (xy 353.006152 -395.786102)
			(xy 353.015042 -395.791436) (xy 353.035845 -395.804288) (xy 353.07375 -395.835178) (xy 353.106692 -395.871315)
			(xy 353.133953 -395.911908) (xy 353.154938 -395.956074) (xy 353.16919 -396.002849) (xy 353.176397 -396.051213)
			(xy 353.17684 -396.075662) (xy 353.176405 -396.100034) (xy 353.16926 -396.148253) (xy 353.155119 -396.194901)
			(xy 353.134289 -396.238971) (xy 353.107219 -396.279508) (xy 353.074495 -396.315637) (xy 353.055936 -396.33144)
			(xy 353.047046 -396.338552) (xy 353.037648 -396.35811) (xy 353.034854 -396.457424) (xy 353.04349 -396.47749)
			(xy 353.051872 -396.48511) (xy 353.070324 -396.502569) (xy 353.10167 -396.542541) (xy 353.125966 -396.58715)
			(xy 353.142542 -396.635166) (xy 353.150941 -396.685264) (xy 353.15144 -396.710662) (xy 353.151371 -396.720021)
			(xy 353.150228 -396.738703) (xy 353.149154 -396.748) (xy 353.148138 -396.75689) (xy 353.151948 -396.773654)
			(xy 353.19589 -396.843504) (xy 353.209606 -396.853918) (xy 353.217988 -396.856712) (xy 353.242083 -396.865198)
			(xy 353.287374 -396.888822) (xy 353.32827 -396.919432) (xy 353.363702 -396.956228) (xy 353.392745 -396.99825)
			(xy 353.414642 -397.044401) (xy 353.422204 -397.068802) (xy 353.423728 -397.074644) (xy 353.743514 -397.627602)
			(xy 353.747578 -397.63192) (xy 353.763779 -397.649618) (xy 353.79114 -397.68903) (xy 353.812222 -397.732129)
			(xy 353.82654 -397.777922) (xy 353.833764 -397.825354) (xy 353.834192 -397.849344) (xy 353.833723 -397.874134)
			(xy 353.825961 -397.923102) (xy 353.810636 -397.970253) (xy 353.788124 -398.014427) (xy 353.75898 -398.054536)
			(xy 353.723921 -398.089593) (xy 353.68381 -398.118734) (xy 353.639634 -398.141243) (xy 353.592482 -398.156566)
			(xy 353.543514 -398.164324) (xy 353.518724 -398.164812) (xy 353.49333 -398.16429) (xy 353.443198 -398.156164)
			(xy 353.395013 -398.140116) (xy 353.350018 -398.11656) (xy 353.309375 -398.086106) (xy 353.274132 -398.049537)
			(xy 353.245198 -398.007798) (xy 353.223319 -397.961966) (xy 353.215702 -397.937736) (xy 353.214178 -397.931894)
			(xy 352.89363 -397.377412) (xy 352.889566 -397.373094) (xy 352.873469 -397.355431) (xy 352.84628 -397.316133)
			(xy 352.825327 -397.273185) (xy 352.811091 -397.227568) (xy 352.803895 -397.180326) (xy 352.80346 -397.156432)
			(xy 352.803541 -397.144384) (xy 352.805323 -397.120355) (xy 352.807016 -397.108426) (xy 352.808286 -397.099536)
			(xy 352.805238 -397.082518) (xy 352.763074 -397.011652) (xy 352.749866 -397.000476) (xy 352.741484 -396.997428)
			(xy 352.719739 -396.989025) (xy 352.67888 -396.966586) (xy 352.641909 -396.938194) (xy 352.609686 -396.90451)
			(xy 352.58296 -396.866317) (xy 352.562354 -396.824504) (xy 352.548346 -396.780043) (xy 352.541262 -396.73397)
			(xy 352.540824 -396.710662) (xy 352.541342 -396.685267) (xy 352.549752 -396.635177) (xy 352.566333 -396.587169)
			(xy 352.59063 -396.542566) (xy 352.621971 -396.502598) (xy 352.640392 -396.48511) (xy 352.648774 -396.47749)
			(xy 352.65741 -396.457424) (xy 352.654616 -396.35811) (xy 352.645218 -396.338552) (xy 352.636328 -396.33144)
			(xy 352.617786 -396.315618) (xy 352.585066 -396.27949) (xy 352.557997 -396.238956) (xy 352.537164 -396.19489)
			(xy 352.523017 -396.148247) (xy 352.515862 -396.100033) (xy 352.515424 -396.075662) (xy 352.515842 -396.051545)
			(xy 352.522848 -396.003822) (xy 352.536708 -395.957621) (xy 352.557126 -395.913921) (xy 352.570034 -395.893544)
			(xy 352.575876 -395.884654) (xy 352.579432 -395.864588) (xy 352.55835 -395.772386) (xy 352.546158 -395.755622)
			(xy 352.537268 -395.750288) (xy 352.516478 -395.737416) (xy 352.478573 -395.706529) (xy 352.445629 -395.670397)
			(xy 352.418367 -395.629806) (xy 352.39738 -395.585644) (xy 352.383125 -395.538871) (xy 352.375915 -395.49051)
			(xy 352.37547 -395.466062) (xy 352.376026 -395.438778) (xy 352.384976 -395.384949) (xy 352.402644 -395.33332)
			(xy 352.428549 -395.285293) (xy 352.461988 -395.242171) (xy 352.481642 -395.223238) (xy 352.48902 -395.215696)
			(xy 352.49756 -395.196432) (xy 352.498152 -395.1859) (xy 352.498152 -395.111224) (xy 352.497637 -395.100672)
			(xy 352.489093 -395.081376) (xy 352.481642 -395.073886) (xy 352.462009 -395.054933) (xy 352.428575 -395.011812)
			(xy 352.40267 -394.963789) (xy 352.384997 -394.912167) (xy 352.376033 -394.858344) (xy 352.37547 -394.831062)
			(xy 352.375724 -394.81887) (xy 352.375978 -394.809218) (xy 352.369882 -394.791184) (xy 352.311208 -394.723874)
			(xy 352.294444 -394.715238) (xy 352.284538 -394.714222) (xy 352.257629 -394.710868) (xy 352.205343 -394.696501)
			(xy 352.156099 -394.673799) (xy 352.111217 -394.643371) (xy 352.071897 -394.606031) (xy 352.039194 -394.562779)
			(xy 352.013981 -394.514773) (xy 351.996934 -394.463298) (xy 351.992184 -394.4366) (xy 351.99066 -394.427202)
			(xy 351.717864 -393.95527) (xy 351.710498 -393.949428) (xy 351.691751 -393.933592) (xy 351.658631 -393.897382)
			(xy 351.631218 -393.856681) (xy 351.610111 -393.81238) (xy 351.595774 -393.765449) (xy 351.58852 -393.716916)
			(xy 351.58807 -393.69238) (xy 351.071272 -393.69238) (xy 351.3201 -394.12291) (xy 351.327212 -394.128752)
			(xy 351.345932 -394.144545) (xy 351.378987 -394.180684) (xy 351.406345 -394.221307) (xy 351.427407 -394.265523)
			(xy 351.44171 -394.312365) (xy 351.448941 -394.360804) (xy 351.449386 -394.385292) (xy 351.449132 -394.397484)
			(xy 351.448878 -394.407136) (xy 351.454974 -394.42517) (xy 351.513648 -394.49248) (xy 351.530412 -394.501116)
			(xy 351.540318 -394.502132) (xy 351.567082 -394.505476) (xy 351.619105 -394.519702) (xy 351.668131 -394.542179)
			(xy 351.71286 -394.572313) (xy 351.752107 -394.609305) (xy 351.784833 -394.652175) (xy 351.810169 -394.699787)
			(xy 351.827444 -394.750878) (xy 351.836201 -394.804096) (xy 351.836736 -394.831062) (xy 351.836193 -394.858347)
			(xy 351.82724 -394.912176) (xy 351.809569 -394.963805) (xy 351.783661 -395.011832) (xy 351.750219 -395.054953)
			(xy 351.730564 -395.073886) (xy 351.723176 -395.081419) (xy 351.714642 -395.10069) (xy 351.714054 -395.111224)
			(xy 351.714054 -395.1859) (xy 351.714583 -395.196449) (xy 351.72312 -395.215744) (xy 351.730564 -395.223238)
			(xy 351.750209 -395.242178) (xy 351.783641 -395.285303) (xy 351.809544 -395.333329) (xy 351.827215 -395.384954)
			(xy 351.836175 -395.438779) (xy 351.836736 -395.466062) (xy 351.836288 -395.490178) (xy 351.829292 -395.537901)
			(xy 351.815442 -395.584102) (xy 351.795031 -395.627802) (xy 351.782126 -395.64818) (xy 351.776284 -395.65707)
			(xy 351.772728 -395.677136) (xy 351.79381 -395.769338) (xy 351.806002 -395.786102) (xy 351.814892 -395.791436)
			(xy 351.835683 -395.804306) (xy 351.873591 -395.835192) (xy 351.906536 -395.871324) (xy 351.933799 -395.911914)
			(xy 351.954786 -395.956078) (xy 351.969039 -396.002851) (xy 351.976247 -396.051214) (xy 351.97669 -396.075662)
			(xy 351.976273 -396.100035) (xy 351.969127 -396.148255) (xy 351.954984 -396.194905) (xy 351.93415 -396.238975)
			(xy 351.907076 -396.279512) (xy 351.874348 -396.315638) (xy 351.855786 -396.33144) (xy 351.846896 -396.338552)
			(xy 351.837498 -396.35811) (xy 351.834704 -396.457424) (xy 351.84334 -396.47749) (xy 351.851722 -396.48511)
			(xy 351.870165 -396.502579) (xy 351.901513 -396.542547) (xy 351.925812 -396.587154) (xy 351.94239 -396.635168)
			(xy 351.95079 -396.685264) (xy 351.95129 -396.710662) (xy 351.951222 -396.720021) (xy 351.950078 -396.738703)
			(xy 351.949004 -396.748) (xy 351.947988 -396.75689) (xy 351.951798 -396.773654) (xy 351.99574 -396.843504)
			(xy 352.009456 -396.853918) (xy 352.017838 -396.856712) (xy 352.041866 -396.865181) (xy 352.087038 -396.888733)
			(xy 352.127843 -396.919233) (xy 352.163223 -396.955887) (xy 352.192258 -396.997747) (xy 352.214197 -397.043724)
			(xy 352.2218 -397.06804) (xy 352.223324 -397.073882) (xy 352.543618 -397.627602) (xy 352.547682 -397.63192)
			(xy 352.563884 -397.649617) (xy 352.591245 -397.68903) (xy 352.612327 -397.732129) (xy 352.626644 -397.777922)
			(xy 352.633868 -397.825354) (xy 352.634296 -397.849344) (xy 352.633823 -397.874133) (xy 352.626061 -397.923101)
			(xy 352.610736 -397.970252) (xy 352.588224 -398.014426) (xy 352.559081 -398.054534) (xy 352.524022 -398.089591)
			(xy 352.483912 -398.118733) (xy 352.439737 -398.141242) (xy 352.392585 -398.156565) (xy 352.343617 -398.164324)
			(xy 352.318828 -398.164812) (xy 352.293435 -398.164287) (xy 352.243302 -398.156161) (xy 352.195117 -398.140113)
			(xy 352.150123 -398.116559) (xy 352.10948 -398.086105) (xy 352.074236 -398.049537) (xy 352.045302 -398.007798)
			(xy 352.023423 -397.961965) (xy 352.015806 -397.937736) (xy 352.014282 -397.931894) (xy 351.693988 -397.378174)
			(xy 351.689924 -397.373856) (xy 351.673725 -397.356144) (xy 351.646299 -397.316755) (xy 351.625155 -397.273666)
			(xy 351.61078 -397.227873) (xy 351.603506 -397.18043) (xy 351.603056 -397.156432) (xy 351.603197 -397.14438)
			(xy 351.605104 -397.12035) (xy 351.606866 -397.108426) (xy 351.608136 -397.099536) (xy 351.605088 -397.082518)
			(xy 351.562924 -397.011652) (xy 351.549716 -397.000476) (xy 351.541334 -396.997428) (xy 351.519578 -396.989052)
			(xy 351.478721 -396.966607) (xy 351.441752 -396.93821) (xy 351.40953 -396.904521) (xy 351.382807 -396.866325)
			(xy 351.362202 -396.824509) (xy 351.348195 -396.780046) (xy 351.341112 -396.73397) (xy 351.340674 -396.710662)
			(xy 351.341208 -396.685268) (xy 351.349617 -396.635179) (xy 351.366195 -396.587172) (xy 351.390487 -396.542569)
			(xy 351.421823 -396.5026) (xy 351.440242 -396.48511) (xy 351.448624 -396.47749) (xy 351.45726 -396.457424)
			(xy 351.454466 -396.35811) (xy 351.445068 -396.338552) (xy 351.436178 -396.33144) (xy 351.417646 -396.315606)
			(xy 351.384924 -396.279482) (xy 351.357852 -396.238951) (xy 351.337017 -396.194887) (xy 351.322868 -396.148245)
			(xy 351.315712 -396.100032) (xy 351.315274 -396.075662) (xy 351.315684 -396.051544) (xy 351.322691 -396.003821)
			(xy 351.336553 -395.95762) (xy 351.356974 -395.91392) (xy 351.369884 -395.893544) (xy 351.375726 -395.884654)
			(xy 351.379282 -395.864588) (xy 351.3582 -395.772386) (xy 351.346008 -395.755622) (xy 351.337118 -395.750288)
			(xy 351.31634 -395.737398) (xy 351.278432 -395.706516) (xy 351.245486 -395.670387) (xy 351.218221 -395.6298)
			(xy 351.197232 -395.58564) (xy 351.182976 -395.538869) (xy 351.175765 -395.490509) (xy 351.17532 -395.466062)
			(xy 351.17586 -395.438777) (xy 351.184812 -395.384946) (xy 351.202482 -395.333317) (xy 351.228391 -395.28529)
			(xy 351.261836 -395.24217) (xy 351.281492 -395.223238) (xy 351.288878 -395.215703) (xy 351.297411 -395.196433)
			(xy 351.298002 -395.1859) (xy 351.298002 -395.111224) (xy 351.297473 -395.100674) (xy 351.288938 -395.081379)
			(xy 351.281492 -395.073886) (xy 351.261869 -395.054924) (xy 351.228431 -395.011806) (xy 351.202524 -394.963786)
			(xy 351.184848 -394.912165) (xy 351.175883 -394.858344) (xy 351.17532 -394.831062) (xy 351.175574 -394.81887)
			(xy 351.175828 -394.809218) (xy 351.169732 -394.791184) (xy 351.111058 -394.723874) (xy 351.094294 -394.715238)
			(xy 351.084388 -394.714222) (xy 351.057438 -394.710836) (xy 351.005055 -394.696492) (xy 350.955722 -394.673776)
			(xy 350.910766 -394.643302) (xy 350.871397 -394.605888) (xy 350.838675 -394.562541) (xy 350.813479 -394.514427)
			(xy 350.796487 -394.462842) (xy 350.79178 -394.436092) (xy 350.79051 -394.426694) (xy 350.517968 -393.95527)
			(xy 350.510602 -393.949428) (xy 350.491856 -393.93359) (xy 350.458736 -393.897381) (xy 350.431322 -393.85668)
			(xy 350.410216 -393.812379) (xy 350.395879 -393.765449) (xy 350.388625 -393.716916) (xy 350.388174 -393.69238)
			(xy 349.871126 -393.69238) (xy 350.119696 -394.122402) (xy 350.127062 -394.128244) (xy 350.145856 -394.144027)
			(xy 350.17897 -394.180249) (xy 350.206376 -394.220962) (xy 350.227474 -394.265273) (xy 350.241801 -394.312213)
			(xy 350.249045 -394.360753) (xy 350.24949 -394.385292) (xy 350.249236 -394.397484) (xy 350.248982 -394.407136)
			(xy 350.255078 -394.42517) (xy 350.313752 -394.49248) (xy 350.330516 -394.501116) (xy 350.340422 -394.502132)
			(xy 350.367186 -394.505473) (xy 350.41921 -394.519699) (xy 350.468235 -394.542177) (xy 350.512965 -394.572312)
			(xy 350.552212 -394.609304) (xy 350.584937 -394.652174) (xy 350.610273 -394.699786) (xy 350.627548 -394.750878)
			(xy 350.636305 -394.804095) (xy 350.63684 -394.831062) (xy 350.636296 -394.858347) (xy 350.627343 -394.912176)
			(xy 350.609672 -394.963805) (xy 350.583764 -395.011832) (xy 350.550322 -395.054953) (xy 350.530668 -395.073886)
			(xy 350.523281 -395.08142) (xy 350.514746 -395.10069) (xy 350.514158 -395.111224) (xy 350.514158 -395.1859)
			(xy 350.514686 -395.196449) (xy 350.523223 -395.215744) (xy 350.530668 -395.223238) (xy 350.550314 -395.242178)
			(xy 350.583746 -395.285302) (xy 350.609648 -395.333328) (xy 350.627319 -395.384954) (xy 350.636279 -395.438779)
			(xy 350.63684 -395.466062) (xy 350.636392 -395.490178) (xy 350.629395 -395.5379) (xy 350.615545 -395.584101)
			(xy 350.595135 -395.627802) (xy 350.58223 -395.64818) (xy 350.576388 -395.65707) (xy 350.572832 -395.677136)
			(xy 350.593914 -395.769338) (xy 350.606106 -395.786102) (xy 350.614996 -395.791436) (xy 350.635788 -395.804305)
			(xy 350.673696 -395.835191) (xy 350.70664 -395.871323) (xy 350.733903 -395.911914) (xy 350.75489 -395.956078)
			(xy 350.769143 -396.002851) (xy 350.776351 -396.051214) (xy 350.776794 -396.075662) (xy 350.776375 -396.100035)
			(xy 350.769229 -396.148255) (xy 350.755086 -396.194905) (xy 350.734253 -396.238975) (xy 350.707179 -396.279512)
			(xy 350.674452 -396.315638) (xy 350.65589 -396.33144) (xy 350.647 -396.338552) (xy 350.637602 -396.35811)
			(xy 350.634808 -396.457424) (xy 350.643444 -396.47749) (xy 350.651826 -396.48511) (xy 350.670269 -396.502578)
			(xy 350.701618 -396.542546) (xy 350.725916 -396.587153) (xy 350.742494 -396.635168) (xy 350.750894 -396.685264)
			(xy 350.751394 -396.710662) (xy 350.751326 -396.720021) (xy 350.750182 -396.738703) (xy 350.749108 -396.748)
			(xy 350.748092 -396.75689) (xy 350.751902 -396.773654) (xy 350.795844 -396.843504) (xy 350.80956 -396.853918)
			(xy 350.817942 -396.856712) (xy 350.842048 -396.865169) (xy 350.887338 -396.888801) (xy 350.928231 -396.919417)
			(xy 350.963661 -396.956218) (xy 350.992702 -396.998245) (xy 351.014597 -397.0444) (xy 351.022158 -397.068802)
			(xy 351.023682 -397.074644) (xy 351.343468 -397.627602) (xy 351.347532 -397.63192) (xy 351.363729 -397.649634)
			(xy 351.391153 -397.689024) (xy 351.412297 -397.732112) (xy 351.426672 -397.777905) (xy 351.433948 -397.825346)
			(xy 351.4344 -397.849344) (xy 351.433947 -397.874148) (xy 351.426177 -397.923143) (xy 351.410835 -397.970319)
			(xy 351.3883 -398.014513) (xy 351.359127 -398.054636) (xy 351.324034 -398.0897) (xy 351.283886 -398.118839)
			(xy 351.239673 -398.141337) (xy 351.192484 -398.156639) (xy 351.143482 -398.164368) (xy 351.118678 -398.164812)
			(xy 351.093283 -398.164331) (xy 351.043148 -398.156197) (xy 350.994963 -398.140142) (xy 350.949968 -398.116581)
			(xy 350.909326 -398.086121) (xy 350.874083 -398.049547) (xy 350.84515 -398.007804) (xy 350.823272 -397.961967)
			(xy 350.815656 -397.937736) (xy 350.814132 -397.931894) (xy 350.493584 -397.377412) (xy 350.48952 -397.373094)
			(xy 350.473428 -397.355414) (xy 350.446176 -397.316139) (xy 350.425162 -397.273202) (xy 350.410867 -397.227585)
			(xy 350.403619 -397.180334) (xy 350.40316 -397.156432) (xy 350.403301 -397.14438) (xy 350.405208 -397.12035)
			(xy 350.40697 -397.108426) (xy 350.40824 -397.099536) (xy 350.405192 -397.082518) (xy 350.363028 -397.011652)
			(xy 350.34982 -397.000476) (xy 350.341438 -396.997428) (xy 350.319683 -396.98905) (xy 350.278826 -396.966605)
			(xy 350.241856 -396.938208) (xy 350.209635 -396.90452) (xy 350.182911 -396.866324) (xy 350.162306 -396.824508)
			(xy 350.148299 -396.780046) (xy 350.141216 -396.73397) (xy 350.140778 -396.710662) (xy 350.141311 -396.685267)
			(xy 350.149719 -396.635179) (xy 350.166298 -396.587172) (xy 350.190591 -396.542569) (xy 350.221927 -396.502599)
			(xy 350.240346 -396.48511) (xy 350.248728 -396.47749) (xy 350.257364 -396.457424) (xy 350.25457 -396.35811)
			(xy 350.245172 -396.338552) (xy 350.236282 -396.33144) (xy 350.217751 -396.315605) (xy 350.185028 -396.279482)
			(xy 350.157956 -396.23895) (xy 350.137121 -396.194887) (xy 350.122972 -396.148245) (xy 350.115816 -396.100032)
			(xy 350.115378 -396.075662) (xy 350.115787 -396.051544) (xy 350.122795 -396.00382) (xy 350.136656 -395.957619)
			(xy 350.157078 -395.91392) (xy 350.169988 -395.893544) (xy 350.17583 -395.884654) (xy 350.179386 -395.864588)
			(xy 350.158304 -395.772386) (xy 350.146112 -395.755622) (xy 350.137222 -395.750288) (xy 350.116445 -395.737396)
			(xy 350.078536 -395.706515) (xy 350.04559 -395.670387) (xy 350.018325 -395.6298) (xy 349.997336 -395.585639)
			(xy 349.98308 -395.538869) (xy 349.975869 -395.490509) (xy 349.975424 -395.466062) (xy 349.975963 -395.438777)
			(xy 349.984915 -395.384946) (xy 350.002585 -395.333316) (xy 350.028495 -395.28529) (xy 350.06194 -395.24217)
			(xy 350.081596 -395.223238) (xy 350.088982 -395.215704) (xy 350.097515 -395.196433) (xy 350.098106 -395.1859)
			(xy 350.098106 -395.111224) (xy 350.097576 -395.100675) (xy 350.089041 -395.081379) (xy 350.081596 -395.073886)
			(xy 350.061973 -395.054923) (xy 350.028536 -395.011806) (xy 350.002628 -394.963786) (xy 349.984952 -394.912165)
			(xy 349.975987 -394.858343) (xy 349.975424 -394.831062) (xy 349.975678 -394.81887) (xy 349.975932 -394.809218)
			(xy 349.969836 -394.791184) (xy 349.911162 -394.723874) (xy 349.894398 -394.715238) (xy 349.884492 -394.714222)
			(xy 349.857589 -394.710825) (xy 349.805303 -394.696466) (xy 349.75606 -394.673772) (xy 349.711177 -394.643351)
			(xy 349.671856 -394.606017) (xy 349.639151 -394.56277) (xy 349.613936 -394.514768) (xy 349.596888 -394.463297)
			(xy 349.592138 -394.4366) (xy 349.590614 -394.427202) (xy 349.317818 -393.95527) (xy 349.310452 -393.949428)
			(xy 349.291695 -393.933603) (xy 349.258578 -393.897389) (xy 349.231167 -393.856686) (xy 349.210063 -393.812383)
			(xy 349.195727 -393.76545) (xy 349.188474 -393.716916) (xy 349.188024 -393.69238) (xy 348.67123 -393.69238)
			(xy 348.9198 -394.122402) (xy 348.927166 -394.128244) (xy 348.945961 -394.144026) (xy 348.979075 -394.180249)
			(xy 349.00648 -394.220962) (xy 349.027578 -394.265273) (xy 349.041905 -394.312213) (xy 349.049149 -394.360753)
			(xy 349.049594 -394.385292) (xy 349.04934 -394.397484) (xy 349.049086 -394.407136) (xy 349.055182 -394.42517)
			(xy 349.113856 -394.49248) (xy 349.13062 -394.501116) (xy 349.140272 -394.502132) (xy 349.167031 -394.505514)
			(xy 349.219053 -394.519732) (xy 349.268079 -394.542204) (xy 349.312809 -394.572332) (xy 349.352058 -394.60932)
			(xy 349.384784 -394.652185) (xy 349.410121 -394.699794) (xy 349.427397 -394.750882) (xy 349.436154 -394.804097)
			(xy 349.43669 -394.831062) (xy 349.43618 -394.857049) (xy 349.42805 -394.908384) (xy 349.411989 -394.957814)
			(xy 349.388393 -395.004124) (xy 349.357843 -395.046172) (xy 349.321092 -395.082923) (xy 349.279044 -395.113473)
			(xy 349.232734 -395.137069) (xy 349.183304 -395.15313) (xy 349.131969 -395.16126) (xy 349.079995 -395.16126)
			(xy 349.02866 -395.15313) (xy 348.97923 -395.137069) (xy 348.93292 -395.113473) (xy 348.890872 -395.082923)
			(xy 348.854121 -395.046172) (xy 348.823571 -395.004124) (xy 348.799975 -394.957814) (xy 348.783914 -394.908384)
			(xy 348.775784 -394.857049) (xy 348.775274 -394.831062) (xy 348.775528 -394.81887) (xy 348.775782 -394.809218)
			(xy 348.769686 -394.791184) (xy 348.711012 -394.723874) (xy 348.694248 -394.715238) (xy 348.684596 -394.714222)
			(xy 348.657693 -394.710822) (xy 348.605408 -394.696464) (xy 348.556164 -394.67377) (xy 348.511281 -394.643349)
			(xy 348.47196 -394.606016) (xy 348.439255 -394.562769) (xy 348.41404 -394.514768) (xy 348.396992 -394.463297)
			(xy 348.392242 -394.4366) (xy 348.390718 -394.427202) (xy 348.117922 -393.95527) (xy 348.110556 -393.949428)
			(xy 348.0918 -393.933602) (xy 348.058683 -393.897389) (xy 348.031272 -393.856685) (xy 348.010167 -393.812382)
			(xy 347.995832 -393.76545) (xy 347.988578 -393.716916) (xy 347.988128 -393.69238) (xy 347.47108 -393.69238)
			(xy 347.71965 -394.122402) (xy 347.727016 -394.128244) (xy 347.745801 -394.144038) (xy 347.778917 -394.180257)
			(xy 347.806326 -394.220967) (xy 347.827425 -394.265276) (xy 347.841754 -394.312215) (xy 347.848999 -394.360754)
			(xy 347.849444 -394.385292) (xy 347.84919 -394.397484) (xy 347.848936 -394.407136) (xy 347.855032 -394.42517)
			(xy 347.913706 -394.49248) (xy 347.93047 -394.501116) (xy 347.940376 -394.502132) (xy 347.967135 -394.505511)
			(xy 348.019158 -394.51973) (xy 348.068184 -394.542201) (xy 348.112914 -394.572331) (xy 348.152162 -394.609318)
			(xy 348.184888 -394.652185) (xy 348.210225 -394.699793) (xy 348.227501 -394.750882) (xy 348.236258 -394.804097)
			(xy 348.236794 -394.831062) (xy 348.23637 -394.855264) (xy 348.229296 -394.903149) (xy 348.215309 -394.949488)
			(xy 348.194709 -394.99329) (xy 348.181676 -395.013688) (xy 348.176889 -395.021645) (xy 348.172854 -395.039756)
			(xy 348.173802 -395.048994) (xy 348.17812 -395.079982) (xy 348.179796 -395.08928) (xy 348.189081 -395.105721)
			(xy 348.196154 -395.111986) (xy 348.21824 -395.13067) (xy 348.258012 -395.172681) (xy 348.292175 -395.219369)
			(xy 348.320183 -395.269988) (xy 348.34159 -395.323733) (xy 348.356056 -395.379747) (xy 348.363349 -395.437136)
			(xy 348.363794 -395.466062) (xy 348.363199 -395.499383) (xy 348.353538 -395.565321) (xy 348.334414 -395.629161)
			(xy 348.320868 -395.65961) (xy 348.316623 -395.670076) (xy 348.316737 -395.692634) (xy 348.326469 -395.712985)
			(xy 348.334838 -395.72057) (xy 348.357076 -395.739254) (xy 348.397138 -395.781308) (xy 348.431559 -395.828093)
			(xy 348.459784 -395.878857) (xy 348.481361 -395.932783) (xy 348.495943 -395.989005) (xy 348.503295 -396.046621)
			(xy 348.503748 -396.075662) (xy 348.503273 -396.104667) (xy 348.495962 -396.162214) (xy 348.48144 -396.218377)
			(xy 348.459939 -396.272255) (xy 348.431804 -396.322986) (xy 348.397487 -396.369756) (xy 348.357535 -396.411815)
			(xy 348.335346 -396.4305) (xy 348.328234 -396.436088) (xy 348.31909 -396.451328) (xy 348.30385 -396.534132)
			(xy 348.306644 -396.551404) (xy 348.311216 -396.559532) (xy 348.323789 -396.58272) (xy 348.341664 -396.63234)
			(xy 348.350766 -396.684291) (xy 348.351348 -396.710662) (xy 348.940628 -396.710662) (xy 348.94115 -396.685407)
			(xy 348.949463 -396.635585) (xy 348.965864 -396.587811) (xy 348.989905 -396.543388) (xy 349.020929 -396.503528)
			(xy 349.058091 -396.469318) (xy 349.100377 -396.441692) (xy 349.146633 -396.421402) (xy 349.195598 -396.409002)
			(xy 349.245936 -396.404831) (xy 349.296274 -396.409002) (xy 349.345239 -396.421402) (xy 349.391495 -396.441692)
			(xy 349.433781 -396.469318) (xy 349.470943 -396.503528) (xy 349.501967 -396.543388) (xy 349.526008 -396.587811)
			(xy 349.542409 -396.635585) (xy 349.550722 -396.685407) (xy 349.551244 -396.710662) (xy 349.551175 -396.720021)
			(xy 349.550032 -396.738703) (xy 349.548958 -396.748) (xy 349.547942 -396.75689) (xy 349.551752 -396.773654)
			(xy 349.595694 -396.843504) (xy 349.60941 -396.853918) (xy 349.617792 -396.856712) (xy 349.641811 -396.865205)
			(xy 349.686984 -396.888752) (xy 349.727791 -396.919245) (xy 349.763172 -396.955896) (xy 349.79221 -396.997751)
			(xy 349.81415 -397.043726) (xy 349.821754 -397.06804) (xy 349.823278 -397.073882) (xy 350.143572 -397.627602)
			(xy 350.147636 -397.63192) (xy 350.163834 -397.649633) (xy 350.191258 -397.689023) (xy 350.212401 -397.732112)
			(xy 350.226776 -397.777904) (xy 350.234052 -397.825346) (xy 350.234504 -397.849344) (xy 350.234047 -397.874148)
			(xy 350.226277 -397.923143) (xy 350.210936 -397.970319) (xy 350.188401 -398.014512) (xy 350.159228 -398.054635)
			(xy 350.124135 -398.089698) (xy 350.083988 -398.118838) (xy 350.039776 -398.141336) (xy 349.992588 -398.156638)
			(xy 349.943586 -398.164367) (xy 349.918782 -398.164812) (xy 349.893387 -398.164327) (xy 349.843253 -398.156194)
			(xy 349.795067 -398.14014) (xy 349.750072 -398.116579) (xy 349.70943 -398.08612) (xy 349.674187 -398.049547)
			(xy 349.645254 -398.007804) (xy 349.623376 -397.961967) (xy 349.61576 -397.937736) (xy 349.614236 -397.931894)
			(xy 349.293942 -397.378174) (xy 349.289878 -397.373856) (xy 349.273723 -397.356118) (xy 349.246353 -397.316718)
			(xy 349.225261 -397.273629) (xy 349.210933 -397.227845) (xy 349.203698 -397.180419) (xy 349.203264 -397.156432)
			(xy 349.203344 -397.144384) (xy 349.205127 -397.120355) (xy 349.20682 -397.108426) (xy 349.20809 -397.099536)
			(xy 349.205042 -397.082518) (xy 349.162878 -397.011652) (xy 349.14967 -397.000476) (xy 349.141288 -396.997428)
			(xy 349.119544 -396.989023) (xy 349.078685 -396.966584) (xy 349.041714 -396.938193) (xy 349.00949 -396.904509)
			(xy 348.982764 -396.866316) (xy 348.962158 -396.824504) (xy 348.94815 -396.780043) (xy 348.941066 -396.73397)
			(xy 348.940628 -396.710662) (xy 348.351348 -396.710662) (xy 348.351279 -396.720021) (xy 348.350136 -396.738703)
			(xy 348.349062 -396.748) (xy 348.348046 -396.75689) (xy 348.351856 -396.773654) (xy 348.395798 -396.843504)
			(xy 348.409514 -396.853918) (xy 348.417896 -396.856712) (xy 348.441916 -396.865203) (xy 348.487089 -396.88875)
			(xy 348.527896 -396.919244) (xy 348.563277 -396.955895) (xy 348.592314 -396.997751) (xy 348.614254 -397.043726)
			(xy 348.621858 -397.06804) (xy 348.623382 -397.073882) (xy 348.943676 -397.627602) (xy 348.94774 -397.63192)
			(xy 348.963938 -397.649633) (xy 348.991362 -397.689023) (xy 349.012505 -397.732111) (xy 349.02688 -397.777904)
			(xy 349.034156 -397.825346) (xy 349.034608 -397.849344) (xy 349.034147 -397.874147) (xy 349.026377 -397.923142)
			(xy 349.011036 -397.970318) (xy 348.988501 -398.014511) (xy 348.959329 -398.054634) (xy 348.924237 -398.089697)
			(xy 348.884091 -398.118836) (xy 348.839879 -398.141335) (xy 348.792691 -398.156637) (xy 348.74369 -398.164367)
			(xy 348.718886 -398.164812) (xy 348.693491 -398.164324) (xy 348.643357 -398.156191) (xy 348.595171 -398.140138)
			(xy 348.550177 -398.116577) (xy 348.509534 -398.086118) (xy 348.474292 -398.049546) (xy 348.445358 -398.007803)
			(xy 348.42348 -397.961967) (xy 348.415864 -397.937736) (xy 348.41434 -397.931894) (xy 348.094046 -397.378174)
			(xy 348.089982 -397.373856) (xy 348.073827 -397.356118) (xy 348.046457 -397.316717) (xy 348.025365 -397.273629)
			(xy 348.011037 -397.227845) (xy 348.003802 -397.180419) (xy 348.003368 -397.156432) (xy 348.003448 -397.144384)
			(xy 348.005231 -397.120355) (xy 348.006924 -397.108426) (xy 348.008194 -397.099536) (xy 348.005146 -397.082518)
			(xy 347.962982 -397.011652) (xy 347.949774 -397.000476) (xy 347.941392 -396.997428) (xy 347.919649 -396.989021)
			(xy 347.87879 -396.966583) (xy 347.841818 -396.938192) (xy 347.809595 -396.904508) (xy 347.782869 -396.866316)
			(xy 347.762262 -396.824503) (xy 347.748254 -396.780043) (xy 347.74117 -396.733969) (xy 347.740732 -396.710662)
			(xy 347.741294 -396.684289) (xy 347.750378 -396.63233) (xy 347.768268 -396.58271) (xy 347.780864 -396.559532)
			(xy 347.785436 -396.551404) (xy 347.78823 -396.534132) (xy 347.77299 -396.451328) (xy 347.763846 -396.436088)
			(xy 347.756734 -396.4305) (xy 347.73457 -396.411786) (xy 347.694622 -396.369727) (xy 347.660303 -396.322961)
			(xy 347.632162 -396.272236) (xy 347.610651 -396.218364) (xy 347.596114 -396.162208) (xy 347.588783 -396.104666)
			(xy 347.588332 -396.075662) (xy 347.588933 -396.042341) (xy 347.598591 -395.976403) (xy 347.617713 -395.912563)
			(xy 347.631258 -395.882114) (xy 347.635504 -395.871647) (xy 347.6354 -395.849087) (xy 347.625662 -395.828735)
			(xy 347.617288 -395.821154) (xy 347.595018 -395.802506) (xy 347.554957 -395.760446) (xy 347.520539 -395.713655)
			(xy 347.492317 -395.662885) (xy 347.470745 -395.608953) (xy 347.45617 -395.552725) (xy 347.448826 -395.495105)
			(xy 347.448378 -395.466062) (xy 347.44882 -395.437135) (xy 347.456104 -395.379742) (xy 347.470564 -395.323725)
			(xy 347.491969 -395.269977) (xy 347.519978 -395.219355) (xy 347.554143 -395.172668) (xy 347.593921 -395.130659)
			(xy 347.616018 -395.111986) (xy 347.622983 -395.105632) (xy 347.632246 -395.089233) (xy 347.634052 -395.079982)
			(xy 347.63837 -395.048994) (xy 347.639271 -395.039757) (xy 347.635248 -395.021658) (xy 347.630496 -395.013688)
			(xy 347.617508 -394.993266) (xy 347.596928 -394.949464) (xy 347.582941 -394.903133) (xy 347.575845 -394.85526)
			(xy 347.575378 -394.831062) (xy 347.575632 -394.81887) (xy 347.575886 -394.809218) (xy 347.56979 -394.791184)
			(xy 347.511116 -394.723874) (xy 347.494352 -394.715238) (xy 347.484446 -394.714222) (xy 347.457538 -394.710862)
			(xy 347.405252 -394.696496) (xy 347.356008 -394.673795) (xy 347.311126 -394.643368) (xy 347.271806 -394.606029)
			(xy 347.239102 -394.562778) (xy 347.213889 -394.514773) (xy 347.196842 -394.463298) (xy 347.192092 -394.4366)
			(xy 347.190568 -394.427202) (xy 346.917772 -393.95527) (xy 346.910406 -393.949428) (xy 346.891661 -393.93359)
			(xy 346.85854 -393.89738) (xy 346.831127 -393.85668) (xy 346.81002 -393.812379) (xy 346.795683 -393.765448)
			(xy 346.788429 -393.716916) (xy 346.787978 -393.69238) (xy 346.271184 -393.69238) (xy 346.519754 -394.122402)
			(xy 346.52712 -394.128244) (xy 346.545906 -394.144037) (xy 346.579022 -394.180256) (xy 346.60643 -394.220966)
			(xy 346.62753 -394.265276) (xy 346.641858 -394.312214) (xy 346.649103 -394.360754) (xy 346.649548 -394.385292)
			(xy 346.649294 -394.397484) (xy 346.64904 -394.407136) (xy 346.655136 -394.42517) (xy 346.71381 -394.49248)
			(xy 346.730574 -394.501116) (xy 346.740226 -394.502132) (xy 346.766991 -394.50547) (xy 346.819014 -394.519696)
			(xy 346.86804 -394.542175) (xy 346.912769 -394.57231) (xy 346.952016 -394.609303) (xy 346.984741 -394.652174)
			(xy 347.010077 -394.699786) (xy 347.027352 -394.750878) (xy 347.036109 -394.804095) (xy 347.036644 -394.831062)
			(xy 347.036099 -394.858347) (xy 347.027145 -394.912176) (xy 347.009475 -394.963805) (xy 346.983568 -395.011832)
			(xy 346.950126 -395.054953) (xy 346.930472 -395.073886) (xy 346.923085 -395.08142) (xy 346.91455 -395.10069)
			(xy 346.913962 -395.111224) (xy 346.913962 -395.1859) (xy 346.914489 -395.19645) (xy 346.923027 -395.215744)
			(xy 346.930472 -395.223238) (xy 346.950119 -395.242177) (xy 346.98355 -395.285302) (xy 347.009453 -395.333328)
			(xy 347.027123 -395.384954) (xy 347.036083 -395.438779) (xy 347.036644 -395.466062) (xy 347.036195 -395.490178)
			(xy 347.029199 -395.5379) (xy 347.015349 -395.584101) (xy 346.994939 -395.627802) (xy 346.982034 -395.64818)
			(xy 346.976192 -395.65707) (xy 346.972636 -395.677136) (xy 346.993718 -395.769338) (xy 347.00591 -395.786102)
			(xy 347.0148 -395.791436) (xy 347.035593 -395.804303) (xy 347.0735 -395.835189) (xy 347.106445 -395.871322)
			(xy 347.133708 -395.911913) (xy 347.154694 -395.956077) (xy 347.168947 -396.002851) (xy 347.176155 -396.051214)
			(xy 347.176598 -396.075662) (xy 347.176178 -396.100035) (xy 347.169032 -396.148255) (xy 347.154889 -396.194904)
			(xy 347.134056 -396.238974) (xy 347.106983 -396.279511) (xy 347.074255 -396.315638) (xy 347.055694 -396.33144)
			(xy 347.046804 -396.338552) (xy 347.037406 -396.35811) (xy 347.034612 -396.457424) (xy 347.043248 -396.47749)
			(xy 347.05163 -396.48511) (xy 347.070074 -396.502577) (xy 347.101422 -396.542546) (xy 347.125721 -396.587153)
			(xy 347.142298 -396.635168) (xy 347.150698 -396.685264) (xy 347.151198 -396.710662) (xy 347.15113 -396.720021)
			(xy 347.149986 -396.738703) (xy 347.148912 -396.748) (xy 347.147896 -396.75689) (xy 347.151706 -396.773654)
			(xy 347.195648 -396.843504) (xy 347.209364 -396.853918) (xy 347.217746 -396.856712) (xy 347.241776 -396.865177)
			(xy 347.286948 -396.88873) (xy 347.327752 -396.91923) (xy 347.363131 -396.955886) (xy 347.392167 -396.997746)
			(xy 347.414105 -397.043724) (xy 347.421708 -397.06804) (xy 347.423232 -397.073882) (xy 347.743526 -397.627602)
			(xy 347.74759 -397.63192) (xy 347.763793 -397.649616) (xy 347.791153 -397.689029) (xy 347.812235 -397.732129)
			(xy 347.826552 -397.777922) (xy 347.833776 -397.825354) (xy 347.834204 -397.849344) (xy 347.833723 -397.874133)
			(xy 347.825961 -397.9231) (xy 347.810637 -397.97025) (xy 347.788126 -398.014423) (xy 347.758983 -398.054532)
			(xy 347.723926 -398.089588) (xy 347.683816 -398.11873) (xy 347.639643 -398.14124) (xy 347.592492 -398.156563)
			(xy 347.543525 -398.164323) (xy 347.518736 -398.164812) (xy 347.493343 -398.16428) (xy 347.443211 -398.156155)
			(xy 347.395026 -398.140109) (xy 347.350031 -398.116555) (xy 347.309388 -398.086102) (xy 347.274145 -398.049535)
			(xy 347.24521 -398.007797) (xy 347.223331 -397.961965) (xy 347.215714 -397.937736) (xy 347.21419 -397.931894)
			(xy 346.893896 -397.378174) (xy 346.889832 -397.373856) (xy 346.873617 -397.356158) (xy 346.846197 -397.316763)
			(xy 346.825058 -397.273671) (xy 346.810686 -397.227875) (xy 346.803414 -397.180431) (xy 346.802964 -397.156432)
			(xy 346.803105 -397.14438) (xy 346.805012 -397.12035) (xy 346.806774 -397.108426) (xy 346.808044 -397.099536)
			(xy 346.804996 -397.082518) (xy 346.762832 -397.011652) (xy 346.749624 -397.000476) (xy 346.741242 -396.997428)
			(xy 346.719488 -396.989048) (xy 346.67863 -396.966604) (xy 346.641661 -396.938207) (xy 346.609439 -396.904519)
			(xy 346.582715 -396.866324) (xy 346.56211 -396.824508) (xy 346.548103 -396.780046) (xy 346.54102 -396.73397)
			(xy 346.540582 -396.710662) (xy 346.541114 -396.685267) (xy 346.549522 -396.635179) (xy 346.566101 -396.587172)
			(xy 346.590394 -396.542569) (xy 346.621731 -396.502599) (xy 346.64015 -396.48511) (xy 346.648532 -396.47749)
			(xy 346.657168 -396.457424) (xy 346.654374 -396.35811) (xy 346.644976 -396.338552) (xy 346.636086 -396.33144)
			(xy 346.617556 -396.315604) (xy 346.584833 -396.279481) (xy 346.557761 -396.23895) (xy 346.536925 -396.194887)
			(xy 346.522776 -396.148245) (xy 346.51562 -396.100032) (xy 346.515182 -396.075662) (xy 346.515591 -396.051544)
			(xy 346.522598 -396.00382) (xy 346.53646 -395.957619) (xy 346.556882 -395.91392) (xy 346.569792 -395.893544)
			(xy 346.575634 -395.884654) (xy 346.57919 -395.864588) (xy 346.558108 -395.772386) (xy 346.545916 -395.755622)
			(xy 346.537026 -395.750288) (xy 346.516227 -395.737431) (xy 346.478323 -395.70654) (xy 346.445382 -395.670404)
			(xy 346.418121 -395.629811) (xy 346.397136 -395.585647) (xy 346.382883 -395.538873) (xy 346.375673 -395.49051)
			(xy 346.375228 -395.466062) (xy 346.375766 -395.438777) (xy 346.384718 -395.384946) (xy 346.402388 -395.333316)
			(xy 346.428298 -395.285289) (xy 346.461743 -395.24217) (xy 346.4814 -395.223238) (xy 346.488787 -395.215704)
			(xy 346.49732 -395.196433) (xy 346.49791 -395.1859) (xy 346.49791 -395.111224) (xy 346.497378 -395.100675)
			(xy 346.488845 -395.08138) (xy 346.4814 -395.073886) (xy 346.461778 -395.054922) (xy 346.42834 -395.011806)
			(xy 346.402432 -394.963786) (xy 346.384756 -394.912165) (xy 346.375791 -394.858343) (xy 346.375228 -394.831062)
			(xy 346.375482 -394.81887) (xy 346.375736 -394.809218) (xy 346.36964 -394.791184) (xy 346.310966 -394.723874)
			(xy 346.294202 -394.715238) (xy 346.28455 -394.714222) (xy 346.257642 -394.710859) (xy 346.205356 -394.696493)
			(xy 346.156113 -394.673793) (xy 346.11123 -394.643367) (xy 346.071911 -394.606028) (xy 346.039206 -394.562777)
			(xy 346.013993 -394.514772) (xy 345.996946 -394.463298) (xy 345.992196 -394.4366) (xy 345.990672 -394.427202)
			(xy 345.717876 -393.95527) (xy 345.71051 -393.949428) (xy 345.691765 -393.933589) (xy 345.658645 -393.89738)
			(xy 345.631231 -393.856679) (xy 345.610124 -393.812379) (xy 345.595787 -393.765448) (xy 345.588533 -393.716916)
			(xy 345.588082 -393.69238) (xy 345.071284 -393.69238) (xy 345.320112 -394.12291) (xy 345.327224 -394.128752)
			(xy 345.345947 -394.144543) (xy 345.379001 -394.180682) (xy 345.406359 -394.221306) (xy 345.427419 -394.265523)
			(xy 345.441722 -394.312364) (xy 345.448953 -394.360804) (xy 345.449398 -394.385292) (xy 345.449144 -394.397484)
			(xy 345.44889 -394.407136) (xy 345.454986 -394.42517) (xy 345.51366 -394.49248) (xy 345.530424 -394.501116)
			(xy 345.54033 -394.502132) (xy 345.567095 -394.505467) (xy 345.619119 -394.519694) (xy 345.668144 -394.542173)
			(xy 345.712873 -394.572308) (xy 345.75212 -394.609302) (xy 345.784845 -394.652173) (xy 345.810181 -394.699785)
			(xy 345.827456 -394.750877) (xy 345.836213 -394.804095) (xy 345.836748 -394.831062) (xy 345.836202 -394.858346)
			(xy 345.827248 -394.912176) (xy 345.809578 -394.963804) (xy 345.783671 -395.011831) (xy 345.75023 -395.054953)
			(xy 345.730576 -395.073886) (xy 345.72319 -395.081421) (xy 345.714654 -395.10069) (xy 345.714066 -395.111224)
			(xy 345.714066 -395.1859) (xy 345.714592 -395.19645) (xy 345.72313 -395.215744) (xy 345.730576 -395.223238)
			(xy 345.750224 -395.242176) (xy 345.783655 -395.285301) (xy 345.809557 -395.333328) (xy 345.827227 -395.384954)
			(xy 345.836187 -395.438779) (xy 345.836748 -395.466062) (xy 345.836298 -395.490178) (xy 345.829302 -395.5379)
			(xy 345.815452 -395.584101) (xy 345.795043 -395.627802) (xy 345.782138 -395.64818) (xy 345.776296 -395.65707)
			(xy 345.77274 -395.677136) (xy 345.793822 -395.769338) (xy 345.806014 -395.786102) (xy 345.814904 -395.791436)
			(xy 345.835698 -395.804302) (xy 345.873605 -395.835188) (xy 345.906549 -395.871321) (xy 345.933812 -395.911913)
			(xy 345.954798 -395.956077) (xy 345.969051 -396.002851) (xy 345.976259 -396.051214) (xy 345.976702 -396.075662)
			(xy 345.97628 -396.100035) (xy 345.969135 -396.148255) (xy 345.954992 -396.194904) (xy 345.934159 -396.238974)
			(xy 345.907086 -396.279511) (xy 345.874359 -396.315638) (xy 345.855798 -396.33144) (xy 345.846908 -396.338552)
			(xy 345.83751 -396.35811) (xy 345.834716 -396.457424) (xy 345.843352 -396.47749) (xy 345.851734 -396.48511)
			(xy 345.870179 -396.502576) (xy 345.901527 -396.542545) (xy 345.925825 -396.587153) (xy 345.942402 -396.635167)
			(xy 345.950802 -396.685264) (xy 345.951302 -396.710662) (xy 345.951234 -396.720021) (xy 345.95009 -396.738703)
			(xy 345.949016 -396.748) (xy 345.948 -396.75689) (xy 345.95181 -396.773654) (xy 345.995752 -396.843504)
			(xy 346.009468 -396.853918) (xy 346.01785 -396.856712) (xy 346.04188 -396.865174) (xy 346.087052 -396.888729)
			(xy 346.127857 -396.919229) (xy 346.163236 -396.955885) (xy 346.192271 -396.997746) (xy 346.214209 -397.043724)
			(xy 346.221812 -397.06804) (xy 346.223336 -397.073882) (xy 346.54363 -397.627602) (xy 346.547694 -397.63192)
			(xy 346.563898 -397.649615) (xy 346.591258 -397.689029) (xy 346.612339 -397.732128) (xy 346.626656 -397.777922)
			(xy 346.63388 -397.825354) (xy 346.634308 -397.849344) (xy 346.633823 -397.874133) (xy 346.626062 -397.923099)
			(xy 346.610737 -397.970249) (xy 346.588227 -398.014422) (xy 346.559084 -398.05453) (xy 346.524027 -398.089587)
			(xy 346.483919 -398.118729) (xy 346.439746 -398.141239) (xy 346.392595 -398.156562) (xy 346.343629 -398.164323)
			(xy 346.31884 -398.164812) (xy 346.293447 -398.164276) (xy 346.243315 -398.156152) (xy 346.19513 -398.140106)
			(xy 346.150136 -398.116553) (xy 346.109493 -398.086101) (xy 346.074249 -398.049534) (xy 346.045314 -398.007796)
			(xy 346.023435 -397.961965) (xy 346.015818 -397.937736) (xy 346.014294 -397.931894) (xy 345.694 -397.378174)
			(xy 345.689936 -397.373856) (xy 345.673722 -397.356157) (xy 345.646302 -397.316763) (xy 345.625162 -397.273671)
			(xy 345.61079 -397.227875) (xy 345.603518 -397.180431) (xy 345.603068 -397.156432) (xy 345.60321 -397.14438)
			(xy 345.605116 -397.12035) (xy 345.606878 -397.108426) (xy 345.608148 -397.099536) (xy 345.6051 -397.082518)
			(xy 345.562936 -397.011652) (xy 345.549728 -397.000476) (xy 345.541346 -396.997428) (xy 345.519593 -396.989046)
			(xy 345.478735 -396.966602) (xy 345.441766 -396.938206) (xy 345.409544 -396.904518) (xy 345.382819 -396.866323)
			(xy 345.362214 -396.824508) (xy 345.348207 -396.780045) (xy 345.341124 -396.73397) (xy 345.340686 -396.710662)
			(xy 345.341216 -396.685267) (xy 345.349625 -396.635179) (xy 345.366204 -396.587171) (xy 345.390497 -396.542569)
			(xy 345.421835 -396.502599) (xy 345.440254 -396.48511) (xy 345.448636 -396.47749) (xy 345.457272 -396.457424)
			(xy 345.454478 -396.35811) (xy 345.44508 -396.338552) (xy 345.43619 -396.33144) (xy 345.41766 -396.315603)
			(xy 345.384937 -396.27948) (xy 345.357865 -396.238949) (xy 345.337029 -396.194887) (xy 345.32288 -396.148245)
			(xy 345.315724 -396.100032) (xy 345.315286 -396.075662) (xy 345.315694 -396.051544) (xy 345.322702 -396.00382)
			(xy 345.336564 -395.957619) (xy 345.356986 -395.91392) (xy 345.369896 -395.893544) (xy 345.375738 -395.884654)
			(xy 345.379294 -395.864588) (xy 345.358212 -395.772386) (xy 345.34602 -395.755622) (xy 345.33713 -395.750288)
			(xy 345.316332 -395.737429) (xy 345.278428 -395.706539) (xy 345.245486 -395.670403) (xy 345.218226 -395.629811)
			(xy 345.19724 -395.585646) (xy 345.182987 -395.538873) (xy 345.175777 -395.49051) (xy 345.175332 -395.466062)
			(xy 345.175869 -395.438777) (xy 345.18482 -395.384946) (xy 345.202491 -395.333316) (xy 345.228402 -395.285289)
			(xy 345.261847 -395.24217) (xy 345.281504 -395.223238) (xy 345.288891 -395.215705) (xy 345.297424 -395.196433)
			(xy 345.298014 -395.1859) (xy 345.298014 -395.111224) (xy 345.297481 -395.100675) (xy 345.288948 -395.08138)
			(xy 345.281504 -395.073886) (xy 345.261864 -395.05494) (xy 345.228433 -395.011816) (xy 345.20253 -394.963792)
			(xy 345.184858 -394.912168) (xy 345.175895 -394.858344) (xy 345.175332 -394.831062) (xy 345.175586 -394.81887)
			(xy 345.17584 -394.809218) (xy 345.169744 -394.791184) (xy 345.11107 -394.723874) (xy 345.094306 -394.715238)
			(xy 345.0844 -394.714222) (xy 345.057451 -394.710827) (xy 345.005068 -394.696484) (xy 344.955735 -394.67377)
			(xy 344.910779 -394.643297) (xy 344.87141 -394.605884) (xy 344.838687 -394.562538) (xy 344.813491 -394.514426)
			(xy 344.796499 -394.462842) (xy 344.791792 -394.436092) (xy 344.790522 -394.426694) (xy 344.51798 -393.95527)
			(xy 344.510614 -393.949428) (xy 344.49187 -393.933588) (xy 344.45875 -393.897379) (xy 344.431336 -393.856679)
			(xy 344.410229 -393.812379) (xy 344.395891 -393.765448) (xy 344.388637 -393.716916) (xy 344.388186 -393.69238)
			(xy 343.871138 -393.69238) (xy 344.119708 -394.122402) (xy 344.127074 -394.128244) (xy 344.145871 -394.144024)
			(xy 344.178984 -394.180247) (xy 344.206389 -394.220961) (xy 344.227486 -394.265273) (xy 344.241813 -394.312213)
			(xy 344.249057 -394.360753) (xy 344.249502 -394.385292) (xy 344.249248 -394.397484) (xy 344.248994 -394.407136)
			(xy 344.25509 -394.42517) (xy 344.313764 -394.49248) (xy 344.330528 -394.501116) (xy 344.340434 -394.502132)
			(xy 344.3672 -394.505464) (xy 344.419223 -394.519691) (xy 344.468249 -394.542171) (xy 344.512978 -394.572307)
			(xy 344.552225 -394.609301) (xy 344.584949 -394.652172) (xy 344.610285 -394.699785) (xy 344.62756 -394.750877)
			(xy 344.636317 -394.804095) (xy 344.636852 -394.831062) (xy 344.636304 -394.858346) (xy 344.627351 -394.912176)
			(xy 344.609681 -394.963804) (xy 344.583774 -395.011831) (xy 344.550334 -395.054953) (xy 344.53068 -395.073886)
			(xy 344.52328 -395.081408) (xy 344.514755 -395.100688) (xy 344.51417 -395.111224) (xy 344.51417 -395.1859)
			(xy 344.514694 -395.19645) (xy 344.523234 -395.215745) (xy 344.53068 -395.223238) (xy 344.550328 -395.242175)
			(xy 344.583759 -395.285301) (xy 344.609661 -395.333328) (xy 344.627331 -395.384953) (xy 344.636291 -395.438779)
			(xy 344.636852 -395.466062) (xy 344.636402 -395.490178) (xy 344.629406 -395.5379) (xy 344.615556 -395.584101)
			(xy 344.595146 -395.627802) (xy 344.582242 -395.64818) (xy 344.5764 -395.65707) (xy 344.572844 -395.677136)
			(xy 344.593926 -395.769338) (xy 344.606118 -395.786102) (xy 344.615008 -395.791436) (xy 344.635803 -395.8043)
			(xy 344.67371 -395.835187) (xy 344.706654 -395.871321) (xy 344.733916 -395.911912) (xy 344.754903 -395.956077)
			(xy 344.769155 -396.002851) (xy 344.776363 -396.051214) (xy 344.776806 -396.075662) (xy 344.776383 -396.100035)
			(xy 344.769237 -396.148254) (xy 344.755095 -396.194904) (xy 344.734262 -396.238974) (xy 344.70719 -396.279511)
			(xy 344.674463 -396.315638) (xy 344.655902 -396.33144) (xy 344.647012 -396.338552) (xy 344.637614 -396.35811)
			(xy 344.63482 -396.457424) (xy 344.643456 -396.47749) (xy 344.651838 -396.48511) (xy 344.670284 -396.502575)
			(xy 344.701631 -396.542545) (xy 344.725929 -396.587153) (xy 344.742507 -396.635167) (xy 344.750906 -396.685264)
			(xy 344.751406 -396.710662) (xy 344.751337 -396.720021) (xy 344.750194 -396.738703) (xy 344.74912 -396.748)
			(xy 344.748104 -396.75689) (xy 344.751914 -396.773654) (xy 344.795856 -396.843504) (xy 344.809572 -396.853918)
			(xy 344.817954 -396.856712) (xy 344.842042 -396.865217) (xy 344.887335 -396.888836) (xy 344.928231 -396.919441)
			(xy 344.963665 -396.956234) (xy 344.992709 -396.998253) (xy 345.014607 -397.044402) (xy 345.02217 -397.068802)
			(xy 345.023694 -397.074644) (xy 345.34348 -397.627602) (xy 345.347544 -397.63192) (xy 345.363743 -397.649632)
			(xy 345.391166 -397.689023) (xy 345.412309 -397.732111) (xy 345.426684 -397.777904) (xy 345.43396 -397.825346)
			(xy 345.434412 -397.849344) (xy 345.433947 -397.874147) (xy 345.426177 -397.923142) (xy 345.410836 -397.970317)
			(xy 345.388302 -398.01451) (xy 345.35913 -398.054632) (xy 345.324039 -398.089695) (xy 345.283893 -398.118835)
			(xy 345.239682 -398.141334) (xy 345.192494 -398.156637) (xy 345.143494 -398.164367) (xy 345.11869 -398.164812)
			(xy 345.093295 -398.16432) (xy 345.043161 -398.156188) (xy 344.994976 -398.140135) (xy 344.949981 -398.116576)
			(xy 344.909339 -398.086117) (xy 344.874096 -398.049545) (xy 344.845163 -398.007803) (xy 344.823285 -397.961967)
			(xy 344.815668 -397.937736) (xy 344.814144 -397.931894) (xy 344.493596 -397.377412) (xy 344.489532 -397.373094)
			(xy 344.473425 -397.355427) (xy 344.446178 -397.316147) (xy 344.425168 -397.273206) (xy 344.410877 -397.227587)
			(xy 344.40363 -397.180334) (xy 344.403172 -397.156432) (xy 344.403314 -397.14438) (xy 344.40522 -397.12035)
			(xy 344.406982 -397.108426) (xy 344.408252 -397.099536) (xy 344.405204 -397.082518) (xy 344.36304 -397.011652)
			(xy 344.349832 -397.000476) (xy 344.34145 -396.997428) (xy 344.319698 -396.989044) (xy 344.27884 -396.9666)
			(xy 344.24187 -396.938205) (xy 344.209648 -396.904518) (xy 344.182924 -396.866322) (xy 344.162318 -396.824507)
			(xy 344.148311 -396.780045) (xy 344.141228 -396.73397) (xy 344.14079 -396.710662) (xy 344.141319 -396.685267)
			(xy 344.149728 -396.635179) (xy 344.166307 -396.587171) (xy 344.190601 -396.542568) (xy 344.221938 -396.502599)
			(xy 344.240358 -396.48511) (xy 344.24874 -396.47749) (xy 344.257376 -396.457424) (xy 344.254582 -396.35811)
			(xy 344.245184 -396.338552) (xy 344.236294 -396.33144) (xy 344.217765 -396.315602) (xy 344.185042 -396.27948)
			(xy 344.15797 -396.238949) (xy 344.137134 -396.194886) (xy 344.122984 -396.148245) (xy 344.115828 -396.100032)
			(xy 344.11539 -396.075662) (xy 344.115797 -396.051544) (xy 344.122805 -396.00382) (xy 344.136667 -395.957619)
			(xy 344.157089 -395.91392) (xy 344.17 -395.893544) (xy 344.175842 -395.884654) (xy 344.179398 -395.864588)
			(xy 344.158316 -395.772386) (xy 344.146124 -395.755622) (xy 344.137234 -395.750288) (xy 344.116436 -395.737428)
			(xy 344.078533 -395.706538) (xy 344.045591 -395.670403) (xy 344.01833 -395.62981) (xy 343.997344 -395.585646)
			(xy 343.983091 -395.538873) (xy 343.975881 -395.49051) (xy 343.975436 -395.466062) (xy 343.976003 -395.438778)
			(xy 343.984952 -395.38495) (xy 344.002618 -395.333322) (xy 344.02852 -395.285295) (xy 344.061956 -395.242172)
			(xy 344.081608 -395.223238) (xy 344.088996 -395.215705) (xy 344.097528 -395.196434) (xy 344.098118 -395.1859)
			(xy 344.098118 -395.111224) (xy 344.097584 -395.100675) (xy 344.089052 -395.08138) (xy 344.081608 -395.073886)
			(xy 344.061969 -395.05494) (xy 344.028537 -395.011816) (xy 344.002634 -394.963792) (xy 343.984962 -394.912168)
			(xy 343.975999 -394.858344) (xy 343.975436 -394.831062) (xy 343.97569 -394.81887) (xy 343.975944 -394.809218)
			(xy 343.969848 -394.791184) (xy 343.911174 -394.723874) (xy 343.89441 -394.715238) (xy 343.884504 -394.714222)
			(xy 343.857602 -394.710816) (xy 343.805317 -394.696458) (xy 343.756073 -394.673766) (xy 343.71119 -394.643346)
			(xy 343.671869 -394.606014) (xy 343.639163 -394.562768) (xy 343.613949 -394.514767) (xy 343.5969 -394.463296)
			(xy 343.59215 -394.4366) (xy 343.590626 -394.427202) (xy 343.31783 -393.95527) (xy 343.310464 -393.949428)
			(xy 343.29171 -393.9336) (xy 343.258592 -393.897388) (xy 343.23118 -393.856684) (xy 343.210076 -393.812382)
			(xy 343.19574 -393.76545) (xy 343.188486 -393.716916) (xy 343.188036 -393.69238) (xy 342.671242 -393.69238)
			(xy 342.919812 -394.122402) (xy 342.927178 -394.128244) (xy 342.945955 -394.144047) (xy 342.979073 -394.180263)
			(xy 343.006484 -394.220971) (xy 343.027585 -394.265279) (xy 343.041915 -394.312216) (xy 343.04916 -394.360754)
			(xy 343.049606 -394.385292) (xy 343.049352 -394.397484) (xy 343.049098 -394.407136) (xy 343.055194 -394.42517)
			(xy 343.113868 -394.49248) (xy 343.130632 -394.501116) (xy 343.140284 -394.502132) (xy 343.167044 -394.505504)
			(xy 343.219067 -394.519724) (xy 343.268093 -394.542197) (xy 343.312822 -394.572327) (xy 343.35207 -394.609316)
			(xy 343.384796 -394.652183) (xy 343.410133 -394.699792) (xy 343.427409 -394.750881) (xy 343.436166 -394.804097)
			(xy 343.436702 -394.831062) (xy 343.43617 -394.858347) (xy 343.427215 -394.912178) (xy 343.409543 -394.963807)
			(xy 343.383632 -395.011834) (xy 343.350186 -395.054954) (xy 343.33053 -395.073886) (xy 343.323137 -395.081415)
			(xy 343.314607 -395.100689) (xy 343.31402 -395.111224) (xy 343.31402 -395.1859) (xy 343.31453 -395.196452)
			(xy 343.323078 -395.215748) (xy 343.33053 -395.223238) (xy 343.350169 -395.242185) (xy 343.383603 -395.285307)
			(xy 343.409508 -395.333331) (xy 343.42718 -395.384955) (xy 343.436141 -395.438779) (xy 343.436702 -395.466062)
			(xy 343.43626 -395.490179) (xy 343.429263 -395.537901) (xy 343.415411 -395.584102) (xy 343.394998 -395.627803)
			(xy 343.382092 -395.64818) (xy 343.37625 -395.65707) (xy 343.372694 -395.677136) (xy 343.393776 -395.769338)
			(xy 343.405968 -395.786102) (xy 343.414858 -395.791436) (xy 343.435664 -395.804282) (xy 343.473569 -395.835174)
			(xy 343.50651 -395.871312) (xy 343.53377 -395.911906) (xy 343.554755 -395.956073) (xy 343.569006 -396.002849)
			(xy 343.576213 -396.051213) (xy 343.576656 -396.075662) (xy 343.576251 -396.100036) (xy 343.569104 -396.148257)
			(xy 343.55496 -396.194907) (xy 343.534123 -396.238978) (xy 343.507047 -396.279514) (xy 343.474315 -396.315639)
			(xy 343.455752 -396.33144) (xy 343.446862 -396.338552) (xy 343.437464 -396.35811) (xy 343.43467 -396.457424)
			(xy 343.443306 -396.47749) (xy 343.451688 -396.48511) (xy 343.470143 -396.502566) (xy 343.501488 -396.542539)
			(xy 343.525783 -396.587149) (xy 343.542358 -396.635166) (xy 343.550757 -396.685263) (xy 343.551256 -396.710662)
			(xy 343.551187 -396.720021) (xy 343.550044 -396.738703) (xy 343.54897 -396.748) (xy 343.547954 -396.75689)
			(xy 343.551764 -396.773654) (xy 343.595706 -396.843504) (xy 343.609422 -396.853918) (xy 343.617804 -396.856712)
			(xy 343.641825 -396.865199) (xy 343.686998 -396.888747) (xy 343.727805 -396.919242) (xy 343.763185 -396.955893)
			(xy 343.792222 -396.99775) (xy 343.814162 -397.043725) (xy 343.821766 -397.06804) (xy 343.82329 -397.073882)
			(xy 344.143584 -397.627602) (xy 344.147648 -397.63192) (xy 344.163848 -397.649631) (xy 344.191271 -397.689022)
			(xy 344.212413 -397.732111) (xy 344.226788 -397.777904) (xy 344.234064 -397.825346) (xy 344.234516 -397.849344)
			(xy 344.234047 -397.874147) (xy 344.226277 -397.923141) (xy 344.210937 -397.970316) (xy 344.188403 -398.014509)
			(xy 344.159231 -398.054631) (xy 344.12414 -398.089694) (xy 344.083995 -398.118834) (xy 344.039784 -398.141332)
			(xy 343.992598 -398.156636) (xy 343.943597 -398.164366) (xy 343.918794 -398.164812) (xy 343.893399 -398.164317)
			(xy 343.843266 -398.156185) (xy 343.79508 -398.140133) (xy 343.750086 -398.116574) (xy 343.709443 -398.086116)
			(xy 343.6742 -398.049544) (xy 343.645267 -398.007802) (xy 343.623389 -397.961967) (xy 343.615772 -397.937736)
			(xy 343.614248 -397.931894) (xy 343.293954 -397.378174) (xy 343.28989 -397.373856) (xy 343.273737 -397.356117)
			(xy 343.246366 -397.316717) (xy 343.225274 -397.273628) (xy 343.210945 -397.227844) (xy 343.20371 -397.180419)
			(xy 343.203276 -397.156432) (xy 343.203356 -397.144384) (xy 343.205139 -397.120355) (xy 343.206832 -397.108426)
			(xy 343.208102 -397.099536) (xy 343.205054 -397.082518) (xy 343.16289 -397.011652) (xy 343.149682 -397.000476)
			(xy 343.1413 -396.997428) (xy 343.119559 -396.989016) (xy 343.078699 -396.966579) (xy 343.041728 -396.938189)
			(xy 343.009504 -396.904506) (xy 342.982777 -396.866315) (xy 342.96217 -396.824502) (xy 342.948162 -396.780042)
			(xy 342.941078 -396.733969) (xy 342.94064 -396.710662) (xy 342.941153 -396.685266) (xy 342.949563 -396.635176)
			(xy 342.966146 -396.587168) (xy 342.990443 -396.542565) (xy 343.021786 -396.502598) (xy 343.040208 -396.48511)
			(xy 343.04859 -396.47749) (xy 343.057226 -396.457424) (xy 343.054432 -396.35811) (xy 343.045034 -396.338552)
			(xy 343.036144 -396.33144) (xy 343.017605 -396.315614) (xy 342.984885 -396.279488) (xy 342.957815 -396.238954)
			(xy 342.936981 -396.194889) (xy 342.922833 -396.148246) (xy 342.915678 -396.100033) (xy 342.91524 -396.075662)
			(xy 342.915655 -396.051545) (xy 342.922662 -396.003821) (xy 342.936522 -395.95762) (xy 342.956941 -395.913921)
			(xy 342.96985 -395.893544) (xy 342.975692 -395.884654) (xy 342.979248 -395.864588) (xy 342.958166 -395.772386)
			(xy 342.945974 -395.755622) (xy 342.937084 -395.750288) (xy 342.916298 -395.73741) (xy 342.878392 -395.706525)
			(xy 342.845447 -395.670394) (xy 342.818184 -395.629804) (xy 342.797196 -395.585642) (xy 342.782942 -395.538871)
			(xy 342.775731 -395.49051) (xy 342.775286 -395.466062) (xy 342.775837 -395.438778) (xy 342.784788 -395.384948)
			(xy 342.802456 -395.333319) (xy 342.828362 -395.285292) (xy 342.861804 -395.242171) (xy 342.881458 -395.223238)
			(xy 342.888839 -395.215698) (xy 342.897376 -395.196432) (xy 342.897968 -395.1859) (xy 342.897968 -395.111224)
			(xy 342.897449 -395.100673) (xy 342.888908 -395.081377) (xy 342.881458 -395.073886) (xy 342.861828 -395.05493)
			(xy 342.828393 -395.01181) (xy 342.802487 -394.963788) (xy 342.784813 -394.912166) (xy 342.775849 -394.858344)
			(xy 342.775286 -394.831062) (xy 342.77554 -394.81887) (xy 342.775794 -394.809218) (xy 342.769698 -394.791184)
			(xy 342.711024 -394.723874) (xy 342.69426 -394.715238) (xy 342.684608 -394.714222) (xy 342.657707 -394.710812)
			(xy 342.605421 -394.696456) (xy 342.556178 -394.673764) (xy 342.511295 -394.643345) (xy 342.471973 -394.606013)
			(xy 342.439268 -394.562767) (xy 342.414053 -394.514767) (xy 342.397004 -394.463296) (xy 342.392254 -394.4366)
			(xy 342.39073 -394.427202) (xy 342.117934 -393.95527) (xy 342.110568 -393.949428) (xy 342.091815 -393.933599)
			(xy 342.058696 -393.897387) (xy 342.031285 -393.856684) (xy 342.01018 -393.812382) (xy 341.995844 -393.76545)
			(xy 341.98859 -393.716916) (xy 341.98814 -393.69238) (xy 341.471092 -393.69238) (xy 341.719662 -394.122402)
			(xy 341.727028 -394.128244) (xy 341.745815 -394.144035) (xy 341.778931 -394.180255) (xy 341.806339 -394.220966)
			(xy 341.827438 -394.265276) (xy 341.841767 -394.312214) (xy 341.849011 -394.360754) (xy 341.849456 -394.385292)
			(xy 341.849202 -394.397484) (xy 341.848948 -394.407136) (xy 341.855044 -394.42517) (xy 341.913718 -394.49248)
			(xy 341.930482 -394.501116) (xy 341.940388 -394.502132) (xy 341.967149 -394.505501) (xy 342.019171 -394.519722)
			(xy 342.068197 -394.542195) (xy 342.112927 -394.572326) (xy 342.152175 -394.609315) (xy 342.184901 -394.652182)
			(xy 342.210237 -394.699791) (xy 342.227513 -394.750881) (xy 342.23627 -394.804096) (xy 342.236806 -394.831062)
			(xy 342.23638 -394.855264) (xy 342.229306 -394.903149) (xy 342.21532 -394.949488) (xy 342.194721 -394.99329)
			(xy 342.181688 -395.013688) (xy 342.176901 -395.021645) (xy 342.172866 -395.039756) (xy 342.173814 -395.048994)
			(xy 342.178132 -395.079982) (xy 342.179804 -395.089281) (xy 342.189091 -395.105722) (xy 342.196166 -395.111986)
			(xy 342.218255 -395.130667) (xy 342.258026 -395.172679) (xy 342.292188 -395.219367) (xy 342.320196 -395.269987)
			(xy 342.341603 -395.323732) (xy 342.356068 -395.379746) (xy 342.363361 -395.437136) (xy 342.363806 -395.466062)
			(xy 342.363219 -395.499384) (xy 342.353556 -395.565322) (xy 342.334429 -395.629161) (xy 342.32088 -395.65961)
			(xy 342.316631 -395.670075) (xy 342.316745 -395.692634) (xy 342.32648 -395.712985) (xy 342.33485 -395.72057)
			(xy 342.35707 -395.739275) (xy 342.397137 -395.781324) (xy 342.431561 -395.828104) (xy 342.45979 -395.878864)
			(xy 342.48137 -395.932787) (xy 342.495954 -395.989008) (xy 342.503307 -396.046621) (xy 342.50376 -396.075662)
			(xy 342.50328 -396.104667) (xy 342.49597 -396.162214) (xy 342.481448 -396.218376) (xy 342.459948 -396.272254)
			(xy 342.431814 -396.322985) (xy 342.397497 -396.369755) (xy 342.357547 -396.411815) (xy 342.335358 -396.4305)
			(xy 342.328246 -396.436088) (xy 342.319102 -396.451328) (xy 342.303862 -396.534132) (xy 342.306656 -396.551404)
			(xy 342.311228 -396.559532) (xy 342.323802 -396.582719) (xy 342.341677 -396.63234) (xy 342.350778 -396.684291)
			(xy 342.35136 -396.710662) (xy 342.351291 -396.720021) (xy 342.350148 -396.738703) (xy 342.349074 -396.748)
			(xy 342.348058 -396.75689) (xy 342.351868 -396.773654) (xy 342.39581 -396.843504) (xy 342.409526 -396.853918)
			(xy 342.417908 -396.856712) (xy 342.44193 -396.865197) (xy 342.487103 -396.888745) (xy 342.527909 -396.919241)
			(xy 342.56329 -396.955893) (xy 342.592327 -396.99775) (xy 342.614266 -397.043725) (xy 342.62187 -397.06804)
			(xy 342.623394 -397.073882) (xy 342.943688 -397.627602) (xy 342.947752 -397.63192) (xy 342.963952 -397.649631)
			(xy 342.991375 -397.689022) (xy 343.012518 -397.732111) (xy 343.026892 -397.777904) (xy 343.034168 -397.825346)
			(xy 343.03462 -397.849344) (xy 343.034246 -397.874152) (xy 343.026474 -397.923155) (xy 343.011128 -397.970338)
			(xy 342.988585 -398.014537) (xy 342.959403 -398.054664) (xy 342.9243 -398.089728) (xy 342.884142 -398.118866)
			(xy 342.839918 -398.14136) (xy 342.792718 -398.156655) (xy 342.743706 -398.164374) (xy 342.718898 -398.164812)
			(xy 342.693504 -398.164313) (xy 342.64337 -398.156182) (xy 342.595184 -398.140131) (xy 342.55019 -398.116572)
			(xy 342.509547 -398.086114) (xy 342.474304 -398.049543) (xy 342.445371 -398.007802) (xy 342.423493 -397.961967)
			(xy 342.415876 -397.937736) (xy 342.414352 -397.931894) (xy 342.094058 -397.378174) (xy 342.089994 -397.373856)
			(xy 342.073841 -397.356116) (xy 342.046471 -397.316716) (xy 342.025378 -397.273628) (xy 342.011049 -397.227844)
			(xy 342.003814 -397.180419) (xy 342.00338 -397.156432) (xy 342.00346 -397.144384) (xy 342.005243 -397.120355)
			(xy 342.006936 -397.108426) (xy 342.008206 -397.099536) (xy 342.005158 -397.082518) (xy 341.962994 -397.011652)
			(xy 341.949786 -397.000476) (xy 341.941404 -396.997428) (xy 341.919664 -396.989014) (xy 341.878804 -396.966578)
			(xy 341.841832 -396.938188) (xy 341.809608 -396.904505) (xy 341.782882 -396.866314) (xy 341.762274 -396.824502)
			(xy 341.748266 -396.780042) (xy 341.741182 -396.733969) (xy 341.740744 -396.710662) (xy 341.741304 -396.684289)
			(xy 341.750388 -396.63233) (xy 341.76828 -396.58271) (xy 341.780876 -396.559532) (xy 341.785448 -396.551404)
			(xy 341.788242 -396.534132) (xy 341.773002 -396.451328) (xy 341.763858 -396.436088) (xy 341.756746 -396.4305)
			(xy 341.734564 -396.411807) (xy 341.69462 -396.369742) (xy 341.660305 -396.322971) (xy 341.632168 -396.272243)
			(xy 341.61066 -396.218369) (xy 341.596125 -396.16221) (xy 341.588794 -396.104666) (xy 341.588344 -396.075662)
			(xy 341.588944 -396.042341) (xy 341.598602 -395.976403) (xy 341.617724 -395.912563) (xy 341.63127 -395.882114)
			(xy 341.635512 -395.871646) (xy 341.635408 -395.849087) (xy 341.625673 -395.828736) (xy 341.6173 -395.821154)
			(xy 341.595033 -395.802503) (xy 341.554971 -395.760444) (xy 341.520552 -395.713653) (xy 341.49233 -395.662884)
			(xy 341.470758 -395.608953) (xy 341.456182 -395.552725) (xy 341.448838 -395.495105) (xy 341.44839 -395.466062)
			(xy 341.448828 -395.437135) (xy 341.456112 -395.379742) (xy 341.470572 -395.323724) (xy 341.491978 -395.269976)
			(xy 341.519987 -395.219355) (xy 341.554154 -395.172667) (xy 341.593933 -395.130659) (xy 341.61603 -395.111986)
			(xy 341.622997 -395.105634) (xy 341.632258 -395.089234) (xy 341.634064 -395.079982) (xy 341.638382 -395.048994)
			(xy 341.639281 -395.039757) (xy 341.635259 -395.021658) (xy 341.630508 -395.013688) (xy 341.617521 -394.993265)
			(xy 341.59694 -394.949463) (xy 341.582953 -394.903133) (xy 341.575857 -394.85526) (xy 341.57539 -394.831062)
			(xy 341.575644 -394.81887) (xy 341.575898 -394.809218) (xy 341.569802 -394.791184) (xy 341.511128 -394.723874)
			(xy 341.494364 -394.715238) (xy 341.484458 -394.714222) (xy 341.457551 -394.710852) (xy 341.405265 -394.696488)
			(xy 341.356022 -394.673789) (xy 341.311139 -394.643364) (xy 341.271819 -394.606026) (xy 341.239115 -394.562776)
			(xy 341.213901 -394.514771) (xy 341.196854 -394.463298) (xy 341.192104 -394.4366) (xy 341.19058 -394.427202)
			(xy 340.917784 -393.95527) (xy 340.910418 -393.949428) (xy 340.891675 -393.933587) (xy 340.858554 -393.897379)
			(xy 340.83114 -393.856679) (xy 340.810033 -393.812378) (xy 340.795695 -393.765448) (xy 340.788441 -393.716916)
			(xy 340.78799 -393.69238) (xy 340.271196 -393.69238) (xy 340.519766 -394.122402) (xy 340.527132 -394.128244)
			(xy 340.54592 -394.144034) (xy 340.579036 -394.180254) (xy 340.606443 -394.220965) (xy 340.627542 -394.265275)
			(xy 340.641871 -394.312214) (xy 340.649115 -394.360753) (xy 340.64956 -394.385292) (xy 340.649306 -394.397484)
			(xy 340.649052 -394.407136) (xy 340.655148 -394.42517) (xy 340.713822 -394.49248) (xy 340.730586 -394.501116)
			(xy 340.740238 -394.502132) (xy 340.767004 -394.50546) (xy 340.819028 -394.519689) (xy 340.868053 -394.542169)
			(xy 340.912782 -394.572305) (xy 340.952029 -394.609299) (xy 340.984754 -394.652171) (xy 341.010089 -394.699784)
			(xy 341.027364 -394.750877) (xy 341.036121 -394.804095) (xy 341.036656 -394.831062) (xy 341.036146 -394.857049)
			(xy 341.028016 -394.908384) (xy 341.011955 -394.957814) (xy 340.988359 -395.004124) (xy 340.957809 -395.046172)
			(xy 340.921058 -395.082923) (xy 340.87901 -395.113473) (xy 340.8327 -395.137069) (xy 340.78327 -395.15313)
			(xy 340.731935 -395.16126) (xy 340.679961 -395.16126) (xy 340.628626 -395.15313) (xy 340.579196 -395.137069)
			(xy 340.532886 -395.113473) (xy 340.490838 -395.082923) (xy 340.454087 -395.046172) (xy 340.423537 -395.004124)
			(xy 340.399941 -394.957814) (xy 340.38388 -394.908384) (xy 340.37575 -394.857049) (xy 340.37524 -394.831062)
			(xy 340.375494 -394.81887) (xy 340.375748 -394.809218) (xy 340.369652 -394.791184) (xy 340.310978 -394.723874)
			(xy 340.294214 -394.715238) (xy 340.284562 -394.714222) (xy 340.257655 -394.710849) (xy 340.20537 -394.696485)
			(xy 340.156126 -394.673787) (xy 340.111244 -394.643362) (xy 340.071924 -394.606025) (xy 340.039219 -394.562775)
			(xy 340.014005 -394.514771) (xy 339.996958 -394.463298) (xy 339.992208 -394.4366) (xy 339.990684 -394.427202)
			(xy 339.717888 -393.95527) (xy 339.710522 -393.949428) (xy 339.69178 -393.933586) (xy 339.658659 -393.897378)
			(xy 339.631244 -393.856678) (xy 339.610137 -393.812378) (xy 339.595799 -393.765448) (xy 339.588545 -393.716916)
			(xy 339.588094 -393.69238) (xy 339.071296 -393.69238) (xy 339.320124 -394.12291) (xy 339.327236 -394.128752)
			(xy 339.345961 -394.14454) (xy 339.379015 -394.18068) (xy 339.406372 -394.221305) (xy 339.427432 -394.265522)
			(xy 339.441734 -394.312364) (xy 339.448965 -394.360804) (xy 339.44941 -394.385292) (xy 339.449156 -394.397484)
			(xy 339.448902 -394.407136) (xy 339.454998 -394.42517) (xy 339.513672 -394.49248) (xy 339.530436 -394.501116)
			(xy 339.540342 -394.502132) (xy 339.567109 -394.505457) (xy 339.619132 -394.519686) (xy 339.668158 -394.542167)
			(xy 339.712887 -394.572304) (xy 339.752133 -394.609298) (xy 339.784858 -394.65217) (xy 339.810193 -394.699783)
			(xy 339.827468 -394.750876) (xy 339.836225 -394.804095) (xy 339.83676 -394.831062) (xy 339.83621 -394.858346)
			(xy 339.827257 -394.912175) (xy 339.809587 -394.963804) (xy 339.783681 -395.011831) (xy 339.750241 -395.054952)
			(xy 339.730588 -395.073886) (xy 339.723189 -395.081409) (xy 339.714663 -395.100688) (xy 339.714078 -395.111224)
			(xy 339.714078 -395.1859) (xy 339.7146 -395.19645) (xy 339.723141 -395.215745) (xy 339.730588 -395.223238)
			(xy 339.750238 -395.242174) (xy 339.783668 -395.2853) (xy 339.80957 -395.333327) (xy 339.827239 -395.384953)
			(xy 339.836199 -395.438779) (xy 339.83676 -395.466062) (xy 339.836308 -395.490178) (xy 339.829312 -395.5379)
			(xy 339.815463 -395.584101) (xy 339.795054 -395.627802) (xy 339.78215 -395.64818) (xy 339.776308 -395.65707)
			(xy 339.772752 -395.677136) (xy 339.793834 -395.769338) (xy 339.806026 -395.786102) (xy 339.814916 -395.791436)
			(xy 339.835713 -395.804298) (xy 339.873619 -395.835185) (xy 339.906563 -395.871319) (xy 339.933825 -395.911911)
			(xy 339.954811 -395.956076) (xy 339.969063 -396.00285) (xy 339.976271 -396.051213) (xy 339.976714 -396.075662)
			(xy 339.976288 -396.100035) (xy 339.969142 -396.148254) (xy 339.955001 -396.194903) (xy 339.934168 -396.238973)
			(xy 339.907096 -396.27951) (xy 339.874371 -396.315637) (xy 339.85581 -396.33144) (xy 339.84692 -396.338552)
			(xy 339.837522 -396.35811) (xy 339.834728 -396.457424) (xy 339.843364 -396.47749) (xy 339.851746 -396.48511)
			(xy 339.870193 -396.502574) (xy 339.901541 -396.542544) (xy 339.925838 -396.587152) (xy 339.942415 -396.635167)
			(xy 339.950815 -396.685264) (xy 339.951314 -396.710662) (xy 340.540594 -396.710662) (xy 340.541116 -396.685407)
			(xy 340.549429 -396.635585) (xy 340.56583 -396.587811) (xy 340.589871 -396.543388) (xy 340.620895 -396.503528)
			(xy 340.658057 -396.469318) (xy 340.700343 -396.441692) (xy 340.746599 -396.421402) (xy 340.795564 -396.409002)
			(xy 340.845902 -396.404831) (xy 340.89624 -396.409002) (xy 340.945205 -396.421402) (xy 340.991461 -396.441692)
			(xy 341.033747 -396.469318) (xy 341.070909 -396.503528) (xy 341.101933 -396.543388) (xy 341.125974 -396.587811)
			(xy 341.142375 -396.635585) (xy 341.150688 -396.685407) (xy 341.15121 -396.710662) (xy 341.151141 -396.720021)
			(xy 341.149998 -396.738703) (xy 341.148924 -396.748) (xy 341.147908 -396.75689) (xy 341.151718 -396.773654)
			(xy 341.19566 -396.843504) (xy 341.209376 -396.853918) (xy 341.217758 -396.856712) (xy 341.24179 -396.86517)
			(xy 341.286962 -396.888725) (xy 341.327766 -396.919227) (xy 341.363145 -396.955884) (xy 341.392179 -396.997745)
			(xy 341.414117 -397.043724) (xy 341.42172 -397.06804) (xy 341.423244 -397.073882) (xy 341.743538 -397.627602)
			(xy 341.747602 -397.63192) (xy 341.76379 -397.649629) (xy 341.791156 -397.689037) (xy 341.812242 -397.732133)
			(xy 341.826562 -397.777924) (xy 341.833787 -397.825355) (xy 341.834216 -397.849344) (xy 341.833723 -397.874132)
			(xy 341.825962 -397.923098) (xy 341.810638 -397.970247) (xy 341.788128 -398.01442) (xy 341.758987 -398.054528)
			(xy 341.723931 -398.089584) (xy 341.683823 -398.118726) (xy 341.639651 -398.141236) (xy 341.592502 -398.156561)
			(xy 341.543536 -398.164322) (xy 341.518748 -398.164812) (xy 341.493355 -398.164269) (xy 341.443223 -398.156146)
			(xy 341.395039 -398.140102) (xy 341.350045 -398.11655) (xy 341.309401 -398.086098) (xy 341.274158 -398.049532)
			(xy 341.245223 -398.007796) (xy 341.223343 -397.961965) (xy 341.215726 -397.937736) (xy 341.214202 -397.931894)
			(xy 340.893908 -397.378174) (xy 340.889844 -397.373856) (xy 340.873631 -397.356156) (xy 340.846211 -397.316762)
			(xy 340.82507 -397.27367) (xy 340.810699 -397.227875) (xy 340.803426 -397.180431) (xy 340.802976 -397.156432)
			(xy 340.803118 -397.14438) (xy 340.805024 -397.12035) (xy 340.806786 -397.108426) (xy 340.808056 -397.099536)
			(xy 340.805008 -397.082518) (xy 340.762844 -397.011652) (xy 340.749636 -397.000476) (xy 340.741254 -396.997428)
			(xy 340.719503 -396.989042) (xy 340.678645 -396.966599) (xy 340.641675 -396.938203) (xy 340.609453 -396.904517)
			(xy 340.582728 -396.866322) (xy 340.562122 -396.824507) (xy 340.548115 -396.780045) (xy 340.541032 -396.73397)
			(xy 340.540594 -396.710662) (xy 339.951314 -396.710662) (xy 339.951245 -396.720021) (xy 339.950102 -396.738703)
			(xy 339.949028 -396.748) (xy 339.948012 -396.75689) (xy 339.951822 -396.773654) (xy 339.995764 -396.843504)
			(xy 340.00948 -396.853918) (xy 340.017862 -396.856712) (xy 340.041895 -396.865168) (xy 340.087066 -396.888724)
			(xy 340.127871 -396.919226) (xy 340.163249 -396.955883) (xy 340.192284 -396.997744) (xy 340.214221 -397.043724)
			(xy 340.221824 -397.06804) (xy 340.223348 -397.073882) (xy 340.543642 -397.627602) (xy 340.547706 -397.63192)
			(xy 340.563895 -397.649628) (xy 340.59126 -397.689037) (xy 340.612346 -397.732133) (xy 340.626667 -397.777924)
			(xy 340.633891 -397.825355) (xy 340.63432 -397.849344) (xy 340.633947 -397.874139) (xy 340.626183 -397.923118)
			(xy 340.610852 -397.970279) (xy 340.588332 -398.014461) (xy 340.559177 -398.054577) (xy 340.524107 -398.089637)
			(xy 340.483983 -398.11878) (xy 340.439794 -398.141287) (xy 340.392628 -398.156604) (xy 340.343647 -398.164355)
			(xy 340.318852 -398.164812) (xy 340.293456 -398.164354) (xy 340.243321 -398.156216) (xy 340.195134 -398.140157)
			(xy 340.15014 -398.116593) (xy 340.109497 -398.086129) (xy 340.074256 -398.049553) (xy 340.045323 -398.007807)
			(xy 340.023446 -397.961968) (xy 340.01583 -397.937736) (xy 340.014306 -397.931894) (xy 339.694012 -397.378174)
			(xy 339.689948 -397.373856) (xy 339.673736 -397.356155) (xy 339.646315 -397.316761) (xy 339.625175 -397.27367)
			(xy 339.610803 -397.227874) (xy 339.60353 -397.180431) (xy 339.60308 -397.156432) (xy 339.603222 -397.14438)
			(xy 339.605128 -397.12035) (xy 339.60689 -397.108426) (xy 339.60816 -397.099536) (xy 339.605112 -397.082518)
			(xy 339.562948 -397.011652) (xy 339.54974 -397.000476) (xy 339.541358 -396.997428) (xy 339.519608 -396.989039)
			(xy 339.478749 -396.966597) (xy 339.441779 -396.938202) (xy 339.409557 -396.904516) (xy 339.382832 -396.866321)
			(xy 339.362227 -396.824507) (xy 339.348219 -396.780045) (xy 339.341136 -396.73397) (xy 339.340698 -396.710662)
			(xy 339.341224 -396.685267) (xy 339.349634 -396.635178) (xy 339.366214 -396.587171) (xy 339.390508 -396.542568)
			(xy 339.421846 -396.502599) (xy 339.440266 -396.48511) (xy 339.448648 -396.47749) (xy 339.457284 -396.457424)
			(xy 339.45449 -396.35811) (xy 339.445092 -396.338552) (xy 339.436202 -396.33144) (xy 339.417675 -396.315601)
			(xy 339.384951 -396.279479) (xy 339.357878 -396.238948) (xy 339.337042 -396.194886) (xy 339.322892 -396.148244)
			(xy 339.315736 -396.100032) (xy 339.315298 -396.075662) (xy 339.315704 -396.051544) (xy 339.322712 -396.00382)
			(xy 339.336574 -395.957619) (xy 339.356997 -395.91392) (xy 339.369908 -395.893544) (xy 339.37575 -395.884654)
			(xy 339.379306 -395.864588) (xy 339.358224 -395.772386) (xy 339.346032 -395.755622) (xy 339.337142 -395.750288)
			(xy 339.316346 -395.737425) (xy 339.278442 -395.706536) (xy 339.2455 -395.670401) (xy 339.218239 -395.629809)
			(xy 339.197252 -395.585645) (xy 339.182999 -395.538872) (xy 339.175789 -395.49051) (xy 339.175344 -395.466062)
			(xy 339.175909 -395.438778) (xy 339.184858 -395.38495) (xy 339.202524 -395.333322) (xy 339.228427 -395.285294)
			(xy 339.261864 -395.242172) (xy 339.281516 -395.223238) (xy 339.288905 -395.215706) (xy 339.297436 -395.196434)
			(xy 339.298026 -395.1859) (xy 339.298026 -395.111224) (xy 339.29749 -395.100675) (xy 339.288959 -395.08138)
			(xy 339.281516 -395.073886) (xy 339.261879 -395.054938) (xy 339.228446 -395.011815) (xy 339.202543 -394.963791)
			(xy 339.18487 -394.912168) (xy 339.175907 -394.858344) (xy 339.175344 -394.831062) (xy 339.175598 -394.81887)
			(xy 339.175852 -394.809218) (xy 339.169756 -394.791184) (xy 339.111082 -394.723874) (xy 339.094318 -394.715238)
			(xy 339.084412 -394.714222) (xy 339.057453 -394.710897) (xy 339.005069 -394.69654) (xy 338.955736 -394.673814)
			(xy 338.910782 -394.64333) (xy 338.871415 -394.605908) (xy 338.838694 -394.562554) (xy 338.8135 -394.514435)
			(xy 338.796511 -394.462845) (xy 338.791804 -394.436092) (xy 338.790534 -394.426694) (xy 338.517992 -393.95527)
			(xy 338.510626 -393.949428) (xy 338.491864 -393.933609) (xy 338.458748 -393.897394) (xy 338.431339 -393.856688)
			(xy 338.410236 -393.812384) (xy 338.395901 -393.765451) (xy 338.388648 -393.716917) (xy 338.388198 -393.69238)
			(xy 337.87115 -393.69238) (xy 338.11972 -394.122402) (xy 338.127086 -394.128244) (xy 338.145864 -394.144045)
			(xy 338.178983 -394.180262) (xy 338.206392 -394.22097) (xy 338.227493 -394.265278) (xy 338.241823 -394.312216)
			(xy 338.249068 -394.360754) (xy 338.249514 -394.385292) (xy 338.24926 -394.397484) (xy 338.249006 -394.407136)
			(xy 338.255102 -394.42517) (xy 338.313776 -394.49248) (xy 338.33054 -394.501116) (xy 338.340446 -394.502132)
			(xy 338.367213 -394.505454) (xy 338.419237 -394.519683) (xy 338.468262 -394.542165) (xy 338.512991 -394.572302)
			(xy 338.552238 -394.609297) (xy 338.584962 -394.652169) (xy 338.610297 -394.699783) (xy 338.627572 -394.750876)
			(xy 338.636329 -394.804095) (xy 338.636864 -394.831062) (xy 338.636313 -394.858346) (xy 338.62736 -394.912175)
			(xy 338.60969 -394.963803) (xy 338.583785 -395.01183) (xy 338.550345 -395.054952) (xy 338.530692 -395.073886)
			(xy 338.523294 -395.08141) (xy 338.514768 -395.100688) (xy 338.514182 -395.111224) (xy 338.514182 -395.1859)
			(xy 338.514703 -395.196451) (xy 338.523244 -395.215745) (xy 338.530692 -395.223238) (xy 338.550342 -395.242173)
			(xy 338.583773 -395.2853) (xy 338.609674 -395.333327) (xy 338.627344 -395.384953) (xy 338.636303 -395.438779)
			(xy 338.636864 -395.466062) (xy 338.636412 -395.490178) (xy 338.629416 -395.5379) (xy 338.615567 -395.584101)
			(xy 338.595158 -395.627802) (xy 338.582254 -395.64818) (xy 338.576412 -395.65707) (xy 338.572856 -395.677136)
			(xy 338.593938 -395.769338) (xy 338.60613 -395.786102) (xy 338.61502 -395.791436) (xy 338.635818 -395.804296)
			(xy 338.673724 -395.835184) (xy 338.706667 -395.871319) (xy 338.733929 -395.911911) (xy 338.754915 -395.956076)
			(xy 338.769167 -396.00285) (xy 338.776375 -396.051213) (xy 338.776818 -396.075662) (xy 338.77639 -396.100035)
			(xy 338.769245 -396.148254) (xy 338.755103 -396.194903) (xy 338.734271 -396.238973) (xy 338.7072 -396.27951)
			(xy 338.674474 -396.315637) (xy 338.655914 -396.33144) (xy 338.647024 -396.338552) (xy 338.637626 -396.35811)
			(xy 338.634832 -396.457424) (xy 338.643468 -396.47749) (xy 338.65185 -396.48511) (xy 338.670298 -396.502573)
			(xy 338.701645 -396.542543) (xy 338.725942 -396.587152) (xy 338.742519 -396.635167) (xy 338.750919 -396.685264)
			(xy 338.751418 -396.710662) (xy 338.751349 -396.720021) (xy 338.750206 -396.738703) (xy 338.749132 -396.748)
			(xy 338.748116 -396.75689) (xy 338.751926 -396.773654) (xy 338.795868 -396.843504) (xy 338.809584 -396.853918)
			(xy 338.817966 -396.856712) (xy 338.842057 -396.86521) (xy 338.887349 -396.888831) (xy 338.928245 -396.919438)
			(xy 338.963678 -396.956232) (xy 338.992722 -396.998252) (xy 339.014619 -397.044402) (xy 339.022182 -397.068802)
			(xy 339.023706 -397.074644) (xy 339.343492 -397.627602) (xy 339.347556 -397.63192) (xy 339.363757 -397.64963)
			(xy 339.39118 -397.689021) (xy 339.412322 -397.732111) (xy 339.426697 -397.777904) (xy 339.433972 -397.825346)
			(xy 339.434424 -397.849344) (xy 339.434046 -397.874152) (xy 339.426274 -397.923155) (xy 339.410928 -397.970337)
			(xy 339.388386 -398.014536) (xy 339.359204 -398.054662) (xy 339.324102 -398.089727) (xy 339.283944 -398.118865)
			(xy 339.239721 -398.141359) (xy 339.192521 -398.156654) (xy 339.14351 -398.164373) (xy 339.118702 -398.164812)
			(xy 339.093308 -398.16431) (xy 339.043174 -398.156179) (xy 338.994989 -398.140128) (xy 338.949994 -398.11657)
			(xy 338.909351 -398.086113) (xy 338.874109 -398.049542) (xy 338.845175 -398.007801) (xy 338.823297 -397.961966)
			(xy 338.81568 -397.937736) (xy 338.814156 -397.931894) (xy 338.493608 -397.377412) (xy 338.489544 -397.373094)
			(xy 338.473439 -397.355426) (xy 338.446191 -397.316146) (xy 338.425181 -397.273206) (xy 338.410889 -397.227587)
			(xy 338.403642 -397.180334) (xy 338.403184 -397.156432) (xy 338.403326 -397.14438) (xy 338.405232 -397.12035)
			(xy 338.406994 -397.108426) (xy 338.408264 -397.099536) (xy 338.405216 -397.082518) (xy 338.363052 -397.011652)
			(xy 338.349844 -397.000476) (xy 338.341462 -396.997428) (xy 338.319713 -396.989037) (xy 338.278854 -396.966595)
			(xy 338.241884 -396.938201) (xy 338.209662 -396.904515) (xy 338.182937 -396.86632) (xy 338.162331 -396.824506)
			(xy 338.148323 -396.780045) (xy 338.14124 -396.73397) (xy 338.140802 -396.710662) (xy 338.141327 -396.685267)
			(xy 338.149736 -396.635178) (xy 338.166317 -396.58717) (xy 338.190611 -396.542568) (xy 338.22195 -396.502599)
			(xy 338.24037 -396.48511) (xy 338.248752 -396.47749) (xy 338.257388 -396.457424) (xy 338.254594 -396.35811)
			(xy 338.245196 -396.338552) (xy 338.236306 -396.33144) (xy 338.217759 -396.315623) (xy 338.185041 -396.279494)
			(xy 338.157973 -396.238958) (xy 338.137141 -396.194892) (xy 338.122995 -396.148247) (xy 338.115839 -396.100033)
			(xy 338.115402 -396.075662) (xy 338.115807 -396.051544) (xy 338.122816 -396.00382) (xy 338.136678 -395.957619)
			(xy 338.157101 -395.91392) (xy 338.170012 -395.893544) (xy 338.175854 -395.884654) (xy 338.17941 -395.864588)
			(xy 338.158328 -395.772386) (xy 338.146136 -395.755622) (xy 338.137246 -395.750288) (xy 338.116451 -395.737424)
			(xy 338.078547 -395.706535) (xy 338.045605 -395.670401) (xy 338.018343 -395.629809) (xy 337.997357 -395.585645)
			(xy 337.983103 -395.538872) (xy 337.975893 -395.49051) (xy 337.975448 -395.466062) (xy 337.976011 -395.438778)
			(xy 337.984961 -395.38495) (xy 338.002627 -395.333321) (xy 338.02853 -395.285294) (xy 338.061968 -395.242172)
			(xy 338.08162 -395.223238) (xy 338.08901 -395.215707) (xy 338.09754 -395.196434) (xy 338.09813 -395.1859)
			(xy 338.09813 -395.111224) (xy 338.097593 -395.100675) (xy 338.089062 -395.081381) (xy 338.08162 -395.073886)
			(xy 338.061983 -395.054937) (xy 338.028551 -395.011815) (xy 338.002647 -394.963791) (xy 337.984974 -394.912168)
			(xy 337.976011 -394.858344) (xy 337.975448 -394.831062) (xy 337.975702 -394.81887) (xy 337.975956 -394.809218)
			(xy 337.96986 -394.791184) (xy 337.911186 -394.723874) (xy 337.894422 -394.715238) (xy 337.884516 -394.714222)
			(xy 337.857615 -394.710806) (xy 337.80533 -394.696451) (xy 337.756087 -394.67376) (xy 337.711203 -394.643342)
			(xy 337.671882 -394.60601) (xy 337.639176 -394.562766) (xy 337.613961 -394.514766) (xy 337.596912 -394.463296)
			(xy 337.592162 -394.4366) (xy 337.590638 -394.427202) (xy 337.317842 -393.95527) (xy 337.310476 -393.949428)
			(xy 337.291724 -393.933597) (xy 337.258606 -393.897386) (xy 337.231194 -393.856683) (xy 337.210088 -393.812381)
			(xy 337.195752 -393.76545) (xy 337.188498 -393.716916) (xy 337.188048 -393.69238) (xy 336.671254 -393.69238)
			(xy 336.919824 -394.122402) (xy 336.92719 -394.128244) (xy 336.945969 -394.144044) (xy 336.979087 -394.180261)
			(xy 337.006497 -394.22097) (xy 337.027598 -394.265278) (xy 337.041927 -394.312215) (xy 337.049172 -394.360754)
			(xy 337.049618 -394.385292) (xy 337.049364 -394.397484) (xy 337.04911 -394.407136) (xy 337.055206 -394.42517)
			(xy 337.11388 -394.49248) (xy 337.130644 -394.501116) (xy 337.140296 -394.502132) (xy 337.167057 -394.505495)
			(xy 337.21908 -394.519717) (xy 337.268106 -394.542191) (xy 337.312836 -394.572322) (xy 337.352083 -394.609312)
			(xy 337.384809 -394.65218) (xy 337.410146 -394.69979) (xy 337.427421 -394.75088) (xy 337.436178 -394.804096)
			(xy 337.436714 -394.831062) (xy 337.436178 -394.858347) (xy 337.427224 -394.912177) (xy 337.409552 -394.963807)
			(xy 337.383642 -395.011833) (xy 337.350198 -395.054954) (xy 337.330542 -395.073886) (xy 337.323151 -395.081417)
			(xy 337.314619 -395.10069) (xy 337.314032 -395.111224) (xy 337.314032 -395.1859) (xy 337.314538 -395.196453)
			(xy 337.323088 -395.215748) (xy 337.330542 -395.223238) (xy 337.350183 -395.242182) (xy 337.383617 -395.285305)
			(xy 337.409521 -395.33333) (xy 337.427192 -395.384955) (xy 337.436153 -395.438779) (xy 337.436714 -395.466062)
			(xy 337.43627 -395.490178) (xy 337.429273 -395.537901) (xy 337.415422 -395.584102) (xy 337.39501 -395.627803)
			(xy 337.382104 -395.64818) (xy 337.376262 -395.65707) (xy 337.372706 -395.677136) (xy 337.393788 -395.769338)
			(xy 337.40598 -395.786102) (xy 337.41487 -395.791436) (xy 337.435679 -395.804278) (xy 337.473583 -395.835171)
			(xy 337.506524 -395.871309) (xy 337.533783 -395.911905) (xy 337.554767 -395.956072) (xy 337.569018 -396.002848)
			(xy 337.576225 -396.051213) (xy 337.576668 -396.075662) (xy 337.576259 -396.100036) (xy 337.569112 -396.148256)
			(xy 337.554968 -396.194907) (xy 337.534133 -396.238977) (xy 337.507057 -396.279513) (xy 337.474327 -396.315639)
			(xy 337.455764 -396.33144) (xy 337.446874 -396.338552) (xy 337.437476 -396.35811) (xy 337.434682 -396.457424)
			(xy 337.443318 -396.47749) (xy 337.4517 -396.48511) (xy 337.470139 -396.502583) (xy 337.501489 -396.542549)
			(xy 337.525789 -396.587155) (xy 337.542368 -396.635168) (xy 337.550768 -396.685264) (xy 337.551268 -396.710662)
			(xy 337.551199 -396.720021) (xy 337.550056 -396.738703) (xy 337.548982 -396.748) (xy 337.547966 -396.75689)
			(xy 337.551776 -396.773654) (xy 337.595718 -396.843504) (xy 337.609434 -396.853918) (xy 337.617816 -396.856712)
			(xy 337.64184 -396.865193) (xy 337.687012 -396.888742) (xy 337.727818 -396.919239) (xy 337.763198 -396.955891)
			(xy 337.792235 -396.997749) (xy 337.814174 -397.043725) (xy 337.821778 -397.06804) (xy 337.823302 -397.073882)
			(xy 338.143596 -397.627602) (xy 338.14766 -397.63192) (xy 338.163862 -397.64963) (xy 338.191284 -397.689021)
			(xy 338.212426 -397.73211) (xy 338.226801 -397.777904) (xy 338.234076 -397.825346) (xy 338.234528 -397.849344)
			(xy 338.234146 -397.874151) (xy 338.226374 -397.923154) (xy 338.211028 -397.970336) (xy 338.188487 -398.014535)
			(xy 338.159306 -398.054661) (xy 338.124204 -398.089725) (xy 338.084046 -398.118864) (xy 338.039823 -398.141358)
			(xy 337.992625 -398.156653) (xy 337.943614 -398.164373) (xy 337.918806 -398.164812) (xy 337.893412 -398.164306)
			(xy 337.843278 -398.156177) (xy 337.795093 -398.140126) (xy 337.750099 -398.116568) (xy 337.709456 -398.086112)
			(xy 337.674213 -398.049541) (xy 337.645279 -398.007801) (xy 337.623401 -397.961966) (xy 337.615784 -397.937736)
			(xy 337.61426 -397.931894) (xy 337.293966 -397.378174) (xy 337.289902 -397.373856) (xy 337.273751 -397.356115)
			(xy 337.24638 -397.316716) (xy 337.225287 -397.273628) (xy 337.210957 -397.227844) (xy 337.203722 -397.180419)
			(xy 337.203288 -397.156432) (xy 337.203369 -397.144384) (xy 337.205152 -397.120355) (xy 337.206844 -397.108426)
			(xy 337.208114 -397.099536) (xy 337.205066 -397.082518) (xy 337.162902 -397.011652) (xy 337.149694 -397.000476)
			(xy 337.141312 -396.997428) (xy 337.119573 -396.98901) (xy 337.078714 -396.966574) (xy 337.041741 -396.938185)
			(xy 337.009517 -396.904504) (xy 336.98279 -396.866313) (xy 336.962183 -396.824501) (xy 336.948174 -396.780042)
			(xy 336.94109 -396.733969) (xy 336.940652 -396.710662) (xy 336.941161 -396.685266) (xy 336.949572 -396.635176)
			(xy 336.966155 -396.587167) (xy 336.990453 -396.542564) (xy 337.021797 -396.502597) (xy 337.04022 -396.48511)
			(xy 337.048602 -396.47749) (xy 337.057238 -396.457424) (xy 337.054444 -396.35811) (xy 337.045046 -396.338552)
			(xy 337.036156 -396.33144) (xy 337.01762 -396.315611) (xy 336.984898 -396.279486) (xy 336.957828 -396.238953)
			(xy 336.936994 -396.194889) (xy 336.922846 -396.148246) (xy 336.91569 -396.100033) (xy 336.915252 -396.075662)
			(xy 336.915665 -396.051544) (xy 336.922673 -396.003821) (xy 336.936533 -395.95762) (xy 336.956953 -395.91392)
			(xy 336.969862 -395.893544) (xy 336.975704 -395.884654) (xy 336.97926 -395.864588) (xy 336.958178 -395.772386)
			(xy 336.945986 -395.755622) (xy 336.937096 -395.750288) (xy 336.916313 -395.737406) (xy 336.878406 -395.706522)
			(xy 336.845461 -395.670391) (xy 336.818197 -395.629803) (xy 336.797209 -395.585641) (xy 336.782954 -395.53887)
			(xy 336.775743 -395.49051) (xy 336.775298 -395.466062) (xy 336.775845 -395.438777) (xy 336.784796 -395.384947)
			(xy 336.802465 -395.333318) (xy 336.828373 -395.285291) (xy 336.861815 -395.242171) (xy 336.88147 -395.223238)
			(xy 336.888853 -395.2157) (xy 336.897389 -395.196433) (xy 336.89798 -395.1859) (xy 336.89798 -395.111224)
			(xy 336.897457 -395.100673) (xy 336.888918 -395.081378) (xy 336.88147 -395.073886) (xy 336.861843 -395.054928)
			(xy 336.828407 -395.011809) (xy 336.8025 -394.963788) (xy 336.784825 -394.912166) (xy 336.775861 -394.858344)
			(xy 336.775298 -394.831062) (xy 336.775552 -394.81887) (xy 336.775806 -394.809218) (xy 336.76971 -394.791184)
			(xy 336.711036 -394.723874) (xy 336.694272 -394.715238) (xy 336.68462 -394.714222) (xy 336.657709 -394.710882)
			(xy 336.605422 -394.696512) (xy 336.556179 -394.673808) (xy 336.511297 -394.643378) (xy 336.471978 -394.606036)
			(xy 336.439274 -394.562783) (xy 336.414062 -394.514775) (xy 336.397015 -394.463299) (xy 336.392266 -394.4366)
			(xy 336.390742 -394.427202) (xy 336.117946 -393.95527) (xy 336.11058 -393.949428) (xy 336.091829 -393.933596)
			(xy 336.05871 -393.897385) (xy 336.031298 -393.856683) (xy 336.010193 -393.812381) (xy 335.995856 -393.765449)
			(xy 335.988602 -393.716916) (xy 335.988152 -393.69238) (xy 333.660882 -393.69238) (xy 333.680396 -393.702323)
			(xy 333.722444 -393.732873) (xy 333.759195 -393.769624) (xy 333.789745 -393.811672) (xy 333.813341 -393.857982)
			(xy 333.829402 -393.907412) (xy 333.837532 -393.958747) (xy 333.838042 -393.984734) (xy 333.837532 -394.010721)
			(xy 333.829402 -394.062056) (xy 333.813341 -394.111486) (xy 333.789745 -394.157796) (xy 333.759195 -394.199844)
			(xy 333.722444 -394.236595) (xy 333.69363 -394.25753) (xy 335.361534 -394.25753) (xy 335.362044 -394.231543)
			(xy 335.370174 -394.180208) (xy 335.386235 -394.130778) (xy 335.409831 -394.084468) (xy 335.440381 -394.04242)
			(xy 335.477132 -394.005669) (xy 335.51918 -393.975119) (xy 335.56549 -393.951523) (xy 335.61492 -393.935462)
			(xy 335.666255 -393.927332) (xy 335.718229 -393.927332) (xy 335.769564 -393.935462) (xy 335.818994 -393.951523)
			(xy 335.865304 -393.975119) (xy 335.907352 -394.005669) (xy 335.944103 -394.04242) (xy 335.974653 -394.084468)
			(xy 335.998249 -394.130778) (xy 336.01431 -394.180208) (xy 336.02244 -394.231543) (xy 336.02295 -394.25753)
			(xy 336.022567 -394.281206) (xy 336.015834 -394.328077) (xy 336.002468 -394.373504) (xy 335.992978 -394.395198)
			(xy 335.98866 -394.404596) (xy 335.987898 -394.424662) (xy 336.020156 -394.511022) (xy 336.033872 -394.525754)
			(xy 336.04327 -394.530072) (xy 336.067643 -394.541753) (xy 336.112512 -394.571883) (xy 336.151889 -394.608903)
			(xy 336.184727 -394.651829) (xy 336.210152 -394.699522) (xy 336.22749 -394.750712) (xy 336.236279 -394.804039)
			(xy 336.236818 -394.831062) (xy 336.236281 -394.858347) (xy 336.227327 -394.912177) (xy 336.209655 -394.963806)
			(xy 336.183746 -395.011833) (xy 336.150302 -395.054954) (xy 336.130646 -395.073886) (xy 336.123255 -395.081417)
			(xy 336.114723 -395.10069) (xy 336.114136 -395.111224) (xy 336.114136 -395.1859) (xy 336.114641 -395.196453)
			(xy 336.123192 -395.215749) (xy 336.130646 -395.223238) (xy 336.150288 -395.242182) (xy 336.183721 -395.285305)
			(xy 336.209625 -395.33333) (xy 336.227296 -395.384955) (xy 336.236257 -395.438779) (xy 336.236818 -395.466062)
			(xy 336.236373 -395.490178) (xy 336.229376 -395.537901) (xy 336.215525 -395.584102) (xy 336.195114 -395.627803)
			(xy 336.182208 -395.64818) (xy 336.176366 -395.65707) (xy 336.17281 -395.677136) (xy 336.193892 -395.769338)
			(xy 336.206084 -395.786102) (xy 336.214974 -395.791436) (xy 336.235784 -395.804277) (xy 336.273688 -395.83517)
			(xy 336.306628 -395.871309) (xy 336.333888 -395.911904) (xy 336.354871 -395.956072) (xy 336.369122 -396.002848)
			(xy 336.376329 -396.051213) (xy 336.376772 -396.075662) (xy 336.376361 -396.100036) (xy 336.369215 -396.148256)
			(xy 336.355071 -396.194906) (xy 336.334236 -396.238977) (xy 336.30716 -396.279513) (xy 336.274431 -396.315639)
			(xy 336.255868 -396.33144) (xy 336.246978 -396.338552) (xy 336.23758 -396.35811) (xy 336.234786 -396.457424)
			(xy 336.243422 -396.47749) (xy 336.251804 -396.48511) (xy 336.270243 -396.502582) (xy 336.301593 -396.542549)
			(xy 336.325893 -396.587155) (xy 336.342472 -396.635168) (xy 336.350872 -396.685264) (xy 336.351372 -396.710662)
			(xy 336.351303 -396.720021) (xy 336.35016 -396.738703) (xy 336.349086 -396.748) (xy 336.34807 -396.75689)
			(xy 336.35188 -396.773654) (xy 336.395822 -396.843504) (xy 336.409538 -396.853918) (xy 336.41792 -396.856712)
			(xy 336.441944 -396.86519) (xy 336.487117 -396.888741) (xy 336.527923 -396.919238) (xy 336.563303 -396.955891)
			(xy 336.592339 -396.997748) (xy 336.614279 -397.043725) (xy 336.621882 -397.06804) (xy 336.623406 -397.073882)
			(xy 336.9437 -397.627602) (xy 336.947764 -397.63192) (xy 336.963966 -397.649629) (xy 336.991388 -397.689021)
			(xy 337.01253 -397.73211) (xy 337.026905 -397.777904) (xy 337.03418 -397.825346) (xy 337.034632 -397.849344)
			(xy 337.034247 -397.874151) (xy 337.026474 -397.923153) (xy 337.011129 -397.970335) (xy 336.988588 -398.014534)
			(xy 336.959407 -398.05466) (xy 336.924305 -398.089724) (xy 336.884149 -398.118862) (xy 336.839926 -398.141357)
			(xy 336.792728 -398.156652) (xy 336.743718 -398.164373) (xy 336.71891 -398.164812) (xy 336.693516 -398.164303)
			(xy 336.643383 -398.156174) (xy 336.595197 -398.140124) (xy 336.550203 -398.116567) (xy 336.50956 -398.08611)
			(xy 336.474317 -398.04954) (xy 336.445383 -398.0078) (xy 336.423505 -397.961966) (xy 336.415888 -397.937736)
			(xy 336.414364 -397.931894) (xy 336.09407 -397.378174) (xy 336.090006 -397.373856) (xy 336.073839 -397.356129)
			(xy 336.046473 -397.316724) (xy 336.025385 -397.273633) (xy 336.011059 -397.227846) (xy 336.003826 -397.18042)
			(xy 336.003392 -397.156432) (xy 336.003473 -397.144384) (xy 336.005256 -397.120355) (xy 336.006948 -397.108426)
			(xy 336.008218 -397.099536) (xy 336.00517 -397.082518) (xy 335.963006 -397.011652) (xy 335.949798 -397.000476)
			(xy 335.941416 -396.997428) (xy 335.919678 -396.989008) (xy 335.878818 -396.966573) (xy 335.841846 -396.938184)
			(xy 335.809621 -396.904503) (xy 335.782894 -396.866312) (xy 335.762287 -396.824501) (xy 335.748278 -396.780042)
			(xy 335.741194 -396.733969) (xy 335.740756 -396.710662) (xy 335.741264 -396.685266) (xy 335.749675 -396.635175)
			(xy 335.766258 -396.587167) (xy 335.790557 -396.542564) (xy 335.821901 -396.502597) (xy 335.840324 -396.48511)
			(xy 335.848706 -396.47749) (xy 335.857342 -396.457424) (xy 335.854548 -396.35811) (xy 335.84515 -396.338552)
			(xy 335.83626 -396.33144) (xy 335.817724 -396.31561) (xy 335.785003 -396.279485) (xy 335.757932 -396.238952)
			(xy 335.737098 -396.194888) (xy 335.72295 -396.148246) (xy 335.715794 -396.100033) (xy 335.715356 -396.075662)
			(xy 335.715769 -396.051544) (xy 335.722776 -396.003821) (xy 335.736636 -395.95762) (xy 335.757057 -395.91392)
			(xy 335.769966 -395.893544) (xy 335.775808 -395.884654) (xy 335.779364 -395.864588) (xy 335.758282 -395.772386)
			(xy 335.74609 -395.755622) (xy 335.7372 -395.750288) (xy 335.716418 -395.737404) (xy 335.67851 -395.706521)
			(xy 335.645565 -395.670391) (xy 335.618301 -395.629802) (xy 335.597313 -395.585641) (xy 335.583058 -395.53887)
			(xy 335.575847 -395.49051) (xy 335.575402 -395.466062) (xy 335.575948 -395.438777) (xy 335.584899 -395.384947)
			(xy 335.602568 -395.333318) (xy 335.628476 -395.285291) (xy 335.661919 -395.24217) (xy 335.681574 -395.223238)
			(xy 335.688957 -395.215701) (xy 335.697493 -395.196433) (xy 335.698084 -395.1859) (xy 335.698084 -395.111224)
			(xy 335.69756 -395.100674) (xy 335.689022 -395.081378) (xy 335.681574 -395.073886) (xy 335.661947 -395.054927)
			(xy 335.628511 -395.011808) (xy 335.602604 -394.963787) (xy 335.584929 -394.912166) (xy 335.575965 -394.858344)
			(xy 335.575402 -394.831062) (xy 335.575787 -394.807386) (xy 335.58252 -394.760515) (xy 335.595884 -394.715089)
			(xy 335.605374 -394.693394) (xy 335.609692 -394.683996) (xy 335.610454 -394.66393) (xy 335.578196 -394.57757)
			(xy 335.56448 -394.562838) (xy 335.555082 -394.55852) (xy 335.530717 -394.546821) (xy 335.485846 -394.516697)
			(xy 335.446466 -394.479681) (xy 335.413627 -394.436758) (xy 335.3882 -394.389067) (xy 335.370861 -394.337879)
			(xy 335.362073 -394.284553) (xy 335.361534 -394.25753) (xy 333.69363 -394.25753) (xy 333.680396 -394.267145)
			(xy 333.634086 -394.290741) (xy 333.584656 -394.306802) (xy 333.533321 -394.314932) (xy 333.481347 -394.314932)
			(xy 333.430012 -394.306802) (xy 333.380582 -394.290741) (xy 333.334272 -394.267145) (xy 333.292224 -394.236595)
			(xy 333.255473 -394.199844) (xy 333.224923 -394.157796) (xy 333.201327 -394.111486) (xy 333.185266 -394.062056)
			(xy 333.177136 -394.010721) (xy 332.971693 -394.010721) (xy 332.966321 -394.047222) (xy 332.950253 -394.100629)
			(xy 332.926581 -394.151126) (xy 332.895808 -394.197639) (xy 332.858591 -394.239176) (xy 332.815723 -394.274851)
			(xy 332.768117 -394.303905) (xy 332.716788 -394.325717) (xy 332.662831 -394.339823) (xy 332.607394 -394.345923)
			(xy 332.55166 -394.343886) (xy 332.496817 -394.333756) (xy 332.444033 -394.315749) (xy 332.394433 -394.290248)
			(xy 332.349075 -394.257797) (xy 332.308926 -394.219088) (xy 332.27484 -394.174945) (xy 332.247544 -394.12631)
			(xy 332.227621 -394.074219) (xy 332.215495 -394.019782) (xy 332.211424 -393.96416) (xy 327.53046 -393.96416)
			(xy 327.407524 -394.087096) (xy 327.403968 -394.123418) (xy 327.414128 -394.138404) (xy 327.430633 -394.163662)
			(xy 327.4582 -394.217337) (xy 327.479223 -394.273896) (xy 327.493407 -394.332545) (xy 327.500554 -394.39246)
			(xy 327.500996 -394.42263) (xy 327.50053 -394.45336) (xy 327.493119 -394.51437) (xy 327.478407 -394.574043)
			(xy 327.456611 -394.631507) (xy 327.428047 -394.685925) (xy 327.393131 -394.736503) (xy 327.352375 -394.782504)
			(xy 327.30637 -394.823257) (xy 327.255789 -394.858168) (xy 327.201369 -394.886728) (xy 327.143903 -394.90852)
			(xy 327.084229 -394.923226) (xy 327.023218 -394.930633) (xy 326.992488 -394.931138) (xy 326.961629 -394.930673)
			(xy 326.90037 -394.923162) (xy 326.870314 -394.916152) (xy 326.860662 -394.913866) (xy 326.84212 -394.916406)
			(xy 326.764396 -394.959586) (xy 326.752204 -394.974064) (xy 326.749156 -394.983462) (xy 326.73826 -395.015428)
			(xy 326.709186 -395.076385) (xy 326.672291 -395.132951) (xy 326.628224 -395.184128) (xy 326.60336 -395.206982)
			(xy 326.594944 -395.21524) (xy 326.586119 -395.237075) (xy 326.587962 -395.260553) (xy 326.593454 -395.27099)
			(xy 326.606182 -395.29321) (xy 326.626227 -395.340331) (xy 326.639791 -395.389709) (xy 326.64663 -395.440458)
			(xy 326.647048 -395.466062) (xy 326.646565 -395.493316) (xy 326.638813 -395.54727) (xy 326.623462 -395.599572)
			(xy 326.600823 -395.649156) (xy 326.571358 -395.695014) (xy 326.535668 -395.736212) (xy 326.494477 -395.771912)
			(xy 326.448625 -395.801386) (xy 326.399045 -395.824034) (xy 326.346746 -395.839396) (xy 326.292794 -395.847159)
			(xy 326.26554 -395.84757) (xy 326.2362 -395.847034) (xy 326.178213 -395.83805) (xy 326.122288 -395.820287)
			(xy 326.069743 -395.794166) (xy 326.021822 -395.760303) (xy 325.979654 -395.719497) (xy 325.961502 -395.69644)
			(xy 325.954644 -395.68755) (xy 325.935594 -395.677136) (xy 325.847964 -395.671294) (xy 325.837062 -395.671047)
			(xy 325.816661 -395.678688) (xy 325.808594 -395.686026) (xy 325.31812 -396.1765) (xy 327.956924 -396.1765)
			(xy 327.960995 -396.120878) (xy 327.973121 -396.066441) (xy 327.993044 -396.01435) (xy 328.02034 -395.965715)
			(xy 328.054426 -395.921572) (xy 328.094575 -395.882863) (xy 328.139933 -395.850412) (xy 328.189533 -395.824911)
			(xy 328.242317 -395.806904) (xy 328.29716 -395.796774) (xy 328.352894 -395.794737) (xy 328.408331 -395.800837)
			(xy 328.462288 -395.814943) (xy 328.513617 -395.836755) (xy 328.561223 -395.865809) (xy 328.604091 -395.901484)
			(xy 328.641308 -395.943021) (xy 328.672081 -395.989534) (xy 328.695753 -396.040031) (xy 328.711821 -396.093438)
			(xy 328.719941 -396.148614) (xy 328.720362 -396.171674) (xy 329.428856 -396.171674) (xy 329.428856 -395.308074)
			(xy 329.429299 -395.280815) (xy 329.437059 -395.226851) (xy 329.452415 -395.17454) (xy 329.475057 -395.124945)
			(xy 329.504524 -395.079076) (xy 329.540216 -395.037865) (xy 329.581408 -395.00215) (xy 329.627261 -394.972658)
			(xy 329.676843 -394.949989) (xy 329.729146 -394.934603) (xy 329.783105 -394.926814) (xy 329.810364 -394.926312)
			(xy 329.820418 -394.926428) (xy 329.840494 -394.927569) (xy 329.850496 -394.928598) (xy 329.86218 -394.929868)
			(xy 329.883262 -394.922248) (xy 329.955906 -394.85062) (xy 329.963526 -394.829538) (xy 329.96251 -394.818108)
			(xy 329.960732 -394.782294) (xy 329.961184 -394.755044) (xy 329.968941 -394.701098) (xy 329.984296 -394.648806)
			(xy 330.006936 -394.599231) (xy 330.036401 -394.553382) (xy 330.072091 -394.512194) (xy 330.11328 -394.476503)
			(xy 330.159128 -394.447038) (xy 330.208703 -394.424397) (xy 330.260995 -394.409042) (xy 330.314941 -394.401284)
			(xy 330.369441 -394.401283) (xy 330.423387 -394.409038) (xy 330.47568 -394.424391) (xy 330.525256 -394.447029)
			(xy 330.571105 -394.476492) (xy 330.612295 -394.512181) (xy 330.647987 -394.553367) (xy 330.677455 -394.599215)
			(xy 330.700098 -394.648788) (xy 330.715455 -394.70108) (xy 330.723215 -394.755025) (xy 330.723218 -394.809525)
			(xy 330.715466 -394.863472) (xy 330.713125 -394.871448) (xy 333.27848 -394.871448) (xy 333.27899 -394.845461)
			(xy 333.28712 -394.794126) (xy 333.303181 -394.744696) (xy 333.326777 -394.698386) (xy 333.357327 -394.656338)
			(xy 333.394078 -394.619587) (xy 333.436126 -394.589037) (xy 333.482436 -394.565441) (xy 333.531866 -394.54938)
			(xy 333.583201 -394.54125) (xy 333.635175 -394.54125) (xy 333.68651 -394.54938) (xy 333.73594 -394.565441)
			(xy 333.78225 -394.589037) (xy 333.824298 -394.619587) (xy 333.861049 -394.656338) (xy 333.891599 -394.698386)
			(xy 333.915195 -394.744696) (xy 333.931256 -394.794126) (xy 333.939386 -394.845461) (xy 333.939896 -394.871448)
			(xy 333.939359 -394.898777) (xy 333.930364 -394.952691) (xy 333.912627 -395.004392) (xy 333.88663 -395.052473)
			(xy 333.8703 -395.074394) (xy 333.864712 -395.08176) (xy 333.859124 -395.098524) (xy 333.86268 -395.182598)
			(xy 333.869538 -395.198854) (xy 333.875634 -395.205712) (xy 333.892019 -395.22411) (xy 333.919669 -395.264883)
			(xy 333.94097 -395.309305) (xy 333.955451 -395.356393) (xy 333.962792 -395.405108) (xy 333.963264 -395.42974)
			(xy 333.962754 -395.455727) (xy 333.954624 -395.507062) (xy 333.938563 -395.556492) (xy 333.914967 -395.602802)
			(xy 333.884417 -395.64485) (xy 333.847666 -395.681601) (xy 333.805618 -395.712151) (xy 333.759308 -395.735747)
			(xy 333.709878 -395.751808) (xy 333.658543 -395.759938) (xy 333.606569 -395.759938) (xy 333.555234 -395.751808)
			(xy 333.505804 -395.735747) (xy 333.459494 -395.712151) (xy 333.417446 -395.681601) (xy 333.380695 -395.64485)
			(xy 333.350145 -395.602802) (xy 333.326549 -395.556492) (xy 333.310488 -395.507062) (xy 333.302358 -395.455727)
			(xy 333.301848 -395.42974) (xy 333.302443 -395.402413) (xy 333.311422 -395.348503) (xy 333.329143 -395.296802)
			(xy 333.355122 -395.248718) (xy 333.371444 -395.226794) (xy 333.377032 -395.219428) (xy 333.38262 -395.202664)
			(xy 333.379064 -395.11859) (xy 333.372206 -395.102334) (xy 333.36611 -395.095476) (xy 333.349774 -395.077037)
			(xy 333.322115 -395.036275) (xy 333.300804 -394.991864) (xy 333.286312 -394.944785) (xy 333.278958 -394.896077)
			(xy 333.27848 -394.871448) (xy 330.713125 -394.871448) (xy 330.700115 -394.915765) (xy 330.677478 -394.965342)
			(xy 330.648017 -395.011193) (xy 330.61233 -395.052384) (xy 330.571145 -395.088078) (xy 330.525299 -395.117547)
			(xy 330.475726 -395.140192) (xy 330.423435 -395.155552) (xy 330.36949 -395.163313) (xy 330.34224 -395.163802)
			(xy 330.332189 -395.163763) (xy 330.312112 -395.162744) (xy 330.302108 -395.16177) (xy 330.290678 -395.1605)
			(xy 330.269342 -395.167866) (xy 330.196952 -395.239494) (xy 330.189332 -395.260576) (xy 330.190348 -395.27226)
			(xy 330.191872 -395.308074) (xy 330.191872 -396.171674) (xy 330.191294 -396.202807) (xy 330.181211 -396.26425)
			(xy 330.161262 -396.323232) (xy 330.147168 -396.350998) (xy 330.142088 -396.360904) (xy 330.140564 -396.382494)
			(xy 330.175108 -396.474442) (xy 330.190348 -396.489936) (xy 330.200508 -396.493746) (xy 330.227168 -396.50447)
			(xy 330.277186 -396.532753) (xy 330.322389 -396.568228) (xy 330.361753 -396.610088) (xy 330.394384 -396.657385)
			(xy 330.419543 -396.709045) (xy 330.4286 -396.736316) (xy 330.43241 -396.749016) (xy 330.451206 -396.766796)
			(xy 330.559918 -396.795752) (xy 330.58481 -396.789656) (xy 330.594462 -396.780512) (xy 330.618039 -396.759299)
			(xy 330.669541 -396.722286) (xy 330.725248 -396.691969) (xy 330.784295 -396.668819) (xy 330.845764 -396.653197)
			(xy 330.908698 -396.645343) (xy 330.94041 -396.644876) (xy 330.97237 -396.64541) (xy 331.035785 -396.653423)
			(xy 331.097696 -396.66932) (xy 331.123846 -396.679674) (xy 332.336392 -396.679674) (xy 332.340463 -396.624052)
			(xy 332.352589 -396.569615) (xy 332.372512 -396.517524) (xy 332.399808 -396.468889) (xy 332.433894 -396.424746)
			(xy 332.474043 -396.386037) (xy 332.519401 -396.353586) (xy 332.569001 -396.328085) (xy 332.621785 -396.310078)
			(xy 332.676628 -396.299948) (xy 332.732362 -396.297911) (xy 332.787799 -396.304011) (xy 332.841756 -396.318117)
			(xy 332.893085 -396.339929) (xy 332.940691 -396.368983) (xy 332.983559 -396.404658) (xy 333.020776 -396.446195)
			(xy 333.051549 -396.492708) (xy 333.075221 -396.543205) (xy 333.091289 -396.596612) (xy 333.099409 -396.651788)
			(xy 333.099918 -396.679674) (xy 333.099471 -396.704137) (xy 333.302358 -396.704137) (xy 333.302358 -396.652163)
			(xy 333.310488 -396.600828) (xy 333.326549 -396.551398) (xy 333.350145 -396.505088) (xy 333.380695 -396.46304)
			(xy 333.417446 -396.426289) (xy 333.459494 -396.395739) (xy 333.505804 -396.372143) (xy 333.555234 -396.356082)
			(xy 333.606569 -396.347952) (xy 333.658543 -396.347952) (xy 333.709878 -396.356082) (xy 333.759308 -396.372143)
			(xy 333.805618 -396.395739) (xy 333.847666 -396.426289) (xy 333.884417 -396.46304) (xy 333.914967 -396.505088)
			(xy 333.938563 -396.551398) (xy 333.954624 -396.600828) (xy 333.962754 -396.652163) (xy 333.963264 -396.67815)
			(xy 333.962754 -396.704137) (xy 333.954624 -396.755472) (xy 333.938563 -396.804902) (xy 333.914967 -396.851212)
			(xy 333.884417 -396.89326) (xy 333.847666 -396.930011) (xy 333.805618 -396.960561) (xy 333.759308 -396.984157)
			(xy 333.709878 -397.000218) (xy 333.658543 -397.008348) (xy 333.606569 -397.008348) (xy 333.555234 -397.000218)
			(xy 333.505804 -396.984157) (xy 333.459494 -396.960561) (xy 333.417446 -396.930011) (xy 333.380695 -396.89326)
			(xy 333.350145 -396.851212) (xy 333.326549 -396.804902) (xy 333.310488 -396.755472) (xy 333.302358 -396.704137)
			(xy 333.099471 -396.704137) (xy 333.099409 -396.70756) (xy 333.091289 -396.762736) (xy 333.075221 -396.816143)
			(xy 333.051549 -396.86664) (xy 333.020776 -396.913153) (xy 332.983559 -396.95469) (xy 332.940691 -396.990365)
			(xy 332.893085 -397.019419) (xy 332.841756 -397.041231) (xy 332.787799 -397.055337) (xy 332.732362 -397.061437)
			(xy 332.676628 -397.0594) (xy 332.621785 -397.04927) (xy 332.569001 -397.031263) (xy 332.519401 -397.005762)
			(xy 332.474043 -396.973311) (xy 332.433894 -396.934602) (xy 332.399808 -396.890459) (xy 332.372512 -396.841824)
			(xy 332.352589 -396.789733) (xy 332.340463 -396.735296) (xy 332.336392 -396.679674) (xy 331.123846 -396.679674)
			(xy 331.157126 -396.692851) (xy 331.213138 -396.723645) (xy 331.26485 -396.761217) (xy 331.311444 -396.804973)
			(xy 331.352188 -396.854224) (xy 331.386437 -396.908193) (xy 331.413652 -396.966029) (xy 331.433404 -397.02682)
			(xy 331.445381 -397.089607) (xy 331.449395 -397.1534) (xy 331.445381 -397.217193) (xy 331.433404 -397.27998)
			(xy 331.413652 -397.340771) (xy 331.386437 -397.398607) (xy 331.352188 -397.452576) (xy 331.311444 -397.501827)
			(xy 331.26485 -397.545583) (xy 331.213138 -397.583155) (xy 331.157126 -397.613949) (xy 331.097696 -397.63748)
			(xy 331.035785 -397.653377) (xy 330.97237 -397.66139) (xy 330.94041 -397.661892) (xy 330.909321 -397.661431)
			(xy 330.84761 -397.653837) (xy 330.787285 -397.638774) (xy 330.729247 -397.616466) (xy 330.674363 -397.587247)
			(xy 330.623452 -397.551553) (xy 330.60005 -397.531082) (xy 330.590144 -397.522192) (xy 330.564236 -397.51635)
			(xy 330.455524 -397.548862) (xy 330.436982 -397.568166) (xy 330.43368 -397.58112) (xy 330.426182 -397.608016)
			(xy 330.404385 -397.659421) (xy 330.375333 -397.707103) (xy 330.339644 -397.750044) (xy 330.298081 -397.787327)
			(xy 330.251529 -397.818158) (xy 330.200983 -397.841879) (xy 330.14752 -397.857982) (xy 330.092282 -397.866125)
			(xy 330.064364 -397.866616) (xy 330.037112 -397.866156) (xy 329.983164 -397.858394) (xy 329.930869 -397.843035)
			(xy 329.881292 -397.82039) (xy 329.835443 -397.790921) (xy 329.794253 -397.755227) (xy 329.758562 -397.714035)
			(xy 329.729096 -397.668183) (xy 329.706455 -397.618604) (xy 329.6911 -397.566309) (xy 329.683342 -397.51236)
			(xy 329.682856 -397.485108) (xy 329.683313 -397.457737) (xy 329.691131 -397.403557) (xy 329.706621 -397.351054)
			(xy 329.729466 -397.301307) (xy 329.759193 -397.255341) (xy 329.776836 -397.23441) (xy 329.782932 -397.227298)
			(xy 329.789282 -397.21028) (xy 329.789282 -397.124936) (xy 329.782932 -397.107918) (xy 329.776836 -397.100806)
			(xy 329.759192 -397.079878) (xy 329.72948 -397.033905) (xy 329.706644 -396.984156) (xy 329.691154 -396.931654)
			(xy 329.683328 -396.877478) (xy 329.682856 -396.850108) (xy 329.683463 -396.818976) (xy 329.693533 -396.757534)
			(xy 329.713471 -396.698551) (xy 329.72756 -396.670784) (xy 329.73264 -396.661132) (xy 329.734164 -396.639542)
			(xy 329.699874 -396.547594) (xy 329.68438 -396.5321) (xy 329.67422 -396.52829) (xy 329.647532 -396.517511)
			(xy 329.597478 -396.489097) (xy 329.552254 -396.453495) (xy 329.512883 -396.411509) (xy 329.480259 -396.364092)
			(xy 329.455118 -396.312317) (xy 329.438031 -396.257355) (xy 329.429384 -396.200452) (xy 329.428856 -396.171674)
			(xy 328.720362 -396.171674) (xy 328.72045 -396.1765) (xy 328.719941 -396.204386) (xy 328.711821 -396.259562)
			(xy 328.695753 -396.312969) (xy 328.672081 -396.363466) (xy 328.641308 -396.409979) (xy 328.604091 -396.451516)
			(xy 328.561223 -396.487191) (xy 328.513617 -396.516245) (xy 328.462288 -396.538057) (xy 328.408331 -396.552163)
			(xy 328.352894 -396.558263) (xy 328.29716 -396.556226) (xy 328.242317 -396.546096) (xy 328.189533 -396.528089)
			(xy 328.139933 -396.502588) (xy 328.094575 -396.470137) (xy 328.054426 -396.431428) (xy 328.02034 -396.387285)
			(xy 327.993044 -396.33865) (xy 327.973121 -396.286559) (xy 327.960995 -396.232122) (xy 327.956924 -396.1765)
			(xy 325.31812 -396.1765) (xy 324.748906 -396.745714) (xy 324.742061 -396.753113) (xy 324.734331 -396.771711)
			(xy 324.73392 -396.781782) (xy 324.73392 -396.822422) (xy 324.734344 -396.832122) (xy 324.741519 -396.850148)
			(xy 324.74789 -396.857474) (xy 324.768718 -396.879318) (xy 324.775221 -396.885626) (xy 324.791494 -396.893562)
			(xy 324.800468 -396.894812) (xy 324.829745 -396.898298) (xy 324.886807 -396.913128) (xy 324.940909 -396.936557)
			(xy 324.990766 -396.968025) (xy 325.01332 -396.987014) (xy 325.020432 -396.99311) (xy 325.03745 -396.99946)
			(xy 325.122794 -396.99946) (xy 325.139812 -396.99311) (xy 325.146924 -396.987014) (xy 325.167857 -396.969373)
			(xy 325.213825 -396.939649) (xy 325.263571 -396.916803) (xy 325.316073 -396.901307) (xy 325.370251 -396.893478)
			(xy 325.424993 -396.893478) (xy 325.479171 -396.901307) (xy 325.531673 -396.916803) (xy 325.581419 -396.939649)
			(xy 325.627387 -396.969373) (xy 325.64832 -396.987014) (xy 325.655432 -396.99311) (xy 325.67245 -396.99946)
			(xy 325.757794 -396.99946) (xy 325.774812 -396.99311) (xy 325.781924 -396.987014) (xy 325.802856 -396.969373)
			(xy 325.848822 -396.939649) (xy 325.898569 -396.916808) (xy 325.951073 -396.90132) (xy 326.005252 -396.893505)
			(xy 326.032622 -396.893034) (xy 326.059869 -396.893522) (xy 326.113809 -396.90128) (xy 326.166095 -396.916635)
			(xy 326.215664 -396.939275) (xy 326.261506 -396.968739) (xy 326.302689 -397.004426) (xy 326.338375 -397.045611)
			(xy 326.367835 -397.091456) (xy 326.390473 -397.141026) (xy 326.40202 -397.180352) (xy 327.740985 -397.180352)
			(xy 327.740985 -397.125848) (xy 327.748742 -397.071899) (xy 327.764099 -397.019603) (xy 327.786741 -396.970025)
			(xy 327.816209 -396.924175) (xy 327.851903 -396.882984) (xy 327.893095 -396.847294) (xy 327.938948 -396.817829)
			(xy 327.988528 -396.795189) (xy 328.040825 -396.779837) (xy 328.094774 -396.772083) (xy 328.122026 -396.771622)
			(xy 328.149397 -396.772067) (xy 328.203577 -396.779889) (xy 328.256081 -396.795383) (xy 328.305827 -396.818229)
			(xy 328.351793 -396.847959) (xy 328.372724 -396.865602) (xy 328.379836 -396.871698) (xy 328.396854 -396.878048)
			(xy 328.482198 -396.878048) (xy 328.499216 -396.871698) (xy 328.506328 -396.865602) (xy 328.527277 -396.847984)
			(xy 328.573245 -396.818269) (xy 328.622988 -396.795429) (xy 328.675485 -396.779933) (xy 328.729658 -396.772099)
			(xy 328.757026 -396.771622) (xy 328.784278 -396.77205) (xy 328.838227 -396.77981) (xy 328.890523 -396.795168)
			(xy 328.940101 -396.817813) (xy 328.985952 -396.847282) (xy 329.027142 -396.882976) (xy 329.062834 -396.924169)
			(xy 329.0923 -396.970022) (xy 329.114941 -397.019601) (xy 329.130296 -397.071898) (xy 329.138052 -397.125848)
			(xy 329.138052 -397.180352) (xy 329.130296 -397.234302) (xy 329.114941 -397.286599) (xy 329.0923 -397.336178)
			(xy 329.062834 -397.382031) (xy 329.027142 -397.423224) (xy 328.985952 -397.458918) (xy 328.940101 -397.488387)
			(xy 328.890523 -397.511032) (xy 328.838227 -397.52639) (xy 328.784278 -397.53415) (xy 328.757026 -397.534638)
			(xy 328.729656 -397.534172) (xy 328.675476 -397.526356) (xy 328.622972 -397.510868) (xy 328.573225 -397.488026)
			(xy 328.527259 -397.4583) (xy 328.506328 -397.440658) (xy 328.499216 -397.434562) (xy 328.482198 -397.428212)
			(xy 328.396854 -397.428212) (xy 328.379836 -397.434562) (xy 328.372724 -397.440658) (xy 328.351788 -397.458293)
			(xy 328.305817 -397.488007) (xy 328.256071 -397.510844) (xy 328.203571 -397.526336) (xy 328.149395 -397.534164)
			(xy 328.122026 -397.534638) (xy 328.094774 -397.534117) (xy 328.040825 -397.526363) (xy 327.988528 -397.511011)
			(xy 327.938948 -397.488371) (xy 327.893095 -397.458906) (xy 327.851903 -397.423216) (xy 327.816209 -397.382025)
			(xy 327.786741 -397.336175) (xy 327.764099 -397.286597) (xy 327.748742 -397.234301) (xy 327.740985 -397.180352)
			(xy 326.40202 -397.180352) (xy 326.405825 -397.193313) (xy 326.41358 -397.247253) (xy 326.41358 -397.301747)
			(xy 326.405825 -397.355687) (xy 326.390473 -397.407974) (xy 326.367835 -397.457544) (xy 326.338375 -397.503389)
			(xy 326.302689 -397.544574) (xy 326.261506 -397.580261) (xy 326.215664 -397.609725) (xy 326.166095 -397.632365)
			(xy 326.113809 -397.64772) (xy 326.059869 -397.655478) (xy 326.032622 -397.65605) (xy 326.005254 -397.655573)
			(xy 325.951082 -397.647738) (xy 325.898586 -397.632241) (xy 325.848844 -397.609399) (xy 325.802878 -397.579682)
			(xy 325.781924 -397.56207) (xy 325.774812 -397.555974) (xy 325.757794 -397.549624) (xy 325.67245 -397.549624)
			(xy 325.655432 -397.555974) (xy 325.64832 -397.56207) (xy 325.627387 -397.579711) (xy 325.581419 -397.609435)
			(xy 325.531673 -397.632281) (xy 325.479171 -397.647777) (xy 325.424993 -397.655606) (xy 325.370251 -397.655606)
			(xy 325.316073 -397.647777) (xy 325.263571 -397.632281) (xy 325.213825 -397.609435) (xy 325.167857 -397.579711)
			(xy 325.146924 -397.56207) (xy 325.139812 -397.555974) (xy 325.122794 -397.549624) (xy 325.03745 -397.549624)
			(xy 325.020432 -397.555974) (xy 325.01332 -397.56207) (xy 325.000067 -397.57341) (xy 324.971827 -397.593887)
			(xy 324.956932 -397.602964) (xy 324.946518 -397.60906) (xy 324.933818 -397.628364) (xy 324.922134 -397.719804)
			(xy 324.921255 -397.731452) (xy 324.928801 -397.753535) (xy 324.936612 -397.762222) (xy 325.124318 -397.949674)
			(xy 325.141389 -397.967378) (xy 325.170308 -398.007155) (xy 325.192641 -398.050971) (xy 325.207838 -398.097743)
			(xy 325.215522 -398.146318) (xy 325.216012 -398.170908) (xy 325.216012 -398.747054) (xy 326.121957 -398.747054)
			(xy 326.121957 -398.692546) (xy 326.129715 -398.638593) (xy 326.145073 -398.586293) (xy 326.167717 -398.536711)
			(xy 326.197188 -398.490857) (xy 326.232885 -398.449663) (xy 326.274081 -398.41397) (xy 326.319937 -398.384503)
			(xy 326.369521 -398.361862) (xy 326.421822 -398.346509) (xy 326.475776 -398.338755) (xy 326.50303 -398.338294)
			(xy 326.530401 -398.338744) (xy 326.584581 -398.346566) (xy 326.637084 -398.362059) (xy 326.68683 -398.384904)
			(xy 326.732797 -398.414632) (xy 326.753728 -398.432274) (xy 326.76084 -398.43837) (xy 326.777858 -398.44472)
			(xy 326.863202 -398.44472) (xy 326.88022 -398.43837) (xy 326.887332 -398.432274) (xy 326.908276 -398.414649)
			(xy 326.954246 -398.384936) (xy 327.00399 -398.362098) (xy 327.056488 -398.346603) (xy 327.110662 -398.338771)
			(xy 327.13803 -398.338294) (xy 327.16528 -398.338778) (xy 327.219225 -398.346538) (xy 327.271516 -398.361896)
			(xy 327.32109 -398.384539) (xy 327.366937 -398.414006) (xy 327.408124 -398.449698) (xy 327.443812 -398.490887)
			(xy 327.473276 -398.536736) (xy 327.495915 -398.586312) (xy 327.511269 -398.638605) (xy 327.519024 -398.69255)
			(xy 327.519024 -398.74705) (xy 327.511269 -398.800995) (xy 327.495915 -398.853288) (xy 327.473276 -398.902864)
			(xy 327.443812 -398.948713) (xy 327.408124 -398.989902) (xy 327.366937 -399.025594) (xy 327.32109 -399.055061)
			(xy 327.271516 -399.077704) (xy 327.219225 -399.093062) (xy 327.16528 -399.100822) (xy 327.13803 -399.10131)
			(xy 327.110661 -399.100824) (xy 327.056482 -399.093011) (xy 327.00398 -399.077526) (xy 326.954232 -399.054689)
			(xy 326.908265 -399.024969) (xy 326.887332 -399.00733) (xy 326.88022 -399.001234) (xy 326.863202 -398.994884)
			(xy 326.777858 -398.994884) (xy 326.76084 -399.001234) (xy 326.753728 -399.00733) (xy 326.7328 -399.024974)
			(xy 326.686826 -399.054684) (xy 326.637077 -399.077519) (xy 326.584576 -399.093009) (xy 326.530399 -399.100836)
			(xy 326.50303 -399.10131) (xy 326.475776 -399.100845) (xy 326.421822 -399.093091) (xy 326.369521 -399.077738)
			(xy 326.319937 -399.055097) (xy 326.274081 -399.02563) (xy 326.232885 -398.989937) (xy 326.197188 -398.948743)
			(xy 326.167717 -398.902889) (xy 326.145073 -398.853307) (xy 326.129715 -398.801007) (xy 326.121957 -398.747054)
			(xy 325.216012 -398.747054) (xy 325.216012 -399.489422) (xy 325.215553 -399.514012) (xy 325.207853 -399.562587)
			(xy 325.192648 -399.609358) (xy 325.170311 -399.653174) (xy 325.141393 -399.692954) (xy 325.124318 -399.710656)
			(xy 324.101968 -400.732752) (xy 324.094508 -400.740975) (xy 324.086858 -400.761789) (xy 324.087236 -400.772884)
			(xy 324.094602 -400.86153) (xy 324.105524 -400.880834) (xy 324.114922 -400.887438) (xy 324.13575 -400.902854)
			(xy 324.173447 -400.938407) (xy 324.205987 -400.978733) (xy 324.232773 -401.023091) (xy 324.253312 -401.070664)
			(xy 324.267226 -401.120579) (xy 324.274259 -401.171917) (xy 324.274688 -401.197826) (xy 324.2742 -401.225075)
			(xy 324.26644 -401.279019) (xy 324.251083 -401.33131) (xy 324.22844 -401.380882) (xy 324.198973 -401.426728)
			(xy 324.163281 -401.467913) (xy 324.122091 -401.5036) (xy 324.076242 -401.533062) (xy 324.026667 -401.555699)
			(xy 323.974374 -401.57105) (xy 323.92043 -401.578803) (xy 323.89318 -401.579334) (xy 323.867688 -401.578945)
			(xy 323.817155 -401.572182) (xy 323.767976 -401.558739) (xy 323.721029 -401.538856) (xy 323.69887 -401.526248)
			(xy 323.687186 -401.519136) (xy 323.659754 -401.518882) (xy 323.571108 -401.569428) (xy 323.563548 -401.574196)
			(xy 323.552084 -401.587895) (xy 323.546007 -401.604692) (xy 323.545708 -401.613624) (xy 323.545708 -401.717002)
			(xy 324.23303 -401.717002) (xy 324.237101 -401.66138) (xy 324.249227 -401.606943) (xy 324.26915 -401.554852)
			(xy 324.296446 -401.506217) (xy 324.330532 -401.462074) (xy 324.370681 -401.423365) (xy 324.416039 -401.390914)
			(xy 324.465639 -401.365413) (xy 324.518423 -401.347406) (xy 324.573266 -401.337276) (xy 324.629 -401.335239)
			(xy 324.684437 -401.341339) (xy 324.738394 -401.355445) (xy 324.789723 -401.377257) (xy 324.837329 -401.406311)
			(xy 324.880197 -401.441986) (xy 324.917414 -401.483523) (xy 324.948187 -401.530036) (xy 324.971859 -401.580533)
			(xy 324.987927 -401.63394) (xy 324.996047 -401.689116) (xy 324.996556 -401.717002) (xy 324.996047 -401.744888)
			(xy 324.987927 -401.800064) (xy 324.971859 -401.853471) (xy 324.948674 -401.90293) (xy 325.225918 -401.90293)
			(xy 325.226372 -401.872233) (xy 325.233778 -401.811287) (xy 325.248475 -401.751678) (xy 325.270247 -401.694275)
			(xy 325.298778 -401.639913) (xy 325.315834 -401.614386) (xy 325.321278 -401.60562) (xy 325.325412 -401.585425)
			(xy 325.321297 -401.565226) (xy 325.315834 -401.556474) (xy 325.298794 -401.530939) (xy 325.270285 -401.476571)
			(xy 325.248522 -401.419168) (xy 325.233822 -401.359564) (xy 325.226398 -401.298625) (xy 325.225918 -401.26793)
			(xy 325.226366 -401.237198) (xy 325.233772 -401.17618) (xy 325.248479 -401.116501) (xy 325.270272 -401.05903)
			(xy 325.298835 -401.004604) (xy 325.33375 -400.954019) (xy 325.374509 -400.908012) (xy 325.420516 -400.867253)
			(xy 325.471101 -400.832337) (xy 325.525526 -400.803774) (xy 325.582997 -400.78198) (xy 325.642676 -400.767272)
			(xy 325.703694 -400.759866) (xy 325.734426 -400.759422) (xy 325.765122 -400.759897) (xy 325.826067 -400.767299)
			(xy 325.885676 -400.78199) (xy 325.94308 -400.803758) (xy 325.997443 -400.832284) (xy 326.02297 -400.849338)
			(xy 326.031722 -400.854809) (xy 326.051926 -400.858937) (xy 326.07213 -400.854809) (xy 326.080882 -400.849338)
			(xy 326.106429 -400.832317) (xy 326.160794 -400.803805) (xy 326.218194 -400.782038) (xy 326.277795 -400.767334)
			(xy 326.338732 -400.759905) (xy 326.369426 -400.759422) (xy 326.400122 -400.759897) (xy 326.461067 -400.767299)
			(xy 326.520676 -400.78199) (xy 326.57808 -400.803758) (xy 326.632443 -400.832284) (xy 326.65797 -400.849338)
			(xy 326.666722 -400.854809) (xy 326.686926 -400.858937) (xy 326.70713 -400.854809) (xy 326.715882 -400.849338)
			(xy 326.741429 -400.832317) (xy 326.795794 -400.803805) (xy 326.853194 -400.782038) (xy 326.912795 -400.767334)
			(xy 326.973732 -400.759905) (xy 327.004426 -400.759422) (xy 327.025508 -400.75993) (xy 327.03643 -400.760438)
			(xy 327.055988 -400.752818) (xy 327.124314 -400.684492) (xy 327.131934 -400.664934) (xy 327.131426 -400.654012)
			(xy 327.130918 -400.63293) (xy 327.131372 -400.602233) (xy 327.138778 -400.541287) (xy 327.153475 -400.481678)
			(xy 327.175247 -400.424275) (xy 327.203778 -400.369913) (xy 327.220834 -400.344386) (xy 327.226278 -400.33562)
			(xy 327.230412 -400.315425) (xy 327.226297 -400.295226) (xy 327.220834 -400.286474) (xy 327.203794 -400.260939)
			(xy 327.175285 -400.206571) (xy 327.153522 -400.149168) (xy 327.138822 -400.089564) (xy 327.131398 -400.028625)
			(xy 327.130918 -399.99793) (xy 327.131521 -399.964696) (xy 327.14019 -399.898797) (xy 327.157371 -399.834588)
			(xy 327.182771 -399.773165) (xy 327.215957 -399.715575) (xy 327.256364 -399.6628) (xy 327.303303 -399.615739)
			(xy 327.355972 -399.575195) (xy 327.413475 -399.541859) (xy 327.474832 -399.516298) (xy 327.538995 -399.49895)
			(xy 327.571862 -399.493994) (xy 327.583292 -399.49247) (xy 327.601834 -399.480532) (xy 327.655682 -399.395188)
			(xy 327.658476 -399.373344) (xy 327.65492 -399.362168) (xy 327.643621 -399.324435) (xy 327.631505 -399.24661)
			(xy 327.63079 -399.207228) (xy 327.631264 -399.176497) (xy 327.638669 -399.115481) (xy 327.653376 -399.055804)
			(xy 327.675168 -398.998334) (xy 327.703729 -398.94391) (xy 327.738642 -398.893326) (xy 327.779398 -398.847319)
			(xy 327.825403 -398.806561) (xy 327.875985 -398.771645) (xy 327.930407 -398.74308) (xy 327.987875 -398.721284)
			(xy 328.047552 -398.706575) (xy 328.108567 -398.699166) (xy 328.139298 -398.69872) (xy 328.169995 -398.699159)
			(xy 328.230942 -398.706569) (xy 328.290551 -398.721269) (xy 328.347954 -398.743044) (xy 328.402316 -398.771579)
			(xy 328.427842 -398.788636) (xy 328.436594 -398.794107) (xy 328.456798 -398.798235) (xy 328.477002 -398.794107)
			(xy 328.485754 -398.788636) (xy 328.511281 -398.771584) (xy 328.565652 -398.743077) (xy 328.623057 -398.721317)
			(xy 328.682662 -398.706619) (xy 328.743603 -398.699199) (xy 328.774298 -398.69872) (xy 328.805031 -398.69914)
			(xy 328.866049 -398.706549) (xy 328.925729 -398.721259) (xy 328.983201 -398.743056) (xy 329.037626 -398.771621)
			(xy 329.088212 -398.806539) (xy 329.134219 -398.8473) (xy 329.174977 -398.893309) (xy 329.209892 -398.943896)
			(xy 329.238455 -398.998323) (xy 329.260249 -399.055795) (xy 329.274956 -399.115476) (xy 329.282362 -399.176495)
			(xy 329.282806 -399.207228) (xy 329.282236 -399.242074) (xy 329.272721 -399.311114) (xy 329.253871 -399.378209)
			(xy 329.226041 -399.442103) (xy 329.208384 -399.47215) (xy 329.203304 -399.480278) (xy 329.200002 -399.498058)
			(xy 329.21448 -399.582386) (xy 329.223624 -399.59788) (xy 329.230736 -399.603976) (xy 329.255363 -399.62474)
			(xy 329.299742 -399.67143) (xy 329.337874 -399.723347) (xy 329.369147 -399.779663) (xy 329.393063 -399.839475)
			(xy 329.409239 -399.901827) (xy 329.417415 -399.965722) (xy 329.417934 -399.99793) (xy 329.417451 -400.028626)
			(xy 329.41005 -400.08957) (xy 329.39536 -400.149179) (xy 329.373594 -400.206583) (xy 329.34507 -400.260946)
			(xy 329.328018 -400.286474) (xy 329.322519 -400.295211) (xy 329.318397 -400.315425) (xy 329.322538 -400.335634)
			(xy 329.328018 -400.344386) (xy 329.345035 -400.369936) (xy 329.37355 -400.424299) (xy 329.395317 -400.481699)
			(xy 329.410022 -400.541299) (xy 329.417451 -400.602236) (xy 329.417934 -400.63293) (xy 329.417472 -400.663661)
			(xy 329.410061 -400.724673) (xy 329.39535 -400.784348) (xy 329.373553 -400.841815) (xy 329.344989 -400.896235)
			(xy 329.310074 -400.946816) (xy 329.269318 -400.992821) (xy 329.223313 -401.033577) (xy 329.172732 -401.068491)
			(xy 329.118311 -401.097055) (xy 329.060844 -401.118851) (xy 329.00117 -401.133561) (xy 328.940157 -401.140972)
			(xy 328.909426 -401.141438) (xy 328.888344 -401.14093) (xy 328.877422 -401.140422) (xy 328.857864 -401.148042)
			(xy 328.789538 -401.216368) (xy 328.781918 -401.235926) (xy 328.782426 -401.246848) (xy 328.782934 -401.26793)
			(xy 328.782451 -401.298626) (xy 328.77505 -401.35957) (xy 328.76036 -401.419179) (xy 328.738594 -401.476583)
			(xy 328.71007 -401.530946) (xy 328.693018 -401.556474) (xy 328.687519 -401.565211) (xy 328.683397 -401.585425)
			(xy 328.687538 -401.605634) (xy 328.693018 -401.614386) (xy 328.710035 -401.639936) (xy 328.73855 -401.694299)
			(xy 328.760317 -401.751699) (xy 328.775022 -401.811299) (xy 328.782451 -401.872236) (xy 328.782934 -401.90293)
			(xy 328.782472 -401.933661) (xy 328.775061 -401.994673) (xy 328.76035 -402.054348) (xy 328.738553 -402.111815)
			(xy 328.709989 -402.166235) (xy 328.675074 -402.216816) (xy 328.634318 -402.262821) (xy 328.588313 -402.303577)
			(xy 328.537732 -402.338491) (xy 328.483311 -402.367055) (xy 328.425844 -402.388851) (xy 328.36617 -402.403561)
			(xy 328.305157 -402.410972) (xy 328.274426 -402.411438) (xy 328.243729 -402.410977) (xy 328.182784 -402.40357)
			(xy 328.123176 -402.388875) (xy 328.065772 -402.367105) (xy 328.011409 -402.338576) (xy 327.985882 -402.321522)
			(xy 327.97713 -402.316051) (xy 327.956926 -402.311923) (xy 327.936722 -402.316051) (xy 327.92797 -402.321522)
			(xy 327.902433 -402.338559) (xy 327.848066 -402.36707) (xy 327.790663 -402.388833) (xy 327.73106 -402.403534)
			(xy 327.670121 -402.410958) (xy 327.639426 -402.411438) (xy 327.608729 -402.410977) (xy 327.547784 -402.40357)
			(xy 327.488176 -402.388875) (xy 327.430772 -402.367105) (xy 327.376409 -402.338576) (xy 327.350882 -402.321522)
			(xy 327.34213 -402.316051) (xy 327.321926 -402.311923) (xy 327.301722 -402.316051) (xy 327.29297 -402.321522)
			(xy 327.267433 -402.338559) (xy 327.213066 -402.36707) (xy 327.155663 -402.388833) (xy 327.09606 -402.403534)
			(xy 327.035121 -402.410958) (xy 327.004426 -402.411438) (xy 326.973729 -402.410977) (xy 326.912784 -402.40357)
			(xy 326.853176 -402.388875) (xy 326.795772 -402.367105) (xy 326.741409 -402.338576) (xy 326.715882 -402.321522)
			(xy 326.70713 -402.316051) (xy 326.686926 -402.311923) (xy 326.666722 -402.316051) (xy 326.65797 -402.321522)
			(xy 326.632433 -402.338559) (xy 326.578066 -402.36707) (xy 326.520663 -402.388833) (xy 326.46106 -402.403534)
			(xy 326.400121 -402.410958) (xy 326.369426 -402.411438) (xy 326.338729 -402.410977) (xy 326.277784 -402.40357)
			(xy 326.218176 -402.388875) (xy 326.160772 -402.367105) (xy 326.106409 -402.338576) (xy 326.080882 -402.321522)
			(xy 326.07213 -402.316051) (xy 326.051926 -402.311923) (xy 326.031722 -402.316051) (xy 326.02297 -402.321522)
			(xy 325.997433 -402.338559) (xy 325.943066 -402.36707) (xy 325.885663 -402.388833) (xy 325.82606 -402.403534)
			(xy 325.765121 -402.410958) (xy 325.734426 -402.411438) (xy 325.703697 -402.41092) (xy 325.642686 -402.403515)
			(xy 325.583012 -402.38881) (xy 325.525547 -402.367019) (xy 325.471126 -402.338461) (xy 325.420545 -402.303551)
			(xy 325.37454 -402.262799) (xy 325.333783 -402.216799) (xy 325.298868 -402.166222) (xy 325.270304 -402.111805)
			(xy 325.248507 -402.054341) (xy 325.233795 -401.994669) (xy 325.226384 -401.933659) (xy 325.225918 -401.90293)
			(xy 324.948674 -401.90293) (xy 324.948187 -401.903968) (xy 324.917414 -401.950481) (xy 324.880197 -401.992018)
			(xy 324.837329 -402.027693) (xy 324.789723 -402.056747) (xy 324.738394 -402.078559) (xy 324.684437 -402.092665)
			(xy 324.629 -402.098765) (xy 324.573266 -402.096728) (xy 324.518423 -402.086598) (xy 324.465639 -402.068591)
			(xy 324.416039 -402.04309) (xy 324.370681 -402.010639) (xy 324.330532 -401.97193) (xy 324.296446 -401.927787)
			(xy 324.26915 -401.879152) (xy 324.249227 -401.827061) (xy 324.237101 -401.772624) (xy 324.23303 -401.717002)
			(xy 323.545708 -401.717002) (xy 323.545708 -402.1709) (xy 323.545274 -402.193455) (xy 323.538729 -402.238089)
			(xy 323.52586 -402.281325) (xy 323.516752 -402.301964) (xy 323.51218 -402.31187) (xy 323.51218 -403.061678)
			(xy 323.512617 -403.071742) (xy 323.520349 -403.090328) (xy 323.527166 -403.097746) (xy 324.266814 -403.837394)
			(xy 324.274213 -403.844239) (xy 324.292811 -403.851969) (xy 324.302882 -403.85238)
		)
		(stroke
			(width 0)
			(type solid)
		)
		(fill yes)
		(layer "In13.Cu")
		(net "P0V9_CPU0_RT1_2A_2D")
	)
	(gr_poly
		(pts
			(xy 456.566524 -440.5884) (xy 456.578091 -440.587851) (xy 456.598882 -440.577712) (xy 456.613098 -440.559465)
			(xy 456.616054 -440.548268) (xy 456.637136 -440.45124) (xy 456.639019 -440.439927) (xy 456.633623 -440.417659)
			(xy 456.61909 -440.399946) (xy 456.608942 -440.394598) (xy 456.608688 -440.394344) (xy 456.514495 -440.350736)
			(xy 456.32923 -440.257076) (xy 456.147796 -440.156195) (xy 455.970475 -440.048248) (xy 455.797541 -439.933404)
			(xy 455.629263 -439.81184) (xy 455.465902 -439.683744) (xy 455.30771 -439.549317) (xy 455.154934 -439.408765)
			(xy 455.007811 -439.262307) (xy 454.866567 -439.110171) (xy 454.731423 -438.952591) (xy 454.602588 -438.789812)
			(xy 454.480262 -438.622088) (xy 454.364634 -438.449677) (xy 454.255884 -438.272847) (xy 454.154181 -438.091873)
			(xy 454.059681 -437.907035) (xy 453.972532 -437.718619) (xy 453.89287 -437.526919) (xy 453.820816 -437.332231)
			(xy 453.756483 -437.134856) (xy 453.699972 -436.935102) (xy 453.651368 -436.733278) (xy 453.610749 -436.529697)
			(xy 453.578177 -436.324674) (xy 453.553702 -436.118528) (xy 453.537362 -435.911578) (xy 453.529183 -435.704145)
			(xy 453.528684 -435.600348) (xy 453.529191 -435.496851) (xy 453.537316 -435.290017) (xy 453.553554 -435.083661)
			(xy 453.577881 -434.878102) (xy 453.610259 -434.673657) (xy 453.650639 -434.47064) (xy 453.698957 -434.269365)
			(xy 453.75514 -434.070142) (xy 453.819102 -433.873278) (xy 453.890742 -433.679077) (xy 453.969951 -433.487838)
			(xy 454.056608 -433.299857) (xy 454.150577 -433.115422) (xy 454.251714 -432.934819) (xy 454.359864 -432.758325)
			(xy 454.474859 -432.586213) (xy 454.596523 -432.418749) (xy 454.724667 -432.25619) (xy 454.859094 -432.098787)
			(xy 454.999597 -431.946783) (xy 455.14596 -431.800412) (xy 455.297955 -431.6599) (xy 455.45535 -431.525464)
			(xy 455.617902 -431.39731) (xy 455.785359 -431.275637) (xy 455.957464 -431.160631) (xy 456.133951 -431.052471)
			(xy 456.314549 -430.951323) (xy 456.498978 -430.857343) (xy 456.686954 -430.770676) (xy 456.878188 -430.691455)
			(xy 457.072385 -430.619803) (xy 457.269245 -430.55583) (xy 457.468465 -430.499636) (xy 457.669737 -430.451305)
			(xy 457.872751 -430.410914) (xy 458.077195 -430.378523) (xy 458.282753 -430.354184) (xy 458.489108 -430.337934)
			(xy 458.695941 -430.329797) (xy 458.799438 -430.32934) (xy 458.799946 -430.32934) (xy 458.903646 -430.329846)
			(xy 459.110886 -430.338006) (xy 459.317644 -430.354311) (xy 459.523601 -430.378736) (xy 459.728438 -430.411243)
			(xy 459.931838 -430.451782) (xy 460.133486 -430.500291) (xy 460.33307 -430.556693) (xy 460.53028 -430.620902)
			(xy 460.724813 -430.692819) (xy 460.916366 -430.772331) (xy 461.104644 -430.859317) (xy 461.289354 -430.953641)
			(xy 461.470211 -431.055158) (xy 461.646935 -431.163709) (xy 461.819253 -431.279129) (xy 461.986897 -431.401236)
			(xy 462.149609 -431.529843) (xy 462.307136 -431.664751) (xy 462.459234 -431.805751) (xy 462.605669 -431.952624)
			(xy 462.746214 -432.105144) (xy 462.88065 -432.263073) (xy 463.00877 -432.426168) (xy 463.130376 -432.594177)
			(xy 463.24528 -432.766839) (xy 463.353303 -432.943886) (xy 463.454279 -433.125046) (xy 463.54805 -433.310037)
			(xy 463.634473 -433.498574) (xy 463.67446 -433.594256) (xy 463.67446 -433.594764) (xy 463.679491 -433.605352)
			(xy 463.697124 -433.620755) (xy 463.719762 -433.626729) (xy 463.731356 -433.62499) (xy 463.829146 -433.605686)
			(xy 463.83321 -433.60467) (xy 463.843156 -433.601261) (xy 463.859337 -433.58787) (xy 463.868849 -433.569145)
			(xy 463.87004 -433.558696) (xy 463.87004 -415.904934) (xy 463.870367 -415.896656) (xy 463.875689 -415.880978)
			(xy 463.880454 -415.8742) (xy 463.885534 -415.867342) (xy 463.890868 -415.851848) (xy 463.890868 -408.086052)
			(xy 463.891299 -408.075985) (xy 463.899022 -408.05739) (xy 463.905854 -408.049984) (xy 466.986874 -404.968964)
			(xy 466.993718 -404.961565) (xy 467.001443 -404.942966) (xy 467.00186 -404.932896) (xy 467.00186 -376.167396)
			(xy 467.001435 -376.157327) (xy 466.993715 -376.138727) (xy 466.986874 -376.131328) (xy 466.29828 -375.442734)
			(xy 466.291168 -375.435368) (xy 466.272372 -375.427748) (xy 437.856376 -375.427748) (xy 437.846309 -375.428177)
			(xy 437.827715 -375.435903) (xy 437.820308 -375.442734) (xy 436.960772 -376.30227) (xy 436.953406 -376.309382)
			(xy 436.945786 -376.328178) (xy 436.945786 -382.342136) (xy 436.945851 -382.346145) (xy 436.947119 -382.354061)
			(xy 436.948326 -382.357884) (xy 436.955438 -382.379982) (xy 436.96001 -382.386332) (xy 437.015094 -382.463802)
			(xy 437.119139 -382.622917) (xy 437.215995 -382.786506) (xy 437.30547 -382.954246) (xy 437.387387 -383.125805)
			(xy 437.461583 -383.30084) (xy 437.494359 -383.388882) (xy 441.915547 -383.388882) (xy 441.919279 -383.335628)
			(xy 441.930398 -383.283415) (xy 441.948686 -383.233261) (xy 441.973787 -383.186146) (xy 442.005209 -383.14299)
			(xy 442.042341 -383.104634) (xy 442.063124 -383.08788) (xy 442.071895 -383.080327) (xy 442.082072 -383.059561)
			(xy 442.082682 -383.048002) (xy 442.082682 -382.967738) (xy 442.082096 -382.956172) (xy 442.071913 -382.9354)
			(xy 442.063124 -382.92786) (xy 442.042313 -382.911141) (xy 442.005185 -382.872782) (xy 441.973767 -382.829623)
			(xy 441.948671 -382.782505) (xy 441.930388 -382.73235) (xy 441.919274 -382.680135) (xy 441.915547 -382.626882)
			(xy 441.919279 -382.573628) (xy 441.930398 -382.521415) (xy 441.948686 -382.471261) (xy 441.973787 -382.424146)
			(xy 442.005209 -382.38099) (xy 442.042341 -382.342634) (xy 442.063124 -382.32588) (xy 442.071895 -382.318327)
			(xy 442.082072 -382.297561) (xy 442.082682 -382.286002) (xy 442.082682 -382.205738) (xy 442.082096 -382.194172)
			(xy 442.071913 -382.1734) (xy 442.063124 -382.16586) (xy 442.040626 -382.147685) (xy 442.000891 -382.105663)
			(xy 441.967953 -382.058125) (xy 441.942567 -382.00616) (xy 441.925314 -381.950959) (xy 441.91659 -381.893787)
			(xy 441.916058 -381.86487) (xy 441.916544 -381.837619) (xy 441.9243 -381.783671) (xy 441.939655 -381.731376)
			(xy 441.962297 -381.681799) (xy 441.991763 -381.635949) (xy 442.027454 -381.594758) (xy 442.068645 -381.559067)
			(xy 442.114495 -381.529601) (xy 442.164072 -381.506959) (xy 442.216367 -381.491604) (xy 442.270315 -381.483848)
			(xy 442.324817 -381.483848) (xy 442.378765 -381.491604) (xy 442.43106 -381.506959) (xy 442.480637 -381.529601)
			(xy 442.526487 -381.559067) (xy 442.567678 -381.594758) (xy 442.603369 -381.635949) (xy 442.632835 -381.681799)
			(xy 442.655477 -381.731376) (xy 442.670832 -381.783671) (xy 442.678588 -381.837619) (xy 442.679074 -381.86487)
			(xy 442.678544 -381.893787) (xy 442.669819 -381.950958) (xy 442.652564 -382.006157) (xy 442.627174 -382.058119)
			(xy 442.594232 -382.105653) (xy 442.554493 -382.14767) (xy 442.532008 -382.16586) (xy 442.52327 -382.173445)
			(xy 442.513073 -382.194186) (xy 442.51245 -382.205738) (xy 442.51245 -382.286002) (xy 442.513002 -382.297573)
			(xy 442.523208 -382.318345) (xy 442.532008 -382.32588) (xy 442.552763 -382.342668) (xy 442.589896 -382.381016)
			(xy 442.62132 -382.424166) (xy 442.646422 -382.471275) (xy 442.664711 -382.521424) (xy 442.675831 -382.573632)
			(xy 442.679563 -382.626882) (xy 442.675836 -382.680131) (xy 442.664721 -382.732341) (xy 442.646437 -382.782491)
			(xy 442.621339 -382.829603) (xy 442.589919 -382.872756) (xy 442.55279 -382.911107) (xy 442.532008 -382.92786)
			(xy 442.52327 -382.935445) (xy 442.513073 -382.956186) (xy 442.51245 -382.967738) (xy 442.51245 -383.048002)
			(xy 442.513002 -383.059573) (xy 442.523208 -383.080345) (xy 442.532008 -383.08788) (xy 442.552763 -383.104668)
			(xy 442.589896 -383.143016) (xy 442.62132 -383.186166) (xy 442.646422 -383.233275) (xy 442.664711 -383.283424)
			(xy 442.675831 -383.335632) (xy 442.679563 -383.388882) (xy 445.725547 -383.388882) (xy 445.729279 -383.335628)
			(xy 445.740398 -383.283415) (xy 445.758686 -383.233261) (xy 445.783787 -383.186146) (xy 445.815209 -383.14299)
			(xy 445.852341 -383.104634) (xy 445.873124 -383.08788) (xy 445.881895 -383.080327) (xy 445.892072 -383.059561)
			(xy 445.892682 -383.048002) (xy 445.892682 -382.967738) (xy 445.892096 -382.956172) (xy 445.881913 -382.9354)
			(xy 445.873124 -382.92786) (xy 445.852313 -382.911141) (xy 445.815185 -382.872782) (xy 445.783767 -382.829623)
			(xy 445.758671 -382.782505) (xy 445.740388 -382.73235) (xy 445.729274 -382.680135) (xy 445.725547 -382.626882)
			(xy 445.729279 -382.573628) (xy 445.740398 -382.521415) (xy 445.758686 -382.471261) (xy 445.783787 -382.424146)
			(xy 445.815209 -382.38099) (xy 445.852341 -382.342634) (xy 445.873124 -382.32588) (xy 445.881895 -382.318327)
			(xy 445.892072 -382.297561) (xy 445.892682 -382.286002) (xy 445.892682 -382.205738) (xy 445.892096 -382.194172)
			(xy 445.881913 -382.1734) (xy 445.873124 -382.16586) (xy 445.850626 -382.147685) (xy 445.810891 -382.105663)
			(xy 445.777953 -382.058125) (xy 445.752567 -382.00616) (xy 445.735314 -381.950959) (xy 445.72659 -381.893787)
			(xy 445.726058 -381.86487) (xy 445.726544 -381.837619) (xy 445.7343 -381.783671) (xy 445.749655 -381.731376)
			(xy 445.772297 -381.681799) (xy 445.801763 -381.635949) (xy 445.837454 -381.594758) (xy 445.878645 -381.559067)
			(xy 445.924495 -381.529601) (xy 445.974072 -381.506959) (xy 446.026367 -381.491604) (xy 446.080315 -381.483848)
			(xy 446.134817 -381.483848) (xy 446.188765 -381.491604) (xy 446.24106 -381.506959) (xy 446.290637 -381.529601)
			(xy 446.336487 -381.559067) (xy 446.377678 -381.594758) (xy 446.413369 -381.635949) (xy 446.442835 -381.681799)
			(xy 446.465477 -381.731376) (xy 446.480832 -381.783671) (xy 446.488588 -381.837619) (xy 446.489074 -381.86487)
			(xy 446.488544 -381.893787) (xy 446.479819 -381.950958) (xy 446.462564 -382.006157) (xy 446.437174 -382.058119)
			(xy 446.404232 -382.105653) (xy 446.364493 -382.14767) (xy 446.342008 -382.16586) (xy 446.33327 -382.173445)
			(xy 446.323073 -382.194186) (xy 446.32245 -382.205738) (xy 446.32245 -382.286002) (xy 446.323002 -382.297573)
			(xy 446.333208 -382.318345) (xy 446.342008 -382.32588) (xy 446.362763 -382.342668) (xy 446.399896 -382.381016)
			(xy 446.43132 -382.424166) (xy 446.456422 -382.471275) (xy 446.474711 -382.521424) (xy 446.485831 -382.573632)
			(xy 446.489563 -382.626882) (xy 446.485836 -382.680131) (xy 446.474721 -382.732341) (xy 446.456437 -382.782491)
			(xy 446.431339 -382.829603) (xy 446.399919 -382.872756) (xy 446.36279 -382.911107) (xy 446.342008 -382.92786)
			(xy 446.33327 -382.935445) (xy 446.323073 -382.956186) (xy 446.32245 -382.967738) (xy 446.32245 -383.048002)
			(xy 446.323002 -383.059573) (xy 446.333208 -383.080345) (xy 446.342008 -383.08788) (xy 446.362763 -383.104668)
			(xy 446.399896 -383.143016) (xy 446.43132 -383.186166) (xy 446.456422 -383.233275) (xy 446.474711 -383.283424)
			(xy 446.485831 -383.335632) (xy 446.489563 -383.388882) (xy 447.681347 -383.388882) (xy 447.685079 -383.335628)
			(xy 447.696198 -383.283415) (xy 447.714486 -383.233261) (xy 447.739587 -383.186146) (xy 447.771009 -383.14299)
			(xy 447.808141 -383.104634) (xy 447.828924 -383.08788) (xy 447.837695 -383.080327) (xy 447.847872 -383.059561)
			(xy 447.848482 -383.048002) (xy 447.848482 -382.967738) (xy 447.847896 -382.956172) (xy 447.837713 -382.9354)
			(xy 447.828924 -382.92786) (xy 447.808113 -382.911141) (xy 447.770985 -382.872782) (xy 447.739567 -382.829623)
			(xy 447.714471 -382.782505) (xy 447.696188 -382.73235) (xy 447.685074 -382.680135) (xy 447.681347 -382.626882)
			(xy 447.685079 -382.573628) (xy 447.696198 -382.521415) (xy 447.714486 -382.471261) (xy 447.739587 -382.424146)
			(xy 447.771009 -382.38099) (xy 447.808141 -382.342634) (xy 447.828924 -382.32588) (xy 447.837695 -382.318327)
			(xy 447.847872 -382.297561) (xy 447.848482 -382.286002) (xy 447.848482 -382.205738) (xy 447.847896 -382.194172)
			(xy 447.837713 -382.1734) (xy 447.828924 -382.16586) (xy 447.806426 -382.147685) (xy 447.766691 -382.105663)
			(xy 447.733753 -382.058125) (xy 447.708367 -382.00616) (xy 447.691114 -381.950959) (xy 447.68239 -381.893787)
			(xy 447.681858 -381.86487) (xy 447.682344 -381.837619) (xy 447.6901 -381.783671) (xy 447.705455 -381.731376)
			(xy 447.728097 -381.681799) (xy 447.757563 -381.635949) (xy 447.793254 -381.594758) (xy 447.834445 -381.559067)
			(xy 447.880295 -381.529601) (xy 447.929872 -381.506959) (xy 447.982167 -381.491604) (xy 448.036115 -381.483848)
			(xy 448.090617 -381.483848) (xy 448.144565 -381.491604) (xy 448.19686 -381.506959) (xy 448.246437 -381.529601)
			(xy 448.292287 -381.559067) (xy 448.333478 -381.594758) (xy 448.369169 -381.635949) (xy 448.398635 -381.681799)
			(xy 448.421277 -381.731376) (xy 448.436632 -381.783671) (xy 448.444388 -381.837619) (xy 448.444874 -381.86487)
			(xy 448.444344 -381.893787) (xy 448.435619 -381.950958) (xy 448.418364 -382.006157) (xy 448.392974 -382.058119)
			(xy 448.360032 -382.105653) (xy 448.320293 -382.14767) (xy 448.297808 -382.16586) (xy 448.28907 -382.173445)
			(xy 448.278873 -382.194186) (xy 448.27825 -382.205738) (xy 448.27825 -382.286002) (xy 448.278802 -382.297573)
			(xy 448.289008 -382.318345) (xy 448.297808 -382.32588) (xy 448.318563 -382.342668) (xy 448.355696 -382.381016)
			(xy 448.38712 -382.424166) (xy 448.412222 -382.471275) (xy 448.430511 -382.521424) (xy 448.441631 -382.573632)
			(xy 448.445363 -382.626882) (xy 448.441636 -382.680131) (xy 448.430521 -382.732341) (xy 448.412237 -382.782491)
			(xy 448.387139 -382.829603) (xy 448.355719 -382.872756) (xy 448.31859 -382.911107) (xy 448.297808 -382.92786)
			(xy 448.28907 -382.935445) (xy 448.278873 -382.956186) (xy 448.27825 -382.967738) (xy 448.27825 -383.048002)
			(xy 448.278802 -383.059573) (xy 448.289008 -383.080345) (xy 448.297808 -383.08788) (xy 448.318563 -383.104668)
			(xy 448.355696 -383.143016) (xy 448.38712 -383.186166) (xy 448.412222 -383.233275) (xy 448.430511 -383.283424)
			(xy 448.441631 -383.335632) (xy 448.445363 -383.388882) (xy 451.491347 -383.388882) (xy 451.495079 -383.335628)
			(xy 451.506198 -383.283415) (xy 451.524486 -383.233261) (xy 451.549587 -383.186146) (xy 451.581009 -383.14299)
			(xy 451.618141 -383.104634) (xy 451.638924 -383.08788) (xy 451.647695 -383.080327) (xy 451.657872 -383.059561)
			(xy 451.658482 -383.048002) (xy 451.658482 -382.967738) (xy 451.657896 -382.956172) (xy 451.647713 -382.9354)
			(xy 451.638924 -382.92786) (xy 451.618113 -382.911141) (xy 451.580985 -382.872782) (xy 451.549567 -382.829623)
			(xy 451.524471 -382.782505) (xy 451.506188 -382.73235) (xy 451.495074 -382.680135) (xy 451.491347 -382.626882)
			(xy 451.495079 -382.573628) (xy 451.506198 -382.521415) (xy 451.524486 -382.471261) (xy 451.549587 -382.424146)
			(xy 451.581009 -382.38099) (xy 451.618141 -382.342634) (xy 451.638924 -382.32588) (xy 451.647695 -382.318327)
			(xy 451.657872 -382.297561) (xy 451.658482 -382.286002) (xy 451.658482 -382.205738) (xy 451.657896 -382.194172)
			(xy 451.647713 -382.1734) (xy 451.638924 -382.16586) (xy 451.616426 -382.147685) (xy 451.576691 -382.105663)
			(xy 451.543753 -382.058125) (xy 451.518367 -382.00616) (xy 451.501114 -381.950959) (xy 451.49239 -381.893787)
			(xy 451.491858 -381.86487) (xy 451.492344 -381.837619) (xy 451.5001 -381.783671) (xy 451.515455 -381.731376)
			(xy 451.538097 -381.681799) (xy 451.567563 -381.635949) (xy 451.603254 -381.594758) (xy 451.644445 -381.559067)
			(xy 451.690295 -381.529601) (xy 451.739872 -381.506959) (xy 451.792167 -381.491604) (xy 451.846115 -381.483848)
			(xy 451.900617 -381.483848) (xy 451.954565 -381.491604) (xy 452.00686 -381.506959) (xy 452.056437 -381.529601)
			(xy 452.102287 -381.559067) (xy 452.143478 -381.594758) (xy 452.179169 -381.635949) (xy 452.208635 -381.681799)
			(xy 452.231277 -381.731376) (xy 452.246632 -381.783671) (xy 452.254388 -381.837619) (xy 452.254874 -381.86487)
			(xy 452.254344 -381.893787) (xy 452.245619 -381.950958) (xy 452.228364 -382.006157) (xy 452.202974 -382.058119)
			(xy 452.170032 -382.105653) (xy 452.130293 -382.14767) (xy 452.107808 -382.16586) (xy 452.09907 -382.173445)
			(xy 452.088873 -382.194186) (xy 452.08825 -382.205738) (xy 452.08825 -382.286002) (xy 452.088802 -382.297573)
			(xy 452.099008 -382.318345) (xy 452.107808 -382.32588) (xy 452.128563 -382.342668) (xy 452.165696 -382.381016)
			(xy 452.19712 -382.424166) (xy 452.222222 -382.471275) (xy 452.240511 -382.521424) (xy 452.251631 -382.573632)
			(xy 452.255363 -382.626882) (xy 452.251636 -382.680131) (xy 452.240521 -382.732341) (xy 452.222237 -382.782491)
			(xy 452.197139 -382.829603) (xy 452.165719 -382.872756) (xy 452.12859 -382.911107) (xy 452.107808 -382.92786)
			(xy 452.09907 -382.935445) (xy 452.088873 -382.956186) (xy 452.08825 -382.967738) (xy 452.08825 -383.048002)
			(xy 452.088802 -383.059573) (xy 452.099008 -383.080345) (xy 452.107808 -383.08788) (xy 452.128563 -383.104668)
			(xy 452.165696 -383.143016) (xy 452.19712 -383.186166) (xy 452.222222 -383.233275) (xy 452.240511 -383.283424)
			(xy 452.251631 -383.335632) (xy 452.255363 -383.388882) (xy 453.777347 -383.388882) (xy 453.781079 -383.335628)
			(xy 453.792198 -383.283415) (xy 453.810486 -383.233261) (xy 453.835587 -383.186146) (xy 453.867009 -383.14299)
			(xy 453.904141 -383.104634) (xy 453.924924 -383.08788) (xy 453.933695 -383.080327) (xy 453.943872 -383.059561)
			(xy 453.944482 -383.048002) (xy 453.944482 -382.967738) (xy 453.943896 -382.956172) (xy 453.933713 -382.9354)
			(xy 453.924924 -382.92786) (xy 453.904113 -382.911141) (xy 453.866985 -382.872782) (xy 453.835567 -382.829623)
			(xy 453.810471 -382.782505) (xy 453.792188 -382.73235) (xy 453.781074 -382.680135) (xy 453.777347 -382.626882)
			(xy 453.781079 -382.573628) (xy 453.792198 -382.521415) (xy 453.810486 -382.471261) (xy 453.835587 -382.424146)
			(xy 453.867009 -382.38099) (xy 453.904141 -382.342634) (xy 453.924924 -382.32588) (xy 453.933695 -382.318327)
			(xy 453.943872 -382.297561) (xy 453.944482 -382.286002) (xy 453.944482 -382.205738) (xy 453.943896 -382.194172)
			(xy 453.933713 -382.1734) (xy 453.924924 -382.16586) (xy 453.902426 -382.147685) (xy 453.862691 -382.105663)
			(xy 453.829753 -382.058125) (xy 453.804367 -382.00616) (xy 453.787114 -381.950959) (xy 453.77839 -381.893787)
			(xy 453.777858 -381.86487) (xy 453.778344 -381.837619) (xy 453.7861 -381.783671) (xy 453.801455 -381.731376)
			(xy 453.824097 -381.681799) (xy 453.853563 -381.635949) (xy 453.889254 -381.594758) (xy 453.930445 -381.559067)
			(xy 453.976295 -381.529601) (xy 454.025872 -381.506959) (xy 454.078167 -381.491604) (xy 454.132115 -381.483848)
			(xy 454.186617 -381.483848) (xy 454.240565 -381.491604) (xy 454.29286 -381.506959) (xy 454.342437 -381.529601)
			(xy 454.388287 -381.559067) (xy 454.429478 -381.594758) (xy 454.465169 -381.635949) (xy 454.494635 -381.681799)
			(xy 454.517277 -381.731376) (xy 454.532632 -381.783671) (xy 454.540388 -381.837619) (xy 454.540874 -381.86487)
			(xy 454.540344 -381.893787) (xy 454.531619 -381.950958) (xy 454.514364 -382.006157) (xy 454.488974 -382.058119)
			(xy 454.456032 -382.105653) (xy 454.416293 -382.14767) (xy 454.393808 -382.16586) (xy 454.38507 -382.173445)
			(xy 454.374873 -382.194186) (xy 454.37425 -382.205738) (xy 454.37425 -382.286002) (xy 454.374802 -382.297573)
			(xy 454.385008 -382.318345) (xy 454.393808 -382.32588) (xy 454.414563 -382.342668) (xy 454.451696 -382.381016)
			(xy 454.48312 -382.424166) (xy 454.508222 -382.471275) (xy 454.526511 -382.521424) (xy 454.537631 -382.573632)
			(xy 454.541363 -382.626882) (xy 454.537636 -382.680131) (xy 454.526521 -382.732341) (xy 454.508237 -382.782491)
			(xy 454.483139 -382.829603) (xy 454.451719 -382.872756) (xy 454.41459 -382.911107) (xy 454.393808 -382.92786)
			(xy 454.38507 -382.935445) (xy 454.374873 -382.956186) (xy 454.37425 -382.967738) (xy 454.37425 -383.048002)
			(xy 454.374802 -383.059573) (xy 454.385008 -383.080345) (xy 454.393808 -383.08788) (xy 454.414563 -383.104668)
			(xy 454.451696 -383.143016) (xy 454.48312 -383.186166) (xy 454.508222 -383.233275) (xy 454.526511 -383.283424)
			(xy 454.537631 -383.335632) (xy 454.541363 -383.388882) (xy 457.587347 -383.388882) (xy 457.591079 -383.335628)
			(xy 457.602198 -383.283415) (xy 457.620486 -383.233261) (xy 457.645587 -383.186146) (xy 457.677009 -383.14299)
			(xy 457.714141 -383.104634) (xy 457.734924 -383.08788) (xy 457.743695 -383.080327) (xy 457.753872 -383.059561)
			(xy 457.754482 -383.048002) (xy 457.754482 -382.967738) (xy 457.753896 -382.956172) (xy 457.743713 -382.9354)
			(xy 457.734924 -382.92786) (xy 457.714113 -382.911141) (xy 457.676985 -382.872782) (xy 457.645567 -382.829623)
			(xy 457.620471 -382.782505) (xy 457.602188 -382.73235) (xy 457.591074 -382.680135) (xy 457.587347 -382.626882)
			(xy 457.591079 -382.573628) (xy 457.602198 -382.521415) (xy 457.620486 -382.471261) (xy 457.645587 -382.424146)
			(xy 457.677009 -382.38099) (xy 457.714141 -382.342634) (xy 457.734924 -382.32588) (xy 457.743695 -382.318327)
			(xy 457.753872 -382.297561) (xy 457.754482 -382.286002) (xy 457.754482 -382.205738) (xy 457.753896 -382.194172)
			(xy 457.743713 -382.1734) (xy 457.734924 -382.16586) (xy 457.712426 -382.147685) (xy 457.672691 -382.105663)
			(xy 457.639753 -382.058125) (xy 457.614367 -382.00616) (xy 457.597114 -381.950959) (xy 457.58839 -381.893787)
			(xy 457.587858 -381.86487) (xy 457.588344 -381.837619) (xy 457.5961 -381.783671) (xy 457.611455 -381.731376)
			(xy 457.634097 -381.681799) (xy 457.663563 -381.635949) (xy 457.699254 -381.594758) (xy 457.740445 -381.559067)
			(xy 457.786295 -381.529601) (xy 457.835872 -381.506959) (xy 457.888167 -381.491604) (xy 457.942115 -381.483848)
			(xy 457.996617 -381.483848) (xy 458.050565 -381.491604) (xy 458.10286 -381.506959) (xy 458.152437 -381.529601)
			(xy 458.198287 -381.559067) (xy 458.239478 -381.594758) (xy 458.275169 -381.635949) (xy 458.304635 -381.681799)
			(xy 458.327277 -381.731376) (xy 458.342632 -381.783671) (xy 458.350388 -381.837619) (xy 458.350874 -381.86487)
			(xy 458.350344 -381.893787) (xy 458.341619 -381.950958) (xy 458.324364 -382.006157) (xy 458.298974 -382.058119)
			(xy 458.266032 -382.105653) (xy 458.226293 -382.14767) (xy 458.203808 -382.16586) (xy 458.19507 -382.173445)
			(xy 458.184873 -382.194186) (xy 458.18425 -382.205738) (xy 458.18425 -382.286002) (xy 458.184802 -382.297573)
			(xy 458.195008 -382.318345) (xy 458.203808 -382.32588) (xy 458.224563 -382.342668) (xy 458.261696 -382.381016)
			(xy 458.29312 -382.424166) (xy 458.318222 -382.471275) (xy 458.336511 -382.521424) (xy 458.347631 -382.573632)
			(xy 458.351363 -382.626882) (xy 458.347636 -382.680131) (xy 458.336521 -382.732341) (xy 458.318237 -382.782491)
			(xy 458.293139 -382.829603) (xy 458.261719 -382.872756) (xy 458.22459 -382.911107) (xy 458.203808 -382.92786)
			(xy 458.19507 -382.935445) (xy 458.184873 -382.956186) (xy 458.18425 -382.967738) (xy 458.18425 -383.048002)
			(xy 458.184802 -383.059573) (xy 458.195008 -383.080345) (xy 458.203808 -383.08788) (xy 458.224563 -383.104668)
			(xy 458.261696 -383.143016) (xy 458.29312 -383.186166) (xy 458.318222 -383.233275) (xy 458.336511 -383.283424)
			(xy 458.347631 -383.335632) (xy 458.351363 -383.388882) (xy 459.873347 -383.388882) (xy 459.877079 -383.335628)
			(xy 459.888198 -383.283415) (xy 459.906486 -383.233261) (xy 459.931587 -383.186146) (xy 459.963009 -383.14299)
			(xy 460.000141 -383.104634) (xy 460.020924 -383.08788) (xy 460.029695 -383.080327) (xy 460.039872 -383.059561)
			(xy 460.040482 -383.048002) (xy 460.040482 -382.967738) (xy 460.039896 -382.956172) (xy 460.029713 -382.9354)
			(xy 460.020924 -382.92786) (xy 460.000113 -382.911141) (xy 459.962985 -382.872782) (xy 459.931567 -382.829623)
			(xy 459.906471 -382.782505) (xy 459.888188 -382.73235) (xy 459.877074 -382.680135) (xy 459.873347 -382.626882)
			(xy 459.877079 -382.573628) (xy 459.888198 -382.521415) (xy 459.906486 -382.471261) (xy 459.931587 -382.424146)
			(xy 459.963009 -382.38099) (xy 460.000141 -382.342634) (xy 460.020924 -382.32588) (xy 460.029695 -382.318327)
			(xy 460.039872 -382.297561) (xy 460.040482 -382.286002) (xy 460.040482 -382.205738) (xy 460.039896 -382.194172)
			(xy 460.029713 -382.1734) (xy 460.020924 -382.16586) (xy 459.998426 -382.147685) (xy 459.958691 -382.105663)
			(xy 459.925753 -382.058125) (xy 459.900367 -382.00616) (xy 459.883114 -381.950959) (xy 459.87439 -381.893787)
			(xy 459.873858 -381.86487) (xy 459.874344 -381.837619) (xy 459.8821 -381.783671) (xy 459.897455 -381.731376)
			(xy 459.920097 -381.681799) (xy 459.949563 -381.635949) (xy 459.985254 -381.594758) (xy 460.026445 -381.559067)
			(xy 460.072295 -381.529601) (xy 460.121872 -381.506959) (xy 460.174167 -381.491604) (xy 460.228115 -381.483848)
			(xy 460.282617 -381.483848) (xy 460.336565 -381.491604) (xy 460.38886 -381.506959) (xy 460.438437 -381.529601)
			(xy 460.484287 -381.559067) (xy 460.525478 -381.594758) (xy 460.561169 -381.635949) (xy 460.590635 -381.681799)
			(xy 460.613277 -381.731376) (xy 460.628632 -381.783671) (xy 460.636388 -381.837619) (xy 460.636874 -381.86487)
			(xy 460.636344 -381.893787) (xy 460.627619 -381.950958) (xy 460.610364 -382.006157) (xy 460.584974 -382.058119)
			(xy 460.552032 -382.105653) (xy 460.512293 -382.14767) (xy 460.489808 -382.16586) (xy 460.48107 -382.173445)
			(xy 460.470873 -382.194186) (xy 460.47025 -382.205738) (xy 460.47025 -382.286002) (xy 460.470802 -382.297573)
			(xy 460.481008 -382.318345) (xy 460.489808 -382.32588) (xy 460.510563 -382.342668) (xy 460.547696 -382.381016)
			(xy 460.57912 -382.424166) (xy 460.604222 -382.471275) (xy 460.622511 -382.521424) (xy 460.633631 -382.573632)
			(xy 460.637363 -382.626882) (xy 460.633636 -382.680131) (xy 460.622521 -382.732341) (xy 460.604237 -382.782491)
			(xy 460.579139 -382.829603) (xy 460.547719 -382.872756) (xy 460.51059 -382.911107) (xy 460.489808 -382.92786)
			(xy 460.48107 -382.935445) (xy 460.470873 -382.956186) (xy 460.47025 -382.967738) (xy 460.47025 -383.048002)
			(xy 460.470802 -383.059573) (xy 460.481008 -383.080345) (xy 460.489808 -383.08788) (xy 460.510563 -383.104668)
			(xy 460.547696 -383.143016) (xy 460.57912 -383.186166) (xy 460.604222 -383.233275) (xy 460.622511 -383.283424)
			(xy 460.633631 -383.335632) (xy 460.637363 -383.388882) (xy 463.683347 -383.388882) (xy 463.687079 -383.335628)
			(xy 463.698198 -383.283415) (xy 463.716486 -383.233261) (xy 463.741587 -383.186146) (xy 463.773009 -383.14299)
			(xy 463.810141 -383.104634) (xy 463.830924 -383.08788) (xy 463.839695 -383.080327) (xy 463.849872 -383.059561)
			(xy 463.850482 -383.048002) (xy 463.850482 -382.967738) (xy 463.849896 -382.956172) (xy 463.839713 -382.9354)
			(xy 463.830924 -382.92786) (xy 463.810113 -382.911141) (xy 463.772985 -382.872782) (xy 463.741567 -382.829623)
			(xy 463.716471 -382.782505) (xy 463.698188 -382.73235) (xy 463.687074 -382.680135) (xy 463.683347 -382.626882)
			(xy 463.687079 -382.573628) (xy 463.698198 -382.521415) (xy 463.716486 -382.471261) (xy 463.741587 -382.424146)
			(xy 463.773009 -382.38099) (xy 463.810141 -382.342634) (xy 463.830924 -382.32588) (xy 463.839695 -382.318327)
			(xy 463.849872 -382.297561) (xy 463.850482 -382.286002) (xy 463.850482 -382.205738) (xy 463.849896 -382.194172)
			(xy 463.839713 -382.1734) (xy 463.830924 -382.16586) (xy 463.808426 -382.147685) (xy 463.768691 -382.105663)
			(xy 463.735753 -382.058125) (xy 463.710367 -382.00616) (xy 463.693114 -381.950959) (xy 463.68439 -381.893787)
			(xy 463.683858 -381.86487) (xy 463.684344 -381.837619) (xy 463.6921 -381.783671) (xy 463.707455 -381.731376)
			(xy 463.730097 -381.681799) (xy 463.759563 -381.635949) (xy 463.795254 -381.594758) (xy 463.836445 -381.559067)
			(xy 463.882295 -381.529601) (xy 463.931872 -381.506959) (xy 463.984167 -381.491604) (xy 464.038115 -381.483848)
			(xy 464.092617 -381.483848) (xy 464.146565 -381.491604) (xy 464.19886 -381.506959) (xy 464.248437 -381.529601)
			(xy 464.294287 -381.559067) (xy 464.335478 -381.594758) (xy 464.371169 -381.635949) (xy 464.400635 -381.681799)
			(xy 464.423277 -381.731376) (xy 464.438632 -381.783671) (xy 464.446388 -381.837619) (xy 464.446874 -381.86487)
			(xy 464.446344 -381.893787) (xy 464.437619 -381.950958) (xy 464.420364 -382.006157) (xy 464.394974 -382.058119)
			(xy 464.362032 -382.105653) (xy 464.322293 -382.14767) (xy 464.299808 -382.16586) (xy 464.29107 -382.173445)
			(xy 464.280873 -382.194186) (xy 464.28025 -382.205738) (xy 464.28025 -382.286002) (xy 464.280802 -382.297573)
			(xy 464.291008 -382.318345) (xy 464.299808 -382.32588) (xy 464.320563 -382.342668) (xy 464.357696 -382.381016)
			(xy 464.38912 -382.424166) (xy 464.414222 -382.471275) (xy 464.432511 -382.521424) (xy 464.443631 -382.573632)
			(xy 464.447363 -382.626882) (xy 464.443636 -382.680131) (xy 464.432521 -382.732341) (xy 464.414237 -382.782491)
			(xy 464.389139 -382.829603) (xy 464.357719 -382.872756) (xy 464.32059 -382.911107) (xy 464.299808 -382.92786)
			(xy 464.29107 -382.935445) (xy 464.280873 -382.956186) (xy 464.28025 -382.967738) (xy 464.28025 -383.048002)
			(xy 464.280802 -383.059573) (xy 464.291008 -383.080345) (xy 464.299808 -383.08788) (xy 464.320563 -383.104668)
			(xy 464.357696 -383.143016) (xy 464.38912 -383.186166) (xy 464.414222 -383.233275) (xy 464.432511 -383.283424)
			(xy 464.443631 -383.335632) (xy 464.447363 -383.388882) (xy 464.443636 -383.442131) (xy 464.432521 -383.494341)
			(xy 464.414237 -383.544491) (xy 464.389139 -383.591603) (xy 464.357719 -383.634756) (xy 464.32059 -383.673107)
			(xy 464.299808 -383.68986) (xy 464.29107 -383.697445) (xy 464.280873 -383.718186) (xy 464.28025 -383.729738)
			(xy 464.28025 -383.810002) (xy 464.280802 -383.821573) (xy 464.291008 -383.842345) (xy 464.299808 -383.84988)
			(xy 464.322284 -383.86808) (xy 464.362019 -383.910098) (xy 464.394959 -383.957631) (xy 464.420348 -384.009591)
			(xy 464.437606 -384.064787) (xy 464.446338 -384.121955) (xy 464.446874 -384.15087) (xy 464.446388 -384.178121)
			(xy 464.438632 -384.232069) (xy 464.423277 -384.284364) (xy 464.400635 -384.333941) (xy 464.371169 -384.379791)
			(xy 464.335478 -384.420982) (xy 464.294287 -384.456673) (xy 464.248437 -384.486139) (xy 464.19886 -384.508781)
			(xy 464.146565 -384.524136) (xy 464.092617 -384.531892) (xy 464.038115 -384.531892) (xy 463.984167 -384.524136)
			(xy 463.931872 -384.508781) (xy 463.882295 -384.486139) (xy 463.836445 -384.456673) (xy 463.795254 -384.420982)
			(xy 463.759563 -384.379791) (xy 463.730097 -384.333941) (xy 463.707455 -384.284364) (xy 463.6921 -384.232069)
			(xy 463.684344 -384.178121) (xy 463.683858 -384.15087) (xy 463.684405 -384.121954) (xy 463.693125 -384.064783)
			(xy 463.710376 -384.009584) (xy 463.735762 -383.957622) (xy 463.768702 -383.910087) (xy 463.80844 -383.86807)
			(xy 463.830924 -383.84988) (xy 463.839695 -383.842327) (xy 463.849872 -383.821561) (xy 463.850482 -383.810002)
			(xy 463.850482 -383.729738) (xy 463.849896 -383.718172) (xy 463.839713 -383.6974) (xy 463.830924 -383.68986)
			(xy 463.810113 -383.673141) (xy 463.772985 -383.634782) (xy 463.741567 -383.591623) (xy 463.716471 -383.544505)
			(xy 463.698188 -383.49435) (xy 463.687074 -383.442135) (xy 463.683347 -383.388882) (xy 460.637363 -383.388882)
			(xy 460.633636 -383.442131) (xy 460.622521 -383.494341) (xy 460.604237 -383.544491) (xy 460.579139 -383.591603)
			(xy 460.547719 -383.634756) (xy 460.51059 -383.673107) (xy 460.489808 -383.68986) (xy 460.48107 -383.697445)
			(xy 460.470873 -383.718186) (xy 460.47025 -383.729738) (xy 460.47025 -383.810002) (xy 460.470802 -383.821573)
			(xy 460.481008 -383.842345) (xy 460.489808 -383.84988) (xy 460.512284 -383.86808) (xy 460.552019 -383.910098)
			(xy 460.584959 -383.957631) (xy 460.610348 -384.009591) (xy 460.627606 -384.064787) (xy 460.636338 -384.121955)
			(xy 460.636874 -384.15087) (xy 460.636388 -384.178121) (xy 460.628632 -384.232069) (xy 460.613277 -384.284364)
			(xy 460.590635 -384.333941) (xy 460.561169 -384.379791) (xy 460.525478 -384.420982) (xy 460.484287 -384.456673)
			(xy 460.438437 -384.486139) (xy 460.38886 -384.508781) (xy 460.336565 -384.524136) (xy 460.282617 -384.531892)
			(xy 460.228115 -384.531892) (xy 460.174167 -384.524136) (xy 460.121872 -384.508781) (xy 460.072295 -384.486139)
			(xy 460.026445 -384.456673) (xy 459.985254 -384.420982) (xy 459.949563 -384.379791) (xy 459.920097 -384.333941)
			(xy 459.897455 -384.284364) (xy 459.8821 -384.232069) (xy 459.874344 -384.178121) (xy 459.873858 -384.15087)
			(xy 459.874405 -384.121954) (xy 459.883125 -384.064783) (xy 459.900376 -384.009584) (xy 459.925762 -383.957622)
			(xy 459.958702 -383.910087) (xy 459.99844 -383.86807) (xy 460.020924 -383.84988) (xy 460.029695 -383.842327)
			(xy 460.039872 -383.821561) (xy 460.040482 -383.810002) (xy 460.040482 -383.729738) (xy 460.039896 -383.718172)
			(xy 460.029713 -383.6974) (xy 460.020924 -383.68986) (xy 460.000113 -383.673141) (xy 459.962985 -383.634782)
			(xy 459.931567 -383.591623) (xy 459.906471 -383.544505) (xy 459.888188 -383.49435) (xy 459.877074 -383.442135)
			(xy 459.873347 -383.388882) (xy 458.351363 -383.388882) (xy 458.347636 -383.442131) (xy 458.336521 -383.494341)
			(xy 458.318237 -383.544491) (xy 458.293139 -383.591603) (xy 458.261719 -383.634756) (xy 458.22459 -383.673107)
			(xy 458.203808 -383.68986) (xy 458.19507 -383.697445) (xy 458.184873 -383.718186) (xy 458.18425 -383.729738)
			(xy 458.18425 -383.810002) (xy 458.184802 -383.821573) (xy 458.195008 -383.842345) (xy 458.203808 -383.84988)
			(xy 458.226284 -383.86808) (xy 458.266019 -383.910098) (xy 458.298959 -383.957631) (xy 458.324348 -384.009591)
			(xy 458.341606 -384.064787) (xy 458.350338 -384.121955) (xy 458.350874 -384.15087) (xy 458.350388 -384.178121)
			(xy 458.342632 -384.232069) (xy 458.327277 -384.284364) (xy 458.304635 -384.333941) (xy 458.275169 -384.379791)
			(xy 458.239478 -384.420982) (xy 458.198287 -384.456673) (xy 458.152437 -384.486139) (xy 458.10286 -384.508781)
			(xy 458.050565 -384.524136) (xy 457.996617 -384.531892) (xy 457.942115 -384.531892) (xy 457.888167 -384.524136)
			(xy 457.835872 -384.508781) (xy 457.786295 -384.486139) (xy 457.740445 -384.456673) (xy 457.699254 -384.420982)
			(xy 457.663563 -384.379791) (xy 457.634097 -384.333941) (xy 457.611455 -384.284364) (xy 457.5961 -384.232069)
			(xy 457.588344 -384.178121) (xy 457.587858 -384.15087) (xy 457.588405 -384.121954) (xy 457.597125 -384.064783)
			(xy 457.614376 -384.009584) (xy 457.639762 -383.957622) (xy 457.672702 -383.910087) (xy 457.71244 -383.86807)
			(xy 457.734924 -383.84988) (xy 457.743695 -383.842327) (xy 457.753872 -383.821561) (xy 457.754482 -383.810002)
			(xy 457.754482 -383.729738) (xy 457.753896 -383.718172) (xy 457.743713 -383.6974) (xy 457.734924 -383.68986)
			(xy 457.714113 -383.673141) (xy 457.676985 -383.634782) (xy 457.645567 -383.591623) (xy 457.620471 -383.544505)
			(xy 457.602188 -383.49435) (xy 457.591074 -383.442135) (xy 457.587347 -383.388882) (xy 454.541363 -383.388882)
			(xy 454.537636 -383.442131) (xy 454.526521 -383.494341) (xy 454.508237 -383.544491) (xy 454.483139 -383.591603)
			(xy 454.451719 -383.634756) (xy 454.41459 -383.673107) (xy 454.393808 -383.68986) (xy 454.38507 -383.697445)
			(xy 454.374873 -383.718186) (xy 454.37425 -383.729738) (xy 454.37425 -383.810002) (xy 454.374802 -383.821573)
			(xy 454.385008 -383.842345) (xy 454.393808 -383.84988) (xy 454.416284 -383.86808) (xy 454.456019 -383.910098)
			(xy 454.488959 -383.957631) (xy 454.514348 -384.009591) (xy 454.531606 -384.064787) (xy 454.540338 -384.121955)
			(xy 454.540874 -384.15087) (xy 454.540388 -384.178121) (xy 454.532632 -384.232069) (xy 454.517277 -384.284364)
			(xy 454.494635 -384.333941) (xy 454.465169 -384.379791) (xy 454.429478 -384.420982) (xy 454.388287 -384.456673)
			(xy 454.342437 -384.486139) (xy 454.29286 -384.508781) (xy 454.240565 -384.524136) (xy 454.186617 -384.531892)
			(xy 454.132115 -384.531892) (xy 454.078167 -384.524136) (xy 454.025872 -384.508781) (xy 453.976295 -384.486139)
			(xy 453.930445 -384.456673) (xy 453.889254 -384.420982) (xy 453.853563 -384.379791) (xy 453.824097 -384.333941)
			(xy 453.801455 -384.284364) (xy 453.7861 -384.232069) (xy 453.778344 -384.178121) (xy 453.777858 -384.15087)
			(xy 453.778405 -384.121954) (xy 453.787125 -384.064783) (xy 453.804376 -384.009584) (xy 453.829762 -383.957622)
			(xy 453.862702 -383.910087) (xy 453.90244 -383.86807) (xy 453.924924 -383.84988) (xy 453.933695 -383.842327)
			(xy 453.943872 -383.821561) (xy 453.944482 -383.810002) (xy 453.944482 -383.729738) (xy 453.943896 -383.718172)
			(xy 453.933713 -383.6974) (xy 453.924924 -383.68986) (xy 453.904113 -383.673141) (xy 453.866985 -383.634782)
			(xy 453.835567 -383.591623) (xy 453.810471 -383.544505) (xy 453.792188 -383.49435) (xy 453.781074 -383.442135)
			(xy 453.777347 -383.388882) (xy 452.255363 -383.388882) (xy 452.251636 -383.442131) (xy 452.240521 -383.494341)
			(xy 452.222237 -383.544491) (xy 452.197139 -383.591603) (xy 452.165719 -383.634756) (xy 452.12859 -383.673107)
			(xy 452.107808 -383.68986) (xy 452.09907 -383.697445) (xy 452.088873 -383.718186) (xy 452.08825 -383.729738)
			(xy 452.08825 -383.810002) (xy 452.088802 -383.821573) (xy 452.099008 -383.842345) (xy 452.107808 -383.84988)
			(xy 452.130284 -383.86808) (xy 452.170019 -383.910098) (xy 452.202959 -383.957631) (xy 452.228348 -384.009591)
			(xy 452.245606 -384.064787) (xy 452.254338 -384.121955) (xy 452.254874 -384.15087) (xy 452.254388 -384.178121)
			(xy 452.246632 -384.232069) (xy 452.231277 -384.284364) (xy 452.208635 -384.333941) (xy 452.179169 -384.379791)
			(xy 452.143478 -384.420982) (xy 452.102287 -384.456673) (xy 452.056437 -384.486139) (xy 452.00686 -384.508781)
			(xy 451.954565 -384.524136) (xy 451.900617 -384.531892) (xy 451.846115 -384.531892) (xy 451.792167 -384.524136)
			(xy 451.739872 -384.508781) (xy 451.690295 -384.486139) (xy 451.644445 -384.456673) (xy 451.603254 -384.420982)
			(xy 451.567563 -384.379791) (xy 451.538097 -384.333941) (xy 451.515455 -384.284364) (xy 451.5001 -384.232069)
			(xy 451.492344 -384.178121) (xy 451.491858 -384.15087) (xy 451.492405 -384.121954) (xy 451.501125 -384.064783)
			(xy 451.518376 -384.009584) (xy 451.543762 -383.957622) (xy 451.576702 -383.910087) (xy 451.61644 -383.86807)
			(xy 451.638924 -383.84988) (xy 451.647695 -383.842327) (xy 451.657872 -383.821561) (xy 451.658482 -383.810002)
			(xy 451.658482 -383.729738) (xy 451.657896 -383.718172) (xy 451.647713 -383.6974) (xy 451.638924 -383.68986)
			(xy 451.618113 -383.673141) (xy 451.580985 -383.634782) (xy 451.549567 -383.591623) (xy 451.524471 -383.544505)
			(xy 451.506188 -383.49435) (xy 451.495074 -383.442135) (xy 451.491347 -383.388882) (xy 448.445363 -383.388882)
			(xy 448.441636 -383.442131) (xy 448.430521 -383.494341) (xy 448.412237 -383.544491) (xy 448.387139 -383.591603)
			(xy 448.355719 -383.634756) (xy 448.31859 -383.673107) (xy 448.297808 -383.68986) (xy 448.28907 -383.697445)
			(xy 448.278873 -383.718186) (xy 448.27825 -383.729738) (xy 448.27825 -383.810002) (xy 448.278802 -383.821573)
			(xy 448.289008 -383.842345) (xy 448.297808 -383.84988) (xy 448.320284 -383.86808) (xy 448.360019 -383.910098)
			(xy 448.392959 -383.957631) (xy 448.418348 -384.009591) (xy 448.435606 -384.064787) (xy 448.444338 -384.121955)
			(xy 448.444874 -384.15087) (xy 448.444388 -384.178121) (xy 448.436632 -384.232069) (xy 448.421277 -384.284364)
			(xy 448.398635 -384.333941) (xy 448.369169 -384.379791) (xy 448.333478 -384.420982) (xy 448.292287 -384.456673)
			(xy 448.246437 -384.486139) (xy 448.19686 -384.508781) (xy 448.144565 -384.524136) (xy 448.090617 -384.531892)
			(xy 448.036115 -384.531892) (xy 447.982167 -384.524136) (xy 447.929872 -384.508781) (xy 447.880295 -384.486139)
			(xy 447.834445 -384.456673) (xy 447.793254 -384.420982) (xy 447.757563 -384.379791) (xy 447.728097 -384.333941)
			(xy 447.705455 -384.284364) (xy 447.6901 -384.232069) (xy 447.682344 -384.178121) (xy 447.681858 -384.15087)
			(xy 447.682405 -384.121954) (xy 447.691125 -384.064783) (xy 447.708376 -384.009584) (xy 447.733762 -383.957622)
			(xy 447.766702 -383.910087) (xy 447.80644 -383.86807) (xy 447.828924 -383.84988) (xy 447.837695 -383.842327)
			(xy 447.847872 -383.821561) (xy 447.848482 -383.810002) (xy 447.848482 -383.729738) (xy 447.847896 -383.718172)
			(xy 447.837713 -383.6974) (xy 447.828924 -383.68986) (xy 447.808113 -383.673141) (xy 447.770985 -383.634782)
			(xy 447.739567 -383.591623) (xy 447.714471 -383.544505) (xy 447.696188 -383.49435) (xy 447.685074 -383.442135)
			(xy 447.681347 -383.388882) (xy 446.489563 -383.388882) (xy 446.485836 -383.442131) (xy 446.474721 -383.494341)
			(xy 446.456437 -383.544491) (xy 446.431339 -383.591603) (xy 446.399919 -383.634756) (xy 446.36279 -383.673107)
			(xy 446.342008 -383.68986) (xy 446.33327 -383.697445) (xy 446.323073 -383.718186) (xy 446.32245 -383.729738)
			(xy 446.32245 -383.810002) (xy 446.323002 -383.821573) (xy 446.333208 -383.842345) (xy 446.342008 -383.84988)
			(xy 446.364484 -383.86808) (xy 446.404219 -383.910098) (xy 446.437159 -383.957631) (xy 446.462548 -384.009591)
			(xy 446.479806 -384.064787) (xy 446.488538 -384.121955) (xy 446.489074 -384.15087) (xy 446.488588 -384.178121)
			(xy 446.480832 -384.232069) (xy 446.465477 -384.284364) (xy 446.442835 -384.333941) (xy 446.413369 -384.379791)
			(xy 446.377678 -384.420982) (xy 446.336487 -384.456673) (xy 446.290637 -384.486139) (xy 446.24106 -384.508781)
			(xy 446.188765 -384.524136) (xy 446.134817 -384.531892) (xy 446.080315 -384.531892) (xy 446.026367 -384.524136)
			(xy 445.974072 -384.508781) (xy 445.924495 -384.486139) (xy 445.878645 -384.456673) (xy 445.837454 -384.420982)
			(xy 445.801763 -384.379791) (xy 445.772297 -384.333941) (xy 445.749655 -384.284364) (xy 445.7343 -384.232069)
			(xy 445.726544 -384.178121) (xy 445.726058 -384.15087) (xy 445.726605 -384.121954) (xy 445.735325 -384.064783)
			(xy 445.752576 -384.009584) (xy 445.777962 -383.957622) (xy 445.810902 -383.910087) (xy 445.85064 -383.86807)
			(xy 445.873124 -383.84988) (xy 445.881895 -383.842327) (xy 445.892072 -383.821561) (xy 445.892682 -383.810002)
			(xy 445.892682 -383.729738) (xy 445.892096 -383.718172) (xy 445.881913 -383.6974) (xy 445.873124 -383.68986)
			(xy 445.852313 -383.673141) (xy 445.815185 -383.634782) (xy 445.783767 -383.591623) (xy 445.758671 -383.544505)
			(xy 445.740388 -383.49435) (xy 445.729274 -383.442135) (xy 445.725547 -383.388882) (xy 442.679563 -383.388882)
			(xy 442.675836 -383.442131) (xy 442.664721 -383.494341) (xy 442.646437 -383.544491) (xy 442.621339 -383.591603)
			(xy 442.589919 -383.634756) (xy 442.55279 -383.673107) (xy 442.532008 -383.68986) (xy 442.52327 -383.697445)
			(xy 442.513073 -383.718186) (xy 442.51245 -383.729738) (xy 442.51245 -383.810002) (xy 442.513002 -383.821573)
			(xy 442.523208 -383.842345) (xy 442.532008 -383.84988) (xy 442.554484 -383.86808) (xy 442.594219 -383.910098)
			(xy 442.627159 -383.957631) (xy 442.652548 -384.009591) (xy 442.669806 -384.064787) (xy 442.678538 -384.121955)
			(xy 442.679074 -384.15087) (xy 442.678588 -384.178121) (xy 442.670832 -384.232069) (xy 442.655477 -384.284364)
			(xy 442.632835 -384.333941) (xy 442.603369 -384.379791) (xy 442.567678 -384.420982) (xy 442.526487 -384.456673)
			(xy 442.480637 -384.486139) (xy 442.43106 -384.508781) (xy 442.378765 -384.524136) (xy 442.324817 -384.531892)
			(xy 442.270315 -384.531892) (xy 442.216367 -384.524136) (xy 442.164072 -384.508781) (xy 442.114495 -384.486139)
			(xy 442.068645 -384.456673) (xy 442.027454 -384.420982) (xy 441.991763 -384.379791) (xy 441.962297 -384.333941)
			(xy 441.939655 -384.284364) (xy 441.9243 -384.232069) (xy 441.916544 -384.178121) (xy 441.916058 -384.15087)
			(xy 441.916605 -384.121954) (xy 441.925325 -384.064783) (xy 441.942576 -384.009584) (xy 441.967962 -383.957622)
			(xy 442.000902 -383.910087) (xy 442.04064 -383.86807) (xy 442.063124 -383.84988) (xy 442.071895 -383.842327)
			(xy 442.082072 -383.821561) (xy 442.082682 -383.810002) (xy 442.082682 -383.729738) (xy 442.082096 -383.718172)
			(xy 442.071913 -383.6974) (xy 442.063124 -383.68986) (xy 442.042313 -383.673141) (xy 442.005185 -383.634782)
			(xy 441.973767 -383.591623) (xy 441.948671 -383.544505) (xy 441.930388 -383.49435) (xy 441.919274 -383.442135)
			(xy 441.915547 -383.388882) (xy 437.494359 -383.388882) (xy 437.527911 -383.479007) (xy 437.58624 -383.65995)
			(xy 437.636453 -383.84331) (xy 437.678451 -384.028725) (xy 437.712152 -384.215827) (xy 437.737487 -384.404243)
			(xy 437.754407 -384.593601) (xy 437.762878 -384.783524) (xy 437.763412 -384.87858) (xy 437.762911 -384.971395)
			(xy 437.759964 -385.039108) (xy 447.973196 -385.039108) (xy 447.973663 -385.011855) (xy 447.981419 -384.957904)
			(xy 447.996774 -384.905606) (xy 448.019416 -384.856026) (xy 448.048883 -384.810172) (xy 448.084577 -384.76898)
			(xy 448.125769 -384.733286) (xy 448.171622 -384.703818) (xy 448.221202 -384.681175) (xy 448.2735 -384.66582)
			(xy 448.327451 -384.658063) (xy 448.354704 -384.6576) (xy 448.383621 -384.658116) (xy 448.440792 -384.666845)
			(xy 448.495991 -384.684104) (xy 448.547953 -384.709496) (xy 448.595487 -384.74244) (xy 448.637504 -384.782181)
			(xy 448.655694 -384.804666) (xy 448.663251 -384.813432) (xy 448.684014 -384.82361) (xy 448.695572 -384.824224)
			(xy 448.775836 -384.824224) (xy 448.787403 -384.823643) (xy 448.808176 -384.813459) (xy 448.815714 -384.804666)
			(xy 448.833889 -384.782169) (xy 448.875913 -384.742436) (xy 448.923451 -384.7095) (xy 448.975416 -384.684114)
			(xy 449.030616 -384.66686) (xy 449.087787 -384.658134) (xy 449.116704 -384.6576) (xy 449.145443 -384.658121)
			(xy 449.20227 -384.666744) (xy 449.257161 -384.683795) (xy 449.308873 -384.708887) (xy 449.356235 -384.741453)
			(xy 449.377562 -384.760724) (xy 449.384674 -384.767328) (xy 449.4022 -384.77444) (xy 449.491608 -384.77444)
			(xy 449.509134 -384.767328) (xy 449.516246 -384.760724) (xy 449.537569 -384.741449) (xy 449.584933 -384.708884)
			(xy 449.636645 -384.683792) (xy 449.691537 -384.666743) (xy 449.748365 -384.658121) (xy 449.777104 -384.6576)
			(xy 449.804357 -384.658052) (xy 449.858309 -384.665809) (xy 449.910608 -384.681166) (xy 449.960188 -384.70381)
			(xy 450.006042 -384.733279) (xy 450.047235 -384.768974) (xy 450.082928 -384.810168) (xy 450.112396 -384.856022)
			(xy 450.135038 -384.905604) (xy 450.150393 -384.957903) (xy 450.158149 -385.011855) (xy 450.158612 -385.039108)
			(xy 450.158178 -385.06581) (xy 450.150724 -385.11869) (xy 450.135962 -385.170013) (xy 450.114183 -385.218773)
			(xy 450.085811 -385.264017) (xy 450.06895 -385.284726) (xy 450.062854 -385.292092) (xy 450.056758 -385.310126)
			(xy 450.060568 -385.397756) (xy 450.068188 -385.415282) (xy 450.074792 -385.421886) (xy 450.095606 -385.443472)
			(xy 450.130859 -385.491977) (xy 450.158087 -385.545401) (xy 450.176618 -385.602428) (xy 450.185997 -385.661653)
			(xy 450.186552 -385.691634) (xy 450.186008 -385.720693) (xy 450.177172 -385.778134) (xy 450.159725 -385.833571)
			(xy 450.134071 -385.88572) (xy 450.100803 -385.933374) (xy 450.081142 -385.954778) (xy 450.074538 -385.96189)
			(xy 450.067172 -385.979924) (xy 450.067172 -386.06984) (xy 450.074538 -386.087874) (xy 450.081142 -386.094986)
			(xy 450.100804 -386.116391) (xy 450.134085 -386.164037) (xy 450.159743 -386.216185) (xy 450.177186 -386.271625)
			(xy 450.186007 -386.329071) (xy 450.186552 -386.35813) (xy 450.186034 -386.386232) (xy 450.18508 -386.392674)
			(xy 450.3547 -386.392674) (xy 450.355208 -386.363935) (xy 450.363834 -386.307106) (xy 450.380888 -386.252216)
			(xy 450.405983 -386.200504) (xy 450.438552 -386.153142) (xy 450.457824 -386.131816) (xy 450.464428 -386.124704)
			(xy 450.47154 -386.107178) (xy 450.47154 -386.01777) (xy 450.464428 -386.000244) (xy 450.457824 -385.993132)
			(xy 450.438527 -385.971828) (xy 450.405963 -385.924461) (xy 450.380873 -385.872746) (xy 450.363825 -385.817852)
			(xy 450.355205 -385.761021) (xy 450.355207 -385.703541) (xy 450.363833 -385.646711) (xy 450.380887 -385.591819)
			(xy 450.405982 -385.540106) (xy 450.438551 -385.492743) (xy 450.457824 -385.471416) (xy 450.464428 -385.464304)
			(xy 450.47154 -385.446778) (xy 450.47154 -385.35737) (xy 450.464428 -385.339844) (xy 450.457824 -385.332732)
			(xy 450.438539 -385.311418) (xy 450.405975 -385.264052) (xy 450.380885 -385.212337) (xy 450.363838 -385.157444)
			(xy 450.355219 -385.100614) (xy 450.3547 -385.071874) (xy 450.355154 -385.044622) (xy 450.362914 -384.990672)
			(xy 450.378273 -384.938377) (xy 450.400917 -384.888799) (xy 450.430387 -384.842948) (xy 450.466082 -384.801758)
			(xy 450.507275 -384.766067) (xy 450.553129 -384.736601) (xy 450.602709 -384.713961) (xy 450.655006 -384.698607)
			(xy 450.708956 -384.690851) (xy 450.736208 -384.690366) (xy 450.764947 -384.690894) (xy 450.821773 -384.699517)
			(xy 450.876664 -384.716566) (xy 450.928376 -384.741657) (xy 450.975739 -384.77422) (xy 450.997066 -384.79349)
			(xy 451.004178 -384.800094) (xy 451.021704 -384.807206) (xy 451.111112 -384.807206) (xy 451.128638 -384.800094)
			(xy 451.13575 -384.79349) (xy 451.157082 -384.774224) (xy 451.204442 -384.741656) (xy 451.256152 -384.716561)
			(xy 451.311042 -384.69951) (xy 451.367869 -384.690887) (xy 451.396608 -384.690366) (xy 451.42367 -384.690813)
			(xy 451.477248 -384.69848) (xy 451.529203 -384.713646) (xy 451.578493 -384.736004) (xy 451.624126 -384.765107)
			(xy 451.665187 -384.800369) (xy 451.683374 -384.820414) (xy 451.690944 -384.828277) (xy 451.710823 -384.83723)
			(xy 451.721728 -384.837686) (xy 451.797928 -384.837686) (xy 451.808828 -384.83722) (xy 451.828698 -384.828258)
			(xy 451.836282 -384.820414) (xy 451.854456 -384.800357) (xy 451.895516 -384.765093) (xy 451.941151 -384.735992)
			(xy 451.990445 -384.71364) (xy 452.042405 -384.698487) (xy 452.095986 -384.690836) (xy 452.123048 -384.690366)
			(xy 452.150299 -384.690833) (xy 452.204246 -384.698595) (xy 452.25654 -384.713955) (xy 452.306115 -384.7366)
			(xy 452.351964 -384.766069) (xy 452.393153 -384.801762) (xy 452.428844 -384.842953) (xy 452.45831 -384.888804)
			(xy 452.480952 -384.938381) (xy 452.496309 -384.990675) (xy 452.504068 -385.044623) (xy 452.504556 -385.071874)
			(xy 452.504001 -385.100612) (xy 452.495384 -385.157437) (xy 452.47834 -385.212327) (xy 452.453256 -385.264039)
			(xy 452.420699 -385.311403) (xy 452.401432 -385.332732) (xy 452.394828 -385.339844) (xy 452.387716 -385.35737)
			(xy 452.387716 -385.446778) (xy 452.394828 -385.464304) (xy 452.401432 -385.471416) (xy 452.420675 -385.492766)
			(xy 452.453236 -385.540126) (xy 452.478325 -385.591835) (xy 452.495374 -385.646721) (xy 452.503998 -385.703544)
			(xy 452.504001 -385.761018) (xy 452.495383 -385.817842) (xy 452.478339 -385.87273) (xy 452.453255 -385.924441)
			(xy 452.420698 -385.971804) (xy 452.401432 -385.993132) (xy 452.394828 -386.000244) (xy 452.387716 -386.01777)
			(xy 452.387716 -386.107178) (xy 452.394828 -386.124704) (xy 452.401432 -386.131816) (xy 452.420675 -386.153166)
			(xy 452.453236 -386.200526) (xy 452.478325 -386.252235) (xy 452.495374 -386.307121) (xy 452.503998 -386.363944)
			(xy 452.504001 -386.421418) (xy 452.495383 -386.478242) (xy 452.478339 -386.53313) (xy 452.453255 -386.584841)
			(xy 452.420698 -386.632204) (xy 452.401432 -386.653532) (xy 452.394574 -386.660898) (xy 452.387716 -386.678678)
			(xy 452.388478 -386.768848) (xy 452.395844 -386.786882) (xy 452.402956 -386.793994) (xy 452.423192 -386.815485)
			(xy 452.457414 -386.86358) (xy 452.48382 -386.916372) (xy 452.50178 -386.972601) (xy 452.510866 -387.030926)
			(xy 452.511414 -387.06044) (xy 452.510909 -387.087809) (xy 452.5031 -387.141986) (xy 452.48762 -387.194489)
			(xy 452.464787 -387.244236) (xy 452.435071 -387.290205) (xy 452.417434 -387.311138) (xy 452.411338 -387.31825)
			(xy 452.404988 -387.335268) (xy 452.404988 -387.420612) (xy 452.411338 -387.43763) (xy 452.417434 -387.444742)
			(xy 452.435065 -387.465681) (xy 452.464777 -387.511652) (xy 452.487614 -387.561398) (xy 452.503107 -387.613897)
			(xy 452.503953 -387.619748) (xy 455.361802 -387.619748) (xy 455.362294 -387.591008) (xy 455.370924 -387.534179)
			(xy 455.387981 -387.479288) (xy 455.41308 -387.427577) (xy 455.445652 -387.380216) (xy 455.464926 -387.35889)
			(xy 455.47153 -387.351778) (xy 455.478642 -387.334252) (xy 455.478642 -387.244844) (xy 455.47153 -387.227318)
			(xy 455.464926 -387.220206) (xy 455.445703 -387.198838) (xy 455.413136 -387.151483) (xy 455.388041 -387.099778)
			(xy 455.370988 -387.044893) (xy 455.362361 -386.988071) (xy 455.362355 -386.930599) (xy 455.370972 -386.873775)
			(xy 455.388016 -386.818888) (xy 455.4131 -386.767178) (xy 455.445659 -386.719817) (xy 455.464926 -386.69849)
			(xy 455.47153 -386.691378) (xy 455.478642 -386.673852) (xy 455.478642 -386.584444) (xy 455.47153 -386.566918)
			(xy 455.464926 -386.559806) (xy 455.445703 -386.538438) (xy 455.413136 -386.491083) (xy 455.388041 -386.439378)
			(xy 455.370988 -386.384493) (xy 455.362361 -386.327671) (xy 455.362355 -386.270199) (xy 455.370972 -386.213375)
			(xy 455.388016 -386.158488) (xy 455.4131 -386.106778) (xy 455.445659 -386.059417) (xy 455.464926 -386.03809)
			(xy 455.47153 -386.030978) (xy 455.478642 -386.013452) (xy 455.478642 -385.924044) (xy 455.47153 -385.906518)
			(xy 455.464926 -385.899406) (xy 455.445629 -385.878102) (xy 455.413066 -385.830734) (xy 455.387979 -385.779016)
			(xy 455.370935 -385.72412) (xy 455.362319 -385.667289) (xy 455.361802 -385.638548) (xy 455.3623 -385.611296)
			(xy 455.370051 -385.557346) (xy 455.385401 -385.505048) (xy 455.408039 -385.455467) (xy 455.437503 -385.409613)
			(xy 455.473193 -385.36842) (xy 455.514383 -385.332725) (xy 455.560234 -385.303257) (xy 455.609812 -385.280614)
			(xy 455.662108 -385.265259) (xy 455.716058 -385.257503) (xy 455.74331 -385.25704) (xy 455.769625 -385.257509)
			(xy 455.821757 -385.264732) (xy 455.8724 -385.279054) (xy 455.920594 -385.300203) (xy 455.965422 -385.327778)
			(xy 456.006034 -385.361253) (xy 456.041657 -385.399994) (xy 456.057 -385.421378) (xy 456.064112 -385.431538)
			(xy 456.085448 -385.442968) (xy 456.193144 -385.444492) (xy 456.214988 -385.43357) (xy 456.222354 -385.423664)
			(xy 456.240463 -385.399945) (xy 456.2828 -385.357892) (xy 456.33117 -385.322946) (xy 456.384392 -385.295959)
			(xy 456.441168 -385.277591) (xy 456.500112 -385.26829) (xy 456.529948 -385.267708) (xy 456.557716 -385.26821)
			(xy 456.612668 -385.276252) (xy 456.665873 -385.292172) (xy 456.71621 -385.315634) (xy 456.762615 -385.346145)
			(xy 456.783694 -385.364228) (xy 456.790552 -385.370324) (xy 456.807824 -385.377182) (xy 456.89393 -385.377436)
			(xy 456.911202 -385.370832) (xy 456.918314 -385.364736) (xy 456.939286 -385.346929) (xy 456.985399 -385.316922)
			(xy 457.035341 -385.293845) (xy 457.088079 -385.278176) (xy 457.14252 -385.27024) (xy 457.170028 -385.26974)
			(xy 457.197284 -385.270129) (xy 457.25124 -385.277891) (xy 457.303542 -385.293253) (xy 457.353126 -385.315902)
			(xy 457.398981 -385.345378) (xy 457.440175 -385.381079) (xy 457.475868 -385.42228) (xy 457.505334 -385.468141)
			(xy 457.527974 -385.517729) (xy 457.543325 -385.570034) (xy 457.551076 -385.623992) (xy 457.551536 -385.651248)
			(xy 457.551032 -385.679988) (xy 457.542403 -385.736815) (xy 457.525348 -385.791706) (xy 457.500252 -385.843417)
			(xy 457.467684 -385.890779) (xy 457.448412 -385.912106) (xy 457.441808 -385.919218) (xy 457.434696 -385.936744)
			(xy 457.434696 -386.026152) (xy 457.441808 -386.043678) (xy 457.448412 -386.05079) (xy 457.467729 -386.072076)
			(xy 457.500289 -386.119447) (xy 457.525376 -386.171165) (xy 457.542421 -386.226062) (xy 457.551038 -386.282894)
			(xy 457.551033 -386.340376) (xy 457.542405 -386.397206) (xy 457.52535 -386.4521) (xy 457.500254 -386.503814)
			(xy 457.467685 -386.551178) (xy 457.448412 -386.572506) (xy 457.441808 -386.579618) (xy 457.434696 -386.597144)
			(xy 457.434696 -386.686552) (xy 457.441808 -386.704078) (xy 457.448412 -386.71119) (xy 457.467729 -386.732476)
			(xy 457.500289 -386.779847) (xy 457.525376 -386.831565) (xy 457.542421 -386.886462) (xy 457.551038 -386.943294)
			(xy 457.551033 -387.000776) (xy 457.542405 -387.057606) (xy 457.52535 -387.1125) (xy 457.500254 -387.164214)
			(xy 457.467685 -387.211578) (xy 457.448412 -387.232906) (xy 457.441808 -387.240018) (xy 457.434696 -387.257544)
			(xy 457.434696 -387.258347) (xy 458.670706 -387.258347) (xy 458.670706 -387.203853) (xy 458.678461 -387.149912)
			(xy 458.693813 -387.097625) (xy 458.716449 -387.048054) (xy 458.74591 -387.002209) (xy 458.781594 -386.961023)
			(xy 458.822777 -386.925334) (xy 458.868619 -386.895869) (xy 458.918187 -386.873227) (xy 458.970473 -386.857869)
			(xy 459.024413 -386.850109) (xy 459.05166 -386.84962) (xy 459.080399 -386.850129) (xy 459.137226 -386.858758)
			(xy 459.192116 -386.875813) (xy 459.243828 -386.900907) (xy 459.291191 -386.933473) (xy 459.312518 -386.952744)
			(xy 459.31963 -386.959348) (xy 459.337156 -386.96646) (xy 459.426564 -386.96646) (xy 459.44409 -386.959348)
			(xy 459.451202 -386.952744) (xy 459.472546 -386.933493) (xy 459.519904 -386.900924) (xy 459.571611 -386.875828)
			(xy 459.626498 -386.858772) (xy 459.683322 -386.850144) (xy 459.71206 -386.84962) (xy 459.739317 -386.850024)
			(xy 459.793276 -386.857777) (xy 459.845583 -386.873131) (xy 459.895171 -386.895773) (xy 459.941033 -386.925242)
			(xy 459.982234 -386.960938) (xy 460.017934 -387.002135) (xy 460.047408 -387.047993) (xy 460.070055 -387.09758)
			(xy 460.085414 -387.149885) (xy 460.093173 -387.203843) (xy 460.093173 -387.258357) (xy 460.087696 -387.296447)
			(xy 460.851306 -387.296447) (xy 460.851306 -387.241953) (xy 460.859061 -387.188014) (xy 460.874412 -387.135727)
			(xy 460.897048 -387.086157) (xy 460.926507 -387.040312) (xy 460.962191 -386.999126) (xy 461.003372 -386.963437)
			(xy 461.049213 -386.933972) (xy 461.09878 -386.91133) (xy 461.151065 -386.895971) (xy 461.205003 -386.88821)
			(xy 461.23225 -386.88772) (xy 461.260989 -386.888235) (xy 461.317816 -386.896863) (xy 461.372706 -386.913916)
			(xy 461.424417 -386.939009) (xy 461.47178 -386.971574) (xy 461.493108 -386.990844) (xy 461.50022 -386.997448)
			(xy 461.517746 -387.00456) (xy 461.607154 -387.00456) (xy 461.62468 -386.997448) (xy 461.631792 -386.990844)
			(xy 461.653099 -386.971551) (xy 461.700467 -386.938987) (xy 461.752183 -386.913899) (xy 461.807078 -386.896854)
			(xy 461.86391 -386.888237) (xy 461.89265 -386.88772) (xy 461.919907 -386.888124) (xy 461.973868 -386.895875)
			(xy 462.026175 -386.911228) (xy 462.075765 -386.933869) (xy 462.121628 -386.963338) (xy 462.16283 -386.999035)
			(xy 462.198532 -387.040232) (xy 462.228007 -387.086091) (xy 462.250654 -387.135678) (xy 462.266014 -387.187983)
			(xy 462.273773 -387.241943) (xy 462.273773 -387.296457) (xy 462.266014 -387.350416) (xy 462.255395 -387.386576)
			(xy 462.824828 -387.386576) (xy 462.828899 -387.330954) (xy 462.841025 -387.276517) (xy 462.860948 -387.224426)
			(xy 462.888244 -387.175791) (xy 462.92233 -387.131648) (xy 462.962479 -387.092939) (xy 463.007837 -387.060488)
			(xy 463.057437 -387.034987) (xy 463.110221 -387.01698) (xy 463.165064 -387.00685) (xy 463.220798 -387.004813)
			(xy 463.276235 -387.010913) (xy 463.330192 -387.025019) (xy 463.381521 -387.046831) (xy 463.429127 -387.075885)
			(xy 463.471995 -387.11156) (xy 463.509212 -387.153097) (xy 463.539985 -387.19961) (xy 463.563657 -387.250107)
			(xy 463.579725 -387.303514) (xy 463.587845 -387.35869) (xy 463.588354 -387.386576) (xy 463.587845 -387.414462)
			(xy 463.579725 -387.469638) (xy 463.563657 -387.523045) (xy 463.539985 -387.573542) (xy 463.509212 -387.620055)
			(xy 463.471995 -387.661592) (xy 463.429127 -387.697267) (xy 463.381521 -387.726321) (xy 463.330192 -387.748133)
			(xy 463.276235 -387.762239) (xy 463.220798 -387.768339) (xy 463.165064 -387.766302) (xy 463.110221 -387.756172)
			(xy 463.057437 -387.738165) (xy 463.007837 -387.712664) (xy 462.962479 -387.680213) (xy 462.92233 -387.641504)
			(xy 462.888244 -387.597361) (xy 462.860948 -387.548726) (xy 462.841025 -387.496635) (xy 462.828899 -387.442198)
			(xy 462.824828 -387.386576) (xy 462.255395 -387.386576) (xy 462.250654 -387.402722) (xy 462.228007 -387.452309)
			(xy 462.198532 -387.498168) (xy 462.16283 -387.539365) (xy 462.121628 -387.575062) (xy 462.075765 -387.604531)
			(xy 462.026175 -387.627172) (xy 461.973868 -387.642525) (xy 461.919907 -387.650276) (xy 461.89265 -387.650736)
			(xy 461.86391 -387.650233) (xy 461.807083 -387.641604) (xy 461.752192 -387.624548) (xy 461.700481 -387.599453)
			(xy 461.653119 -387.566884) (xy 461.631792 -387.547612) (xy 461.62468 -387.541008) (xy 461.607154 -387.533896)
			(xy 461.517746 -387.533896) (xy 461.50022 -387.541008) (xy 461.493108 -387.547612) (xy 461.471794 -387.566898)
			(xy 461.424429 -387.599464) (xy 461.372715 -387.624555) (xy 461.317821 -387.641601) (xy 461.26099 -387.650219)
			(xy 461.23225 -387.650736) (xy 461.205003 -387.65019) (xy 461.151065 -387.642429) (xy 461.09878 -387.62707)
			(xy 461.049213 -387.604428) (xy 461.003372 -387.574963) (xy 460.962191 -387.539274) (xy 460.926507 -387.498088)
			(xy 460.897048 -387.452243) (xy 460.874412 -387.402673) (xy 460.859061 -387.350386) (xy 460.851306 -387.296447)
			(xy 460.087696 -387.296447) (xy 460.085414 -387.312315) (xy 460.070055 -387.36462) (xy 460.047408 -387.414207)
			(xy 460.017934 -387.460065) (xy 459.982234 -387.501262) (xy 459.941033 -387.536958) (xy 459.895171 -387.566427)
			(xy 459.845583 -387.589069) (xy 459.793276 -387.604423) (xy 459.739317 -387.612176) (xy 459.71206 -387.612636)
			(xy 459.683321 -387.612127) (xy 459.626493 -387.603499) (xy 459.571603 -387.586445) (xy 459.519891 -387.561351)
			(xy 459.472529 -387.528783) (xy 459.451202 -387.509512) (xy 459.44409 -387.502908) (xy 459.426564 -387.495796)
			(xy 459.337156 -387.495796) (xy 459.31963 -387.502908) (xy 459.312518 -387.509512) (xy 459.2912 -387.528793)
			(xy 459.243836 -387.56136) (xy 459.192123 -387.586451) (xy 459.137229 -387.603499) (xy 459.0804 -387.612118)
			(xy 459.05166 -387.612636) (xy 459.024413 -387.612091) (xy 458.970473 -387.604331) (xy 458.918187 -387.588973)
			(xy 458.868619 -387.566331) (xy 458.822777 -387.536866) (xy 458.781594 -387.501177) (xy 458.74591 -387.459991)
			(xy 458.716449 -387.414146) (xy 458.693813 -387.364575) (xy 458.678461 -387.312288) (xy 458.670706 -387.258347)
			(xy 457.434696 -387.258347) (xy 457.434696 -387.346952) (xy 457.441808 -387.364478) (xy 457.448412 -387.37159)
			(xy 457.467697 -387.392905) (xy 457.500263 -387.440269) (xy 457.525354 -387.491984) (xy 457.542401 -387.546878)
			(xy 457.551018 -387.603708) (xy 457.551536 -387.632448) (xy 457.551061 -387.659007) (xy 457.543703 -387.711613)
			(xy 457.529123 -387.762691) (xy 457.507601 -387.811254) (xy 457.479554 -387.856364) (xy 457.46289 -387.87705)
			(xy 457.45654 -387.884416) (xy 457.450698 -387.90245) (xy 457.454508 -387.989826) (xy 457.462128 -388.007098)
			(xy 457.468732 -388.013956) (xy 457.489405 -388.035575) (xy 457.524504 -388.084004) (xy 457.542741 -388.119874)
			(xy 457.846428 -388.119874) (xy 457.850499 -388.064252) (xy 457.862625 -388.009815) (xy 457.882548 -387.957724)
			(xy 457.909844 -387.909089) (xy 457.94393 -387.864946) (xy 457.984079 -387.826237) (xy 458.029437 -387.793786)
			(xy 458.079037 -387.768285) (xy 458.131821 -387.750278) (xy 458.186664 -387.740148) (xy 458.242398 -387.738111)
			(xy 458.297835 -387.744211) (xy 458.351792 -387.758317) (xy 458.403121 -387.780129) (xy 458.450727 -387.809183)
			(xy 458.493595 -387.844858) (xy 458.530812 -387.886395) (xy 458.561585 -387.932908) (xy 458.585257 -387.983405)
			(xy 458.601325 -388.036812) (xy 458.609445 -388.091988) (xy 458.609954 -388.119874) (xy 458.609445 -388.14776)
			(xy 458.601325 -388.202936) (xy 458.585257 -388.256343) (xy 458.561585 -388.30684) (xy 458.530812 -388.353353)
			(xy 458.493595 -388.39489) (xy 458.450727 -388.430565) (xy 458.403121 -388.459619) (xy 458.351792 -388.481431)
			(xy 458.297835 -388.495537) (xy 458.242398 -388.501637) (xy 458.186664 -388.4996) (xy 458.131821 -388.48947)
			(xy 458.079037 -388.471463) (xy 458.029437 -388.445962) (xy 457.984079 -388.413511) (xy 457.94393 -388.374802)
			(xy 457.909844 -388.330659) (xy 457.882548 -388.282024) (xy 457.862625 -388.229933) (xy 457.850499 -388.175496)
			(xy 457.846428 -388.119874) (xy 457.542741 -388.119874) (xy 457.551611 -388.137319) (xy 457.570061 -388.194213)
			(xy 457.5794 -388.253291) (xy 457.579984 -388.283196) (xy 457.579541 -388.31045) (xy 457.571784 -388.364403)
			(xy 457.556427 -388.416702) (xy 457.533783 -388.466284) (xy 457.504313 -388.512138) (xy 457.468618 -388.553332)
			(xy 457.427422 -388.589025) (xy 457.381567 -388.618493) (xy 457.331984 -388.641134) (xy 457.279683 -388.656488)
			(xy 457.22573 -388.664242) (xy 457.198476 -388.664704) (xy 457.171906 -388.664233) (xy 457.119283 -388.656837)
			(xy 457.068197 -388.642205) (xy 457.019637 -388.620622) (xy 456.974545 -388.592504) (xy 456.953874 -388.575804)
			(xy 456.946508 -388.569708) (xy 456.928982 -388.563866) (xy 456.84186 -388.566914) (xy 456.824842 -388.57428)
			(xy 456.817984 -388.580884) (xy 456.796502 -388.600972) (xy 456.748506 -388.634959) (xy 456.695863 -388.66118)
			(xy 456.639821 -388.679013) (xy 456.581706 -388.688037) (xy 456.5523 -388.68858) (xy 456.524869 -388.688153)
			(xy 456.470576 -388.680275) (xy 456.417969 -388.66471) (xy 456.36813 -388.641778) (xy 456.322085 -388.611952)
			(xy 456.280781 -388.575844) (xy 456.245068 -388.534198) (xy 456.229974 -388.511288) (xy 456.223116 -388.500366)
			(xy 456.200764 -388.48792) (xy 456.09002 -388.486142) (xy 456.067414 -388.497826) (xy 456.060048 -388.508748)
			(xy 456.044731 -388.530502) (xy 456.009069 -388.569982) (xy 455.968269 -388.604127) (xy 455.923123 -388.632275)
			(xy 455.874505 -388.65388) (xy 455.823358 -388.668523) (xy 455.770673 -388.675922) (xy 455.744072 -388.676388)
			(xy 455.716819 -388.675948) (xy 455.662869 -388.668187) (xy 455.610572 -388.652828) (xy 455.560993 -388.630182)
			(xy 455.515142 -388.600711) (xy 455.473952 -388.565014) (xy 455.43826 -388.523819) (xy 455.408795 -388.477965)
			(xy 455.386156 -388.428383) (xy 455.370802 -388.376084) (xy 455.363048 -388.322133) (xy 455.362564 -388.29488)
			(xy 455.363074 -388.265401) (xy 455.372148 -388.207146) (xy 455.390076 -388.15098) (xy 455.416433 -388.098241)
			(xy 455.450589 -388.050185) (xy 455.470768 -388.028688) (xy 455.47788 -388.021322) (xy 455.485246 -388.003034)
			(xy 455.485246 -387.912102) (xy 455.477626 -387.893814) (xy 455.470768 -387.886702) (xy 455.450437 -387.865202)
			(xy 455.416059 -387.817042) (xy 455.389529 -387.764151) (xy 455.371483 -387.707798) (xy 455.362355 -387.649334)
			(xy 455.361802 -387.619748) (xy 452.503953 -387.619748) (xy 452.510938 -387.668071) (xy 452.511414 -387.69544)
			(xy 452.510874 -387.723834) (xy 452.502458 -387.779995) (xy 452.485804 -387.834286) (xy 452.46128 -387.885505)
			(xy 452.429428 -387.932519) (xy 452.410576 -387.953758) (xy 452.404226 -387.960616) (xy 452.397368 -387.977888)
			(xy 452.396098 -388.064248) (xy 452.402194 -388.08152) (xy 452.408544 -388.088632) (xy 452.425852 -388.109521)
			(xy 452.455038 -388.155246) (xy 452.47745 -388.204647) (xy 452.492635 -388.256725) (xy 452.500286 -388.310429)
			(xy 452.500746 -388.337552) (xy 452.50026 -388.364803) (xy 452.492504 -388.418751) (xy 452.477149 -388.471046)
			(xy 452.454507 -388.520623) (xy 452.425041 -388.566473) (xy 452.38935 -388.607664) (xy 452.348159 -388.643355)
			(xy 452.302309 -388.672821) (xy 452.252732 -388.695463) (xy 452.200437 -388.710818) (xy 452.146489 -388.718574)
			(xy 452.091987 -388.718574) (xy 452.038039 -388.710818) (xy 451.985744 -388.695463) (xy 451.936167 -388.672821)
			(xy 451.890317 -388.643355) (xy 451.849126 -388.607664) (xy 451.813435 -388.566473) (xy 451.783969 -388.520623)
			(xy 451.761327 -388.471046) (xy 451.745972 -388.418751) (xy 451.738216 -388.364803) (xy 451.73773 -388.337552)
			(xy 451.738128 -388.312092) (xy 451.744897 -388.261624) (xy 451.758321 -388.212505) (xy 451.778162 -388.16561)
			(xy 451.804066 -388.121772) (xy 451.835573 -388.08177) (xy 451.853554 -388.06374) (xy 451.860334 -388.056435)
			(xy 451.86817 -388.038128) (xy 451.868794 -388.02818) (xy 451.869556 -387.996176) (xy 451.869232 -387.98619)
			(xy 451.861915 -387.967623) (xy 451.855332 -387.960108) (xy 451.84314 -387.9469) (xy 451.835578 -387.93903)
			(xy 451.815692 -387.930084) (xy 451.804786 -387.929628) (xy 451.728586 -387.929628) (xy 451.717691 -387.930128)
			(xy 451.697822 -387.939068) (xy 451.690232 -387.9469) (xy 451.672054 -387.966953) (xy 451.630995 -388.002217)
			(xy 451.58536 -388.031318) (xy 451.536067 -388.05367) (xy 451.484108 -388.068825) (xy 451.430528 -388.076477)
			(xy 451.403466 -388.076948) (xy 451.374727 -388.076432) (xy 451.3179 -388.067806) (xy 451.263009 -388.050753)
			(xy 451.211298 -388.02566) (xy 451.163935 -387.993095) (xy 451.142608 -387.973824) (xy 451.135496 -387.96722)
			(xy 451.11797 -387.960108) (xy 451.028562 -387.960108) (xy 451.011036 -387.96722) (xy 451.003924 -387.973824)
			(xy 450.982605 -387.993105) (xy 450.935242 -388.025671) (xy 450.883528 -388.050762) (xy 450.828635 -388.06781)
			(xy 450.771806 -388.076429) (xy 450.743066 -388.076948) (xy 450.715816 -388.076454) (xy 450.66187 -388.068694)
			(xy 450.609578 -388.053336) (xy 450.560004 -388.030694) (xy 450.514155 -388.001228) (xy 450.472966 -387.965538)
			(xy 450.437275 -387.92435) (xy 450.407809 -387.878502) (xy 450.385166 -387.828927) (xy 450.369807 -387.776635)
			(xy 450.362046 -387.72269) (xy 450.361558 -387.69544) (xy 450.362033 -387.66807) (xy 450.369847 -387.613891)
			(xy 450.385333 -387.561387) (xy 450.408173 -387.51164) (xy 450.437897 -387.465673) (xy 450.455538 -387.444742)
			(xy 450.461634 -387.43763) (xy 450.467984 -387.420612) (xy 450.467984 -387.335268) (xy 450.461634 -387.31825)
			(xy 450.455538 -387.311138) (xy 450.437909 -387.290198) (xy 450.408194 -387.244228) (xy 450.385356 -387.194482)
			(xy 450.369863 -387.141983) (xy 450.362033 -387.087809) (xy 450.361558 -387.06044) (xy 450.362056 -387.0317)
			(xy 450.370687 -386.974872) (xy 450.387744 -386.919982) (xy 450.41284 -386.86827) (xy 450.44541 -386.820909)
			(xy 450.464682 -386.799582) (xy 450.47154 -386.792216) (xy 450.478398 -386.774436) (xy 450.477636 -386.684266)
			(xy 450.47027 -386.666232) (xy 450.463158 -386.65912) (xy 450.442931 -386.637621) (xy 450.408707 -386.589528)
			(xy 450.382299 -386.536738) (xy 450.364337 -386.480511) (xy 450.35525 -386.422187) (xy 450.3547 -386.392674)
			(xy 450.18508 -386.392674) (xy 450.177797 -386.441828) (xy 450.16149 -386.495614) (xy 450.137467 -386.546424)
			(xy 450.106249 -386.59316) (xy 450.06851 -386.634808) (xy 450.047106 -386.653024) (xy 450.03847 -386.660136)
			(xy 450.028818 -386.680202) (xy 450.027294 -386.780532) (xy 450.036438 -386.800598) (xy 450.045074 -386.808218)
			(xy 450.065287 -386.826445) (xy 450.100884 -386.867614) (xy 450.130271 -386.913424) (xy 450.152851 -386.962944)
			(xy 450.168167 -387.015169) (xy 450.175906 -387.069041) (xy 450.176392 -387.096254) (xy 450.175903 -387.124994)
			(xy 450.167272 -387.181823) (xy 450.150214 -387.236714) (xy 450.125115 -387.288426) (xy 450.092542 -387.335786)
			(xy 450.073268 -387.357112) (xy 450.066664 -387.364224) (xy 450.059552 -387.38175) (xy 450.059552 -387.471158)
			(xy 450.066664 -387.488684) (xy 450.073268 -387.495796) (xy 450.092565 -387.5171) (xy 450.125128 -387.564468)
			(xy 450.150215 -387.616186) (xy 450.167259 -387.671082) (xy 450.175875 -387.727913) (xy 450.176392 -387.756654)
			(xy 450.175902 -387.783906) (xy 450.168151 -387.837857) (xy 450.1528 -387.890156) (xy 450.130161 -387.939737)
			(xy 450.100697 -387.985591) (xy 450.065006 -388.026784) (xy 450.023815 -388.062479) (xy 449.977963 -388.091947)
			(xy 449.928384 -388.114589) (xy 449.876087 -388.129944) (xy 449.822136 -388.1377) (xy 449.794884 -388.138162)
			(xy 449.769022 -388.137724) (xy 449.717771 -388.13074) (xy 449.667935 -388.11689) (xy 449.620431 -388.096427)
			(xy 449.57613 -388.069728) (xy 449.535847 -388.037283) (xy 449.51777 -388.018782) (xy 449.510244 -388.011554)
			(xy 449.491108 -388.003288) (xy 449.480686 -388.00278) (xy 449.448682 -388.00278) (xy 449.43825 -388.003245)
			(xy 449.419097 -388.011514) (xy 449.411598 -388.018782) (xy 449.407534 -388.0231) (xy 449.400168 -388.030466)
			(xy 449.392802 -388.04977) (xy 449.39585 -388.14375) (xy 449.404486 -388.162546) (xy 449.41236 -388.169404)
			(xy 449.431867 -388.187546) (xy 449.466085 -388.228374) (xy 449.494285 -388.27357) (xy 449.515917 -388.322252)
			(xy 449.530559 -388.373472) (xy 449.537926 -388.426232) (xy 449.538344 -388.452868) (xy 449.537792 -388.480117)
			(xy 449.530041 -388.53406) (xy 449.514692 -388.586352) (xy 449.492057 -388.635926) (xy 449.462597 -388.681775)
			(xy 449.426913 -388.722965) (xy 449.385729 -388.758657) (xy 449.339886 -388.788124) (xy 449.290315 -388.810768)
			(xy 449.238027 -388.826126) (xy 449.184085 -388.833887) (xy 449.156836 -388.834376) (xy 449.12792 -388.833841)
			(xy 449.070749 -388.825117) (xy 449.01555 -388.807863) (xy 448.963588 -388.782474) (xy 448.916054 -388.749533)
			(xy 448.874036 -388.709794) (xy 448.855846 -388.68731) (xy 448.848258 -388.678575) (xy 448.827519 -388.668376)
			(xy 448.815968 -388.667752) (xy 448.735704 -388.667752) (xy 448.724134 -388.668307) (xy 448.703362 -388.678511)
			(xy 448.695826 -388.68731) (xy 448.677623 -388.709783) (xy 448.635605 -388.749519) (xy 448.588073 -388.782458)
			(xy 448.536114 -388.807848) (xy 448.480919 -388.825107) (xy 448.423751 -388.833839) (xy 448.394836 -388.834376)
			(xy 448.367583 -388.833911) (xy 448.31363 -388.826158) (xy 448.26133 -388.810805) (xy 448.211748 -388.788164)
			(xy 448.165893 -388.758697) (xy 448.124699 -388.723003) (xy 448.089005 -388.68181) (xy 448.059537 -388.635955)
			(xy 448.036896 -388.586374) (xy 448.021543 -388.534074) (xy 448.013789 -388.480121) (xy 448.013328 -388.452868)
			(xy 448.013848 -388.423354) (xy 448.022944 -388.36503) (xy 448.040916 -388.308804) (xy 448.067333 -388.256017)
			(xy 448.101565 -388.207928) (xy 448.121786 -388.186422) (xy 448.129152 -388.179056) (xy 448.136518 -388.159752)
			(xy 448.13347 -388.065772) (xy 448.124834 -388.046976) (xy 448.11696 -388.040118) (xy 448.097468 -388.021961)
			(xy 448.063247 -387.981136) (xy 448.035045 -387.935944) (xy 448.013411 -387.887265) (xy 447.998766 -387.836047)
			(xy 447.991395 -387.783289) (xy 447.990976 -387.756654) (xy 447.991478 -387.727914) (xy 448.000107 -387.671086)
			(xy 448.017162 -387.616196) (xy 448.042259 -387.564484) (xy 448.074828 -387.517122) (xy 448.0941 -387.495796)
			(xy 448.100704 -387.488684) (xy 448.107816 -387.471158) (xy 448.107816 -387.38175) (xy 448.100704 -387.364224)
			(xy 448.0941 -387.357112) (xy 448.074818 -387.335794) (xy 448.042251 -387.288431) (xy 448.01716 -387.236717)
			(xy 448.000112 -387.181824) (xy 447.991494 -387.124994) (xy 447.990976 -387.096254) (xy 447.991473 -387.068151)
			(xy 447.999713 -387.012554) (xy 448.016023 -386.958767) (xy 448.04005 -386.907956) (xy 448.071273 -386.861222)
			(xy 448.109016 -386.819575) (xy 448.130422 -386.80136) (xy 448.139058 -386.794248) (xy 448.14871 -386.774182)
			(xy 448.150234 -386.673852) (xy 448.14109 -386.653786) (xy 448.132454 -386.646166) (xy 448.112239 -386.627941)
			(xy 448.076641 -386.586772) (xy 448.047253 -386.540963) (xy 448.024673 -386.491442) (xy 448.009359 -386.439215)
			(xy 448.001621 -386.385343) (xy 448.001136 -386.35813) (xy 448.001696 -386.329072) (xy 448.010524 -386.27163)
			(xy 448.027966 -386.216192) (xy 448.053618 -386.164043) (xy 448.086885 -386.11639) (xy 448.106546 -386.094986)
			(xy 448.11315 -386.087874) (xy 448.120516 -386.06984) (xy 448.120516 -385.979924) (xy 448.11315 -385.96189)
			(xy 448.106546 -385.954778) (xy 448.086865 -385.93339) (xy 448.053587 -385.885739) (xy 448.027932 -385.833586)
			(xy 448.010495 -385.778143) (xy 448.001679 -385.720695) (xy 448.001136 -385.691634) (xy 448.001606 -385.664934)
			(xy 448.009054 -385.612055) (xy 448.023807 -385.560733) (xy 448.045578 -385.511973) (xy 448.073941 -385.466727)
			(xy 448.090798 -385.446016) (xy 448.096894 -385.43865) (xy 448.10299 -385.420616) (xy 448.09918 -385.332986)
			(xy 448.09156 -385.31546) (xy 448.084956 -385.308856) (xy 448.064171 -385.287243) (xy 448.028912 -385.238746)
			(xy 448.001679 -385.185329) (xy 447.98314 -385.128308) (xy 447.973755 -385.069088) (xy 447.973196 -385.039108)
			(xy 437.759964 -385.039108) (xy 437.754841 -385.15685) (xy 437.738715 -385.341778) (xy 437.714563 -385.525831)
			(xy 437.682432 -385.708659) (xy 437.642381 -385.889917) (xy 437.594487 -386.069262) (xy 437.538841 -386.246356)
			(xy 437.485035 -386.394706) (xy 442.279024 -386.394706) (xy 442.279461 -386.367452) (xy 442.287218 -386.313498)
			(xy 442.302575 -386.261198) (xy 442.325219 -386.211616) (xy 442.354689 -386.165761) (xy 442.390386 -386.124568)
			(xy 442.431582 -386.088874) (xy 442.477439 -386.059407) (xy 442.527022 -386.036766) (xy 442.579324 -386.021412)
			(xy 442.633278 -386.013659) (xy 442.660532 -386.013198) (xy 442.687801 -386.013699) (xy 442.741781 -386.02148)
			(xy 442.794103 -386.036866) (xy 442.843704 -386.059542) (xy 442.889571 -386.089047) (xy 442.930772 -386.124781)
			(xy 442.966467 -386.166015) (xy 442.981588 -386.188712) (xy 442.989127 -386.198999) (xy 443.011525 -386.21113)
			(xy 443.02426 -386.211826) (xy 443.055756 -386.211826) (xy 443.06422 -386.211559) (xy 443.080231 -386.20607)
			(xy 443.093566 -386.195646) (xy 443.098428 -386.188712) (xy 443.118748 -386.16001) (xy 443.12459 -386.152644)
			(xy 443.129924 -386.134356) (xy 443.123066 -386.04698) (xy 443.114938 -386.029708) (xy 443.107826 -386.023358)
			(xy 443.089012 -386.005256) (xy 443.056035 -385.96478) (xy 443.028882 -385.920186) (xy 443.008061 -385.872308)
			(xy 442.993959 -385.822039) (xy 442.986841 -385.770317) (xy 442.986414 -385.744212) (xy 442.986867 -385.716958)
			(xy 442.994622 -385.663006) (xy 443.009978 -385.610707) (xy 443.032621 -385.561125) (xy 443.06209 -385.515271)
			(xy 443.097785 -385.474077) (xy 443.138979 -385.438384) (xy 443.184834 -385.408916) (xy 443.234416 -385.386275)
			(xy 443.286716 -385.37092) (xy 443.340668 -385.363166) (xy 443.367922 -385.362704) (xy 443.394158 -385.363146)
			(xy 443.446135 -385.370344) (xy 443.496634 -385.384602) (xy 443.5447 -385.405649) (xy 443.589427 -385.433089)
			(xy 443.629968 -385.466403) (xy 443.648084 -385.485386) (xy 443.65545 -385.493006) (xy 443.6745 -385.501642)
			(xy 443.769496 -385.502404) (xy 443.7888 -385.494276) (xy 443.796166 -385.486656) (xy 443.814239 -385.468464)
			(xy 443.854381 -385.436556) (xy 443.898434 -385.41031) (xy 443.945606 -385.390201) (xy 443.995046 -385.37659)
			(xy 444.045863 -385.369723) (xy 444.071502 -385.369308) (xy 444.097485 -385.369722) (xy 444.148968 -385.376788)
			(xy 444.199017 -385.390774) (xy 444.246704 -385.411422) (xy 444.291149 -385.43835) (xy 444.331529 -385.471061)
			(xy 444.349632 -385.489704) (xy 444.357159 -385.496931) (xy 444.376294 -385.505198) (xy 444.386716 -385.505706)
			(xy 444.460884 -385.505706) (xy 444.471315 -385.505227) (xy 444.490468 -385.496968) (xy 444.497968 -385.489704)
			(xy 444.516083 -385.471073) (xy 444.556457 -385.438359) (xy 444.600899 -385.41143) (xy 444.648585 -385.390784)
			(xy 444.698633 -385.376803) (xy 444.750116 -385.369748) (xy 444.776098 -385.369308) (xy 444.803352 -385.369757)
			(xy 444.857304 -385.377514) (xy 444.909603 -385.392871) (xy 444.959184 -385.415514) (xy 445.005038 -385.444984)
			(xy 445.046231 -385.480679) (xy 445.081925 -385.521873) (xy 445.111392 -385.567728) (xy 445.134034 -385.61731)
			(xy 445.149389 -385.66961) (xy 445.157144 -385.723562) (xy 445.157606 -385.750816) (xy 445.157128 -385.77795)
			(xy 445.149441 -385.831671) (xy 445.134212 -385.883758) (xy 445.111748 -385.933158) (xy 445.082504 -385.978871)
			(xy 445.06515 -385.999736) (xy 445.059054 -386.006848) (xy 445.052704 -386.02412) (xy 445.053974 -386.110226)
			(xy 445.060832 -386.127244) (xy 445.066928 -386.134356) (xy 445.085435 -386.155533) (xy 445.116711 -386.202273)
			(xy 445.140793 -386.253095) (xy 445.157162 -386.3069) (xy 445.165462 -386.362523) (xy 445.165988 -386.390642)
			(xy 445.165412 -386.419767) (xy 445.156552 -386.477339) (xy 445.139044 -386.532895) (xy 445.113296 -386.585145)
			(xy 445.079906 -386.632874) (xy 445.039649 -386.674974) (xy 445.01689 -386.693156) (xy 445.007492 -386.700268)
			(xy 444.997078 -386.721604) (xy 444.997586 -386.826252) (xy 445.008 -386.847588) (xy 445.017652 -386.8547)
			(xy 445.040752 -386.872847) (xy 445.081617 -386.915042) (xy 445.115533 -386.963003) (xy 445.141697 -387.015595)
			(xy 445.159491 -387.071575) (xy 445.168495 -387.129622) (xy 445.169036 -387.158992) (xy 445.168581 -387.186363)
			(xy 445.160763 -387.240543) (xy 445.145272 -387.293047) (xy 445.122427 -387.342794) (xy 445.092699 -387.388759)
			(xy 445.075056 -387.40969) (xy 445.06896 -387.416802) (xy 445.06261 -387.43382) (xy 445.06261 -387.519164)
			(xy 445.06896 -387.536182) (xy 445.075056 -387.543294) (xy 445.09269 -387.564233) (xy 445.122416 -387.610199)
			(xy 445.145263 -387.659944) (xy 445.16076 -387.712446) (xy 445.16859 -387.766624) (xy 445.168591 -387.821364)
			(xy 445.160763 -387.875543) (xy 445.145267 -387.928044) (xy 445.122422 -387.97779) (xy 445.092697 -388.023758)
			(xy 445.075056 -388.04469) (xy 445.06896 -388.051802) (xy 445.06261 -388.06882) (xy 445.06261 -388.154164)
			(xy 445.06896 -388.171182) (xy 445.075056 -388.178294) (xy 445.092699 -388.199223) (xy 445.122412 -388.245196)
			(xy 445.145248 -388.294944) (xy 445.160738 -388.347446) (xy 445.168564 -388.401623) (xy 445.169036 -388.428992)
			(xy 445.168515 -388.456242) (xy 445.16076 -388.510187) (xy 445.145407 -388.562479) (xy 445.122769 -388.612055)
			(xy 445.093306 -388.657904) (xy 445.057619 -388.699093) (xy 445.016432 -388.734785) (xy 444.970586 -388.764252)
			(xy 444.921013 -388.786895) (xy 444.868722 -388.802253) (xy 444.814778 -388.810012) (xy 444.787528 -388.8105)
			(xy 444.761546 -388.810064) (xy 444.710064 -388.803002) (xy 444.660016 -388.78902) (xy 444.612328 -388.768376)
			(xy 444.567883 -388.741452) (xy 444.527502 -388.708746) (xy 444.509398 -388.690104) (xy 444.501859 -388.682891)
			(xy 444.482733 -388.674616) (xy 444.472314 -388.674102) (xy 444.398146 -388.674102) (xy 444.387711 -388.674541)
			(xy 444.368558 -388.682828) (xy 444.361062 -388.690104) (xy 444.342982 -388.70877) (xy 444.3026 -388.741481)
			(xy 444.258151 -388.768405) (xy 444.210458 -388.789045) (xy 444.160404 -388.803018) (xy 444.108916 -388.810065)
			(xy 444.082932 -388.8105) (xy 444.05568 -388.810015) (xy 444.001729 -388.802262) (xy 443.949431 -388.78691)
			(xy 443.899851 -388.76427) (xy 443.853997 -388.734805) (xy 443.812804 -388.699113) (xy 443.777109 -388.657922)
			(xy 443.747641 -388.612071) (xy 443.724999 -388.562491) (xy 443.709643 -388.510194) (xy 443.701887 -388.456244)
			(xy 443.701424 -388.428992) (xy 443.70188 -388.401621) (xy 443.709699 -388.347442) (xy 443.72519 -388.294938)
			(xy 443.748034 -388.245191) (xy 443.777762 -388.199225) (xy 443.795404 -388.178294) (xy 443.8015 -388.171182)
			(xy 443.80785 -388.154164) (xy 443.80785 -388.06882) (xy 443.8015 -388.051802) (xy 443.795404 -388.04469)
			(xy 443.777747 -388.023772) (xy 443.748038 -387.977795) (xy 443.725205 -387.928044) (xy 443.709718 -387.875541)
			(xy 443.701895 -387.821362) (xy 443.701424 -387.793992) (xy 443.701952 -387.764514) (xy 443.711023 -387.70626)
			(xy 443.728948 -387.650095) (xy 443.7553 -387.597356) (xy 443.789452 -387.549299) (xy 443.809628 -387.5278)
			(xy 443.816159 -387.520463) (xy 443.823606 -387.502304) (xy 443.824106 -387.492494) (xy 443.824106 -387.439154)
			(xy 443.81039 -387.425946) (xy 443.802262 -387.417564) (xy 443.780672 -387.40969) (xy 443.678818 -387.419596)
			(xy 443.65926 -387.431534) (xy 443.65291 -387.441186) (xy 443.637716 -387.463474) (xy 443.602042 -387.503932)
			(xy 443.561022 -387.538959) (xy 443.515476 -387.567856) (xy 443.466313 -387.590047) (xy 443.414513 -387.605089)
			(xy 443.36111 -387.612682) (xy 443.33414 -387.613144) (xy 443.3054 -387.612645) (xy 443.248572 -387.604015)
			(xy 443.193682 -387.586958) (xy 443.141971 -387.561861) (xy 443.094609 -387.529292) (xy 443.073282 -387.51002)
			(xy 443.06617 -387.503416) (xy 443.048644 -387.496304) (xy 442.959236 -387.496304) (xy 442.94171 -387.503416)
			(xy 442.934598 -387.51002) (xy 442.913248 -387.529265) (xy 442.865893 -387.561836) (xy 442.814187 -387.586934)
			(xy 442.759301 -387.603991) (xy 442.702478 -387.61262) (xy 442.67374 -387.613144) (xy 442.64649 -387.612608)
			(xy 442.592543 -387.604857) (xy 442.540249 -387.589508) (xy 442.490671 -387.566873) (xy 442.44482 -387.537412)
			(xy 442.403628 -387.501726) (xy 442.367933 -387.460541) (xy 442.338464 -387.414695) (xy 442.315819 -387.365122)
			(xy 442.300459 -387.312831) (xy 442.292698 -387.258886) (xy 442.292232 -387.231636) (xy 442.292795 -387.203509)
			(xy 442.30105 -387.147864) (xy 442.317387 -387.094035) (xy 442.341452 -387.043188) (xy 442.372723 -386.996426)
			(xy 442.410521 -386.954764) (xy 442.454028 -386.919103) (xy 442.477906 -386.90423) (xy 442.489844 -386.897118)
			(xy 442.503052 -386.87375) (xy 442.50102 -386.757926) (xy 442.487304 -386.734812) (xy 442.475112 -386.728208)
			(xy 442.450014 -386.713677) (xy 442.404186 -386.678139) (xy 442.364263 -386.636074) (xy 442.331165 -386.588453)
			(xy 442.305654 -386.536372) (xy 442.288319 -386.481031) (xy 442.279557 -386.423703) (xy 442.279024 -386.394706)
			(xy 437.485035 -386.394706) (xy 437.475548 -386.420862) (xy 437.404726 -386.592452) (xy 437.326511 -386.760799)
			(xy 437.24105 -386.925587) (xy 437.148505 -387.086503) (xy 437.049051 -387.243243) (xy 436.942876 -387.395511)
			(xy 436.830181 -387.543018) (xy 436.711179 -387.685486) (xy 436.586095 -387.822645) (xy 436.455165 -387.954235)
			(xy 436.318638 -388.080008) (xy 436.249123 -388.13867) (xy 441.467492 -388.13867) (xy 441.471563 -388.083048)
			(xy 441.483689 -388.028611) (xy 441.503612 -387.97652) (xy 441.530908 -387.927885) (xy 441.564994 -387.883742)
			(xy 441.605143 -387.845033) (xy 441.650501 -387.812582) (xy 441.700101 -387.787081) (xy 441.752885 -387.769074)
			(xy 441.807728 -387.758944) (xy 441.863462 -387.756907) (xy 441.918899 -387.763007) (xy 441.972856 -387.777113)
			(xy 442.024185 -387.798925) (xy 442.071791 -387.827979) (xy 442.114659 -387.863654) (xy 442.151876 -387.905191)
			(xy 442.182649 -387.951704) (xy 442.206321 -388.002201) (xy 442.222389 -388.055608) (xy 442.230509 -388.110784)
			(xy 442.231018 -388.13867) (xy 442.230509 -388.166556) (xy 442.222389 -388.221732) (xy 442.206321 -388.275139)
			(xy 442.182649 -388.325636) (xy 442.151876 -388.372149) (xy 442.114659 -388.413686) (xy 442.071791 -388.449361)
			(xy 442.024185 -388.478415) (xy 441.972856 -388.500227) (xy 441.918899 -388.514333) (xy 441.863462 -388.520433)
			(xy 441.807728 -388.518396) (xy 441.752885 -388.508266) (xy 441.700101 -388.490259) (xy 441.650501 -388.464758)
			(xy 441.605143 -388.432307) (xy 441.564994 -388.393598) (xy 441.530908 -388.349455) (xy 441.503612 -388.30082)
			(xy 441.483689 -388.248729) (xy 441.471563 -388.194292) (xy 441.467492 -388.13867) (xy 436.249123 -388.13867)
			(xy 436.176771 -388.199726) (xy 436.029833 -388.313162) (xy 435.878102 -388.420103) (xy 435.721864 -388.520345)
			(xy 435.561416 -388.613698) (xy 435.397061 -388.699988) (xy 435.229109 -388.779049) (xy 435.057878 -388.850733)
			(xy 434.883692 -388.914905) (xy 434.795422 -388.943596) (xy 434.788564 -388.94639) (xy 434.784793 -388.948279)
			(xy 434.777893 -388.953125) (xy 434.774848 -388.956042) (xy 432.297235 -391.433655) (xy 438.176335 -391.433655)
			(xy 438.176335 -391.379145) (xy 438.184093 -391.32519) (xy 438.19945 -391.272888) (xy 438.222095 -391.223304)
			(xy 438.251566 -391.177448) (xy 438.287264 -391.136252) (xy 438.32846 -391.100557) (xy 438.374318 -391.071088)
			(xy 438.423903 -391.048445) (xy 438.476205 -391.033089) (xy 438.530161 -391.025334) (xy 438.557416 -391.024872)
			(xy 438.583782 -391.025269) (xy 438.636008 -391.032558) (xy 438.686734 -391.046966) (xy 438.734993 -391.068221)
			(xy 438.779867 -391.095916) (xy 438.820502 -391.129524) (xy 438.856123 -391.168407) (xy 438.886053 -391.211822)
			(xy 438.898284 -391.235184) (xy 438.904969 -391.24758) (xy 438.924002 -391.268328) (xy 438.947979 -391.283088)
			(xy 438.975075 -391.290738) (xy 439.003231 -391.290696) (xy 439.030304 -391.282964) (xy 439.054235 -391.268131)
			(xy 439.073206 -391.247326) (xy 439.079894 -391.23493) (xy 439.092167 -391.211565) (xy 439.122096 -391.168096)
			(xy 439.157728 -391.129165) (xy 439.198386 -391.095516) (xy 439.243291 -391.06779) (xy 439.291589 -391.046516)
			(xy 439.342358 -391.032099) (xy 439.394628 -391.024816) (xy 439.421016 -391.024364) (xy 439.448264 -391.024907)
			(xy 439.502206 -391.032665) (xy 439.554495 -391.04802) (xy 439.604067 -391.070661) (xy 439.649912 -391.100125)
			(xy 439.691097 -391.135814) (xy 439.726784 -391.177001) (xy 439.756247 -391.222847) (xy 439.778885 -391.27242)
			(xy 439.794238 -391.324709) (xy 439.801994 -391.378652) (xy 439.801994 -391.433148) (xy 439.794238 -391.487091)
			(xy 439.778885 -391.53938) (xy 439.756247 -391.588953) (xy 439.726784 -391.634799) (xy 439.691097 -391.675986)
			(xy 439.649912 -391.711675) (xy 439.604067 -391.741139) (xy 439.554495 -391.76378) (xy 439.502206 -391.779135)
			(xy 439.448264 -391.786893) (xy 439.421016 -391.78738) (xy 439.394652 -391.786928) (xy 439.34243 -391.779645)
			(xy 439.291707 -391.765243) (xy 439.243449 -391.743996) (xy 439.198575 -391.716308) (xy 439.157939 -391.682708)
			(xy 439.122316 -391.643833) (xy 439.092382 -391.600426) (xy 439.080148 -391.577068) (xy 439.073412 -391.564705)
			(xy 439.054384 -391.54397) (xy 439.030417 -391.529218) (xy 439.003333 -391.52157) (xy 438.97519 -391.521609)
			(xy 438.948127 -391.52933) (xy 438.924201 -391.544148) (xy 438.90523 -391.564935) (xy 438.898538 -391.577322)
			(xy 438.886339 -391.600728) (xy 438.856398 -391.644196) (xy 438.820754 -391.683123) (xy 438.780085 -391.716769)
			(xy 438.735169 -391.74449) (xy 438.686862 -391.765757) (xy 438.636085 -391.780166) (xy 438.583807 -391.787441)
			(xy 438.557416 -391.787888) (xy 438.530161 -391.787466) (xy 438.476205 -391.779711) (xy 438.423903 -391.764355)
			(xy 438.374318 -391.741712) (xy 438.32846 -391.712243) (xy 438.287264 -391.676548) (xy 438.251566 -391.635352)
			(xy 438.222095 -391.589496) (xy 438.19945 -391.539912) (xy 438.184093 -391.48761) (xy 438.176335 -391.433655)
			(xy 432.297235 -391.433655) (xy 432.275742 -391.455148) (xy 432.268376 -391.46226) (xy 432.260756 -391.481056)
			(xy 432.260756 -397.835628) (xy 440.404248 -397.835628) (xy 440.408319 -397.780006) (xy 440.420445 -397.725569)
			(xy 440.440368 -397.673478) (xy 440.467664 -397.624843) (xy 440.50175 -397.5807) (xy 440.541899 -397.541991)
			(xy 440.587257 -397.50954) (xy 440.636857 -397.484039) (xy 440.689641 -397.466032) (xy 440.744484 -397.455902)
			(xy 440.800218 -397.453865) (xy 440.855655 -397.459965) (xy 440.909612 -397.474071) (xy 440.960941 -397.495883)
			(xy 441.008547 -397.524937) (xy 441.051415 -397.560612) (xy 441.088632 -397.602149) (xy 441.119405 -397.648662)
			(xy 441.143077 -397.699159) (xy 441.159145 -397.752566) (xy 441.167265 -397.807742) (xy 441.167774 -397.835628)
			(xy 441.167265 -397.863514) (xy 441.159145 -397.91869) (xy 441.145926 -397.962628) (xy 449.472048 -397.962628)
			(xy 449.476119 -397.907006) (xy 449.488245 -397.852569) (xy 449.508168 -397.800478) (xy 449.535464 -397.751843)
			(xy 449.56955 -397.7077) (xy 449.609699 -397.668991) (xy 449.655057 -397.63654) (xy 449.704657 -397.611039)
			(xy 449.757441 -397.593032) (xy 449.812284 -397.582902) (xy 449.868018 -397.580865) (xy 449.923455 -397.586965)
			(xy 449.977412 -397.601071) (xy 450.028741 -397.622883) (xy 450.076347 -397.651937) (xy 450.119215 -397.687612)
			(xy 450.156432 -397.729149) (xy 450.187205 -397.775662) (xy 450.210877 -397.826159) (xy 450.226945 -397.879566)
			(xy 450.235065 -397.934742) (xy 450.235574 -397.962628) (xy 450.235065 -397.990514) (xy 450.226945 -398.04569)
			(xy 450.210877 -398.099097) (xy 450.187205 -398.149594) (xy 450.156432 -398.196107) (xy 450.119215 -398.237644)
			(xy 450.076347 -398.273319) (xy 450.028741 -398.302373) (xy 449.977412 -398.324185) (xy 449.923455 -398.338291)
			(xy 449.868018 -398.344391) (xy 449.812284 -398.342354) (xy 449.757441 -398.332224) (xy 449.704657 -398.314217)
			(xy 449.655057 -398.288716) (xy 449.609699 -398.256265) (xy 449.56955 -398.217556) (xy 449.535464 -398.173413)
			(xy 449.508168 -398.124778) (xy 449.488245 -398.072687) (xy 449.476119 -398.01825) (xy 449.472048 -397.962628)
			(xy 441.145926 -397.962628) (xy 441.143077 -397.972097) (xy 441.119405 -398.022594) (xy 441.088632 -398.069107)
			(xy 441.051415 -398.110644) (xy 441.008547 -398.146319) (xy 440.960941 -398.175373) (xy 440.909612 -398.197185)
			(xy 440.855655 -398.211291) (xy 440.800218 -398.217391) (xy 440.744484 -398.215354) (xy 440.689641 -398.205224)
			(xy 440.636857 -398.187217) (xy 440.587257 -398.161716) (xy 440.541899 -398.129265) (xy 440.50175 -398.090556)
			(xy 440.467664 -398.046413) (xy 440.440368 -397.997778) (xy 440.420445 -397.945687) (xy 440.408319 -397.89125)
			(xy 440.404248 -397.835628) (xy 432.260756 -397.835628) (xy 432.260756 -398.737328) (xy 440.397136 -398.737328)
			(xy 440.401207 -398.681706) (xy 440.413333 -398.627269) (xy 440.433256 -398.575178) (xy 440.460552 -398.526543)
			(xy 440.494638 -398.4824) (xy 440.534787 -398.443691) (xy 440.580145 -398.41124) (xy 440.629745 -398.385739)
			(xy 440.682529 -398.367732) (xy 440.737372 -398.357602) (xy 440.793106 -398.355565) (xy 440.848543 -398.361665)
			(xy 440.9025 -398.375771) (xy 440.953829 -398.397583) (xy 441.001435 -398.426637) (xy 441.044303 -398.462312)
			(xy 441.08152 -398.503849) (xy 441.112293 -398.550362) (xy 441.135965 -398.600859) (xy 441.152033 -398.654266)
			(xy 441.160153 -398.709442) (xy 441.160662 -398.737328) (xy 441.160153 -398.765214) (xy 441.152033 -398.82039)
			(xy 441.138814 -398.864328) (xy 449.475858 -398.864328) (xy 449.479929 -398.808706) (xy 449.492055 -398.754269)
			(xy 449.511978 -398.702178) (xy 449.539274 -398.653543) (xy 449.57336 -398.6094) (xy 449.613509 -398.570691)
			(xy 449.658867 -398.53824) (xy 449.708467 -398.512739) (xy 449.761251 -398.494732) (xy 449.816094 -398.484602)
			(xy 449.871828 -398.482565) (xy 449.927265 -398.488665) (xy 449.981222 -398.502771) (xy 450.032551 -398.524583)
			(xy 450.080157 -398.553637) (xy 450.123025 -398.589312) (xy 450.160242 -398.630849) (xy 450.191015 -398.677362)
			(xy 450.214687 -398.727859) (xy 450.230755 -398.781266) (xy 450.238875 -398.836442) (xy 450.239384 -398.864328)
			(xy 450.238875 -398.892214) (xy 450.230755 -398.94739) (xy 450.214687 -399.000797) (xy 450.191015 -399.051294)
			(xy 450.160242 -399.097807) (xy 450.123025 -399.139344) (xy 450.080157 -399.175019) (xy 450.032551 -399.204073)
			(xy 449.981222 -399.225885) (xy 449.927265 -399.239991) (xy 449.871828 -399.246091) (xy 449.816094 -399.244054)
			(xy 449.761251 -399.233924) (xy 449.708467 -399.215917) (xy 449.658867 -399.190416) (xy 449.613509 -399.157965)
			(xy 449.57336 -399.119256) (xy 449.539274 -399.075113) (xy 449.511978 -399.026478) (xy 449.492055 -398.974387)
			(xy 449.479929 -398.91995) (xy 449.475858 -398.864328) (xy 441.138814 -398.864328) (xy 441.135965 -398.873797)
			(xy 441.112293 -398.924294) (xy 441.08152 -398.970807) (xy 441.044303 -399.012344) (xy 441.001435 -399.048019)
			(xy 440.953829 -399.077073) (xy 440.9025 -399.098885) (xy 440.848543 -399.112991) (xy 440.793106 -399.119091)
			(xy 440.737372 -399.117054) (xy 440.682529 -399.106924) (xy 440.629745 -399.088917) (xy 440.580145 -399.063416)
			(xy 440.534787 -399.030965) (xy 440.494638 -398.992256) (xy 440.460552 -398.948113) (xy 440.433256 -398.899478)
			(xy 440.413333 -398.847387) (xy 440.401207 -398.79295) (xy 440.397136 -398.737328) (xy 432.260756 -398.737328)
			(xy 432.260756 -399.2834) (xy 445.415396 -399.2834) (xy 445.419379 -399.230248) (xy 445.431241 -399.178283)
			(xy 445.450715 -399.128667) (xy 445.477367 -399.082508) (xy 445.510601 -399.040836) (xy 445.549675 -399.004584)
			(xy 445.593717 -398.974561) (xy 445.641741 -398.951438) (xy 445.692675 -398.935731) (xy 445.745381 -398.927791)
			(xy 445.772032 -398.92732) (xy 445.798392 -398.927815) (xy 445.850533 -398.9356) (xy 445.900956 -398.950994)
			(xy 445.948554 -398.973661) (xy 445.992286 -399.003103) (xy 446.012062 -399.020538) (xy 446.019174 -399.026888)
			(xy 446.036954 -399.033746) (xy 446.12433 -399.033746) (xy 446.14211 -399.026888) (xy 446.149222 -399.020538)
			(xy 446.169016 -399.003127) (xy 446.212754 -398.973702) (xy 446.260349 -398.95104) (xy 446.310763 -398.935634)
			(xy 446.362895 -398.92782) (xy 446.389252 -398.92732) (xy 446.415612 -398.927803) (xy 446.467754 -398.935591)
			(xy 446.518177 -398.950988) (xy 446.565775 -398.973657) (xy 446.609506 -399.003102) (xy 446.629282 -399.020538)
			(xy 446.636394 -399.026888) (xy 446.654174 -399.033746) (xy 446.74155 -399.033746) (xy 446.75933 -399.026888)
			(xy 446.766442 -399.020538) (xy 446.786228 -399.003117) (xy 446.829969 -398.973694) (xy 446.877566 -398.951034)
			(xy 446.927981 -398.93563) (xy 446.980115 -398.927819) (xy 447.006472 -398.92732) (xy 447.031468 -398.927745)
			(xy 447.080968 -398.93474) (xy 447.129005 -398.948582) (xy 447.174638 -398.968999) (xy 447.21697 -398.995592)
			(xy 447.236342 -399.011394) (xy 447.243454 -399.01749) (xy 447.259964 -399.023586) (xy 447.344038 -399.023586)
			(xy 447.360548 -399.01749) (xy 447.36766 -399.011394) (xy 447.387032 -398.995591) (xy 447.42936 -398.968989)
			(xy 447.474992 -398.948567) (xy 447.523031 -398.934727) (xy 447.572533 -398.92774) (xy 447.59753 -398.92732)
			(xy 447.624436 -398.927823) (xy 447.677639 -398.9359) (xy 447.72902 -398.951895) (xy 447.777406 -398.975444)
			(xy 447.821695 -399.00601) (xy 447.841624 -399.024094) (xy 447.848736 -399.030698) (xy 447.865754 -399.03781)
			(xy 447.953384 -399.039588) (xy 447.970656 -399.033238) (xy 447.978022 -399.026888) (xy 447.998965 -399.009317)
			(xy 448.044897 -398.979676) (xy 448.094591 -398.956895) (xy 448.147027 -398.941443) (xy 448.201133 -398.933634)
			(xy 448.228466 -398.933162) (xy 448.255718 -398.933683) (xy 448.309669 -398.941435) (xy 448.361966 -398.956787)
			(xy 448.411547 -398.979426) (xy 448.457401 -399.008891) (xy 448.498594 -399.044582) (xy 448.534289 -399.085772)
			(xy 448.563758 -399.131623) (xy 448.586401 -399.181202) (xy 448.601757 -399.233498) (xy 448.608933 -399.2834)
			(xy 454.494221 -399.2834) (xy 454.498203 -399.230259) (xy 454.51006 -399.178305) (xy 454.529528 -399.128698)
			(xy 454.556171 -399.082546) (xy 454.589394 -399.040881) (xy 454.628456 -399.004632) (xy 454.672484 -398.974609)
			(xy 454.720494 -398.951483) (xy 454.771415 -398.93577) (xy 454.824109 -398.927821) (xy 454.850754 -398.92732)
			(xy 454.877114 -398.927802) (xy 454.929257 -398.93559) (xy 454.979679 -398.950987) (xy 455.027277 -398.973657)
			(xy 455.071008 -399.003102) (xy 455.090784 -399.020538) (xy 455.097896 -399.026888) (xy 455.115676 -399.033746)
			(xy 455.203052 -399.033746) (xy 455.220832 -399.026888) (xy 455.227944 -399.020538) (xy 455.247729 -399.003116)
			(xy 455.29147 -398.973694) (xy 455.339067 -398.951033) (xy 455.389482 -398.93563) (xy 455.441616 -398.927819)
			(xy 455.467974 -398.92732) (xy 455.494335 -398.92779) (xy 455.546478 -398.935581) (xy 455.5969 -398.950981)
			(xy 455.644498 -398.973653) (xy 455.688228 -399.003101) (xy 455.708004 -399.020538) (xy 455.715116 -399.026888)
			(xy 455.732896 -399.033746) (xy 455.820272 -399.033746) (xy 455.838052 -399.026888) (xy 455.845164 -399.020538)
			(xy 455.864941 -399.003107) (xy 455.908684 -398.973685) (xy 455.956283 -398.951027) (xy 456.0067 -398.935626)
			(xy 456.058836 -398.927817) (xy 456.085194 -398.92732) (xy 456.11019 -398.927733) (xy 456.159691 -398.93473)
			(xy 456.207729 -398.948575) (xy 456.253361 -398.968996) (xy 456.295692 -398.995591) (xy 456.315064 -399.011394)
			(xy 456.322176 -399.01749) (xy 456.338686 -399.023586) (xy 456.42276 -399.023586) (xy 456.43927 -399.01749)
			(xy 456.446382 -399.011394) (xy 456.465746 -398.995581) (xy 456.508076 -398.96898) (xy 456.55371 -398.94856)
			(xy 456.601751 -398.934722) (xy 456.651255 -398.927738) (xy 456.676252 -398.92732) (xy 456.701833 -398.927781)
			(xy 456.75247 -398.935097) (xy 456.801538 -398.949585) (xy 456.848027 -398.970947) (xy 456.89098 -398.998743)
			(xy 456.929513 -399.032401) (xy 456.946508 -399.051526) (xy 456.952858 -399.059146) (xy 456.97013 -399.068036)
			(xy 457.059792 -399.076926) (xy 457.078334 -399.071338) (xy 457.086208 -399.065242) (xy 457.106427 -399.049888)
			(xy 457.150186 -399.024146) (xy 457.196972 -399.004433) (xy 457.245959 -398.991098) (xy 457.296281 -398.984375)
			(xy 457.321666 -398.983962) (xy 457.348918 -398.984483) (xy 457.402869 -398.992235) (xy 457.455166 -399.007587)
			(xy 457.504747 -399.030226) (xy 457.550601 -399.059691) (xy 457.591794 -399.095382) (xy 457.627489 -399.136572)
			(xy 457.656958 -399.182423) (xy 457.679601 -399.232002) (xy 457.694957 -399.284298) (xy 457.702715 -399.338248)
			(xy 457.702715 -399.392752) (xy 457.694957 -399.446702) (xy 457.679601 -399.498998) (xy 457.656958 -399.548577)
			(xy 457.627489 -399.594428) (xy 457.591794 -399.635618) (xy 457.550601 -399.671309) (xy 457.504747 -399.700774)
			(xy 457.455166 -399.723413) (xy 457.402869 -399.738765) (xy 457.348918 -399.746517) (xy 457.321666 -399.746978)
			(xy 457.292465 -399.746417) (xy 457.234744 -399.737518) (xy 457.179057 -399.719918) (xy 457.126706 -399.694029)
			(xy 457.078917 -399.660458) (xy 457.036808 -399.619989) (xy 457.018644 -399.597118) (xy 457.012548 -399.589244)
			(xy 456.996038 -399.579338) (xy 456.906884 -399.565622) (xy 456.888088 -399.56994) (xy 456.87996 -399.575528)
			(xy 456.857414 -399.59061) (xy 456.808731 -399.61453) (xy 456.756986 -399.630793) (xy 456.703373 -399.639024)
			(xy 456.676252 -399.639536) (xy 456.651257 -399.639084) (xy 456.601759 -399.632094) (xy 456.553722 -399.618257)
			(xy 456.508089 -399.597846) (xy 456.465756 -399.57126) (xy 456.446382 -399.555462) (xy 456.43927 -399.549366)
			(xy 456.42276 -399.54327) (xy 456.338686 -399.54327) (xy 456.322176 -399.549366) (xy 456.315064 -399.555462)
			(xy 456.29569 -399.571262) (xy 456.253362 -399.597863) (xy 456.207731 -399.618285) (xy 456.159692 -399.632126)
			(xy 456.11019 -399.639114) (xy 456.085194 -399.639536) (xy 456.058833 -399.639071) (xy 456.006691 -399.631277)
			(xy 455.956269 -399.615875) (xy 455.908672 -399.593202) (xy 455.86494 -399.563754) (xy 455.845164 -399.546318)
			(xy 455.838052 -399.539968) (xy 455.820272 -399.53311) (xy 455.732896 -399.53311) (xy 455.715116 -399.539968)
			(xy 455.708004 -399.546318) (xy 455.688233 -399.563757) (xy 455.644489 -399.593179) (xy 455.596888 -399.615836)
			(xy 455.54647 -399.631236) (xy 455.494333 -399.639041) (xy 455.467974 -399.639536) (xy 455.441615 -399.639023)
			(xy 455.389475 -399.63124) (xy 455.339054 -399.615849) (xy 455.291455 -399.593187) (xy 455.247722 -399.56375)
			(xy 455.227944 -399.546318) (xy 455.220832 -399.539968) (xy 455.203052 -399.53311) (xy 455.115676 -399.53311)
			(xy 455.097896 -399.539968) (xy 455.090784 -399.546318) (xy 455.070981 -399.563719) (xy 455.027246 -399.593146)
			(xy 454.979653 -399.615811) (xy 454.929242 -399.631219) (xy 454.87711 -399.639035) (xy 454.850754 -399.639536)
			(xy 454.824109 -399.638979) (xy 454.771415 -399.63103) (xy 454.720494 -399.615317) (xy 454.672484 -399.592191)
			(xy 454.628456 -399.562168) (xy 454.589394 -399.525919) (xy 454.556171 -399.484254) (xy 454.529528 -399.438102)
			(xy 454.51006 -399.388495) (xy 454.498203 -399.336541) (xy 454.494221 -399.2834) (xy 448.608933 -399.2834)
			(xy 448.609515 -399.287448) (xy 448.609515 -399.341952) (xy 448.601757 -399.395902) (xy 448.586401 -399.448198)
			(xy 448.563758 -399.497777) (xy 448.534289 -399.543628) (xy 448.498594 -399.584818) (xy 448.457401 -399.620509)
			(xy 448.411547 -399.649974) (xy 448.361966 -399.672613) (xy 448.309669 -399.687965) (xy 448.255718 -399.695717)
			(xy 448.228466 -399.696178) (xy 448.202545 -399.69574) (xy 448.151182 -399.688705) (xy 448.101244 -399.674782)
			(xy 448.05365 -399.654229) (xy 448.009276 -399.627422) (xy 447.968939 -399.594855) (xy 447.950844 -399.57629)
			(xy 447.94424 -399.569178) (xy 447.927476 -399.561304) (xy 447.840354 -399.554446) (xy 447.822574 -399.559526)
			(xy 447.814954 -399.565622) (xy 447.79142 -399.582994) (xy 447.739865 -399.610621) (xy 447.684487 -399.629448)
			(xy 447.626776 -399.638967) (xy 447.59753 -399.639536) (xy 447.572535 -399.639096) (xy 447.523036 -399.632103)
			(xy 447.474999 -399.618264) (xy 447.429367 -399.59785) (xy 447.387033 -399.571261) (xy 447.36766 -399.555462)
			(xy 447.360548 -399.549366) (xy 447.344038 -399.54327) (xy 447.259964 -399.54327) (xy 447.243454 -399.549366)
			(xy 447.236342 -399.555462) (xy 447.216976 -399.571273) (xy 447.174646 -399.597872) (xy 447.129012 -399.618291)
			(xy 447.080972 -399.63213) (xy 447.031469 -399.639116) (xy 447.006472 -399.639536) (xy 446.980113 -399.639024)
			(xy 446.927973 -399.631241) (xy 446.877551 -399.61585) (xy 446.829953 -399.593188) (xy 446.78622 -399.56375)
			(xy 446.766442 -399.546318) (xy 446.75933 -399.539968) (xy 446.74155 -399.53311) (xy 446.654174 -399.53311)
			(xy 446.636394 -399.539968) (xy 446.629282 -399.546318) (xy 446.60948 -399.56372) (xy 446.565744 -399.593147)
			(xy 446.518152 -399.615812) (xy 446.46774 -399.63122) (xy 446.415608 -399.639035) (xy 446.389252 -399.639536)
			(xy 446.362893 -399.639036) (xy 446.310752 -399.63125) (xy 446.26033 -399.615856) (xy 446.212732 -399.593191)
			(xy 446.168999 -399.563751) (xy 446.149222 -399.546318) (xy 446.14211 -399.539968) (xy 446.12433 -399.53311)
			(xy 446.036954 -399.53311) (xy 446.019174 -399.539968) (xy 446.012062 -399.546318) (xy 445.992268 -399.563729)
			(xy 445.94853 -399.593155) (xy 445.900935 -399.615818) (xy 445.850522 -399.631224) (xy 445.798389 -399.639036)
			(xy 445.772032 -399.639536) (xy 445.745381 -399.639009) (xy 445.692675 -399.631069) (xy 445.641741 -399.615362)
			(xy 445.593716 -399.592239) (xy 445.549675 -399.562216) (xy 445.510601 -399.525964) (xy 445.477367 -399.484292)
			(xy 445.450715 -399.438133) (xy 445.431241 -399.388517) (xy 445.419379 -399.336552) (xy 445.415396 -399.2834)
			(xy 432.260756 -399.2834) (xy 432.260756 -400.15287) (xy 447.338958 -400.15287) (xy 447.33945 -400.12562)
			(xy 447.34721 -400.071674) (xy 447.362567 -400.019381) (xy 447.385209 -399.969806) (xy 447.414675 -399.923958)
			(xy 447.450366 -399.882769) (xy 447.491554 -399.847078) (xy 447.537403 -399.817611) (xy 447.586978 -399.794968)
			(xy 447.63927 -399.77961) (xy 447.693216 -399.77185) (xy 447.720466 -399.771362) (xy 447.749383 -399.771881)
			(xy 447.806555 -399.780607) (xy 447.861755 -399.797863) (xy 447.913718 -399.823254) (xy 447.961251 -399.856199)
			(xy 448.003267 -399.895941) (xy 448.021456 -399.918428) (xy 448.029036 -399.92717) (xy 448.049781 -399.937363)
			(xy 448.061334 -399.937986) (xy 448.141598 -399.937986) (xy 448.153166 -399.937419) (xy 448.173937 -399.927222)
			(xy 448.181476 -399.918428) (xy 448.199688 -399.895962) (xy 448.241702 -399.856224) (xy 448.289233 -399.823282)
			(xy 448.34119 -399.797891) (xy 448.396384 -399.780631) (xy 448.453551 -399.771899) (xy 448.482466 -399.771362)
			(xy 448.509717 -399.771887) (xy 448.563664 -399.779638) (xy 448.615959 -399.794989) (xy 448.665537 -399.817625)
			(xy 448.711389 -399.847087) (xy 448.752581 -399.882774) (xy 448.788275 -399.92396) (xy 448.817744 -399.969807)
			(xy 448.840389 -400.019381) (xy 448.855748 -400.071674) (xy 448.863509 -400.125619) (xy 448.863649 -400.13382)
			(xy 449.300598 -400.13382) (xy 449.304669 -400.078198) (xy 449.316795 -400.023761) (xy 449.336718 -399.97167)
			(xy 449.364014 -399.923035) (xy 449.3981 -399.878892) (xy 449.438249 -399.840183) (xy 449.483607 -399.807732)
			(xy 449.533207 -399.782231) (xy 449.585991 -399.764224) (xy 449.640834 -399.754094) (xy 449.696568 -399.752057)
			(xy 449.752005 -399.758157) (xy 449.805962 -399.772263) (xy 449.857291 -399.794075) (xy 449.904897 -399.823129)
			(xy 449.947765 -399.858804) (xy 449.984982 -399.900341) (xy 450.015755 -399.946854) (xy 450.039427 -399.997351)
			(xy 450.055495 -400.050758) (xy 450.063615 -400.105934) (xy 450.064124 -400.13382) (xy 450.063615 -400.161706)
			(xy 450.057439 -400.20367) (xy 456.432158 -400.20367) (xy 456.43265 -400.17642) (xy 456.44041 -400.122474)
			(xy 456.455767 -400.070181) (xy 456.478409 -400.020606) (xy 456.507875 -399.974758) (xy 456.543566 -399.933569)
			(xy 456.584754 -399.897878) (xy 456.630603 -399.868411) (xy 456.680178 -399.845768) (xy 456.73247 -399.83041)
			(xy 456.786416 -399.82265) (xy 456.813666 -399.822162) (xy 456.842583 -399.822681) (xy 456.899755 -399.831407)
			(xy 456.954955 -399.848663) (xy 457.006918 -399.874054) (xy 457.054451 -399.906999) (xy 457.096467 -399.946741)
			(xy 457.114656 -399.969228) (xy 457.122236 -399.97797) (xy 457.142981 -399.988163) (xy 457.154534 -399.988786)
			(xy 457.234798 -399.988786) (xy 457.246366 -399.988219) (xy 457.267137 -399.978022) (xy 457.274676 -399.969228)
			(xy 457.292888 -399.946762) (xy 457.334902 -399.907024) (xy 457.382433 -399.874082) (xy 457.43439 -399.848691)
			(xy 457.489584 -399.831431) (xy 457.546751 -399.822699) (xy 457.575666 -399.822162) (xy 457.602917 -399.822687)
			(xy 457.656864 -399.830438) (xy 457.709159 -399.845789) (xy 457.758737 -399.868425) (xy 457.804589 -399.897887)
			(xy 457.845781 -399.933574) (xy 457.881475 -399.97476) (xy 457.910944 -400.020607) (xy 457.933589 -400.070181)
			(xy 457.948948 -400.122474) (xy 457.956709 -400.176419) (xy 457.957174 -400.20367) (xy 457.956772 -400.22936)
			(xy 457.949869 -400.280274) (xy 457.936196 -400.329801) (xy 457.916 -400.377046) (xy 457.889648 -400.421154)
			(xy 457.857616 -400.461326) (xy 457.820483 -400.496838) (xy 457.799948 -400.51228) (xy 457.788772 -400.520408)
			(xy 457.777596 -400.545808) (xy 457.791566 -400.661378) (xy 457.80833 -400.683476) (xy 457.821284 -400.688556)
			(xy 457.847233 -400.699707) (xy 457.895816 -400.728508) (xy 457.939623 -400.764156) (xy 457.977696 -400.805872)
			(xy 458.009205 -400.852744) (xy 458.03346 -400.903748) (xy 458.049932 -400.95777) (xy 458.058262 -401.013631)
			(xy 458.058774 -401.04187) (xy 458.058317 -401.069124) (xy 458.050563 -401.123077) (xy 458.035209 -401.175377)
			(xy 458.012567 -401.224959) (xy 457.983099 -401.270814) (xy 457.947405 -401.312008) (xy 457.906211 -401.347702)
			(xy 457.860355 -401.377169) (xy 457.810773 -401.39981) (xy 457.758473 -401.415164) (xy 457.70452 -401.422917)
			(xy 457.677266 -401.423378) (xy 457.64835 -401.422821) (xy 457.591181 -401.414101) (xy 457.535982 -401.396851)
			(xy 457.48402 -401.371467) (xy 457.436485 -401.33853) (xy 457.394467 -401.298795) (xy 457.376276 -401.276312)
			(xy 457.368718 -401.267546) (xy 457.347957 -401.257364) (xy 457.336398 -401.256754) (xy 457.256134 -401.256754)
			(xy 457.244566 -401.257325) (xy 457.223794 -401.267517) (xy 457.216256 -401.276312) (xy 457.198093 -401.298819)
			(xy 457.156067 -401.338552) (xy 457.108526 -401.371488) (xy 457.056559 -401.396872) (xy 457.001357 -401.414123)
			(xy 456.944184 -401.422846) (xy 456.915266 -401.423378) (xy 456.888013 -401.422954) (xy 456.834061 -401.415192)
			(xy 456.781763 -401.399831) (xy 456.732184 -401.377184) (xy 456.686332 -401.347711) (xy 456.645142 -401.312013)
			(xy 456.609451 -401.270816) (xy 456.579986 -401.22496) (xy 456.557347 -401.175377) (xy 456.541995 -401.123076)
			(xy 456.534242 -401.069124) (xy 456.533758 -401.04187) (xy 456.534176 -401.01618) (xy 456.541075 -400.965267)
			(xy 456.554745 -400.915739) (xy 456.574937 -400.868494) (xy 456.601286 -400.824386) (xy 456.633317 -400.784213)
			(xy 456.670449 -400.748702) (xy 456.690984 -400.73326) (xy 456.70216 -400.725132) (xy 456.713336 -400.699732)
			(xy 456.699366 -400.584162) (xy 456.682602 -400.562064) (xy 456.669648 -400.556984) (xy 456.643698 -400.545835)
			(xy 456.595119 -400.517029) (xy 456.551316 -400.481379) (xy 456.513245 -400.439663) (xy 456.481737 -400.392791)
			(xy 456.457481 -400.341788) (xy 456.441006 -400.287767) (xy 456.432673 -400.231908) (xy 456.432158 -400.20367)
			(xy 450.057439 -400.20367) (xy 450.055495 -400.216882) (xy 450.039427 -400.270289) (xy 450.015755 -400.320786)
			(xy 449.984982 -400.367299) (xy 449.947765 -400.408836) (xy 449.904897 -400.444511) (xy 449.857291 -400.473565)
			(xy 449.805962 -400.495377) (xy 449.752005 -400.509483) (xy 449.696568 -400.515583) (xy 449.640834 -400.513546)
			(xy 449.585991 -400.503416) (xy 449.533207 -400.485409) (xy 449.483607 -400.459908) (xy 449.438249 -400.427457)
			(xy 449.3981 -400.388748) (xy 449.364014 -400.344605) (xy 449.336718 -400.29597) (xy 449.316795 -400.243879)
			(xy 449.304669 -400.189442) (xy 449.300598 -400.13382) (xy 448.863649 -400.13382) (xy 448.863974 -400.15287)
			(xy 448.863572 -400.17856) (xy 448.856669 -400.229474) (xy 448.842996 -400.279001) (xy 448.8228 -400.326246)
			(xy 448.796448 -400.370354) (xy 448.764416 -400.410526) (xy 448.727283 -400.446038) (xy 448.706748 -400.46148)
			(xy 448.695572 -400.469608) (xy 448.684396 -400.495008) (xy 448.698366 -400.610578) (xy 448.71513 -400.632676)
			(xy 448.728084 -400.637756) (xy 448.754033 -400.648907) (xy 448.802616 -400.677708) (xy 448.846423 -400.713356)
			(xy 448.884496 -400.755072) (xy 448.916005 -400.801944) (xy 448.94026 -400.852948) (xy 448.956732 -400.90697)
			(xy 448.965062 -400.962831) (xy 448.965574 -400.99107) (xy 448.965117 -401.018324) (xy 448.957363 -401.072277)
			(xy 448.953672 -401.084848) (xy 452.907696 -401.084848) (xy 452.907696 -401.030352) (xy 452.915451 -400.976411)
			(xy 452.930803 -400.924123) (xy 452.95344 -400.874551) (xy 452.9829 -400.828705) (xy 453.018585 -400.787518)
			(xy 453.059768 -400.751828) (xy 453.10561 -400.722362) (xy 453.155179 -400.699719) (xy 453.207466 -400.684361)
			(xy 453.261406 -400.676599) (xy 453.288654 -400.67611) (xy 453.314407 -400.676537) (xy 453.365442 -400.683484)
			(xy 453.415079 -400.697231) (xy 453.462417 -400.717528) (xy 453.506596 -400.744006) (xy 453.546812 -400.776185)
			(xy 453.582336 -400.813479) (xy 453.597772 -400.834098) (xy 453.603868 -400.842226) (xy 453.620632 -400.85264)
			(xy 453.711056 -400.867626) (xy 453.73036 -400.863308) (xy 453.738742 -400.857466) (xy 453.763002 -400.840983)
			(xy 453.815524 -400.814883) (xy 453.871423 -400.797134) (xy 453.929381 -400.788154) (xy 453.958706 -400.787616)
			(xy 453.985959 -400.788054) (xy 454.039909 -400.795812) (xy 454.092206 -400.811169) (xy 454.141786 -400.833811)
			(xy 454.187639 -400.86328) (xy 454.228831 -400.898974) (xy 454.264524 -400.940166) (xy 454.293991 -400.986019)
			(xy 454.316634 -401.035599) (xy 454.331989 -401.087897) (xy 454.339746 -401.141847) (xy 454.339746 -401.196353)
			(xy 454.331989 -401.250303) (xy 454.316634 -401.302601) (xy 454.293991 -401.352181) (xy 454.264524 -401.398034)
			(xy 454.228831 -401.439226) (xy 454.187639 -401.47492) (xy 454.141786 -401.504389) (xy 454.092206 -401.527031)
			(xy 454.039909 -401.542388) (xy 453.985959 -401.550146) (xy 453.958706 -401.550632) (xy 453.932954 -401.550184)
			(xy 453.881919 -401.543244) (xy 453.832281 -401.529503) (xy 453.784942 -401.50921) (xy 453.740763 -401.482734)
			(xy 453.700546 -401.450557) (xy 453.665023 -401.413263) (xy 453.649588 -401.392644) (xy 453.643492 -401.384516)
			(xy 453.626728 -401.374102) (xy 453.536304 -401.359116) (xy 453.517 -401.363434) (xy 453.508618 -401.369276)
			(xy 453.484365 -401.385769) (xy 453.431841 -401.411869) (xy 453.375939 -401.429615) (xy 453.317979 -401.438591)
			(xy 453.288654 -401.439126) (xy 453.261406 -401.438601) (xy 453.207466 -401.430839) (xy 453.155179 -401.415481)
			(xy 453.10561 -401.392838) (xy 453.059768 -401.363372) (xy 453.018585 -401.327682) (xy 452.9829 -401.286495)
			(xy 452.95344 -401.240649) (xy 452.930803 -401.191077) (xy 452.915451 -401.138789) (xy 452.907696 -401.084848)
			(xy 448.953672 -401.084848) (xy 448.942009 -401.124577) (xy 448.919367 -401.174159) (xy 448.889899 -401.220014)
			(xy 448.854205 -401.261208) (xy 448.813011 -401.296902) (xy 448.767155 -401.326369) (xy 448.717573 -401.34901)
			(xy 448.665273 -401.364364) (xy 448.61132 -401.372117) (xy 448.584066 -401.372578) (xy 448.55515 -401.372021)
			(xy 448.497981 -401.363301) (xy 448.442782 -401.346051) (xy 448.39082 -401.320667) (xy 448.343285 -401.28773)
			(xy 448.301267 -401.247995) (xy 448.283076 -401.225512) (xy 448.275518 -401.216746) (xy 448.254757 -401.206564)
			(xy 448.243198 -401.205954) (xy 448.162934 -401.205954) (xy 448.151366 -401.206525) (xy 448.130594 -401.216717)
			(xy 448.123056 -401.225512) (xy 448.104893 -401.248019) (xy 448.062867 -401.287752) (xy 448.015326 -401.320688)
			(xy 447.963359 -401.346072) (xy 447.908157 -401.363323) (xy 447.850984 -401.372046) (xy 447.822066 -401.372578)
			(xy 447.794813 -401.372154) (xy 447.740861 -401.364392) (xy 447.688563 -401.349031) (xy 447.638984 -401.326384)
			(xy 447.593132 -401.296911) (xy 447.551942 -401.261213) (xy 447.516251 -401.220016) (xy 447.486786 -401.17416)
			(xy 447.464147 -401.124577) (xy 447.448795 -401.072276) (xy 447.441042 -401.018324) (xy 447.440558 -400.99107)
			(xy 447.440976 -400.96538) (xy 447.447875 -400.914467) (xy 447.461545 -400.864939) (xy 447.481737 -400.817694)
			(xy 447.508086 -400.773586) (xy 447.540117 -400.733413) (xy 447.577249 -400.697902) (xy 447.597784 -400.68246)
			(xy 447.60896 -400.674332) (xy 447.620136 -400.648932) (xy 447.606166 -400.533362) (xy 447.589402 -400.511264)
			(xy 447.576448 -400.506184) (xy 447.550498 -400.495035) (xy 447.501919 -400.466229) (xy 447.458116 -400.430579)
			(xy 447.420045 -400.388863) (xy 447.388537 -400.341991) (xy 447.364281 -400.290988) (xy 447.347806 -400.236967)
			(xy 447.339473 -400.181108) (xy 447.338958 -400.15287) (xy 432.260756 -400.15287) (xy 432.260756 -401.44192)
			(xy 440.397898 -401.44192) (xy 440.401969 -401.386298) (xy 440.414095 -401.331861) (xy 440.434018 -401.27977)
			(xy 440.461314 -401.231135) (xy 440.4954 -401.186992) (xy 440.535549 -401.148283) (xy 440.580907 -401.115832)
			(xy 440.630507 -401.090331) (xy 440.683291 -401.072324) (xy 440.738134 -401.062194) (xy 440.793868 -401.060157)
			(xy 440.849305 -401.066257) (xy 440.903262 -401.080363) (xy 440.954591 -401.102175) (xy 441.002197 -401.131229)
			(xy 441.025147 -401.150328) (xy 444.513714 -401.150328) (xy 444.517785 -401.094706) (xy 444.529911 -401.040269)
			(xy 444.549834 -400.988178) (xy 444.57713 -400.939543) (xy 444.611216 -400.8954) (xy 444.651365 -400.856691)
			(xy 444.696723 -400.82424) (xy 444.746323 -400.798739) (xy 444.799107 -400.780732) (xy 444.85395 -400.770602)
			(xy 444.909684 -400.768565) (xy 444.965121 -400.774665) (xy 445.019078 -400.788771) (xy 445.070407 -400.810583)
			(xy 445.118013 -400.839637) (xy 445.160881 -400.875312) (xy 445.198098 -400.916849) (xy 445.228871 -400.963362)
			(xy 445.252543 -401.013859) (xy 445.268611 -401.067266) (xy 445.276731 -401.122442) (xy 445.27724 -401.150328)
			(xy 445.276731 -401.178214) (xy 445.268611 -401.23339) (xy 445.252543 -401.286797) (xy 445.228871 -401.337294)
			(xy 445.198098 -401.383807) (xy 445.160881 -401.425344) (xy 445.118013 -401.461019) (xy 445.070407 -401.490073)
			(xy 445.019078 -401.511885) (xy 444.965121 -401.525991) (xy 444.909684 -401.532091) (xy 444.85395 -401.530054)
			(xy 444.799107 -401.519924) (xy 444.746323 -401.501917) (xy 444.696723 -401.476416) (xy 444.651365 -401.443965)
			(xy 444.611216 -401.405256) (xy 444.57713 -401.361113) (xy 444.549834 -401.312478) (xy 444.529911 -401.260387)
			(xy 444.517785 -401.20595) (xy 444.513714 -401.150328) (xy 441.025147 -401.150328) (xy 441.045065 -401.166904)
			(xy 441.082282 -401.208441) (xy 441.113055 -401.254954) (xy 441.136727 -401.305451) (xy 441.152795 -401.358858)
			(xy 441.160915 -401.414034) (xy 441.161424 -401.44192) (xy 441.160915 -401.469806) (xy 441.152795 -401.524982)
			(xy 441.136727 -401.578389) (xy 441.113055 -401.628886) (xy 441.082282 -401.675399) (xy 441.045065 -401.716936)
			(xy 441.002197 -401.752611) (xy 440.954591 -401.781665) (xy 440.903262 -401.803477) (xy 440.849305 -401.817583)
			(xy 440.793868 -401.823683) (xy 440.738134 -401.821646) (xy 440.683291 -401.811516) (xy 440.630507 -401.793509)
			(xy 440.580907 -401.768008) (xy 440.535549 -401.735557) (xy 440.4954 -401.696848) (xy 440.461314 -401.652705)
			(xy 440.434018 -401.60407) (xy 440.414095 -401.551979) (xy 440.401969 -401.497542) (xy 440.397898 -401.44192)
			(xy 432.260756 -401.44192) (xy 432.260756 -402.41982) (xy 440.683648 -402.41982) (xy 440.687719 -402.364198)
			(xy 440.699845 -402.309761) (xy 440.719768 -402.25767) (xy 440.747064 -402.209035) (xy 440.78115 -402.164892)
			(xy 440.821299 -402.126183) (xy 440.866657 -402.093732) (xy 440.916257 -402.068231) (xy 440.969041 -402.050224)
			(xy 441.023884 -402.040094) (xy 441.079618 -402.038057) (xy 441.135055 -402.044157) (xy 441.189012 -402.058263)
			(xy 441.240341 -402.080075) (xy 441.287947 -402.109129) (xy 441.330815 -402.144804) (xy 441.360569 -402.178012)
			(xy 443.299848 -402.178012) (xy 443.303919 -402.12239) (xy 443.316045 -402.067953) (xy 443.335968 -402.015862)
			(xy 443.363264 -401.967227) (xy 443.39735 -401.923084) (xy 443.437499 -401.884375) (xy 443.482857 -401.851924)
			(xy 443.532457 -401.826423) (xy 443.585241 -401.808416) (xy 443.640084 -401.798286) (xy 443.695818 -401.796249)
			(xy 443.751255 -401.802349) (xy 443.805212 -401.816455) (xy 443.856541 -401.838267) (xy 443.904147 -401.867321)
			(xy 443.947015 -401.902996) (xy 443.984232 -401.944533) (xy 444.015005 -401.991046) (xy 444.038677 -402.041543)
			(xy 444.054745 -402.09495) (xy 444.062865 -402.150126) (xy 444.063374 -402.178012) (xy 444.06291 -402.203412)
			(xy 445.01003 -402.203412) (xy 445.014101 -402.14779) (xy 445.026227 -402.093353) (xy 445.04615 -402.041262)
			(xy 445.073446 -401.992627) (xy 445.107532 -401.948484) (xy 445.147681 -401.909775) (xy 445.193039 -401.877324)
			(xy 445.242639 -401.851823) (xy 445.295423 -401.833816) (xy 445.350266 -401.823686) (xy 445.406 -401.821649)
			(xy 445.461437 -401.827749) (xy 445.515394 -401.841855) (xy 445.566723 -401.863667) (xy 445.582363 -401.873212)
			(xy 451.885048 -401.873212) (xy 451.889119 -401.81759) (xy 451.901245 -401.763153) (xy 451.921168 -401.711062)
			(xy 451.948464 -401.662427) (xy 451.98255 -401.618284) (xy 452.022699 -401.579575) (xy 452.068057 -401.547124)
			(xy 452.117657 -401.521623) (xy 452.170441 -401.503616) (xy 452.225284 -401.493486) (xy 452.281018 -401.491449)
			(xy 452.336455 -401.497549) (xy 452.390412 -401.511655) (xy 452.441741 -401.533467) (xy 452.489347 -401.562521)
			(xy 452.532215 -401.598196) (xy 452.569432 -401.639733) (xy 452.600205 -401.686246) (xy 452.623877 -401.736743)
			(xy 452.639945 -401.79015) (xy 452.648065 -401.845326) (xy 452.648574 -401.873212) (xy 452.648065 -401.901098)
			(xy 452.639945 -401.956274) (xy 452.623877 -402.009681) (xy 452.600205 -402.060178) (xy 452.569432 -402.106691)
			(xy 452.532215 -402.148228) (xy 452.526947 -402.152612) (xy 454.098658 -402.152612) (xy 454.102729 -402.09699)
			(xy 454.114855 -402.042553) (xy 454.134778 -401.990462) (xy 454.162074 -401.941827) (xy 454.19616 -401.897684)
			(xy 454.236309 -401.858975) (xy 454.281667 -401.826524) (xy 454.331267 -401.801023) (xy 454.384051 -401.783016)
			(xy 454.438894 -401.772886) (xy 454.494628 -401.770849) (xy 454.550065 -401.776949) (xy 454.604022 -401.791055)
			(xy 454.655351 -401.812867) (xy 454.702957 -401.841921) (xy 454.745825 -401.877596) (xy 454.783042 -401.919133)
			(xy 454.813815 -401.965646) (xy 454.837487 -402.016143) (xy 454.853555 -402.06955) (xy 454.861675 -402.124726)
			(xy 454.862184 -402.152612) (xy 454.861675 -402.180498) (xy 454.853555 -402.235674) (xy 454.837487 -402.289081)
			(xy 454.813815 -402.339578) (xy 454.783042 -402.386091) (xy 454.745825 -402.427628) (xy 454.702957 -402.463303)
			(xy 454.655351 -402.492357) (xy 454.604022 -402.514169) (xy 454.550065 -402.528275) (xy 454.494628 -402.534375)
			(xy 454.438894 -402.532338) (xy 454.384051 -402.522208) (xy 454.331267 -402.504201) (xy 454.281667 -402.4787)
			(xy 454.236309 -402.446249) (xy 454.19616 -402.40754) (xy 454.162074 -402.363397) (xy 454.134778 -402.314762)
			(xy 454.114855 -402.262671) (xy 454.102729 -402.208234) (xy 454.098658 -402.152612) (xy 452.526947 -402.152612)
			(xy 452.489347 -402.183903) (xy 452.441741 -402.212957) (xy 452.390412 -402.234769) (xy 452.336455 -402.248875)
			(xy 452.281018 -402.254975) (xy 452.225284 -402.252938) (xy 452.170441 -402.242808) (xy 452.117657 -402.224801)
			(xy 452.068057 -402.1993) (xy 452.022699 -402.166849) (xy 451.98255 -402.12814) (xy 451.948464 -402.083997)
			(xy 451.921168 -402.035362) (xy 451.901245 -401.983271) (xy 451.889119 -401.928834) (xy 451.885048 -401.873212)
			(xy 445.582363 -401.873212) (xy 445.614329 -401.892721) (xy 445.657197 -401.928396) (xy 445.694414 -401.969933)
			(xy 445.725187 -402.016446) (xy 445.748859 -402.066943) (xy 445.764927 -402.12035) (xy 445.773047 -402.175526)
			(xy 445.773556 -402.203412) (xy 445.773047 -402.231298) (xy 445.764927 -402.286474) (xy 445.748859 -402.339881)
			(xy 445.725187 -402.390378) (xy 445.694414 -402.436891) (xy 445.657197 -402.478428) (xy 445.614329 -402.514103)
			(xy 445.566723 -402.543157) (xy 445.515394 -402.564969) (xy 445.461437 -402.579075) (xy 445.406 -402.585175)
			(xy 445.350266 -402.583138) (xy 445.295423 -402.573008) (xy 445.242639 -402.555001) (xy 445.193039 -402.5295)
			(xy 445.147681 -402.497049) (xy 445.107532 -402.45834) (xy 445.073446 -402.414197) (xy 445.04615 -402.365562)
			(xy 445.026227 -402.313471) (xy 445.014101 -402.259034) (xy 445.01003 -402.203412) (xy 444.06291 -402.203412)
			(xy 444.062865 -402.205898) (xy 444.054745 -402.261074) (xy 444.038677 -402.314481) (xy 444.015005 -402.364978)
			(xy 443.984232 -402.411491) (xy 443.947015 -402.453028) (xy 443.904147 -402.488703) (xy 443.856541 -402.517757)
			(xy 443.805212 -402.539569) (xy 443.751255 -402.553675) (xy 443.695818 -402.559775) (xy 443.640084 -402.557738)
			(xy 443.585241 -402.547608) (xy 443.532457 -402.529601) (xy 443.482857 -402.5041) (xy 443.437499 -402.471649)
			(xy 443.39735 -402.43294) (xy 443.363264 -402.388797) (xy 443.335968 -402.340162) (xy 443.316045 -402.288071)
			(xy 443.303919 -402.233634) (xy 443.299848 -402.178012) (xy 441.360569 -402.178012) (xy 441.368032 -402.186341)
			(xy 441.398805 -402.232854) (xy 441.422477 -402.283351) (xy 441.438545 -402.336758) (xy 441.446665 -402.391934)
			(xy 441.447174 -402.41982) (xy 441.446665 -402.447706) (xy 441.438545 -402.502882) (xy 441.422477 -402.556289)
			(xy 441.398805 -402.606786) (xy 441.368032 -402.653299) (xy 441.330815 -402.694836) (xy 441.32275 -402.701548)
			(xy 450.670706 -402.701548) (xy 450.670706 -402.647052) (xy 450.678461 -402.59311) (xy 450.693814 -402.540821)
			(xy 450.716452 -402.491249) (xy 450.745914 -402.445404) (xy 450.7816 -402.404217) (xy 450.822784 -402.368528)
			(xy 450.868628 -402.339063) (xy 450.918199 -402.316423) (xy 450.970487 -402.301067) (xy 451.024428 -402.293308)
			(xy 451.051676 -402.29282) (xy 451.080593 -402.293348) (xy 451.137764 -402.302074) (xy 451.192963 -402.31933)
			(xy 451.244925 -402.344719) (xy 451.292459 -402.377661) (xy 451.334476 -402.417401) (xy 451.352666 -402.439886)
			(xy 451.360249 -402.448626) (xy 451.380992 -402.458822) (xy 451.392544 -402.459444) (xy 451.472808 -402.459444)
			(xy 451.48438 -402.458898) (xy 451.505151 -402.448688) (xy 451.512686 -402.439886) (xy 451.530881 -402.417406)
			(xy 451.572901 -402.377672) (xy 451.620435 -402.344732) (xy 451.672395 -402.319344) (xy 451.727592 -402.302086)
			(xy 451.78476 -402.293356) (xy 451.813676 -402.29282) (xy 451.840932 -402.293225) (xy 451.89489 -402.30098)
			(xy 451.947194 -402.316335) (xy 451.996781 -402.338978) (xy 452.042641 -402.368448) (xy 452.083839 -402.404144)
			(xy 452.119538 -402.44534) (xy 452.149011 -402.491198) (xy 452.171656 -402.540783) (xy 452.187015 -402.593087)
			(xy 452.194773 -402.647044) (xy 452.194773 -402.701556) (xy 452.187015 -402.755513) (xy 452.171656 -402.807817)
			(xy 452.149011 -402.857402) (xy 452.119538 -402.90326) (xy 452.083839 -402.944456) (xy 452.042641 -402.980152)
			(xy 451.996781 -403.009622) (xy 451.947194 -403.032265) (xy 451.89489 -403.04762) (xy 451.840932 -403.055375)
			(xy 451.813676 -403.055836) (xy 451.78476 -403.055287) (xy 451.727589 -403.046568) (xy 451.67239 -403.029318)
			(xy 451.620427 -403.003932) (xy 451.572893 -402.970992) (xy 451.530876 -402.931254) (xy 451.512686 -402.90877)
			(xy 451.505131 -402.900001) (xy 451.484367 -402.889823) (xy 451.472808 -402.889212) (xy 451.392544 -402.889212)
			(xy 451.380979 -402.889803) (xy 451.360207 -402.899983) (xy 451.352666 -402.90877) (xy 451.334487 -402.931264)
			(xy 451.292465 -402.970999) (xy 451.244928 -403.003938) (xy 451.192965 -403.029325) (xy 451.137765 -403.046579)
			(xy 451.080593 -403.055304) (xy 451.051676 -403.055836) (xy 451.024428 -403.055292) (xy 450.970487 -403.047533)
			(xy 450.918199 -403.032177) (xy 450.868628 -403.009537) (xy 450.822784 -402.980072) (xy 450.7816 -402.944383)
			(xy 450.745914 -402.903196) (xy 450.716452 -402.857351) (xy 450.693814 -402.807779) (xy 450.678461 -402.75549)
			(xy 450.670706 -402.701548) (xy 441.32275 -402.701548) (xy 441.287947 -402.730511) (xy 441.240341 -402.759565)
			(xy 441.189012 -402.781377) (xy 441.135055 -402.795483) (xy 441.079618 -402.801583) (xy 441.023884 -402.799546)
			(xy 440.969041 -402.789416) (xy 440.916257 -402.771409) (xy 440.866657 -402.745908) (xy 440.821299 -402.713457)
			(xy 440.78115 -402.674748) (xy 440.747064 -402.630605) (xy 440.719768 -402.58197) (xy 440.699845 -402.529879)
			(xy 440.687719 -402.475442) (xy 440.683648 -402.41982) (xy 432.260756 -402.41982) (xy 432.260756 -403.00021)
			(xy 434.686962 -403.00021) (xy 434.691033 -402.944588) (xy 434.703159 -402.890151) (xy 434.723082 -402.83806)
			(xy 434.750378 -402.789425) (xy 434.784464 -402.745282) (xy 434.824613 -402.706573) (xy 434.869971 -402.674122)
			(xy 434.919571 -402.648621) (xy 434.972355 -402.630614) (xy 435.027198 -402.620484) (xy 435.082932 -402.618447)
			(xy 435.138369 -402.624547) (xy 435.192326 -402.638653) (xy 435.243655 -402.660465) (xy 435.291261 -402.689519)
			(xy 435.334129 -402.725194) (xy 435.371346 -402.766731) (xy 435.402119 -402.813244) (xy 435.425791 -402.863741)
			(xy 435.441859 -402.917148) (xy 435.449979 -402.972324) (xy 435.450488 -403.00021) (xy 435.449979 -403.028096)
			(xy 435.441859 -403.083272) (xy 435.425791 -403.136679) (xy 435.402119 -403.187176) (xy 435.371346 -403.233689)
			(xy 435.334129 -403.275226) (xy 435.331913 -403.27707) (xy 443.122048 -403.27707) (xy 443.126119 -403.221448)
			(xy 443.138245 -403.167011) (xy 443.158168 -403.11492) (xy 443.185464 -403.066285) (xy 443.21955 -403.022142)
			(xy 443.259699 -402.983433) (xy 443.305057 -402.950982) (xy 443.354657 -402.925481) (xy 443.407441 -402.907474)
			(xy 443.462284 -402.897344) (xy 443.518018 -402.895307) (xy 443.573455 -402.901407) (xy 443.627412 -402.915513)
			(xy 443.678741 -402.937325) (xy 443.726347 -402.966379) (xy 443.769215 -403.002054) (xy 443.806432 -403.043591)
			(xy 443.837205 -403.090104) (xy 443.860877 -403.140601) (xy 443.876945 -403.194008) (xy 443.885065 -403.249184)
			(xy 443.885574 -403.27707) (xy 443.885065 -403.304956) (xy 443.876945 -403.360132) (xy 443.860877 -403.413539)
			(xy 443.837205 -403.464036) (xy 443.806432 -403.510549) (xy 443.769215 -403.552086) (xy 443.726347 -403.587761)
			(xy 443.678741 -403.616815) (xy 443.627412 -403.638627) (xy 443.573455 -403.652733) (xy 443.518018 -403.658833)
			(xy 443.462284 -403.656796) (xy 443.407441 -403.646666) (xy 443.354657 -403.628659) (xy 443.305057 -403.603158)
			(xy 443.259699 -403.570707) (xy 443.21955 -403.531998) (xy 443.185464 -403.487855) (xy 443.158168 -403.43922)
			(xy 443.138245 -403.387129) (xy 443.126119 -403.332692) (xy 443.122048 -403.27707) (xy 435.331913 -403.27707)
			(xy 435.291261 -403.310901) (xy 435.243655 -403.339955) (xy 435.192326 -403.361767) (xy 435.138369 -403.375873)
			(xy 435.082932 -403.381973) (xy 435.027198 -403.379936) (xy 434.972355 -403.369806) (xy 434.919571 -403.351799)
			(xy 434.869971 -403.326298) (xy 434.824613 -403.293847) (xy 434.784464 -403.255138) (xy 434.750378 -403.210995)
			(xy 434.723082 -403.16236) (xy 434.703159 -403.110269) (xy 434.691033 -403.055832) (xy 434.686962 -403.00021)
			(xy 432.260756 -403.00021) (xy 432.260756 -405.76246) (xy 433.948838 -405.76246) (xy 433.952909 -405.706838)
			(xy 433.965035 -405.652401) (xy 433.984958 -405.60031) (xy 434.012254 -405.551675) (xy 434.04634 -405.507532)
			(xy 434.086489 -405.468823) (xy 434.131847 -405.436372) (xy 434.181447 -405.410871) (xy 434.234231 -405.392864)
			(xy 434.289074 -405.382734) (xy 434.344808 -405.380697) (xy 434.400245 -405.386797) (xy 434.454202 -405.400903)
			(xy 434.505531 -405.422715) (xy 434.553137 -405.451769) (xy 434.596005 -405.487444) (xy 434.633222 -405.528981)
			(xy 434.663995 -405.575494) (xy 434.687667 -405.625991) (xy 434.703735 -405.679398) (xy 434.704745 -405.68626)
			(xy 435.404004 -405.68626) (xy 435.408075 -405.630638) (xy 435.420201 -405.576201) (xy 435.440124 -405.52411)
			(xy 435.46742 -405.475475) (xy 435.501506 -405.431332) (xy 435.541655 -405.392623) (xy 435.587013 -405.360172)
			(xy 435.636613 -405.334671) (xy 435.689397 -405.316664) (xy 435.74424 -405.306534) (xy 435.799974 -405.304497)
			(xy 435.855411 -405.310597) (xy 435.909368 -405.324703) (xy 435.960697 -405.346515) (xy 436.008303 -405.375569)
			(xy 436.051171 -405.411244) (xy 436.088388 -405.452781) (xy 436.119161 -405.499294) (xy 436.142833 -405.549791)
			(xy 436.158901 -405.603198) (xy 436.167021 -405.658374) (xy 436.16753 -405.68626) (xy 436.167021 -405.714146)
			(xy 436.158901 -405.769322) (xy 436.142833 -405.822729) (xy 436.119161 -405.873226) (xy 436.088388 -405.919739)
			(xy 436.051171 -405.961276) (xy 436.008303 -405.996951) (xy 435.960697 -406.026005) (xy 435.909368 -406.047817)
			(xy 435.855411 -406.061923) (xy 435.799974 -406.068023) (xy 435.74424 -406.065986) (xy 435.689397 -406.055856)
			(xy 435.636613 -406.037849) (xy 435.587013 -406.012348) (xy 435.541655 -405.979897) (xy 435.501506 -405.941188)
			(xy 435.46742 -405.897045) (xy 435.440124 -405.84841) (xy 435.420201 -405.796319) (xy 435.408075 -405.741882)
			(xy 435.404004 -405.68626) (xy 434.704745 -405.68626) (xy 434.711855 -405.734574) (xy 434.712364 -405.76246)
			(xy 434.711855 -405.790346) (xy 434.703735 -405.845522) (xy 434.687667 -405.898929) (xy 434.663995 -405.949426)
			(xy 434.633222 -405.995939) (xy 434.596005 -406.037476) (xy 434.553137 -406.073151) (xy 434.505531 -406.102205)
			(xy 434.454202 -406.124017) (xy 434.400245 -406.138123) (xy 434.344808 -406.144223) (xy 434.289074 -406.142186)
			(xy 434.234231 -406.132056) (xy 434.181447 -406.114049) (xy 434.131847 -406.088548) (xy 434.086489 -406.056097)
			(xy 434.04634 -406.017388) (xy 434.012254 -405.973245) (xy 433.984958 -405.92461) (xy 433.965035 -405.872519)
			(xy 433.952909 -405.818082) (xy 433.948838 -405.76246) (xy 432.260756 -405.76246) (xy 432.260756 -406.209246)
			(xy 448.698112 -406.209246) (xy 448.698678 -406.179635) (xy 448.707823 -406.121123) (xy 448.7259 -406.064727)
			(xy 448.752476 -406.011803) (xy 448.786911 -405.963621) (xy 448.828378 -405.92134) (xy 448.875882 -405.885974)
			(xy 448.90182 -405.87168) (xy 448.913621 -405.865041) (xy 448.933432 -405.846593) (xy 448.947695 -405.823585)
			(xy 448.955406 -405.797636) (xy 448.956023 -405.770573) (xy 448.949502 -405.7443) (xy 448.936302 -405.720666)
			(xy 448.917353 -405.701334) (xy 448.905884 -405.694134) (xy 448.881637 -405.679373) (xy 448.837444 -405.643748)
			(xy 448.799017 -405.601968) (xy 448.767207 -405.554953) (xy 448.742716 -405.503744) (xy 448.726084 -405.449471)
			(xy 448.717679 -405.393332) (xy 448.717162 -405.36495) (xy 448.717648 -405.337699) (xy 448.725404 -405.283751)
			(xy 448.740759 -405.231456) (xy 448.763401 -405.181879) (xy 448.792867 -405.136029) (xy 448.828558 -405.094838)
			(xy 448.869749 -405.059147) (xy 448.915599 -405.029681) (xy 448.965176 -405.007039) (xy 449.017471 -404.991684)
			(xy 449.071419 -404.983928) (xy 449.125921 -404.983928) (xy 449.179869 -404.991684) (xy 449.232164 -405.007039)
			(xy 449.281741 -405.029681) (xy 449.327591 -405.059147) (xy 449.368782 -405.094838) (xy 449.404473 -405.136029)
			(xy 449.433939 -405.181879) (xy 449.456581 -405.231456) (xy 449.471936 -405.283751) (xy 449.479692 -405.337699)
			(xy 449.480178 -405.36495) (xy 449.479614 -405.394561) (xy 449.47047 -405.453073) (xy 449.452392 -405.509469)
			(xy 449.425817 -405.562394) (xy 449.391381 -405.610576) (xy 449.349913 -405.652857) (xy 449.302409 -405.688222)
			(xy 449.27647 -405.702516) (xy 449.264673 -405.709161) (xy 449.244864 -405.727609) (xy 449.230603 -405.750616)
			(xy 449.222893 -405.776563) (xy 449.222275 -405.803624) (xy 449.228795 -405.829896) (xy 449.241992 -405.853529)
			(xy 449.260939 -405.872861) (xy 449.272406 -405.880062) (xy 449.296649 -405.894829) (xy 449.340843 -405.930453)
			(xy 449.37927 -405.972232) (xy 449.41108 -406.019245) (xy 449.435572 -406.070453) (xy 449.452205 -406.124726)
			(xy 449.46061 -406.180864) (xy 449.461128 -406.209246) (xy 449.460642 -406.236497) (xy 449.452886 -406.290445)
			(xy 449.437531 -406.34274) (xy 449.433305 -406.351994) (xy 456.067414 -406.351994) (xy 456.067927 -406.323785)
			(xy 456.076229 -406.267981) (xy 456.092666 -406.214011) (xy 456.116878 -406.163053) (xy 456.148338 -406.11622)
			(xy 456.186356 -406.074536) (xy 456.230104 -406.038912) (xy 456.254104 -406.02408) (xy 456.266496 -406.016145)
			(xy 456.286401 -405.994487) (xy 456.299322 -405.968061) (xy 456.30419 -405.939051) (xy 456.300602 -405.909854)
			(xy 456.288857 -405.882886) (xy 456.269923 -405.860373) (xy 456.257914 -405.851868) (xy 456.235704 -405.836632)
			(xy 456.195365 -405.800945) (xy 456.160445 -405.759942) (xy 456.131636 -405.714436) (xy 456.109511 -405.665331)
			(xy 456.09451 -405.613604) (xy 456.08693 -405.560281) (xy 456.086464 -405.533352) (xy 456.08695 -405.506101)
			(xy 456.094706 -405.452153) (xy 456.110061 -405.399858) (xy 456.132703 -405.350281) (xy 456.162169 -405.304431)
			(xy 456.19786 -405.26324) (xy 456.239051 -405.227549) (xy 456.284901 -405.198083) (xy 456.334478 -405.175441)
			(xy 456.386773 -405.160086) (xy 456.440721 -405.15233) (xy 456.495223 -405.15233) (xy 456.549171 -405.160086)
			(xy 456.601466 -405.175441) (xy 456.651043 -405.198083) (xy 456.696893 -405.227549) (xy 456.738084 -405.26324)
			(xy 456.773775 -405.304431) (xy 456.803241 -405.350281) (xy 456.825883 -405.399858) (xy 456.841238 -405.452153)
			(xy 456.848994 -405.506101) (xy 456.84948 -405.533352) (xy 456.848927 -405.56156) (xy 456.840633 -405.617362)
			(xy 456.824203 -405.671331) (xy 456.799998 -405.722289) (xy 456.768544 -405.769122) (xy 456.730531 -405.810808)
			(xy 456.686788 -405.846434) (xy 456.66279 -405.861266) (xy 456.650449 -405.869273) (xy 456.630548 -405.890916)
			(xy 456.617626 -405.917326) (xy 456.612753 -405.946321) (xy 456.61633 -405.975505) (xy 456.628062 -406.002465)
			(xy 456.646979 -406.024973) (xy 456.65898 -406.033478) (xy 456.68121 -406.048686) (xy 456.721549 -406.084377)
			(xy 456.756468 -406.125386) (xy 456.785275 -406.170896) (xy 456.807396 -406.220005) (xy 456.822393 -406.271737)
			(xy 456.829967 -406.325063) (xy 456.83043 -406.351994) (xy 456.829944 -406.379245) (xy 456.822188 -406.433193)
			(xy 456.806833 -406.485488) (xy 456.784191 -406.535065) (xy 456.754725 -406.580915) (xy 456.719034 -406.622106)
			(xy 456.677843 -406.657797) (xy 456.631993 -406.687263) (xy 456.582416 -406.709905) (xy 456.530121 -406.72526)
			(xy 456.476173 -406.733016) (xy 456.421671 -406.733016) (xy 456.367723 -406.72526) (xy 456.315428 -406.709905)
			(xy 456.265851 -406.687263) (xy 456.220001 -406.657797) (xy 456.17881 -406.622106) (xy 456.143119 -406.580915)
			(xy 456.113653 -406.535065) (xy 456.091011 -406.485488) (xy 456.075656 -406.433193) (xy 456.0679 -406.379245)
			(xy 456.067414 -406.351994) (xy 449.433305 -406.351994) (xy 449.414889 -406.392317) (xy 449.385423 -406.438167)
			(xy 449.349732 -406.479358) (xy 449.308541 -406.515049) (xy 449.262691 -406.544515) (xy 449.213114 -406.567157)
			(xy 449.160819 -406.582512) (xy 449.106871 -406.590268) (xy 449.052369 -406.590268) (xy 448.998421 -406.582512)
			(xy 448.946126 -406.567157) (xy 448.896549 -406.544515) (xy 448.850699 -406.515049) (xy 448.809508 -406.479358)
			(xy 448.773817 -406.438167) (xy 448.744351 -406.392317) (xy 448.721709 -406.34274) (xy 448.706354 -406.290445)
			(xy 448.698598 -406.236497) (xy 448.698112 -406.209246) (xy 432.260756 -406.209246) (xy 432.260756 -407.17216)
			(xy 434.870604 -407.17216) (xy 434.874675 -407.116538) (xy 434.886801 -407.062101) (xy 434.906724 -407.01001)
			(xy 434.93402 -406.961375) (xy 434.968106 -406.917232) (xy 435.008255 -406.878523) (xy 435.053613 -406.846072)
			(xy 435.103213 -406.820571) (xy 435.155997 -406.802564) (xy 435.21084 -406.792434) (xy 435.266574 -406.790397)
			(xy 435.322011 -406.796497) (xy 435.375968 -406.810603) (xy 435.427297 -406.832415) (xy 435.474903 -406.861469)
			(xy 435.517771 -406.897144) (xy 435.548663 -406.931622) (xy 439.08929 -406.931622) (xy 439.093361 -406.876)
			(xy 439.105487 -406.821563) (xy 439.12541 -406.769472) (xy 439.152706 -406.720837) (xy 439.186792 -406.676694)
			(xy 439.226941 -406.637985) (xy 439.272299 -406.605534) (xy 439.321899 -406.580033) (xy 439.374683 -406.562026)
			(xy 439.429526 -406.551896) (xy 439.48526 -406.549859) (xy 439.540697 -406.555959) (xy 439.594654 -406.570065)
			(xy 439.645983 -406.591877) (xy 439.693589 -406.620931) (xy 439.736457 -406.656606) (xy 439.773674 -406.698143)
			(xy 439.804447 -406.744656) (xy 439.828119 -406.795153) (xy 439.844187 -406.84856) (xy 439.852307 -406.903736)
			(xy 439.852816 -406.931622) (xy 439.852307 -406.959508) (xy 439.844187 -407.014684) (xy 439.828119 -407.068091)
			(xy 439.804447 -407.118588) (xy 439.773674 -407.165101) (xy 439.742543 -407.199846) (xy 448.698112 -407.199846)
			(xy 448.698598 -407.172595) (xy 448.706354 -407.118647) (xy 448.721709 -407.066352) (xy 448.744351 -407.016775)
			(xy 448.773817 -406.970925) (xy 448.809508 -406.929734) (xy 448.850699 -406.894043) (xy 448.896549 -406.864577)
			(xy 448.946126 -406.841935) (xy 448.998421 -406.82658) (xy 449.052369 -406.818824) (xy 449.106871 -406.818824)
			(xy 449.160819 -406.82658) (xy 449.213114 -406.841935) (xy 449.262691 -406.864577) (xy 449.308541 -406.894043)
			(xy 449.349732 -406.929734) (xy 449.385423 -406.970925) (xy 449.414889 -407.016775) (xy 449.437531 -407.066352)
			(xy 449.452886 -407.118647) (xy 449.460642 -407.172595) (xy 449.461128 -407.199846) (xy 449.460563 -407.228837)
			(xy 449.451777 -407.286151) (xy 449.43798 -407.330148) (xy 456.075796 -407.330148) (xy 456.076282 -407.302897)
			(xy 456.084038 -407.248949) (xy 456.099393 -407.196654) (xy 456.122035 -407.147077) (xy 456.151501 -407.101227)
			(xy 456.187192 -407.060036) (xy 456.228383 -407.024345) (xy 456.274233 -406.994879) (xy 456.32381 -406.972237)
			(xy 456.376105 -406.956882) (xy 456.430053 -406.949126) (xy 456.484555 -406.949126) (xy 456.538503 -406.956882)
			(xy 456.590798 -406.972237) (xy 456.640375 -406.994879) (xy 456.686225 -407.024345) (xy 456.727416 -407.060036)
			(xy 456.763107 -407.101227) (xy 456.792573 -407.147077) (xy 456.815215 -407.196654) (xy 456.83057 -407.248949)
			(xy 456.838326 -407.302897) (xy 456.838812 -407.330148) (xy 456.838291 -407.35901) (xy 456.829609 -407.416078)
			(xy 456.812419 -407.471184) (xy 456.787116 -407.523067) (xy 456.754278 -407.570541) (xy 456.714656 -407.612519)
			(xy 456.669156 -407.648043) (xy 456.644248 -407.662634) (xy 456.632498 -407.669733) (xy 456.61303 -407.689076)
			(xy 456.599416 -407.712904) (xy 456.592637 -407.739497) (xy 456.593184 -407.766935) (xy 456.601016 -407.793237)
			(xy 456.615569 -407.816504) (xy 456.635792 -407.835056) (xy 456.647804 -407.841704) (xy 456.670957 -407.854001)
			(xy 456.713937 -407.884023) (xy 456.752403 -407.919644) (xy 456.785633 -407.960193) (xy 456.813001 -408.004909)
			(xy 456.833993 -408.05295) (xy 456.848213 -408.103411) (xy 456.855393 -408.155343) (xy 456.85583 -408.181556)
			(xy 456.855344 -408.208807) (xy 456.847588 -408.262755) (xy 456.832233 -408.31505) (xy 456.809591 -408.364627)
			(xy 456.780125 -408.410477) (xy 456.744434 -408.451668) (xy 456.703243 -408.487359) (xy 456.657393 -408.516825)
			(xy 456.607816 -408.539467) (xy 456.555521 -408.554822) (xy 456.501573 -408.562578) (xy 456.447071 -408.562578)
			(xy 456.393123 -408.554822) (xy 456.340828 -408.539467) (xy 456.291251 -408.516825) (xy 456.245401 -408.487359)
			(xy 456.20421 -408.451668) (xy 456.168519 -408.410477) (xy 456.139053 -408.364627) (xy 456.116411 -408.31505)
			(xy 456.101056 -408.262755) (xy 456.0933 -408.208807) (xy 456.092814 -408.181556) (xy 456.093325 -408.152693)
			(xy 456.102008 -408.095624) (xy 456.119198 -408.040518) (xy 456.144503 -407.988634) (xy 456.177343 -407.94116)
			(xy 456.216967 -407.899183) (xy 456.262469 -407.863661) (xy 456.287378 -407.84907) (xy 456.299122 -407.841963)
			(xy 456.318584 -407.822619) (xy 456.332195 -407.798793) (xy 456.338971 -407.772203) (xy 456.338425 -407.744769)
			(xy 456.330596 -407.718469) (xy 456.316048 -407.695203) (xy 456.295831 -407.67665) (xy 456.283822 -407.67)
			(xy 456.260676 -407.657689) (xy 456.217696 -407.62767) (xy 456.179228 -407.592052) (xy 456.145997 -407.551504)
			(xy 456.118628 -407.50679) (xy 456.097635 -407.458752) (xy 456.083415 -407.408292) (xy 456.076233 -407.356361)
			(xy 456.075796 -407.330148) (xy 449.43798 -407.330148) (xy 449.434427 -407.341477) (xy 449.408913 -407.393546)
			(xy 449.375822 -407.441159) (xy 449.335914 -407.483223) (xy 449.290106 -407.51877) (xy 449.26504 -407.533348)
			(xy 449.25296 -407.540612) (xy 449.233005 -407.560503) (xy 449.219245 -407.585089) (xy 449.212726 -407.6125)
			(xy 449.213945 -407.640649) (xy 449.222808 -407.667394) (xy 449.238641 -407.690699) (xy 449.260239 -407.708792)
			(xy 449.272914 -407.714958) (xy 449.29783 -407.726553) (xy 449.344309 -407.755877) (xy 449.386098 -407.791567)
			(xy 449.422332 -407.832886) (xy 449.452262 -407.878977) (xy 449.475267 -407.928886) (xy 449.490871 -407.98158)
			(xy 449.498752 -408.035968) (xy 449.499228 -408.063446) (xy 449.498742 -408.090697) (xy 449.490986 -408.144645)
			(xy 449.475631 -408.19694) (xy 449.452989 -408.246517) (xy 449.423523 -408.292367) (xy 449.387832 -408.333558)
			(xy 449.346641 -408.369249) (xy 449.300791 -408.398715) (xy 449.251214 -408.421357) (xy 449.198919 -408.436712)
			(xy 449.144971 -408.444468) (xy 449.090469 -408.444468) (xy 449.036521 -408.436712) (xy 448.984226 -408.421357)
			(xy 448.934649 -408.398715) (xy 448.888799 -408.369249) (xy 448.847608 -408.333558) (xy 448.811917 -408.292367)
			(xy 448.782451 -408.246517) (xy 448.759809 -408.19694) (xy 448.744454 -408.144645) (xy 448.736698 -408.090697)
			(xy 448.736212 -408.063446) (xy 448.73675 -408.034453) (xy 448.745539 -407.977138) (xy 448.762892 -407.92181)
			(xy 448.788409 -407.869741) (xy 448.821505 -407.822128) (xy 448.861418 -407.780065) (xy 448.907232 -407.74452)
			(xy 448.9323 -407.729944) (xy 448.944382 -407.722687) (xy 448.964329 -407.702791) (xy 448.978083 -407.678204)
			(xy 448.984598 -407.650795) (xy 448.983379 -407.622649) (xy 448.974518 -407.595905) (xy 448.95869 -407.5726)
			(xy 448.937098 -407.554503) (xy 448.924426 -407.548334) (xy 448.899516 -407.536726) (xy 448.853036 -407.507406)
			(xy 448.811245 -407.471718) (xy 448.775009 -407.430402) (xy 448.745078 -407.384313) (xy 448.722072 -407.334405)
			(xy 448.706468 -407.281711) (xy 448.698588 -407.227324) (xy 448.698112 -407.199846) (xy 439.742543 -407.199846)
			(xy 439.736457 -407.206638) (xy 439.693589 -407.242313) (xy 439.645983 -407.271367) (xy 439.594654 -407.293179)
			(xy 439.540697 -407.307285) (xy 439.48526 -407.313385) (xy 439.429526 -407.311348) (xy 439.374683 -407.301218)
			(xy 439.321899 -407.283211) (xy 439.272299 -407.25771) (xy 439.226941 -407.225259) (xy 439.186792 -407.18655)
			(xy 439.152706 -407.142407) (xy 439.12541 -407.093772) (xy 439.105487 -407.041681) (xy 439.093361 -406.987244)
			(xy 439.08929 -406.931622) (xy 435.548663 -406.931622) (xy 435.554988 -406.938681) (xy 435.585761 -406.985194)
			(xy 435.609433 -407.035691) (xy 435.625501 -407.089098) (xy 435.633621 -407.144274) (xy 435.63413 -407.17216)
			(xy 435.633621 -407.200046) (xy 435.625501 -407.255222) (xy 435.609433 -407.308629) (xy 435.585761 -407.359126)
			(xy 435.554988 -407.405639) (xy 435.517771 -407.447176) (xy 435.474903 -407.482851) (xy 435.427297 -407.511905)
			(xy 435.375968 -407.533717) (xy 435.322011 -407.547823) (xy 435.266574 -407.553923) (xy 435.21084 -407.551886)
			(xy 435.155997 -407.541756) (xy 435.103213 -407.523749) (xy 435.053613 -407.498248) (xy 435.008255 -407.465797)
			(xy 434.968106 -407.427088) (xy 434.93402 -407.382945) (xy 434.906724 -407.33431) (xy 434.886801 -407.282219)
			(xy 434.874675 -407.227782) (xy 434.870604 -407.17216) (xy 432.260756 -407.17216) (xy 432.260756 -408.01036)
			(xy 433.915564 -408.01036) (xy 433.919635 -407.954738) (xy 433.931761 -407.900301) (xy 433.951684 -407.84821)
			(xy 433.97898 -407.799575) (xy 434.013066 -407.755432) (xy 434.053215 -407.716723) (xy 434.098573 -407.684272)
			(xy 434.148173 -407.658771) (xy 434.200957 -407.640764) (xy 434.2558 -407.630634) (xy 434.311534 -407.628597)
			(xy 434.366971 -407.634697) (xy 434.420928 -407.648803) (xy 434.472257 -407.670615) (xy 434.519863 -407.699669)
			(xy 434.562731 -407.735344) (xy 434.599948 -407.776881) (xy 434.630721 -407.823394) (xy 434.654393 -407.873891)
			(xy 434.670461 -407.927298) (xy 434.678581 -407.982474) (xy 434.67909 -408.01036) (xy 434.678581 -408.038246)
			(xy 434.670461 -408.093422) (xy 434.654393 -408.146829) (xy 434.630721 -408.197326) (xy 434.599948 -408.243839)
			(xy 434.562731 -408.285376) (xy 434.519863 -408.321051) (xy 434.472257 -408.350105) (xy 434.420928 -408.371917)
			(xy 434.366971 -408.386023) (xy 434.311534 -408.392123) (xy 434.2558 -408.390086) (xy 434.200957 -408.379956)
			(xy 434.148173 -408.361949) (xy 434.098573 -408.336448) (xy 434.053215 -408.303997) (xy 434.013066 -408.265288)
			(xy 433.97898 -408.221145) (xy 433.951684 -408.17251) (xy 433.931761 -408.120419) (xy 433.919635 -408.065982)
			(xy 433.915564 -408.01036) (xy 432.260756 -408.01036) (xy 432.260756 -408.84856) (xy 434.870604 -408.84856)
			(xy 434.874675 -408.792938) (xy 434.886801 -408.738501) (xy 434.906724 -408.68641) (xy 434.93402 -408.637775)
			(xy 434.968106 -408.593632) (xy 435.008255 -408.554923) (xy 435.053613 -408.522472) (xy 435.103213 -408.496971)
			(xy 435.155997 -408.478964) (xy 435.21084 -408.468834) (xy 435.266574 -408.466797) (xy 435.322011 -408.472897)
			(xy 435.375968 -408.487003) (xy 435.427297 -408.508815) (xy 435.474903 -408.537869) (xy 435.517771 -408.573544)
			(xy 435.554988 -408.615081) (xy 435.585761 -408.661594) (xy 435.609433 -408.712091) (xy 435.625501 -408.765498)
			(xy 435.633621 -408.820674) (xy 435.63413 -408.84856) (xy 435.633621 -408.876446) (xy 435.625501 -408.931622)
			(xy 435.609433 -408.985029) (xy 435.585761 -409.035526) (xy 435.554988 -409.082039) (xy 435.517771 -409.123576)
			(xy 435.474903 -409.159251) (xy 435.427297 -409.188305) (xy 435.375968 -409.210117) (xy 435.322011 -409.224223)
			(xy 435.266574 -409.230323) (xy 435.21084 -409.228286) (xy 435.155997 -409.218156) (xy 435.103213 -409.200149)
			(xy 435.053613 -409.174648) (xy 435.008255 -409.142197) (xy 434.968106 -409.103488) (xy 434.93402 -409.059345)
			(xy 434.906724 -409.01071) (xy 434.886801 -408.958619) (xy 434.874675 -408.904182) (xy 434.870604 -408.84856)
			(xy 432.260756 -408.84856) (xy 432.260756 -409.68676) (xy 433.915564 -409.68676) (xy 433.919635 -409.631138)
			(xy 433.931761 -409.576701) (xy 433.951684 -409.52461) (xy 433.97898 -409.475975) (xy 434.013066 -409.431832)
			(xy 434.053215 -409.393123) (xy 434.098573 -409.360672) (xy 434.148173 -409.335171) (xy 434.200957 -409.317164)
			(xy 434.2558 -409.307034) (xy 434.311534 -409.304997) (xy 434.366971 -409.311097) (xy 434.420928 -409.325203)
			(xy 434.472257 -409.347015) (xy 434.519863 -409.376069) (xy 434.562731 -409.411744) (xy 434.599948 -409.453281)
			(xy 434.630721 -409.499794) (xy 434.654393 -409.550291) (xy 434.670461 -409.603698) (xy 434.678581 -409.658874)
			(xy 434.67909 -409.68676) (xy 434.678581 -409.714646) (xy 434.670461 -409.769822) (xy 434.654393 -409.823229)
			(xy 434.630721 -409.873726) (xy 434.599948 -409.920239) (xy 434.562731 -409.961776) (xy 434.519863 -409.997451)
			(xy 434.472257 -410.026505) (xy 434.420928 -410.048317) (xy 434.366971 -410.062423) (xy 434.311534 -410.068523)
			(xy 434.2558 -410.066486) (xy 434.200957 -410.056356) (xy 434.148173 -410.038349) (xy 434.098573 -410.012848)
			(xy 434.053215 -409.980397) (xy 434.013066 -409.941688) (xy 433.97898 -409.897545) (xy 433.951684 -409.84891)
			(xy 433.931761 -409.796819) (xy 433.919635 -409.742382) (xy 433.915564 -409.68676) (xy 432.260756 -409.68676)
			(xy 432.260756 -410.578554) (xy 446.710306 -410.578554) (xy 446.714377 -410.522932) (xy 446.726503 -410.468495)
			(xy 446.746426 -410.416404) (xy 446.773722 -410.367769) (xy 446.807808 -410.323626) (xy 446.847957 -410.284917)
			(xy 446.893315 -410.252466) (xy 446.942915 -410.226965) (xy 446.995699 -410.208958) (xy 447.050542 -410.198828)
			(xy 447.106276 -410.196791) (xy 447.161713 -410.202891) (xy 447.21567 -410.216997) (xy 447.266999 -410.238809)
			(xy 447.314605 -410.267863) (xy 447.357473 -410.303538) (xy 447.39469 -410.345075) (xy 447.425463 -410.391588)
			(xy 447.449135 -410.442085) (xy 447.465203 -410.495492) (xy 447.473323 -410.550668) (xy 447.473832 -410.578554)
			(xy 447.599306 -410.578554) (xy 447.603377 -410.522932) (xy 447.615503 -410.468495) (xy 447.635426 -410.416404)
			(xy 447.662722 -410.367769) (xy 447.696808 -410.323626) (xy 447.736957 -410.284917) (xy 447.782315 -410.252466)
			(xy 447.831915 -410.226965) (xy 447.884699 -410.208958) (xy 447.939542 -410.198828) (xy 447.995276 -410.196791)
			(xy 448.050713 -410.202891) (xy 448.10467 -410.216997) (xy 448.155999 -410.238809) (xy 448.203605 -410.267863)
			(xy 448.246473 -410.303538) (xy 448.28369 -410.345075) (xy 448.314463 -410.391588) (xy 448.338135 -410.442085)
			(xy 448.354203 -410.495492) (xy 448.362323 -410.550668) (xy 448.362832 -410.578554) (xy 448.488306 -410.578554)
			(xy 448.492377 -410.522932) (xy 448.504503 -410.468495) (xy 448.524426 -410.416404) (xy 448.551722 -410.367769)
			(xy 448.585808 -410.323626) (xy 448.625957 -410.284917) (xy 448.671315 -410.252466) (xy 448.720915 -410.226965)
			(xy 448.773699 -410.208958) (xy 448.828542 -410.198828) (xy 448.884276 -410.196791) (xy 448.939713 -410.202891)
			(xy 448.99367 -410.216997) (xy 449.044999 -410.238809) (xy 449.092605 -410.267863) (xy 449.135473 -410.303538)
			(xy 449.17269 -410.345075) (xy 449.203463 -410.391588) (xy 449.227135 -410.442085) (xy 449.243203 -410.495492)
			(xy 449.251323 -410.550668) (xy 449.251832 -410.578554) (xy 449.251323 -410.60644) (xy 449.243203 -410.661616)
			(xy 449.227135 -410.715023) (xy 449.203463 -410.76552) (xy 449.17269 -410.812033) (xy 449.135473 -410.85357)
			(xy 449.092605 -410.889245) (xy 449.071044 -410.902404) (xy 451.091808 -410.902404) (xy 451.092365 -410.87228)
			(xy 451.101847 -410.812782) (xy 451.12056 -410.755513) (xy 451.14804 -410.701897) (xy 451.183603 -410.653264)
			(xy 451.204584 -410.63164) (xy 451.21195 -410.624528) (xy 451.21957 -410.605732) (xy 451.21957 -410.513276)
			(xy 451.21195 -410.49448) (xy 451.204584 -410.487368) (xy 451.183608 -410.465739) (xy 451.14804 -410.417111)
			(xy 451.12056 -410.363495) (xy 451.10185 -410.306226) (xy 451.092377 -410.246728) (xy 451.091808 -410.216604)
			(xy 451.092259 -410.189351) (xy 451.100016 -410.135398) (xy 451.115372 -410.083099) (xy 451.138015 -410.033518)
			(xy 451.167485 -409.987664) (xy 451.20318 -409.946471) (xy 451.244374 -409.910777) (xy 451.290229 -409.88131)
			(xy 451.339811 -409.858668) (xy 451.39211 -409.843313) (xy 451.446063 -409.835558) (xy 451.473316 -409.835096)
			(xy 451.503441 -409.835643) (xy 451.562939 -409.845128) (xy 451.620207 -409.863844) (xy 451.673824 -409.891325)
			(xy 451.722457 -409.92689) (xy 451.74408 -409.947872) (xy 451.751192 -409.955238) (xy 451.769988 -409.962858)
			(xy 451.862444 -409.962858) (xy 451.88124 -409.955238) (xy 451.888352 -409.947872) (xy 451.909987 -409.926903)
			(xy 451.958612 -409.89133) (xy 452.012225 -409.863847) (xy 452.069494 -409.845136) (xy 452.128992 -409.835665)
			(xy 452.159116 -409.835096) (xy 452.186487 -409.835554) (xy 452.240666 -409.843374) (xy 452.293169 -409.858865)
			(xy 452.342916 -409.881708) (xy 452.388882 -409.911434) (xy 452.409814 -409.929076) (xy 452.416926 -409.935172)
			(xy 452.433944 -409.941522) (xy 452.519288 -409.941522) (xy 452.536306 -409.935172) (xy 452.543418 -409.929076)
			(xy 452.564367 -409.911458) (xy 452.610336 -409.881744) (xy 452.660079 -409.858904) (xy 452.712576 -409.843408)
			(xy 452.766748 -409.835574) (xy 452.794116 -409.835096) (xy 452.821368 -409.835563) (xy 452.875316 -409.843322)
			(xy 452.927612 -409.858679) (xy 452.977189 -409.881322) (xy 453.02304 -409.910791) (xy 453.06423 -409.946484)
			(xy 453.099921 -409.987676) (xy 453.129387 -410.033528) (xy 453.152028 -410.083107) (xy 453.167383 -410.135403)
			(xy 453.175139 -410.189352) (xy 453.175624 -410.216604) (xy 453.175063 -410.246728) (xy 453.165581 -410.306225)
			(xy 453.146868 -410.363493) (xy 453.11939 -410.41711) (xy 453.083828 -410.465744) (xy 453.062848 -410.487368)
			(xy 453.055482 -410.49448) (xy 453.047862 -410.513276) (xy 453.047862 -410.6037) (xy 454.780648 -410.6037)
			(xy 454.784719 -410.548078) (xy 454.796845 -410.493641) (xy 454.816768 -410.44155) (xy 454.844064 -410.392915)
			(xy 454.87815 -410.348772) (xy 454.918299 -410.310063) (xy 454.963657 -410.277612) (xy 455.013257 -410.252111)
			(xy 455.066041 -410.234104) (xy 455.120884 -410.223974) (xy 455.176618 -410.221937) (xy 455.232055 -410.228037)
			(xy 455.286012 -410.242143) (xy 455.337341 -410.263955) (xy 455.384947 -410.293009) (xy 455.427815 -410.328684)
			(xy 455.465032 -410.370221) (xy 455.495805 -410.416734) (xy 455.519477 -410.467231) (xy 455.535545 -410.520638)
			(xy 455.543665 -410.575814) (xy 455.544174 -410.6037) (xy 455.669648 -410.6037) (xy 455.673719 -410.548078)
			(xy 455.685845 -410.493641) (xy 455.705768 -410.44155) (xy 455.733064 -410.392915) (xy 455.76715 -410.348772)
			(xy 455.807299 -410.310063) (xy 455.852657 -410.277612) (xy 455.902257 -410.252111) (xy 455.955041 -410.234104)
			(xy 456.009884 -410.223974) (xy 456.065618 -410.221937) (xy 456.121055 -410.228037) (xy 456.175012 -410.242143)
			(xy 456.226341 -410.263955) (xy 456.273947 -410.293009) (xy 456.316815 -410.328684) (xy 456.354032 -410.370221)
			(xy 456.384805 -410.416734) (xy 456.408477 -410.467231) (xy 456.424545 -410.520638) (xy 456.432665 -410.575814)
			(xy 456.433174 -410.6037) (xy 456.558648 -410.6037) (xy 456.562719 -410.548078) (xy 456.574845 -410.493641)
			(xy 456.594768 -410.44155) (xy 456.622064 -410.392915) (xy 456.65615 -410.348772) (xy 456.696299 -410.310063)
			(xy 456.741657 -410.277612) (xy 456.791257 -410.252111) (xy 456.844041 -410.234104) (xy 456.898884 -410.223974)
			(xy 456.954618 -410.221937) (xy 457.010055 -410.228037) (xy 457.064012 -410.242143) (xy 457.115341 -410.263955)
			(xy 457.162947 -410.293009) (xy 457.205815 -410.328684) (xy 457.243032 -410.370221) (xy 457.273805 -410.416734)
			(xy 457.297477 -410.467231) (xy 457.313545 -410.520638) (xy 457.321665 -410.575814) (xy 457.322174 -410.6037)
			(xy 457.321665 -410.631586) (xy 457.313545 -410.686762) (xy 457.297477 -410.740169) (xy 457.273805 -410.790666)
			(xy 457.243032 -410.837179) (xy 457.205815 -410.878716) (xy 457.162947 -410.914391) (xy 457.115341 -410.943445)
			(xy 457.064012 -410.965257) (xy 457.010055 -410.979363) (xy 456.954618 -410.985463) (xy 456.898884 -410.983426)
			(xy 456.844041 -410.973296) (xy 456.791257 -410.955289) (xy 456.741657 -410.929788) (xy 456.696299 -410.897337)
			(xy 456.65615 -410.858628) (xy 456.622064 -410.814485) (xy 456.594768 -410.76585) (xy 456.574845 -410.713759)
			(xy 456.562719 -410.659322) (xy 456.558648 -410.6037) (xy 456.433174 -410.6037) (xy 456.432665 -410.631586)
			(xy 456.424545 -410.686762) (xy 456.408477 -410.740169) (xy 456.384805 -410.790666) (xy 456.354032 -410.837179)
			(xy 456.316815 -410.878716) (xy 456.273947 -410.914391) (xy 456.226341 -410.943445) (xy 456.175012 -410.965257)
			(xy 456.121055 -410.979363) (xy 456.065618 -410.985463) (xy 456.009884 -410.983426) (xy 455.955041 -410.973296)
			(xy 455.902257 -410.955289) (xy 455.852657 -410.929788) (xy 455.807299 -410.897337) (xy 455.76715 -410.858628)
			(xy 455.733064 -410.814485) (xy 455.705768 -410.76585) (xy 455.685845 -410.713759) (xy 455.673719 -410.659322)
			(xy 455.669648 -410.6037) (xy 455.544174 -410.6037) (xy 455.543665 -410.631586) (xy 455.535545 -410.686762)
			(xy 455.519477 -410.740169) (xy 455.495805 -410.790666) (xy 455.465032 -410.837179) (xy 455.427815 -410.878716)
			(xy 455.384947 -410.914391) (xy 455.337341 -410.943445) (xy 455.286012 -410.965257) (xy 455.232055 -410.979363)
			(xy 455.176618 -410.985463) (xy 455.120884 -410.983426) (xy 455.066041 -410.973296) (xy 455.013257 -410.955289)
			(xy 454.963657 -410.929788) (xy 454.918299 -410.897337) (xy 454.87815 -410.858628) (xy 454.844064 -410.814485)
			(xy 454.816768 -410.76585) (xy 454.796845 -410.713759) (xy 454.784719 -410.659322) (xy 454.780648 -410.6037)
			(xy 453.047862 -410.6037) (xy 453.047862 -410.605732) (xy 453.055482 -410.624528) (xy 453.062848 -410.63164)
			(xy 453.083816 -410.653277) (xy 453.119388 -410.701901) (xy 453.146871 -410.755515) (xy 453.165582 -410.812783)
			(xy 453.175055 -410.87228) (xy 453.175624 -410.902404) (xy 453.175126 -410.929655) (xy 453.167369 -410.983601)
			(xy 453.152015 -411.035895) (xy 453.129374 -411.085471) (xy 453.099909 -411.13132) (xy 453.064219 -411.17251)
			(xy 453.02303 -411.208202) (xy 452.977181 -411.237668) (xy 452.927606 -411.26031) (xy 452.875313 -411.275667)
			(xy 452.821367 -411.283425) (xy 452.794116 -411.283912) (xy 452.766746 -411.283434) (xy 452.712568 -411.275618)
			(xy 452.660065 -411.260132) (xy 452.610318 -411.237293) (xy 452.56435 -411.207572) (xy 452.543418 -411.189932)
			(xy 452.536306 -411.183836) (xy 452.519288 -411.177486) (xy 452.433944 -411.177486) (xy 452.416926 -411.183836)
			(xy 452.409814 -411.189932) (xy 452.388892 -411.207583) (xy 452.342916 -411.237292) (xy 452.293166 -411.260125)
			(xy 452.240663 -411.275613) (xy 452.186486 -411.283439) (xy 452.159116 -411.283912) (xy 452.128992 -411.283342)
			(xy 452.069496 -411.273862) (xy 452.012227 -411.255152) (xy 451.95861 -411.227675) (xy 451.909976 -411.192116)
			(xy 451.888352 -411.171136) (xy 451.88124 -411.16377) (xy 451.862444 -411.15615) (xy 451.769988 -411.15615)
			(xy 451.751192 -411.16377) (xy 451.74408 -411.171136) (xy 451.722432 -411.192091) (xy 451.673811 -411.227665)
			(xy 451.6202 -411.255151) (xy 451.562935 -411.273865) (xy 451.503439 -411.283341) (xy 451.473316 -411.283912)
			(xy 451.446064 -411.28343) (xy 451.392114 -411.275675) (xy 451.339816 -411.260321) (xy 451.290237 -411.237681)
			(xy 451.244384 -411.208215) (xy 451.203191 -411.172523) (xy 451.167497 -411.131332) (xy 451.138029 -411.085481)
			(xy 451.115386 -411.035902) (xy 451.100029 -410.983606) (xy 451.092272 -410.929656) (xy 451.091808 -410.902404)
			(xy 449.071044 -410.902404) (xy 449.044999 -410.918299) (xy 448.99367 -410.940111) (xy 448.939713 -410.954217)
			(xy 448.884276 -410.960317) (xy 448.828542 -410.95828) (xy 448.773699 -410.94815) (xy 448.720915 -410.930143)
			(xy 448.671315 -410.904642) (xy 448.625957 -410.872191) (xy 448.585808 -410.833482) (xy 448.551722 -410.789339)
			(xy 448.524426 -410.740704) (xy 448.504503 -410.688613) (xy 448.492377 -410.634176) (xy 448.488306 -410.578554)
			(xy 448.362832 -410.578554) (xy 448.362323 -410.60644) (xy 448.354203 -410.661616) (xy 448.338135 -410.715023)
			(xy 448.314463 -410.76552) (xy 448.28369 -410.812033) (xy 448.246473 -410.85357) (xy 448.203605 -410.889245)
			(xy 448.155999 -410.918299) (xy 448.10467 -410.940111) (xy 448.050713 -410.954217) (xy 447.995276 -410.960317)
			(xy 447.939542 -410.95828) (xy 447.884699 -410.94815) (xy 447.831915 -410.930143) (xy 447.782315 -410.904642)
			(xy 447.736957 -410.872191) (xy 447.696808 -410.833482) (xy 447.662722 -410.789339) (xy 447.635426 -410.740704)
			(xy 447.615503 -410.688613) (xy 447.603377 -410.634176) (xy 447.599306 -410.578554) (xy 447.473832 -410.578554)
			(xy 447.473323 -410.60644) (xy 447.465203 -410.661616) (xy 447.449135 -410.715023) (xy 447.425463 -410.76552)
			(xy 447.39469 -410.812033) (xy 447.357473 -410.85357) (xy 447.314605 -410.889245) (xy 447.266999 -410.918299)
			(xy 447.21567 -410.940111) (xy 447.161713 -410.954217) (xy 447.106276 -410.960317) (xy 447.050542 -410.95828)
			(xy 446.995699 -410.94815) (xy 446.942915 -410.930143) (xy 446.893315 -410.904642) (xy 446.847957 -410.872191)
			(xy 446.807808 -410.833482) (xy 446.773722 -410.789339) (xy 446.746426 -410.740704) (xy 446.726503 -410.688613)
			(xy 446.714377 -410.634176) (xy 446.710306 -410.578554) (xy 432.260756 -410.578554) (xy 432.260756 -415.147252)
			(xy 449.363338 -415.147252) (xy 449.363825 -415.119882) (xy 449.371637 -415.065704) (xy 449.38712 -415.013201)
			(xy 449.409957 -414.963453) (xy 449.439678 -414.917486) (xy 449.457318 -414.896554) (xy 449.463414 -414.889442)
			(xy 449.469764 -414.872424) (xy 449.469764 -414.78708) (xy 449.463414 -414.770062) (xy 449.457318 -414.76295)
			(xy 449.439692 -414.742008) (xy 449.409977 -414.696038) (xy 449.387139 -414.646293) (xy 449.371645 -414.593795)
			(xy 449.363813 -414.539621) (xy 449.363338 -414.512252) (xy 449.363733 -414.484997) (xy 449.371498 -414.431044)
			(xy 449.386861 -414.378745) (xy 449.409511 -414.329164) (xy 449.438987 -414.283312) (xy 449.474688 -414.242121)
			(xy 449.515887 -414.20643) (xy 449.561747 -414.176966) (xy 449.611333 -414.154328) (xy 449.663636 -414.138978)
			(xy 449.717591 -414.131227) (xy 449.744846 -414.130744) (xy 449.774968 -414.13135) (xy 449.834463 -414.140823)
			(xy 449.89173 -414.159526) (xy 449.945348 -414.186993) (xy 449.993984 -414.222544) (xy 450.01561 -414.24352)
			(xy 450.022722 -414.250886) (xy 450.041518 -414.258506) (xy 450.133974 -414.258506) (xy 450.15277 -414.250886)
			(xy 450.159882 -414.24352) (xy 450.181495 -414.222527) (xy 450.230127 -414.186959) (xy 450.283746 -414.159481)
			(xy 450.341019 -414.140776) (xy 450.400521 -414.13131) (xy 450.430646 -414.130744) (xy 450.457896 -414.131235)
			(xy 450.511841 -414.138996) (xy 450.564133 -414.154355) (xy 450.613707 -414.176998) (xy 450.659555 -414.206465)
			(xy 450.700743 -414.242155) (xy 450.736434 -414.283343) (xy 450.765901 -414.329191) (xy 450.788544 -414.378765)
			(xy 450.803903 -414.431057) (xy 450.811665 -414.485002) (xy 450.812154 -414.512252) (xy 450.811597 -414.541729)
			(xy 450.802533 -414.599982) (xy 450.784616 -414.656147) (xy 450.75827 -414.708887) (xy 450.724123 -414.756945)
			(xy 450.70395 -414.778444) (xy 450.697396 -414.785764) (xy 450.689964 -414.803936) (xy 450.689472 -414.81375)
			(xy 450.689472 -414.86709) (xy 450.702426 -414.879536) (xy 450.710329 -414.886933) (xy 450.730463 -414.894828)
			(xy 450.741288 -414.894776) (xy 450.7738 -414.892998) (xy 450.784574 -414.891856) (xy 450.803779 -414.881872)
			(xy 450.810884 -414.873694) (xy 450.829064 -414.851551) (xy 450.870964 -414.812479) (xy 450.918237 -414.780112)
			(xy 450.969818 -414.755179) (xy 451.024548 -414.738242) (xy 451.081196 -414.729679) (xy 451.109842 -414.729168)
			(xy 451.139964 -414.72977) (xy 451.199459 -414.739243) (xy 451.256727 -414.757946) (xy 451.310345 -414.785415)
			(xy 451.35898 -414.820968) (xy 451.380606 -414.841944) (xy 451.387718 -414.84931) (xy 451.406514 -414.85693)
			(xy 451.49897 -414.85693) (xy 451.517766 -414.84931) (xy 451.524878 -414.841944) (xy 451.546497 -414.820957)
			(xy 451.595126 -414.785388) (xy 451.648744 -414.757908) (xy 451.706016 -414.739202) (xy 451.765517 -414.729734)
			(xy 451.795642 -414.729168) (xy 451.821941 -414.729585) (xy 451.87404 -414.73681) (xy 451.92465 -414.751129)
			(xy 451.972811 -414.772271) (xy 452.017608 -414.799834) (xy 452.058189 -414.833295) (xy 452.076312 -414.852358)
			(xy 452.083424 -414.859978) (xy 452.101712 -414.86836) (xy 452.194168 -414.871662) (xy 452.213218 -414.864804)
			(xy 452.220584 -414.857692) (xy 452.241902 -414.838411) (xy 452.289266 -414.805844) (xy 452.340979 -414.780753)
			(xy 452.395873 -414.763705) (xy 452.452702 -414.755087) (xy 452.481442 -414.754568) (xy 452.510242 -414.755066)
			(xy 452.567191 -414.763698) (xy 452.622196 -414.78079) (xy 452.674009 -414.805954) (xy 452.721451 -414.838618)
			(xy 452.742808 -414.857946) (xy 452.74992 -414.864804) (xy 452.767954 -414.871916) (xy 452.85787 -414.871154)
			(xy 452.875904 -414.864042) (xy 452.883016 -414.857184) (xy 452.904484 -414.837172) (xy 452.9524 -414.803287)
			(xy 453.004938 -414.777135) (xy 453.060861 -414.759334) (xy 453.118849 -414.750304) (xy 453.148192 -414.749742)
			(xy 453.17451 -414.750141) (xy 453.226647 -414.75737) (xy 453.277297 -414.771693) (xy 453.325499 -414.792837)
			(xy 453.370339 -414.820403) (xy 453.410968 -414.853867) (xy 453.429116 -414.872932) (xy 453.43626 -414.879989)
			(xy 453.454426 -414.888492) (xy 453.464422 -414.889442) (xy 453.51827 -414.891474) (xy 453.52462 -414.885124)
			(xy 453.531732 -414.878012) (xy 453.539352 -414.859724) (xy 453.540368 -414.76803) (xy 453.533002 -414.749742)
			(xy 453.52589 -414.742376) (xy 453.505877 -414.720922) (xy 453.472052 -414.672985) (xy 453.44596 -414.620436)
			(xy 453.428217 -414.564514) (xy 453.419239 -414.506535) (xy 453.418702 -414.4772) (xy 453.419188 -414.449949)
			(xy 453.426944 -414.396001) (xy 453.442299 -414.343706) (xy 453.464941 -414.294129) (xy 453.494407 -414.248279)
			(xy 453.530098 -414.207088) (xy 453.571289 -414.171397) (xy 453.617139 -414.141931) (xy 453.666716 -414.119289)
			(xy 453.719011 -414.103934) (xy 453.772959 -414.096178) (xy 453.827461 -414.096178) (xy 453.881409 -414.103934)
			(xy 453.933704 -414.119289) (xy 453.983281 -414.141931) (xy 454.029131 -414.171397) (xy 454.070322 -414.207088)
			(xy 454.106013 -414.248279) (xy 454.135479 -414.294129) (xy 454.158121 -414.343706) (xy 454.173476 -414.396001)
			(xy 454.181232 -414.449949) (xy 454.181718 -414.4772) (xy 454.181157 -414.507324) (xy 454.171675 -414.566821)
			(xy 454.152962 -414.62409) (xy 454.125484 -414.677707) (xy 454.089923 -414.72634) (xy 454.068942 -414.747964)
			(xy 454.06183 -414.755076) (xy 454.05421 -414.773364) (xy 454.053194 -414.865058) (xy 454.06056 -414.883346)
			(xy 454.067672 -414.890712) (xy 454.087673 -414.912177) (xy 454.121501 -414.960111) (xy 454.147596 -415.012656)
			(xy 454.165342 -415.068577) (xy 454.174322 -415.126554) (xy 454.17486 -415.155888) (xy 454.174371 -415.183386)
			(xy 454.166481 -415.237812) (xy 454.150863 -415.290544) (xy 454.12784 -415.340488) (xy 454.097888 -415.386612)
			(xy 454.080118 -415.407602) (xy 454.073768 -415.414714) (xy 454.067418 -415.43224) (xy 454.068688 -415.519362)
			(xy 454.075546 -415.536634) (xy 454.081896 -415.543746) (xy 454.100923 -415.565062) (xy 454.133149 -415.612242)
			(xy 454.157985 -415.663697) (xy 454.174875 -415.718278) (xy 454.183443 -415.774767) (xy 454.184004 -415.803334)
			(xy 454.183554 -415.830586) (xy 454.175793 -415.884535) (xy 454.160433 -415.936831) (xy 454.137788 -415.986409)
			(xy 454.108317 -416.032259) (xy 454.072622 -416.073449) (xy 454.031429 -416.10914) (xy 453.985575 -416.138606)
			(xy 453.935995 -416.161246) (xy 453.883698 -416.176601) (xy 453.829748 -416.184357) (xy 453.802496 -416.184842)
			(xy 453.776975 -416.18445) (xy 453.726387 -416.177654) (xy 453.677158 -416.164171) (xy 453.630167 -416.144242)
			(xy 453.586254 -416.118222) (xy 453.546205 -416.086578) (xy 453.528176 -416.06851) (xy 453.521572 -416.061652)
			(xy 453.5043 -416.053778) (xy 453.416162 -416.048698) (xy 453.398128 -416.05454) (xy 453.390762 -416.06089)
			(xy 453.37018 -416.077259) (xy 453.325366 -416.104777) (xy 453.277195 -416.125875) (xy 453.226582 -416.140152)
			(xy 453.174487 -416.147338) (xy 453.148192 -416.147758) (xy 453.119392 -416.14726) (xy 453.062442 -416.138631)
			(xy 453.007436 -416.12154) (xy 452.955623 -416.096376) (xy 452.908182 -416.06371) (xy 452.886826 -416.04438)
			(xy 452.879714 -416.037522) (xy 452.86168 -416.03041) (xy 452.771764 -416.031172) (xy 452.75373 -416.038284)
			(xy 452.746618 -416.045142) (xy 452.725182 -416.06519) (xy 452.677257 -416.099069) (xy 452.62471 -416.125214)
			(xy 452.568781 -416.143006) (xy 452.510787 -416.152027) (xy 452.481442 -416.152584) (xy 452.45132 -416.151977)
			(xy 452.391826 -416.142503) (xy 452.334559 -416.1238) (xy 452.280941 -416.096333) (xy 452.232305 -416.060783)
			(xy 452.210678 -416.039808) (xy 452.203566 -416.032442) (xy 452.18477 -416.024822) (xy 452.092314 -416.024822)
			(xy 452.073518 -416.032442) (xy 452.066406 -416.039808) (xy 452.046782 -416.05891) (xy 452.003043 -416.091863)
			(xy 451.955042 -416.118223) (xy 451.903764 -416.137449) (xy 451.850264 -416.149145) (xy 451.795642 -416.15307)
			(xy 451.74102 -416.149145) (xy 451.68752 -416.137449) (xy 451.636242 -416.118223) (xy 451.588241 -416.091863)
			(xy 451.544502 -416.05891) (xy 451.524878 -416.039808) (xy 451.517766 -416.032442) (xy 451.49897 -416.024822)
			(xy 451.406514 -416.024822) (xy 451.387718 -416.032442) (xy 451.380606 -416.039808) (xy 451.359003 -416.060812)
			(xy 451.310368 -416.096377) (xy 451.256746 -416.123852) (xy 451.199471 -416.142555) (xy 451.139968 -416.152019)
			(xy 451.109842 -416.152584) (xy 451.080711 -416.152045) (xy 451.023129 -416.14317) (xy 450.967568 -416.125637)
			(xy 450.915322 -416.099853) (xy 450.867607 -416.06642) (xy 450.84619 -416.046666) (xy 450.838824 -416.039808)
			(xy 450.820282 -416.032442) (xy 450.728588 -416.033966) (xy 450.710554 -416.04184) (xy 450.703188 -416.049206)
			(xy 450.681532 -416.070516) (xy 450.632677 -416.106631) (xy 450.578715 -416.134546) (xy 450.521011 -416.153554)
			(xy 450.461023 -416.163175) (xy 450.430646 -416.16376) (xy 450.403392 -416.163302) (xy 450.349438 -416.15555)
			(xy 450.297138 -416.140197) (xy 450.247554 -416.117557) (xy 450.201699 -416.088089) (xy 450.160504 -416.052394)
			(xy 450.12481 -416.0112) (xy 450.095343 -415.965344) (xy 450.072702 -415.915761) (xy 450.05735 -415.86346)
			(xy 450.049598 -415.809506) (xy 450.049138 -415.782252) (xy 450.0497 -415.752775) (xy 450.058762 -415.694522)
			(xy 450.076679 -415.638357) (xy 450.103024 -415.585618) (xy 450.137169 -415.537559) (xy 450.157342 -415.51606)
			(xy 450.163893 -415.508738) (xy 450.171327 -415.490568) (xy 450.17182 -415.480754) (xy 450.17182 -415.427414)
			(xy 450.159882 -415.415984) (xy 450.15277 -415.408618) (xy 450.133974 -415.400998) (xy 450.041518 -415.400998)
			(xy 450.022722 -415.408618) (xy 450.01561 -415.415984) (xy 449.994001 -415.436982) (xy 449.945368 -415.472548)
			(xy 449.891748 -415.500026) (xy 449.834474 -415.51873) (xy 449.774971 -415.528195) (xy 449.744846 -415.52876)
			(xy 449.717592 -415.528302) (xy 449.663638 -415.52055) (xy 449.611338 -415.505197) (xy 449.561754 -415.482557)
			(xy 449.515899 -415.453089) (xy 449.474704 -415.417394) (xy 449.43901 -415.3762) (xy 449.409543 -415.330344)
			(xy 449.386902 -415.280761) (xy 449.37155 -415.22846) (xy 449.363798 -415.174506) (xy 449.363338 -415.147252)
			(xy 432.260756 -415.147252) (xy 432.260756 -418.436044) (xy 438.118756 -418.436044) (xy 438.122827 -418.380422)
			(xy 438.134953 -418.325985) (xy 438.154876 -418.273894) (xy 438.182172 -418.225259) (xy 438.216258 -418.181116)
			(xy 438.256407 -418.142407) (xy 438.301765 -418.109956) (xy 438.351365 -418.084455) (xy 438.404149 -418.066448)
			(xy 438.458992 -418.056318) (xy 438.514726 -418.054281) (xy 438.570163 -418.060381) (xy 438.62412 -418.074487)
			(xy 438.675449 -418.096299) (xy 438.723055 -418.125353) (xy 438.765923 -418.161028) (xy 438.80314 -418.202565)
			(xy 438.833913 -418.249078) (xy 438.857585 -418.299575) (xy 438.873653 -418.352982) (xy 438.881773 -418.408158)
			(xy 438.882282 -418.436044) (xy 439.134756 -418.436044) (xy 439.138827 -418.380422) (xy 439.150953 -418.325985)
			(xy 439.170876 -418.273894) (xy 439.198172 -418.225259) (xy 439.232258 -418.181116) (xy 439.272407 -418.142407)
			(xy 439.317765 -418.109956) (xy 439.367365 -418.084455) (xy 439.420149 -418.066448) (xy 439.474992 -418.056318)
			(xy 439.530726 -418.054281) (xy 439.586163 -418.060381) (xy 439.64012 -418.074487) (xy 439.691449 -418.096299)
			(xy 439.739055 -418.125353) (xy 439.781923 -418.161028) (xy 439.816684 -418.199824) (xy 448.144898 -418.199824)
			(xy 448.148969 -418.144202) (xy 448.161095 -418.089765) (xy 448.181018 -418.037674) (xy 448.208314 -417.989039)
			(xy 448.2424 -417.944896) (xy 448.282549 -417.906187) (xy 448.327907 -417.873736) (xy 448.377507 -417.848235)
			(xy 448.430291 -417.830228) (xy 448.485134 -417.820098) (xy 448.540868 -417.818061) (xy 448.596305 -417.824161)
			(xy 448.650262 -417.838267) (xy 448.701591 -417.860079) (xy 448.749197 -417.889133) (xy 448.792065 -417.924808)
			(xy 448.829282 -417.966345) (xy 448.860055 -418.012858) (xy 448.883727 -418.063355) (xy 448.899795 -418.116762)
			(xy 448.907915 -418.171938) (xy 448.908424 -418.199824) (xy 448.907915 -418.22771) (xy 448.899795 -418.282886)
			(xy 448.883727 -418.336293) (xy 448.860055 -418.38679) (xy 448.829282 -418.433303) (xy 448.792065 -418.47484)
			(xy 448.749197 -418.510515) (xy 448.701591 -418.539569) (xy 448.650262 -418.561381) (xy 448.596305 -418.575487)
			(xy 448.540868 -418.581587) (xy 448.485134 -418.57955) (xy 448.430291 -418.56942) (xy 448.377507 -418.551413)
			(xy 448.327907 -418.525912) (xy 448.282549 -418.493461) (xy 448.2424 -418.454752) (xy 448.208314 -418.410609)
			(xy 448.181018 -418.361974) (xy 448.161095 -418.309883) (xy 448.148969 -418.255446) (xy 448.144898 -418.199824)
			(xy 439.816684 -418.199824) (xy 439.81914 -418.202565) (xy 439.849913 -418.249078) (xy 439.873585 -418.299575)
			(xy 439.889653 -418.352982) (xy 439.897773 -418.408158) (xy 439.898282 -418.436044) (xy 439.897773 -418.46393)
			(xy 439.889653 -418.519106) (xy 439.873585 -418.572513) (xy 439.849913 -418.62301) (xy 439.81914 -418.669523)
			(xy 439.781923 -418.71106) (xy 439.739055 -418.746735) (xy 439.691449 -418.775789) (xy 439.64012 -418.797601)
			(xy 439.586163 -418.811707) (xy 439.530726 -418.817807) (xy 439.474992 -418.81577) (xy 439.420149 -418.80564)
			(xy 439.367365 -418.787633) (xy 439.317765 -418.762132) (xy 439.272407 -418.729681) (xy 439.232258 -418.690972)
			(xy 439.198172 -418.646829) (xy 439.170876 -418.598194) (xy 439.150953 -418.546103) (xy 439.138827 -418.491666)
			(xy 439.134756 -418.436044) (xy 438.882282 -418.436044) (xy 438.881773 -418.46393) (xy 438.873653 -418.519106)
			(xy 438.857585 -418.572513) (xy 438.833913 -418.62301) (xy 438.80314 -418.669523) (xy 438.765923 -418.71106)
			(xy 438.723055 -418.746735) (xy 438.675449 -418.775789) (xy 438.62412 -418.797601) (xy 438.570163 -418.811707)
			(xy 438.514726 -418.817807) (xy 438.458992 -418.81577) (xy 438.404149 -418.80564) (xy 438.351365 -418.787633)
			(xy 438.301765 -418.762132) (xy 438.256407 -418.729681) (xy 438.216258 -418.690972) (xy 438.182172 -418.646829)
			(xy 438.154876 -418.598194) (xy 438.134953 -418.546103) (xy 438.122827 -418.491666) (xy 438.118756 -418.436044)
			(xy 432.260756 -418.436044) (xy 432.260756 -419.59911) (xy 440.425584 -419.59911) (xy 440.429655 -419.543488)
			(xy 440.441781 -419.489051) (xy 440.461704 -419.43696) (xy 440.489 -419.388325) (xy 440.523086 -419.344182)
			(xy 440.563235 -419.305473) (xy 440.608593 -419.273022) (xy 440.658193 -419.247521) (xy 440.710977 -419.229514)
			(xy 440.76582 -419.219384) (xy 440.821554 -419.217347) (xy 440.876991 -419.223447) (xy 440.930948 -419.237553)
			(xy 440.982277 -419.259365) (xy 441.029883 -419.288419) (xy 441.072751 -419.324094) (xy 441.109968 -419.365631)
			(xy 441.140741 -419.412144) (xy 441.140751 -419.412166) (xy 442.711584 -419.412166) (xy 442.715655 -419.356544)
			(xy 442.727781 -419.302107) (xy 442.747704 -419.250016) (xy 442.775 -419.201381) (xy 442.809086 -419.157238)
			(xy 442.849235 -419.118529) (xy 442.894593 -419.086078) (xy 442.944193 -419.060577) (xy 442.996977 -419.04257)
			(xy 443.05182 -419.03244) (xy 443.107554 -419.030403) (xy 443.162991 -419.036503) (xy 443.216948 -419.050609)
			(xy 443.268277 -419.072421) (xy 443.315883 -419.101475) (xy 443.358751 -419.13715) (xy 443.395968 -419.178687)
			(xy 443.426741 -419.2252) (xy 443.450413 -419.275697) (xy 443.466481 -419.329104) (xy 443.474601 -419.38428)
			(xy 443.47511 -419.412166) (xy 443.474601 -419.440052) (xy 443.466481 -419.495228) (xy 443.450413 -419.548635)
			(xy 443.427823 -419.596824) (xy 448.925948 -419.596824) (xy 448.930019 -419.541202) (xy 448.942145 -419.486765)
			(xy 448.962068 -419.434674) (xy 448.989364 -419.386039) (xy 449.02345 -419.341896) (xy 449.063599 -419.303187)
			(xy 449.108957 -419.270736) (xy 449.158557 -419.245235) (xy 449.211341 -419.227228) (xy 449.266184 -419.217098)
			(xy 449.321918 -419.215061) (xy 449.377355 -419.221161) (xy 449.431312 -419.235267) (xy 449.482641 -419.257079)
			(xy 449.530247 -419.286133) (xy 449.573115 -419.321808) (xy 449.610332 -419.363345) (xy 449.641105 -419.409858)
			(xy 449.664777 -419.460355) (xy 449.680845 -419.513762) (xy 449.688965 -419.568938) (xy 449.689474 -419.596824)
			(xy 449.688965 -419.62471) (xy 449.680845 -419.679886) (xy 449.664777 -419.733293) (xy 449.641105 -419.78379)
			(xy 449.610332 -419.830303) (xy 449.573115 -419.87184) (xy 449.530247 -419.907515) (xy 449.482641 -419.936569)
			(xy 449.431312 -419.958381) (xy 449.377355 -419.972487) (xy 449.321918 -419.978587) (xy 449.266184 -419.97655)
			(xy 449.211341 -419.96642) (xy 449.158557 -419.948413) (xy 449.108957 -419.922912) (xy 449.063599 -419.890461)
			(xy 449.02345 -419.851752) (xy 448.989364 -419.807609) (xy 448.962068 -419.758974) (xy 448.942145 -419.706883)
			(xy 448.930019 -419.652446) (xy 448.925948 -419.596824) (xy 443.427823 -419.596824) (xy 443.426741 -419.599132)
			(xy 443.395968 -419.645645) (xy 443.358751 -419.687182) (xy 443.315883 -419.722857) (xy 443.268277 -419.751911)
			(xy 443.216948 -419.773723) (xy 443.162991 -419.787829) (xy 443.107554 -419.793929) (xy 443.05182 -419.791892)
			(xy 442.996977 -419.781762) (xy 442.944193 -419.763755) (xy 442.894593 -419.738254) (xy 442.849235 -419.705803)
			(xy 442.809086 -419.667094) (xy 442.775 -419.622951) (xy 442.747704 -419.574316) (xy 442.727781 -419.522225)
			(xy 442.715655 -419.467788) (xy 442.711584 -419.412166) (xy 441.140751 -419.412166) (xy 441.164413 -419.462641)
			(xy 441.180481 -419.516048) (xy 441.188601 -419.571224) (xy 441.18911 -419.59911) (xy 441.188601 -419.626996)
			(xy 441.180481 -419.682172) (xy 441.164413 -419.735579) (xy 441.140741 -419.786076) (xy 441.109968 -419.832589)
			(xy 441.072751 -419.874126) (xy 441.029883 -419.909801) (xy 440.982277 -419.938855) (xy 440.930948 -419.960667)
			(xy 440.876991 -419.974773) (xy 440.821554 -419.980873) (xy 440.76582 -419.978836) (xy 440.710977 -419.968706)
			(xy 440.658193 -419.950699) (xy 440.608593 -419.925198) (xy 440.563235 -419.892747) (xy 440.523086 -419.854038)
			(xy 440.489 -419.809895) (xy 440.461704 -419.76126) (xy 440.441781 -419.709169) (xy 440.429655 -419.654732)
			(xy 440.425584 -419.59911) (xy 432.260756 -419.59911) (xy 432.260756 -420.23411) (xy 444.235584 -420.23411)
			(xy 444.239655 -420.178488) (xy 444.251781 -420.124051) (xy 444.271704 -420.07196) (xy 444.299 -420.023325)
			(xy 444.333086 -419.979182) (xy 444.373235 -419.940473) (xy 444.418593 -419.908022) (xy 444.468193 -419.882521)
			(xy 444.520977 -419.864514) (xy 444.57582 -419.854384) (xy 444.631554 -419.852347) (xy 444.686991 -419.858447)
			(xy 444.740948 -419.872553) (xy 444.792277 -419.894365) (xy 444.839883 -419.923419) (xy 444.882751 -419.959094)
			(xy 444.919968 -420.000631) (xy 444.950741 -420.047144) (xy 444.974413 -420.097641) (xy 444.990481 -420.151048)
			(xy 444.998601 -420.206224) (xy 444.99911 -420.23411) (xy 445.505584 -420.23411) (xy 445.509655 -420.178488)
			(xy 445.521781 -420.124051) (xy 445.541704 -420.07196) (xy 445.569 -420.023325) (xy 445.603086 -419.979182)
			(xy 445.643235 -419.940473) (xy 445.688593 -419.908022) (xy 445.738193 -419.882521) (xy 445.790977 -419.864514)
			(xy 445.84582 -419.854384) (xy 445.901554 -419.852347) (xy 445.956991 -419.858447) (xy 446.010948 -419.872553)
			(xy 446.062277 -419.894365) (xy 446.109883 -419.923419) (xy 446.152751 -419.959094) (xy 446.189968 -420.000631)
			(xy 446.220741 -420.047144) (xy 446.244413 -420.097641) (xy 446.260481 -420.151048) (xy 446.268601 -420.206224)
			(xy 446.26911 -420.23411) (xy 446.268601 -420.261996) (xy 446.260481 -420.317172) (xy 446.244413 -420.370579)
			(xy 446.220741 -420.421076) (xy 446.189968 -420.467589) (xy 446.152751 -420.509126) (xy 446.109883 -420.544801)
			(xy 446.062277 -420.573855) (xy 446.010948 -420.595667) (xy 445.956991 -420.609773) (xy 445.901554 -420.615873)
			(xy 445.84582 -420.613836) (xy 445.790977 -420.603706) (xy 445.738193 -420.585699) (xy 445.688593 -420.560198)
			(xy 445.643235 -420.527747) (xy 445.603086 -420.489038) (xy 445.569 -420.444895) (xy 445.541704 -420.39626)
			(xy 445.521781 -420.344169) (xy 445.509655 -420.289732) (xy 445.505584 -420.23411) (xy 444.99911 -420.23411)
			(xy 444.998601 -420.261996) (xy 444.990481 -420.317172) (xy 444.974413 -420.370579) (xy 444.950741 -420.421076)
			(xy 444.919968 -420.467589) (xy 444.882751 -420.509126) (xy 444.839883 -420.544801) (xy 444.792277 -420.573855)
			(xy 444.740948 -420.595667) (xy 444.686991 -420.609773) (xy 444.631554 -420.615873) (xy 444.57582 -420.613836)
			(xy 444.520977 -420.603706) (xy 444.468193 -420.585699) (xy 444.418593 -420.560198) (xy 444.373235 -420.527747)
			(xy 444.333086 -420.489038) (xy 444.299 -420.444895) (xy 444.271704 -420.39626) (xy 444.251781 -420.344169)
			(xy 444.239655 -420.289732) (xy 444.235584 -420.23411) (xy 432.260756 -420.23411) (xy 432.260756 -420.86911)
			(xy 440.180982 -420.86911) (xy 440.185053 -420.813488) (xy 440.197179 -420.759051) (xy 440.217102 -420.70696)
			(xy 440.244398 -420.658325) (xy 440.278484 -420.614182) (xy 440.318633 -420.575473) (xy 440.363991 -420.543022)
			(xy 440.413591 -420.517521) (xy 440.466375 -420.499514) (xy 440.521218 -420.489384) (xy 440.576952 -420.487347)
			(xy 440.632389 -420.493447) (xy 440.686346 -420.507553) (xy 440.737675 -420.529365) (xy 440.785281 -420.558419)
			(xy 440.828149 -420.594094) (xy 440.865366 -420.635631) (xy 440.896139 -420.682144) (xy 440.919811 -420.732641)
			(xy 440.92266 -420.74211) (xy 442.838584 -420.74211) (xy 442.842655 -420.686488) (xy 442.854781 -420.632051)
			(xy 442.874704 -420.57996) (xy 442.902 -420.531325) (xy 442.936086 -420.487182) (xy 442.976235 -420.448473)
			(xy 443.021593 -420.416022) (xy 443.071193 -420.390521) (xy 443.123977 -420.372514) (xy 443.17882 -420.362384)
			(xy 443.234554 -420.360347) (xy 443.289991 -420.366447) (xy 443.343948 -420.380553) (xy 443.395277 -420.402365)
			(xy 443.442883 -420.431419) (xy 443.485751 -420.467094) (xy 443.522968 -420.508631) (xy 443.553741 -420.555144)
			(xy 443.577413 -420.605641) (xy 443.593481 -420.659048) (xy 443.601601 -420.714224) (xy 443.60211 -420.74211)
			(xy 443.601601 -420.769996) (xy 443.593481 -420.825172) (xy 443.577413 -420.878579) (xy 443.553741 -420.929076)
			(xy 443.522968 -420.975589) (xy 443.504581 -420.99611) (xy 450.196458 -420.99611) (xy 450.196941 -420.968612)
			(xy 450.204832 -420.914185) (xy 450.220451 -420.861453) (xy 450.243476 -420.811509) (xy 450.27343 -420.765386)
			(xy 450.2912 -420.744396) (xy 450.29755 -420.737284) (xy 450.3039 -420.720266) (xy 450.3039 -420.634668)
			(xy 450.29755 -420.61765) (xy 450.2912 -420.610538) (xy 450.273442 -420.589537) (xy 450.243486 -420.543417)
			(xy 450.220458 -420.493476) (xy 450.204835 -420.440747) (xy 450.19694 -420.386321) (xy 450.196458 -420.358824)
			(xy 450.196944 -420.331573) (xy 450.2047 -420.277625) (xy 450.220055 -420.22533) (xy 450.242697 -420.175753)
			(xy 450.272163 -420.129903) (xy 450.307854 -420.088712) (xy 450.349045 -420.053021) (xy 450.394895 -420.023555)
			(xy 450.444472 -420.000913) (xy 450.496767 -419.985558) (xy 450.550715 -419.977802) (xy 450.605217 -419.977802)
			(xy 450.659165 -419.985558) (xy 450.71146 -420.000913) (xy 450.761037 -420.023555) (xy 450.806887 -420.053021)
			(xy 450.848078 -420.088712) (xy 450.883769 -420.129903) (xy 450.913235 -420.175753) (xy 450.935877 -420.22533)
			(xy 450.951232 -420.277625) (xy 450.958988 -420.331573) (xy 450.959474 -420.358824) (xy 450.959003 -420.386322)
			(xy 450.951108 -420.44075) (xy 450.935486 -420.493481) (xy 450.912458 -420.543425) (xy 450.882503 -420.589548)
			(xy 450.864732 -420.610538) (xy 450.858382 -420.61765) (xy 450.852032 -420.634668) (xy 450.852032 -420.720266)
			(xy 450.858382 -420.737284) (xy 450.864732 -420.744396) (xy 450.882511 -420.76538) (xy 450.912463 -420.811505)
			(xy 450.935486 -420.861451) (xy 450.951105 -420.914183) (xy 450.958995 -420.968611) (xy 450.959474 -420.99611)
			(xy 450.958988 -421.023361) (xy 450.951232 -421.077309) (xy 450.935877 -421.129604) (xy 450.913235 -421.179181)
			(xy 450.883769 -421.225031) (xy 450.848078 -421.266222) (xy 450.806887 -421.301913) (xy 450.761037 -421.331379)
			(xy 450.71146 -421.354021) (xy 450.659165 -421.369376) (xy 450.605217 -421.377132) (xy 450.550715 -421.377132)
			(xy 450.496767 -421.369376) (xy 450.444472 -421.354021) (xy 450.394895 -421.331379) (xy 450.349045 -421.301913)
			(xy 450.307854 -421.266222) (xy 450.272163 -421.225031) (xy 450.242697 -421.179181) (xy 450.220055 -421.129604)
			(xy 450.2047 -421.077309) (xy 450.196944 -421.023361) (xy 450.196458 -420.99611) (xy 443.504581 -420.99611)
			(xy 443.485751 -421.017126) (xy 443.442883 -421.052801) (xy 443.395277 -421.081855) (xy 443.343948 -421.103667)
			(xy 443.289991 -421.117773) (xy 443.234554 -421.123873) (xy 443.17882 -421.121836) (xy 443.123977 -421.111706)
			(xy 443.071193 -421.093699) (xy 443.021593 -421.068198) (xy 442.976235 -421.035747) (xy 442.936086 -420.997038)
			(xy 442.902 -420.952895) (xy 442.874704 -420.90426) (xy 442.854781 -420.852169) (xy 442.842655 -420.797732)
			(xy 442.838584 -420.74211) (xy 440.92266 -420.74211) (xy 440.935879 -420.786048) (xy 440.943999 -420.841224)
			(xy 440.944508 -420.86911) (xy 440.943999 -420.896996) (xy 440.935879 -420.952172) (xy 440.919811 -421.005579)
			(xy 440.896139 -421.056076) (xy 440.865366 -421.102589) (xy 440.828149 -421.144126) (xy 440.785281 -421.179801)
			(xy 440.737675 -421.208855) (xy 440.686346 -421.230667) (xy 440.632389 -421.244773) (xy 440.576952 -421.250873)
			(xy 440.521218 -421.248836) (xy 440.466375 -421.238706) (xy 440.413591 -421.220699) (xy 440.363991 -421.195198)
			(xy 440.318633 -421.162747) (xy 440.278484 -421.124038) (xy 440.244398 -421.079895) (xy 440.217102 -421.03126)
			(xy 440.197179 -420.979169) (xy 440.185053 -420.924732) (xy 440.180982 -420.86911) (xy 432.260756 -420.86911)
			(xy 432.260756 -423.215562) (xy 440.204098 -423.215562) (xy 440.204539 -423.188278) (xy 440.212331 -423.134267)
			(xy 440.227736 -423.081918) (xy 440.25044 -423.032296) (xy 440.279981 -422.986414) (xy 440.315756 -422.945208)
			(xy 440.357035 -422.909517) (xy 440.402977 -422.880069) (xy 440.427618 -422.868344) (xy 440.44102 -422.861668)
			(xy 440.463477 -422.841883) (xy 440.479241 -422.816442) (xy 440.486961 -422.787526) (xy 440.485975 -422.757613)
			(xy 440.476368 -422.729268) (xy 440.458964 -422.70492) (xy 440.44743 -422.69537) (xy 440.424753 -422.677154)
			(xy 440.384614 -422.63506) (xy 440.351326 -422.587363) (xy 440.325662 -422.535167) (xy 440.308214 -422.479682)
			(xy 440.299387 -422.422192) (xy 440.29884 -422.39311) (xy 440.299326 -422.365859) (xy 440.307082 -422.311911)
			(xy 440.322437 -422.259616) (xy 440.345079 -422.210039) (xy 440.374545 -422.164189) (xy 440.410236 -422.122998)
			(xy 440.451427 -422.087307) (xy 440.497277 -422.057841) (xy 440.546854 -422.035199) (xy 440.599149 -422.019844)
			(xy 440.653097 -422.012088) (xy 440.707599 -422.012088) (xy 440.761547 -422.019844) (xy 440.813842 -422.035199)
			(xy 440.863419 -422.057841) (xy 440.909269 -422.087307) (xy 440.95046 -422.122998) (xy 440.986151 -422.164189)
			(xy 441.015617 -422.210039) (xy 441.038259 -422.259616) (xy 441.053614 -422.311911) (xy 441.06137 -422.365859)
			(xy 441.061856 -422.39311) (xy 441.061419 -422.420395) (xy 441.05363 -422.474406) (xy 441.038226 -422.526757)
			(xy 441.015522 -422.57638) (xy 440.98598 -422.622263) (xy 440.950204 -422.663469) (xy 440.908923 -422.699159)
			(xy 440.862979 -422.728605) (xy 440.838336 -422.740328) (xy 440.824956 -422.747048) (xy 440.802492 -422.76682)
			(xy 440.797971 -422.77411) (xy 448.661534 -422.77411) (xy 448.665605 -422.718488) (xy 448.677731 -422.664051)
			(xy 448.697654 -422.61196) (xy 448.72495 -422.563325) (xy 448.759036 -422.519182) (xy 448.799185 -422.480473)
			(xy 448.844543 -422.448022) (xy 448.894143 -422.422521) (xy 448.946927 -422.404514) (xy 449.00177 -422.394384)
			(xy 449.057504 -422.392347) (xy 449.112941 -422.398447) (xy 449.166898 -422.412553) (xy 449.218227 -422.434365)
			(xy 449.265833 -422.463419) (xy 449.308701 -422.499094) (xy 449.345918 -422.540631) (xy 449.376691 -422.587144)
			(xy 449.400363 -422.637641) (xy 449.416431 -422.691048) (xy 449.424551 -422.746224) (xy 449.42506 -422.77411)
			(xy 449.424551 -422.801996) (xy 449.416431 -422.857172) (xy 449.400363 -422.910579) (xy 449.376691 -422.961076)
			(xy 449.345918 -423.007589) (xy 449.308701 -423.049126) (xy 449.265833 -423.084801) (xy 449.218227 -423.113855)
			(xy 449.166898 -423.135667) (xy 449.112941 -423.149773) (xy 449.057504 -423.155873) (xy 449.00177 -423.153836)
			(xy 448.946927 -423.143706) (xy 448.894143 -423.125699) (xy 448.844543 -423.100198) (xy 448.799185 -423.067747)
			(xy 448.759036 -423.029038) (xy 448.72495 -422.984895) (xy 448.697654 -422.93626) (xy 448.677731 -422.884169)
			(xy 448.665605 -422.829732) (xy 448.661534 -422.77411) (xy 440.797971 -422.77411) (xy 440.786721 -422.792252)
			(xy 440.778996 -422.821163) (xy 440.779978 -422.851072) (xy 440.789584 -422.879414) (xy 440.80699 -422.903756)
			(xy 440.818524 -422.913302) (xy 440.841247 -422.931463) (xy 440.881381 -422.97357) (xy 440.914661 -423.021279)
			(xy 440.940317 -423.073485) (xy 440.957756 -423.128979) (xy 440.966572 -423.186477) (xy 440.967114 -423.215562)
			(xy 440.966628 -423.242813) (xy 440.958872 -423.296761) (xy 440.943517 -423.349056) (xy 440.920875 -423.398633)
			(xy 440.891409 -423.444483) (xy 440.855718 -423.485674) (xy 440.814527 -423.521365) (xy 440.768677 -423.550831)
			(xy 440.755743 -423.556738) (xy 456.285335 -423.556738) (xy 456.285335 -423.427598) (xy 456.293285 -423.298703)
			(xy 456.309155 -423.170543) (xy 456.332884 -423.043602) (xy 456.364383 -422.918363) (xy 456.403532 -422.7953)
			(xy 456.450183 -422.674881) (xy 456.504158 -422.557562) (xy 456.565253 -422.443788) (xy 456.633236 -422.333991)
			(xy 456.70785 -422.228588) (xy 456.788811 -422.127978) (xy 456.875811 -422.032543) (xy 456.968522 -421.942644)
			(xy 457.066592 -421.858623) (xy 457.169647 -421.780799) (xy 457.277298 -421.709467) (xy 457.389137 -421.644897)
			(xy 457.504738 -421.587335) (xy 457.623663 -421.536998) (xy 457.745462 -421.494078) (xy 457.869672 -421.458737)
			(xy 457.995821 -421.43111) (xy 458.123433 -421.411301) (xy 458.252022 -421.399385) (xy 458.3811 -421.395409)
			(xy 458.510178 -421.399385) (xy 458.638767 -421.411301) (xy 458.766379 -421.43111) (xy 458.892528 -421.458737)
			(xy 459.016738 -421.494078) (xy 459.138537 -421.536998) (xy 459.257462 -421.587335) (xy 459.373063 -421.644897)
			(xy 459.484902 -421.709467) (xy 459.592553 -421.780799) (xy 459.695608 -421.858623) (xy 459.793678 -421.942644)
			(xy 459.886389 -422.032543) (xy 459.973389 -422.127978) (xy 460.05435 -422.228588) (xy 460.128964 -422.333991)
			(xy 460.196947 -422.443788) (xy 460.258042 -422.557562) (xy 460.312017 -422.674881) (xy 460.358668 -422.7953)
			(xy 460.397817 -422.918363) (xy 460.429316 -423.043602) (xy 460.453045 -423.170543) (xy 460.468915 -423.298703)
			(xy 460.476865 -423.427598) (xy 460.477362 -423.492168) (xy 460.476865 -423.556738) (xy 460.468915 -423.685633)
			(xy 460.453045 -423.813793) (xy 460.429316 -423.940734) (xy 460.397817 -424.065973) (xy 460.358668 -424.189036)
			(xy 460.312017 -424.309455) (xy 460.258042 -424.426774) (xy 460.196947 -424.540548) (xy 460.128964 -424.650345)
			(xy 460.05435 -424.755748) (xy 459.973389 -424.856358) (xy 459.886389 -424.951793) (xy 459.793678 -425.041692)
			(xy 459.695608 -425.125713) (xy 459.592553 -425.203537) (xy 459.484902 -425.274869) (xy 459.373063 -425.339439)
			(xy 459.257462 -425.397001) (xy 459.138537 -425.447338) (xy 459.016738 -425.490258) (xy 458.892528 -425.525599)
			(xy 458.766379 -425.553226) (xy 458.638767 -425.573035) (xy 458.510178 -425.584951) (xy 458.3811 -425.588928)
			(xy 458.252022 -425.584951) (xy 458.123433 -425.573035) (xy 457.995821 -425.553226) (xy 457.869672 -425.525599)
			(xy 457.745462 -425.490258) (xy 457.623663 -425.447338) (xy 457.504738 -425.397001) (xy 457.389137 -425.339439)
			(xy 457.277298 -425.274869) (xy 457.169647 -425.203537) (xy 457.066592 -425.125713) (xy 456.968522 -425.041692)
			(xy 456.875811 -424.951793) (xy 456.788811 -424.856358) (xy 456.70785 -424.755748) (xy 456.633236 -424.650345)
			(xy 456.565253 -424.540548) (xy 456.504158 -424.426774) (xy 456.450183 -424.309455) (xy 456.403532 -424.189036)
			(xy 456.364383 -424.065973) (xy 456.332884 -423.940734) (xy 456.309155 -423.813793) (xy 456.293285 -423.685633)
			(xy 456.285335 -423.556738) (xy 440.755743 -423.556738) (xy 440.7191 -423.573473) (xy 440.666805 -423.588828)
			(xy 440.612857 -423.596584) (xy 440.558355 -423.596584) (xy 440.504407 -423.588828) (xy 440.452112 -423.573473)
			(xy 440.402535 -423.550831) (xy 440.356685 -423.521365) (xy 440.315494 -423.485674) (xy 440.279803 -423.444483)
			(xy 440.250337 -423.398633) (xy 440.227695 -423.349056) (xy 440.21234 -423.296761) (xy 440.204584 -423.242813)
			(xy 440.204098 -423.215562) (xy 432.260756 -423.215562) (xy 432.260756 -423.798492) (xy 436.712612 -423.798492)
			(xy 436.716683 -423.74287) (xy 436.728809 -423.688433) (xy 436.748732 -423.636342) (xy 436.776028 -423.587707)
			(xy 436.810114 -423.543564) (xy 436.850263 -423.504855) (xy 436.895621 -423.472404) (xy 436.945221 -423.446903)
			(xy 436.998005 -423.428896) (xy 437.052848 -423.418766) (xy 437.108582 -423.416729) (xy 437.164019 -423.422829)
			(xy 437.217976 -423.436935) (xy 437.269305 -423.458747) (xy 437.316911 -423.487801) (xy 437.359779 -423.523476)
			(xy 437.396996 -423.565013) (xy 437.427769 -423.611526) (xy 437.451441 -423.662023) (xy 437.467509 -423.71543)
			(xy 437.475629 -423.770606) (xy 437.476138 -423.798492) (xy 437.475629 -423.826378) (xy 437.467509 -423.881554)
			(xy 437.451441 -423.934961) (xy 437.427769 -423.985458) (xy 437.396996 -424.031971) (xy 437.359779 -424.073508)
			(xy 437.316911 -424.109183) (xy 437.269305 -424.138237) (xy 437.217976 -424.160049) (xy 437.164019 -424.174155)
			(xy 437.108582 -424.180255) (xy 437.052848 -424.178218) (xy 436.998005 -424.168088) (xy 436.945221 -424.150081)
			(xy 436.895621 -424.12458) (xy 436.850263 -424.092129) (xy 436.810114 -424.05342) (xy 436.776028 -424.009277)
			(xy 436.748732 -423.960642) (xy 436.728809 -423.908551) (xy 436.716683 -423.854114) (xy 436.712612 -423.798492)
			(xy 432.260756 -423.798492) (xy 432.260756 -424.137836) (xy 432.260981 -424.145313) (xy 432.26524 -424.159645)
			(xy 432.269138 -424.16603) (xy 432.275488 -424.173904) (xy 432.289966 -424.188636) (xy 432.293271 -424.191824)
			(xy 432.300814 -424.197059) (xy 432.304952 -424.19905) (xy 432.329082 -424.210226) (xy 432.337718 -424.210988)
			(xy 432.365846 -424.214007) (xy 432.420834 -424.227286) (xy 432.473259 -424.24854) (xy 432.52197 -424.277302)
			(xy 432.565901 -424.312941) (xy 432.604087 -424.354676) (xy 432.635692 -424.401593) (xy 432.660023 -424.452662)
			(xy 432.676547 -424.506764) (xy 432.6849 -424.562713) (xy 432.684901 -424.619282) (xy 432.676548 -424.675231)
			(xy 432.660025 -424.729333) (xy 432.635695 -424.780403) (xy 432.618378 -424.80611) (xy 437.580784 -424.80611)
			(xy 437.584855 -424.750488) (xy 437.596981 -424.696051) (xy 437.616904 -424.64396) (xy 437.6442 -424.595325)
			(xy 437.678286 -424.551182) (xy 437.718435 -424.512473) (xy 437.763793 -424.480022) (xy 437.813393 -424.454521)
			(xy 437.866177 -424.436514) (xy 437.92102 -424.426384) (xy 437.976754 -424.424347) (xy 438.032191 -424.430447)
			(xy 438.086148 -424.444553) (xy 438.137477 -424.466365) (xy 438.185083 -424.495419) (xy 438.227951 -424.531094)
			(xy 438.265168 -424.572631) (xy 438.295941 -424.619144) (xy 438.313008 -424.655552) (xy 447.233765 -424.655552)
			(xy 447.233765 -424.601048) (xy 447.241522 -424.547098) (xy 447.256878 -424.494801) (xy 447.27952 -424.445222)
			(xy 447.308987 -424.39937) (xy 447.34468 -424.358179) (xy 447.385872 -424.322486) (xy 447.431724 -424.293019)
			(xy 447.481303 -424.270377) (xy 447.5336 -424.255022) (xy 447.58755 -424.247265) (xy 447.614802 -424.246802)
			(xy 447.642246 -424.247291) (xy 447.696568 -424.255158) (xy 447.749197 -424.270743) (xy 447.799044 -424.293723)
			(xy 447.82232 -424.30827) (xy 447.834456 -424.315613) (xy 447.861559 -424.323945) (xy 447.889908 -424.324497)
			(xy 447.917314 -424.317226) (xy 447.941661 -424.302693) (xy 447.961068 -424.282021) (xy 447.974037 -424.256806)
			(xy 447.97726 -424.242992) (xy 447.983544 -424.214555) (xy 448.003543 -424.159862) (xy 448.031619 -424.108841)
			(xy 448.067119 -424.062677) (xy 448.10922 -424.022442) (xy 448.156944 -423.989069) (xy 448.209184 -423.963333)
			(xy 448.264727 -423.945832) (xy 448.322285 -423.936971) (xy 448.351402 -423.936414) (xy 448.378655 -423.936856)
			(xy 448.432605 -423.944613) (xy 448.484903 -423.959969) (xy 448.534483 -423.982612) (xy 448.580336 -424.01208)
			(xy 448.621528 -424.047774) (xy 448.657221 -424.088966) (xy 448.686689 -424.134819) (xy 448.709331 -424.184399)
			(xy 448.724687 -424.236697) (xy 448.732444 -424.290647) (xy 448.732444 -424.345153) (xy 448.724687 -424.399103)
			(xy 448.709331 -424.451401) (xy 448.686689 -424.500981) (xy 448.657221 -424.546834) (xy 448.621528 -424.588026)
			(xy 448.580336 -424.62372) (xy 448.534483 -424.653188) (xy 448.484903 -424.675831) (xy 448.432605 -424.691187)
			(xy 448.378655 -424.698944) (xy 448.351402 -424.69943) (xy 448.323958 -424.698934) (xy 448.269637 -424.691069)
			(xy 448.217008 -424.675486) (xy 448.167161 -424.652508) (xy 448.143884 -424.637962) (xy 448.131723 -424.630667)
			(xy 448.104631 -424.622343) (xy 448.076293 -424.621793) (xy 448.048898 -424.629059) (xy 448.024558 -424.64358)
			(xy 448.005151 -424.664236) (xy 447.992174 -424.689434) (xy 447.988944 -424.70324) (xy 447.982701 -424.731688)
			(xy 447.962704 -424.786389) (xy 447.934628 -424.837415) (xy 447.899125 -424.883583) (xy 447.857018 -424.923821)
			(xy 447.809287 -424.957193) (xy 447.757038 -424.982924) (xy 447.701487 -425.000418) (xy 447.643922 -425.009268)
			(xy 447.614802 -425.009818) (xy 447.58755 -425.009335) (xy 447.5336 -425.001578) (xy 447.481303 -424.986223)
			(xy 447.431724 -424.963581) (xy 447.385872 -424.934114) (xy 447.34468 -424.898421) (xy 447.308987 -424.85723)
			(xy 447.27952 -424.811378) (xy 447.256878 -424.761799) (xy 447.241522 -424.709502) (xy 447.233765 -424.655552)
			(xy 438.313008 -424.655552) (xy 438.319613 -424.669641) (xy 438.335681 -424.723048) (xy 438.343801 -424.778224)
			(xy 438.34431 -424.80611) (xy 438.343801 -424.833996) (xy 438.335681 -424.889172) (xy 438.319613 -424.942579)
			(xy 438.295941 -424.993076) (xy 438.265168 -425.039589) (xy 438.246781 -425.06011) (xy 440.298584 -425.06011)
			(xy 440.302655 -425.004488) (xy 440.314781 -424.950051) (xy 440.334704 -424.89796) (xy 440.362 -424.849325)
			(xy 440.396086 -424.805182) (xy 440.436235 -424.766473) (xy 440.481593 -424.734022) (xy 440.531193 -424.708521)
			(xy 440.583977 -424.690514) (xy 440.63882 -424.680384) (xy 440.694554 -424.678347) (xy 440.749991 -424.684447)
			(xy 440.803948 -424.698553) (xy 440.855277 -424.720365) (xy 440.902883 -424.749419) (xy 440.945751 -424.785094)
			(xy 440.982968 -424.826631) (xy 441.013741 -424.873144) (xy 441.037413 -424.923641) (xy 441.053481 -424.977048)
			(xy 441.061601 -425.032224) (xy 441.06211 -425.06011) (xy 441.061601 -425.087996) (xy 441.053481 -425.143172)
			(xy 441.037413 -425.196579) (xy 441.013741 -425.247076) (xy 440.982968 -425.293589) (xy 440.945751 -425.335126)
			(xy 440.902883 -425.370801) (xy 440.855277 -425.399855) (xy 440.803948 -425.421667) (xy 440.749991 -425.435773)
			(xy 440.694554 -425.441873) (xy 440.63882 -425.439836) (xy 440.583977 -425.429706) (xy 440.531193 -425.411699)
			(xy 440.481593 -425.386198) (xy 440.436235 -425.353747) (xy 440.396086 -425.315038) (xy 440.362 -425.270895)
			(xy 440.334704 -425.22226) (xy 440.314781 -425.170169) (xy 440.302655 -425.115732) (xy 440.298584 -425.06011)
			(xy 438.246781 -425.06011) (xy 438.227951 -425.081126) (xy 438.185083 -425.116801) (xy 438.137477 -425.145855)
			(xy 438.086148 -425.167667) (xy 438.032191 -425.181773) (xy 437.976754 -425.187873) (xy 437.92102 -425.185836)
			(xy 437.866177 -425.175706) (xy 437.813393 -425.157699) (xy 437.763793 -425.132198) (xy 437.718435 -425.099747)
			(xy 437.678286 -425.061038) (xy 437.6442 -425.016895) (xy 437.616904 -424.96826) (xy 437.596981 -424.916169)
			(xy 437.584855 -424.861732) (xy 437.580784 -424.80611) (xy 432.618378 -424.80611) (xy 432.60409 -424.82732)
			(xy 432.565904 -424.869056) (xy 432.521974 -424.904696) (xy 432.473263 -424.933458) (xy 432.420839 -424.954712)
			(xy 432.365851 -424.967993) (xy 432.337718 -424.970956) (xy 432.329082 -424.971718) (xy 432.304952 -424.982894)
			(xy 432.300822 -424.984897) (xy 432.293287 -424.990139) (xy 432.289966 -424.993308) (xy 432.275488 -425.00804)
			(xy 432.269138 -425.015914) (xy 432.265243 -425.022301) (xy 432.260977 -425.036631) (xy 432.260756 -425.044108)
			(xy 432.260756 -426.07611) (xy 448.045584 -426.07611) (xy 448.049655 -426.020488) (xy 448.061781 -425.966051)
			(xy 448.081704 -425.91396) (xy 448.109 -425.865325) (xy 448.143086 -425.821182) (xy 448.183235 -425.782473)
			(xy 448.228593 -425.750022) (xy 448.278193 -425.724521) (xy 448.330977 -425.706514) (xy 448.38582 -425.696384)
			(xy 448.441554 -425.694347) (xy 448.496991 -425.700447) (xy 448.550948 -425.714553) (xy 448.602277 -425.736365)
			(xy 448.649883 -425.765419) (xy 448.692751 -425.801094) (xy 448.729968 -425.842631) (xy 448.760741 -425.889144)
			(xy 448.776945 -425.92371) (xy 450.299834 -425.92371) (xy 450.303905 -425.868088) (xy 450.316031 -425.813651)
			(xy 450.335954 -425.76156) (xy 450.36325 -425.712925) (xy 450.397336 -425.668782) (xy 450.437485 -425.630073)
			(xy 450.482843 -425.597622) (xy 450.532443 -425.572121) (xy 450.585227 -425.554114) (xy 450.64007 -425.543984)
			(xy 450.695804 -425.541947) (xy 450.751241 -425.548047) (xy 450.805198 -425.562153) (xy 450.856527 -425.583965)
			(xy 450.904133 -425.613019) (xy 450.947001 -425.648694) (xy 450.984218 -425.690231) (xy 451.014991 -425.736744)
			(xy 451.038663 -425.787241) (xy 451.054731 -425.840648) (xy 451.062851 -425.895824) (xy 451.06336 -425.92371)
			(xy 451.062851 -425.951596) (xy 451.054731 -426.006772) (xy 451.038663 -426.060179) (xy 451.014991 -426.110676)
			(xy 450.984218 -426.157189) (xy 450.947001 -426.198726) (xy 450.904133 -426.234401) (xy 450.856527 -426.263455)
			(xy 450.805198 -426.285267) (xy 450.751241 -426.299373) (xy 450.695804 -426.305473) (xy 450.64007 -426.303436)
			(xy 450.585227 -426.293306) (xy 450.532443 -426.275299) (xy 450.482843 -426.249798) (xy 450.437485 -426.217347)
			(xy 450.397336 -426.178638) (xy 450.36325 -426.134495) (xy 450.335954 -426.08586) (xy 450.316031 -426.033769)
			(xy 450.303905 -425.979332) (xy 450.299834 -425.92371) (xy 448.776945 -425.92371) (xy 448.784413 -425.939641)
			(xy 448.800481 -425.993048) (xy 448.808601 -426.048224) (xy 448.80911 -426.07611) (xy 448.808601 -426.103996)
			(xy 448.800481 -426.159172) (xy 448.784413 -426.212579) (xy 448.760741 -426.263076) (xy 448.729968 -426.309589)
			(xy 448.692751 -426.351126) (xy 448.649883 -426.386801) (xy 448.602277 -426.415855) (xy 448.550948 -426.437667)
			(xy 448.496991 -426.451773) (xy 448.441554 -426.457873) (xy 448.38582 -426.455836) (xy 448.330977 -426.445706)
			(xy 448.278193 -426.427699) (xy 448.228593 -426.402198) (xy 448.183235 -426.369747) (xy 448.143086 -426.331038)
			(xy 448.109 -426.286895) (xy 448.081704 -426.23826) (xy 448.061781 -426.186169) (xy 448.049655 -426.131732)
			(xy 448.045584 -426.07611) (xy 432.260756 -426.07611) (xy 432.260756 -426.83811) (xy 440.247784 -426.83811)
			(xy 440.251855 -426.782488) (xy 440.263981 -426.728051) (xy 440.283904 -426.67596) (xy 440.3112 -426.627325)
			(xy 440.345286 -426.583182) (xy 440.385435 -426.544473) (xy 440.430793 -426.512022) (xy 440.480393 -426.486521)
			(xy 440.533177 -426.468514) (xy 440.58802 -426.458384) (xy 440.643754 -426.456347) (xy 440.699191 -426.462447)
			(xy 440.753148 -426.476553) (xy 440.804477 -426.498365) (xy 440.852083 -426.527419) (xy 440.894951 -426.563094)
			(xy 440.932168 -426.604631) (xy 440.962941 -426.651144) (xy 440.986613 -426.701641) (xy 441.002681 -426.755048)
			(xy 441.010801 -426.810224) (xy 441.01131 -426.83811) (xy 441.010801 -426.865996) (xy 441.002681 -426.921172)
			(xy 440.986613 -426.974579) (xy 440.962941 -427.025076) (xy 440.932168 -427.071589) (xy 440.894951 -427.113126)
			(xy 440.852083 -427.148801) (xy 440.804477 -427.177855) (xy 440.753148 -427.199667) (xy 440.699191 -427.213773)
			(xy 440.643754 -427.219873) (xy 440.58802 -427.217836) (xy 440.533177 -427.207706) (xy 440.480393 -427.189699)
			(xy 440.430793 -427.164198) (xy 440.385435 -427.131747) (xy 440.345286 -427.093038) (xy 440.3112 -427.048895)
			(xy 440.283904 -427.00026) (xy 440.263981 -426.948169) (xy 440.251855 -426.893732) (xy 440.247784 -426.83811)
			(xy 432.260756 -426.83811) (xy 432.260756 -427.60011) (xy 447.029584 -427.60011) (xy 447.033655 -427.544488)
			(xy 447.045781 -427.490051) (xy 447.065704 -427.43796) (xy 447.093 -427.389325) (xy 447.127086 -427.345182)
			(xy 447.167235 -427.306473) (xy 447.212593 -427.274022) (xy 447.262193 -427.248521) (xy 447.314977 -427.230514)
			(xy 447.36982 -427.220384) (xy 447.425554 -427.218347) (xy 447.480991 -427.224447) (xy 447.534948 -427.238553)
			(xy 447.586277 -427.260365) (xy 447.633883 -427.289419) (xy 447.676751 -427.325094) (xy 447.713968 -427.366631)
			(xy 447.744741 -427.413144) (xy 447.768413 -427.463641) (xy 447.784481 -427.517048) (xy 447.792601 -427.572224)
			(xy 447.79311 -427.60011) (xy 447.792601 -427.627996) (xy 447.784481 -427.683172) (xy 447.768413 -427.736579)
			(xy 447.744741 -427.787076) (xy 447.713968 -427.833589) (xy 447.676751 -427.875126) (xy 447.633883 -427.910801)
			(xy 447.586277 -427.939855) (xy 447.534948 -427.961667) (xy 447.480991 -427.975773) (xy 447.425554 -427.981873)
			(xy 447.36982 -427.979836) (xy 447.314977 -427.969706) (xy 447.262193 -427.951699) (xy 447.212593 -427.926198)
			(xy 447.167235 -427.893747) (xy 447.127086 -427.855038) (xy 447.093 -427.810895) (xy 447.065704 -427.76226)
			(xy 447.045781 -427.710169) (xy 447.033655 -427.655732) (xy 447.029584 -427.60011) (xy 432.260756 -427.60011)
			(xy 432.260756 -428.325854) (xy 443.607365 -428.325854) (xy 443.607365 -428.271346) (xy 443.615123 -428.217392)
			(xy 443.630481 -428.165093) (xy 443.653126 -428.115511) (xy 443.682598 -428.069657) (xy 443.718295 -428.028464)
			(xy 443.759492 -427.992771) (xy 443.805349 -427.963305) (xy 443.854934 -427.940666) (xy 443.907236 -427.925314)
			(xy 443.96119 -427.917562) (xy 443.988444 -427.917102) (xy 444.017293 -427.917646) (xy 444.074335 -427.926313)
			(xy 444.129421 -427.943475) (xy 444.181293 -427.968738) (xy 444.228767 -428.001527) (xy 444.270761 -428.041093)
			(xy 444.306316 -428.086533) (xy 444.32093 -428.111412) (xy 444.3281 -428.123128) (xy 444.347478 -428.142576)
			(xy 444.371341 -428.156153) (xy 444.39796 -428.162874) (xy 444.425407 -428.162254) (xy 444.451695 -428.154337)
			(xy 444.47492 -428.139697) (xy 444.4934 -428.119393) (xy 444.5 -428.107348) (xy 444.512235 -428.084067)
			(xy 444.54219 -428.040838) (xy 444.577801 -428.002135) (xy 444.618393 -427.968693) (xy 444.663195 -427.941146)
			(xy 444.711358 -427.920018) (xy 444.761968 -427.905708) (xy 444.814063 -427.898489) (xy 444.84036 -427.898052)
			(xy 444.867612 -427.898593) (xy 444.921561 -427.906344) (xy 444.973859 -427.921695) (xy 445.023439 -427.944333)
			(xy 445.069292 -427.973797) (xy 445.110485 -428.009487) (xy 445.146179 -428.050676) (xy 445.175648 -428.096526)
			(xy 445.198291 -428.146104) (xy 445.213647 -428.198399) (xy 445.221405 -428.252348) (xy 445.221405 -428.306852)
			(xy 445.213647 -428.360801) (xy 445.198291 -428.413096) (xy 445.175648 -428.462674) (xy 445.146179 -428.508524)
			(xy 445.110485 -428.549713) (xy 445.069292 -428.585403) (xy 445.023439 -428.614867) (xy 444.973859 -428.637505)
			(xy 444.921561 -428.652856) (xy 444.867612 -428.660607) (xy 444.84036 -428.661068) (xy 444.811511 -428.660536)
			(xy 444.754467 -428.651868) (xy 444.69938 -428.634706) (xy 444.647508 -428.609441) (xy 444.600033 -428.57665)
			(xy 444.55804 -428.537081) (xy 444.522487 -428.491638) (xy 444.507874 -428.466758) (xy 444.500695 -428.45505)
			(xy 444.481316 -428.435607) (xy 444.457456 -428.422035) (xy 444.43084 -428.415316) (xy 444.403397 -428.415935)
			(xy 444.377112 -428.423849) (xy 444.353888 -428.438484) (xy 444.335406 -428.458781) (xy 444.328804 -428.470822)
			(xy 444.316553 -428.494094) (xy 444.286602 -428.537325) (xy 444.250993 -428.576029) (xy 444.210404 -428.609472)
			(xy 444.165604 -428.63702) (xy 444.117443 -428.65815) (xy 444.066835 -428.672461) (xy 444.01474 -428.679681)
			(xy 443.988444 -428.680118) (xy 443.96119 -428.679638) (xy 443.907236 -428.671886) (xy 443.854934 -428.656534)
			(xy 443.805349 -428.633895) (xy 443.759492 -428.604429) (xy 443.718295 -428.568736) (xy 443.682598 -428.527543)
			(xy 443.653126 -428.481689) (xy 443.630481 -428.432107) (xy 443.615123 -428.379808) (xy 443.607365 -428.325854)
			(xy 432.260756 -428.325854) (xy 432.260756 -429.658272) (xy 432.963826 -429.658272) (xy 432.967897 -429.60265)
			(xy 432.980023 -429.548213) (xy 432.999946 -429.496122) (xy 433.027242 -429.447487) (xy 433.061328 -429.403344)
			(xy 433.101477 -429.364635) (xy 433.146835 -429.332184) (xy 433.196435 -429.306683) (xy 433.249219 -429.288676)
			(xy 433.304062 -429.278546) (xy 433.359796 -429.276509) (xy 433.415233 -429.282609) (xy 433.46919 -429.296715)
			(xy 433.481415 -429.30191) (xy 439.529726 -429.30191) (xy 439.533797 -429.246288) (xy 439.545923 -429.191851)
			(xy 439.565846 -429.13976) (xy 439.593142 -429.091125) (xy 439.627228 -429.046982) (xy 439.667377 -429.008273)
			(xy 439.712735 -428.975822) (xy 439.762335 -428.950321) (xy 439.815119 -428.932314) (xy 439.869962 -428.922184)
			(xy 439.925696 -428.920147) (xy 439.981133 -428.926247) (xy 440.03509 -428.940353) (xy 440.086419 -428.962165)
			(xy 440.134025 -428.991219) (xy 440.176893 -429.026894) (xy 440.21411 -429.068431) (xy 440.244883 -429.114944)
			(xy 440.268555 -429.165441) (xy 440.284623 -429.218848) (xy 440.292743 -429.274024) (xy 440.293252 -429.30191)
			(xy 440.292743 -429.329796) (xy 440.284623 -429.384972) (xy 440.268555 -429.438379) (xy 440.244883 -429.488876)
			(xy 440.21411 -429.535389) (xy 440.176893 -429.576926) (xy 440.134025 -429.612601) (xy 440.086419 -429.641655)
			(xy 440.03509 -429.663467) (xy 439.981133 -429.677573) (xy 439.925696 -429.683673) (xy 439.869962 -429.681636)
			(xy 439.815119 -429.671506) (xy 439.762335 -429.653499) (xy 439.712735 -429.627998) (xy 439.667377 -429.595547)
			(xy 439.627228 -429.556838) (xy 439.593142 -429.512695) (xy 439.565846 -429.46406) (xy 439.545923 -429.411969)
			(xy 439.533797 -429.357532) (xy 439.529726 -429.30191) (xy 433.481415 -429.30191) (xy 433.520519 -429.318527)
			(xy 433.568125 -429.347581) (xy 433.610993 -429.383256) (xy 433.64821 -429.424793) (xy 433.678983 -429.471306)
			(xy 433.702655 -429.521803) (xy 433.718723 -429.57521) (xy 433.726843 -429.630386) (xy 433.727352 -429.658272)
			(xy 433.726843 -429.686158) (xy 433.718723 -429.741334) (xy 433.702655 -429.794741) (xy 433.678983 -429.845238)
			(xy 433.64821 -429.891751) (xy 433.610993 -429.933288) (xy 433.609388 -429.934624) (xy 437.875424 -429.934624)
			(xy 437.879495 -429.879002) (xy 437.891621 -429.824565) (xy 437.911544 -429.772474) (xy 437.93884 -429.723839)
			(xy 437.972926 -429.679696) (xy 438.013075 -429.640987) (xy 438.058433 -429.608536) (xy 438.108033 -429.583035)
			(xy 438.160817 -429.565028) (xy 438.21566 -429.554898) (xy 438.271394 -429.552861) (xy 438.326831 -429.558961)
			(xy 438.380788 -429.573067) (xy 438.432117 -429.594879) (xy 438.479723 -429.623933) (xy 438.522591 -429.659608)
			(xy 438.559808 -429.701145) (xy 438.590581 -429.747658) (xy 438.614253 -429.798155) (xy 438.630321 -429.851562)
			(xy 438.638441 -429.906738) (xy 438.63895 -429.934624) (xy 438.638441 -429.96251) (xy 438.631331 -430.010824)
			(xy 449.461634 -430.010824) (xy 449.465705 -429.955202) (xy 449.477831 -429.900765) (xy 449.497754 -429.848674)
			(xy 449.52505 -429.800039) (xy 449.559136 -429.755896) (xy 449.599285 -429.717187) (xy 449.644643 -429.684736)
			(xy 449.694243 -429.659235) (xy 449.747027 -429.641228) (xy 449.80187 -429.631098) (xy 449.857604 -429.629061)
			(xy 449.913041 -429.635161) (xy 449.966998 -429.649267) (xy 450.018327 -429.671079) (xy 450.065933 -429.700133)
			(xy 450.108801 -429.735808) (xy 450.146018 -429.777345) (xy 450.176791 -429.823858) (xy 450.200463 -429.874355)
			(xy 450.216531 -429.927762) (xy 450.224651 -429.982938) (xy 450.22516 -430.010824) (xy 450.224651 -430.03871)
			(xy 450.216531 -430.093886) (xy 450.200463 -430.147293) (xy 450.176791 -430.19779) (xy 450.146018 -430.244303)
			(xy 450.108801 -430.28584) (xy 450.065933 -430.321515) (xy 450.018327 -430.350569) (xy 449.966998 -430.372381)
			(xy 449.913041 -430.386487) (xy 449.857604 -430.392587) (xy 449.80187 -430.39055) (xy 449.747027 -430.38042)
			(xy 449.694243 -430.362413) (xy 449.644643 -430.336912) (xy 449.599285 -430.304461) (xy 449.559136 -430.265752)
			(xy 449.52505 -430.221609) (xy 449.497754 -430.172974) (xy 449.477831 -430.120883) (xy 449.465705 -430.066446)
			(xy 449.461634 -430.010824) (xy 438.631331 -430.010824) (xy 438.630321 -430.017686) (xy 438.614253 -430.071093)
			(xy 438.590581 -430.12159) (xy 438.559808 -430.168103) (xy 438.522591 -430.20964) (xy 438.479723 -430.245315)
			(xy 438.432117 -430.274369) (xy 438.380788 -430.296181) (xy 438.326831 -430.310287) (xy 438.271394 -430.316387)
			(xy 438.21566 -430.31435) (xy 438.160817 -430.30422) (xy 438.108033 -430.286213) (xy 438.058433 -430.260712)
			(xy 438.013075 -430.228261) (xy 437.972926 -430.189552) (xy 437.93884 -430.145409) (xy 437.911544 -430.096774)
			(xy 437.891621 -430.044683) (xy 437.879495 -429.990246) (xy 437.875424 -429.934624) (xy 433.609388 -429.934624)
			(xy 433.568125 -429.968963) (xy 433.520519 -429.998017) (xy 433.46919 -430.019829) (xy 433.415233 -430.033935)
			(xy 433.359796 -430.040035) (xy 433.304062 -430.037998) (xy 433.249219 -430.027868) (xy 433.196435 -430.009861)
			(xy 433.146835 -429.98436) (xy 433.101477 -429.951909) (xy 433.061328 -429.9132) (xy 433.027242 -429.869057)
			(xy 432.999946 -429.820422) (xy 432.980023 -429.768331) (xy 432.967897 -429.713894) (xy 432.963826 -429.658272)
			(xy 432.260756 -429.658272) (xy 432.260756 -430.36744) (xy 432.261382 -430.379283) (xy 432.2688 -430.39411)
			(xy 440.425584 -430.39411) (xy 440.429655 -430.338488) (xy 440.441781 -430.284051) (xy 440.461704 -430.23196)
			(xy 440.489 -430.183325) (xy 440.523086 -430.139182) (xy 440.563235 -430.100473) (xy 440.608593 -430.068022)
			(xy 440.658193 -430.042521) (xy 440.710977 -430.024514) (xy 440.76582 -430.014384) (xy 440.821554 -430.012347)
			(xy 440.876991 -430.018447) (xy 440.930948 -430.032553) (xy 440.982277 -430.054365) (xy 441.029883 -430.083419)
			(xy 441.072751 -430.119094) (xy 441.109968 -430.160631) (xy 441.140741 -430.207144) (xy 441.164413 -430.257641)
			(xy 441.180481 -430.311048) (xy 441.188601 -430.366224) (xy 441.18911 -430.39411) (xy 441.188601 -430.421996)
			(xy 441.180481 -430.477172) (xy 441.164413 -430.530579) (xy 441.140741 -430.581076) (xy 441.109968 -430.627589)
			(xy 441.072751 -430.669126) (xy 441.029883 -430.704801) (xy 440.982277 -430.733855) (xy 440.930948 -430.755667)
			(xy 440.876991 -430.769773) (xy 440.821554 -430.775873) (xy 440.76582 -430.773836) (xy 440.710977 -430.763706)
			(xy 440.658193 -430.745699) (xy 440.608593 -430.720198) (xy 440.563235 -430.687747) (xy 440.523086 -430.649038)
			(xy 440.489 -430.604895) (xy 440.461704 -430.55626) (xy 440.441781 -430.504169) (xy 440.429655 -430.449732)
			(xy 440.425584 -430.39411) (xy 432.2688 -430.39411) (xy 432.271981 -430.400467) (xy 432.281076 -430.40808)
			(xy 432.346354 -430.456848) (xy 432.356083 -430.463388) (xy 432.379095 -430.467732) (xy 432.39055 -430.46523)
			(xy 432.391058 -430.464976) (xy 432.391312 -430.464976) (xy 432.417521 -430.457763) (xy 432.471321 -430.449985)
			(xy 432.4985 -430.449482) (xy 432.525752 -430.449968) (xy 432.579701 -430.457725) (xy 432.631997 -430.47308)
			(xy 432.681576 -430.495722) (xy 432.727427 -430.525189) (xy 432.768619 -430.560881) (xy 432.804311 -430.602073)
			(xy 432.833778 -430.647924) (xy 432.85642 -430.697503) (xy 432.871775 -430.749799) (xy 432.879532 -430.803748)
			(xy 432.879532 -430.858252) (xy 432.871775 -430.912201) (xy 432.85642 -430.964497) (xy 432.833778 -431.014076)
			(xy 432.804311 -431.059927) (xy 432.768619 -431.101119) (xy 432.727427 -431.136811) (xy 432.681576 -431.166278)
			(xy 432.631997 -431.18892) (xy 432.579701 -431.204275) (xy 432.525752 -431.212032) (xy 432.4985 -431.212498)
			(xy 432.471322 -431.211979) (xy 432.417525 -431.204201) (xy 432.391312 -431.197004) (xy 432.391058 -431.197004)
			(xy 432.39055 -431.19675) (xy 432.379101 -431.19416) (xy 432.35607 -431.198543) (xy 432.346354 -431.205132)
			(xy 432.281076 -431.2539) (xy 432.271984 -431.261509) (xy 432.261414 -431.282699) (xy 432.260756 -431.29454)
			(xy 432.260756 -433.451508) (xy 434.049422 -433.451508) (xy 434.053493 -433.395886) (xy 434.065619 -433.341449)
			(xy 434.085542 -433.289358) (xy 434.112838 -433.240723) (xy 434.146924 -433.19658) (xy 434.187073 -433.157871)
			(xy 434.232431 -433.12542) (xy 434.282031 -433.099919) (xy 434.334815 -433.081912) (xy 434.389658 -433.071782)
			(xy 434.445392 -433.069745) (xy 434.500829 -433.075845) (xy 434.554786 -433.089951) (xy 434.606115 -433.111763)
			(xy 434.653721 -433.140817) (xy 434.696589 -433.176492) (xy 434.733806 -433.218029) (xy 434.764579 -433.264542)
			(xy 434.788251 -433.315039) (xy 434.804319 -433.368446) (xy 434.812439 -433.423622) (xy 434.812948 -433.451508)
			(xy 434.812439 -433.479394) (xy 434.80469 -433.532047) (xy 436.291026 -433.532047) (xy 436.291026 -433.477553)
			(xy 436.298781 -433.423615) (xy 436.314133 -433.371329) (xy 436.336769 -433.32176) (xy 436.366229 -433.275916)
			(xy 436.401913 -433.234732) (xy 436.443095 -433.199045) (xy 436.488937 -433.169582) (xy 436.538504 -433.146942)
			(xy 436.590789 -433.131586) (xy 436.644727 -433.123828) (xy 436.671974 -433.12334) (xy 436.700771 -433.123876)
			(xy 436.757713 -433.132512) (xy 436.812716 -433.149594) (xy 436.838852 -433.161694) (xy 436.851879 -433.167588)
			(xy 436.880028 -433.172549) (xy 436.908449 -433.169513) (xy 436.934916 -433.158718) (xy 436.957353 -433.141011)
			(xy 436.974003 -433.117778) (xy 436.983562 -433.090841) (xy 436.984902 -433.076604) (xy 436.987183 -433.047844)
			(xy 436.999207 -432.991423) (xy 437.019594 -432.937457) (xy 437.047877 -432.887178) (xy 437.083412 -432.841733)
			(xy 437.125387 -432.80216) (xy 437.172844 -432.769362) (xy 437.224701 -432.744086) (xy 437.279773 -432.726911)
			(xy 437.336804 -432.718228) (xy 437.365648 -432.717702) (xy 437.392898 -432.718171) (xy 437.446842 -432.725933)
			(xy 437.499132 -432.741293) (xy 437.548705 -432.763938) (xy 437.59455 -432.793406) (xy 437.635736 -432.829098)
			(xy 437.671423 -432.870288) (xy 437.700886 -432.916138) (xy 437.723524 -432.965713) (xy 437.738877 -433.018005)
			(xy 437.746632 -433.07195) (xy 437.746632 -433.12645) (xy 437.738877 -433.180395) (xy 437.723524 -433.232687)
			(xy 437.700886 -433.282262) (xy 437.671423 -433.328112) (xy 437.635736 -433.369302) (xy 437.59455 -433.404994)
			(xy 437.548705 -433.434462) (xy 437.499132 -433.457107) (xy 437.446842 -433.472467) (xy 437.392898 -433.480229)
			(xy 437.365648 -433.480718) (xy 437.33685 -433.480215) (xy 437.279906 -433.471565) (xy 437.224905 -433.454471)
			(xy 437.19877 -433.442364) (xy 437.185719 -433.436532) (xy 437.157582 -433.431571) (xy 437.129171 -433.434602)
			(xy 437.102714 -433.445388) (xy 437.080281 -433.463082) (xy 437.06363 -433.486301) (xy 437.054066 -433.513224)
			(xy 437.05272 -433.527454) (xy 437.050467 -433.556216) (xy 437.038436 -433.612636) (xy 437.018043 -433.666601)
			(xy 436.989755 -433.716878) (xy 436.954217 -433.762321) (xy 436.912239 -433.801893) (xy 436.86478 -433.834691)
			(xy 436.812923 -433.859967) (xy 436.75785 -433.877143) (xy 436.700819 -433.885828) (xy 436.671974 -433.886356)
			(xy 436.644727 -433.885772) (xy 436.590789 -433.878014) (xy 436.538504 -433.862658) (xy 436.488937 -433.840018)
			(xy 436.443095 -433.810555) (xy 436.401913 -433.774868) (xy 436.366229 -433.733684) (xy 436.336769 -433.68784)
			(xy 436.314133 -433.638271) (xy 436.298781 -433.585985) (xy 436.291026 -433.532047) (xy 434.80469 -433.532047)
			(xy 434.804319 -433.53457) (xy 434.788251 -433.587977) (xy 434.764579 -433.638474) (xy 434.733806 -433.684987)
			(xy 434.696589 -433.726524) (xy 434.653721 -433.762199) (xy 434.606115 -433.791253) (xy 434.554786 -433.813065)
			(xy 434.500829 -433.827171) (xy 434.445392 -433.833271) (xy 434.389658 -433.831234) (xy 434.334815 -433.821104)
			(xy 434.282031 -433.803097) (xy 434.232431 -433.777596) (xy 434.187073 -433.745145) (xy 434.146924 -433.706436)
			(xy 434.112838 -433.662293) (xy 434.085542 -433.613658) (xy 434.065619 -433.561567) (xy 434.053493 -433.50713)
			(xy 434.049422 -433.451508) (xy 432.260756 -433.451508) (xy 432.260756 -433.89931) (xy 439.609736 -433.89931)
			(xy 439.613807 -433.843688) (xy 439.625933 -433.789251) (xy 439.645856 -433.73716) (xy 439.673152 -433.688525)
			(xy 439.707238 -433.644382) (xy 439.747387 -433.605673) (xy 439.792745 -433.573222) (xy 439.842345 -433.547721)
			(xy 439.895129 -433.529714) (xy 439.949972 -433.519584) (xy 440.005706 -433.517547) (xy 440.061143 -433.523647)
			(xy 440.1151 -433.537753) (xy 440.166429 -433.559565) (xy 440.214035 -433.588619) (xy 440.256903 -433.624294)
			(xy 440.29412 -433.665831) (xy 440.314657 -433.696872) (xy 444.214502 -433.696872) (xy 444.218573 -433.64125)
			(xy 444.230699 -433.586813) (xy 444.250622 -433.534722) (xy 444.277918 -433.486087) (xy 444.312004 -433.441944)
			(xy 444.352153 -433.403235) (xy 444.397511 -433.370784) (xy 444.447111 -433.345283) (xy 444.499895 -433.327276)
			(xy 444.554738 -433.317146) (xy 444.610472 -433.315109) (xy 444.665909 -433.321209) (xy 444.719866 -433.335315)
			(xy 444.771195 -433.357127) (xy 444.818801 -433.386181) (xy 444.861669 -433.421856) (xy 444.898886 -433.463393)
			(xy 444.929659 -433.509906) (xy 444.953331 -433.560403) (xy 444.969399 -433.61381) (xy 444.977519 -433.668986)
			(xy 444.978028 -433.696872) (xy 444.977519 -433.724758) (xy 444.969399 -433.779934) (xy 444.953331 -433.833341)
			(xy 444.929659 -433.883838) (xy 444.898886 -433.930351) (xy 444.861669 -433.971888) (xy 444.818801 -434.007563)
			(xy 444.771195 -434.036617) (xy 444.719866 -434.058429) (xy 444.665909 -434.072535) (xy 444.610472 -434.078635)
			(xy 444.554738 -434.076598) (xy 444.499895 -434.066468) (xy 444.447111 -434.048461) (xy 444.397511 -434.02296)
			(xy 444.352153 -433.990509) (xy 444.312004 -433.9518) (xy 444.277918 -433.907657) (xy 444.250622 -433.859022)
			(xy 444.230699 -433.806931) (xy 444.218573 -433.752494) (xy 444.214502 -433.696872) (xy 440.314657 -433.696872)
			(xy 440.324893 -433.712344) (xy 440.348565 -433.762841) (xy 440.364633 -433.816248) (xy 440.372753 -433.871424)
			(xy 440.373262 -433.89931) (xy 440.372753 -433.927196) (xy 440.364633 -433.982372) (xy 440.348565 -434.035779)
			(xy 440.324893 -434.086276) (xy 440.29412 -434.132789) (xy 440.256903 -434.174326) (xy 440.214035 -434.210001)
			(xy 440.166429 -434.239055) (xy 440.1151 -434.260867) (xy 440.061143 -434.274973) (xy 440.005706 -434.281073)
			(xy 439.949972 -434.279036) (xy 439.895129 -434.268906) (xy 439.842345 -434.250899) (xy 439.792745 -434.225398)
			(xy 439.747387 -434.192947) (xy 439.707238 -434.154238) (xy 439.673152 -434.110095) (xy 439.645856 -434.06146)
			(xy 439.625933 -434.009369) (xy 439.613807 -433.954932) (xy 439.609736 -433.89931) (xy 432.260756 -433.89931)
			(xy 432.260756 -434.87721) (xy 436.79567 -434.87721) (xy 436.799741 -434.821588) (xy 436.811867 -434.767151)
			(xy 436.83179 -434.71506) (xy 436.859086 -434.666425) (xy 436.893172 -434.622282) (xy 436.933321 -434.583573)
			(xy 436.978679 -434.551122) (xy 437.028279 -434.525621) (xy 437.081063 -434.507614) (xy 437.135906 -434.497484)
			(xy 437.19164 -434.495447) (xy 437.247077 -434.501547) (xy 437.301034 -434.515653) (xy 437.352363 -434.537465)
			(xy 437.371749 -434.549296) (xy 443.386462 -434.549296) (xy 443.390533 -434.493674) (xy 443.402659 -434.439237)
			(xy 443.422582 -434.387146) (xy 443.449878 -434.338511) (xy 443.483964 -434.294368) (xy 443.524113 -434.255659)
			(xy 443.569471 -434.223208) (xy 443.619071 -434.197707) (xy 443.671855 -434.1797) (xy 443.726698 -434.16957)
			(xy 443.782432 -434.167533) (xy 443.837869 -434.173633) (xy 443.891826 -434.187739) (xy 443.943155 -434.209551)
			(xy 443.990761 -434.238605) (xy 444.033629 -434.27428) (xy 444.070846 -434.315817) (xy 444.101619 -434.36233)
			(xy 444.125291 -434.412827) (xy 444.141359 -434.466234) (xy 444.149479 -434.52141) (xy 444.149988 -434.549296)
			(xy 444.149479 -434.577182) (xy 444.141359 -434.632358) (xy 444.125291 -434.685765) (xy 444.101619 -434.736262)
			(xy 444.070846 -434.782775) (xy 444.033629 -434.824312) (xy 443.990761 -434.859987) (xy 443.943155 -434.889041)
			(xy 443.891826 -434.910853) (xy 443.837869 -434.924959) (xy 443.782432 -434.931059) (xy 443.726698 -434.929022)
			(xy 443.671855 -434.918892) (xy 443.619071 -434.900885) (xy 443.569471 -434.875384) (xy 443.524113 -434.842933)
			(xy 443.483964 -434.804224) (xy 443.449878 -434.760081) (xy 443.422582 -434.711446) (xy 443.402659 -434.659355)
			(xy 443.390533 -434.604918) (xy 443.386462 -434.549296) (xy 437.371749 -434.549296) (xy 437.399969 -434.566519)
			(xy 437.442837 -434.602194) (xy 437.480054 -434.643731) (xy 437.510827 -434.690244) (xy 437.534499 -434.740741)
			(xy 437.550567 -434.794148) (xy 437.558687 -434.849324) (xy 437.559196 -434.87721) (xy 437.558687 -434.905096)
			(xy 437.550567 -434.960272) (xy 437.534499 -435.013679) (xy 437.510827 -435.064176) (xy 437.480054 -435.110689)
			(xy 437.442837 -435.152226) (xy 437.399969 -435.187901) (xy 437.352363 -435.216955) (xy 437.301034 -435.238767)
			(xy 437.247077 -435.252873) (xy 437.19164 -435.258973) (xy 437.135906 -435.256936) (xy 437.081063 -435.246806)
			(xy 437.028279 -435.228799) (xy 436.978679 -435.203298) (xy 436.933321 -435.170847) (xy 436.893172 -435.132138)
			(xy 436.859086 -435.087995) (xy 436.83179 -435.03936) (xy 436.811867 -434.987269) (xy 436.799741 -434.932832)
			(xy 436.79567 -434.87721) (xy 432.260756 -434.87721) (xy 432.260756 -435.67731) (xy 439.3217 -435.67731)
			(xy 439.325771 -435.621688) (xy 439.337897 -435.567251) (xy 439.35782 -435.51516) (xy 439.385116 -435.466525)
			(xy 439.419202 -435.422382) (xy 439.459351 -435.383673) (xy 439.504709 -435.351222) (xy 439.554309 -435.325721)
			(xy 439.607093 -435.307714) (xy 439.661936 -435.297584) (xy 439.71767 -435.295547) (xy 439.773107 -435.301647)
			(xy 439.827064 -435.315753) (xy 439.878393 -435.337565) (xy 439.925999 -435.366619) (xy 439.968867 -435.402294)
			(xy 440.006084 -435.443831) (xy 440.036857 -435.490344) (xy 440.060529 -435.540841) (xy 440.076597 -435.594248)
			(xy 440.084717 -435.649424) (xy 440.085226 -435.67731) (xy 440.084717 -435.705196) (xy 440.076597 -435.760372)
			(xy 440.060529 -435.813779) (xy 440.036857 -435.864276) (xy 440.034015 -435.868572) (xy 442.751462 -435.868572)
			(xy 442.755533 -435.81295) (xy 442.767659 -435.758513) (xy 442.787582 -435.706422) (xy 442.814878 -435.657787)
			(xy 442.848964 -435.613644) (xy 442.889113 -435.574935) (xy 442.934471 -435.542484) (xy 442.984071 -435.516983)
			(xy 443.036855 -435.498976) (xy 443.091698 -435.488846) (xy 443.147432 -435.486809) (xy 443.202869 -435.492909)
			(xy 443.256826 -435.507015) (xy 443.308155 -435.528827) (xy 443.355761 -435.557881) (xy 443.398629 -435.593556)
			(xy 443.435846 -435.635093) (xy 443.463648 -435.677116) (xy 445.799708 -435.677116) (xy 445.799708 -435.522564)
			(xy 445.807664 -435.368217) (xy 445.823555 -435.214484) (xy 445.847339 -435.061773) (xy 445.878953 -434.910489)
			(xy 445.918313 -434.761033) (xy 445.965314 -434.613801) (xy 446.019833 -434.469184) (xy 446.081724 -434.327565)
			(xy 446.150823 -434.189321) (xy 446.226947 -434.054816) (xy 446.309895 -433.924409) (xy 446.399446 -433.798445)
			(xy 446.495362 -433.677257) (xy 446.59739 -433.561169) (xy 446.705259 -433.450486) (xy 446.818682 -433.345503)
			(xy 446.93736 -433.246498) (xy 447.060976 -433.153733) (xy 447.189205 -433.067456) (xy 447.321704 -432.987893)
			(xy 447.458124 -432.915258) (xy 447.598102 -432.849741) (xy 447.741268 -432.791517) (xy 447.88724 -432.74074)
			(xy 448.035633 -432.697545) (xy 448.186053 -432.662046) (xy 448.338101 -432.634338) (xy 448.491374 -432.614494)
			(xy 448.645465 -432.602566) (xy 448.799966 -432.598587) (xy 448.954467 -432.602566) (xy 449.108558 -432.614494)
			(xy 449.261831 -432.634338) (xy 449.413879 -432.662046) (xy 449.564299 -432.697545) (xy 449.712692 -432.74074)
			(xy 449.858664 -432.791517) (xy 450.00183 -432.849741) (xy 450.141808 -432.915258) (xy 450.278228 -432.987893)
			(xy 450.410727 -433.067456) (xy 450.538956 -433.153733) (xy 450.662572 -433.246498) (xy 450.78125 -433.345503)
			(xy 450.894673 -433.450486) (xy 451.002542 -433.561169) (xy 451.10457 -433.677257) (xy 451.200486 -433.798445)
			(xy 451.290037 -433.924409) (xy 451.372985 -434.054816) (xy 451.449109 -434.189321) (xy 451.518208 -434.327565)
			(xy 451.580099 -434.469184) (xy 451.634618 -434.613801) (xy 451.681619 -434.761033) (xy 451.720979 -434.910489)
			(xy 451.752593 -435.061773) (xy 451.776377 -435.214484) (xy 451.792268 -435.368217) (xy 451.800224 -435.522564)
			(xy 451.800722 -435.59984) (xy 451.800224 -435.677116) (xy 451.792268 -435.831463) (xy 451.776377 -435.985196)
			(xy 451.752593 -436.137907) (xy 451.720979 -436.289191) (xy 451.681619 -436.438647) (xy 451.634618 -436.585879)
			(xy 451.580099 -436.730496) (xy 451.518208 -436.872115) (xy 451.449109 -437.010359) (xy 451.372985 -437.144864)
			(xy 451.290037 -437.275271) (xy 451.200486 -437.401235) (xy 451.10457 -437.522423) (xy 451.002542 -437.638511)
			(xy 450.894673 -437.749194) (xy 450.78125 -437.854177) (xy 450.662572 -437.953182) (xy 450.538956 -438.045947)
			(xy 450.410727 -438.132224) (xy 450.278228 -438.211787) (xy 450.141808 -438.284422) (xy 450.00183 -438.349939)
			(xy 449.858664 -438.408163) (xy 449.712692 -438.45894) (xy 449.564299 -438.502135) (xy 449.413879 -438.537634)
			(xy 449.261831 -438.565342) (xy 449.108558 -438.585186) (xy 448.954467 -438.597114) (xy 448.799966 -438.601094)
			(xy 448.645465 -438.597114) (xy 448.491374 -438.585186) (xy 448.338101 -438.565342) (xy 448.186053 -438.537634)
			(xy 448.035633 -438.502135) (xy 447.88724 -438.45894) (xy 447.741268 -438.408163) (xy 447.598102 -438.349939)
			(xy 447.458124 -438.284422) (xy 447.321704 -438.211787) (xy 447.189205 -438.132224) (xy 447.060976 -438.045947)
			(xy 446.93736 -437.953182) (xy 446.818682 -437.854177) (xy 446.705259 -437.749194) (xy 446.59739 -437.638511)
			(xy 446.495362 -437.522423) (xy 446.399446 -437.401235) (xy 446.309895 -437.275271) (xy 446.226947 -437.144864)
			(xy 446.150823 -437.010359) (xy 446.081724 -436.872115) (xy 446.019833 -436.730496) (xy 445.965314 -436.585879)
			(xy 445.918313 -436.438647) (xy 445.878953 -436.289191) (xy 445.847339 -436.137907) (xy 445.823555 -435.985196)
			(xy 445.807664 -435.831463) (xy 445.799708 -435.677116) (xy 443.463648 -435.677116) (xy 443.466619 -435.681606)
			(xy 443.490291 -435.732103) (xy 443.506359 -435.78551) (xy 443.514479 -435.840686) (xy 443.514988 -435.868572)
			(xy 443.514479 -435.896458) (xy 443.506359 -435.951634) (xy 443.490291 -436.005041) (xy 443.466619 -436.055538)
			(xy 443.435846 -436.102051) (xy 443.398629 -436.143588) (xy 443.355761 -436.179263) (xy 443.308155 -436.208317)
			(xy 443.256826 -436.230129) (xy 443.202869 -436.244235) (xy 443.147432 -436.250335) (xy 443.091698 -436.248298)
			(xy 443.036855 -436.238168) (xy 442.984071 -436.220161) (xy 442.934471 -436.19466) (xy 442.889113 -436.162209)
			(xy 442.848964 -436.1235) (xy 442.814878 -436.079357) (xy 442.787582 -436.030722) (xy 442.767659 -435.978631)
			(xy 442.755533 -435.924194) (xy 442.751462 -435.868572) (xy 440.034015 -435.868572) (xy 440.006084 -435.910789)
			(xy 439.968867 -435.952326) (xy 439.925999 -435.988001) (xy 439.878393 -436.017055) (xy 439.827064 -436.038867)
			(xy 439.773107 -436.052973) (xy 439.71767 -436.059073) (xy 439.661936 -436.057036) (xy 439.607093 -436.046906)
			(xy 439.554309 -436.028899) (xy 439.504709 -436.003398) (xy 439.459351 -435.970947) (xy 439.419202 -435.932238)
			(xy 439.385116 -435.888095) (xy 439.35782 -435.83946) (xy 439.337897 -435.787369) (xy 439.325771 -435.732932)
			(xy 439.3217 -435.67731) (xy 432.260756 -435.67731) (xy 432.260756 -435.879748) (xy 432.26092 -435.886107)
			(xy 432.264002 -435.898445) (xy 432.266852 -435.904132) (xy 432.279471 -435.928256) (xy 432.298497 -435.979264)
			(xy 432.310072 -436.032461) (xy 432.31396 -436.086763) (xy 432.310082 -436.141066) (xy 432.298518 -436.194265)
			(xy 432.279502 -436.245277) (xy 432.266852 -436.269384) (xy 432.264008 -436.275073) (xy 432.26093 -436.28741)
			(xy 432.260756 -436.293768) (xy 432.260756 -436.412132) (xy 443.985902 -436.412132) (xy 443.989973 -436.35651)
			(xy 444.002099 -436.302073) (xy 444.022022 -436.249982) (xy 444.049318 -436.201347) (xy 444.083404 -436.157204)
			(xy 444.123553 -436.118495) (xy 444.168911 -436.086044) (xy 444.218511 -436.060543) (xy 444.271295 -436.042536)
			(xy 444.326138 -436.032406) (xy 444.381872 -436.030369) (xy 444.437309 -436.036469) (xy 444.491266 -436.050575)
			(xy 444.542595 -436.072387) (xy 444.590201 -436.101441) (xy 444.633069 -436.137116) (xy 444.670286 -436.178653)
			(xy 444.701059 -436.225166) (xy 444.724731 -436.275663) (xy 444.740799 -436.32907) (xy 444.748919 -436.384246)
			(xy 444.749428 -436.412132) (xy 444.748919 -436.440018) (xy 444.740799 -436.495194) (xy 444.724731 -436.548601)
			(xy 444.701059 -436.599098) (xy 444.670286 -436.645611) (xy 444.633069 -436.687148) (xy 444.590201 -436.722823)
			(xy 444.542595 -436.751877) (xy 444.491266 -436.773689) (xy 444.437309 -436.787795) (xy 444.381872 -436.793895)
			(xy 444.326138 -436.791858) (xy 444.271295 -436.781728) (xy 444.218511 -436.763721) (xy 444.168911 -436.73822)
			(xy 444.123553 -436.705769) (xy 444.083404 -436.66706) (xy 444.049318 -436.622917) (xy 444.022022 -436.574282)
			(xy 444.002099 -436.522191) (xy 443.989973 -436.467754) (xy 443.985902 -436.412132) (xy 432.260756 -436.412132)
			(xy 432.260756 -437.295849) (xy 436.282598 -437.295849) (xy 436.282598 -437.241351) (xy 436.290354 -437.187406)
			(xy 436.305708 -437.135115) (xy 436.328347 -437.085541) (xy 436.357811 -437.039694) (xy 436.3935 -436.998506)
			(xy 436.434687 -436.962816) (xy 436.480534 -436.933351) (xy 436.530108 -436.910711) (xy 436.582399 -436.895356)
			(xy 436.636343 -436.887599) (xy 436.663592 -436.887112) (xy 436.693578 -436.887697) (xy 436.752813 -436.897077)
			(xy 436.80985 -436.915609) (xy 436.863287 -436.942836) (xy 436.887874 -436.96001) (xy 436.900244 -436.96847)
			(xy 436.928519 -436.978373) (xy 436.95845 -436.979651) (xy 436.987467 -436.972197) (xy 437.013075 -436.956649)
			(xy 437.033075 -436.934344) (xy 437.045749 -436.907198) (xy 437.048402 -436.892446) (xy 437.052819 -436.865583)
			(xy 437.068205 -436.813364) (xy 437.090861 -436.763864) (xy 437.120327 -436.71809) (xy 437.156003 -436.676971)
			(xy 437.197165 -436.641345) (xy 437.242976 -436.611936) (xy 437.292503 -436.589341) (xy 437.344741 -436.574019)
			(xy 437.398627 -436.566283) (xy 437.425846 -436.565802) (xy 437.453096 -436.566271) (xy 437.50704 -436.574033)
			(xy 437.559331 -436.589392) (xy 437.608903 -436.612037) (xy 437.654749 -436.641505) (xy 437.695935 -436.677198)
			(xy 437.731622 -436.718388) (xy 437.761085 -436.764237) (xy 437.783724 -436.813813) (xy 437.799077 -436.866105)
			(xy 437.806832 -436.92005) (xy 437.806832 -436.97455) (xy 437.799077 -437.028495) (xy 437.783724 -437.080787)
			(xy 437.761085 -437.130363) (xy 437.731622 -437.176212) (xy 437.695935 -437.217402) (xy 437.654749 -437.253095)
			(xy 437.608903 -437.282563) (xy 437.559331 -437.305208) (xy 437.50704 -437.320567) (xy 437.453096 -437.328329)
			(xy 437.425846 -437.328818) (xy 437.395861 -437.328229) (xy 437.336631 -437.31884) (xy 437.279598 -437.300302)
			(xy 437.226167 -437.273071) (xy 437.201564 -437.25592) (xy 437.189139 -437.247552) (xy 437.160883 -437.237656)
			(xy 437.130972 -437.236374) (xy 437.101974 -437.243816) (xy 437.076377 -437.259344) (xy 437.056379 -437.281624)
			(xy 437.043698 -437.308744) (xy 437.041036 -437.323484) (xy 437.036702 -437.350363) (xy 437.021309 -437.402586)
			(xy 436.998644 -437.45209) (xy 436.969169 -437.497866) (xy 436.933483 -437.538985) (xy 436.892312 -437.57461)
			(xy 436.846491 -437.604016) (xy 436.796955 -437.626607) (xy 436.744708 -437.641922) (xy 436.690815 -437.649651)
			(xy 436.663592 -437.650128) (xy 436.636343 -437.649601) (xy 436.582399 -437.641844) (xy 436.530108 -437.626489)
			(xy 436.480534 -437.603849) (xy 436.434687 -437.574384) (xy 436.3935 -437.538694) (xy 436.357811 -437.497506)
			(xy 436.328347 -437.451659) (xy 436.305708 -437.402085) (xy 436.290354 -437.349794) (xy 436.282598 -437.295849)
			(xy 432.260756 -437.295849) (xy 432.260756 -438.627266) (xy 432.261193 -438.63733) (xy 432.26893 -438.655911)
			(xy 432.275742 -438.663334) (xy 432.337718 -438.72531) (xy 436.299354 -438.72531) (xy 436.303425 -438.669688)
			(xy 436.315551 -438.615251) (xy 436.335474 -438.56316) (xy 436.36277 -438.514525) (xy 436.396856 -438.470382)
			(xy 436.437005 -438.431673) (xy 436.482363 -438.399222) (xy 436.531963 -438.373721) (xy 436.584747 -438.355714)
			(xy 436.63959 -438.345584) (xy 436.695324 -438.343547) (xy 436.750761 -438.349647) (xy 436.804718 -438.363753)
			(xy 436.856047 -438.385565) (xy 436.903653 -438.414619) (xy 436.946521 -438.450294) (xy 436.983738 -438.491831)
			(xy 437.014511 -438.538344) (xy 437.038183 -438.588841) (xy 437.054251 -438.642248) (xy 437.062371 -438.697424)
			(xy 437.06288 -438.72531) (xy 437.062371 -438.753196) (xy 437.054251 -438.808372) (xy 437.038183 -438.861779)
			(xy 437.014511 -438.912276) (xy 436.983738 -438.958789) (xy 436.946521 -439.000326) (xy 436.903653 -439.036001)
			(xy 436.856047 -439.065055) (xy 436.804718 -439.086867) (xy 436.750761 -439.100973) (xy 436.695324 -439.107073)
			(xy 436.63959 -439.105036) (xy 436.584747 -439.094906) (xy 436.531963 -439.076899) (xy 436.482363 -439.051398)
			(xy 436.437005 -439.018947) (xy 436.396856 -438.980238) (xy 436.36277 -438.936095) (xy 436.335474 -438.88746)
			(xy 436.315551 -438.835369) (xy 436.303425 -438.780932) (xy 436.299354 -438.72531) (xy 432.337718 -438.72531)
			(xy 432.944524 -439.332116) (xy 434.016402 -439.332116) (xy 434.020473 -439.276494) (xy 434.032599 -439.222057)
			(xy 434.052522 -439.169966) (xy 434.079818 -439.121331) (xy 434.113904 -439.077188) (xy 434.154053 -439.038479)
			(xy 434.199411 -439.006028) (xy 434.249011 -438.980527) (xy 434.301795 -438.96252) (xy 434.356638 -438.95239)
			(xy 434.412372 -438.950353) (xy 434.467809 -438.956453) (xy 434.521766 -438.970559) (xy 434.573095 -438.992371)
			(xy 434.620701 -439.021425) (xy 434.663569 -439.0571) (xy 434.700786 -439.098637) (xy 434.731559 -439.14515)
			(xy 434.755231 -439.195647) (xy 434.771299 -439.249054) (xy 434.779419 -439.30423) (xy 434.779928 -439.332116)
			(xy 434.779419 -439.360002) (xy 434.771299 -439.415178) (xy 434.755231 -439.468585) (xy 434.731559 -439.519082)
			(xy 434.727372 -439.52541) (xy 439.3217 -439.52541) (xy 439.325771 -439.469788) (xy 439.337897 -439.415351)
			(xy 439.35782 -439.36326) (xy 439.385116 -439.314625) (xy 439.419202 -439.270482) (xy 439.459351 -439.231773)
			(xy 439.504709 -439.199322) (xy 439.554309 -439.173821) (xy 439.607093 -439.155814) (xy 439.661936 -439.145684)
			(xy 439.71767 -439.143647) (xy 439.773107 -439.149747) (xy 439.827064 -439.163853) (xy 439.878393 -439.185665)
			(xy 439.925999 -439.214719) (xy 439.968867 -439.250394) (xy 440.006084 -439.291931) (xy 440.036857 -439.338444)
			(xy 440.060529 -439.388941) (xy 440.076597 -439.442348) (xy 440.084717 -439.497524) (xy 440.085226 -439.52541)
			(xy 440.084717 -439.553296) (xy 440.076597 -439.608472) (xy 440.060529 -439.661879) (xy 440.036857 -439.712376)
			(xy 440.006084 -439.758889) (xy 439.968867 -439.800426) (xy 439.925999 -439.836101) (xy 439.878393 -439.865155)
			(xy 439.827064 -439.886967) (xy 439.773107 -439.901073) (xy 439.71767 -439.907173) (xy 439.661936 -439.905136)
			(xy 439.607093 -439.895006) (xy 439.554309 -439.876999) (xy 439.504709 -439.851498) (xy 439.459351 -439.819047)
			(xy 439.419202 -439.780338) (xy 439.385116 -439.736195) (xy 439.35782 -439.68756) (xy 439.337897 -439.635469)
			(xy 439.325771 -439.581032) (xy 439.3217 -439.52541) (xy 434.727372 -439.52541) (xy 434.700786 -439.565595)
			(xy 434.663569 -439.607132) (xy 434.620701 -439.642807) (xy 434.573095 -439.671861) (xy 434.521766 -439.693673)
			(xy 434.467809 -439.707779) (xy 434.412372 -439.713879) (xy 434.356638 -439.711842) (xy 434.301795 -439.701712)
			(xy 434.249011 -439.683705) (xy 434.199411 -439.658204) (xy 434.154053 -439.625753) (xy 434.113904 -439.587044)
			(xy 434.079818 -439.542901) (xy 434.052522 -439.494266) (xy 434.032599 -439.442175) (xy 434.020473 -439.387738)
			(xy 434.016402 -439.332116) (xy 432.944524 -439.332116) (xy 434.185822 -440.573414) (xy 434.193218 -440.580266)
			(xy 434.211817 -440.588006) (xy 434.22189 -440.5884)
		)
		(stroke
			(width 0)
			(type solid)
		)
		(fill yes)
		(layer "In13.Cu")
		(net "GND")
	)
	(gr_poly
		(pts
			(xy 104.278938 -190.23838) (xy 104.288813 -190.237916) (xy 104.307105 -190.230465) (xy 104.314498 -190.223902)
			(xy 104.314752 -190.223648) (xy 105.202228 -189.336172) (xy 105.209625 -189.329322) (xy 105.228223 -189.321587)
			(xy 105.238296 -189.321186) (xy 125.724666 -189.321186) (xy 125.734539 -189.320717) (xy 125.752824 -189.31326)
			(xy 125.760226 -189.306708) (xy 125.76048 -189.306454) (xy 142.687294 -172.37964) (xy 142.687802 -172.379132)
			(xy 142.694387 -172.371752) (xy 142.70184 -172.353453) (xy 142.70228 -172.343572) (xy 142.70228 -150.22703)
			(xy 142.701844 -150.216966) (xy 142.694109 -150.198382) (xy 142.687294 -150.190962) (xy 140.898626 -148.402294)
			(xy 140.891214 -148.39561) (xy 140.872781 -148.388013) (xy 140.852843 -148.388013) (xy 140.83441 -148.39561)
			(xy 140.826998 -148.402294) (xy 138.13536 -151.093932) (xy 138.109803 -151.118798) (xy 138.054041 -151.163246)
			(xy 137.993652 -151.20117) (xy 137.929395 -151.232091) (xy 137.86208 -151.255622) (xy 137.792553 -151.271465)
			(xy 137.721689 -151.279422) (xy 137.686034 -151.27986) (xy 137.650571 -151.279384) (xy 137.580084 -151.27151)
			(xy 137.510913 -151.255833) (xy 137.443919 -151.23255) (xy 137.379935 -151.201949) (xy 137.319757 -151.164412)
			(xy 137.264135 -151.120405) (xy 137.213761 -151.070477) (xy 137.169262 -151.015248) (xy 137.131191 -150.955407)
			(xy 137.100023 -150.891697) (xy 137.08761 -150.858474) (xy 137.083292 -150.846282) (xy 137.06475 -150.829518)
			(xy 136.958324 -150.802594) (xy 136.93394 -150.808436) (xy 136.924288 -150.817072) (xy 136.903174 -150.835443)
			(xy 136.856573 -150.866434) (xy 136.805941 -150.890277) (xy 136.752366 -150.906458) (xy 136.697001 -150.914631)
			(xy 136.669018 -150.915116) (xy 136.641764 -150.914654) (xy 136.58781 -150.906899) (xy 136.535509 -150.891544)
			(xy 136.485925 -150.868902) (xy 136.440069 -150.839434) (xy 136.398873 -150.80374) (xy 136.363177 -150.762546)
			(xy 136.333707 -150.716691) (xy 136.311062 -150.667108) (xy 136.295705 -150.614808) (xy 136.287947 -150.560854)
			(xy 136.287947 -150.506346) (xy 136.295705 -150.452392) (xy 136.311062 -150.400092) (xy 136.333707 -150.350509)
			(xy 136.363177 -150.304654) (xy 136.398873 -150.26346) (xy 136.440069 -150.227766) (xy 136.485925 -150.198298)
			(xy 136.535509 -150.175656) (xy 136.58781 -150.160301) (xy 136.641764 -150.152546) (xy 136.669018 -150.1521)
			(xy 136.669272 -150.1521) (xy 136.698751 -150.152674) (xy 136.757001 -150.161785) (xy 136.813161 -150.179733)
			(xy 136.865899 -150.206092) (xy 136.890252 -150.222712) (xy 136.90219 -150.231094) (xy 136.93013 -150.233126)
			(xy 137.023094 -150.18512) (xy 137.031173 -150.18053) (xy 137.043613 -150.166747) (xy 137.050338 -150.149442)
			(xy 137.05078 -150.140162) (xy 137.05078 -144.575276) (xy 137.050238 -144.565291) (xy 137.042516 -144.546867)
			(xy 137.035794 -144.539462) (xy 131.497832 -139.001754) (xy 131.49072 -138.994388) (xy 131.471924 -138.986768)
			(xy 105.47731 -138.986768) (xy 105.258108 -138.986768) (xy 105.222216 -138.986268) (xy 105.15089 -138.978168)
			(xy 105.080931 -138.962082) (xy 105.013231 -138.938215) (xy 104.948651 -138.906871) (xy 104.888015 -138.868449)
			(xy 104.832095 -138.823438) (xy 104.781604 -138.772412) (xy 104.737184 -138.716022) (xy 104.71785 -138.685778)
			(xy 104.713019 -138.678613) (xy 104.699579 -138.667768) (xy 104.683304 -138.66199) (xy 104.67467 -138.661648)
			(xy 102.992174 -138.661648) (xy 102.982268 -138.662664) (xy 102.972362 -138.664696) (xy 102.96271 -138.66749)
			(xy 102.954074 -138.671046) (xy 102.89032 -138.759946) (xy 102.886764 -138.784076) (xy 102.890828 -138.79576)
			(xy 102.89994 -138.825022) (xy 102.909765 -138.885514) (xy 102.910386 -138.916156) (xy 102.910386 -138.922252)
			(xy 102.909504 -138.949227) (xy 102.901078 -139.002536) (xy 102.88522 -139.054125) (xy 102.862249 -139.102964)
			(xy 102.832623 -139.148077) (xy 102.796934 -139.188563) (xy 102.755893 -139.223614) (xy 102.710322 -139.25253)
			(xy 102.661129 -139.274734) (xy 102.609298 -139.289781) (xy 102.555864 -139.297372) (xy 102.528878 -139.297918)
			(xy 102.501628 -139.297431) (xy 102.447682 -139.289672) (xy 102.395389 -139.274315) (xy 102.345814 -139.251673)
			(xy 102.299965 -139.222206) (xy 102.258777 -139.186514) (xy 102.223087 -139.145325) (xy 102.193622 -139.099476)
			(xy 102.170981 -139.0499) (xy 102.155626 -138.997607) (xy 102.147868 -138.94366) (xy 102.14737 -138.91641)
			(xy 102.147878 -138.887822) (xy 102.156406 -138.831286) (xy 102.173273 -138.776655) (xy 102.1981 -138.725152)
			(xy 102.230334 -138.677928) (xy 102.269251 -138.636042) (xy 102.313981 -138.60043) (xy 102.363523 -138.571889)
			(xy 102.416769 -138.551058) (xy 102.44455 -138.5443) (xy 102.458266 -138.541252) (xy 102.478332 -138.522202)
			(xy 102.50678 -138.423396) (xy 102.508915 -138.414578) (xy 102.507537 -138.3965) (xy 102.499987 -138.380016)
			(xy 102.493826 -138.373358) (xy 101.99624 -137.875772) (xy 101.988831 -137.869085) (xy 101.970396 -137.861492)
			(xy 101.960426 -137.86104) (xy 96.436688 -137.86104) (xy 96.426722 -137.861518) (xy 96.408288 -137.869096)
			(xy 96.400874 -137.875772) (xy 96.34093 -137.935462) (xy 96.334119 -137.94284) (xy 96.326419 -137.961369)
			(xy 96.32642 -137.981435) (xy 96.334121 -137.999963) (xy 96.34093 -138.007344) (xy 96.346518 -138.012932)
			(xy 96.359726 -138.01979) (xy 96.367346 -138.021314) (xy 96.393107 -138.026742) (xy 96.442934 -138.043742)
			(xy 96.489948 -138.067434) (xy 96.533257 -138.097367) (xy 96.572038 -138.132971) (xy 96.605554 -138.173571)
			(xy 96.633167 -138.218395) (xy 96.654352 -138.266591) (xy 96.668708 -138.317242) (xy 96.675961 -138.369387)
			(xy 96.676464 -138.39571) (xy 96.676891 -138.405778) (xy 96.684615 -138.424374) (xy 96.69145 -138.431778)
			(xy 96.741742 -138.48207) (xy 96.748581 -138.48838) (xy 96.765509 -138.496074) (xy 96.774762 -138.497056)
			(xy 96.950022 -138.497056) (xy 96.953578 -138.497056) (xy 96.959931 -138.496397) (xy 96.972019 -138.492284)
			(xy 96.977454 -138.488928) (xy 96.978978 -138.488166) (xy 96.980502 -138.486896) (xy 97.004909 -138.469635)
			(xy 97.057972 -138.442109) (xy 97.114674 -138.423184) (xy 97.173632 -138.41332) (xy 97.203514 -138.412474)
			(xy 97.20961 -138.412474) (xy 97.236745 -138.41313) (xy 97.290422 -138.421176) (xy 97.342417 -138.436747)
			(xy 97.391681 -138.459529) (xy 97.437218 -138.489064) (xy 97.478111 -138.524753) (xy 97.513533 -138.565878)
			(xy 97.542769 -138.611608) (xy 97.56523 -138.661019) (xy 97.580461 -138.713115) (xy 97.588155 -138.766844)
			(xy 97.588578 -138.793982) (xy 97.588019 -138.823511) (xy 97.57891 -138.881861) (xy 97.560922 -138.938113)
			(xy 97.534484 -138.990922) (xy 97.500227 -139.039029) (xy 97.458969 -139.081285) (xy 97.411695 -139.116681)
			(xy 97.385886 -139.13104) (xy 97.385124 -139.131548) (xy 97.37598 -139.13739) (xy 97.356182 -139.153739)
			(xy 97.312848 -139.181278) (xy 97.266066 -139.202435) (xy 97.216768 -139.216787) (xy 97.16594 -139.224048)
			(xy 97.140268 -139.224512) (xy 93.69044 -139.224512) (xy 93.680441 -139.225002) (xy 93.661952 -139.23263)
			(xy 93.647755 -139.246717) (xy 93.64345 -139.255754) (xy 93.637608 -139.270232) (xy 93.64345 -139.300204)
			(xy 93.806264 -139.463018) (xy 93.808963 -139.465547) (xy 93.814955 -139.469883) (xy 93.818202 -139.471654)
			(xy 93.843692 -139.486094) (xy 93.890309 -139.521575) (xy 93.930958 -139.563761) (xy 93.964685 -139.611662)
			(xy 93.9907 -139.664152) (xy 94.00839 -139.720001) (xy 94.017341 -139.777896) (xy 94.017846 -139.807188)
			(xy 94.01735 -139.834822) (xy 94.009367 -139.88951) (xy 93.993582 -139.942476) (xy 93.970324 -139.992611)
			(xy 93.940079 -140.038869) (xy 93.90348 -140.080282) (xy 93.882718 -140.098526) (xy 93.875098 -140.104876)
			(xy 93.865954 -140.121894) (xy 93.856556 -140.21181) (xy 93.86189 -140.230352) (xy 93.867986 -140.238226)
			(xy 93.883046 -140.258347) (xy 93.908314 -140.301791) (xy 93.927659 -140.348177) (xy 93.940748 -140.396701)
			(xy 93.947352 -140.446523) (xy 93.947742 -140.471652) (xy 93.947234 -140.49121) (xy 93.946726 -140.501878)
			(xy 93.953838 -140.521182) (xy 94.019116 -140.590016) (xy 94.038166 -140.598144) (xy 94.048834 -140.598144)
			(xy 94.050866 -140.598144) (xy 94.086934 -140.557758) (xy 94.093347 -140.54999) (xy 94.100024 -140.531001)
			(xy 94.099888 -140.520928) (xy 94.099126 -140.497052) (xy 94.099612 -140.469801) (xy 94.107368 -140.415853)
			(xy 94.122723 -140.363558) (xy 94.145365 -140.313981) (xy 94.174831 -140.268131) (xy 94.210522 -140.22694)
			(xy 94.251713 -140.191249) (xy 94.297563 -140.161783) (xy 94.34714 -140.139141) (xy 94.399435 -140.123786)
			(xy 94.453383 -140.11603) (xy 94.507885 -140.11603) (xy 94.561833 -140.123786) (xy 94.614128 -140.139141)
			(xy 94.663705 -140.161783) (xy 94.709555 -140.191249) (xy 94.750746 -140.22694) (xy 94.766624 -140.245265)
			(xy 94.973013 -140.245265) (xy 94.980769 -140.191306) (xy 94.996124 -140.139) (xy 95.018768 -140.089412)
			(xy 95.048238 -140.043552) (xy 95.083935 -140.002352) (xy 95.125133 -139.966653) (xy 95.170991 -139.937179)
			(xy 95.220578 -139.914533) (xy 95.272883 -139.899174) (xy 95.326841 -139.891415) (xy 95.381354 -139.891415)
			(xy 95.435312 -139.899173) (xy 95.487617 -139.914531) (xy 95.537204 -139.937177) (xy 95.583063 -139.966649)
			(xy 95.624261 -140.002349) (xy 95.659959 -140.043548) (xy 95.68943 -140.089408) (xy 95.712074 -140.138995)
			(xy 95.72743 -140.191301) (xy 95.735186 -140.245259) (xy 95.735648 -140.272516) (xy 95.735648 -140.281914)
			(xy 95.73514 -140.292836) (xy 95.743776 -140.312902) (xy 95.815658 -140.379704) (xy 95.836232 -140.386562)
			(xy 95.847154 -140.385546) (xy 95.885508 -140.383514) (xy 95.914971 -140.384028) (xy 95.9732 -140.393065)
			(xy 96.02934 -140.410969) (xy 96.055942 -140.423646) (xy 96.066102 -140.428726) (xy 96.087692 -140.429488)
			(xy 96.179386 -140.391388) (xy 96.194118 -140.375386) (xy 96.197674 -140.364718) (xy 96.20646 -140.339692)
			(xy 96.229977 -140.292153) (xy 96.259852 -140.248328) (xy 96.29551 -140.209064) (xy 96.336261 -140.175118)
			(xy 96.381322 -140.147142) (xy 96.429823 -140.125678) (xy 96.48083 -140.111138) (xy 96.533359 -140.103802)
			(xy 96.559878 -140.103352) (xy 96.586625 -140.103759) (xy 96.639593 -140.111249) (xy 96.690996 -140.126058)
			(xy 96.739831 -140.147895) (xy 96.78514 -140.176333) (xy 96.826037 -140.210816) (xy 96.861722 -140.250669)
			(xy 96.891496 -140.295112) (xy 96.90354 -140.318998) (xy 96.90862 -140.329666) (xy 96.926654 -140.34389)
			(xy 97.027746 -140.366496) (xy 97.049844 -140.361162) (xy 97.058988 -140.353542) (xy 97.079508 -140.337414)
			(xy 97.124099 -140.310294) (xy 97.171971 -140.289506) (xy 97.22223 -140.275439) (xy 97.273938 -140.268355)
			(xy 97.300034 -140.267944) (xy 97.326337 -140.268382) (xy 97.378441 -140.275627) (xy 97.429057 -140.289961)
			(xy 97.477223 -140.311112) (xy 97.522027 -140.33868) (xy 97.56262 -140.372141) (xy 97.598231 -140.410861)
			(xy 97.628185 -140.454106) (xy 97.651914 -140.501056) (xy 97.668969 -140.55082) (xy 97.67443 -140.576554)
			(xy 97.676462 -140.58646) (xy 97.687638 -140.603478) (xy 97.7646 -140.654786) (xy 97.784412 -140.658596)
			(xy 97.794572 -140.656564) (xy 97.813418 -140.652987) (xy 97.851591 -140.64917) (xy 97.870772 -140.648944)
			(xy 97.898023 -140.649501) (xy 97.95197 -140.657254) (xy 98.004265 -140.672606) (xy 98.053842 -140.695244)
			(xy 98.099693 -140.724707) (xy 98.140884 -140.760397) (xy 98.176576 -140.801585) (xy 98.206043 -140.847433)
			(xy 98.228684 -140.897009) (xy 98.240421 -140.93698) (xy 98.420172 -140.93698) (xy 98.424243 -140.881358)
			(xy 98.436369 -140.826921) (xy 98.456292 -140.77483) (xy 98.483588 -140.726195) (xy 98.517674 -140.682052)
			(xy 98.557823 -140.643343) (xy 98.603181 -140.610892) (xy 98.652781 -140.585391) (xy 98.705565 -140.567384)
			(xy 98.760408 -140.557254) (xy 98.816142 -140.555217) (xy 98.871579 -140.561317) (xy 98.925536 -140.575423)
			(xy 98.976865 -140.597235) (xy 99.024471 -140.626289) (xy 99.067339 -140.661964) (xy 99.104556 -140.703501)
			(xy 99.135329 -140.750014) (xy 99.159001 -140.800511) (xy 99.175069 -140.853918) (xy 99.183189 -140.909094)
			(xy 99.183698 -140.93698) (xy 99.183189 -140.964866) (xy 99.175069 -141.020042) (xy 99.159001 -141.073449)
			(xy 99.135329 -141.123946) (xy 99.104556 -141.170459) (xy 99.067339 -141.211996) (xy 99.024471 -141.247671)
			(xy 98.976865 -141.276725) (xy 98.925536 -141.298537) (xy 98.871579 -141.312643) (xy 98.816142 -141.318743)
			(xy 98.760408 -141.316706) (xy 98.705565 -141.306576) (xy 98.652781 -141.288569) (xy 98.603181 -141.263068)
			(xy 98.557823 -141.230617) (xy 98.517674 -141.191908) (xy 98.483588 -141.147765) (xy 98.456292 -141.09913)
			(xy 98.436369 -141.047039) (xy 98.424243 -140.992602) (xy 98.420172 -140.93698) (xy 98.240421 -140.93698)
			(xy 98.24404 -140.949303) (xy 98.251797 -141.003249) (xy 98.251797 -141.057751) (xy 98.24404 -141.111697)
			(xy 98.228684 -141.163991) (xy 98.206043 -141.213567) (xy 98.176576 -141.259415) (xy 98.140884 -141.300603)
			(xy 98.099693 -141.336293) (xy 98.053842 -141.365756) (xy 98.004265 -141.388394) (xy 97.95197 -141.403746)
			(xy 97.898023 -141.411499) (xy 97.870772 -141.41196) (xy 97.84447 -141.411513) (xy 97.792365 -141.404269)
			(xy 97.74175 -141.389936) (xy 97.693584 -141.368786) (xy 97.64878 -141.341219) (xy 97.608188 -141.307759)
			(xy 97.572577 -141.26904) (xy 97.542622 -141.225796) (xy 97.518893 -141.178847) (xy 97.501837 -141.129083)
			(xy 97.496376 -141.10335) (xy 97.494344 -141.093444) (xy 97.483168 -141.076426) (xy 97.406206 -141.025118)
			(xy 97.386394 -141.021308) (xy 97.376234 -141.02334) (xy 97.357388 -141.026916) (xy 97.319215 -141.030734)
			(xy 97.300034 -141.03096) (xy 97.273288 -141.030536) (xy 97.220321 -141.023048) (xy 97.168918 -141.008242)
			(xy 97.120084 -140.986407) (xy 97.074775 -140.957971) (xy 97.033877 -140.92349) (xy 96.998192 -140.88364)
			(xy 96.968417 -140.839199) (xy 96.956372 -140.815314) (xy 96.951292 -140.804646) (xy 96.933258 -140.790422)
			(xy 96.832166 -140.767816) (xy 96.810068 -140.77315) (xy 96.800924 -140.78077) (xy 96.780402 -140.796895)
			(xy 96.735811 -140.824015) (xy 96.68794 -140.844804) (xy 96.637681 -140.858872) (xy 96.585974 -140.865957)
			(xy 96.559878 -140.866368) (xy 96.530415 -140.865851) (xy 96.472187 -140.856813) (xy 96.416046 -140.838912)
			(xy 96.389444 -140.826236) (xy 96.379284 -140.821156) (xy 96.357694 -140.820394) (xy 96.266 -140.858494)
			(xy 96.251268 -140.874496) (xy 96.247712 -140.885164) (xy 96.238928 -140.910191) (xy 96.215411 -140.957731)
			(xy 96.185537 -141.001556) (xy 96.14988 -141.040821) (xy 96.109128 -141.074768) (xy 96.064066 -141.102744)
			(xy 96.015565 -141.124208) (xy 95.964557 -141.138747) (xy 95.912028 -141.146081) (xy 95.885508 -141.14653)
			(xy 95.858258 -141.146015) (xy 95.804312 -141.13826) (xy 95.75202 -141.122907) (xy 95.702444 -141.100268)
			(xy 95.656594 -141.070805) (xy 95.615405 -141.035117) (xy 95.579713 -140.99393) (xy 95.550246 -140.948083)
			(xy 95.527604 -140.898509) (xy 95.512246 -140.846217) (xy 95.504487 -140.792272) (xy 95.504 -140.765022)
			(xy 95.504 -140.755624) (xy 95.504508 -140.744702) (xy 95.495872 -140.724636) (xy 95.42399 -140.657834)
			(xy 95.403416 -140.650976) (xy 95.392494 -140.651992) (xy 95.35414 -140.654024) (xy 95.326883 -140.653588)
			(xy 95.272924 -140.645835) (xy 95.220618 -140.630482) (xy 95.171029 -140.607841) (xy 95.125167 -140.578373)
			(xy 95.083966 -140.542678) (xy 95.048264 -140.501482) (xy 95.018788 -140.455625) (xy 94.996139 -140.40604)
			(xy 94.980778 -140.353736) (xy 94.973017 -140.299778) (xy 94.973013 -140.245265) (xy 94.766624 -140.245265)
			(xy 94.786437 -140.268131) (xy 94.815903 -140.313981) (xy 94.838545 -140.363558) (xy 94.8539 -140.415853)
			(xy 94.861656 -140.469801) (xy 94.862142 -140.497052) (xy 94.861649 -140.52501) (xy 94.853485 -140.580328)
			(xy 94.837337 -140.633863) (xy 94.813553 -140.684469) (xy 94.782641 -140.731064) (xy 94.745262 -140.772652)
			(xy 94.702216 -140.808341) (xy 94.654424 -140.837369) (xy 94.602909 -140.859115) (xy 94.548773 -140.873113)
			(xy 94.52102 -140.876528) (xy 94.511622 -140.877544) (xy 94.495112 -140.885926) (xy 94.436946 -140.95095)
			(xy 94.430342 -140.968222) (xy 94.430342 -140.977874) (xy 94.430342 -140.979652) (xy 94.429856 -141.006903)
			(xy 94.4221 -141.060851) (xy 94.406745 -141.113146) (xy 94.384103 -141.162723) (xy 94.354637 -141.208573)
			(xy 94.318946 -141.249764) (xy 94.277755 -141.285455) (xy 94.231905 -141.314921) (xy 94.182328 -141.337563)
			(xy 94.130033 -141.352918) (xy 94.076085 -141.360674) (xy 94.021583 -141.360674) (xy 93.967635 -141.352918)
			(xy 93.91534 -141.337563) (xy 93.865763 -141.314921) (xy 93.819913 -141.285455) (xy 93.778722 -141.249764)
			(xy 93.743031 -141.208573) (xy 93.713565 -141.162723) (xy 93.690923 -141.113146) (xy 93.675568 -141.060851)
			(xy 93.667812 -141.006903) (xy 93.667326 -140.979652) (xy 93.667834 -140.960094) (xy 93.668342 -140.949426)
			(xy 93.66123 -140.930122) (xy 93.595952 -140.861288) (xy 93.576902 -140.85316) (xy 93.566234 -140.85316)
			(xy 93.538981 -140.852699) (xy 93.485029 -140.844946) (xy 93.43273 -140.829592) (xy 93.383148 -140.806951)
			(xy 93.337294 -140.777483) (xy 93.296101 -140.741789) (xy 93.260409 -140.700595) (xy 93.230942 -140.654739)
			(xy 93.208303 -140.605157) (xy 93.192951 -140.552858) (xy 93.1852 -140.498905) (xy 93.184726 -140.471652)
			(xy 93.185219 -140.444017) (xy 93.193196 -140.389325) (xy 93.208976 -140.336355) (xy 93.23223 -140.286214)
			(xy 93.262471 -140.23995) (xy 93.299068 -140.198531) (xy 93.319854 -140.180314) (xy 93.327474 -140.173964)
			(xy 93.336618 -140.156946) (xy 93.346016 -140.06703) (xy 93.340682 -140.048488) (xy 93.334586 -140.040614)
			(xy 93.325237 -140.028338) (xy 93.308323 -140.002526) (xy 93.300804 -139.989052) (xy 93.297502 -139.982448)
			(xy 93.27769 -139.96289) (xy 93.270816 -139.956475) (xy 93.253668 -139.948795) (xy 93.234904 -139.947828)
			(xy 93.225874 -139.950444) (xy 93.125798 -139.983464) (xy 93.10751 -140.005308) (xy 93.105478 -140.019786)
			(xy 93.101009 -140.046583) (xy 93.085478 -140.09864) (xy 93.062717 -140.147967) (xy 93.033188 -140.193566)
			(xy 92.997488 -140.234514) (xy 92.956339 -140.269982) (xy 92.910575 -140.299253) (xy 92.86112 -140.321734)
			(xy 92.808975 -140.336971) (xy 92.755197 -140.344656) (xy 92.728034 -140.34516) (xy 92.700781 -140.344699)
			(xy 92.646829 -140.336946) (xy 92.59453 -140.321592) (xy 92.544948 -140.298951) (xy 92.499094 -140.269483)
			(xy 92.457901 -140.233789) (xy 92.422209 -140.192595) (xy 92.392742 -140.146739) (xy 92.370103 -140.097157)
			(xy 92.354751 -140.044858) (xy 92.347 -139.990905) (xy 92.346526 -139.963652) (xy 92.346901 -139.939709)
			(xy 92.352888 -139.892198) (xy 92.358464 -139.86891) (xy 92.361512 -139.857226) (xy 92.356686 -139.83462)
			(xy 92.300298 -139.761722) (xy 92.292708 -139.752893) (xy 92.271797 -139.742715) (xy 92.260166 -139.742164)
			(xy 92.243148 -139.742164) (xy 92.233184 -139.742647) (xy 92.214753 -139.750227) (xy 92.207334 -139.756896)
			(xy 91.323922 -140.640308) (xy 91.303331 -140.660125) (xy 91.257117 -140.69374) (xy 91.206216 -140.719717)
			(xy 91.151881 -140.737419) (xy 91.095446 -140.74641) (xy 91.066874 -140.746988) (xy 89.632028 -140.746988)
			(xy 89.620806 -140.747636) (xy 89.600518 -140.757254) (xy 89.592912 -140.76553) (xy 89.543382 -140.825982)
			(xy 89.539855 -140.830437) (xy 89.534713 -140.840566) (xy 89.533222 -140.846048) (xy 89.530428 -140.857224)
			(xy 89.532714 -140.8684) (xy 89.536192 -140.887) (xy 89.539884 -140.924662) (xy 89.54008 -140.943584)
			(xy 89.539594 -140.970835) (xy 89.531838 -141.024783) (xy 89.516483 -141.077078) (xy 89.493841 -141.126655)
			(xy 89.464375 -141.172505) (xy 89.428684 -141.213696) (xy 89.387493 -141.249387) (xy 89.341643 -141.278853)
			(xy 89.292066 -141.301495) (xy 89.239771 -141.31685) (xy 89.185823 -141.324606) (xy 89.131321 -141.324606)
			(xy 89.077373 -141.31685) (xy 89.025078 -141.301495) (xy 88.975501 -141.278853) (xy 88.929651 -141.249387)
			(xy 88.88846 -141.213696) (xy 88.852769 -141.172505) (xy 88.823303 -141.126655) (xy 88.800661 -141.077078)
			(xy 88.785306 -141.024783) (xy 88.77755 -140.970835) (xy 88.777064 -140.943584) (xy 88.77727 -140.924663)
			(xy 88.780956 -140.887001) (xy 88.78443 -140.8684) (xy 88.786716 -140.857224) (xy 88.783922 -140.846048)
			(xy 88.782377 -140.840586) (xy 88.777245 -140.830464) (xy 88.773762 -140.825982) (xy 88.724232 -140.76553)
			(xy 88.716608 -140.75717) (xy 88.696163 -140.747553) (xy 88.684862 -140.746988) (xy 77.147928 -140.746988)
			(xy 77.129132 -140.754608) (xy 77.12202 -140.761974) (xy 76.622322 -141.261592) (xy 81.648552 -141.261592)
			(xy 81.652623 -141.20597) (xy 81.664749 -141.151533) (xy 81.684672 -141.099442) (xy 81.711968 -141.050807)
			(xy 81.746054 -141.006664) (xy 81.786203 -140.967955) (xy 81.831561 -140.935504) (xy 81.881161 -140.910003)
			(xy 81.933945 -140.891996) (xy 81.988788 -140.881866) (xy 82.044522 -140.879829) (xy 82.099959 -140.885929)
			(xy 82.153916 -140.900035) (xy 82.205245 -140.921847) (xy 82.252851 -140.950901) (xy 82.295719 -140.986576)
			(xy 82.332936 -141.028113) (xy 82.363709 -141.074626) (xy 82.387381 -141.125123) (xy 82.403449 -141.17853)
			(xy 82.411569 -141.233706) (xy 82.412078 -141.261592) (xy 82.411569 -141.289478) (xy 82.403449 -141.344654)
			(xy 82.387381 -141.398061) (xy 82.376936 -141.420342) (xy 92.08592 -141.420342) (xy 92.089991 -141.36472)
			(xy 92.102117 -141.310283) (xy 92.12204 -141.258192) (xy 92.149336 -141.209557) (xy 92.183422 -141.165414)
			(xy 92.223571 -141.126705) (xy 92.268929 -141.094254) (xy 92.318529 -141.068753) (xy 92.371313 -141.050746)
			(xy 92.426156 -141.040616) (xy 92.48189 -141.038579) (xy 92.537327 -141.044679) (xy 92.591284 -141.058785)
			(xy 92.642613 -141.080597) (xy 92.690219 -141.109651) (xy 92.733087 -141.145326) (xy 92.770304 -141.186863)
			(xy 92.801077 -141.233376) (xy 92.824749 -141.283873) (xy 92.840817 -141.33728) (xy 92.848937 -141.392456)
			(xy 92.849446 -141.420342) (xy 92.848937 -141.448228) (xy 92.840817 -141.503404) (xy 92.824749 -141.556811)
			(xy 92.801077 -141.607308) (xy 92.770304 -141.653821) (xy 92.734393 -141.6939) (xy 103.389682 -141.6939)
			(xy 103.393753 -141.638278) (xy 103.405879 -141.583841) (xy 103.425802 -141.53175) (xy 103.453098 -141.483115)
			(xy 103.487184 -141.438972) (xy 103.527333 -141.400263) (xy 103.572691 -141.367812) (xy 103.622291 -141.342311)
			(xy 103.675075 -141.324304) (xy 103.729918 -141.314174) (xy 103.785652 -141.312137) (xy 103.841089 -141.318237)
			(xy 103.895046 -141.332343) (xy 103.946375 -141.354155) (xy 103.993981 -141.383209) (xy 104.036849 -141.418884)
			(xy 104.074066 -141.460421) (xy 104.104839 -141.506934) (xy 104.128511 -141.557431) (xy 104.144579 -141.610838)
			(xy 104.152699 -141.666014) (xy 104.153208 -141.6939) (xy 104.152699 -141.721786) (xy 104.144579 -141.776962)
			(xy 104.128511 -141.830369) (xy 104.104839 -141.880866) (xy 104.074066 -141.927379) (xy 104.036849 -141.968916)
			(xy 103.993981 -142.004591) (xy 103.946375 -142.033645) (xy 103.895046 -142.055457) (xy 103.841089 -142.069563)
			(xy 103.785652 -142.075663) (xy 103.729918 -142.073626) (xy 103.675075 -142.063496) (xy 103.622291 -142.045489)
			(xy 103.572691 -142.019988) (xy 103.527333 -141.987537) (xy 103.487184 -141.948828) (xy 103.453098 -141.904685)
			(xy 103.425802 -141.85605) (xy 103.405879 -141.803959) (xy 103.393753 -141.749522) (xy 103.389682 -141.6939)
			(xy 92.734393 -141.6939) (xy 92.733087 -141.695358) (xy 92.690219 -141.731033) (xy 92.642613 -141.760087)
			(xy 92.591284 -141.781899) (xy 92.537327 -141.796005) (xy 92.48189 -141.802105) (xy 92.426156 -141.800068)
			(xy 92.371313 -141.789938) (xy 92.318529 -141.771931) (xy 92.268929 -141.74643) (xy 92.223571 -141.713979)
			(xy 92.183422 -141.67527) (xy 92.149336 -141.631127) (xy 92.12204 -141.582492) (xy 92.102117 -141.530401)
			(xy 92.089991 -141.475964) (xy 92.08592 -141.420342) (xy 82.376936 -141.420342) (xy 82.363709 -141.448558)
			(xy 82.332936 -141.495071) (xy 82.295719 -141.536608) (xy 82.252851 -141.572283) (xy 82.205245 -141.601337)
			(xy 82.153916 -141.623149) (xy 82.099959 -141.637255) (xy 82.044522 -141.643355) (xy 81.988788 -141.641318)
			(xy 81.933945 -141.631188) (xy 81.881161 -141.613181) (xy 81.831561 -141.58768) (xy 81.786203 -141.555229)
			(xy 81.746054 -141.51652) (xy 81.711968 -141.472377) (xy 81.684672 -141.423742) (xy 81.664749 -141.371651)
			(xy 81.652623 -141.317214) (xy 81.648552 -141.261592) (xy 76.622322 -141.261592) (xy 75.780177 -142.103602)
			(xy 99.991416 -142.103602) (xy 99.995487 -142.04798) (xy 100.007613 -141.993543) (xy 100.027536 -141.941452)
			(xy 100.054832 -141.892817) (xy 100.088918 -141.848674) (xy 100.129067 -141.809965) (xy 100.174425 -141.777514)
			(xy 100.224025 -141.752013) (xy 100.276809 -141.734006) (xy 100.331652 -141.723876) (xy 100.387386 -141.721839)
			(xy 100.442823 -141.727939) (xy 100.49678 -141.742045) (xy 100.548109 -141.763857) (xy 100.595715 -141.792911)
			(xy 100.638583 -141.828586) (xy 100.6758 -141.870123) (xy 100.706573 -141.916636) (xy 100.730245 -141.967133)
			(xy 100.746313 -142.02054) (xy 100.754433 -142.075716) (xy 100.754942 -142.103602) (xy 100.754433 -142.131488)
			(xy 100.746313 -142.186664) (xy 100.730245 -142.240071) (xy 100.706573 -142.290568) (xy 100.6758 -142.337081)
			(xy 100.638583 -142.378618) (xy 100.595715 -142.414293) (xy 100.548109 -142.443347) (xy 100.49678 -142.465159)
			(xy 100.442823 -142.479265) (xy 100.387386 -142.485365) (xy 100.331652 -142.483328) (xy 100.276809 -142.473198)
			(xy 100.224025 -142.455191) (xy 100.174425 -142.42969) (xy 100.129067 -142.397239) (xy 100.088918 -142.35853)
			(xy 100.054832 -142.314387) (xy 100.027536 -142.265752) (xy 100.007613 -142.213661) (xy 99.995487 -142.159224)
			(xy 99.991416 -142.103602) (xy 75.780177 -142.103602) (xy 75.535536 -142.348204) (xy 75.528134 -142.35504)
			(xy 75.509536 -142.362751) (xy 75.499468 -142.36319) (xy 65.83426 -142.36319) (xy 65.824193 -142.36362)
			(xy 65.805598 -142.371343) (xy 65.798192 -142.378176) (xy 65.671192 -142.505176) (xy 91.124276 -142.505176)
			(xy 91.128347 -142.449554) (xy 91.140473 -142.395117) (xy 91.160396 -142.343026) (xy 91.187692 -142.294391)
			(xy 91.221778 -142.250248) (xy 91.261927 -142.211539) (xy 91.307285 -142.179088) (xy 91.356885 -142.153587)
			(xy 91.409669 -142.13558) (xy 91.464512 -142.12545) (xy 91.520246 -142.123413) (xy 91.575683 -142.129513)
			(xy 91.62964 -142.143619) (xy 91.680969 -142.165431) (xy 91.728575 -142.194485) (xy 91.771443 -142.23016)
			(xy 91.80866 -142.271697) (xy 91.839433 -142.31821) (xy 91.863105 -142.368707) (xy 91.879173 -142.422114)
			(xy 91.887293 -142.47729) (xy 91.887802 -142.505176) (xy 91.887293 -142.533062) (xy 91.879173 -142.588238)
			(xy 91.863105 -142.641645) (xy 91.839433 -142.692142) (xy 91.80866 -142.738655) (xy 91.771443 -142.780192)
			(xy 91.728575 -142.815867) (xy 91.680969 -142.844921) (xy 91.62964 -142.866733) (xy 91.575683 -142.880839)
			(xy 91.520246 -142.886939) (xy 91.464512 -142.884902) (xy 91.409669 -142.874772) (xy 91.356885 -142.856765)
			(xy 91.307285 -142.831264) (xy 91.261927 -142.798813) (xy 91.221778 -142.760104) (xy 91.187692 -142.715961)
			(xy 91.160396 -142.667326) (xy 91.140473 -142.615235) (xy 91.128347 -142.560798) (xy 91.124276 -142.505176)
			(xy 65.671192 -142.505176) (xy 65.502028 -142.67434) (xy 65.481436 -142.694156) (xy 65.435221 -142.727768)
			(xy 65.384321 -142.753744) (xy 65.329986 -142.771445) (xy 65.273552 -142.780436) (xy 65.24498 -142.78102)
			(xy 60.417456 -142.78102) (xy 60.39866 -142.78864) (xy 60.391548 -142.796006) (xy 59.832916 -143.354552)
			(xy 87.380316 -143.354552) (xy 87.384387 -143.29893) (xy 87.396513 -143.244493) (xy 87.416436 -143.192402)
			(xy 87.443732 -143.143767) (xy 87.477818 -143.099624) (xy 87.517967 -143.060915) (xy 87.563325 -143.028464)
			(xy 87.612925 -143.002963) (xy 87.665709 -142.984956) (xy 87.720552 -142.974826) (xy 87.776286 -142.972789)
			(xy 87.831723 -142.978889) (xy 87.88568 -142.992995) (xy 87.937009 -143.014807) (xy 87.984615 -143.043861)
			(xy 88.027483 -143.079536) (xy 88.0647 -143.121073) (xy 88.095473 -143.167586) (xy 88.119145 -143.218083)
			(xy 88.135213 -143.27149) (xy 88.143333 -143.326666) (xy 88.143842 -143.354552) (xy 88.143333 -143.382438)
			(xy 88.135213 -143.437614) (xy 88.119145 -143.491021) (xy 88.095473 -143.541518) (xy 88.0647 -143.588031)
			(xy 88.027483 -143.629568) (xy 87.984615 -143.665243) (xy 87.937009 -143.694297) (xy 87.88568 -143.716109)
			(xy 87.831723 -143.730215) (xy 87.776286 -143.736315) (xy 87.720552 -143.734278) (xy 87.665709 -143.724148)
			(xy 87.612925 -143.706141) (xy 87.563325 -143.68064) (xy 87.517967 -143.648189) (xy 87.477818 -143.60948)
			(xy 87.443732 -143.565337) (xy 87.416436 -143.516702) (xy 87.396513 -143.464611) (xy 87.384387 -143.410174)
			(xy 87.380316 -143.354552) (xy 59.832916 -143.354552) (xy 59.401558 -143.785844) (xy 82.07832 -143.785844)
			(xy 82.082391 -143.730222) (xy 82.094517 -143.675785) (xy 82.11444 -143.623694) (xy 82.141736 -143.575059)
			(xy 82.175822 -143.530916) (xy 82.215971 -143.492207) (xy 82.261329 -143.459756) (xy 82.310929 -143.434255)
			(xy 82.363713 -143.416248) (xy 82.418556 -143.406118) (xy 82.47429 -143.404081) (xy 82.529727 -143.410181)
			(xy 82.583684 -143.424287) (xy 82.635013 -143.446099) (xy 82.682619 -143.475153) (xy 82.725487 -143.510828)
			(xy 82.762704 -143.552365) (xy 82.793477 -143.598878) (xy 82.817149 -143.649375) (xy 82.833217 -143.702782)
			(xy 82.841337 -143.757958) (xy 82.841846 -143.785844) (xy 82.841337 -143.81373) (xy 82.833217 -143.868906)
			(xy 82.817149 -143.922313) (xy 82.793477 -143.97281) (xy 82.762704 -144.019323) (xy 82.725487 -144.06086)
			(xy 82.682619 -144.096535) (xy 82.635013 -144.125589) (xy 82.583684 -144.147401) (xy 82.529727 -144.161507)
			(xy 82.47429 -144.167607) (xy 82.418556 -144.16557) (xy 82.363713 -144.15544) (xy 82.310929 -144.137433)
			(xy 82.261329 -144.111932) (xy 82.215971 -144.079481) (xy 82.175822 -144.040772) (xy 82.141736 -143.996629)
			(xy 82.11444 -143.947994) (xy 82.094517 -143.895903) (xy 82.082391 -143.841466) (xy 82.07832 -143.785844)
			(xy 59.401558 -143.785844) (xy 58.732674 -144.454626) (xy 58.725824 -144.462022) (xy 58.718087 -144.480621)
			(xy 58.717688 -144.490694) (xy 58.717688 -145.973292) (xy 69.238366 -145.973292) (xy 69.242437 -145.91767)
			(xy 69.254563 -145.863233) (xy 69.274486 -145.811142) (xy 69.301782 -145.762507) (xy 69.335868 -145.718364)
			(xy 69.376017 -145.679655) (xy 69.421375 -145.647204) (xy 69.470975 -145.621703) (xy 69.523759 -145.603696)
			(xy 69.578602 -145.593566) (xy 69.634336 -145.591529) (xy 69.689773 -145.597629) (xy 69.74373 -145.611735)
			(xy 69.795059 -145.633547) (xy 69.842665 -145.662601) (xy 69.885533 -145.698276) (xy 69.92275 -145.739813)
			(xy 69.953523 -145.786326) (xy 69.977195 -145.836823) (xy 69.993263 -145.89023) (xy 70.001383 -145.945406)
			(xy 70.001892 -145.973292) (xy 70.001383 -146.001178) (xy 69.993263 -146.056354) (xy 69.987686 -146.074892)
			(xy 73.130916 -146.074892) (xy 73.134987 -146.01927) (xy 73.147113 -145.964833) (xy 73.167036 -145.912742)
			(xy 73.194332 -145.864107) (xy 73.228418 -145.819964) (xy 73.268567 -145.781255) (xy 73.313925 -145.748804)
			(xy 73.363525 -145.723303) (xy 73.416309 -145.705296) (xy 73.471152 -145.695166) (xy 73.526886 -145.693129)
			(xy 73.582323 -145.699229) (xy 73.63628 -145.713335) (xy 73.687609 -145.735147) (xy 73.735215 -145.764201)
			(xy 73.778083 -145.799876) (xy 73.8153 -145.841413) (xy 73.846073 -145.887926) (xy 73.869745 -145.938423)
			(xy 73.885813 -145.99183) (xy 73.893933 -146.047006) (xy 73.894442 -146.074892) (xy 73.893933 -146.102778)
			(xy 73.885813 -146.157954) (xy 73.869745 -146.211361) (xy 73.846073 -146.261858) (xy 73.8153 -146.308371)
			(xy 73.778083 -146.349908) (xy 73.735215 -146.385583) (xy 73.687609 -146.414637) (xy 73.63628 -146.436449)
			(xy 73.582323 -146.450555) (xy 73.526886 -146.456655) (xy 73.471152 -146.454618) (xy 73.416309 -146.444488)
			(xy 73.363525 -146.426481) (xy 73.313925 -146.40098) (xy 73.268567 -146.368529) (xy 73.228418 -146.32982)
			(xy 73.194332 -146.285677) (xy 73.167036 -146.237042) (xy 73.147113 -146.184951) (xy 73.134987 -146.130514)
			(xy 73.130916 -146.074892) (xy 69.987686 -146.074892) (xy 69.977195 -146.109761) (xy 69.953523 -146.160258)
			(xy 69.92275 -146.206771) (xy 69.885533 -146.248308) (xy 69.842665 -146.283983) (xy 69.795059 -146.313037)
			(xy 69.74373 -146.334849) (xy 69.689773 -146.348955) (xy 69.634336 -146.355055) (xy 69.578602 -146.353018)
			(xy 69.523759 -146.342888) (xy 69.470975 -146.324881) (xy 69.421375 -146.29938) (xy 69.376017 -146.266929)
			(xy 69.335868 -146.22822) (xy 69.301782 -146.184077) (xy 69.274486 -146.135442) (xy 69.254563 -146.083351)
			(xy 69.242437 -146.028914) (xy 69.238366 -145.973292) (xy 58.717688 -145.973292) (xy 58.717688 -146.605752)
			(xy 74.369928 -146.605752) (xy 74.373999 -146.55013) (xy 74.386125 -146.495693) (xy 74.406048 -146.443602)
			(xy 74.433344 -146.394967) (xy 74.46743 -146.350824) (xy 74.507579 -146.312115) (xy 74.552937 -146.279664)
			(xy 74.602537 -146.254163) (xy 74.655321 -146.236156) (xy 74.710164 -146.226026) (xy 74.765898 -146.223989)
			(xy 74.821335 -146.230089) (xy 74.875292 -146.244195) (xy 74.926621 -146.266007) (xy 74.974227 -146.295061)
			(xy 75.017095 -146.330736) (xy 75.054312 -146.372273) (xy 75.085085 -146.418786) (xy 75.108757 -146.469283)
			(xy 75.124825 -146.52269) (xy 75.132945 -146.577866) (xy 75.133454 -146.605752) (xy 75.132945 -146.633638)
			(xy 75.124825 -146.688814) (xy 75.108757 -146.742221) (xy 75.085085 -146.792718) (xy 75.054312 -146.839231)
			(xy 75.017095 -146.880768) (xy 74.974227 -146.916443) (xy 74.926621 -146.945497) (xy 74.875292 -146.967309)
			(xy 74.821335 -146.981415) (xy 74.765898 -146.987515) (xy 74.710164 -146.985478) (xy 74.655321 -146.975348)
			(xy 74.602537 -146.957341) (xy 74.552937 -146.93184) (xy 74.507579 -146.899389) (xy 74.46743 -146.86068)
			(xy 74.433344 -146.816537) (xy 74.406048 -146.767902) (xy 74.386125 -146.715811) (xy 74.373999 -146.661374)
			(xy 74.369928 -146.605752) (xy 58.717688 -146.605752) (xy 58.717688 -147.417536) (xy 75.262992 -147.417536)
			(xy 75.267063 -147.361914) (xy 75.279189 -147.307477) (xy 75.299112 -147.255386) (xy 75.326408 -147.206751)
			(xy 75.360494 -147.162608) (xy 75.400643 -147.123899) (xy 75.446001 -147.091448) (xy 75.495601 -147.065947)
			(xy 75.548385 -147.04794) (xy 75.603228 -147.03781) (xy 75.658962 -147.035773) (xy 75.714399 -147.041873)
			(xy 75.768356 -147.055979) (xy 75.819685 -147.077791) (xy 75.867291 -147.106845) (xy 75.910159 -147.14252)
			(xy 75.947376 -147.184057) (xy 75.978149 -147.23057) (xy 76.001821 -147.281067) (xy 76.017889 -147.334474)
			(xy 76.026009 -147.38965) (xy 76.026518 -147.417536) (xy 76.026009 -147.445422) (xy 76.017889 -147.500598)
			(xy 76.001821 -147.554005) (xy 75.978149 -147.604502) (xy 75.947376 -147.651015) (xy 75.910159 -147.692552)
			(xy 75.867291 -147.728227) (xy 75.819685 -147.757281) (xy 75.768356 -147.779093) (xy 75.714399 -147.793199)
			(xy 75.658962 -147.799299) (xy 75.603228 -147.797262) (xy 75.548385 -147.787132) (xy 75.495601 -147.769125)
			(xy 75.446001 -147.743624) (xy 75.400643 -147.711173) (xy 75.360494 -147.672464) (xy 75.326408 -147.628321)
			(xy 75.299112 -147.579686) (xy 75.279189 -147.527595) (xy 75.267063 -147.473158) (xy 75.262992 -147.417536)
			(xy 58.717688 -147.417536) (xy 58.717688 -148.37664) (xy 76.359002 -148.37664) (xy 76.363073 -148.321018)
			(xy 76.375199 -148.266581) (xy 76.395122 -148.21449) (xy 76.422418 -148.165855) (xy 76.456504 -148.121712)
			(xy 76.496653 -148.083003) (xy 76.542011 -148.050552) (xy 76.591611 -148.025051) (xy 76.644395 -148.007044)
			(xy 76.699238 -147.996914) (xy 76.754972 -147.994877) (xy 76.810409 -148.000977) (xy 76.864366 -148.015083)
			(xy 76.915695 -148.036895) (xy 76.963301 -148.065949) (xy 77.006169 -148.101624) (xy 77.043386 -148.143161)
			(xy 77.074159 -148.189674) (xy 77.097831 -148.240171) (xy 77.113899 -148.293578) (xy 77.122019 -148.348754)
			(xy 77.122528 -148.37664) (xy 77.122019 -148.404526) (xy 77.113899 -148.459702) (xy 77.097831 -148.513109)
			(xy 77.074159 -148.563606) (xy 77.043386 -148.610119) (xy 77.006169 -148.651656) (xy 76.963301 -148.687331)
			(xy 76.915695 -148.716385) (xy 76.864366 -148.738197) (xy 76.810409 -148.752303) (xy 76.754972 -148.758403)
			(xy 76.699238 -148.756366) (xy 76.644395 -148.746236) (xy 76.591611 -148.728229) (xy 76.542011 -148.702728)
			(xy 76.496653 -148.670277) (xy 76.456504 -148.631568) (xy 76.422418 -148.587425) (xy 76.395122 -148.53879)
			(xy 76.375199 -148.486699) (xy 76.363073 -148.432262) (xy 76.359002 -148.37664) (xy 58.717688 -148.37664)
			(xy 58.717688 -149.412198) (xy 69.012814 -149.412198) (xy 69.016885 -149.356576) (xy 69.029011 -149.302139)
			(xy 69.048934 -149.250048) (xy 69.07623 -149.201413) (xy 69.110316 -149.15727) (xy 69.150465 -149.118561)
			(xy 69.195823 -149.08611) (xy 69.245423 -149.060609) (xy 69.298207 -149.042602) (xy 69.35305 -149.032472)
			(xy 69.408784 -149.030435) (xy 69.464221 -149.036535) (xy 69.518178 -149.050641) (xy 69.569507 -149.072453)
			(xy 69.617113 -149.101507) (xy 69.659981 -149.137182) (xy 69.697198 -149.178719) (xy 69.727971 -149.225232)
			(xy 69.751643 -149.275729) (xy 69.767711 -149.329136) (xy 69.775831 -149.384312) (xy 69.77634 -149.412198)
			(xy 69.775831 -149.440084) (xy 69.767711 -149.49526) (xy 69.751643 -149.548667) (xy 69.727971 -149.599164)
			(xy 69.697198 -149.645677) (xy 69.659981 -149.687214) (xy 69.617113 -149.722889) (xy 69.569507 -149.751943)
			(xy 69.518178 -149.773755) (xy 69.464221 -149.787861) (xy 69.408784 -149.793961) (xy 69.35305 -149.791924)
			(xy 69.298207 -149.781794) (xy 69.245423 -149.763787) (xy 69.195823 -149.738286) (xy 69.150465 -149.705835)
			(xy 69.110316 -149.667126) (xy 69.07623 -149.622983) (xy 69.048934 -149.574348) (xy 69.029011 -149.522257)
			(xy 69.016885 -149.46782) (xy 69.012814 -149.412198) (xy 58.717688 -149.412198) (xy 58.717688 -154.528012)
			(xy 67.588636 -154.528012) (xy 67.592707 -154.47239) (xy 67.604833 -154.417953) (xy 67.624756 -154.365862)
			(xy 67.652052 -154.317227) (xy 67.686138 -154.273084) (xy 67.726287 -154.234375) (xy 67.771645 -154.201924)
			(xy 67.821245 -154.176423) (xy 67.874029 -154.158416) (xy 67.928872 -154.148286) (xy 67.984606 -154.146249)
			(xy 68.040043 -154.152349) (xy 68.094 -154.166455) (xy 68.145329 -154.188267) (xy 68.192935 -154.217321)
			(xy 68.235803 -154.252996) (xy 68.27302 -154.294533) (xy 68.303793 -154.341046) (xy 68.327465 -154.391543)
			(xy 68.343533 -154.44495) (xy 68.351653 -154.500126) (xy 68.352162 -154.528012) (xy 68.351653 -154.555898)
			(xy 68.343533 -154.611074) (xy 68.327465 -154.664481) (xy 68.303793 -154.714978) (xy 68.27302 -154.761491)
			(xy 68.235803 -154.803028) (xy 68.192935 -154.838703) (xy 68.145329 -154.867757) (xy 68.094 -154.889569)
			(xy 68.040043 -154.903675) (xy 67.984606 -154.909775) (xy 67.928872 -154.907738) (xy 67.874029 -154.897608)
			(xy 67.821245 -154.879601) (xy 67.771645 -154.8541) (xy 67.726287 -154.821649) (xy 67.686138 -154.78294)
			(xy 67.652052 -154.738797) (xy 67.624756 -154.690162) (xy 67.604833 -154.638071) (xy 67.592707 -154.583634)
			(xy 67.588636 -154.528012) (xy 58.717688 -154.528012) (xy 58.717688 -155.698952) (xy 58.71812 -155.709018)
			(xy 58.725846 -155.72761) (xy 58.732674 -155.73502) (xy 59.103514 -156.10586) (xy 59.11036 -156.113258)
			(xy 59.118086 -156.131857) (xy 59.1185 -156.141928) (xy 59.1185 -157.653736) (xy 59.118994 -157.663739)
			(xy 59.12666 -157.682218) (xy 59.140812 -157.69636) (xy 59.159297 -157.704013) (xy 59.1693 -157.704536)
			(xy 78.41361 -157.704536) (xy 78.421948 -157.703553) (xy 78.437362 -157.69693) (xy 78.443836 -157.691582)
			(xy 79.395828 -156.73959) (xy 80.596486 -155.538932) (xy 80.596994 -155.538424) (xy 80.603568 -155.53104)
			(xy 80.611004 -155.512741) (xy 80.611472 -155.502864) (xy 80.611472 -149.955504) (xy 80.611472 -149.51202)
			(xy 80.612028 -149.482039) (xy 80.621409 -149.422816) (xy 80.639943 -149.365792) (xy 80.667174 -149.31237)
			(xy 80.702429 -149.263868) (xy 80.723232 -149.242272) (xy 85.70722 -144.258284) (xy 85.728834 -144.237503)
			(xy 85.777339 -144.202261) (xy 85.830757 -144.175037) (xy 85.887775 -144.156499) (xy 85.94699 -144.147104)
			(xy 85.976968 -144.146524) (xy 86.411308 -144.146524) (xy 87.837264 -144.146524) (xy 87.847138 -144.146057)
			(xy 87.865427 -144.138604) (xy 87.872824 -144.132046) (xy 87.873078 -144.131792) (xy 87.96655 -144.038574)
			(xy 87.990066 -144.015964) (xy 88.043322 -143.978297) (xy 88.072468 -143.963644) (xy 88.081358 -143.95958)
			(xy 88.218772 -143.822166) (xy 88.240139 -143.801655) (xy 88.288391 -143.767312) (xy 88.341659 -143.741426)
			(xy 88.369902 -143.732504) (xy 88.38184 -143.728948) (xy 88.399112 -143.712692) (xy 88.435688 -143.613632)
			(xy 88.433148 -143.59001) (xy 88.426544 -143.57985) (xy 88.412058 -143.556586) (xy 88.389179 -143.506787)
			(xy 88.373661 -143.454227) (xy 88.365822 -143.399988) (xy 88.36533 -143.372586) (xy 88.365816 -143.345335)
			(xy 88.373572 -143.291387) (xy 88.388927 -143.239092) (xy 88.411569 -143.189515) (xy 88.441035 -143.143665)
			(xy 88.476726 -143.102474) (xy 88.517917 -143.066783) (xy 88.563767 -143.037317) (xy 88.613344 -143.014675)
			(xy 88.665639 -142.99932) (xy 88.719587 -142.991564) (xy 88.774089 -142.991564) (xy 88.828037 -142.99932)
			(xy 88.880332 -143.014675) (xy 88.929909 -143.037317) (xy 88.975759 -143.066783) (xy 88.997143 -143.085312)
			(xy 100.117908 -143.085312) (xy 100.121979 -143.02969) (xy 100.134105 -142.975253) (xy 100.154028 -142.923162)
			(xy 100.181324 -142.874527) (xy 100.21541 -142.830384) (xy 100.255559 -142.791675) (xy 100.300917 -142.759224)
			(xy 100.350517 -142.733723) (xy 100.403301 -142.715716) (xy 100.458144 -142.705586) (xy 100.513878 -142.703549)
			(xy 100.569315 -142.709649) (xy 100.623272 -142.723755) (xy 100.674601 -142.745567) (xy 100.722207 -142.774621)
			(xy 100.765075 -142.810296) (xy 100.802292 -142.851833) (xy 100.833065 -142.898346) (xy 100.856737 -142.948843)
			(xy 100.872805 -143.00225) (xy 100.880925 -143.057426) (xy 100.881434 -143.085312) (xy 100.880925 -143.113198)
			(xy 100.872805 -143.168374) (xy 100.856737 -143.221781) (xy 100.833065 -143.272278) (xy 100.802292 -143.318791)
			(xy 100.765075 -143.360328) (xy 100.722207 -143.396003) (xy 100.674601 -143.425057) (xy 100.623272 -143.446869)
			(xy 100.569315 -143.460975) (xy 100.513878 -143.467075) (xy 100.458144 -143.465038) (xy 100.403301 -143.454908)
			(xy 100.350517 -143.436901) (xy 100.300917 -143.4114) (xy 100.255559 -143.378949) (xy 100.21541 -143.34024)
			(xy 100.181324 -143.296097) (xy 100.154028 -143.247462) (xy 100.134105 -143.195371) (xy 100.121979 -143.140934)
			(xy 100.117908 -143.085312) (xy 88.997143 -143.085312) (xy 89.01695 -143.102474) (xy 89.052641 -143.143665)
			(xy 89.082107 -143.189515) (xy 89.104749 -143.239092) (xy 89.120104 -143.291387) (xy 89.12786 -143.345335)
			(xy 89.128346 -143.372586) (xy 89.127785 -143.402671) (xy 89.118337 -143.462095) (xy 89.099657 -143.519292)
			(xy 89.086436 -143.546322) (xy 89.083896 -143.551656) (xy 89.081356 -143.56207) (xy 89.079097 -143.57386)
			(xy 89.084518 -143.59721) (xy 89.09177 -143.606774) (xy 89.099644 -143.616172) (xy 89.121742 -143.62557)
			(xy 89.136728 -143.624554) (xy 89.13876 -143.6243) (xy 89.152461 -143.622405) (xy 89.180047 -143.620373)
			(xy 89.193878 -143.620236) (xy 89.425526 -143.620236) (xy 89.455509 -143.620788) (xy 89.514737 -143.630161)
			(xy 89.571768 -143.648688) (xy 89.625197 -143.675911) (xy 89.673707 -143.711161) (xy 89.695274 -143.731996)
			(xy 90.006032 -144.042754) (xy 90.855738 -144.042754) (xy 90.855738 -143.988246) (xy 90.863495 -143.934293)
			(xy 90.878852 -143.881992) (xy 90.901495 -143.83241) (xy 90.930965 -143.786555) (xy 90.96666 -143.74536)
			(xy 91.007855 -143.709665) (xy 91.05371 -143.680195) (xy 91.103292 -143.657552) (xy 91.155593 -143.642195)
			(xy 91.209546 -143.634438) (xy 91.2368 -143.633952) (xy 91.26329 -143.634388) (xy 91.315759 -143.641738)
			(xy 91.366705 -143.65628) (xy 91.415147 -143.677737) (xy 91.460151 -143.705694) (xy 91.500851 -143.739612)
			(xy 91.518994 -143.75892) (xy 91.52822 -143.768469) (xy 91.550551 -143.782819) (xy 91.575827 -143.790926)
			(xy 91.602338 -143.792242) (xy 91.628293 -143.786678) (xy 91.651935 -143.77461) (xy 91.671666 -143.756854)
			(xy 91.679268 -143.745966) (xy 91.694495 -143.723592) (xy 91.730189 -143.682913) (xy 91.771271 -143.647684)
			(xy 91.816917 -143.618611) (xy 91.866212 -143.596277) (xy 91.918167 -143.581129) (xy 91.971741 -143.573471)
			(xy 91.9988 -143.572992) (xy 92.026051 -143.573478) (xy 92.079999 -143.581234) (xy 92.132294 -143.596589)
			(xy 92.181871 -143.619231) (xy 92.227721 -143.648697) (xy 92.228585 -143.649446) (xy 112.505996 -143.649446)
			(xy 112.510067 -143.593824) (xy 112.522193 -143.539387) (xy 112.542116 -143.487296) (xy 112.569412 -143.438661)
			(xy 112.603498 -143.394518) (xy 112.643647 -143.355809) (xy 112.689005 -143.323358) (xy 112.738605 -143.297857)
			(xy 112.791389 -143.27985) (xy 112.846232 -143.26972) (xy 112.901966 -143.267683) (xy 112.957403 -143.273783)
			(xy 113.01136 -143.287889) (xy 113.062689 -143.309701) (xy 113.110295 -143.338755) (xy 113.153163 -143.37443)
			(xy 113.19038 -143.415967) (xy 113.221153 -143.46248) (xy 113.244825 -143.512977) (xy 113.260893 -143.566384)
			(xy 113.269013 -143.62156) (xy 113.269522 -143.649446) (xy 113.269013 -143.677332) (xy 113.260893 -143.732508)
			(xy 113.244825 -143.785915) (xy 113.221153 -143.836412) (xy 113.19038 -143.882925) (xy 113.153163 -143.924462)
			(xy 113.110295 -143.960137) (xy 113.062689 -143.989191) (xy 113.01136 -144.011003) (xy 112.957403 -144.025109)
			(xy 112.901966 -144.031209) (xy 112.846232 -144.029172) (xy 112.791389 -144.019042) (xy 112.738605 -144.001035)
			(xy 112.689005 -143.975534) (xy 112.643647 -143.943083) (xy 112.603498 -143.904374) (xy 112.569412 -143.860231)
			(xy 112.542116 -143.811596) (xy 112.522193 -143.759505) (xy 112.510067 -143.705068) (xy 112.505996 -143.649446)
			(xy 92.228585 -143.649446) (xy 92.268912 -143.684388) (xy 92.304603 -143.725579) (xy 92.334069 -143.771429)
			(xy 92.356711 -143.821006) (xy 92.372066 -143.873301) (xy 92.379822 -143.927249) (xy 92.379822 -143.981751)
			(xy 92.372066 -144.035699) (xy 92.356711 -144.087994) (xy 92.334069 -144.137571) (xy 92.304603 -144.183421)
			(xy 92.268912 -144.224612) (xy 92.227721 -144.260303) (xy 92.181871 -144.289769) (xy 92.132294 -144.312411)
			(xy 92.079999 -144.327766) (xy 92.026051 -144.335522) (xy 91.9988 -144.336008) (xy 91.972309 -144.335585)
			(xy 91.919839 -144.328235) (xy 91.868893 -144.31369) (xy 91.820451 -144.292231) (xy 91.775447 -144.264272)
			(xy 91.734748 -144.23035) (xy 91.716606 -144.21104) (xy 91.705788 -144.199934) (xy 91.679009 -144.184333)
			(xy 91.648787 -144.177468) (xy 91.617896 -144.179968) (xy 91.589172 -144.191605) (xy 91.565251 -144.21131)
			(xy 91.556332 -144.223994) (xy 91.541125 -144.246382) (xy 91.505425 -144.287057) (xy 91.464339 -144.322283)
			(xy 91.418689 -144.351353) (xy 91.369392 -144.373686) (xy 91.317435 -144.388832) (xy 91.26386 -144.396489)
			(xy 91.2368 -144.396968) (xy 91.209546 -144.396562) (xy 91.155593 -144.388805) (xy 91.103292 -144.373448)
			(xy 91.05371 -144.350805) (xy 91.007855 -144.321335) (xy 90.96666 -144.28564) (xy 90.930965 -144.244445)
			(xy 90.901495 -144.19859) (xy 90.878852 -144.149008) (xy 90.863495 -144.096707) (xy 90.855738 -144.042754)
			(xy 90.006032 -144.042754) (xy 90.651076 -144.687798) (xy 90.651584 -144.688306) (xy 90.658965 -144.694889)
			(xy 90.677264 -144.702335) (xy 90.687144 -144.702784) (xy 91.047316 -144.702784) (xy 91.057282 -144.702307)
			(xy 91.075718 -144.69473) (xy 91.08313 -144.688052) (xy 91.10476 -144.667303) (xy 91.153282 -144.632123)
			(xy 91.206704 -144.604952) (xy 91.263713 -144.586458) (xy 91.322911 -144.577095) (xy 91.352878 -144.576546)
			(xy 91.365832 -144.5768) (xy 92.008198 -144.5768) (xy 92.038178 -144.577358) (xy 92.097399 -144.586742)
			(xy 92.154421 -144.605279) (xy 92.207839 -144.632513) (xy 92.256337 -144.667771) (xy 92.277946 -144.68856)
			(xy 92.68206 -145.092928) (xy 92.683841 -145.094706) (xy 99.562666 -145.094706) (xy 99.563113 -145.068765)
			(xy 99.570142 -145.017363) (xy 99.584073 -144.967387) (xy 99.604648 -144.919759) (xy 99.631486 -144.875359)
			(xy 99.664094 -144.835006) (xy 99.70187 -144.799444) (xy 99.744116 -144.769329) (xy 99.766882 -144.756886)
			(xy 99.776788 -144.751806) (xy 99.789996 -144.735042) (xy 99.813618 -144.639792) (xy 99.809808 -144.61871)
			(xy 99.803712 -144.609566) (xy 99.788026 -144.585661) (xy 99.763183 -144.534166) (xy 99.746289 -144.479544)
			(xy 99.737722 -144.423015) (xy 99.737164 -144.394428) (xy 99.73765 -144.367177) (xy 99.745406 -144.313229)
			(xy 99.760761 -144.260934) (xy 99.783403 -144.211357) (xy 99.812869 -144.165507) (xy 99.84856 -144.124316)
			(xy 99.889751 -144.088625) (xy 99.935601 -144.059159) (xy 99.985178 -144.036517) (xy 100.037473 -144.021162)
			(xy 100.091421 -144.013406) (xy 100.145923 -144.013406) (xy 100.199871 -144.021162) (xy 100.252166 -144.036517)
			(xy 100.301743 -144.059159) (xy 100.347593 -144.088625) (xy 100.365166 -144.103852) (xy 102.455216 -144.103852)
			(xy 102.459287 -144.04823) (xy 102.471413 -143.993793) (xy 102.491336 -143.941702) (xy 102.518632 -143.893067)
			(xy 102.552718 -143.848924) (xy 102.592867 -143.810215) (xy 102.638225 -143.777764) (xy 102.687825 -143.752263)
			(xy 102.740609 -143.734256) (xy 102.795452 -143.724126) (xy 102.851186 -143.722089) (xy 102.906623 -143.728189)
			(xy 102.96058 -143.742295) (xy 103.011909 -143.764107) (xy 103.059515 -143.793161) (xy 103.102383 -143.828836)
			(xy 103.1396 -143.870373) (xy 103.170373 -143.916886) (xy 103.194045 -143.967383) (xy 103.210113 -144.02079)
			(xy 103.218233 -144.075966) (xy 103.218742 -144.103852) (xy 103.218233 -144.131738) (xy 103.210113 -144.186914)
			(xy 103.194045 -144.240321) (xy 103.170373 -144.290818) (xy 103.1396 -144.337331) (xy 103.102383 -144.378868)
			(xy 103.059515 -144.414543) (xy 103.011909 -144.443597) (xy 102.96058 -144.465409) (xy 102.906623 -144.479515)
			(xy 102.851186 -144.485615) (xy 102.795452 -144.483578) (xy 102.740609 -144.473448) (xy 102.687825 -144.455441)
			(xy 102.638225 -144.42994) (xy 102.592867 -144.397489) (xy 102.552718 -144.35878) (xy 102.518632 -144.314637)
			(xy 102.491336 -144.266002) (xy 102.471413 -144.213911) (xy 102.459287 -144.159474) (xy 102.455216 -144.103852)
			(xy 100.365166 -144.103852) (xy 100.388784 -144.124316) (xy 100.424475 -144.165507) (xy 100.453941 -144.211357)
			(xy 100.476583 -144.260934) (xy 100.491938 -144.313229) (xy 100.499694 -144.367177) (xy 100.50018 -144.394428)
			(xy 100.49979 -144.420371) (xy 100.492755 -144.471777) (xy 100.478818 -144.521756) (xy 100.458236 -144.569385)
			(xy 100.431389 -144.613785) (xy 100.398773 -144.654138) (xy 100.360989 -144.689697) (xy 100.318734 -144.719808)
			(xy 100.295964 -144.732248) (xy 100.286058 -144.737328) (xy 100.27285 -144.754092) (xy 100.249228 -144.849342)
			(xy 100.253038 -144.870424) (xy 100.259134 -144.879568) (xy 100.274797 -144.903487) (xy 100.299645 -144.954978)
			(xy 100.316544 -145.009595) (xy 100.325119 -145.06612) (xy 100.325682 -145.094706) (xy 100.325346 -145.117825)
			(xy 100.31978 -145.163725) (xy 100.308693 -145.208614) (xy 100.30079 -145.230342) (xy 100.296218 -145.242026)
			(xy 100.298758 -145.265902) (xy 100.357178 -145.35531) (xy 100.378006 -145.367502) (xy 100.390198 -145.36801)
			(xy 100.419095 -145.370045) (xy 100.475808 -145.38185) (xy 100.530086 -145.402092) (xy 100.58068 -145.430305)
			(xy 100.626428 -145.465842) (xy 100.66628 -145.507885) (xy 100.699318 -145.555469) (xy 100.724785 -145.6075)
			(xy 100.742094 -145.662782) (xy 100.750849 -145.720046) (xy 100.751386 -145.74901) (xy 100.7509 -145.776261)
			(xy 100.743144 -145.830209) (xy 100.727789 -145.882504) (xy 100.705147 -145.932081) (xy 100.675681 -145.977931)
			(xy 100.63999 -146.019122) (xy 100.598799 -146.054813) (xy 100.552949 -146.084279) (xy 100.503372 -146.106921)
			(xy 100.451077 -146.122276) (xy 100.397129 -146.130032) (xy 100.342627 -146.130032) (xy 100.288679 -146.122276)
			(xy 100.236384 -146.106921) (xy 100.186807 -146.084279) (xy 100.140957 -146.054813) (xy 100.099766 -146.019122)
			(xy 100.064075 -145.977931) (xy 100.034609 -145.932081) (xy 100.011967 -145.882504) (xy 99.996612 -145.830209)
			(xy 99.988856 -145.776261) (xy 99.98837 -145.74901) (xy 99.988678 -145.72589) (xy 99.994255 -145.679989)
			(xy 100.005353 -145.635101) (xy 100.013262 -145.613374) (xy 100.017834 -145.60169) (xy 100.015294 -145.577814)
			(xy 99.956874 -145.488406) (xy 99.936046 -145.476214) (xy 99.923854 -145.475706) (xy 99.894962 -145.47361)
			(xy 99.838252 -145.461813) (xy 99.783976 -145.441579) (xy 99.733382 -145.413373) (xy 99.687633 -145.377844)
			(xy 99.647781 -145.335808) (xy 99.614741 -145.28823) (xy 99.589273 -145.236205) (xy 99.571961 -145.180927)
			(xy 99.563204 -145.123668) (xy 99.562666 -145.094706) (xy 92.683841 -145.094706) (xy 92.835222 -145.245836)
			(xy 92.856014 -145.267431) (xy 92.891228 -145.315943) (xy 92.918412 -145.369371) (xy 92.936895 -145.426395)
			(xy 92.946221 -145.485611) (xy 92.946728 -145.515584) (xy 92.946728 -146.771614) (xy 92.947154 -146.781682)
			(xy 92.954875 -146.800281) (xy 92.961714 -146.807682) (xy 93.054424 -146.900392) (xy 93.172026 -147.01774)
			(xy 93.179439 -147.024416) (xy 93.197875 -147.031982) (xy 93.20784 -147.032472) (xy 101.372924 -147.032472)
			(xy 101.382889 -147.031993) (xy 101.401322 -147.024413) (xy 101.408738 -147.01774) (xy 101.77399 -146.652742)
			(xy 102.064566 -146.361912) (xy 102.069974 -146.35548) (xy 102.076581 -146.340038) (xy 102.07752 -146.331686)
			(xy 102.07752 -145.673064) (xy 102.078006 -145.645831) (xy 102.085757 -145.591919) (xy 102.101102 -145.539659)
			(xy 102.123728 -145.490115) (xy 102.153175 -145.444295) (xy 102.188842 -145.403132) (xy 102.230005 -145.367465)
			(xy 102.275825 -145.338018) (xy 102.325369 -145.315392) (xy 102.377629 -145.300047) (xy 102.431541 -145.292296)
			(xy 102.486007 -145.292296) (xy 102.539919 -145.300047) (xy 102.592179 -145.315392) (xy 102.641723 -145.338018)
			(xy 102.687543 -145.367465) (xy 102.728706 -145.403132) (xy 102.762759 -145.442432) (xy 103.786176 -145.442432)
			(xy 103.790247 -145.38681) (xy 103.802373 -145.332373) (xy 103.822296 -145.280282) (xy 103.849592 -145.231647)
			(xy 103.883678 -145.187504) (xy 103.923827 -145.148795) (xy 103.969185 -145.116344) (xy 104.018785 -145.090843)
			(xy 104.071569 -145.072836) (xy 104.126412 -145.062706) (xy 104.182146 -145.060669) (xy 104.237583 -145.066769)
			(xy 104.29154 -145.080875) (xy 104.342869 -145.102687) (xy 104.390475 -145.131741) (xy 104.433343 -145.167416)
			(xy 104.47056 -145.208953) (xy 104.501333 -145.255466) (xy 104.525005 -145.305963) (xy 104.541073 -145.35937)
			(xy 104.549193 -145.414546) (xy 104.549702 -145.442432) (xy 104.549193 -145.470318) (xy 104.541073 -145.525494)
			(xy 104.525005 -145.578901) (xy 104.501333 -145.629398) (xy 104.47056 -145.675911) (xy 104.433343 -145.717448)
			(xy 104.390475 -145.753123) (xy 104.342869 -145.782177) (xy 104.29154 -145.803989) (xy 104.237583 -145.818095)
			(xy 104.182146 -145.824195) (xy 104.126412 -145.822158) (xy 104.071569 -145.812028) (xy 104.018785 -145.794021)
			(xy 103.969185 -145.76852) (xy 103.923827 -145.736069) (xy 103.883678 -145.69736) (xy 103.849592 -145.653217)
			(xy 103.822296 -145.604582) (xy 103.802373 -145.552491) (xy 103.790247 -145.498054) (xy 103.786176 -145.442432)
			(xy 102.762759 -145.442432) (xy 102.764373 -145.444295) (xy 102.79382 -145.490115) (xy 102.816446 -145.539659)
			(xy 102.831791 -145.591919) (xy 102.839542 -145.645831) (xy 102.840028 -145.673064) (xy 102.840028 -146.5072)
			(xy 102.839457 -146.537167) (xy 102.830116 -146.596369) (xy 102.811634 -146.653383) (xy 102.784463 -146.706804)
			(xy 102.749274 -146.755321) (xy 102.728522 -146.776948) (xy 102.06101 -147.44446) (xy 103.134414 -147.44446)
			(xy 103.134842 -147.418796) (xy 103.14171 -147.367929) (xy 103.155345 -147.318446) (xy 103.175498 -147.27124)
			(xy 103.201806 -147.227166) (xy 103.233791 -147.187023) (xy 103.270876 -147.151537) (xy 103.291386 -147.136104)
			(xy 103.302172 -147.127651) (xy 103.319255 -147.106243) (xy 103.330025 -147.081061) (xy 103.333708 -147.053921)
			(xy 103.330036 -147.026779) (xy 103.319276 -147.001593) (xy 103.302202 -146.980177) (xy 103.291386 -146.971766)
			(xy 103.267495 -146.953705) (xy 103.225182 -146.911322) (xy 103.190012 -146.862847) (xy 103.162849 -146.809472)
			(xy 103.14436 -146.752508) (xy 103.135 -146.693355) (xy 103.134414 -146.66341) (xy 103.1349 -146.636159)
			(xy 103.142656 -146.582211) (xy 103.158011 -146.529916) (xy 103.180653 -146.480339) (xy 103.210119 -146.434489)
			(xy 103.24581 -146.393298) (xy 103.287001 -146.357607) (xy 103.332851 -146.328141) (xy 103.382428 -146.305499)
			(xy 103.434723 -146.290144) (xy 103.488671 -146.282388) (xy 103.543173 -146.282388) (xy 103.597121 -146.290144)
			(xy 103.649416 -146.305499) (xy 103.698993 -146.328141) (xy 103.744843 -146.357607) (xy 103.786034 -146.393298)
			(xy 103.821725 -146.434489) (xy 103.84103 -146.464528) (xy 115.805966 -146.464528) (xy 115.806432 -146.437158)
			(xy 115.814248 -146.382978) (xy 115.829736 -146.330474) (xy 115.852578 -146.280727) (xy 115.882304 -146.234761)
			(xy 115.899946 -146.21383) (xy 115.906042 -146.206718) (xy 115.912392 -146.1897) (xy 115.912392 -146.104356)
			(xy 115.906042 -146.087338) (xy 115.899946 -146.080226) (xy 115.882332 -146.059271) (xy 115.852605 -146.013308)
			(xy 115.829756 -145.963565) (xy 115.814257 -145.911066) (xy 115.806426 -145.856891) (xy 115.806422 -145.802152)
			(xy 115.814248 -145.747975) (xy 115.829742 -145.695474) (xy 115.852584 -145.645729) (xy 115.882307 -145.599762)
			(xy 115.899946 -145.57883) (xy 115.906042 -145.571718) (xy 115.912392 -145.5547) (xy 115.912392 -145.469356)
			(xy 115.906042 -145.452338) (xy 115.899946 -145.445226) (xy 115.882332 -145.424271) (xy 115.852605 -145.378308)
			(xy 115.829756 -145.328565) (xy 115.814257 -145.276066) (xy 115.806426 -145.221891) (xy 115.806422 -145.167152)
			(xy 115.814248 -145.112975) (xy 115.829742 -145.060474) (xy 115.852584 -145.010729) (xy 115.882307 -144.964762)
			(xy 115.899946 -144.94383) (xy 115.906042 -144.936718) (xy 115.912392 -144.9197) (xy 115.912392 -144.834356)
			(xy 115.906042 -144.817338) (xy 115.899946 -144.810226) (xy 115.882332 -144.789271) (xy 115.852605 -144.743308)
			(xy 115.829756 -144.693565) (xy 115.814257 -144.641066) (xy 115.806426 -144.586891) (xy 115.806422 -144.532152)
			(xy 115.814248 -144.477975) (xy 115.829742 -144.425474) (xy 115.852584 -144.375729) (xy 115.882307 -144.329762)
			(xy 115.899946 -144.30883) (xy 115.906042 -144.301718) (xy 115.912392 -144.2847) (xy 115.912392 -144.199356)
			(xy 115.906042 -144.182338) (xy 115.899946 -144.175226) (xy 115.882313 -144.154289) (xy 115.852598 -144.108318)
			(xy 115.829761 -144.058572) (xy 115.814268 -144.006072) (xy 115.80644 -143.951897) (xy 115.805966 -143.924528)
			(xy 115.806481 -143.897277) (xy 115.814234 -143.843329) (xy 115.829585 -143.791034) (xy 115.852222 -143.741456)
			(xy 115.881685 -143.695604) (xy 115.917373 -143.654411) (xy 115.95856 -143.618717) (xy 116.004408 -143.589248)
			(xy 116.053983 -143.566604) (xy 116.106276 -143.551245) (xy 116.160223 -143.543485) (xy 116.187474 -143.54302)
			(xy 116.214844 -143.543496) (xy 116.269023 -143.551311) (xy 116.321526 -143.566797) (xy 116.371273 -143.589637)
			(xy 116.41724 -143.61936) (xy 116.438172 -143.637) (xy 116.445284 -143.643096) (xy 116.462302 -143.649446)
			(xy 116.547646 -143.649446) (xy 116.564664 -143.643096) (xy 116.571776 -143.637) (xy 116.592706 -143.619359)
			(xy 116.63868 -143.589647) (xy 116.688428 -143.566812) (xy 116.740929 -143.551321) (xy 116.795105 -143.543494)
			(xy 116.822474 -143.54302) (xy 116.850048 -143.543497) (xy 116.904621 -143.551446) (xy 116.957481 -143.567168)
			(xy 117.007527 -143.590336) (xy 117.053717 -143.620467) (xy 117.095088 -143.656933) (xy 117.113304 -143.67764)
			(xy 117.120903 -143.685762) (xy 117.141057 -143.695113) (xy 117.152166 -143.695674) (xy 117.229382 -143.695674)
			(xy 117.240494 -143.69512) (xy 117.260653 -143.685773) (xy 117.268244 -143.67764) (xy 117.28649 -143.656961)
			(xy 117.32785 -143.620486) (xy 117.374033 -143.590349) (xy 117.424074 -143.567177) (xy 117.476931 -143.551455)
			(xy 117.531501 -143.543509) (xy 117.559074 -143.54302) (xy 117.586444 -143.543496) (xy 117.640623 -143.551311)
			(xy 117.693126 -143.566797) (xy 117.742873 -143.589637) (xy 117.78884 -143.61936) (xy 117.809772 -143.637)
			(xy 117.816884 -143.643096) (xy 117.833902 -143.649446) (xy 117.919246 -143.649446) (xy 117.936264 -143.643096)
			(xy 117.943376 -143.637) (xy 117.964309 -143.619359) (xy 118.010277 -143.589635) (xy 118.060023 -143.566789)
			(xy 118.112525 -143.551293) (xy 118.166703 -143.543464) (xy 118.221445 -143.543464) (xy 118.275623 -143.551293)
			(xy 118.328125 -143.566789) (xy 118.377871 -143.589635) (xy 118.423839 -143.619359) (xy 118.444772 -143.637)
			(xy 118.451884 -143.643096) (xy 118.468902 -143.649446) (xy 118.554246 -143.649446) (xy 118.571264 -143.643096)
			(xy 118.578376 -143.637) (xy 118.599309 -143.619359) (xy 118.645277 -143.589635) (xy 118.695023 -143.566789)
			(xy 118.747525 -143.551293) (xy 118.801703 -143.543464) (xy 118.856445 -143.543464) (xy 118.910623 -143.551293)
			(xy 118.963125 -143.566789) (xy 119.012871 -143.589635) (xy 119.058839 -143.619359) (xy 119.079772 -143.637)
			(xy 119.086884 -143.643096) (xy 119.103902 -143.649446) (xy 119.189246 -143.649446) (xy 119.206264 -143.643096)
			(xy 119.213376 -143.637) (xy 119.234306 -143.619359) (xy 119.28028 -143.589647) (xy 119.330028 -143.566812)
			(xy 119.382529 -143.551321) (xy 119.436705 -143.543494) (xy 119.464074 -143.54302) (xy 119.491648 -143.543497)
			(xy 119.546221 -143.551446) (xy 119.599081 -143.567168) (xy 119.649127 -143.590336) (xy 119.695317 -143.620467)
			(xy 119.736688 -143.656933) (xy 119.754904 -143.67764) (xy 119.762503 -143.685762) (xy 119.782657 -143.695113)
			(xy 119.793766 -143.695674) (xy 119.870982 -143.695674) (xy 119.882094 -143.69512) (xy 119.902253 -143.685773)
			(xy 119.909844 -143.67764) (xy 119.92809 -143.656961) (xy 119.96945 -143.620486) (xy 120.015633 -143.590349)
			(xy 120.065674 -143.567177) (xy 120.118531 -143.551455) (xy 120.173101 -143.543509) (xy 120.200674 -143.54302)
			(xy 120.228044 -143.543496) (xy 120.282223 -143.551311) (xy 120.334726 -143.566797) (xy 120.384473 -143.589637)
			(xy 120.43044 -143.61936) (xy 120.451372 -143.637) (xy 120.458484 -143.643096) (xy 120.475502 -143.649446)
			(xy 120.560846 -143.649446) (xy 120.577864 -143.643096) (xy 120.584976 -143.637) (xy 120.605906 -143.619359)
			(xy 120.65188 -143.589647) (xy 120.701628 -143.566812) (xy 120.754129 -143.551321) (xy 120.808305 -143.543494)
			(xy 120.835674 -143.54302) (xy 120.862927 -143.54348) (xy 120.91688 -143.551234) (xy 120.96918 -143.566588)
			(xy 121.018762 -143.589229) (xy 121.064616 -143.618697) (xy 121.10581 -143.654392) (xy 121.141504 -143.695585)
			(xy 121.170972 -143.74144) (xy 121.193613 -143.791022) (xy 121.208967 -143.843322) (xy 121.216721 -143.897275)
			(xy 121.217182 -143.924528) (xy 121.216737 -143.951899) (xy 121.208915 -144.006079) (xy 121.193421 -144.058583)
			(xy 121.170574 -144.108329) (xy 121.140845 -144.154295) (xy 121.123202 -144.175226) (xy 121.117106 -144.182338)
			(xy 121.110756 -144.199356) (xy 121.110756 -144.2847) (xy 121.117106 -144.301718) (xy 121.123202 -144.30883)
			(xy 121.140869 -144.329741) (xy 121.17059 -144.375713) (xy 121.193432 -144.425463) (xy 121.208925 -144.477968)
			(xy 121.216751 -144.532149) (xy 121.216747 -144.586893) (xy 121.208916 -144.641073) (xy 121.193417 -144.693576)
			(xy 121.17057 -144.743324) (xy 121.140843 -144.789293) (xy 121.123202 -144.810226) (xy 121.117106 -144.817338)
			(xy 121.110756 -144.834356) (xy 121.110756 -144.9197) (xy 121.117106 -144.936718) (xy 121.123202 -144.94383)
			(xy 121.140869 -144.964741) (xy 121.17059 -145.010713) (xy 121.193432 -145.060463) (xy 121.208925 -145.112968)
			(xy 121.216751 -145.167149) (xy 121.216747 -145.221893) (xy 121.208916 -145.276073) (xy 121.193417 -145.328576)
			(xy 121.17057 -145.378324) (xy 121.140843 -145.424293) (xy 121.123202 -145.445226) (xy 121.117106 -145.452338)
			(xy 121.110756 -145.469356) (xy 121.110756 -145.5547) (xy 121.117106 -145.571718) (xy 121.123202 -145.57883)
			(xy 121.140869 -145.599741) (xy 121.17059 -145.645713) (xy 121.193432 -145.695463) (xy 121.208925 -145.747968)
			(xy 121.216751 -145.802149) (xy 121.216747 -145.856893) (xy 121.208916 -145.911073) (xy 121.193417 -145.963576)
			(xy 121.17057 -146.013324) (xy 121.140843 -146.059293) (xy 121.123202 -146.080226) (xy 121.117106 -146.087338)
			(xy 121.110756 -146.104356) (xy 121.110756 -146.1897) (xy 121.117106 -146.206718) (xy 121.123202 -146.21383)
			(xy 121.140822 -146.234777) (xy 121.170537 -146.280746) (xy 121.193376 -146.33049) (xy 121.208872 -146.382987)
			(xy 121.216705 -146.43716) (xy 121.217182 -146.464528) (xy 121.216748 -146.491781) (xy 121.208987 -146.545732)
			(xy 121.193627 -146.598029) (xy 121.170981 -146.647608) (xy 121.141509 -146.69346) (xy 121.105812 -146.734651)
			(xy 121.064617 -146.770342) (xy 121.018761 -146.799807) (xy 120.969179 -146.822446) (xy 120.916879 -146.837799)
			(xy 120.862927 -146.845552) (xy 120.835674 -146.846036) (xy 120.808302 -146.845601) (xy 120.754121 -146.837778)
			(xy 120.701617 -146.822282) (xy 120.651871 -146.799433) (xy 120.605906 -146.769701) (xy 120.584976 -146.752056)
			(xy 120.577864 -146.74596) (xy 120.560846 -146.73961) (xy 120.475502 -146.73961) (xy 120.458484 -146.74596)
			(xy 120.451372 -146.752056) (xy 120.430418 -146.769668) (xy 120.384452 -146.799385) (xy 120.33471 -146.822227)
			(xy 120.282214 -146.837725) (xy 120.228042 -146.845559) (xy 120.200674 -146.846036) (xy 120.173354 -146.845559)
			(xy 120.119273 -146.83776) (xy 120.066857 -146.822326) (xy 120.01718 -146.799573) (xy 119.971256 -146.769965)
			(xy 119.930026 -146.734109) (xy 119.894333 -146.692738) (xy 119.864907 -146.646698) (xy 119.853202 -146.622008)
			(xy 119.847106 -146.608292) (xy 119.82196 -146.592036) (xy 119.759984 -146.592036) (xy 119.741188 -146.59991)
			(xy 119.734076 -146.607022) (xy 119.714472 -146.626004) (xy 119.670814 -146.658738) (xy 119.622937 -146.684918)
			(xy 119.571819 -146.704009) (xy 119.518502 -146.715621) (xy 119.464074 -146.719519) (xy 119.409646 -146.715621)
			(xy 119.356329 -146.704009) (xy 119.305211 -146.684918) (xy 119.257334 -146.658738) (xy 119.213676 -146.626004)
			(xy 119.194072 -146.607022) (xy 119.18696 -146.59991) (xy 119.168164 -146.592036) (xy 119.124984 -146.592036)
			(xy 119.106188 -146.59991) (xy 119.099076 -146.607022) (xy 119.079472 -146.626004) (xy 119.035814 -146.658738)
			(xy 118.987937 -146.684918) (xy 118.936819 -146.704009) (xy 118.883502 -146.715621) (xy 118.829074 -146.719519)
			(xy 118.774646 -146.715621) (xy 118.721329 -146.704009) (xy 118.670211 -146.684918) (xy 118.622334 -146.658738)
			(xy 118.578676 -146.626004) (xy 118.559072 -146.607022) (xy 118.55196 -146.59991) (xy 118.533164 -146.592036)
			(xy 118.489984 -146.592036) (xy 118.471188 -146.59991) (xy 118.464076 -146.607022) (xy 118.444472 -146.626004)
			(xy 118.400814 -146.658738) (xy 118.352937 -146.684918) (xy 118.301819 -146.704009) (xy 118.248502 -146.715621)
			(xy 118.194074 -146.719519) (xy 118.139646 -146.715621) (xy 118.086329 -146.704009) (xy 118.035211 -146.684918)
			(xy 117.987334 -146.658738) (xy 117.943676 -146.626004) (xy 117.924072 -146.607022) (xy 117.91696 -146.59991)
			(xy 117.898164 -146.592036) (xy 117.854984 -146.592036) (xy 117.836188 -146.59991) (xy 117.829076 -146.607022)
			(xy 117.809472 -146.626004) (xy 117.765814 -146.658738) (xy 117.717937 -146.684918) (xy 117.666819 -146.704009)
			(xy 117.613502 -146.715621) (xy 117.559074 -146.719519) (xy 117.504646 -146.715621) (xy 117.451329 -146.704009)
			(xy 117.400211 -146.684918) (xy 117.352334 -146.658738) (xy 117.308676 -146.626004) (xy 117.289072 -146.607022)
			(xy 117.28196 -146.59991) (xy 117.263164 -146.592036) (xy 117.201188 -146.592036) (xy 117.176042 -146.608292)
			(xy 117.169946 -146.622008) (xy 117.158242 -146.6467) (xy 117.128821 -146.692745) (xy 117.093131 -146.734122)
			(xy 117.051901 -146.769981) (xy 117.005977 -146.799591) (xy 116.956297 -146.822344) (xy 116.903879 -146.837776)
			(xy 116.849795 -146.845569) (xy 116.822474 -146.846036) (xy 116.795102 -146.845601) (xy 116.740921 -146.837778)
			(xy 116.688417 -146.822282) (xy 116.638671 -146.799433) (xy 116.592706 -146.769701) (xy 116.571776 -146.752056)
			(xy 116.564664 -146.74596) (xy 116.547646 -146.73961) (xy 116.462302 -146.73961) (xy 116.445284 -146.74596)
			(xy 116.438172 -146.752056) (xy 116.417218 -146.769668) (xy 116.371252 -146.799385) (xy 116.32151 -146.822227)
			(xy 116.269014 -146.837725) (xy 116.214842 -146.845559) (xy 116.187474 -146.846036) (xy 116.160223 -146.845546)
			(xy 116.106277 -146.837787) (xy 116.053984 -146.82243) (xy 116.004409 -146.799788) (xy 115.95856 -146.770322)
			(xy 115.917371 -146.734631) (xy 115.88168 -146.693442) (xy 115.852213 -146.647593) (xy 115.829571 -146.598018)
			(xy 115.814213 -146.545725) (xy 115.806454 -146.491779) (xy 115.805966 -146.464528) (xy 103.84103 -146.464528)
			(xy 103.851191 -146.480339) (xy 103.873833 -146.529916) (xy 103.889188 -146.582211) (xy 103.896944 -146.636159)
			(xy 103.89743 -146.66341) (xy 103.897037 -146.689075) (xy 103.89016 -146.739942) (xy 103.876518 -146.789426)
			(xy 103.856359 -146.836632) (xy 103.830046 -146.880705) (xy 103.798057 -146.920847) (xy 103.760969 -146.956334)
			(xy 103.740458 -146.971766) (xy 103.729652 -146.980167) (xy 103.712661 -147.001617) (xy 103.701957 -147.026801)
			(xy 103.698306 -147.053921) (xy 103.701968 -147.081039) (xy 103.712682 -147.106219) (xy 103.729682 -147.127662)
			(xy 103.740458 -147.136104) (xy 103.764322 -147.154199) (xy 103.806639 -147.196573) (xy 103.841814 -147.24504)
			(xy 103.868982 -147.298409) (xy 103.887476 -147.355368) (xy 103.896841 -147.414517) (xy 103.89743 -147.44446)
			(xy 103.896944 -147.471711) (xy 103.889188 -147.525659) (xy 103.873833 -147.577954) (xy 103.851191 -147.627531)
			(xy 103.821725 -147.673381) (xy 103.786034 -147.714572) (xy 103.744843 -147.750263) (xy 103.698993 -147.779729)
			(xy 103.649416 -147.802371) (xy 103.597121 -147.817726) (xy 103.543173 -147.825482) (xy 103.488671 -147.825482)
			(xy 103.434723 -147.817726) (xy 103.382428 -147.802371) (xy 103.332851 -147.779729) (xy 103.287001 -147.750263)
			(xy 103.24581 -147.714572) (xy 103.210119 -147.673381) (xy 103.180653 -147.627531) (xy 103.158011 -147.577954)
			(xy 103.142656 -147.525659) (xy 103.1349 -147.471711) (xy 103.134414 -147.44446) (xy 102.06101 -147.44446)
			(xy 101.821742 -147.683728) (xy 101.800127 -147.704506) (xy 101.751621 -147.739742) (xy 101.698202 -147.76696)
			(xy 101.641184 -147.785492) (xy 101.581971 -147.79488) (xy 101.551994 -147.795488) (xy 93.02877 -147.795488)
			(xy 92.998788 -147.794935) (xy 92.939562 -147.78556) (xy 92.882533 -147.76703) (xy 92.829108 -147.739802)
			(xy 92.780603 -147.704548) (xy 92.759022 -147.683728) (xy 92.42298 -147.347686) (xy 92.295726 -147.220432)
			(xy 92.274933 -147.198837) (xy 92.239719 -147.150326) (xy 92.212537 -147.096898) (xy 92.194056 -147.039873)
			(xy 92.184733 -146.980657) (xy 92.18422 -146.950684) (xy 92.18422 -145.694654) (xy 92.183789 -145.684587)
			(xy 92.176065 -145.665993) (xy 92.169234 -145.658586) (xy 92.034868 -145.524474) (xy 91.865196 -145.354802)
			(xy 91.858084 -145.347436) (xy 91.839288 -145.339816) (xy 91.532456 -145.339816) (xy 91.522492 -145.340299)
			(xy 91.504064 -145.347882) (xy 91.496642 -145.354548) (xy 91.481358 -145.369433) (xy 91.448003 -145.396039)
			(xy 91.430094 -145.407634) (xy 91.42299 -145.412445) (xy 91.412252 -145.425814) (xy 91.406554 -145.441987)
			(xy 91.406218 -145.45056) (xy 91.406218 -145.536158) (xy 91.406539 -145.544707) (xy 91.412157 -145.560855)
			(xy 91.422782 -145.574251) (xy 91.42984 -145.579084) (xy 91.452788 -145.594146) (xy 91.494509 -145.629815)
			(xy 91.530682 -145.6711) (xy 91.560558 -145.717148) (xy 91.583519 -145.767005) (xy 91.599089 -145.81964)
			(xy 91.606948 -145.873965) (xy 91.607386 -145.90141) (xy 91.6069 -145.928661) (xy 91.599144 -145.982609)
			(xy 91.583789 -146.034904) (xy 91.561147 -146.084481) (xy 91.531681 -146.130331) (xy 91.49599 -146.171522)
			(xy 91.454799 -146.207213) (xy 91.408949 -146.236679) (xy 91.359372 -146.259321) (xy 91.307077 -146.274676)
			(xy 91.253129 -146.282432) (xy 91.198627 -146.282432) (xy 91.144679 -146.274676) (xy 91.092384 -146.259321)
			(xy 91.042807 -146.236679) (xy 90.996957 -146.207213) (xy 90.955766 -146.171522) (xy 90.920075 -146.130331)
			(xy 90.890609 -146.084481) (xy 90.867967 -146.034904) (xy 90.852612 -145.982609) (xy 90.844856 -145.928661)
			(xy 90.84437 -145.90141) (xy 90.844116 -145.90141) (xy 90.84467 -145.872221) (xy 90.853558 -145.814522)
			(xy 90.871129 -145.758851) (xy 90.896973 -145.706504) (xy 90.930487 -145.658703) (xy 90.950288 -145.63725)
			(xy 90.960956 -145.626074) (xy 90.96629 -145.596102) (xy 90.923618 -145.496534) (xy 90.919283 -145.48761)
			(xy 90.905146 -145.473718) (xy 90.886793 -145.466234) (xy 90.876882 -145.4658) (xy 90.508074 -145.4658)
			(xy 90.478092 -145.465247) (xy 90.418865 -145.455873) (xy 90.361836 -145.437344) (xy 90.30841 -145.410117)
			(xy 90.259903 -145.374864) (xy 90.238326 -145.35404) (xy 90.085418 -145.201132) (xy 89.746582 -144.862042)
			(xy 89.739522 -144.855498) (xy 89.721895 -144.847805) (xy 89.702671 -144.847197) (xy 89.693496 -144.850104)
			(xy 89.592912 -144.885918) (xy 89.574878 -144.908778) (xy 89.573354 -144.923764) (xy 89.570033 -144.95162)
			(xy 89.556268 -145.006004) (xy 89.534689 -145.057786) (xy 89.505762 -145.105851) (xy 89.470108 -145.149163)
			(xy 89.428498 -145.186788) (xy 89.381828 -145.217916) (xy 89.331103 -145.241875) (xy 89.277417 -145.258149)
			(xy 89.221927 -145.266389) (xy 89.193878 -145.266918) (xy 89.166628 -145.266431) (xy 89.112682 -145.258672)
			(xy 89.060389 -145.243315) (xy 89.010814 -145.220673) (xy 88.964965 -145.191206) (xy 88.923777 -145.155514)
			(xy 88.888087 -145.114325) (xy 88.858622 -145.068476) (xy 88.835981 -145.0189) (xy 88.820626 -144.966607)
			(xy 88.812868 -144.91266) (xy 88.81237 -144.88541) (xy 88.812786 -144.860041) (xy 88.819509 -144.809751)
			(xy 88.832839 -144.760795) (xy 88.85254 -144.714039) (xy 88.878265 -144.670306) (xy 88.909559 -144.630368)
			(xy 88.927432 -144.61236) (xy 88.934544 -144.605502) (xy 88.944196 -144.583404) (xy 88.94776 -144.574035)
			(xy 88.948007 -144.554007) (xy 88.944704 -144.544542) (xy 88.912446 -144.462246) (xy 88.906604 -144.447514)
			(xy 88.88095 -144.429988) (xy 88.639142 -144.429988) (xy 88.629179 -144.430473) (xy 88.610751 -144.438057)
			(xy 88.603328 -144.44472) (xy 88.584786 -144.463008) (xy 88.580722 -144.471898) (xy 88.566092 -144.501057)
			(xy 88.528413 -144.554308) (xy 88.505792 -144.577816) (xy 88.286082 -144.79778) (xy 88.264469 -144.818563)
			(xy 88.215965 -144.853808) (xy 88.162547 -144.881036) (xy 88.105528 -144.899575) (xy 88.046312 -144.908971)
			(xy 88.016334 -144.90954) (xy 86.599522 -144.90954) (xy 86.589459 -144.909979) (xy 86.570879 -144.917717)
			(xy 86.563454 -144.924526) (xy 86.079838 -145.408142) (xy 86.071477 -145.41741) (xy 86.064155 -145.441244)
			(xy 86.065868 -145.453608) (xy 86.083648 -145.548604) (xy 86.099396 -145.568162) (xy 86.11108 -145.573242)
			(xy 86.13421 -145.583793) (xy 86.177692 -145.610135) (xy 86.217291 -145.642018) (xy 86.252304 -145.678878)
			(xy 86.267544 -145.699226) (xy 86.275163 -145.708575) (xy 86.296647 -145.719455) (xy 86.308692 -145.720054)
			(xy 86.390988 -145.720054) (xy 86.403016 -145.71939) (xy 86.424483 -145.708529) (xy 86.432136 -145.699226)
			(xy 86.44756 -145.678629) (xy 86.483058 -145.641376) (xy 86.523243 -145.609236) (xy 86.567387 -145.582794)
			(xy 86.614686 -145.56253) (xy 86.664282 -145.548813) (xy 86.715271 -145.541891) (xy 86.741 -145.541492)
			(xy 86.768251 -145.541978) (xy 86.822199 -145.549734) (xy 86.874494 -145.565089) (xy 86.924071 -145.587731)
			(xy 86.969921 -145.617197) (xy 87.011112 -145.652888) (xy 87.046803 -145.694079) (xy 87.076269 -145.739929)
			(xy 87.098911 -145.789506) (xy 87.114266 -145.841801) (xy 87.122022 -145.895749) (xy 87.122022 -145.950251)
			(xy 87.114266 -146.004199) (xy 87.098911 -146.056494) (xy 87.076269 -146.106071) (xy 87.046803 -146.151921)
			(xy 87.011112 -146.193112) (xy 86.969921 -146.228803) (xy 86.924071 -146.258269) (xy 86.874494 -146.280911)
			(xy 86.822199 -146.296266) (xy 86.768251 -146.304022) (xy 86.741 -146.304508) (xy 86.715272 -146.304086)
			(xy 86.664283 -146.297166) (xy 86.614689 -146.283452) (xy 86.567389 -146.263192) (xy 86.523243 -146.236756)
			(xy 86.483053 -146.204623) (xy 86.44755 -146.167378) (xy 86.432136 -146.146774) (xy 86.424515 -146.137429)
			(xy 86.403031 -146.126556) (xy 86.390988 -146.125946) (xy 86.308692 -146.125946) (xy 86.296666 -146.126614)
			(xy 86.275206 -146.13748) (xy 86.267544 -146.146774) (xy 86.252119 -146.16737) (xy 86.216621 -146.204621)
			(xy 86.176435 -146.236759) (xy 86.132291 -146.263199) (xy 86.084992 -146.28346) (xy 86.035397 -146.297175)
			(xy 85.984408 -146.304094) (xy 85.95868 -146.304508) (xy 85.931012 -146.304013) (xy 85.876256 -146.296016)
			(xy 85.823231 -146.280192) (xy 85.773047 -146.256872) (xy 85.72676 -146.226548) (xy 85.685338 -146.189854)
			(xy 85.649653 -146.147561) (xy 85.620452 -146.100557) (xy 85.608922 -146.0754) (xy 85.603842 -146.063716)
			(xy 85.584284 -146.047968) (xy 85.489288 -146.030188) (xy 85.476918 -146.028429) (xy 85.453062 -146.03575)
			(xy 85.443822 -146.044158) (xy 84.54898 -146.939) (xy 86.612982 -146.939) (xy 86.617053 -146.883378)
			(xy 86.629179 -146.828941) (xy 86.649102 -146.77685) (xy 86.676398 -146.728215) (xy 86.710484 -146.684072)
			(xy 86.750633 -146.645363) (xy 86.795991 -146.612912) (xy 86.845591 -146.587411) (xy 86.898375 -146.569404)
			(xy 86.953218 -146.559274) (xy 87.008952 -146.557237) (xy 87.064389 -146.563337) (xy 87.118346 -146.577443)
			(xy 87.169675 -146.599255) (xy 87.217281 -146.628309) (xy 87.260149 -146.663984) (xy 87.297366 -146.705521)
			(xy 87.328139 -146.752034) (xy 87.351811 -146.802531) (xy 87.367879 -146.855938) (xy 87.375999 -146.911114)
			(xy 87.376508 -146.939) (xy 87.375999 -146.966886) (xy 87.367879 -147.022062) (xy 87.351811 -147.075469)
			(xy 87.328139 -147.125966) (xy 87.297366 -147.172479) (xy 87.260149 -147.214016) (xy 87.217281 -147.249691)
			(xy 87.169675 -147.278745) (xy 87.118346 -147.300557) (xy 87.064389 -147.314663) (xy 87.008952 -147.320763)
			(xy 86.953218 -147.318726) (xy 86.898375 -147.308596) (xy 86.845591 -147.290589) (xy 86.795991 -147.265088)
			(xy 86.750633 -147.232637) (xy 86.710484 -147.193928) (xy 86.676398 -147.149785) (xy 86.649102 -147.10115)
			(xy 86.629179 -147.049059) (xy 86.617053 -146.994622) (xy 86.612982 -146.939) (xy 84.54898 -146.939)
			(xy 83.53298 -147.955) (xy 86.612982 -147.955) (xy 86.617053 -147.899378) (xy 86.629179 -147.844941)
			(xy 86.649102 -147.79285) (xy 86.676398 -147.744215) (xy 86.710484 -147.700072) (xy 86.750633 -147.661363)
			(xy 86.795991 -147.628912) (xy 86.845591 -147.603411) (xy 86.898375 -147.585404) (xy 86.953218 -147.575274)
			(xy 87.008952 -147.573237) (xy 87.064389 -147.579337) (xy 87.118346 -147.593443) (xy 87.169675 -147.615255)
			(xy 87.217281 -147.644309) (xy 87.260149 -147.679984) (xy 87.297366 -147.721521) (xy 87.328139 -147.768034)
			(xy 87.351811 -147.818531) (xy 87.367879 -147.871938) (xy 87.375999 -147.927114) (xy 87.376508 -147.955)
			(xy 87.375999 -147.982886) (xy 87.367879 -148.038062) (xy 87.351811 -148.091469) (xy 87.328139 -148.141966)
			(xy 87.297366 -148.188479) (xy 87.260149 -148.230016) (xy 87.217281 -148.265691) (xy 87.169675 -148.294745)
			(xy 87.118346 -148.316557) (xy 87.064389 -148.330663) (xy 87.008952 -148.336763) (xy 86.953218 -148.334726)
			(xy 86.898375 -148.324596) (xy 86.845591 -148.306589) (xy 86.795991 -148.281088) (xy 86.750633 -148.248637)
			(xy 86.710484 -148.209928) (xy 86.676398 -148.165785) (xy 86.649102 -148.11715) (xy 86.629179 -148.065059)
			(xy 86.617053 -148.010622) (xy 86.612982 -147.955) (xy 83.53298 -147.955) (xy 83.023456 -148.464524)
			(xy 97.942144 -148.464524) (xy 97.946215 -148.408902) (xy 97.958341 -148.354465) (xy 97.978264 -148.302374)
			(xy 98.00556 -148.253739) (xy 98.039646 -148.209596) (xy 98.079795 -148.170887) (xy 98.125153 -148.138436)
			(xy 98.174753 -148.112935) (xy 98.227537 -148.094928) (xy 98.28238 -148.084798) (xy 98.338114 -148.082761)
			(xy 98.393551 -148.088861) (xy 98.447508 -148.102967) (xy 98.498837 -148.124779) (xy 98.546443 -148.153833)
			(xy 98.589311 -148.189508) (xy 98.626528 -148.231045) (xy 98.657301 -148.277558) (xy 98.680973 -148.328055)
			(xy 98.697041 -148.381462) (xy 98.705161 -148.436638) (xy 98.70567 -148.464524) (xy 98.705161 -148.49241)
			(xy 98.697041 -148.547586) (xy 98.680973 -148.600993) (xy 98.657301 -148.65149) (xy 98.626528 -148.698003)
			(xy 98.589311 -148.73954) (xy 98.546443 -148.775215) (xy 98.498837 -148.804269) (xy 98.447508 -148.826081)
			(xy 98.393551 -148.840187) (xy 98.338114 -148.846287) (xy 98.28238 -148.84425) (xy 98.227537 -148.83412)
			(xy 98.174753 -148.816113) (xy 98.125153 -148.790612) (xy 98.079795 -148.758161) (xy 98.039646 -148.719452)
			(xy 98.00556 -148.675309) (xy 97.978264 -148.626674) (xy 97.958341 -148.574583) (xy 97.946215 -148.520146)
			(xy 97.942144 -148.464524) (xy 83.023456 -148.464524) (xy 82.53857 -148.94941) (xy 88.81186 -148.94941)
			(xy 88.815931 -148.893788) (xy 88.828057 -148.839351) (xy 88.84798 -148.78726) (xy 88.875276 -148.738625)
			(xy 88.909362 -148.694482) (xy 88.949511 -148.655773) (xy 88.994869 -148.623322) (xy 89.044469 -148.597821)
			(xy 89.097253 -148.579814) (xy 89.152096 -148.569684) (xy 89.20783 -148.567647) (xy 89.263267 -148.573747)
			(xy 89.317224 -148.587853) (xy 89.368553 -148.609665) (xy 89.416159 -148.638719) (xy 89.459027 -148.674394)
			(xy 89.496244 -148.715931) (xy 89.527017 -148.762444) (xy 89.550689 -148.812941) (xy 89.56309 -148.85416)
			(xy 96.058988 -148.85416) (xy 96.063059 -148.798538) (xy 96.075185 -148.744101) (xy 96.095108 -148.69201)
			(xy 96.122404 -148.643375) (xy 96.15649 -148.599232) (xy 96.196639 -148.560523) (xy 96.241997 -148.528072)
			(xy 96.291597 -148.502571) (xy 96.344381 -148.484564) (xy 96.399224 -148.474434) (xy 96.454958 -148.472397)
			(xy 96.510395 -148.478497) (xy 96.564352 -148.492603) (xy 96.615681 -148.514415) (xy 96.663287 -148.543469)
			(xy 96.706155 -148.579144) (xy 96.743372 -148.620681) (xy 96.774145 -148.667194) (xy 96.797817 -148.717691)
			(xy 96.813885 -148.771098) (xy 96.822005 -148.826274) (xy 96.822514 -148.85416) (xy 96.822005 -148.882046)
			(xy 96.813885 -148.937222) (xy 96.797817 -148.990629) (xy 96.774145 -149.041126) (xy 96.743372 -149.087639)
			(xy 96.706155 -149.129176) (xy 96.663287 -149.164851) (xy 96.615681 -149.193905) (xy 96.564352 -149.215717)
			(xy 96.510395 -149.229823) (xy 96.454958 -149.235923) (xy 96.399224 -149.233886) (xy 96.344381 -149.223756)
			(xy 96.291597 -149.205749) (xy 96.241997 -149.180248) (xy 96.196639 -149.147797) (xy 96.15649 -149.109088)
			(xy 96.122404 -149.064945) (xy 96.095108 -149.01631) (xy 96.075185 -148.964219) (xy 96.063059 -148.909782)
			(xy 96.058988 -148.85416) (xy 89.56309 -148.85416) (xy 89.566757 -148.866348) (xy 89.574877 -148.921524)
			(xy 89.575386 -148.94941) (xy 89.574877 -148.977296) (xy 89.566757 -149.032472) (xy 89.550689 -149.085879)
			(xy 89.527017 -149.136376) (xy 89.496244 -149.182889) (xy 89.459027 -149.224426) (xy 89.416159 -149.260101)
			(xy 89.368553 -149.289155) (xy 89.317224 -149.310967) (xy 89.263267 -149.325073) (xy 89.20783 -149.331173)
			(xy 89.152096 -149.329136) (xy 89.097253 -149.319006) (xy 89.044469 -149.300999) (xy 88.994869 -149.275498)
			(xy 88.949511 -149.243047) (xy 88.909362 -149.204338) (xy 88.875276 -149.160195) (xy 88.84798 -149.11156)
			(xy 88.828057 -149.059469) (xy 88.815931 -149.005032) (xy 88.81186 -148.94941) (xy 82.53857 -148.94941)
			(xy 82.151728 -149.336252) (xy 93.292674 -149.336252) (xy 93.296745 -149.28063) (xy 93.308871 -149.226193)
			(xy 93.328794 -149.174102) (xy 93.35609 -149.125467) (xy 93.390176 -149.081324) (xy 93.430325 -149.042615)
			(xy 93.475683 -149.010164) (xy 93.525283 -148.984663) (xy 93.578067 -148.966656) (xy 93.63291 -148.956526)
			(xy 93.688644 -148.954489) (xy 93.744081 -148.960589) (xy 93.798038 -148.974695) (xy 93.849367 -148.996507)
			(xy 93.896973 -149.025561) (xy 93.939841 -149.061236) (xy 93.977058 -149.102773) (xy 94.007831 -149.149286)
			(xy 94.031503 -149.199783) (xy 94.047571 -149.25319) (xy 94.055691 -149.308366) (xy 94.0562 -149.336252)
			(xy 94.055691 -149.364138) (xy 94.047571 -149.419314) (xy 94.031503 -149.472721) (xy 94.007831 -149.523218)
			(xy 93.977058 -149.569731) (xy 93.939841 -149.611268) (xy 93.896973 -149.646943) (xy 93.849367 -149.675997)
			(xy 93.798038 -149.697809) (xy 93.744081 -149.711915) (xy 93.688644 -149.718015) (xy 93.63291 -149.715978)
			(xy 93.578067 -149.705848) (xy 93.525283 -149.687841) (xy 93.475683 -149.66234) (xy 93.430325 -149.629889)
			(xy 93.390176 -149.59118) (xy 93.35609 -149.547037) (xy 93.328794 -149.498402) (xy 93.308871 -149.446311)
			(xy 93.296745 -149.391874) (xy 93.292674 -149.336252) (xy 82.151728 -149.336252) (xy 81.52257 -149.96541)
			(xy 88.81186 -149.96541) (xy 88.815931 -149.909788) (xy 88.828057 -149.855351) (xy 88.84798 -149.80326)
			(xy 88.875276 -149.754625) (xy 88.909362 -149.710482) (xy 88.949511 -149.671773) (xy 88.994869 -149.639322)
			(xy 89.044469 -149.613821) (xy 89.097253 -149.595814) (xy 89.152096 -149.585684) (xy 89.20783 -149.583647)
			(xy 89.263267 -149.589747) (xy 89.317224 -149.603853) (xy 89.368553 -149.625665) (xy 89.416159 -149.654719)
			(xy 89.459027 -149.690394) (xy 89.496244 -149.731931) (xy 89.527017 -149.778444) (xy 89.550689 -149.828941)
			(xy 89.566757 -149.882348) (xy 89.568178 -149.892004) (xy 95.52305 -149.892004) (xy 95.523536 -149.864753)
			(xy 95.531292 -149.810805) (xy 95.546647 -149.75851) (xy 95.569289 -149.708933) (xy 95.598755 -149.663083)
			(xy 95.634446 -149.621892) (xy 95.675637 -149.586201) (xy 95.721487 -149.556735) (xy 95.771064 -149.534093)
			(xy 95.823359 -149.518738) (xy 95.877307 -149.510982) (xy 95.931809 -149.510982) (xy 95.985757 -149.518738)
			(xy 96.038052 -149.534093) (xy 96.077594 -149.552152) (xy 98.937316 -149.552152) (xy 98.941387 -149.49653)
			(xy 98.953513 -149.442093) (xy 98.973436 -149.390002) (xy 99.000732 -149.341367) (xy 99.034818 -149.297224)
			(xy 99.074967 -149.258515) (xy 99.120325 -149.226064) (xy 99.169925 -149.200563) (xy 99.222709 -149.182556)
			(xy 99.277552 -149.172426) (xy 99.333286 -149.170389) (xy 99.388723 -149.176489) (xy 99.44268 -149.190595)
			(xy 99.494009 -149.212407) (xy 99.541615 -149.241461) (xy 99.584483 -149.277136) (xy 99.6217 -149.318673)
			(xy 99.652473 -149.365186) (xy 99.676145 -149.415683) (xy 99.692213 -149.46909) (xy 99.700333 -149.524266)
			(xy 99.700842 -149.552152) (xy 99.700333 -149.580038) (xy 99.692213 -149.635214) (xy 99.676145 -149.688621)
			(xy 99.652473 -149.739118) (xy 99.6217 -149.785631) (xy 99.584483 -149.827168) (xy 99.541615 -149.862843)
			(xy 99.494009 -149.891897) (xy 99.44268 -149.913709) (xy 99.388723 -149.927815) (xy 99.333286 -149.933915)
			(xy 99.277552 -149.931878) (xy 99.222709 -149.921748) (xy 99.169925 -149.903741) (xy 99.120325 -149.87824)
			(xy 99.074967 -149.845789) (xy 99.034818 -149.80708) (xy 99.000732 -149.762937) (xy 98.973436 -149.714302)
			(xy 98.953513 -149.662211) (xy 98.941387 -149.607774) (xy 98.937316 -149.552152) (xy 96.077594 -149.552152)
			(xy 96.087629 -149.556735) (xy 96.133479 -149.586201) (xy 96.17467 -149.621892) (xy 96.210361 -149.663083)
			(xy 96.239827 -149.708933) (xy 96.262469 -149.75851) (xy 96.277824 -149.810805) (xy 96.28558 -149.864753)
			(xy 96.286066 -149.892004) (xy 96.285543 -149.920929) (xy 96.276862 -149.978124) (xy 96.25964 -150.033351)
			(xy 96.234273 -150.085342) (xy 96.218248 -150.109428) (xy 96.210868 -150.120879) (xy 96.201847 -150.146571)
			(xy 96.199948 -150.173736) (xy 96.205307 -150.200434) (xy 96.217541 -150.224761) (xy 96.235777 -150.244983)
			(xy 96.258715 -150.259658) (xy 96.271588 -150.264114) (xy 96.297187 -150.272507) (xy 96.345882 -150.295554)
			(xy 96.390851 -150.325221) (xy 96.4312 -150.360919) (xy 96.466126 -150.401936) (xy 96.494936 -150.447459)
			(xy 96.517056 -150.496582) (xy 96.532047 -150.548327) (xy 96.53961 -150.601667) (xy 96.540066 -150.628604)
			(xy 96.53958 -150.655855) (xy 96.531824 -150.709803) (xy 96.516469 -150.762098) (xy 96.493827 -150.811675)
			(xy 96.464361 -150.857525) (xy 96.42867 -150.898716) (xy 96.387479 -150.934407) (xy 96.341629 -150.963873)
			(xy 96.292052 -150.986515) (xy 96.239757 -151.00187) (xy 96.185809 -151.009626) (xy 96.131307 -151.009626)
			(xy 96.077359 -151.00187) (xy 96.025064 -150.986515) (xy 95.975487 -150.963873) (xy 95.929637 -150.934407)
			(xy 95.888446 -150.898716) (xy 95.852755 -150.857525) (xy 95.823289 -150.811675) (xy 95.800647 -150.762098)
			(xy 95.785292 -150.709803) (xy 95.777536 -150.655855) (xy 95.77705 -150.628604) (xy 95.777543 -150.599678)
			(xy 95.786235 -150.542482) (xy 95.803466 -150.487256) (xy 95.828841 -150.435266) (xy 95.844868 -150.41118)
			(xy 95.85223 -150.399719) (xy 95.861249 -150.37403) (xy 95.863149 -150.346869) (xy 95.857793 -150.320174)
			(xy 95.845563 -150.295849) (xy 95.827331 -150.275627) (xy 95.804398 -150.260952) (xy 95.791528 -150.256494)
			(xy 95.765935 -150.248084) (xy 95.71724 -150.22504) (xy 95.672271 -150.195375) (xy 95.631922 -150.15968)
			(xy 95.596994 -150.118664) (xy 95.568184 -150.073144) (xy 95.546063 -150.024023) (xy 95.531071 -149.972279)
			(xy 95.523506 -149.91894) (xy 95.52305 -149.892004) (xy 89.568178 -149.892004) (xy 89.574877 -149.937524)
			(xy 89.575386 -149.96541) (xy 89.574877 -149.993296) (xy 89.566757 -150.048472) (xy 89.550689 -150.101879)
			(xy 89.527017 -150.152376) (xy 89.496244 -150.198889) (xy 89.459027 -150.240426) (xy 89.416159 -150.276101)
			(xy 89.368553 -150.305155) (xy 89.317224 -150.326967) (xy 89.263267 -150.341073) (xy 89.20783 -150.347173)
			(xy 89.152096 -150.345136) (xy 89.097253 -150.335006) (xy 89.044469 -150.316999) (xy 88.994869 -150.291498)
			(xy 88.949511 -150.259047) (xy 88.909362 -150.220338) (xy 88.875276 -150.176195) (xy 88.84798 -150.12756)
			(xy 88.828057 -150.075469) (xy 88.815931 -150.021032) (xy 88.81186 -149.96541) (xy 81.52257 -149.96541)
			(xy 81.389474 -150.098506) (xy 81.382108 -150.105618) (xy 81.374488 -150.124414) (xy 81.374488 -150.76932)
			(xy 92.368114 -150.76932) (xy 92.372185 -150.713698) (xy 92.384311 -150.659261) (xy 92.404234 -150.60717)
			(xy 92.43153 -150.558535) (xy 92.465616 -150.514392) (xy 92.505765 -150.475683) (xy 92.551123 -150.443232)
			(xy 92.600723 -150.417731) (xy 92.653507 -150.399724) (xy 92.70835 -150.389594) (xy 92.764084 -150.387557)
			(xy 92.819521 -150.393657) (xy 92.873478 -150.407763) (xy 92.924807 -150.429575) (xy 92.972413 -150.458629)
			(xy 93.015281 -150.494304) (xy 93.052498 -150.535841) (xy 93.083271 -150.582354) (xy 93.106943 -150.632851)
			(xy 93.123011 -150.686258) (xy 93.126189 -150.707852) (xy 94.48114 -150.707852) (xy 94.485211 -150.65223)
			(xy 94.497337 -150.597793) (xy 94.51726 -150.545702) (xy 94.544556 -150.497067) (xy 94.578642 -150.452924)
			(xy 94.618791 -150.414215) (xy 94.664149 -150.381764) (xy 94.713749 -150.356263) (xy 94.766533 -150.338256)
			(xy 94.821376 -150.328126) (xy 94.87711 -150.326089) (xy 94.932547 -150.332189) (xy 94.986504 -150.346295)
			(xy 95.037833 -150.368107) (xy 95.085439 -150.397161) (xy 95.128307 -150.432836) (xy 95.165524 -150.474373)
			(xy 95.196297 -150.520886) (xy 95.219969 -150.571383) (xy 95.236037 -150.62479) (xy 95.244157 -150.679966)
			(xy 95.244666 -150.707852) (xy 95.244157 -150.735738) (xy 95.236037 -150.790914) (xy 95.219969 -150.844321)
			(xy 95.196297 -150.894818) (xy 95.165524 -150.941331) (xy 95.128307 -150.982868) (xy 95.085439 -151.018543)
			(xy 95.037833 -151.047597) (xy 94.986504 -151.069409) (xy 94.932547 -151.083515) (xy 94.87711 -151.089615)
			(xy 94.821376 -151.087578) (xy 94.766533 -151.077448) (xy 94.713749 -151.059441) (xy 94.664149 -151.03394)
			(xy 94.618791 -151.001489) (xy 94.578642 -150.96278) (xy 94.544556 -150.918637) (xy 94.51726 -150.870002)
			(xy 94.497337 -150.817911) (xy 94.485211 -150.763474) (xy 94.48114 -150.707852) (xy 93.126189 -150.707852)
			(xy 93.131131 -150.741434) (xy 93.13164 -150.76932) (xy 93.131131 -150.797206) (xy 93.123011 -150.852382)
			(xy 93.106943 -150.905789) (xy 93.083271 -150.956286) (xy 93.052498 -151.002799) (xy 93.015281 -151.044336)
			(xy 92.972413 -151.080011) (xy 92.924807 -151.109065) (xy 92.873478 -151.130877) (xy 92.819521 -151.144983)
			(xy 92.764084 -151.151083) (xy 92.70835 -151.149046) (xy 92.653507 -151.138916) (xy 92.600723 -151.120909)
			(xy 92.551123 -151.095408) (xy 92.505765 -151.062957) (xy 92.465616 -151.024248) (xy 92.43153 -150.980105)
			(xy 92.404234 -150.93147) (xy 92.384311 -150.879379) (xy 92.372185 -150.824942) (xy 92.368114 -150.76932)
			(xy 81.374488 -150.76932) (xy 81.374488 -151.776684) (xy 92.368114 -151.776684) (xy 92.372185 -151.721062)
			(xy 92.384311 -151.666625) (xy 92.404234 -151.614534) (xy 92.43153 -151.565899) (xy 92.465616 -151.521756)
			(xy 92.505765 -151.483047) (xy 92.551123 -151.450596) (xy 92.600723 -151.425095) (xy 92.653507 -151.407088)
			(xy 92.70835 -151.396958) (xy 92.764084 -151.394921) (xy 92.819521 -151.401021) (xy 92.873478 -151.415127)
			(xy 92.924807 -151.436939) (xy 92.972413 -151.465993) (xy 93.015281 -151.501668) (xy 93.052498 -151.543205)
			(xy 93.083271 -151.589718) (xy 93.104476 -151.634952) (xy 99.305616 -151.634952) (xy 99.309687 -151.57933)
			(xy 99.321813 -151.524893) (xy 99.341736 -151.472802) (xy 99.369032 -151.424167) (xy 99.403118 -151.380024)
			(xy 99.443267 -151.341315) (xy 99.488625 -151.308864) (xy 99.538225 -151.283363) (xy 99.591009 -151.265356)
			(xy 99.645852 -151.255226) (xy 99.701586 -151.253189) (xy 99.757023 -151.259289) (xy 99.81098 -151.273395)
			(xy 99.862309 -151.295207) (xy 99.909915 -151.324261) (xy 99.952783 -151.359936) (xy 99.99 -151.401473)
			(xy 100.020773 -151.447986) (xy 100.044445 -151.498483) (xy 100.060513 -151.55189) (xy 100.068633 -151.607066)
			(xy 100.069142 -151.634952) (xy 100.068633 -151.662838) (xy 100.060513 -151.718014) (xy 100.044445 -151.771421)
			(xy 100.020773 -151.821918) (xy 99.99 -151.868431) (xy 99.952783 -151.909968) (xy 99.909915 -151.945643)
			(xy 99.862309 -151.974697) (xy 99.81098 -151.996509) (xy 99.757023 -152.010615) (xy 99.701586 -152.016715)
			(xy 99.645852 -152.014678) (xy 99.591009 -152.004548) (xy 99.538225 -151.986541) (xy 99.488625 -151.96104)
			(xy 99.443267 -151.928589) (xy 99.403118 -151.88988) (xy 99.369032 -151.845737) (xy 99.341736 -151.797102)
			(xy 99.321813 -151.745011) (xy 99.309687 -151.690574) (xy 99.305616 -151.634952) (xy 93.104476 -151.634952)
			(xy 93.106943 -151.640215) (xy 93.123011 -151.693622) (xy 93.131131 -151.748798) (xy 93.13164 -151.776684)
			(xy 93.131131 -151.80457) (xy 93.123011 -151.859746) (xy 93.106943 -151.913153) (xy 93.083271 -151.96365)
			(xy 93.052498 -152.010163) (xy 93.015281 -152.0517) (xy 92.972413 -152.087375) (xy 92.924807 -152.116429)
			(xy 92.873478 -152.138241) (xy 92.819521 -152.152347) (xy 92.764084 -152.158447) (xy 92.70835 -152.15641)
			(xy 92.653507 -152.14628) (xy 92.600723 -152.128273) (xy 92.551123 -152.102772) (xy 92.505765 -152.070321)
			(xy 92.465616 -152.031612) (xy 92.43153 -151.987469) (xy 92.404234 -151.938834) (xy 92.384311 -151.886743)
			(xy 92.372185 -151.832306) (xy 92.368114 -151.776684) (xy 81.374488 -151.776684) (xy 81.374488 -153.894282)
			(xy 83.466178 -153.894282) (xy 83.466726 -153.865366) (xy 83.475445 -153.808195) (xy 83.492695 -153.752995)
			(xy 83.518081 -153.701033) (xy 83.551021 -153.653498) (xy 83.590759 -153.611482) (xy 83.613244 -153.593292)
			(xy 83.622012 -153.585737) (xy 83.63219 -153.564973) (xy 83.632802 -153.553414) (xy 83.632802 -153.47315)
			(xy 83.632202 -153.461586) (xy 83.622028 -153.440815) (xy 83.613244 -153.433272) (xy 83.590756 -153.415086)
			(xy 83.551019 -153.373066) (xy 83.51808 -153.325531) (xy 83.492691 -153.273568) (xy 83.475437 -153.218369)
			(xy 83.466711 -153.161199) (xy 83.466178 -153.132282) (xy 83.466661 -153.105031) (xy 83.47442 -153.051084)
			(xy 83.489776 -152.99879) (xy 83.512419 -152.949214) (xy 83.541885 -152.903364) (xy 83.577577 -152.862174)
			(xy 83.618767 -152.826483) (xy 83.664617 -152.797017) (xy 83.714194 -152.774375) (xy 83.766488 -152.759019)
			(xy 83.820435 -152.751261) (xy 83.847686 -152.750774) (xy 83.874961 -152.751244) (xy 83.928959 -152.758987)
			(xy 83.981303 -152.774346) (xy 84.030923 -152.797008) (xy 84.076808 -152.82651) (xy 84.11802 -152.86225)
			(xy 84.153718 -152.903497) (xy 84.183174 -152.949411) (xy 84.194904 -152.97404) (xy 84.201 -152.987248)
			(xy 84.224622 -153.00325) (xy 84.344256 -153.008076) (xy 84.369148 -152.994106) (xy 84.376006 -152.981406)
			(xy 84.388811 -152.959294) (xy 84.419408 -152.918369) (xy 84.455175 -152.881876) (xy 84.475066 -152.865836)
			(xy 84.483818 -152.858266) (xy 84.494004 -152.837513) (xy 84.494624 -152.825958) (xy 84.494624 -152.745694)
			(xy 84.494084 -152.734121) (xy 84.483871 -152.713349) (xy 84.475066 -152.705816) (xy 84.452583 -152.687625)
			(xy 84.412849 -152.645604) (xy 84.379911 -152.598069) (xy 84.354523 -152.546108) (xy 84.337266 -152.490911)
			(xy 84.328536 -152.433742) (xy 84.328 -152.404826) (xy 84.328486 -152.377575) (xy 84.336242 -152.323627)
			(xy 84.351597 -152.271332) (xy 84.374239 -152.221755) (xy 84.403705 -152.175905) (xy 84.439396 -152.134714)
			(xy 84.480587 -152.099023) (xy 84.526437 -152.069557) (xy 84.576014 -152.046915) (xy 84.628309 -152.03156)
			(xy 84.682257 -152.023804) (xy 84.736759 -152.023804) (xy 84.790707 -152.03156) (xy 84.843002 -152.046915)
			(xy 84.892579 -152.069557) (xy 84.938429 -152.099023) (xy 84.97962 -152.134714) (xy 85.015311 -152.175905)
			(xy 85.044777 -152.221755) (xy 85.067419 -152.271332) (xy 85.082774 -152.323627) (xy 85.09053 -152.377575)
			(xy 85.091016 -152.404826) (xy 85.090476 -152.433743) (xy 85.090276 -152.435052) (xy 93.412816 -152.435052)
			(xy 93.416887 -152.37943) (xy 93.429013 -152.324993) (xy 93.448936 -152.272902) (xy 93.476232 -152.224267)
			(xy 93.510318 -152.180124) (xy 93.550467 -152.141415) (xy 93.595825 -152.108964) (xy 93.645425 -152.083463)
			(xy 93.698209 -152.065456) (xy 93.753052 -152.055326) (xy 93.808786 -152.053289) (xy 93.864223 -152.059389)
			(xy 93.91818 -152.073495) (xy 93.969509 -152.095307) (xy 94.017115 -152.124361) (xy 94.059983 -152.160036)
			(xy 94.0972 -152.201573) (xy 94.127973 -152.248086) (xy 94.151645 -152.298583) (xy 94.167713 -152.35199)
			(xy 94.175833 -152.407166) (xy 94.176342 -152.435052) (xy 94.175833 -152.462938) (xy 94.167713 -152.518114)
			(xy 94.151645 -152.571521) (xy 94.127973 -152.622018) (xy 94.0972 -152.668531) (xy 94.059983 -152.710068)
			(xy 94.017115 -152.745743) (xy 93.969509 -152.774797) (xy 93.91818 -152.796609) (xy 93.864223 -152.810715)
			(xy 93.808786 -152.816815) (xy 93.753052 -152.814778) (xy 93.698209 -152.804648) (xy 93.645425 -152.786641)
			(xy 93.595825 -152.76114) (xy 93.550467 -152.728689) (xy 93.510318 -152.68998) (xy 93.476232 -152.645837)
			(xy 93.448936 -152.597202) (xy 93.429013 -152.545111) (xy 93.416887 -152.490674) (xy 93.412816 -152.435052)
			(xy 85.090276 -152.435052) (xy 85.081756 -152.490914) (xy 85.064505 -152.546114) (xy 85.039117 -152.598076)
			(xy 85.006176 -152.645611) (xy 84.966435 -152.687626) (xy 84.94395 -152.705816) (xy 84.935177 -152.713367)
			(xy 84.925001 -152.734134) (xy 84.924392 -152.745694) (xy 84.924392 -152.825958) (xy 84.924989 -152.837522)
			(xy 84.935165 -152.858293) (xy 84.94395 -152.865836) (xy 84.966461 -152.883994) (xy 85.006192 -152.926022)
			(xy 85.039127 -152.973564) (xy 85.06451 -153.025532) (xy 85.081761 -153.080735) (xy 85.090484 -153.137908)
			(xy 85.091016 -153.166826) (xy 85.090546 -153.194078) (xy 85.082787 -153.248025) (xy 85.067429 -153.30032)
			(xy 85.044785 -153.349897) (xy 85.015317 -153.395747) (xy 84.979624 -153.436936) (xy 84.938432 -153.472628)
			(xy 84.892581 -153.502094) (xy 84.843003 -153.524735) (xy 84.790708 -153.54009) (xy 84.73676 -153.547848)
			(xy 84.709508 -153.548334) (xy 84.682233 -153.547865) (xy 84.628235 -153.540121) (xy 84.575892 -153.524761)
			(xy 84.526271 -153.502099) (xy 84.480387 -153.472597) (xy 84.439175 -153.436857) (xy 84.403476 -153.39561)
			(xy 84.37402 -153.349696) (xy 84.36229 -153.325068) (xy 84.356194 -153.31186) (xy 84.332572 -153.295858)
			(xy 84.212938 -153.291032) (xy 84.188046 -153.305002) (xy 84.181188 -153.317702) (xy 84.168386 -153.339816)
			(xy 84.137788 -153.38074) (xy 84.102019 -153.417232) (xy 84.082128 -153.433272) (xy 84.073371 -153.440838)
			(xy 84.063188 -153.461594) (xy 84.06257 -153.47315) (xy 84.06257 -153.553414) (xy 84.063108 -153.564987)
			(xy 84.073323 -153.585759) (xy 84.082128 -153.593292) (xy 84.104613 -153.61148) (xy 84.144347 -153.653502)
			(xy 84.177285 -153.701037) (xy 84.202673 -153.752999) (xy 84.219929 -153.808197) (xy 84.228659 -153.865366)
			(xy 84.229194 -153.894282) (xy 84.228708 -153.921533) (xy 84.220952 -153.975481) (xy 84.205597 -154.027776)
			(xy 84.182955 -154.077353) (xy 84.153489 -154.123203) (xy 84.117798 -154.164394) (xy 84.076607 -154.200085)
			(xy 84.030757 -154.229551) (xy 83.98118 -154.252193) (xy 83.928885 -154.267548) (xy 83.874937 -154.275304)
			(xy 83.820435 -154.275304) (xy 83.766487 -154.267548) (xy 83.714192 -154.252193) (xy 83.664615 -154.229551)
			(xy 83.618765 -154.200085) (xy 83.577574 -154.164394) (xy 83.541883 -154.123203) (xy 83.512417 -154.077353)
			(xy 83.489775 -154.027776) (xy 83.47442 -153.975481) (xy 83.466664 -153.921533) (xy 83.466178 -153.894282)
			(xy 81.374488 -153.894282) (xy 81.374488 -155.681934) (xy 81.373935 -155.711916) (xy 81.364559 -155.771141)
			(xy 81.346029 -155.82817) (xy 81.345863 -155.828495) (xy 83.791294 -155.828495) (xy 83.795025 -155.775242)
			(xy 83.806143 -155.72303) (xy 83.824431 -155.672877) (xy 83.849532 -155.625763) (xy 83.880955 -155.582608)
			(xy 83.918088 -155.544255) (xy 83.938872 -155.527502) (xy 83.947641 -155.519947) (xy 83.957817 -155.499183)
			(xy 83.95843 -155.487624) (xy 83.95843 -155.40736) (xy 83.957849 -155.395793) (xy 83.947664 -155.37502)
			(xy 83.938872 -155.367482) (xy 83.916374 -155.349308) (xy 83.876641 -155.307284) (xy 83.843705 -155.259745)
			(xy 83.818319 -155.207781) (xy 83.801066 -155.152581) (xy 83.79234 -155.095409) (xy 83.791806 -155.066492)
			(xy 83.792248 -155.039238) (xy 83.800006 -154.985286) (xy 83.815364 -154.932987) (xy 83.838009 -154.883406)
			(xy 83.867479 -154.837552) (xy 83.903175 -154.796359) (xy 83.94437 -154.760666) (xy 83.990225 -154.731198)
			(xy 84.039807 -154.708556) (xy 84.092107 -154.693202) (xy 84.14606 -154.685446) (xy 84.173314 -154.684984)
			(xy 84.202588 -154.685536) (xy 84.260445 -154.694503) (xy 84.316252 -154.712208) (xy 84.368696 -154.738236)
			(xy 84.416546 -154.771974) (xy 84.437982 -154.791918) (xy 84.445348 -154.798776) (xy 84.463382 -154.806142)
			(xy 84.553806 -154.806142) (xy 84.57184 -154.798776) (xy 84.579206 -154.791918) (xy 84.600664 -154.772)
			(xy 84.648515 -154.738272) (xy 84.700954 -154.712245) (xy 84.756753 -154.694529) (xy 84.814603 -154.685541)
			(xy 84.843874 -154.684984) (xy 84.872792 -154.685489) (xy 84.929965 -154.694216) (xy 84.985166 -154.711475)
			(xy 85.037128 -154.736869) (xy 85.084661 -154.769816) (xy 85.126676 -154.809562) (xy 85.144864 -154.83205)
			(xy 85.152437 -154.8408) (xy 85.173188 -154.850988) (xy 85.184742 -154.851608) (xy 85.265006 -154.851608)
			(xy 85.276574 -154.851038) (xy 85.297344 -154.840843) (xy 85.304884 -154.83205) (xy 85.319664 -154.813652)
			(xy 85.353034 -154.780281) (xy 85.371432 -154.765502) (xy 85.380194 -154.75794) (xy 85.390376 -154.737181)
			(xy 85.39099 -154.725624) (xy 85.39099 -154.64536) (xy 85.390389 -154.633796) (xy 85.380216 -154.613025)
			(xy 85.371432 -154.605482) (xy 85.348947 -154.587293) (xy 85.30921 -154.545274) (xy 85.27627 -154.497739)
			(xy 85.250882 -154.445777) (xy 85.233627 -154.390579) (xy 85.2249 -154.333408) (xy 85.224366 -154.304492)
			(xy 85.22487 -154.277242) (xy 85.232627 -154.223296) (xy 85.247982 -154.171003) (xy 85.270622 -154.121428)
			(xy 85.300087 -154.075579) (xy 85.335776 -154.034389) (xy 85.376964 -153.998698) (xy 85.422812 -153.969231)
			(xy 85.472386 -153.946588) (xy 85.524678 -153.931231) (xy 85.578624 -153.923472) (xy 85.605874 -153.922984)
			(xy 85.634792 -153.923489) (xy 85.691965 -153.932216) (xy 85.747166 -153.949475) (xy 85.799128 -153.974869)
			(xy 85.846661 -154.007816) (xy 85.888676 -154.047562) (xy 85.906864 -154.07005) (xy 85.914437 -154.0788)
			(xy 85.935188 -154.088988) (xy 85.946742 -154.089608) (xy 86.027006 -154.089608) (xy 86.038574 -154.089038)
			(xy 86.059344 -154.078843) (xy 86.066884 -154.07005) (xy 86.081664 -154.051652) (xy 86.115034 -154.018281)
			(xy 86.133432 -154.003502) (xy 86.142194 -153.99594) (xy 86.152376 -153.975181) (xy 86.15299 -153.963624)
			(xy 86.15299 -153.88336) (xy 86.152389 -153.871796) (xy 86.142216 -153.851025) (xy 86.133432 -153.843482)
			(xy 86.110947 -153.825293) (xy 86.07121 -153.783274) (xy 86.03827 -153.735739) (xy 86.012882 -153.683777)
			(xy 85.995627 -153.628579) (xy 85.9869 -153.571408) (xy 85.986366 -153.542492) (xy 85.98687 -153.515242)
			(xy 85.994627 -153.461296) (xy 86.009982 -153.409003) (xy 86.032622 -153.359428) (xy 86.062087 -153.313579)
			(xy 86.097776 -153.272389) (xy 86.138964 -153.236698) (xy 86.184812 -153.207231) (xy 86.234386 -153.184588)
			(xy 86.286678 -153.169231) (xy 86.340624 -153.161472) (xy 86.367874 -153.160984) (xy 86.396792 -153.161489)
			(xy 86.453965 -153.170216) (xy 86.509166 -153.187475) (xy 86.561128 -153.212869) (xy 86.608661 -153.245816)
			(xy 86.650676 -153.285562) (xy 86.668864 -153.30805) (xy 86.676437 -153.3168) (xy 86.697188 -153.326988)
			(xy 86.708742 -153.327608) (xy 86.789006 -153.327608) (xy 86.800574 -153.327038) (xy 86.821344 -153.316843)
			(xy 86.828884 -153.30805) (xy 86.845637 -153.287267) (xy 86.883991 -153.250137) (xy 86.927145 -153.218715)
			(xy 86.974259 -153.193616) (xy 87.024411 -153.17533) (xy 87.076622 -153.164213) (xy 87.129874 -153.160483)
			(xy 87.183126 -153.164213) (xy 87.235337 -153.17533) (xy 87.285489 -153.193616) (xy 87.332603 -153.218715)
			(xy 87.375757 -153.250137) (xy 87.414111 -153.287267) (xy 87.430864 -153.30805) (xy 87.438437 -153.3168)
			(xy 87.459188 -153.326988) (xy 87.470742 -153.327608) (xy 87.551006 -153.327608) (xy 87.562574 -153.327038)
			(xy 87.583344 -153.316843) (xy 87.590884 -153.30805) (xy 87.607637 -153.287267) (xy 87.645991 -153.250137)
			(xy 87.689145 -153.218715) (xy 87.736259 -153.193616) (xy 87.786411 -153.17533) (xy 87.838622 -153.164213)
			(xy 87.891874 -153.160483) (xy 87.945126 -153.164213) (xy 87.997337 -153.17533) (xy 88.047489 -153.193616)
			(xy 88.094603 -153.218715) (xy 88.137757 -153.250137) (xy 88.176111 -153.287267) (xy 88.192864 -153.30805)
			(xy 88.200437 -153.3168) (xy 88.221188 -153.326988) (xy 88.232742 -153.327608) (xy 88.313006 -153.327608)
			(xy 88.324574 -153.327038) (xy 88.345344 -153.316843) (xy 88.352884 -153.30805) (xy 88.369637 -153.287267)
			(xy 88.407991 -153.250137) (xy 88.451145 -153.218715) (xy 88.498259 -153.193616) (xy 88.548411 -153.17533)
			(xy 88.600622 -153.164213) (xy 88.653874 -153.160483) (xy 88.707126 -153.164213) (xy 88.759337 -153.17533)
			(xy 88.809489 -153.193616) (xy 88.856603 -153.218715) (xy 88.899757 -153.250137) (xy 88.938111 -153.287267)
			(xy 88.954864 -153.30805) (xy 88.962437 -153.3168) (xy 88.983188 -153.326988) (xy 88.994742 -153.327608)
			(xy 89.075006 -153.327608) (xy 89.086574 -153.327038) (xy 89.107344 -153.316843) (xy 89.114884 -153.30805)
			(xy 89.131637 -153.287267) (xy 89.169991 -153.250137) (xy 89.213145 -153.218715) (xy 89.260259 -153.193616)
			(xy 89.310411 -153.17533) (xy 89.362622 -153.164213) (xy 89.415874 -153.160483) (xy 89.469126 -153.164213)
			(xy 89.521337 -153.17533) (xy 89.571489 -153.193616) (xy 89.618603 -153.218715) (xy 89.661757 -153.250137)
			(xy 89.700111 -153.287267) (xy 89.716864 -153.30805) (xy 89.724437 -153.3168) (xy 89.745188 -153.326988)
			(xy 89.756742 -153.327608) (xy 89.837006 -153.327608) (xy 89.848574 -153.327038) (xy 89.869344 -153.316843)
			(xy 89.876884 -153.30805) (xy 89.893637 -153.287267) (xy 89.931991 -153.250137) (xy 89.975145 -153.218715)
			(xy 90.022259 -153.193616) (xy 90.072411 -153.17533) (xy 90.124622 -153.164213) (xy 90.177874 -153.160483)
			(xy 90.231126 -153.164213) (xy 90.283337 -153.17533) (xy 90.333489 -153.193616) (xy 90.380603 -153.218715)
			(xy 90.423757 -153.250137) (xy 90.462111 -153.287267) (xy 90.478864 -153.30805) (xy 90.486437 -153.3168)
			(xy 90.507188 -153.326988) (xy 90.518742 -153.327608) (xy 90.599006 -153.327608) (xy 90.610574 -153.327038)
			(xy 90.631344 -153.316843) (xy 90.638884 -153.30805) (xy 90.657071 -153.285564) (xy 90.699093 -153.245831)
			(xy 90.74663 -153.212894) (xy 90.798591 -153.187506) (xy 90.853789 -153.17025) (xy 90.910958 -153.16152)
			(xy 90.939874 -153.160984) (xy 90.967126 -153.161479) (xy 91.021075 -153.169233) (xy 91.073372 -153.184585)
			(xy 91.122951 -153.207224) (xy 91.168804 -153.236688) (xy 91.209997 -153.272379) (xy 91.245691 -153.313568)
			(xy 91.27516 -153.359419) (xy 91.297803 -153.408996) (xy 91.31316 -153.461292) (xy 91.320918 -153.51524)
			(xy 91.321382 -153.542492) (xy 91.320865 -153.571409) (xy 91.312136 -153.628581) (xy 91.294879 -153.68378)
			(xy 91.269487 -153.735741) (xy 91.236543 -153.783275) (xy 91.196802 -153.825292) (xy 91.174316 -153.843482)
			(xy 91.165552 -153.851041) (xy 91.155373 -153.871803) (xy 91.154758 -153.88336) (xy 91.154758 -153.963624)
			(xy 91.155352 -153.975189) (xy 91.165528 -153.995962) (xy 91.174316 -154.003502) (xy 91.192712 -154.018284)
			(xy 91.226085 -154.051652) (xy 91.240864 -154.07005) (xy 91.248437 -154.0788) (xy 91.269188 -154.088988)
			(xy 91.280742 -154.089608) (xy 91.361006 -154.089608) (xy 91.372574 -154.089038) (xy 91.393344 -154.078843)
			(xy 91.400884 -154.07005) (xy 91.419071 -154.047564) (xy 91.461093 -154.007831) (xy 91.50863 -153.974894)
			(xy 91.560591 -153.949506) (xy 91.615789 -153.93225) (xy 91.672958 -153.92352) (xy 91.701874 -153.922984)
			(xy 91.729126 -153.923479) (xy 91.783075 -153.931233) (xy 91.835372 -153.946585) (xy 91.884951 -153.969224)
			(xy 91.930804 -153.998688) (xy 91.971997 -154.034379) (xy 92.007691 -154.075568) (xy 92.03716 -154.121419)
			(xy 92.059803 -154.170996) (xy 92.07516 -154.223292) (xy 92.082918 -154.27724) (xy 92.083382 -154.304492)
			(xy 92.082865 -154.333409) (xy 92.074136 -154.390581) (xy 92.056879 -154.44578) (xy 92.031487 -154.497741)
			(xy 91.998543 -154.545275) (xy 91.958802 -154.587292) (xy 91.936316 -154.605482) (xy 91.927552 -154.613041)
			(xy 91.917373 -154.633803) (xy 91.916758 -154.64536) (xy 91.916758 -154.725624) (xy 91.917352 -154.737189)
			(xy 91.927528 -154.757962) (xy 91.936316 -154.765502) (xy 91.957092 -154.782264) (xy 91.994224 -154.820615)
			(xy 92.025648 -154.863768) (xy 92.050749 -154.910881) (xy 92.069037 -154.961032) (xy 92.080155 -155.013244)
			(xy 92.083885 -155.066495) (xy 92.080156 -155.119747) (xy 92.06904 -155.171958) (xy 92.050753 -155.22211)
			(xy 92.025653 -155.269223) (xy 91.994231 -155.312377) (xy 91.957099 -155.350729) (xy 91.936316 -155.367482)
			(xy 91.927552 -155.375041) (xy 91.917373 -155.395803) (xy 91.916758 -155.40736) (xy 91.916758 -155.487624)
			(xy 91.917352 -155.499189) (xy 91.927528 -155.519962) (xy 91.936316 -155.527502) (xy 91.957092 -155.544264)
			(xy 91.994224 -155.582615) (xy 92.025648 -155.625768) (xy 92.050749 -155.672881) (xy 92.069037 -155.723032)
			(xy 92.080155 -155.775244) (xy 92.083885 -155.828495) (xy 92.080156 -155.881747) (xy 92.06904 -155.933958)
			(xy 92.050753 -155.98411) (xy 92.025653 -156.031223) (xy 91.994231 -156.074377) (xy 91.957099 -156.112729)
			(xy 91.936316 -156.129482) (xy 91.927552 -156.137041) (xy 91.917373 -156.157803) (xy 91.916758 -156.16936)
			(xy 91.916758 -156.249624) (xy 91.917352 -156.261189) (xy 91.927528 -156.281962) (xy 91.936316 -156.289502)
			(xy 91.958804 -156.307688) (xy 91.998538 -156.349709) (xy 92.031476 -156.397245) (xy 92.056863 -156.449207)
			(xy 92.074119 -156.504406) (xy 92.082847 -156.561576) (xy 92.083382 -156.590492) (xy 92.082917 -156.618067)
			(xy 92.074965 -156.67264) (xy 92.059241 -156.7255) (xy 92.03607 -156.775546) (xy 92.005937 -156.821736)
			(xy 91.969469 -156.863106) (xy 91.948762 -156.881322) (xy 91.940632 -156.888914) (xy 91.931286 -156.909074)
			(xy 91.930728 -156.920184) (xy 91.930728 -156.9974) (xy 91.931271 -157.008513) (xy 91.940626 -157.028672)
			(xy 91.948762 -157.036262) (xy 91.96945 -157.054498) (xy 92.005924 -157.095861) (xy 92.03606 -157.142045)
			(xy 92.05923 -157.192088) (xy 92.074951 -157.244947) (xy 92.082895 -157.299519) (xy 92.083382 -157.327092)
			(xy 92.082937 -157.354346) (xy 92.075181 -157.408299) (xy 92.059824 -157.460599) (xy 92.037181 -157.51018)
			(xy 92.007711 -157.556035) (xy 91.972015 -157.597228) (xy 91.93082 -157.632922) (xy 91.884965 -157.662389)
			(xy 91.835382 -157.685031) (xy 91.783081 -157.700384) (xy 91.729128 -157.708138) (xy 91.701874 -157.7086)
			(xy 91.672959 -157.708029) (xy 91.61579 -157.699311) (xy 91.560593 -157.682063) (xy 91.508631 -157.656682)
			(xy 91.461095 -157.623747) (xy 91.419076 -157.584015) (xy 91.400884 -157.561534) (xy 91.393336 -157.552758)
			(xy 91.372566 -157.542585) (xy 91.361006 -157.541976) (xy 91.280742 -157.541976) (xy 91.269173 -157.542544)
			(xy 91.248401 -157.552738) (xy 91.240864 -157.561534) (xy 91.224111 -157.582317) (xy 91.185757 -157.619447)
			(xy 91.142603 -157.650869) (xy 91.095489 -157.675968) (xy 91.045337 -157.694254) (xy 90.993126 -157.705371)
			(xy 90.939874 -157.709101) (xy 90.886622 -157.705371) (xy 90.834411 -157.694254) (xy 90.784259 -157.675968)
			(xy 90.737145 -157.650869) (xy 90.693991 -157.619447) (xy 90.655637 -157.582317) (xy 90.638884 -157.561534)
			(xy 90.631336 -157.552758) (xy 90.610566 -157.542585) (xy 90.599006 -157.541976) (xy 90.518742 -157.541976)
			(xy 90.507173 -157.542544) (xy 90.486401 -157.552738) (xy 90.478864 -157.561534) (xy 90.460702 -157.584042)
			(xy 90.418675 -157.623774) (xy 90.371134 -157.656709) (xy 90.319167 -157.682093) (xy 90.263965 -157.699344)
			(xy 90.206792 -157.708068) (xy 90.177874 -157.7086) (xy 90.15153 -157.708154) (xy 90.099341 -157.700917)
			(xy 90.048644 -157.686571) (xy 90.000402 -157.665389) (xy 89.955532 -157.637772) (xy 89.914886 -157.604247)
			(xy 89.879239 -157.565449) (xy 89.849266 -157.522118) (xy 89.837006 -157.498796) (xy 89.830656 -157.485588)
			(xy 89.806272 -157.470856) (xy 86.739476 -157.470856) (xy 86.715092 -157.485588) (xy 86.708742 -157.498796)
			(xy 86.696496 -157.522125) (xy 86.666517 -157.565453) (xy 86.630865 -157.604247) (xy 86.590217 -157.63777)
			(xy 86.545346 -157.665386) (xy 86.497103 -157.686569) (xy 86.446407 -157.700918) (xy 86.394218 -157.708159)
			(xy 86.367874 -157.7086) (xy 86.338959 -157.708029) (xy 86.28179 -157.699311) (xy 86.226593 -157.682063)
			(xy 86.174631 -157.656682) (xy 86.127095 -157.623747) (xy 86.085076 -157.584015) (xy 86.066884 -157.561534)
			(xy 86.059336 -157.552758) (xy 86.038566 -157.542585) (xy 86.027006 -157.541976) (xy 85.946742 -157.541976)
			(xy 85.935173 -157.542544) (xy 85.914401 -157.552738) (xy 85.906864 -157.561534) (xy 85.890111 -157.582317)
			(xy 85.851757 -157.619447) (xy 85.808603 -157.650869) (xy 85.761489 -157.675968) (xy 85.711337 -157.694254)
			(xy 85.659126 -157.705371) (xy 85.605874 -157.709101) (xy 85.552622 -157.705371) (xy 85.500411 -157.694254)
			(xy 85.450259 -157.675968) (xy 85.403145 -157.650869) (xy 85.359991 -157.619447) (xy 85.321637 -157.582317)
			(xy 85.304884 -157.561534) (xy 85.297336 -157.552758) (xy 85.276566 -157.542585) (xy 85.265006 -157.541976)
			(xy 85.184742 -157.541976) (xy 85.173173 -157.542544) (xy 85.152401 -157.552738) (xy 85.144864 -157.561534)
			(xy 85.126702 -157.584042) (xy 85.084675 -157.623774) (xy 85.037134 -157.656709) (xy 84.985167 -157.682093)
			(xy 84.929965 -157.699344) (xy 84.872792 -157.708068) (xy 84.843874 -157.7086) (xy 84.8146 -157.70806)
			(xy 84.756742 -157.699091) (xy 84.700935 -157.681383) (xy 84.64849 -157.655352) (xy 84.600641 -157.621611)
			(xy 84.579206 -157.601666) (xy 84.57184 -157.594808) (xy 84.553806 -157.587442) (xy 84.463382 -157.587442)
			(xy 84.445348 -157.594808) (xy 84.437982 -157.601666) (xy 84.416527 -157.621587) (xy 84.368676 -157.655316)
			(xy 84.316235 -157.681342) (xy 84.260436 -157.699057) (xy 84.202586 -157.708044) (xy 84.173314 -157.7086)
			(xy 84.146061 -157.708132) (xy 84.09211 -157.700376) (xy 84.039812 -157.685022) (xy 83.990231 -157.66238)
			(xy 83.944378 -157.632913) (xy 83.903185 -157.59722) (xy 83.867491 -157.556027) (xy 83.838023 -157.510174)
			(xy 83.81538 -157.460594) (xy 83.800025 -157.408296) (xy 83.792269 -157.354345) (xy 83.791806 -157.327092)
			(xy 83.792333 -157.29952) (xy 83.800273 -157.244949) (xy 83.815985 -157.192091) (xy 83.839144 -157.142044)
			(xy 83.869266 -157.095853) (xy 83.905723 -157.054479) (xy 83.926426 -157.036262) (xy 83.934561 -157.028675)
			(xy 83.943905 -157.008512) (xy 83.94446 -156.9974) (xy 83.94446 -156.920184) (xy 83.94393 -156.909069)
			(xy 83.934566 -156.88891) (xy 83.926426 -156.881322) (xy 83.905727 -156.863097) (xy 83.869255 -156.821732)
			(xy 83.839121 -156.775545) (xy 83.815953 -156.7255) (xy 83.800234 -156.672639) (xy 83.792292 -156.618066)
			(xy 83.791806 -156.590492) (xy 83.792388 -156.561577) (xy 83.801103 -156.504409) (xy 83.818349 -156.449211)
			(xy 83.843728 -156.397249) (xy 83.876661 -156.349714) (xy 83.916391 -156.307694) (xy 83.938872 -156.289502)
			(xy 83.947641 -156.281947) (xy 83.957817 -156.261183) (xy 83.95843 -156.249624) (xy 83.95843 -156.16936)
			(xy 83.957849 -156.157793) (xy 83.947664 -156.13702) (xy 83.938872 -156.129482) (xy 83.91808 -156.112738)
			(xy 83.880949 -156.074385) (xy 83.849526 -156.031229) (xy 83.824427 -155.984115) (xy 83.80614 -155.933961)
			(xy 83.795023 -155.881748) (xy 83.791294 -155.828495) (xy 81.345863 -155.828495) (xy 81.318801 -155.881595)
			(xy 81.283546 -155.930099) (xy 81.262728 -155.951682) (xy 78.858872 -158.355538) (xy 78.837277 -158.376329)
			(xy 78.788765 -158.411538) (xy 78.735336 -158.438715) (xy 78.678311 -158.457189) (xy 78.619096 -158.466503)
			(xy 78.589124 -158.467044) (xy 59.165744 -158.467044) (xy 59.156244 -158.468175) (xy 59.139031 -158.476491)
			(xy 59.126025 -158.490503) (xy 59.119012 -158.508287) (xy 59.1185 -158.517844) (xy 59.1185 -162.891978)
			(xy 59.118062 -162.902042) (xy 59.110328 -162.920626) (xy 59.103514 -162.928046) (xy 58.181494 -163.850066)
			(xy 58.174097 -163.856915) (xy 58.155498 -163.864653) (xy 58.145426 -163.865052) (xy 53.497988 -163.865052)
			(xy 53.48792 -163.865479) (xy 53.469324 -163.873202) (xy 53.46192 -163.880038) (xy 50.495708 -166.84625)
			(xy 50.488342 -166.853362) (xy 50.480722 -166.872158) (xy 50.480722 -168.464992) (xy 60.095892 -168.464992)
			(xy 60.095892 -160.324292) (xy 60.096355 -160.314287) (xy 60.104071 -160.295824) (xy 60.110878 -160.288478)
			(xy 61.144658 -159.254698) (xy 61.152063 -159.247977) (xy 61.170487 -159.240255) (xy 61.180472 -159.239712)
			(xy 79.662528 -159.239712) (xy 79.672575 -159.239355) (xy 79.691172 -159.231759) (xy 79.698596 -159.22498)
			(xy 80.510126 -158.41345) (xy 80.517503 -158.406692) (xy 80.535948 -158.398993) (xy 80.54594 -158.398464)
			(xy 102.682548 -158.398464) (xy 102.692554 -158.398914) (xy 102.711017 -158.40664) (xy 102.718362 -158.41345)
			(xy 103.2764 -158.971488) (xy 103.283092 -158.978889) (xy 103.290659 -158.997334) (xy 103.291132 -159.007302)
			(xy 103.291132 -160.83788) (xy 105.696512 -160.83788) (xy 105.696512 -150.278846) (xy 105.696972 -150.268842)
			(xy 105.704693 -150.250379) (xy 105.711498 -150.243032) (xy 107.558332 -148.396198) (xy 107.565712 -148.389445)
			(xy 107.584155 -148.381741) (xy 107.594146 -148.381212) (xy 129.678176 -148.381212) (xy 129.688182 -148.381661)
			(xy 129.706644 -148.389389) (xy 129.71399 -148.396198) (xy 131.412742 -150.09495) (xy 131.419465 -150.102353)
			(xy 131.427185 -150.120779) (xy 131.427728 -150.130764) (xy 131.427728 -152.191212) (xy 132.117846 -152.191212)
			(xy 132.118332 -152.163961) (xy 132.126088 -152.110013) (xy 132.141443 -152.057718) (xy 132.164085 -152.008141)
			(xy 132.193551 -151.962291) (xy 132.229242 -151.9211) (xy 132.270433 -151.885409) (xy 132.316283 -151.855943)
			(xy 132.36586 -151.833301) (xy 132.418155 -151.817946) (xy 132.472103 -151.81019) (xy 132.526605 -151.81019)
			(xy 132.580553 -151.817946) (xy 132.632848 -151.833301) (xy 132.682425 -151.855943) (xy 132.728275 -151.885409)
			(xy 132.769466 -151.9211) (xy 132.805157 -151.962291) (xy 132.834623 -152.008141) (xy 132.857265 -152.057718)
			(xy 132.863423 -152.07869) (xy 134.023354 -152.07869) (xy 134.02384 -152.051439) (xy 134.031596 -151.997491)
			(xy 134.046951 -151.945196) (xy 134.069593 -151.895619) (xy 134.099059 -151.849769) (xy 134.13475 -151.808578)
			(xy 134.175941 -151.772887) (xy 134.221791 -151.743421) (xy 134.271368 -151.720779) (xy 134.323663 -151.705424)
			(xy 134.377611 -151.697668) (xy 134.432113 -151.697668) (xy 134.486061 -151.705424) (xy 134.538356 -151.720779)
			(xy 134.587933 -151.743421) (xy 134.633783 -151.772887) (xy 134.674974 -151.808578) (xy 134.710665 -151.849769)
			(xy 134.740131 -151.895619) (xy 134.762773 -151.945196) (xy 134.778128 -151.997491) (xy 134.785884 -152.051439)
			(xy 134.78637 -152.07869) (xy 134.785938 -152.104179) (xy 134.779161 -152.154704) (xy 134.765712 -152.203876)
			(xy 134.745833 -152.250818) (xy 134.719877 -152.294693) (xy 134.688307 -152.334719) (xy 134.670292 -152.352756)
			(xy 134.662418 -152.360376) (xy 134.654544 -152.380188) (xy 134.657338 -152.476454) (xy 134.666482 -152.495758)
			(xy 134.67461 -152.50287) (xy 134.695019 -152.52108) (xy 134.730949 -152.562319) (xy 134.760621 -152.608266)
			(xy 134.783427 -152.65798) (xy 134.7989 -152.710441) (xy 134.804508 -152.74925) (xy 135.34593 -152.74925)
			(xy 135.350001 -152.693628) (xy 135.362127 -152.639191) (xy 135.38205 -152.5871) (xy 135.409346 -152.538465)
			(xy 135.443432 -152.494322) (xy 135.483581 -152.455613) (xy 135.528939 -152.423162) (xy 135.578539 -152.397661)
			(xy 135.631323 -152.379654) (xy 135.686166 -152.369524) (xy 135.7419 -152.367487) (xy 135.797337 -152.373587)
			(xy 135.851294 -152.387693) (xy 135.902623 -152.409505) (xy 135.950229 -152.438559) (xy 135.993097 -152.474234)
			(xy 136.030314 -152.515771) (xy 136.061087 -152.562284) (xy 136.084759 -152.612781) (xy 136.100827 -152.666188)
			(xy 136.108947 -152.721364) (xy 136.109456 -152.74925) (xy 136.108947 -152.777136) (xy 136.100827 -152.832312)
			(xy 136.084759 -152.885719) (xy 136.061087 -152.936216) (xy 136.030314 -152.982729) (xy 135.993097 -153.024266)
			(xy 135.950229 -153.059941) (xy 135.902623 -153.088995) (xy 135.851294 -153.110807) (xy 135.797337 -153.124913)
			(xy 135.7419 -153.131013) (xy 135.686166 -153.128976) (xy 135.631323 -153.118846) (xy 135.578539 -153.100839)
			(xy 135.528939 -153.075338) (xy 135.483581 -153.042887) (xy 135.443432 -153.004178) (xy 135.409346 -152.960035)
			(xy 135.38205 -152.9114) (xy 135.362127 -152.859309) (xy 135.350001 -152.804872) (xy 135.34593 -152.74925)
			(xy 134.804508 -152.74925) (xy 134.806722 -152.764574) (xy 134.807198 -152.791922) (xy 134.806712 -152.819173)
			(xy 134.798956 -152.873121) (xy 134.783601 -152.925416) (xy 134.760959 -152.974993) (xy 134.731493 -153.020843)
			(xy 134.695802 -153.062034) (xy 134.654611 -153.097725) (xy 134.608761 -153.127191) (xy 134.559184 -153.149833)
			(xy 134.506889 -153.165188) (xy 134.452941 -153.172944) (xy 134.398439 -153.172944) (xy 134.344491 -153.165188)
			(xy 134.292196 -153.149833) (xy 134.242619 -153.127191) (xy 134.196769 -153.097725) (xy 134.155578 -153.062034)
			(xy 134.119887 -153.020843) (xy 134.090421 -152.974993) (xy 134.067779 -152.925416) (xy 134.052424 -152.873121)
			(xy 134.044668 -152.819173) (xy 134.044182 -152.791922) (xy 134.044637 -152.766434) (xy 134.051411 -152.71591)
			(xy 134.064856 -152.666739) (xy 134.084731 -152.619797) (xy 134.110683 -152.575922) (xy 134.142248 -152.535894)
			(xy 134.16026 -152.517856) (xy 134.168134 -152.510236) (xy 134.176008 -152.490424) (xy 134.173214 -152.394158)
			(xy 134.16407 -152.374854) (xy 134.155942 -152.367742) (xy 134.135549 -152.349514) (xy 134.099616 -152.30828)
			(xy 134.06994 -152.262337) (xy 134.047131 -152.212627) (xy 134.031655 -152.160168) (xy 134.023831 -152.106037)
			(xy 134.023354 -152.07869) (xy 132.863423 -152.07869) (xy 132.87262 -152.110013) (xy 132.880376 -152.163961)
			(xy 132.880862 -152.191212) (xy 132.880196 -152.222775) (xy 132.869812 -152.28504) (xy 132.849329 -152.344749)
			(xy 132.834888 -152.372822) (xy 132.830062 -152.381712) (xy 132.82803 -152.40127) (xy 132.853684 -152.489408)
			(xy 132.86613 -152.504902) (xy 132.87502 -152.509982) (xy 132.882386 -152.514046) (xy 132.892038 -152.519888)
			(xy 132.914136 -152.52192) (xy 133.008624 -152.488392) (xy 133.024626 -152.472898) (xy 133.02869 -152.462484)
			(xy 133.039369 -152.4357) (xy 133.067659 -152.385458) (xy 133.103192 -152.340049) (xy 133.145156 -152.300507)
			(xy 133.192596 -152.267734) (xy 133.244429 -152.242477) (xy 133.299474 -152.225313) (xy 133.356476 -152.216632)
			(xy 133.385306 -152.216104) (xy 133.412558 -152.216566) (xy 133.466507 -152.224324) (xy 133.518802 -152.23968)
			(xy 133.56838 -152.262322) (xy 133.614231 -152.291789) (xy 133.655422 -152.327482) (xy 133.691114 -152.368673)
			(xy 133.720581 -152.414525) (xy 133.743222 -152.464103) (xy 133.758578 -152.516399) (xy 133.766334 -152.570348)
			(xy 133.766334 -152.624852) (xy 133.758578 -152.678801) (xy 133.743222 -152.731097) (xy 133.720581 -152.780675)
			(xy 133.691114 -152.826527) (xy 133.655422 -152.867718) (xy 133.614231 -152.903411) (xy 133.56838 -152.932878)
			(xy 133.518802 -152.95552) (xy 133.466507 -152.970876) (xy 133.412558 -152.978634) (xy 133.385306 -152.97912)
			(xy 133.360071 -152.978718) (xy 133.310037 -152.972101) (xy 133.261317 -152.958929) (xy 133.214765 -152.939434)
			(xy 133.192774 -152.92705) (xy 133.183122 -152.921208) (xy 133.161024 -152.919176) (xy 133.066536 -152.952704)
			(xy 133.050534 -152.968198) (xy 133.04647 -152.978612) (xy 133.035739 -153.005373) (xy 133.007455 -153.055613)
			(xy 132.97193 -153.101022) (xy 132.929973 -153.140565) (xy 132.882541 -153.17334) (xy 132.830715 -153.198601)
			(xy 132.775677 -153.215771) (xy 132.718681 -153.224459) (xy 132.689854 -153.224992) (xy 132.662601 -153.224565)
			(xy 132.60865 -153.216802) (xy 132.556353 -153.20144) (xy 132.506775 -153.178792) (xy 132.460924 -153.14932)
			(xy 132.419734 -153.113622) (xy 132.384043 -153.072426) (xy 132.354578 -153.026571) (xy 132.331938 -152.976988)
			(xy 132.316585 -152.924689) (xy 132.308831 -152.870737) (xy 132.308346 -152.843484) (xy 132.309009 -152.811921)
			(xy 132.319394 -152.749656) (xy 132.339879 -152.689947) (xy 132.35432 -152.661874) (xy 132.359146 -152.652984)
			(xy 132.361178 -152.633426) (xy 132.335524 -152.545288) (xy 132.323078 -152.529794) (xy 132.314188 -152.524714)
			(xy 132.289062 -152.510206) (xy 132.24318 -152.474696) (xy 132.203207 -152.432645) (xy 132.170065 -152.385024)
			(xy 132.144518 -152.332933) (xy 132.127157 -152.277572) (xy 132.118382 -152.220221) (xy 132.117846 -152.191212)
			(xy 131.427728 -152.191212) (xy 131.427728 -153.200608) (xy 131.428112 -153.210652) (xy 131.435691 -153.229248)
			(xy 131.44246 -153.236676) (xy 131.850384 -153.6446) (xy 134.76681 -153.6446) (xy 134.770881 -153.588978)
			(xy 134.783007 -153.534541) (xy 134.80293 -153.48245) (xy 134.830226 -153.433815) (xy 134.864312 -153.389672)
			(xy 134.904461 -153.350963) (xy 134.949819 -153.318512) (xy 134.999419 -153.293011) (xy 135.052203 -153.275004)
			(xy 135.107046 -153.264874) (xy 135.16278 -153.262837) (xy 135.218217 -153.268937) (xy 135.272174 -153.283043)
			(xy 135.323503 -153.304855) (xy 135.371109 -153.333909) (xy 135.413977 -153.369584) (xy 135.451194 -153.411121)
			(xy 135.481967 -153.457634) (xy 135.505639 -153.508131) (xy 135.521707 -153.561538) (xy 135.529827 -153.616714)
			(xy 135.530336 -153.6446) (xy 135.529827 -153.672486) (xy 135.521707 -153.727662) (xy 135.505639 -153.781069)
			(xy 135.481967 -153.831566) (xy 135.451194 -153.878079) (xy 135.413977 -153.919616) (xy 135.371109 -153.955291)
			(xy 135.323503 -153.984345) (xy 135.272174 -154.006157) (xy 135.218217 -154.020263) (xy 135.16278 -154.026363)
			(xy 135.107046 -154.024326) (xy 135.052203 -154.014196) (xy 134.999419 -153.996189) (xy 134.949819 -153.970688)
			(xy 134.904461 -153.938237) (xy 134.864312 -153.899528) (xy 134.830226 -153.855385) (xy 134.80293 -153.80675)
			(xy 134.783007 -153.754659) (xy 134.770881 -153.700222) (xy 134.76681 -153.6446) (xy 131.850384 -153.6446)
			(xy 132.282438 -154.076654) (xy 132.289163 -154.084057) (xy 132.296882 -154.102483) (xy 132.297424 -154.112468)
			(xy 132.297424 -154.345132) (xy 136.69086 -154.345132) (xy 136.694931 -154.28951) (xy 136.707057 -154.235073)
			(xy 136.72698 -154.182982) (xy 136.754276 -154.134347) (xy 136.788362 -154.090204) (xy 136.828511 -154.051495)
			(xy 136.873869 -154.019044) (xy 136.923469 -153.993543) (xy 136.976253 -153.975536) (xy 137.031096 -153.965406)
			(xy 137.08683 -153.963369) (xy 137.142267 -153.969469) (xy 137.196224 -153.983575) (xy 137.247553 -154.005387)
			(xy 137.295159 -154.034441) (xy 137.338027 -154.070116) (xy 137.375244 -154.111653) (xy 137.406017 -154.158166)
			(xy 137.429689 -154.208663) (xy 137.445757 -154.26207) (xy 137.453877 -154.317246) (xy 137.454386 -154.345132)
			(xy 137.453877 -154.373018) (xy 137.445757 -154.428194) (xy 137.429689 -154.481601) (xy 137.406017 -154.532098)
			(xy 137.375244 -154.578611) (xy 137.338027 -154.620148) (xy 137.295159 -154.655823) (xy 137.247553 -154.684877)
			(xy 137.196224 -154.706689) (xy 137.142267 -154.720795) (xy 137.08683 -154.726895) (xy 137.031096 -154.724858)
			(xy 136.976253 -154.714728) (xy 136.923469 -154.696721) (xy 136.873869 -154.67122) (xy 136.828511 -154.638769)
			(xy 136.788362 -154.60006) (xy 136.754276 -154.555917) (xy 136.72698 -154.507282) (xy 136.707057 -154.455191)
			(xy 136.694931 -154.400754) (xy 136.69086 -154.345132) (xy 132.297424 -154.345132) (xy 132.297424 -155.52166)
			(xy 135.725662 -155.52166) (xy 135.726138 -155.493749) (xy 135.734277 -155.438522) (xy 135.750377 -155.385072)
			(xy 135.774094 -155.334537) (xy 135.80492 -155.287998) (xy 135.823198 -155.266898) (xy 135.829548 -155.259786)
			(xy 135.836152 -155.242514) (xy 135.836152 -155.155392) (xy 135.829548 -155.13812) (xy 135.823198 -155.131008)
			(xy 135.804902 -155.109923) (xy 135.774077 -155.063381) (xy 135.750365 -155.012842) (xy 135.734273 -154.959388)
			(xy 135.726144 -154.904158) (xy 135.725662 -154.876246) (xy 135.726148 -154.848995) (xy 135.733904 -154.795047)
			(xy 135.749259 -154.742752) (xy 135.771901 -154.693175) (xy 135.801367 -154.647325) (xy 135.837058 -154.606134)
			(xy 135.878249 -154.570443) (xy 135.924099 -154.540977) (xy 135.973676 -154.518335) (xy 136.025971 -154.50298)
			(xy 136.079919 -154.495224) (xy 136.134421 -154.495224) (xy 136.188369 -154.50298) (xy 136.240664 -154.518335)
			(xy 136.290241 -154.540977) (xy 136.336091 -154.570443) (xy 136.377282 -154.606134) (xy 136.412973 -154.647325)
			(xy 136.442439 -154.693175) (xy 136.465081 -154.742752) (xy 136.480436 -154.795047) (xy 136.488192 -154.848995)
			(xy 136.488678 -154.876246) (xy 136.488196 -154.904157) (xy 136.480056 -154.959383) (xy 136.463957 -155.012833)
			(xy 136.440243 -155.063367) (xy 136.409418 -155.109907) (xy 136.391142 -155.131008) (xy 136.384792 -155.13812)
			(xy 136.378188 -155.155392) (xy 136.378188 -155.242514) (xy 136.384792 -155.259786) (xy 136.391142 -155.266898)
			(xy 136.4094 -155.288014) (xy 136.440229 -155.334549) (xy 136.463947 -155.385079) (xy 136.480049 -155.438527)
			(xy 136.488189 -155.49375) (xy 136.488678 -155.52166) (xy 136.488192 -155.548911) (xy 136.480436 -155.602859)
			(xy 136.465081 -155.655154) (xy 136.442439 -155.704731) (xy 136.412973 -155.750581) (xy 136.377282 -155.791772)
			(xy 136.336091 -155.827463) (xy 136.290241 -155.856929) (xy 136.240664 -155.879571) (xy 136.188369 -155.894926)
			(xy 136.134421 -155.902682) (xy 136.079919 -155.902682) (xy 136.025971 -155.894926) (xy 135.973676 -155.879571)
			(xy 135.924099 -155.856929) (xy 135.878249 -155.827463) (xy 135.837058 -155.791772) (xy 135.801367 -155.750581)
			(xy 135.771901 -155.704731) (xy 135.749259 -155.655154) (xy 135.733904 -155.602859) (xy 135.726148 -155.548911)
			(xy 135.725662 -155.52166) (xy 132.297424 -155.52166) (xy 132.297424 -156.306012) (xy 132.296959 -156.316016)
			(xy 132.289244 -156.33448) (xy 132.282438 -156.341826) (xy 132.13334 -156.490924) (xy 132.125921 -156.497594)
			(xy 132.10749 -156.505176) (xy 132.097526 -156.505656) (xy 130.442208 -156.505656) (xy 130.432137 -156.506071)
			(xy 130.413539 -156.513797) (xy 130.40614 -156.520642) (xy 130.385058 -156.541724) (xy 130.377633 -156.548386)
			(xy 130.359207 -156.555973) (xy 130.349244 -156.556456) (xy 126.251208 -156.556456) (xy 126.241137 -156.556871)
			(xy 126.222539 -156.564597) (xy 126.21514 -156.571442) (xy 123.19381 -159.592772) (xy 123.186952 -159.592772)
			(xy 122.97918 -159.800544) (xy 122.972482 -159.808022) (xy 122.964894 -159.826584) (xy 122.964448 -159.836612)
			(xy 122.964448 -160.852612) (xy 123.659646 -160.852612) (xy 123.660132 -160.825361) (xy 123.667888 -160.771413)
			(xy 123.683243 -160.719118) (xy 123.705885 -160.669541) (xy 123.735351 -160.623691) (xy 123.771042 -160.5825)
			(xy 123.812233 -160.546809) (xy 123.858083 -160.517343) (xy 123.90766 -160.494701) (xy 123.959955 -160.479346)
			(xy 124.013903 -160.47159) (xy 124.068405 -160.47159) (xy 124.122353 -160.479346) (xy 124.174648 -160.494701)
			(xy 124.224225 -160.517343) (xy 124.270075 -160.546809) (xy 124.311266 -160.5825) (xy 124.346957 -160.623691)
			(xy 124.376423 -160.669541) (xy 124.399065 -160.719118) (xy 124.403731 -160.73501) (xy 125.549914 -160.73501)
			(xy 125.5504 -160.707759) (xy 125.558156 -160.653811) (xy 125.573511 -160.601516) (xy 125.596153 -160.551939)
			(xy 125.625619 -160.506089) (xy 125.66131 -160.464898) (xy 125.702501 -160.429207) (xy 125.748351 -160.399741)
			(xy 125.797928 -160.377099) (xy 125.850223 -160.361744) (xy 125.904171 -160.353988) (xy 125.958673 -160.353988)
			(xy 126.012621 -160.361744) (xy 126.064916 -160.377099) (xy 126.114493 -160.399741) (xy 126.160343 -160.429207)
			(xy 126.201534 -160.464898) (xy 126.237225 -160.506089) (xy 126.266691 -160.551939) (xy 126.289333 -160.601516)
			(xy 126.304688 -160.653811) (xy 126.312444 -160.707759) (xy 126.31293 -160.73501) (xy 126.312484 -160.761804)
			(xy 126.304979 -160.814864) (xy 126.290129 -160.866354) (xy 126.268229 -160.915263) (xy 126.239707 -160.960631)
			(xy 126.22276 -160.98139) (xy 126.216664 -160.988502) (xy 126.210568 -161.00552) (xy 126.212092 -161.091372)
			(xy 126.21895 -161.108136) (xy 126.2253 -161.115248) (xy 126.243886 -161.136439) (xy 126.275271 -161.183257)
			(xy 126.299425 -161.234183) (xy 126.315825 -161.288108) (xy 126.324111 -161.34386) (xy 126.324614 -161.372042)
			(xy 126.324128 -161.399293) (xy 126.322495 -161.41065) (xy 126.88773 -161.41065) (xy 126.891801 -161.355028)
			(xy 126.903927 -161.300591) (xy 126.92385 -161.2485) (xy 126.951146 -161.199865) (xy 126.985232 -161.155722)
			(xy 127.025381 -161.117013) (xy 127.070739 -161.084562) (xy 127.120339 -161.059061) (xy 127.173123 -161.041054)
			(xy 127.227966 -161.030924) (xy 127.2837 -161.028887) (xy 127.339137 -161.034987) (xy 127.393094 -161.049093)
			(xy 127.444423 -161.070905) (xy 127.492029 -161.099959) (xy 127.534897 -161.135634) (xy 127.572114 -161.177171)
			(xy 127.602887 -161.223684) (xy 127.626559 -161.274181) (xy 127.642627 -161.327588) (xy 127.650747 -161.382764)
			(xy 127.651256 -161.41065) (xy 127.650747 -161.438536) (xy 127.642627 -161.493712) (xy 127.626559 -161.547119)
			(xy 127.602887 -161.597616) (xy 127.572114 -161.644129) (xy 127.534897 -161.685666) (xy 127.492029 -161.721341)
			(xy 127.444423 -161.750395) (xy 127.393094 -161.772207) (xy 127.339137 -161.786313) (xy 127.2837 -161.792413)
			(xy 127.227966 -161.790376) (xy 127.173123 -161.780246) (xy 127.120339 -161.762239) (xy 127.070739 -161.736738)
			(xy 127.025381 -161.704287) (xy 126.985232 -161.665578) (xy 126.951146 -161.621435) (xy 126.92385 -161.5728)
			(xy 126.903927 -161.520709) (xy 126.891801 -161.466272) (xy 126.88773 -161.41065) (xy 126.322495 -161.41065)
			(xy 126.316372 -161.453241) (xy 126.301017 -161.505536) (xy 126.278375 -161.555113) (xy 126.248909 -161.600963)
			(xy 126.213218 -161.642154) (xy 126.172027 -161.677845) (xy 126.126177 -161.707311) (xy 126.0766 -161.729953)
			(xy 126.024305 -161.745308) (xy 125.970357 -161.753064) (xy 125.915855 -161.753064) (xy 125.861907 -161.745308)
			(xy 125.809612 -161.729953) (xy 125.760035 -161.707311) (xy 125.714185 -161.677845) (xy 125.672994 -161.642154)
			(xy 125.637303 -161.600963) (xy 125.607837 -161.555113) (xy 125.585195 -161.505536) (xy 125.56984 -161.453241)
			(xy 125.562084 -161.399293) (xy 125.561598 -161.372042) (xy 125.562067 -161.345249) (xy 125.569567 -161.292189)
			(xy 125.58441 -161.240699) (xy 125.606306 -161.19179) (xy 125.634823 -161.146422) (xy 125.651768 -161.125662)
			(xy 125.657864 -161.11855) (xy 125.66396 -161.101532) (xy 125.662436 -161.01568) (xy 125.655578 -160.998916)
			(xy 125.649228 -160.991804) (xy 125.630608 -160.970642) (xy 125.59923 -160.923815) (xy 125.575084 -160.872882)
			(xy 125.558692 -160.81895) (xy 125.550413 -160.763194) (xy 125.549914 -160.73501) (xy 124.403731 -160.73501)
			(xy 124.41442 -160.771413) (xy 124.422176 -160.825361) (xy 124.422662 -160.852612) (xy 124.421996 -160.884175)
			(xy 124.411612 -160.94644) (xy 124.391129 -161.006149) (xy 124.376688 -161.034222) (xy 124.371862 -161.043112)
			(xy 124.36983 -161.06267) (xy 124.395484 -161.150808) (xy 124.40793 -161.166302) (xy 124.41682 -161.171382)
			(xy 124.424186 -161.175446) (xy 124.433838 -161.181288) (xy 124.455936 -161.18332) (xy 124.550424 -161.149792)
			(xy 124.566426 -161.134298) (xy 124.57049 -161.123884) (xy 124.581169 -161.0971) (xy 124.609459 -161.046858)
			(xy 124.644992 -161.001449) (xy 124.686956 -160.961907) (xy 124.734396 -160.929134) (xy 124.786229 -160.903877)
			(xy 124.841274 -160.886713) (xy 124.898276 -160.878032) (xy 124.927106 -160.877504) (xy 124.954358 -160.877966)
			(xy 125.008307 -160.885724) (xy 125.060602 -160.90108) (xy 125.11018 -160.923722) (xy 125.156031 -160.953189)
			(xy 125.197222 -160.988882) (xy 125.232914 -161.030073) (xy 125.262381 -161.075925) (xy 125.285022 -161.125503)
			(xy 125.300378 -161.177799) (xy 125.308134 -161.231748) (xy 125.308134 -161.286252) (xy 125.300378 -161.340201)
			(xy 125.285022 -161.392497) (xy 125.262381 -161.442075) (xy 125.232914 -161.487927) (xy 125.197222 -161.529118)
			(xy 125.156031 -161.564811) (xy 125.11018 -161.594278) (xy 125.060602 -161.61692) (xy 125.008307 -161.632276)
			(xy 124.954358 -161.640034) (xy 124.927106 -161.64052) (xy 124.901871 -161.640118) (xy 124.851837 -161.633501)
			(xy 124.803117 -161.620329) (xy 124.756565 -161.600834) (xy 124.734574 -161.58845) (xy 124.724922 -161.582608)
			(xy 124.702824 -161.580576) (xy 124.608336 -161.614104) (xy 124.592334 -161.629598) (xy 124.58827 -161.640012)
			(xy 124.577539 -161.666773) (xy 124.549255 -161.717013) (xy 124.51373 -161.762422) (xy 124.471773 -161.801965)
			(xy 124.424341 -161.83474) (xy 124.372515 -161.860001) (xy 124.317477 -161.877171) (xy 124.260481 -161.885859)
			(xy 124.231654 -161.886392) (xy 124.204401 -161.885965) (xy 124.15045 -161.878202) (xy 124.098153 -161.86284)
			(xy 124.048575 -161.840192) (xy 124.002724 -161.81072) (xy 123.961534 -161.775022) (xy 123.925843 -161.733826)
			(xy 123.896378 -161.687971) (xy 123.873738 -161.638388) (xy 123.858385 -161.586089) (xy 123.850631 -161.532137)
			(xy 123.850146 -161.504884) (xy 123.850809 -161.473321) (xy 123.861194 -161.411056) (xy 123.881679 -161.351347)
			(xy 123.89612 -161.323274) (xy 123.900946 -161.314384) (xy 123.902978 -161.294826) (xy 123.877324 -161.206688)
			(xy 123.864878 -161.191194) (xy 123.855988 -161.186114) (xy 123.830862 -161.171606) (xy 123.78498 -161.136096)
			(xy 123.745007 -161.094045) (xy 123.711865 -161.046424) (xy 123.686318 -160.994333) (xy 123.668957 -160.938972)
			(xy 123.660182 -160.881621) (xy 123.659646 -160.852612) (xy 122.964448 -160.852612) (xy 122.964448 -161.862008)
			(xy 122.964826 -161.872053) (xy 122.972408 -161.890649) (xy 122.97918 -161.898076) (xy 123.387104 -162.306)
			(xy 126.30861 -162.306) (xy 126.312681 -162.250378) (xy 126.324807 -162.195941) (xy 126.34473 -162.14385)
			(xy 126.372026 -162.095215) (xy 126.406112 -162.051072) (xy 126.446261 -162.012363) (xy 126.491619 -161.979912)
			(xy 126.541219 -161.954411) (xy 126.594003 -161.936404) (xy 126.648846 -161.926274) (xy 126.70458 -161.924237)
			(xy 126.760017 -161.930337) (xy 126.813974 -161.944443) (xy 126.865303 -161.966255) (xy 126.912909 -161.995309)
			(xy 126.955777 -162.030984) (xy 126.992994 -162.072521) (xy 127.023767 -162.119034) (xy 127.047439 -162.169531)
			(xy 127.063507 -162.222938) (xy 127.071627 -162.278114) (xy 127.072136 -162.306) (xy 127.071627 -162.333886)
			(xy 127.063507 -162.389062) (xy 127.047439 -162.442469) (xy 127.023767 -162.492966) (xy 126.992994 -162.539479)
			(xy 126.955777 -162.581016) (xy 126.912909 -162.616691) (xy 126.865303 -162.645745) (xy 126.813974 -162.667557)
			(xy 126.760017 -162.681663) (xy 126.70458 -162.687763) (xy 126.648846 -162.685726) (xy 126.594003 -162.675596)
			(xy 126.541219 -162.657589) (xy 126.491619 -162.632088) (xy 126.446261 -162.599637) (xy 126.406112 -162.560928)
			(xy 126.372026 -162.516785) (xy 126.34473 -162.46815) (xy 126.324807 -162.416059) (xy 126.312681 -162.361622)
			(xy 126.30861 -162.306) (xy 123.387104 -162.306) (xy 123.824238 -162.743134) (xy 123.830997 -162.750509)
			(xy 123.838696 -162.768956) (xy 123.839224 -162.778948) (xy 123.839224 -164.18306) (xy 127.267462 -164.18306)
			(xy 127.267938 -164.155149) (xy 127.276077 -164.099922) (xy 127.292177 -164.046472) (xy 127.315894 -163.995937)
			(xy 127.34672 -163.949398) (xy 127.364998 -163.928298) (xy 127.371348 -163.921186) (xy 127.377952 -163.903914)
			(xy 127.377952 -163.816792) (xy 127.371348 -163.79952) (xy 127.364998 -163.792408) (xy 127.346702 -163.771323)
			(xy 127.315877 -163.724781) (xy 127.292165 -163.674242) (xy 127.276073 -163.620788) (xy 127.267944 -163.565558)
			(xy 127.267462 -163.537646) (xy 127.267948 -163.510395) (xy 127.275704 -163.456447) (xy 127.291059 -163.404152)
			(xy 127.313701 -163.354575) (xy 127.343167 -163.308725) (xy 127.378858 -163.267534) (xy 127.420049 -163.231843)
			(xy 127.465899 -163.202377) (xy 127.515476 -163.179735) (xy 127.567771 -163.16438) (xy 127.621719 -163.156624)
			(xy 127.676221 -163.156624) (xy 127.730169 -163.16438) (xy 127.782464 -163.179735) (xy 127.832041 -163.202377)
			(xy 127.877891 -163.231843) (xy 127.919082 -163.267534) (xy 127.954773 -163.308725) (xy 127.984239 -163.354575)
			(xy 128.006881 -163.404152) (xy 128.022236 -163.456447) (xy 128.029992 -163.510395) (xy 128.030478 -163.537646)
			(xy 128.029996 -163.565557) (xy 128.021856 -163.620783) (xy 128.005757 -163.674233) (xy 127.982043 -163.724767)
			(xy 127.951218 -163.771307) (xy 127.932942 -163.792408) (xy 127.926592 -163.79952) (xy 127.919988 -163.816792)
			(xy 127.919988 -163.903914) (xy 127.926592 -163.921186) (xy 127.932942 -163.928298) (xy 127.9512 -163.949414)
			(xy 127.982029 -163.995949) (xy 128.005747 -164.046479) (xy 128.021849 -164.099927) (xy 128.029989 -164.15515)
			(xy 128.030478 -164.18306) (xy 128.029992 -164.210311) (xy 128.022236 -164.264259) (xy 128.006881 -164.316554)
			(xy 127.984239 -164.366131) (xy 127.954773 -164.411981) (xy 127.919082 -164.453172) (xy 127.877891 -164.488863)
			(xy 127.832041 -164.518329) (xy 127.782464 -164.540971) (xy 127.730169 -164.556326) (xy 127.676221 -164.564082)
			(xy 127.621719 -164.564082) (xy 127.567771 -164.556326) (xy 127.515476 -164.540971) (xy 127.465899 -164.518329)
			(xy 127.420049 -164.488863) (xy 127.378858 -164.453172) (xy 127.343167 -164.411981) (xy 127.313701 -164.366131)
			(xy 127.291059 -164.316554) (xy 127.275704 -164.264259) (xy 127.267948 -164.210311) (xy 127.267462 -164.18306)
			(xy 123.839224 -164.18306) (xy 123.839224 -164.972492) (xy 123.838801 -164.982501) (xy 123.831056 -165.000964)
			(xy 123.824238 -165.008306) (xy 123.68022 -165.152324) (xy 123.672808 -165.159002) (xy 123.654372 -165.166579)
			(xy 123.644406 -165.167056) (xy 121.984008 -165.167056) (xy 121.973937 -165.167471) (xy 121.955339 -165.175197)
			(xy 121.94794 -165.182042) (xy 121.926858 -165.203124) (xy 121.919433 -165.209786) (xy 121.901007 -165.217373)
			(xy 121.891044 -165.217856) (xy 119.084852 -165.217856) (xy 119.074784 -165.218294) (xy 119.056185 -165.226004)
			(xy 119.048784 -165.232842) (xy 118.602506 -165.67912) (xy 118.595098 -165.685804) (xy 118.576659 -165.693378)
			(xy 118.566692 -165.693852) (xy 114.777012 -165.693852) (xy 114.766942 -165.69427) (xy 114.748343 -165.701995)
			(xy 114.740944 -165.708838) (xy 114.6683 -165.781482) (xy 114.661574 -165.788938) (xy 114.654005 -165.807517)
			(xy 114.653568 -165.81755) (xy 114.653568 -167.583612) (xy 115.379246 -167.583612) (xy 115.379732 -167.556361)
			(xy 115.387488 -167.502413) (xy 115.402843 -167.450118) (xy 115.425485 -167.400541) (xy 115.454951 -167.354691)
			(xy 115.490642 -167.3135) (xy 115.531833 -167.277809) (xy 115.577683 -167.248343) (xy 115.62726 -167.225701)
			(xy 115.679555 -167.210346) (xy 115.733503 -167.20259) (xy 115.788005 -167.20259) (xy 115.841953 -167.210346)
			(xy 115.894248 -167.225701) (xy 115.943825 -167.248343) (xy 115.989675 -167.277809) (xy 116.030866 -167.3135)
			(xy 116.066557 -167.354691) (xy 116.096023 -167.400541) (xy 116.118665 -167.450118) (xy 116.13402 -167.502413)
			(xy 116.141776 -167.556361) (xy 116.142262 -167.583612) (xy 116.141596 -167.615175) (xy 116.131212 -167.67744)
			(xy 116.110729 -167.737149) (xy 116.096288 -167.765222) (xy 116.091462 -167.774112) (xy 116.08943 -167.79367)
			(xy 116.115084 -167.881808) (xy 116.12753 -167.897302) (xy 116.13642 -167.902382) (xy 116.143786 -167.906446)
			(xy 116.153438 -167.912288) (xy 116.175536 -167.91432) (xy 116.270024 -167.880792) (xy 116.286026 -167.865298)
			(xy 116.29009 -167.854884) (xy 116.300769 -167.8281) (xy 116.329059 -167.777858) (xy 116.364592 -167.732449)
			(xy 116.406556 -167.692907) (xy 116.453996 -167.660134) (xy 116.505829 -167.634877) (xy 116.560874 -167.617713)
			(xy 116.617876 -167.609032) (xy 116.646706 -167.608504) (xy 116.673958 -167.608966) (xy 116.727907 -167.616724)
			(xy 116.780202 -167.63208) (xy 116.82978 -167.654722) (xy 116.875631 -167.684189) (xy 116.916822 -167.719882)
			(xy 116.952514 -167.761073) (xy 116.981981 -167.806925) (xy 117.004622 -167.856503) (xy 117.019978 -167.908799)
			(xy 117.027734 -167.962748) (xy 117.027734 -168.017252) (xy 117.019978 -168.071201) (xy 117.010628 -168.103042)
			(xy 117.269514 -168.103042) (xy 117.270022 -168.075568) (xy 117.277908 -168.021189) (xy 117.293523 -167.968507)
			(xy 117.316543 -167.918614) (xy 117.34649 -167.872544) (xy 117.364256 -167.851582) (xy 117.370352 -167.84447)
			(xy 117.376702 -167.827452) (xy 117.376702 -167.7416) (xy 117.370352 -167.724582) (xy 117.364256 -167.71747)
			(xy 117.34649 -167.69651) (xy 117.316567 -167.650427) (xy 117.293555 -167.600532) (xy 117.27793 -167.547855)
			(xy 117.270013 -167.493482) (xy 117.269514 -167.46601) (xy 117.27 -167.438759) (xy 117.277756 -167.384811)
			(xy 117.293111 -167.332516) (xy 117.315753 -167.282939) (xy 117.345219 -167.237089) (xy 117.38091 -167.195898)
			(xy 117.422101 -167.160207) (xy 117.467951 -167.130741) (xy 117.517528 -167.108099) (xy 117.569823 -167.092744)
			(xy 117.623771 -167.084988) (xy 117.678273 -167.084988) (xy 117.732221 -167.092744) (xy 117.784516 -167.108099)
			(xy 117.834093 -167.130741) (xy 117.879943 -167.160207) (xy 117.921134 -167.195898) (xy 117.956825 -167.237089)
			(xy 117.986291 -167.282939) (xy 118.008933 -167.332516) (xy 118.024288 -167.384811) (xy 118.032044 -167.438759)
			(xy 118.03253 -167.46601) (xy 118.032042 -167.493484) (xy 118.02415 -167.547864) (xy 118.008529 -167.600546)
			(xy 117.985505 -167.650439) (xy 117.955555 -167.696508) (xy 117.937788 -167.71747) (xy 117.931692 -167.724582)
			(xy 117.925342 -167.7416) (xy 117.925342 -167.827452) (xy 117.931692 -167.84447) (xy 117.937788 -167.851582)
			(xy 117.955523 -167.872568) (xy 117.985452 -167.918643) (xy 118.008471 -167.968531) (xy 118.024104 -168.021203)
			(xy 118.032027 -168.075571) (xy 118.03253 -168.103042) (xy 118.032044 -168.130293) (xy 118.030411 -168.14165)
			(xy 118.60733 -168.14165) (xy 118.611401 -168.086028) (xy 118.623527 -168.031591) (xy 118.64345 -167.9795)
			(xy 118.670746 -167.930865) (xy 118.704832 -167.886722) (xy 118.744981 -167.848013) (xy 118.790339 -167.815562)
			(xy 118.839939 -167.790061) (xy 118.892723 -167.772054) (xy 118.947566 -167.761924) (xy 119.0033 -167.759887)
			(xy 119.058737 -167.765987) (xy 119.112694 -167.780093) (xy 119.164023 -167.801905) (xy 119.211629 -167.830959)
			(xy 119.254497 -167.866634) (xy 119.291714 -167.908171) (xy 119.322487 -167.954684) (xy 119.346159 -168.005181)
			(xy 119.349237 -168.015412) (xy 139.30757 -168.015412) (xy 139.30807 -167.986494) (xy 139.316799 -167.929321)
			(xy 139.334059 -167.874121) (xy 139.359454 -167.822158) (xy 139.392402 -167.774625) (xy 139.432148 -167.73261)
			(xy 139.454636 -167.714422) (xy 139.46339 -167.706852) (xy 139.473576 -167.686099) (xy 139.474194 -167.674544)
			(xy 139.474194 -167.59428) (xy 139.47358 -167.582718) (xy 139.463416 -167.561946) (xy 139.454636 -167.554402)
			(xy 139.432161 -167.536201) (xy 139.392424 -167.494184) (xy 139.359483 -167.446652) (xy 139.334092 -167.394692)
			(xy 139.316835 -167.339496) (xy 139.308105 -167.282328) (xy 139.30757 -167.253412) (xy 139.308056 -167.226161)
			(xy 139.315812 -167.172213) (xy 139.331167 -167.119918) (xy 139.353809 -167.070341) (xy 139.383275 -167.024491)
			(xy 139.418966 -166.9833) (xy 139.460157 -166.947609) (xy 139.506007 -166.918143) (xy 139.555584 -166.895501)
			(xy 139.607879 -166.880146) (xy 139.661827 -166.87239) (xy 139.716329 -166.87239) (xy 139.770277 -166.880146)
			(xy 139.822572 -166.895501) (xy 139.872149 -166.918143) (xy 139.917999 -166.947609) (xy 139.95919 -166.9833)
			(xy 139.994881 -167.024491) (xy 140.024347 -167.070341) (xy 140.046989 -167.119918) (xy 140.062344 -167.172213)
			(xy 140.0701 -167.226161) (xy 140.070586 -167.253412) (xy 140.07001 -167.282327) (xy 140.061294 -167.339496)
			(xy 140.044048 -167.394694) (xy 140.018667 -167.446656) (xy 139.985733 -167.494191) (xy 139.946001 -167.53621)
			(xy 139.92352 -167.554402) (xy 139.914748 -167.561954) (xy 139.904574 -167.582721) (xy 139.903962 -167.59428)
			(xy 139.903962 -167.674544) (xy 139.904543 -167.686111) (xy 139.914728 -167.706884) (xy 139.92352 -167.714422)
			(xy 139.946018 -167.732596) (xy 139.985752 -167.77462) (xy 140.018688 -167.822158) (xy 140.044074 -167.874123)
			(xy 140.061327 -167.929323) (xy 140.070053 -167.986495) (xy 140.070586 -168.015412) (xy 140.0701 -168.042663)
			(xy 140.062344 -168.096611) (xy 140.046989 -168.148906) (xy 140.024347 -168.198483) (xy 139.994881 -168.244333)
			(xy 139.95919 -168.285524) (xy 139.917999 -168.321215) (xy 139.872149 -168.350681) (xy 139.822572 -168.373323)
			(xy 139.770277 -168.388678) (xy 139.716329 -168.396434) (xy 139.661827 -168.396434) (xy 139.607879 -168.388678)
			(xy 139.555584 -168.373323) (xy 139.506007 -168.350681) (xy 139.460157 -168.321215) (xy 139.418966 -168.285524)
			(xy 139.383275 -168.244333) (xy 139.353809 -168.198483) (xy 139.331167 -168.148906) (xy 139.315812 -168.096611)
			(xy 139.308056 -168.042663) (xy 139.30757 -168.015412) (xy 119.349237 -168.015412) (xy 119.362227 -168.058588)
			(xy 119.370347 -168.113764) (xy 119.370856 -168.14165) (xy 119.370347 -168.169536) (xy 119.362227 -168.224712)
			(xy 119.346159 -168.278119) (xy 119.322487 -168.328616) (xy 119.291714 -168.375129) (xy 119.254497 -168.416666)
			(xy 119.211629 -168.452341) (xy 119.164023 -168.481395) (xy 119.112694 -168.503207) (xy 119.058737 -168.517313)
			(xy 119.0033 -168.523413) (xy 118.947566 -168.521376) (xy 118.892723 -168.511246) (xy 118.839939 -168.493239)
			(xy 118.790339 -168.467738) (xy 118.744981 -168.435287) (xy 118.704832 -168.396578) (xy 118.670746 -168.352435)
			(xy 118.64345 -168.3038) (xy 118.623527 -168.251709) (xy 118.611401 -168.197272) (xy 118.60733 -168.14165)
			(xy 118.030411 -168.14165) (xy 118.024288 -168.184241) (xy 118.008933 -168.236536) (xy 117.986291 -168.286113)
			(xy 117.956825 -168.331963) (xy 117.921134 -168.373154) (xy 117.879943 -168.408845) (xy 117.834093 -168.438311)
			(xy 117.784516 -168.460953) (xy 117.732221 -168.476308) (xy 117.678273 -168.484064) (xy 117.623771 -168.484064)
			(xy 117.569823 -168.476308) (xy 117.517528 -168.460953) (xy 117.467951 -168.438311) (xy 117.422101 -168.408845)
			(xy 117.38091 -168.373154) (xy 117.345219 -168.331963) (xy 117.315753 -168.286113) (xy 117.293111 -168.236536)
			(xy 117.277756 -168.184241) (xy 117.27 -168.130293) (xy 117.269514 -168.103042) (xy 117.010628 -168.103042)
			(xy 117.004622 -168.123497) (xy 116.981981 -168.173075) (xy 116.952514 -168.218927) (xy 116.916822 -168.260118)
			(xy 116.875631 -168.295811) (xy 116.82978 -168.325278) (xy 116.780202 -168.34792) (xy 116.727907 -168.363276)
			(xy 116.673958 -168.371034) (xy 116.646706 -168.37152) (xy 116.621471 -168.371118) (xy 116.571437 -168.364501)
			(xy 116.522717 -168.351329) (xy 116.476165 -168.331834) (xy 116.454174 -168.31945) (xy 116.444522 -168.313608)
			(xy 116.422424 -168.311576) (xy 116.327936 -168.345104) (xy 116.311934 -168.360598) (xy 116.30787 -168.371012)
			(xy 116.297139 -168.397773) (xy 116.268855 -168.448013) (xy 116.23333 -168.493422) (xy 116.191373 -168.532965)
			(xy 116.143941 -168.56574) (xy 116.092115 -168.591001) (xy 116.037077 -168.608171) (xy 115.980081 -168.616859)
			(xy 115.951254 -168.617392) (xy 115.924001 -168.616965) (xy 115.87005 -168.609202) (xy 115.817753 -168.59384)
			(xy 115.768175 -168.571192) (xy 115.722324 -168.54172) (xy 115.681134 -168.506022) (xy 115.645443 -168.464826)
			(xy 115.615978 -168.418971) (xy 115.593338 -168.369388) (xy 115.577985 -168.317089) (xy 115.570231 -168.263137)
			(xy 115.569746 -168.235884) (xy 115.570409 -168.204321) (xy 115.580794 -168.142056) (xy 115.601279 -168.082347)
			(xy 115.61572 -168.054274) (xy 115.620546 -168.045384) (xy 115.622578 -168.025826) (xy 115.596924 -167.937688)
			(xy 115.584478 -167.922194) (xy 115.575588 -167.917114) (xy 115.550462 -167.902606) (xy 115.50458 -167.867096)
			(xy 115.464607 -167.825045) (xy 115.431465 -167.777424) (xy 115.405918 -167.725333) (xy 115.388557 -167.669972)
			(xy 115.379782 -167.612621) (xy 115.379246 -167.583612) (xy 114.653568 -167.583612) (xy 114.653568 -168.610788)
			(xy 114.653899 -168.620838) (xy 114.661513 -168.639434) (xy 114.6683 -168.646856) (xy 115.058444 -169.037)
			(xy 118.02821 -169.037) (xy 118.032281 -168.981378) (xy 118.044407 -168.926941) (xy 118.06433 -168.87485)
			(xy 118.091626 -168.826215) (xy 118.125712 -168.782072) (xy 118.165861 -168.743363) (xy 118.211219 -168.710912)
			(xy 118.260819 -168.685411) (xy 118.313603 -168.667404) (xy 118.368446 -168.657274) (xy 118.42418 -168.655237)
			(xy 118.479617 -168.661337) (xy 118.533574 -168.675443) (xy 118.584903 -168.697255) (xy 118.632509 -168.726309)
			(xy 118.675377 -168.761984) (xy 118.712594 -168.803521) (xy 118.743367 -168.850034) (xy 118.767039 -168.900531)
			(xy 118.783107 -168.953938) (xy 118.791227 -169.009114) (xy 118.791736 -169.037) (xy 118.791227 -169.064886)
			(xy 118.783107 -169.120062) (xy 118.767039 -169.173469) (xy 118.743367 -169.223966) (xy 118.712594 -169.270479)
			(xy 118.675377 -169.312016) (xy 118.632509 -169.347691) (xy 118.584903 -169.376745) (xy 118.533574 -169.398557)
			(xy 118.479617 -169.412663) (xy 118.42418 -169.418763) (xy 118.368446 -169.416726) (xy 118.313603 -169.406596)
			(xy 118.260819 -169.388589) (xy 118.211219 -169.363088) (xy 118.165861 -169.330637) (xy 118.125712 -169.291928)
			(xy 118.091626 -169.247785) (xy 118.06433 -169.19915) (xy 118.044407 -169.147059) (xy 118.032281 -169.092622)
			(xy 118.02821 -169.037) (xy 115.058444 -169.037) (xy 115.530376 -169.508932) (xy 115.53704 -169.516354)
			(xy 115.544624 -169.534783) (xy 115.545108 -169.544746) (xy 115.545108 -170.91406) (xy 118.987062 -170.91406)
			(xy 118.987538 -170.886149) (xy 118.995677 -170.830922) (xy 119.011777 -170.777472) (xy 119.035494 -170.726937)
			(xy 119.06632 -170.680398) (xy 119.084598 -170.659298) (xy 119.090948 -170.652186) (xy 119.097552 -170.634914)
			(xy 119.097552 -170.547792) (xy 119.090948 -170.53052) (xy 119.084598 -170.523408) (xy 119.066302 -170.502323)
			(xy 119.035477 -170.455781) (xy 119.011765 -170.405242) (xy 118.995673 -170.351788) (xy 118.987544 -170.296558)
			(xy 118.987062 -170.268646) (xy 118.987548 -170.241395) (xy 118.995304 -170.187447) (xy 119.010659 -170.135152)
			(xy 119.033301 -170.085575) (xy 119.062767 -170.039725) (xy 119.098458 -169.998534) (xy 119.139649 -169.962843)
			(xy 119.185499 -169.933377) (xy 119.235076 -169.910735) (xy 119.287371 -169.89538) (xy 119.341319 -169.887624)
			(xy 119.395821 -169.887624) (xy 119.449769 -169.89538) (xy 119.502064 -169.910735) (xy 119.551641 -169.933377)
			(xy 119.597491 -169.962843) (xy 119.638682 -169.998534) (xy 119.674373 -170.039725) (xy 119.703839 -170.085575)
			(xy 119.726481 -170.135152) (xy 119.741836 -170.187447) (xy 119.749592 -170.241395) (xy 119.750078 -170.268646)
			(xy 119.749596 -170.296557) (xy 119.741456 -170.351783) (xy 119.725357 -170.405233) (xy 119.701643 -170.455767)
			(xy 119.670818 -170.502307) (xy 119.652542 -170.523408) (xy 119.646192 -170.53052) (xy 119.639588 -170.547792)
			(xy 119.639588 -170.634914) (xy 119.646192 -170.652186) (xy 119.652542 -170.659298) (xy 119.6708 -170.680414)
			(xy 119.701629 -170.726949) (xy 119.725347 -170.777479) (xy 119.741449 -170.830927) (xy 119.749589 -170.88615)
			(xy 119.750078 -170.91406) (xy 119.749592 -170.941311) (xy 119.741836 -170.995259) (xy 119.726481 -171.047554)
			(xy 119.703839 -171.097131) (xy 119.674373 -171.142981) (xy 119.638682 -171.184172) (xy 119.597491 -171.219863)
			(xy 119.551641 -171.249329) (xy 119.502064 -171.271971) (xy 119.449769 -171.287326) (xy 119.395821 -171.295082)
			(xy 119.341319 -171.295082) (xy 119.287371 -171.287326) (xy 119.235076 -171.271971) (xy 119.185499 -171.249329)
			(xy 119.139649 -171.219863) (xy 119.098458 -171.184172) (xy 119.062767 -171.142981) (xy 119.033301 -171.097131)
			(xy 119.010659 -171.047554) (xy 118.995304 -170.995259) (xy 118.987548 -170.941311) (xy 118.987062 -170.91406)
			(xy 115.545108 -170.91406) (xy 115.545108 -171.691554) (xy 115.544632 -171.701521) (xy 115.537058 -171.719958)
			(xy 115.530376 -171.727368) (xy 115.37442 -171.883324) (xy 115.367008 -171.890002) (xy 115.348572 -171.897579)
			(xy 115.338606 -171.898056) (xy 113.703608 -171.898056) (xy 113.693537 -171.898471) (xy 113.674939 -171.906197)
			(xy 113.66754 -171.913042) (xy 113.663222 -171.91736) (xy 113.655813 -171.924042) (xy 113.637375 -171.931616)
			(xy 113.627408 -171.932092) (xy 110.441232 -171.932092) (xy 110.43125 -171.931696) (xy 110.412788 -171.924104)
			(xy 110.405418 -171.91736) (xy 109.857032 -171.368974) (xy 109.850371 -171.361549) (xy 109.842785 -171.343123)
			(xy 109.8423 -171.33316) (xy 109.8423 -165.025578) (xy 109.841913 -165.015504) (xy 109.834168 -164.996905)
			(xy 109.827314 -164.98951) (xy 105.711498 -160.873694) (xy 105.704756 -160.866305) (xy 105.697046 -160.847869)
			(xy 105.696512 -160.83788) (xy 103.291132 -160.83788) (xy 103.291132 -167.725344) (xy 103.291526 -167.735417)
			(xy 103.299268 -167.754015) (xy 103.306118 -167.761412) (xy 106.426762 -170.882056) (xy 106.433477 -170.889467)
			(xy 106.441204 -170.907886) (xy 106.441748 -170.91787) (xy 106.441748 -173.832012) (xy 107.149646 -173.832012)
			(xy 107.150132 -173.804761) (xy 107.157888 -173.750813) (xy 107.173243 -173.698518) (xy 107.195885 -173.648941)
			(xy 107.225351 -173.603091) (xy 107.261042 -173.5619) (xy 107.302233 -173.526209) (xy 107.348083 -173.496743)
			(xy 107.39766 -173.474101) (xy 107.449955 -173.458746) (xy 107.503903 -173.45099) (xy 107.558405 -173.45099)
			(xy 107.612353 -173.458746) (xy 107.664648 -173.474101) (xy 107.714225 -173.496743) (xy 107.760075 -173.526209)
			(xy 107.801266 -173.5619) (xy 107.836957 -173.603091) (xy 107.866423 -173.648941) (xy 107.889065 -173.698518)
			(xy 107.90442 -173.750813) (xy 107.912176 -173.804761) (xy 107.912662 -173.832012) (xy 107.911996 -173.863575)
			(xy 107.901612 -173.92584) (xy 107.881129 -173.985549) (xy 107.866688 -174.013622) (xy 107.861862 -174.022512)
			(xy 107.85983 -174.04207) (xy 107.885484 -174.130208) (xy 107.89793 -174.145702) (xy 107.90682 -174.150782)
			(xy 107.914186 -174.154846) (xy 107.923838 -174.160688) (xy 107.945936 -174.16272) (xy 108.040424 -174.129192)
			(xy 108.056426 -174.113698) (xy 108.06049 -174.103284) (xy 108.071169 -174.0765) (xy 108.099459 -174.026258)
			(xy 108.134992 -173.980849) (xy 108.176956 -173.941307) (xy 108.224396 -173.908534) (xy 108.276229 -173.883277)
			(xy 108.331274 -173.866113) (xy 108.388276 -173.857432) (xy 108.417106 -173.856904) (xy 108.444358 -173.857366)
			(xy 108.498307 -173.865124) (xy 108.550602 -173.88048) (xy 108.60018 -173.903122) (xy 108.646031 -173.932589)
			(xy 108.687222 -173.968282) (xy 108.722914 -174.009473) (xy 108.752381 -174.055325) (xy 108.775022 -174.104903)
			(xy 108.790378 -174.157199) (xy 108.798134 -174.211148) (xy 108.798134 -174.265652) (xy 108.790378 -174.319601)
			(xy 108.781028 -174.351442) (xy 109.039914 -174.351442) (xy 109.040422 -174.323968) (xy 109.048308 -174.269589)
			(xy 109.063923 -174.216907) (xy 109.086943 -174.167014) (xy 109.11689 -174.120944) (xy 109.134656 -174.099982)
			(xy 109.140752 -174.09287) (xy 109.147102 -174.075852) (xy 109.147102 -173.99) (xy 109.140752 -173.972982)
			(xy 109.134656 -173.96587) (xy 109.11689 -173.94491) (xy 109.086967 -173.898827) (xy 109.063955 -173.848932)
			(xy 109.04833 -173.796255) (xy 109.040413 -173.741882) (xy 109.039914 -173.71441) (xy 109.0404 -173.687159)
			(xy 109.048156 -173.633211) (xy 109.063511 -173.580916) (xy 109.086153 -173.531339) (xy 109.115619 -173.485489)
			(xy 109.15131 -173.444298) (xy 109.192501 -173.408607) (xy 109.238351 -173.379141) (xy 109.287928 -173.356499)
			(xy 109.340223 -173.341144) (xy 109.394171 -173.333388) (xy 109.448673 -173.333388) (xy 109.502621 -173.341144)
			(xy 109.554916 -173.356499) (xy 109.604493 -173.379141) (xy 109.650343 -173.408607) (xy 109.691534 -173.444298)
			(xy 109.727225 -173.485489) (xy 109.756691 -173.531339) (xy 109.779333 -173.580916) (xy 109.784596 -173.59884)
			(xy 130.214624 -173.59884) (xy 130.215108 -173.57147) (xy 130.22292 -173.517292) (xy 130.238405 -173.464789)
			(xy 130.261243 -173.415041) (xy 130.290964 -173.369074) (xy 130.308604 -173.348142) (xy 130.3147 -173.34103)
			(xy 130.32105 -173.324012) (xy 130.32105 -173.238668) (xy 130.3147 -173.22165) (xy 130.308604 -173.214538)
			(xy 130.291003 -173.193573) (xy 130.261279 -173.14761) (xy 130.238432 -173.097869) (xy 130.222934 -173.045372)
			(xy 130.215102 -172.991199) (xy 130.215098 -172.936462) (xy 130.222921 -172.882287) (xy 130.238411 -172.829787)
			(xy 130.26125 -172.780043) (xy 130.290967 -172.734075) (xy 130.308604 -172.713142) (xy 130.3147 -172.70603)
			(xy 130.32105 -172.689012) (xy 130.32105 -172.603668) (xy 130.3147 -172.58665) (xy 130.308604 -172.579538)
			(xy 130.291003 -172.558573) (xy 130.261279 -172.51261) (xy 130.238432 -172.462869) (xy 130.222934 -172.410372)
			(xy 130.215102 -172.356199) (xy 130.215098 -172.301462) (xy 130.222921 -172.247287) (xy 130.238411 -172.194787)
			(xy 130.26125 -172.145043) (xy 130.290967 -172.099075) (xy 130.308604 -172.078142) (xy 130.3147 -172.07103)
			(xy 130.32105 -172.054012) (xy 130.32105 -171.968668) (xy 130.3147 -171.95165) (xy 130.308604 -171.944538)
			(xy 130.29097 -171.923602) (xy 130.261257 -171.87763) (xy 130.23842 -171.827884) (xy 130.222928 -171.775384)
			(xy 130.215099 -171.721209) (xy 130.214624 -171.69384) (xy 130.215109 -171.665965) (xy 130.22322 -171.610807)
			(xy 130.239275 -171.557418) (xy 130.262932 -171.506936) (xy 130.293686 -171.460435) (xy 130.311906 -171.439332)
			(xy 130.318002 -171.432474) (xy 130.32486 -171.415202) (xy 130.32486 -171.328588) (xy 130.318256 -171.311316)
			(xy 130.31216 -171.304204) (xy 130.294099 -171.283136) (xy 130.263576 -171.236796) (xy 130.240103 -171.186515)
			(xy 130.224177 -171.13336) (xy 130.216135 -171.078457) (xy 130.21564 -171.050712) (xy 130.216103 -171.023342)
			(xy 130.22392 -170.969162) (xy 130.23941 -170.916658) (xy 130.262252 -170.866912) (xy 130.291978 -170.820945)
			(xy 130.30962 -170.800014) (xy 130.315716 -170.792902) (xy 130.322066 -170.775884) (xy 130.322066 -170.69054)
			(xy 130.315716 -170.673522) (xy 130.30962 -170.66641) (xy 130.291991 -170.645468) (xy 130.262267 -170.599501)
			(xy 130.239421 -170.549757) (xy 130.223924 -170.497256) (xy 130.216095 -170.443079) (xy 130.216093 -170.388339)
			(xy 130.22392 -170.334162) (xy 130.239415 -170.28166) (xy 130.262258 -170.231915) (xy 130.29198 -170.185947)
			(xy 130.30962 -170.165014) (xy 130.315716 -170.157902) (xy 130.322066 -170.140884) (xy 130.322066 -170.05554)
			(xy 130.315716 -170.038522) (xy 130.30962 -170.03141) (xy 130.291991 -170.010468) (xy 130.262267 -169.964501)
			(xy 130.239421 -169.914757) (xy 130.223924 -169.862256) (xy 130.216095 -169.808079) (xy 130.216093 -169.753339)
			(xy 130.22392 -169.699162) (xy 130.239415 -169.64666) (xy 130.262258 -169.596915) (xy 130.29198 -169.550947)
			(xy 130.30962 -169.530014) (xy 130.315716 -169.522902) (xy 130.322066 -169.505884) (xy 130.322066 -169.42054)
			(xy 130.315716 -169.403522) (xy 130.30962 -169.39641) (xy 130.291975 -169.375482) (xy 130.262264 -169.329509)
			(xy 130.239428 -169.27976) (xy 130.223939 -169.227258) (xy 130.216113 -169.173082) (xy 130.21564 -169.145712)
			(xy 130.216121 -169.118413) (xy 130.223892 -169.064371) (xy 130.23929 -169.01199) (xy 130.262002 -168.96234)
			(xy 130.291562 -168.916437) (xy 130.309112 -168.895522) (xy 130.315462 -168.88841) (xy 130.321558 -168.871392)
			(xy 130.321558 -168.785794) (xy 130.315208 -168.76903) (xy 130.309112 -168.761918) (xy 130.291409 -168.740948)
			(xy 130.261528 -168.694919) (xy 130.238559 -168.645079) (xy 130.222977 -168.592461) (xy 130.215103 -168.538151)
			(xy 130.214624 -168.510712) (xy 130.215067 -168.483458) (xy 130.222823 -168.429505) (xy 130.238179 -168.377204)
			(xy 130.260822 -168.327622) (xy 130.290292 -168.281768) (xy 130.325988 -168.240574) (xy 130.367184 -168.20488)
			(xy 130.41304 -168.175413) (xy 130.462623 -168.152772) (xy 130.514924 -168.137418) (xy 130.568878 -168.129665)
			(xy 130.596132 -168.129204) (xy 130.623503 -168.12965) (xy 130.677683 -168.137473) (xy 130.730186 -168.152966)
			(xy 130.779933 -168.175813) (xy 130.825899 -168.205541) (xy 130.84683 -168.223184) (xy 130.853942 -168.22928)
			(xy 130.87096 -168.23563) (xy 130.956304 -168.23563) (xy 130.973322 -168.22928) (xy 130.980434 -168.223184)
			(xy 131.001378 -168.20556) (xy 131.047348 -168.175846) (xy 131.097092 -168.153008) (xy 131.14959 -168.137513)
			(xy 131.203764 -168.129681) (xy 131.231132 -168.129204) (xy 131.258385 -168.129648) (xy 131.312334 -168.137409)
			(xy 131.364631 -168.152769) (xy 131.414209 -168.175415) (xy 131.46006 -168.204886) (xy 131.50125 -168.240581)
			(xy 131.536941 -168.281776) (xy 131.566406 -168.32763) (xy 131.589046 -168.377211) (xy 131.6044 -168.429509)
			(xy 131.612155 -168.483459) (xy 131.61264 -168.510712) (xy 131.612153 -168.538011) (xy 131.604381 -168.592051)
			(xy 131.588983 -168.644432) (xy 131.566273 -168.694081) (xy 131.536716 -168.739986) (xy 131.519168 -168.760902)
			(xy 131.512818 -168.768014) (xy 131.506722 -168.785032) (xy 131.506722 -168.87063) (xy 131.513072 -168.887394)
			(xy 131.519168 -168.894506) (xy 131.53688 -168.915469) (xy 131.56676 -168.9615) (xy 131.589727 -169.011341)
			(xy 131.605308 -169.063962) (xy 131.613178 -169.118273) (xy 131.613656 -169.145712) (xy 131.613208 -169.173083)
			(xy 131.605387 -169.227263) (xy 131.589895 -169.279767) (xy 131.567049 -169.329514) (xy 131.53732 -169.375479)
			(xy 131.519676 -169.39641) (xy 131.51358 -169.403522) (xy 131.50723 -169.42054) (xy 131.50723 -169.505884)
			(xy 131.51358 -169.522902) (xy 131.519676 -169.530014) (xy 131.537328 -169.550937) (xy 131.567052 -169.596907)
			(xy 131.589897 -169.646655) (xy 131.605392 -169.699158) (xy 131.61322 -169.753338) (xy 131.613218 -169.80808)
			(xy 131.605388 -169.86226) (xy 131.589891 -169.914762) (xy 131.567044 -169.964509) (xy 131.537317 -170.010477)
			(xy 131.519676 -170.03141) (xy 131.51358 -170.038522) (xy 131.50723 -170.05554) (xy 131.50723 -170.140884)
			(xy 131.51358 -170.157902) (xy 131.519676 -170.165014) (xy 131.537328 -170.185937) (xy 131.567052 -170.231907)
			(xy 131.589897 -170.281655) (xy 131.605392 -170.334158) (xy 131.61322 -170.388338) (xy 131.613218 -170.44308)
			(xy 131.605388 -170.49726) (xy 131.589891 -170.549762) (xy 131.567044 -170.599509) (xy 131.537317 -170.645477)
			(xy 131.519676 -170.66641) (xy 131.51358 -170.673522) (xy 131.50723 -170.69054) (xy 131.50723 -170.775884)
			(xy 131.51358 -170.792902) (xy 131.519676 -170.800014) (xy 131.537285 -170.820971) (xy 131.567002 -170.866936)
			(xy 131.589844 -170.916678) (xy 131.605342 -170.969173) (xy 131.613178 -171.023344) (xy 131.613656 -171.050712)
			(xy 131.613122 -171.078585) (xy 131.60502 -171.13374) (xy 131.588975 -171.187128) (xy 131.56533 -171.237611)
			(xy 131.534587 -171.284114) (xy 131.516374 -171.30522) (xy 131.510278 -171.312078) (xy 131.50342 -171.32935)
			(xy 131.50342 -171.415964) (xy 131.510024 -171.433236) (xy 131.51612 -171.440348) (xy 131.534202 -171.461398)
			(xy 131.564723 -171.507743) (xy 131.588192 -171.558028) (xy 131.604113 -171.611187) (xy 131.612148 -171.666094)
			(xy 131.61264 -171.69384) (xy 131.612153 -171.72121) (xy 131.604343 -171.775388) (xy 131.588859 -171.827892)
			(xy 131.566022 -171.877639) (xy 131.5363 -171.923606) (xy 131.51866 -171.944538) (xy 131.512564 -171.95165)
			(xy 131.506214 -171.968668) (xy 131.506214 -172.054012) (xy 131.512564 -172.07103) (xy 131.51866 -172.078142)
			(xy 131.53634 -172.099043) (xy 131.566065 -172.145016) (xy 131.588908 -172.194767) (xy 131.604402 -172.247274)
			(xy 131.612227 -172.301457) (xy 131.612225 -172.32884) (xy 133.592824 -172.32884) (xy 133.593308 -172.30147)
			(xy 133.60112 -172.247292) (xy 133.616605 -172.194789) (xy 133.639443 -172.145041) (xy 133.669164 -172.099074)
			(xy 133.686804 -172.078142) (xy 133.6929 -172.07103) (xy 133.69925 -172.054012) (xy 133.69925 -171.968668)
			(xy 133.6929 -171.95165) (xy 133.686804 -171.944538) (xy 133.66917 -171.923602) (xy 133.639457 -171.87763)
			(xy 133.61662 -171.827884) (xy 133.601128 -171.775384) (xy 133.593299 -171.721209) (xy 133.592824 -171.69384)
			(xy 133.593309 -171.665965) (xy 133.60142 -171.610807) (xy 133.617475 -171.557418) (xy 133.641132 -171.506936)
			(xy 133.671886 -171.460435) (xy 133.690106 -171.439332) (xy 133.696202 -171.432474) (xy 133.70306 -171.415202)
			(xy 133.70306 -171.328588) (xy 133.696456 -171.311316) (xy 133.69036 -171.304204) (xy 133.672299 -171.283136)
			(xy 133.641776 -171.236796) (xy 133.618303 -171.186515) (xy 133.602377 -171.13336) (xy 133.594335 -171.078457)
			(xy 133.59384 -171.050712) (xy 133.594303 -171.023342) (xy 133.60212 -170.969162) (xy 133.61761 -170.916658)
			(xy 133.640452 -170.866912) (xy 133.670178 -170.820945) (xy 133.68782 -170.800014) (xy 133.693916 -170.792902)
			(xy 133.700266 -170.775884) (xy 133.700266 -170.69054) (xy 133.693916 -170.673522) (xy 133.68782 -170.66641)
			(xy 133.670191 -170.645468) (xy 133.640467 -170.599501) (xy 133.617621 -170.549757) (xy 133.602124 -170.497256)
			(xy 133.594295 -170.443079) (xy 133.594293 -170.388339) (xy 133.60212 -170.334162) (xy 133.617615 -170.28166)
			(xy 133.640458 -170.231915) (xy 133.67018 -170.185947) (xy 133.68782 -170.165014) (xy 133.693916 -170.157902)
			(xy 133.700266 -170.140884) (xy 133.700266 -170.05554) (xy 133.693916 -170.038522) (xy 133.68782 -170.03141)
			(xy 133.670191 -170.010468) (xy 133.640467 -169.964501) (xy 133.617621 -169.914757) (xy 133.602124 -169.862256)
			(xy 133.594295 -169.808079) (xy 133.594293 -169.753339) (xy 133.60212 -169.699162) (xy 133.617615 -169.64666)
			(xy 133.640458 -169.596915) (xy 133.67018 -169.550947) (xy 133.68782 -169.530014) (xy 133.693916 -169.522902)
			(xy 133.700266 -169.505884) (xy 133.700266 -169.42054) (xy 133.693916 -169.403522) (xy 133.68782 -169.39641)
			(xy 133.670175 -169.375482) (xy 133.640464 -169.329509) (xy 133.617628 -169.27976) (xy 133.602139 -169.227258)
			(xy 133.594313 -169.173082) (xy 133.59384 -169.145712) (xy 133.594321 -169.118413) (xy 133.602092 -169.064371)
			(xy 133.61749 -169.01199) (xy 133.640202 -168.96234) (xy 133.669762 -168.916437) (xy 133.687312 -168.895522)
			(xy 133.693662 -168.88841) (xy 133.699758 -168.871392) (xy 133.699758 -168.785794) (xy 133.693408 -168.76903)
			(xy 133.687312 -168.761918) (xy 133.669609 -168.740948) (xy 133.639728 -168.694919) (xy 133.616759 -168.645079)
			(xy 133.601177 -168.592461) (xy 133.593303 -168.538151) (xy 133.592824 -168.510712) (xy 133.593267 -168.483458)
			(xy 133.601023 -168.429505) (xy 133.616379 -168.377204) (xy 133.639022 -168.327622) (xy 133.668492 -168.281768)
			(xy 133.704188 -168.240574) (xy 133.745384 -168.20488) (xy 133.79124 -168.175413) (xy 133.840823 -168.152772)
			(xy 133.893124 -168.137418) (xy 133.947078 -168.129665) (xy 133.974332 -168.129204) (xy 134.001703 -168.12965)
			(xy 134.055883 -168.137473) (xy 134.108386 -168.152966) (xy 134.158133 -168.175813) (xy 134.204099 -168.205541)
			(xy 134.22503 -168.223184) (xy 134.232142 -168.22928) (xy 134.24916 -168.23563) (xy 134.334504 -168.23563)
			(xy 134.351522 -168.22928) (xy 134.358634 -168.223184) (xy 134.379578 -168.20556) (xy 134.425548 -168.175846)
			(xy 134.475292 -168.153008) (xy 134.52779 -168.137513) (xy 134.581964 -168.129681) (xy 134.609332 -168.129204)
			(xy 134.637242 -168.129699) (xy 134.692467 -168.137836) (xy 134.745917 -168.153933) (xy 134.796452 -168.177644)
			(xy 134.842993 -168.208465) (xy 134.864094 -168.22674) (xy 134.871206 -168.23309) (xy 134.88797 -168.239694)
			(xy 134.973822 -168.24071) (xy 134.990586 -168.234614) (xy 134.997952 -168.228518) (xy 135.018731 -168.211373)
			(xy 135.064232 -168.182532) (xy 135.11334 -168.160384) (xy 135.165077 -168.145372) (xy 135.218412 -168.137793)
			(xy 135.245348 -168.137332) (xy 135.272718 -168.137821) (xy 135.326896 -168.145632) (xy 135.379399 -168.161115)
			(xy 135.429146 -168.183952) (xy 135.475114 -168.213673) (xy 135.496046 -168.231312) (xy 135.503158 -168.237408)
			(xy 135.520176 -168.243758) (xy 135.60552 -168.243758) (xy 135.622538 -168.237408) (xy 135.62965 -168.231312)
			(xy 135.650592 -168.213685) (xy 135.696562 -168.183971) (xy 135.746307 -168.161132) (xy 135.798805 -168.145639)
			(xy 135.852979 -168.137807) (xy 135.880348 -168.137332) (xy 135.907602 -168.137733) (xy 135.961555 -168.145497)
			(xy 136.013854 -168.160861) (xy 136.063434 -168.18351) (xy 136.109286 -168.212985) (xy 136.150477 -168.248686)
			(xy 136.186168 -168.289885) (xy 136.215632 -168.335743) (xy 136.23827 -168.385329) (xy 136.253621 -168.437631)
			(xy 136.261373 -168.491586) (xy 136.261856 -168.51884) (xy 136.261365 -168.546209) (xy 136.253555 -168.600388)
			(xy 136.238072 -168.652891) (xy 136.215236 -168.702639) (xy 136.185515 -168.748606) (xy 136.167876 -168.769538)
			(xy 136.16178 -168.77665) (xy 136.15543 -168.793668) (xy 136.15543 -168.879012) (xy 136.16178 -168.89603)
			(xy 136.167876 -168.903142) (xy 136.185556 -168.924043) (xy 136.215279 -168.970016) (xy 136.238122 -169.019768)
			(xy 136.253615 -169.072275) (xy 136.261439 -169.126458) (xy 136.261435 -169.181203) (xy 136.253602 -169.235384)
			(xy 136.2381 -169.287889) (xy 136.21525 -169.337636) (xy 136.185519 -169.383605) (xy 136.167876 -169.404538)
			(xy 136.16178 -169.41165) (xy 136.15543 -169.428668) (xy 136.15543 -169.514012) (xy 136.16178 -169.53103)
			(xy 136.167876 -169.538142) (xy 136.185556 -169.559043) (xy 136.215279 -169.605016) (xy 136.238122 -169.654768)
			(xy 136.253615 -169.707275) (xy 136.261439 -169.761458) (xy 136.261435 -169.816203) (xy 136.253602 -169.870384)
			(xy 136.2381 -169.922889) (xy 136.21525 -169.972636) (xy 136.185519 -170.018605) (xy 136.167876 -170.039538)
			(xy 136.16178 -170.04665) (xy 136.15543 -170.063668) (xy 136.15543 -170.149012) (xy 136.16178 -170.16603)
			(xy 136.167876 -170.173142) (xy 136.185556 -170.194043) (xy 136.215279 -170.240016) (xy 136.238122 -170.289768)
			(xy 136.253615 -170.342275) (xy 136.261439 -170.396458) (xy 136.261435 -170.451203) (xy 136.253602 -170.505384)
			(xy 136.2381 -170.557889) (xy 136.21525 -170.607636) (xy 136.185519 -170.653605) (xy 136.167876 -170.674538)
			(xy 136.16178 -170.68165) (xy 136.15543 -170.698668) (xy 136.15543 -170.784012) (xy 136.16178 -170.80103)
			(xy 136.167876 -170.808142) (xy 136.185556 -170.829043) (xy 136.215279 -170.875016) (xy 136.238122 -170.924768)
			(xy 136.253615 -170.977275) (xy 136.261439 -171.031458) (xy 136.261435 -171.086203) (xy 136.253602 -171.140384)
			(xy 136.2381 -171.192889) (xy 136.21525 -171.242636) (xy 136.185519 -171.288605) (xy 136.167876 -171.309538)
			(xy 136.16178 -171.31665) (xy 136.15543 -171.333668) (xy 136.15543 -171.419012) (xy 136.16178 -171.43603)
			(xy 136.167876 -171.443142) (xy 136.185498 -171.464088) (xy 136.215213 -171.510057) (xy 136.238053 -171.559801)
			(xy 136.253548 -171.612298) (xy 136.26138 -171.666472) (xy 136.261856 -171.69384) (xy 136.26136 -171.72109)
			(xy 136.253599 -171.775035) (xy 136.238241 -171.827326) (xy 136.215599 -171.876901) (xy 136.186133 -171.922749)
			(xy 136.150443 -171.963937) (xy 136.109255 -171.999628) (xy 136.063408 -172.029095) (xy 136.013834 -172.051738)
			(xy 135.961543 -172.067097) (xy 135.907598 -172.074859) (xy 135.880348 -172.075348) (xy 135.852978 -172.074866)
			(xy 135.798799 -172.067054) (xy 135.746296 -172.05157) (xy 135.696549 -172.028731) (xy 135.650582 -171.999009)
			(xy 135.62965 -171.981368) (xy 135.622538 -171.975272) (xy 135.60552 -171.968922) (xy 135.520176 -171.968922)
			(xy 135.503158 -171.975272) (xy 135.496046 -171.981368) (xy 135.475103 -171.998994) (xy 135.429134 -172.028709)
			(xy 135.379389 -172.051548) (xy 135.326891 -172.067042) (xy 135.272717 -172.074873) (xy 135.245348 -172.075348)
			(xy 135.215799 -172.074812) (xy 135.157408 -172.065693) (xy 135.101122 -172.047679) (xy 135.048286 -172.021203)
			(xy 135.000164 -171.986897) (xy 134.978648 -171.966636) (xy 134.971299 -171.96012) (xy 134.953149 -171.952666)
			(xy 134.943342 -171.952158) (xy 134.890002 -171.952158) (xy 134.882636 -171.960032) (xy 134.876086 -171.967354)
			(xy 134.868652 -171.985524) (xy 134.868158 -171.995338) (xy 134.868158 -172.027342) (xy 134.868643 -172.037156)
			(xy 134.87609 -172.05532) (xy 134.882636 -172.062648) (xy 134.90283 -172.084129) (xy 134.936972 -172.132193)
			(xy 134.963315 -172.184937) (xy 134.981232 -172.241106) (xy 134.990294 -172.299362) (xy 134.99084 -172.32884)
			(xy 134.990359 -172.356091) (xy 134.982598 -172.410037) (xy 134.96724 -172.46233) (xy 134.944596 -172.511905)
			(xy 134.915129 -172.557754) (xy 134.879437 -172.598943) (xy 134.838247 -172.634634) (xy 134.792398 -172.6641)
			(xy 134.742822 -172.686743) (xy 134.690529 -172.7021) (xy 134.636583 -172.70986) (xy 134.609332 -172.710348)
			(xy 134.581962 -172.709876) (xy 134.527783 -172.702061) (xy 134.475279 -172.686574) (xy 134.425532 -172.663734)
			(xy 134.379565 -172.634009) (xy 134.358634 -172.616368) (xy 134.351522 -172.610272) (xy 134.334504 -172.603922)
			(xy 134.24916 -172.603922) (xy 134.232142 -172.610272) (xy 134.22503 -172.616368) (xy 134.204093 -172.634002)
			(xy 134.158122 -172.663715) (xy 134.108376 -172.686553) (xy 134.055876 -172.702045) (xy 134.001701 -172.709874)
			(xy 133.974332 -172.710348) (xy 133.947083 -172.709792) (xy 133.89314 -172.702041) (xy 133.840849 -172.686692)
			(xy 133.791275 -172.664057) (xy 133.745426 -172.634598) (xy 133.704237 -172.598914) (xy 133.668545 -172.557731)
			(xy 133.639077 -172.511888) (xy 133.616433 -172.462318) (xy 133.601074 -172.41003) (xy 133.593313 -172.356089)
			(xy 133.592824 -172.32884) (xy 131.612225 -172.32884) (xy 131.612223 -172.356203) (xy 131.604389 -172.410385)
			(xy 131.588887 -172.462889) (xy 131.566036 -172.512637) (xy 131.536304 -172.558605) (xy 131.51866 -172.579538)
			(xy 131.512564 -172.58665) (xy 131.506214 -172.603668) (xy 131.506214 -172.689012) (xy 131.512564 -172.70603)
			(xy 131.51866 -172.713142) (xy 131.53634 -172.734043) (xy 131.566065 -172.780016) (xy 131.588908 -172.829767)
			(xy 131.604402 -172.882274) (xy 131.612227 -172.936457) (xy 131.612223 -172.991203) (xy 131.604389 -173.045385)
			(xy 131.588887 -173.097889) (xy 131.566036 -173.147637) (xy 131.536304 -173.193605) (xy 131.51866 -173.214538)
			(xy 131.512564 -173.22165) (xy 131.506214 -173.238668) (xy 131.506214 -173.324012) (xy 131.512564 -173.34103)
			(xy 131.51866 -173.348142) (xy 131.536279 -173.36909) (xy 131.565995 -173.415058) (xy 131.588836 -173.464801)
			(xy 131.604331 -173.517299) (xy 131.612164 -173.571472) (xy 131.61264 -173.59884) (xy 131.612159 -173.626091)
			(xy 131.604398 -173.680037) (xy 131.58904 -173.73233) (xy 131.566396 -173.781905) (xy 131.536929 -173.827754)
			(xy 131.501237 -173.868943) (xy 131.460047 -173.904634) (xy 131.414198 -173.9341) (xy 131.364622 -173.956743)
			(xy 131.312329 -173.9721) (xy 131.258383 -173.97986) (xy 131.231132 -173.980348) (xy 131.203762 -173.979876)
			(xy 131.149583 -173.972061) (xy 131.097079 -173.956574) (xy 131.047332 -173.933734) (xy 131.001365 -173.904009)
			(xy 130.980434 -173.886368) (xy 130.973322 -173.880272) (xy 130.956304 -173.873922) (xy 130.87096 -173.873922)
			(xy 130.853942 -173.880272) (xy 130.84683 -173.886368) (xy 130.825893 -173.904002) (xy 130.779922 -173.933715)
			(xy 130.730176 -173.956553) (xy 130.677676 -173.972045) (xy 130.623501 -173.979874) (xy 130.596132 -173.980348)
			(xy 130.568883 -173.979792) (xy 130.51494 -173.972041) (xy 130.462649 -173.956692) (xy 130.413075 -173.934057)
			(xy 130.367226 -173.904598) (xy 130.326037 -173.868914) (xy 130.290345 -173.827731) (xy 130.260877 -173.781888)
			(xy 130.238233 -173.732318) (xy 130.222874 -173.68003) (xy 130.215113 -173.626089) (xy 130.214624 -173.59884)
			(xy 109.784596 -173.59884) (xy 109.794688 -173.633211) (xy 109.802444 -173.687159) (xy 109.80293 -173.71441)
			(xy 109.802442 -173.741884) (xy 109.79455 -173.796264) (xy 109.778929 -173.848946) (xy 109.755905 -173.898839)
			(xy 109.725955 -173.944908) (xy 109.708188 -173.96587) (xy 109.702092 -173.972982) (xy 109.695742 -173.99)
			(xy 109.695742 -174.075852) (xy 109.702092 -174.09287) (xy 109.708188 -174.099982) (xy 109.725923 -174.120968)
			(xy 109.755852 -174.167043) (xy 109.778871 -174.216931) (xy 109.794504 -174.269603) (xy 109.802427 -174.323971)
			(xy 109.80293 -174.351442) (xy 109.802444 -174.378693) (xy 109.800811 -174.39005) (xy 110.37773 -174.39005)
			(xy 110.381801 -174.334428) (xy 110.393927 -174.279991) (xy 110.41385 -174.2279) (xy 110.441146 -174.179265)
			(xy 110.475232 -174.135122) (xy 110.515381 -174.096413) (xy 110.560739 -174.063962) (xy 110.610339 -174.038461)
			(xy 110.663123 -174.020454) (xy 110.717966 -174.010324) (xy 110.7737 -174.008287) (xy 110.829137 -174.014387)
			(xy 110.883094 -174.028493) (xy 110.934423 -174.050305) (xy 110.982029 -174.079359) (xy 111.024897 -174.115034)
			(xy 111.062114 -174.156571) (xy 111.092887 -174.203084) (xy 111.116559 -174.253581) (xy 111.132627 -174.306988)
			(xy 111.140747 -174.362164) (xy 111.141256 -174.39005) (xy 111.140747 -174.417936) (xy 111.132627 -174.473112)
			(xy 111.116559 -174.526519) (xy 111.092887 -174.577016) (xy 111.062114 -174.623529) (xy 111.024897 -174.665066)
			(xy 110.982029 -174.700741) (xy 110.934423 -174.729795) (xy 110.883094 -174.751607) (xy 110.829137 -174.765713)
			(xy 110.7737 -174.771813) (xy 110.717966 -174.769776) (xy 110.663123 -174.759646) (xy 110.610339 -174.741639)
			(xy 110.560739 -174.716138) (xy 110.515381 -174.683687) (xy 110.475232 -174.644978) (xy 110.441146 -174.600835)
			(xy 110.41385 -174.5522) (xy 110.393927 -174.500109) (xy 110.381801 -174.445672) (xy 110.37773 -174.39005)
			(xy 109.800811 -174.39005) (xy 109.794688 -174.432641) (xy 109.779333 -174.484936) (xy 109.756691 -174.534513)
			(xy 109.727225 -174.580363) (xy 109.691534 -174.621554) (xy 109.650343 -174.657245) (xy 109.604493 -174.686711)
			(xy 109.554916 -174.709353) (xy 109.502621 -174.724708) (xy 109.448673 -174.732464) (xy 109.394171 -174.732464)
			(xy 109.340223 -174.724708) (xy 109.287928 -174.709353) (xy 109.238351 -174.686711) (xy 109.192501 -174.657245)
			(xy 109.15131 -174.621554) (xy 109.115619 -174.580363) (xy 109.086153 -174.534513) (xy 109.063511 -174.484936)
			(xy 109.048156 -174.432641) (xy 109.0404 -174.378693) (xy 109.039914 -174.351442) (xy 108.781028 -174.351442)
			(xy 108.775022 -174.371897) (xy 108.752381 -174.421475) (xy 108.722914 -174.467327) (xy 108.687222 -174.508518)
			(xy 108.646031 -174.544211) (xy 108.60018 -174.573678) (xy 108.550602 -174.59632) (xy 108.498307 -174.611676)
			(xy 108.444358 -174.619434) (xy 108.417106 -174.61992) (xy 108.391871 -174.619518) (xy 108.341837 -174.612901)
			(xy 108.293117 -174.599729) (xy 108.246565 -174.580234) (xy 108.224574 -174.56785) (xy 108.214922 -174.562008)
			(xy 108.192824 -174.559976) (xy 108.098336 -174.593504) (xy 108.082334 -174.608998) (xy 108.07827 -174.619412)
			(xy 108.067539 -174.646173) (xy 108.039255 -174.696413) (xy 108.00373 -174.741822) (xy 107.961773 -174.781365)
			(xy 107.914341 -174.81414) (xy 107.862515 -174.839401) (xy 107.807477 -174.856571) (xy 107.750481 -174.865259)
			(xy 107.721654 -174.865792) (xy 107.694401 -174.865365) (xy 107.64045 -174.857602) (xy 107.588153 -174.84224)
			(xy 107.538575 -174.819592) (xy 107.492724 -174.79012) (xy 107.451534 -174.754422) (xy 107.415843 -174.713226)
			(xy 107.386378 -174.667371) (xy 107.363738 -174.617788) (xy 107.348385 -174.565489) (xy 107.340631 -174.511537)
			(xy 107.340146 -174.484284) (xy 107.340809 -174.452721) (xy 107.351194 -174.390456) (xy 107.371679 -174.330747)
			(xy 107.38612 -174.302674) (xy 107.390946 -174.293784) (xy 107.392978 -174.274226) (xy 107.367324 -174.186088)
			(xy 107.354878 -174.170594) (xy 107.345988 -174.165514) (xy 107.320862 -174.151006) (xy 107.27498 -174.115496)
			(xy 107.235007 -174.073445) (xy 107.201865 -174.025824) (xy 107.176318 -173.973733) (xy 107.158957 -173.918372)
			(xy 107.150182 -173.861021) (xy 107.149646 -173.832012) (xy 106.441748 -173.832012) (xy 106.441748 -174.846488)
			(xy 106.442085 -174.856537) (xy 106.449696 -174.875133) (xy 106.45648 -174.882556) (xy 106.859324 -175.2854)
			(xy 109.79861 -175.2854) (xy 109.802681 -175.229778) (xy 109.814807 -175.175341) (xy 109.83473 -175.12325)
			(xy 109.862026 -175.074615) (xy 109.896112 -175.030472) (xy 109.936261 -174.991763) (xy 109.981619 -174.959312)
			(xy 110.031219 -174.933811) (xy 110.084003 -174.915804) (xy 110.138846 -174.905674) (xy 110.19458 -174.903637)
			(xy 110.250017 -174.909737) (xy 110.303974 -174.923843) (xy 110.355303 -174.945655) (xy 110.402909 -174.974709)
			(xy 110.445777 -175.010384) (xy 110.482994 -175.051921) (xy 110.513767 -175.098434) (xy 110.537439 -175.148931)
			(xy 110.553507 -175.202338) (xy 110.561627 -175.257514) (xy 110.562136 -175.2854) (xy 110.561627 -175.313286)
			(xy 110.553507 -175.368462) (xy 110.537439 -175.421869) (xy 110.513767 -175.472366) (xy 110.482994 -175.518879)
			(xy 110.445777 -175.560416) (xy 110.402909 -175.596091) (xy 110.355303 -175.625145) (xy 110.303974 -175.646957)
			(xy 110.250017 -175.661063) (xy 110.19458 -175.667163) (xy 110.138846 -175.665126) (xy 110.084003 -175.654996)
			(xy 110.031219 -175.636989) (xy 109.981619 -175.611488) (xy 109.936261 -175.579037) (xy 109.896112 -175.540328)
			(xy 109.862026 -175.496185) (xy 109.83473 -175.44755) (xy 109.814807 -175.395459) (xy 109.802681 -175.341022)
			(xy 109.79861 -175.2854) (xy 106.859324 -175.2854) (xy 107.314238 -175.740314) (xy 107.320989 -175.747696)
			(xy 107.328692 -175.766138) (xy 107.329224 -175.776128) (xy 107.329224 -177.16246) (xy 110.757462 -177.16246)
			(xy 110.757938 -177.134549) (xy 110.766077 -177.079322) (xy 110.782177 -177.025872) (xy 110.805894 -176.975337)
			(xy 110.83672 -176.928798) (xy 110.854998 -176.907698) (xy 110.861348 -176.900586) (xy 110.867952 -176.883314)
			(xy 110.867952 -176.796192) (xy 110.861348 -176.77892) (xy 110.854998 -176.771808) (xy 110.836702 -176.750723)
			(xy 110.805877 -176.704181) (xy 110.782165 -176.653642) (xy 110.766073 -176.600188) (xy 110.757944 -176.544958)
			(xy 110.757462 -176.517046) (xy 110.757948 -176.489795) (xy 110.765704 -176.435847) (xy 110.781059 -176.383552)
			(xy 110.803701 -176.333975) (xy 110.833167 -176.288125) (xy 110.868858 -176.246934) (xy 110.910049 -176.211243)
			(xy 110.955899 -176.181777) (xy 111.005476 -176.159135) (xy 111.057771 -176.14378) (xy 111.111719 -176.136024)
			(xy 111.166221 -176.136024) (xy 111.220169 -176.14378) (xy 111.272464 -176.159135) (xy 111.322041 -176.181777)
			(xy 111.367891 -176.211243) (xy 111.409082 -176.246934) (xy 111.444773 -176.288125) (xy 111.474239 -176.333975)
			(xy 111.496881 -176.383552) (xy 111.512236 -176.435847) (xy 111.519992 -176.489795) (xy 111.520478 -176.517046)
			(xy 111.519996 -176.544957) (xy 111.511856 -176.600183) (xy 111.495757 -176.653633) (xy 111.472043 -176.704167)
			(xy 111.441218 -176.750707) (xy 111.422942 -176.771808) (xy 111.416592 -176.77892) (xy 111.409988 -176.796192)
			(xy 111.409988 -176.883314) (xy 111.416592 -176.900586) (xy 111.422942 -176.907698) (xy 111.4412 -176.928814)
			(xy 111.472029 -176.975349) (xy 111.495747 -177.025879) (xy 111.511849 -177.079327) (xy 111.519989 -177.13455)
			(xy 111.520478 -177.16246) (xy 111.519992 -177.189711) (xy 111.512236 -177.243659) (xy 111.496881 -177.295954)
			(xy 111.474239 -177.345531) (xy 111.444773 -177.391381) (xy 111.409082 -177.432572) (xy 111.367891 -177.468263)
			(xy 111.322041 -177.497729) (xy 111.272464 -177.520371) (xy 111.220169 -177.535726) (xy 111.166221 -177.543482)
			(xy 111.111719 -177.543482) (xy 111.057771 -177.535726) (xy 111.005476 -177.520371) (xy 110.955899 -177.497729)
			(xy 110.910049 -177.468263) (xy 110.868858 -177.432572) (xy 110.833167 -177.391381) (xy 110.803701 -177.345531)
			(xy 110.781059 -177.295954) (xy 110.765704 -177.243659) (xy 110.757948 -177.189711) (xy 110.757462 -177.16246)
			(xy 107.329224 -177.16246) (xy 107.329224 -177.841402) (xy 107.328809 -177.865389) (xy 107.321299 -177.912773)
			(xy 107.306466 -177.958397) (xy 107.284673 -178.001137) (xy 107.25646 -178.039938) (xy 107.222521 -178.073846)
			(xy 107.183692 -178.102023) (xy 107.140932 -178.123775) (xy 107.095294 -178.138566) (xy 107.047904 -178.146031)
			(xy 107.023916 -178.146456) (xy 105.459022 -178.146456) (xy 105.452128 -178.146668) (xy 105.438856 -178.150411)
			(xy 105.43286 -178.153822) (xy 105.408968 -178.167449) (xy 105.357494 -178.186816) (xy 105.303386 -178.196666)
			(xy 105.275888 -178.197256) (xy 103.616506 -178.197256) (xy 103.592508 -178.196855) (xy 103.545098 -178.189375)
			(xy 103.499448 -178.174552) (xy 103.456688 -178.152753) (xy 103.417876 -178.124517) (xy 103.400606 -178.107848)
			(xy 103.398828 -178.10607) (xy 103.382227 -178.088745) (xy 103.354036 -178.049922) (xy 103.332257 -178.007172)
			(xy 103.317424 -177.961544) (xy 103.309902 -177.914159) (xy 103.30942 -177.89017) (xy 103.30942 -177.474372)
			(xy 103.309031 -177.464298) (xy 103.301287 -177.445699) (xy 103.294434 -177.438304) (xy 103.254048 -177.397918)
			(xy 102.804468 -176.948592) (xy 102.520496 -176.66462) (xy 102.513011 -176.657932) (xy 102.494454 -176.65034)
			(xy 102.484428 -176.649888) (xy 101.84892 -176.649888) (xy 101.83887 -176.650218) (xy 101.820273 -176.657832)
			(xy 101.812852 -176.66462) (xy 101.478842 -176.99863) (xy 101.47144 -177.005355) (xy 101.453013 -177.013074)
			(xy 101.443028 -177.013616) (xy 98.291904 -177.013616) (xy 98.281861 -177.014009) (xy 98.263265 -177.021582)
			(xy 98.255836 -177.028348) (xy 98.06178 -177.222404) (xy 98.0551 -177.229896) (xy 98.047501 -177.248447)
			(xy 98.047048 -177.258472) (xy 98.047048 -178.353212) (xy 98.767646 -178.353212) (xy 98.768132 -178.325961)
			(xy 98.775888 -178.272013) (xy 98.791243 -178.219718) (xy 98.813885 -178.170141) (xy 98.843351 -178.124291)
			(xy 98.879042 -178.0831) (xy 98.920233 -178.047409) (xy 98.966083 -178.017943) (xy 99.01566 -177.995301)
			(xy 99.067955 -177.979946) (xy 99.121903 -177.97219) (xy 99.176405 -177.97219) (xy 99.230353 -177.979946)
			(xy 99.282648 -177.995301) (xy 99.332225 -178.017943) (xy 99.378075 -178.047409) (xy 99.419266 -178.0831)
			(xy 99.454957 -178.124291) (xy 99.484423 -178.170141) (xy 99.507065 -178.219718) (xy 99.52242 -178.272013)
			(xy 99.530176 -178.325961) (xy 99.530662 -178.353212) (xy 99.529996 -178.384775) (xy 99.519612 -178.44704)
			(xy 99.499129 -178.506749) (xy 99.484688 -178.534822) (xy 99.479862 -178.543712) (xy 99.47783 -178.56327)
			(xy 99.503484 -178.651408) (xy 99.51593 -178.666902) (xy 99.52482 -178.671982) (xy 99.532186 -178.676046)
			(xy 99.541838 -178.681888) (xy 99.563936 -178.68392) (xy 99.658424 -178.650392) (xy 99.674426 -178.634898)
			(xy 99.67849 -178.624484) (xy 99.689169 -178.5977) (xy 99.717459 -178.547458) (xy 99.752992 -178.502049)
			(xy 99.794956 -178.462507) (xy 99.842396 -178.429734) (xy 99.894229 -178.404477) (xy 99.949274 -178.387313)
			(xy 100.006276 -178.378632) (xy 100.035106 -178.378104) (xy 100.062358 -178.378566) (xy 100.116307 -178.386324)
			(xy 100.168602 -178.40168) (xy 100.21818 -178.424322) (xy 100.264031 -178.453789) (xy 100.305222 -178.489482)
			(xy 100.340914 -178.530673) (xy 100.370381 -178.576525) (xy 100.393022 -178.626103) (xy 100.408378 -178.678399)
			(xy 100.416134 -178.732348) (xy 100.416134 -178.786852) (xy 100.408378 -178.840801) (xy 100.399028 -178.872642)
			(xy 100.657914 -178.872642) (xy 100.658422 -178.845168) (xy 100.666308 -178.790789) (xy 100.681923 -178.738107)
			(xy 100.704943 -178.688214) (xy 100.73489 -178.642144) (xy 100.752656 -178.621182) (xy 100.758752 -178.61407)
			(xy 100.765102 -178.597052) (xy 100.765102 -178.5112) (xy 100.758752 -178.494182) (xy 100.752656 -178.48707)
			(xy 100.73489 -178.46611) (xy 100.704967 -178.420027) (xy 100.681955 -178.370132) (xy 100.66633 -178.317455)
			(xy 100.658413 -178.263082) (xy 100.657914 -178.23561) (xy 100.6584 -178.208359) (xy 100.666156 -178.154411)
			(xy 100.681511 -178.102116) (xy 100.704153 -178.052539) (xy 100.733619 -178.006689) (xy 100.76931 -177.965498)
			(xy 100.810501 -177.929807) (xy 100.856351 -177.900341) (xy 100.905928 -177.877699) (xy 100.958223 -177.862344)
			(xy 101.012171 -177.854588) (xy 101.066673 -177.854588) (xy 101.120621 -177.862344) (xy 101.172916 -177.877699)
			(xy 101.222493 -177.900341) (xy 101.268343 -177.929807) (xy 101.309534 -177.965498) (xy 101.345225 -178.006689)
			(xy 101.374691 -178.052539) (xy 101.397333 -178.102116) (xy 101.412688 -178.154411) (xy 101.420444 -178.208359)
			(xy 101.42093 -178.23561) (xy 101.420442 -178.263084) (xy 101.41255 -178.317464) (xy 101.396929 -178.370146)
			(xy 101.373905 -178.420039) (xy 101.343955 -178.466108) (xy 101.326188 -178.48707) (xy 101.320092 -178.494182)
			(xy 101.313742 -178.5112) (xy 101.313742 -178.597052) (xy 101.320092 -178.61407) (xy 101.326188 -178.621182)
			(xy 101.343923 -178.642168) (xy 101.373852 -178.688243) (xy 101.396871 -178.738131) (xy 101.412504 -178.790803)
			(xy 101.420427 -178.845171) (xy 101.42093 -178.872642) (xy 101.420444 -178.899893) (xy 101.418811 -178.91125)
			(xy 101.99573 -178.91125) (xy 101.999801 -178.855628) (xy 102.011927 -178.801191) (xy 102.03185 -178.7491)
			(xy 102.059146 -178.700465) (xy 102.093232 -178.656322) (xy 102.133381 -178.617613) (xy 102.178739 -178.585162)
			(xy 102.228339 -178.559661) (xy 102.281123 -178.541654) (xy 102.335966 -178.531524) (xy 102.3917 -178.529487)
			(xy 102.447137 -178.535587) (xy 102.501094 -178.549693) (xy 102.552423 -178.571505) (xy 102.600029 -178.600559)
			(xy 102.642897 -178.636234) (xy 102.680114 -178.677771) (xy 102.710887 -178.724284) (xy 102.734559 -178.774781)
			(xy 102.750627 -178.828188) (xy 102.758747 -178.883364) (xy 102.759256 -178.91125) (xy 102.758747 -178.939136)
			(xy 102.750627 -178.994312) (xy 102.734559 -179.047719) (xy 102.710887 -179.098216) (xy 102.680114 -179.144729)
			(xy 102.642897 -179.186266) (xy 102.600029 -179.221941) (xy 102.552423 -179.250995) (xy 102.501094 -179.272807)
			(xy 102.447137 -179.286913) (xy 102.3917 -179.293013) (xy 102.335966 -179.290976) (xy 102.281123 -179.280846)
			(xy 102.228339 -179.262839) (xy 102.178739 -179.237338) (xy 102.133381 -179.204887) (xy 102.093232 -179.166178)
			(xy 102.059146 -179.122035) (xy 102.03185 -179.0734) (xy 102.011927 -179.021309) (xy 101.999801 -178.966872)
			(xy 101.99573 -178.91125) (xy 101.418811 -178.91125) (xy 101.412688 -178.953841) (xy 101.397333 -179.006136)
			(xy 101.374691 -179.055713) (xy 101.345225 -179.101563) (xy 101.309534 -179.142754) (xy 101.268343 -179.178445)
			(xy 101.222493 -179.207911) (xy 101.172916 -179.230553) (xy 101.120621 -179.245908) (xy 101.066673 -179.253664)
			(xy 101.012171 -179.253664) (xy 100.958223 -179.245908) (xy 100.905928 -179.230553) (xy 100.856351 -179.207911)
			(xy 100.810501 -179.178445) (xy 100.76931 -179.142754) (xy 100.733619 -179.101563) (xy 100.704153 -179.055713)
			(xy 100.681511 -179.006136) (xy 100.666156 -178.953841) (xy 100.6584 -178.899893) (xy 100.657914 -178.872642)
			(xy 100.399028 -178.872642) (xy 100.393022 -178.893097) (xy 100.370381 -178.942675) (xy 100.340914 -178.988527)
			(xy 100.305222 -179.029718) (xy 100.264031 -179.065411) (xy 100.21818 -179.094878) (xy 100.168602 -179.11752)
			(xy 100.116307 -179.132876) (xy 100.062358 -179.140634) (xy 100.035106 -179.14112) (xy 100.009871 -179.140718)
			(xy 99.959837 -179.134101) (xy 99.911117 -179.120929) (xy 99.864565 -179.101434) (xy 99.842574 -179.08905)
			(xy 99.832922 -179.083208) (xy 99.810824 -179.081176) (xy 99.716336 -179.114704) (xy 99.700334 -179.130198)
			(xy 99.69627 -179.140612) (xy 99.685539 -179.167373) (xy 99.657255 -179.217613) (xy 99.62173 -179.263022)
			(xy 99.579773 -179.302565) (xy 99.532341 -179.33534) (xy 99.480515 -179.360601) (xy 99.425477 -179.377771)
			(xy 99.368481 -179.386459) (xy 99.339654 -179.386992) (xy 99.312401 -179.386565) (xy 99.25845 -179.378802)
			(xy 99.206153 -179.36344) (xy 99.156575 -179.340792) (xy 99.110724 -179.31132) (xy 99.069534 -179.275622)
			(xy 99.033843 -179.234426) (xy 99.004378 -179.188571) (xy 98.981738 -179.138988) (xy 98.966385 -179.086689)
			(xy 98.958631 -179.032737) (xy 98.958146 -179.005484) (xy 98.958809 -178.973921) (xy 98.969194 -178.911656)
			(xy 98.989679 -178.851947) (xy 99.00412 -178.823874) (xy 99.008946 -178.814984) (xy 99.010978 -178.795426)
			(xy 98.985324 -178.707288) (xy 98.972878 -178.691794) (xy 98.963988 -178.686714) (xy 98.938862 -178.672206)
			(xy 98.89298 -178.636696) (xy 98.853007 -178.594645) (xy 98.819865 -178.547024) (xy 98.794318 -178.494933)
			(xy 98.776957 -178.439572) (xy 98.768182 -178.382221) (xy 98.767646 -178.353212) (xy 98.047048 -178.353212)
			(xy 98.047048 -179.405788) (xy 98.047385 -179.415837) (xy 98.054996 -179.434433) (xy 98.06178 -179.441856)
			(xy 98.426524 -179.8066) (xy 101.41661 -179.8066) (xy 101.420681 -179.750978) (xy 101.432807 -179.696541)
			(xy 101.45273 -179.64445) (xy 101.480026 -179.595815) (xy 101.514112 -179.551672) (xy 101.554261 -179.512963)
			(xy 101.599619 -179.480512) (xy 101.649219 -179.455011) (xy 101.702003 -179.437004) (xy 101.756846 -179.426874)
			(xy 101.81258 -179.424837) (xy 101.868017 -179.430937) (xy 101.921974 -179.445043) (xy 101.973303 -179.466855)
			(xy 102.020909 -179.495909) (xy 102.063777 -179.531584) (xy 102.100994 -179.573121) (xy 102.131767 -179.619634)
			(xy 102.155439 -179.670131) (xy 102.171507 -179.723538) (xy 102.179627 -179.778714) (xy 102.180136 -179.8066)
			(xy 102.179627 -179.834486) (xy 102.171507 -179.889662) (xy 102.155439 -179.943069) (xy 102.131767 -179.993566)
			(xy 102.100994 -180.040079) (xy 102.063777 -180.081616) (xy 102.020909 -180.117291) (xy 101.973303 -180.146345)
			(xy 101.921974 -180.168157) (xy 101.868017 -180.182263) (xy 101.81258 -180.188363) (xy 101.756846 -180.186326)
			(xy 101.702003 -180.176196) (xy 101.649219 -180.158189) (xy 101.599619 -180.132688) (xy 101.554261 -180.100237)
			(xy 101.514112 -180.061528) (xy 101.480026 -180.017385) (xy 101.45273 -179.96875) (xy 101.432807 -179.916659)
			(xy 101.420681 -179.862222) (xy 101.41661 -179.8066) (xy 98.426524 -179.8066) (xy 98.931476 -180.311552)
			(xy 98.938149 -180.318968) (xy 98.945728 -180.337401) (xy 98.946208 -180.347366) (xy 98.946208 -181.68366)
			(xy 102.375462 -181.68366) (xy 102.375938 -181.655749) (xy 102.384077 -181.600522) (xy 102.400177 -181.547072)
			(xy 102.423894 -181.496537) (xy 102.45472 -181.449998) (xy 102.472998 -181.428898) (xy 102.479348 -181.421786)
			(xy 102.485952 -181.404514) (xy 102.485952 -181.317392) (xy 102.479348 -181.30012) (xy 102.472998 -181.293008)
			(xy 102.454702 -181.271923) (xy 102.423877 -181.225381) (xy 102.400165 -181.174842) (xy 102.384073 -181.121388)
			(xy 102.375944 -181.066158) (xy 102.375462 -181.038246) (xy 102.375948 -181.010995) (xy 102.383704 -180.957047)
			(xy 102.399059 -180.904752) (xy 102.421701 -180.855175) (xy 102.451167 -180.809325) (xy 102.486858 -180.768134)
			(xy 102.528049 -180.732443) (xy 102.573899 -180.702977) (xy 102.623476 -180.680335) (xy 102.675771 -180.66498)
			(xy 102.729719 -180.657224) (xy 102.784221 -180.657224) (xy 102.838169 -180.66498) (xy 102.890464 -180.680335)
			(xy 102.940041 -180.702977) (xy 102.985891 -180.732443) (xy 103.027082 -180.768134) (xy 103.062773 -180.809325)
			(xy 103.092239 -180.855175) (xy 103.114881 -180.904752) (xy 103.130236 -180.957047) (xy 103.137992 -181.010995)
			(xy 103.138478 -181.038246) (xy 103.137996 -181.066157) (xy 103.129856 -181.121383) (xy 103.113757 -181.174833)
			(xy 103.090043 -181.225367) (xy 103.059218 -181.271907) (xy 103.040942 -181.293008) (xy 103.034592 -181.30012)
			(xy 103.027988 -181.317392) (xy 103.027988 -181.404514) (xy 103.034592 -181.421786) (xy 103.040942 -181.428898)
			(xy 103.0592 -181.450014) (xy 103.090029 -181.496549) (xy 103.113747 -181.547079) (xy 103.129849 -181.600527)
			(xy 103.137989 -181.65575) (xy 103.138478 -181.68366) (xy 103.137992 -181.710911) (xy 103.130236 -181.764859)
			(xy 103.114881 -181.817154) (xy 103.092239 -181.866731) (xy 103.062773 -181.912581) (xy 103.027082 -181.953772)
			(xy 102.985891 -181.989463) (xy 102.940041 -182.018929) (xy 102.890464 -182.041571) (xy 102.838169 -182.056926)
			(xy 102.784221 -182.064682) (xy 102.729719 -182.064682) (xy 102.675771 -182.056926) (xy 102.623476 -182.041571)
			(xy 102.573899 -182.018929) (xy 102.528049 -181.989463) (xy 102.486858 -181.953772) (xy 102.451167 -181.912581)
			(xy 102.421701 -181.866731) (xy 102.399059 -181.817154) (xy 102.383704 -181.764859) (xy 102.375948 -181.710911)
			(xy 102.375462 -181.68366) (xy 98.946208 -181.68366) (xy 98.946208 -182.28564) (xy 121.299224 -182.28564)
			(xy 121.299708 -182.25827) (xy 121.30752 -182.204092) (xy 121.323005 -182.151589) (xy 121.345843 -182.101841)
			(xy 121.375564 -182.055874) (xy 121.393204 -182.034942) (xy 121.3993 -182.02783) (xy 121.40565 -182.010812)
			(xy 121.40565 -181.925468) (xy 121.3993 -181.90845) (xy 121.393204 -181.901338) (xy 121.375603 -181.880373)
			(xy 121.345879 -181.83441) (xy 121.323032 -181.784669) (xy 121.307534 -181.732172) (xy 121.299702 -181.677999)
			(xy 121.299698 -181.623262) (xy 121.307521 -181.569087) (xy 121.323011 -181.516587) (xy 121.34585 -181.466843)
			(xy 121.375567 -181.420875) (xy 121.393204 -181.399942) (xy 121.3993 -181.39283) (xy 121.40565 -181.375812)
			(xy 121.40565 -181.290468) (xy 121.3993 -181.27345) (xy 121.393204 -181.266338) (xy 121.375603 -181.245373)
			(xy 121.345879 -181.19941) (xy 121.323032 -181.149669) (xy 121.307534 -181.097172) (xy 121.299702 -181.042999)
			(xy 121.299698 -180.988262) (xy 121.307521 -180.934087) (xy 121.323011 -180.881587) (xy 121.34585 -180.831843)
			(xy 121.375567 -180.785875) (xy 121.393204 -180.764942) (xy 121.3993 -180.75783) (xy 121.40565 -180.740812)
			(xy 121.40565 -180.655468) (xy 121.3993 -180.63845) (xy 121.393204 -180.631338) (xy 121.375603 -180.610373)
			(xy 121.345879 -180.56441) (xy 121.323032 -180.514669) (xy 121.307534 -180.462172) (xy 121.299702 -180.407999)
			(xy 121.299698 -180.353262) (xy 121.307521 -180.299087) (xy 121.323011 -180.246587) (xy 121.34585 -180.196843)
			(xy 121.375567 -180.150875) (xy 121.393204 -180.129942) (xy 121.3993 -180.12283) (xy 121.40565 -180.105812)
			(xy 121.40565 -180.020468) (xy 121.3993 -180.00345) (xy 121.393204 -179.996338) (xy 121.375603 -179.975373)
			(xy 121.345879 -179.92941) (xy 121.323032 -179.879669) (xy 121.307534 -179.827172) (xy 121.299702 -179.772999)
			(xy 121.299698 -179.718262) (xy 121.307521 -179.664087) (xy 121.323011 -179.611587) (xy 121.34585 -179.561843)
			(xy 121.375567 -179.515875) (xy 121.393204 -179.494942) (xy 121.3993 -179.48783) (xy 121.40565 -179.470812)
			(xy 121.40565 -179.385468) (xy 121.3993 -179.36845) (xy 121.393204 -179.361338) (xy 121.375603 -179.340373)
			(xy 121.345879 -179.29441) (xy 121.323032 -179.244669) (xy 121.307534 -179.192172) (xy 121.299702 -179.137999)
			(xy 121.299698 -179.083262) (xy 121.307521 -179.029087) (xy 121.323011 -178.976587) (xy 121.34585 -178.926843)
			(xy 121.375567 -178.880875) (xy 121.393204 -178.859942) (xy 121.3993 -178.85283) (xy 121.40565 -178.835812)
			(xy 121.40565 -178.750468) (xy 121.3993 -178.73345) (xy 121.393204 -178.726338) (xy 121.375603 -178.705373)
			(xy 121.345879 -178.65941) (xy 121.323032 -178.609669) (xy 121.307534 -178.557172) (xy 121.299702 -178.502999)
			(xy 121.299698 -178.448262) (xy 121.307521 -178.394087) (xy 121.323011 -178.341587) (xy 121.34585 -178.291843)
			(xy 121.375567 -178.245875) (xy 121.393204 -178.224942) (xy 121.3993 -178.21783) (xy 121.40565 -178.200812)
			(xy 121.40565 -178.115468) (xy 121.3993 -178.09845) (xy 121.393204 -178.091338) (xy 121.37557 -178.070402)
			(xy 121.345857 -178.02443) (xy 121.32302 -177.974684) (xy 121.307528 -177.922184) (xy 121.299699 -177.868009)
			(xy 121.299224 -177.84064) (xy 121.29977 -177.811474) (xy 121.308667 -177.753823) (xy 121.326243 -177.698201)
			(xy 121.352088 -177.645906) (xy 121.385599 -177.59816) (xy 121.405396 -177.576734) (xy 121.412254 -177.569368)
			(xy 121.419366 -177.551588) (xy 121.419366 -177.461164) (xy 121.412254 -177.443384) (xy 121.405396 -177.436018)
			(xy 121.385611 -177.414586) (xy 121.352127 -177.366827) (xy 121.326295 -177.314532) (xy 121.308716 -177.258917)
			(xy 121.299799 -177.201275) (xy 121.299224 -177.172112) (xy 121.299667 -177.144858) (xy 121.307423 -177.090905)
			(xy 121.322779 -177.038604) (xy 121.345422 -176.989022) (xy 121.374892 -176.943168) (xy 121.410588 -176.901974)
			(xy 121.451784 -176.86628) (xy 121.49764 -176.836813) (xy 121.547223 -176.814172) (xy 121.599524 -176.798818)
			(xy 121.653478 -176.791065) (xy 121.680732 -176.790604) (xy 121.708103 -176.79105) (xy 121.762283 -176.798873)
			(xy 121.814786 -176.814366) (xy 121.864533 -176.837213) (xy 121.910499 -176.866941) (xy 121.93143 -176.884584)
			(xy 121.938542 -176.89068) (xy 121.95556 -176.89703) (xy 122.040904 -176.89703) (xy 122.057922 -176.89068)
			(xy 122.065034 -176.884584) (xy 122.085967 -176.866943) (xy 122.131935 -176.837219) (xy 122.181681 -176.814373)
			(xy 122.234183 -176.798877) (xy 122.288361 -176.791048) (xy 122.343103 -176.791048) (xy 122.397281 -176.798877)
			(xy 122.449783 -176.814373) (xy 122.499529 -176.837219) (xy 122.545497 -176.866943) (xy 122.56643 -176.884584)
			(xy 122.573542 -176.89068) (xy 122.59056 -176.89703) (xy 122.675904 -176.89703) (xy 122.692922 -176.89068)
			(xy 122.700034 -176.884584) (xy 122.720978 -176.86696) (xy 122.766948 -176.837246) (xy 122.816692 -176.814408)
			(xy 122.86919 -176.798913) (xy 122.923364 -176.791081) (xy 122.950732 -176.790604) (xy 122.977985 -176.791048)
			(xy 123.031934 -176.798809) (xy 123.084231 -176.814169) (xy 123.133809 -176.836815) (xy 123.17966 -176.866286)
			(xy 123.22085 -176.901981) (xy 123.256541 -176.943176) (xy 123.286006 -176.98903) (xy 123.308646 -177.038611)
			(xy 123.324 -177.090909) (xy 123.331755 -177.144859) (xy 123.33224 -177.172112) (xy 125.312424 -177.172112)
			(xy 125.312867 -177.144858) (xy 125.320623 -177.090905) (xy 125.335979 -177.038604) (xy 125.358622 -176.989022)
			(xy 125.388092 -176.943168) (xy 125.423788 -176.901974) (xy 125.464984 -176.86628) (xy 125.51084 -176.836813)
			(xy 125.560423 -176.814172) (xy 125.612724 -176.798818) (xy 125.666678 -176.791065) (xy 125.693932 -176.790604)
			(xy 125.721303 -176.79105) (xy 125.775483 -176.798873) (xy 125.827986 -176.814366) (xy 125.877733 -176.837213)
			(xy 125.923699 -176.866941) (xy 125.94463 -176.884584) (xy 125.951742 -176.89068) (xy 125.96876 -176.89703)
			(xy 126.054104 -176.89703) (xy 126.071122 -176.89068) (xy 126.078234 -176.884584) (xy 126.099167 -176.866943)
			(xy 126.145135 -176.837219) (xy 126.194881 -176.814373) (xy 126.247383 -176.798877) (xy 126.301561 -176.791048)
			(xy 126.356303 -176.791048) (xy 126.410481 -176.798877) (xy 126.462983 -176.814373) (xy 126.512729 -176.837219)
			(xy 126.558697 -176.866943) (xy 126.57963 -176.884584) (xy 126.586742 -176.89068) (xy 126.60376 -176.89703)
			(xy 126.689104 -176.89703) (xy 126.706122 -176.89068) (xy 126.713234 -176.884584) (xy 126.734178 -176.86696)
			(xy 126.780148 -176.837246) (xy 126.829892 -176.814408) (xy 126.88239 -176.798913) (xy 126.936564 -176.791081)
			(xy 126.963932 -176.790604) (xy 126.991185 -176.791048) (xy 127.045134 -176.798809) (xy 127.097431 -176.814169)
			(xy 127.147009 -176.836815) (xy 127.19286 -176.866286) (xy 127.23405 -176.901981) (xy 127.269741 -176.943176)
			(xy 127.299206 -176.98903) (xy 127.321846 -177.038611) (xy 127.3372 -177.090909) (xy 127.344955 -177.144859)
			(xy 127.34544 -177.172112) (xy 127.344905 -177.201231) (xy 127.336058 -177.258792) (xy 127.31857 -177.314341)
			(xy 127.292849 -177.366591) (xy 127.25949 -177.414327) (xy 127.239776 -177.435764) (xy 127.232918 -177.442876)
			(xy 127.225806 -177.46091) (xy 127.225806 -177.55108) (xy 127.233172 -177.569114) (xy 127.24003 -177.576226)
			(xy 127.259872 -177.59769) (xy 127.293469 -177.64552) (xy 127.319378 -177.697914) (xy 127.336993 -177.753647)
			(xy 127.345901 -177.811415) (xy 127.346456 -177.84064) (xy 127.345965 -177.868009) (xy 127.338155 -177.922188)
			(xy 127.322672 -177.974691) (xy 127.299836 -178.024439) (xy 127.270115 -178.070406) (xy 127.252476 -178.091338)
			(xy 127.24638 -178.09845) (xy 127.24003 -178.115468) (xy 127.24003 -178.200812) (xy 127.24638 -178.21783)
			(xy 127.252476 -178.224942) (xy 127.270156 -178.245843) (xy 127.299879 -178.291816) (xy 127.322722 -178.341568)
			(xy 127.338215 -178.394075) (xy 127.346039 -178.448258) (xy 127.346035 -178.503003) (xy 127.338202 -178.557184)
			(xy 127.3227 -178.609689) (xy 127.29985 -178.659436) (xy 127.270119 -178.705405) (xy 127.252476 -178.726338)
			(xy 127.24638 -178.73345) (xy 127.24003 -178.750468) (xy 127.24003 -178.835812) (xy 127.24638 -178.85283)
			(xy 127.252476 -178.859942) (xy 127.270098 -178.880888) (xy 127.299813 -178.926857) (xy 127.322653 -178.976601)
			(xy 127.338148 -179.029098) (xy 127.34598 -179.083272) (xy 127.346456 -179.11064) (xy 127.34596 -179.13789)
			(xy 127.338199 -179.191835) (xy 127.322841 -179.244126) (xy 127.300199 -179.293701) (xy 127.270733 -179.339549)
			(xy 127.235043 -179.380737) (xy 127.193855 -179.416428) (xy 127.148008 -179.445895) (xy 127.098434 -179.468538)
			(xy 127.046143 -179.483897) (xy 126.992198 -179.491659) (xy 126.964948 -179.492148) (xy 126.935506 -179.4916)
			(xy 126.877322 -179.482559) (xy 126.821217 -179.464683) (xy 126.768527 -179.438398) (xy 126.720501 -179.404329)
			(xy 126.69901 -179.384198) (xy 126.692406 -179.377594) (xy 126.675642 -179.370482) (xy 126.590298 -179.36591)
			(xy 126.573026 -179.371498) (xy 126.56566 -179.377086) (xy 126.545426 -179.392476) (xy 126.501634 -179.418299)
			(xy 126.454801 -179.438076) (xy 126.405755 -179.451457) (xy 126.355367 -179.458203) (xy 126.329948 -179.45862)
			(xy 126.302578 -179.458145) (xy 126.248398 -179.450333) (xy 126.195895 -179.434847) (xy 126.146147 -179.412006)
			(xy 126.100181 -179.382282) (xy 126.07925 -179.36464) (xy 126.072138 -179.358544) (xy 126.05512 -179.352194)
			(xy 125.969776 -179.352194) (xy 125.952758 -179.358544) (xy 125.945646 -179.36464) (xy 125.924713 -179.382278)
			(xy 125.87874 -179.411988) (xy 125.828992 -179.434824) (xy 125.776492 -179.450316) (xy 125.722317 -179.458145)
			(xy 125.694948 -179.45862) (xy 125.667697 -179.4581) (xy 125.613749 -179.45035) (xy 125.561453 -179.435001)
			(xy 125.511873 -179.412365) (xy 125.466021 -179.382903) (xy 125.424828 -179.347215) (xy 125.389133 -179.306028)
			(xy 125.359664 -179.260179) (xy 125.33702 -179.210604) (xy 125.321663 -179.15831) (xy 125.313904 -179.104363)
			(xy 125.31344 -179.077112) (xy 125.313903 -179.049742) (xy 125.32172 -178.995562) (xy 125.33721 -178.943058)
			(xy 125.360052 -178.893312) (xy 125.389778 -178.847345) (xy 125.40742 -178.826414) (xy 125.413516 -178.819302)
			(xy 125.419866 -178.802284) (xy 125.419866 -178.71694) (xy 125.413516 -178.699922) (xy 125.40742 -178.69281)
			(xy 125.389791 -178.671868) (xy 125.360067 -178.625901) (xy 125.337221 -178.576157) (xy 125.321724 -178.523656)
			(xy 125.313895 -178.469479) (xy 125.313893 -178.414739) (xy 125.32172 -178.360562) (xy 125.337215 -178.30806)
			(xy 125.360058 -178.258315) (xy 125.38978 -178.212347) (xy 125.40742 -178.191414) (xy 125.413516 -178.184302)
			(xy 125.419866 -178.167284) (xy 125.419866 -178.08194) (xy 125.413516 -178.064922) (xy 125.40742 -178.05781)
			(xy 125.389775 -178.036882) (xy 125.360064 -177.990909) (xy 125.337228 -177.94116) (xy 125.321739 -177.888658)
			(xy 125.313913 -177.834482) (xy 125.31344 -177.807112) (xy 125.313921 -177.779813) (xy 125.321692 -177.725771)
			(xy 125.33709 -177.67339) (xy 125.359802 -177.62374) (xy 125.389362 -177.577837) (xy 125.406912 -177.556922)
			(xy 125.413262 -177.54981) (xy 125.419358 -177.532792) (xy 125.419358 -177.447194) (xy 125.413008 -177.43043)
			(xy 125.406912 -177.423318) (xy 125.389209 -177.402348) (xy 125.359328 -177.356319) (xy 125.336359 -177.306479)
			(xy 125.320777 -177.253861) (xy 125.312903 -177.199551) (xy 125.312424 -177.172112) (xy 123.33224 -177.172112)
			(xy 123.331753 -177.199411) (xy 123.323981 -177.253451) (xy 123.308583 -177.305832) (xy 123.285873 -177.355481)
			(xy 123.256316 -177.401386) (xy 123.238768 -177.422302) (xy 123.232418 -177.429414) (xy 123.226322 -177.446432)
			(xy 123.226322 -177.53203) (xy 123.232672 -177.548794) (xy 123.238768 -177.555906) (xy 123.25648 -177.576869)
			(xy 123.28636 -177.6229) (xy 123.309327 -177.672741) (xy 123.324908 -177.725362) (xy 123.332778 -177.779673)
			(xy 123.333256 -177.807112) (xy 123.332808 -177.834483) (xy 123.324987 -177.888663) (xy 123.309495 -177.941167)
			(xy 123.286649 -177.990914) (xy 123.25692 -178.036879) (xy 123.239276 -178.05781) (xy 123.23318 -178.064922)
			(xy 123.22683 -178.08194) (xy 123.22683 -178.167284) (xy 123.23318 -178.184302) (xy 123.239276 -178.191414)
			(xy 123.256928 -178.212337) (xy 123.286652 -178.258307) (xy 123.309497 -178.308055) (xy 123.324992 -178.360558)
			(xy 123.33282 -178.414738) (xy 123.332818 -178.46948) (xy 123.324988 -178.52366) (xy 123.309491 -178.576162)
			(xy 123.286644 -178.625909) (xy 123.256917 -178.671877) (xy 123.239276 -178.69281) (xy 123.23318 -178.699922)
			(xy 123.22683 -178.71694) (xy 123.22683 -178.802284) (xy 123.23318 -178.819302) (xy 123.239276 -178.826414)
			(xy 123.256928 -178.847337) (xy 123.286652 -178.893307) (xy 123.309497 -178.943055) (xy 123.324992 -178.995558)
			(xy 123.33282 -179.049738) (xy 123.332818 -179.10448) (xy 123.324988 -179.15866) (xy 123.309491 -179.211162)
			(xy 123.286644 -179.260909) (xy 123.256917 -179.306877) (xy 123.239276 -179.32781) (xy 123.23318 -179.334922)
			(xy 123.22683 -179.35194) (xy 123.22683 -179.437284) (xy 123.23318 -179.454302) (xy 123.239276 -179.461414)
			(xy 123.256885 -179.482371) (xy 123.286602 -179.528336) (xy 123.309444 -179.578078) (xy 123.324942 -179.630573)
			(xy 123.332778 -179.684744) (xy 123.333256 -179.712112) (xy 123.33272 -179.741337) (xy 123.323795 -179.799103)
			(xy 123.306173 -179.854833) (xy 123.280264 -179.907228) (xy 123.246673 -179.955062) (xy 123.22683 -179.976526)
			(xy 123.219972 -179.983638) (xy 123.212606 -180.001672) (xy 123.212606 -180.091842) (xy 123.219718 -180.109876)
			(xy 123.226576 -180.116988) (xy 123.246304 -180.138413) (xy 123.279658 -180.186153) (xy 123.305373 -180.238406)
			(xy 123.322854 -180.293958) (xy 123.331694 -180.351521) (xy 123.33224 -180.38064) (xy 123.331753 -180.40801)
			(xy 123.323943 -180.462188) (xy 123.308459 -180.514692) (xy 123.285622 -180.564439) (xy 123.2559 -180.610406)
			(xy 123.23826 -180.631338) (xy 123.232164 -180.63845) (xy 123.225814 -180.655468) (xy 123.225814 -180.740812)
			(xy 123.232164 -180.75783) (xy 123.23826 -180.764942) (xy 123.25594 -180.785843) (xy 123.285665 -180.831816)
			(xy 123.308508 -180.881567) (xy 123.324002 -180.934074) (xy 123.331827 -180.988257) (xy 123.331823 -181.043003)
			(xy 123.323989 -181.097185) (xy 123.308487 -181.149689) (xy 123.285636 -181.199437) (xy 123.255904 -181.245405)
			(xy 123.23826 -181.266338) (xy 123.232164 -181.27345) (xy 123.225814 -181.290468) (xy 123.225814 -181.375812)
			(xy 123.232164 -181.39283) (xy 123.23826 -181.399942) (xy 123.255879 -181.42089) (xy 123.285595 -181.466858)
			(xy 123.308436 -181.516601) (xy 123.323931 -181.569099) (xy 123.331764 -181.623272) (xy 123.33224 -181.65064)
			(xy 123.331759 -181.677891) (xy 123.323998 -181.731837) (xy 123.30864 -181.78413) (xy 123.285996 -181.833705)
			(xy 123.256529 -181.879554) (xy 123.220837 -181.920743) (xy 123.179647 -181.956434) (xy 123.133798 -181.9859)
			(xy 123.084222 -182.008543) (xy 123.031929 -182.0239) (xy 122.977983 -182.03166) (xy 122.950732 -182.032148)
			(xy 122.923362 -182.031676) (xy 122.869183 -182.023861) (xy 122.816679 -182.008374) (xy 122.766932 -181.985534)
			(xy 122.720965 -181.955809) (xy 122.700034 -181.938168) (xy 122.692922 -181.932072) (xy 122.675904 -181.925722)
			(xy 122.59056 -181.925722) (xy 122.573542 -181.932072) (xy 122.56643 -181.938168) (xy 122.545493 -181.955802)
			(xy 122.499522 -181.985515) (xy 122.449776 -182.008353) (xy 122.397276 -182.023845) (xy 122.343101 -182.031674)
			(xy 122.315732 -182.032148) (xy 122.286254 -182.031603) (xy 122.228001 -182.022537) (xy 122.171836 -182.004617)
			(xy 122.119096 -181.978268) (xy 122.071039 -181.944119) (xy 122.04954 -181.923944) (xy 122.042193 -181.917426)
			(xy 122.024042 -181.909973) (xy 122.014234 -181.909466) (xy 121.960894 -181.909466) (xy 121.954036 -181.916832)
			(xy 121.947486 -181.924154) (xy 121.940052 -181.942324) (xy 121.939558 -181.952138) (xy 121.939558 -181.984142)
			(xy 121.940043 -181.993956) (xy 121.94749 -182.01212) (xy 121.954036 -182.019448) (xy 121.97423 -182.040929)
			(xy 122.008372 -182.088993) (xy 122.034715 -182.141737) (xy 122.052632 -182.197906) (xy 122.061694 -182.256162)
			(xy 122.06224 -182.28564) (xy 122.061754 -182.312891) (xy 122.053998 -182.366839) (xy 122.038643 -182.419134)
			(xy 122.016001 -182.468711) (xy 121.986535 -182.514561) (xy 121.950844 -182.555752) (xy 121.909653 -182.591443)
			(xy 121.863803 -182.620909) (xy 121.814226 -182.643551) (xy 121.761931 -182.658906) (xy 121.707983 -182.666662)
			(xy 121.653481 -182.666662) (xy 121.599533 -182.658906) (xy 121.547238 -182.643551) (xy 121.497661 -182.620909)
			(xy 121.451811 -182.591443) (xy 121.41062 -182.555752) (xy 121.374929 -182.514561) (xy 121.345463 -182.468711)
			(xy 121.322821 -182.419134) (xy 121.307466 -182.366839) (xy 121.29971 -182.312891) (xy 121.299224 -182.28564)
			(xy 98.946208 -182.28564) (xy 98.946208 -182.362602) (xy 98.94581 -182.386578) (xy 98.938308 -182.433938)
			(xy 98.923488 -182.479542) (xy 98.901717 -182.522265) (xy 98.873529 -182.561057) (xy 98.83962 -182.594961)
			(xy 98.800824 -182.623142) (xy 98.758097 -182.644907) (xy 98.712491 -182.659719) (xy 98.66513 -182.667214)
			(xy 98.641154 -182.667656) (xy 97.067116 -182.667656) (xy 97.05467 -182.670958) (xy 97.048828 -182.674514)
			(xy 97.025705 -182.687006) (xy 96.976248 -182.704775) (xy 96.924481 -182.713819) (xy 96.898206 -182.714392)
			(xy 95.693992 -182.714392) (xy 95.68399 -182.713907) (xy 95.665528 -182.706204) (xy 95.658178 -182.699406)
			(xy 95.317818 -182.359046) (xy 95.311101 -182.351637) (xy 95.303376 -182.333216) (xy 95.302832 -182.323232)
			(xy 95.302832 -181.248558) (xy 95.302476 -181.238511) (xy 95.294879 -181.219914) (xy 95.2881 -181.21249)
			(xy 94.731332 -180.655722) (xy 94.724649 -180.648314) (xy 94.717076 -180.629875) (xy 94.7166 -180.619908)
			(xy 94.7166 -177.146204) (xy 94.716199 -177.136131) (xy 94.708464 -177.117532) (xy 94.701614 -177.110136)
			(xy 94.60484 -177.013362) (xy 94.597425 -177.006542) (xy 94.578837 -176.998812) (xy 94.568772 -176.998376)
			(xy 89.938352 -176.998376) (xy 89.928283 -176.998809) (xy 89.909684 -177.006522) (xy 89.902284 -177.013362)
			(xy 89.67978 -177.235866) (xy 89.673073 -177.243336) (xy 89.66549 -177.261904) (xy 89.665048 -177.271934)
			(xy 89.665048 -178.33594) (xy 90.375486 -178.33594) (xy 90.375972 -178.308689) (xy 90.383728 -178.254741)
			(xy 90.399083 -178.202446) (xy 90.421725 -178.152869) (xy 90.451191 -178.107019) (xy 90.486882 -178.065828)
			(xy 90.528073 -178.030137) (xy 90.573923 -178.000671) (xy 90.6235 -177.978029) (xy 90.675795 -177.962674)
			(xy 90.729743 -177.954918) (xy 90.784245 -177.954918) (xy 90.838193 -177.962674) (xy 90.890488 -177.978029)
			(xy 90.940065 -178.000671) (xy 90.985915 -178.030137) (xy 91.027106 -178.065828) (xy 91.062797 -178.107019)
			(xy 91.092263 -178.152869) (xy 91.114905 -178.202446) (xy 91.13026 -178.254741) (xy 91.138016 -178.308689)
			(xy 91.138502 -178.33594) (xy 91.137843 -178.367503) (xy 91.127455 -178.429768) (xy 91.106969 -178.489477)
			(xy 91.092528 -178.51755) (xy 91.087702 -178.52644) (xy 91.08567 -178.545998) (xy 91.111324 -178.634136)
			(xy 91.12377 -178.64963) (xy 91.13266 -178.65471) (xy 91.140026 -178.658774) (xy 91.149678 -178.664616)
			(xy 91.171776 -178.666648) (xy 91.266264 -178.63312) (xy 91.282266 -178.617626) (xy 91.28633 -178.607212)
			(xy 91.297074 -178.580456) (xy 91.325355 -178.530215) (xy 91.360878 -178.484806) (xy 91.402832 -178.445262)
			(xy 91.450263 -178.412485) (xy 91.502087 -178.387224) (xy 91.557124 -178.370053) (xy 91.614119 -178.361365)
			(xy 91.642946 -178.360832) (xy 91.670198 -178.361241) (xy 91.724146 -178.369004) (xy 91.776441 -178.384364)
			(xy 91.826018 -178.407011) (xy 91.871867 -178.436481) (xy 91.913056 -178.472176) (xy 91.948746 -178.51337)
			(xy 91.978212 -178.559223) (xy 92.000852 -178.608802) (xy 92.016206 -178.661099) (xy 92.023962 -178.715048)
			(xy 92.023962 -178.769552) (xy 92.016206 -178.823501) (xy 92.00685 -178.85537) (xy 92.265754 -178.85537)
			(xy 92.266209 -178.827894) (xy 92.274107 -178.773513) (xy 92.289733 -178.720829) (xy 92.312765 -178.670937)
			(xy 92.342725 -178.62487) (xy 92.360496 -178.60391) (xy 92.366592 -178.596798) (xy 92.372942 -178.57978)
			(xy 92.372942 -178.493928) (xy 92.366592 -178.47691) (xy 92.360496 -178.469798) (xy 92.34275 -178.448822)
			(xy 92.312822 -178.402744) (xy 92.289806 -178.352853) (xy 92.274176 -178.300179) (xy 92.266255 -178.245809)
			(xy 92.265754 -178.218338) (xy 92.26624 -178.191087) (xy 92.273996 -178.137139) (xy 92.289351 -178.084844)
			(xy 92.311993 -178.035267) (xy 92.341459 -177.989417) (xy 92.37715 -177.948226) (xy 92.418341 -177.912535)
			(xy 92.464191 -177.883069) (xy 92.513768 -177.860427) (xy 92.566063 -177.845072) (xy 92.620011 -177.837316)
			(xy 92.674513 -177.837316) (xy 92.728461 -177.845072) (xy 92.780756 -177.860427) (xy 92.830333 -177.883069)
			(xy 92.876183 -177.912535) (xy 92.917374 -177.948226) (xy 92.953065 -177.989417) (xy 92.982531 -178.035267)
			(xy 93.005173 -178.084844) (xy 93.020528 -178.137139) (xy 93.028284 -178.191087) (xy 93.02877 -178.218338)
			(xy 93.028313 -178.245814) (xy 93.020415 -178.300195) (xy 93.004789 -178.352878) (xy 92.981757 -178.40277)
			(xy 92.951799 -178.448837) (xy 92.934028 -178.469798) (xy 92.927932 -178.47691) (xy 92.921582 -178.493928)
			(xy 92.921582 -178.57978) (xy 92.927932 -178.596798) (xy 92.934028 -178.60391) (xy 92.951782 -178.62488)
			(xy 92.981707 -178.67096) (xy 93.004722 -178.720852) (xy 93.02035 -178.773527) (xy 93.028269 -178.827898)
			(xy 93.02877 -178.85537) (xy 93.028284 -178.882621) (xy 93.026651 -178.893978) (xy 93.60357 -178.893978)
			(xy 93.607641 -178.838356) (xy 93.619767 -178.783919) (xy 93.63969 -178.731828) (xy 93.666986 -178.683193)
			(xy 93.701072 -178.63905) (xy 93.741221 -178.600341) (xy 93.786579 -178.56789) (xy 93.836179 -178.542389)
			(xy 93.888963 -178.524382) (xy 93.943806 -178.514252) (xy 93.99954 -178.512215) (xy 94.054977 -178.518315)
			(xy 94.108934 -178.532421) (xy 94.160263 -178.554233) (xy 94.207869 -178.583287) (xy 94.250737 -178.618962)
			(xy 94.287954 -178.660499) (xy 94.318727 -178.707012) (xy 94.342399 -178.757509) (xy 94.358467 -178.810916)
			(xy 94.366587 -178.866092) (xy 94.367096 -178.893978) (xy 94.366587 -178.921864) (xy 94.358467 -178.97704)
			(xy 94.342399 -179.030447) (xy 94.318727 -179.080944) (xy 94.287954 -179.127457) (xy 94.250737 -179.168994)
			(xy 94.207869 -179.204669) (xy 94.160263 -179.233723) (xy 94.108934 -179.255535) (xy 94.054977 -179.269641)
			(xy 93.99954 -179.275741) (xy 93.943806 -179.273704) (xy 93.888963 -179.263574) (xy 93.836179 -179.245567)
			(xy 93.786579 -179.220066) (xy 93.741221 -179.187615) (xy 93.701072 -179.148906) (xy 93.666986 -179.104763)
			(xy 93.63969 -179.056128) (xy 93.619767 -179.004037) (xy 93.607641 -178.9496) (xy 93.60357 -178.893978)
			(xy 93.026651 -178.893978) (xy 93.020528 -178.936569) (xy 93.005173 -178.988864) (xy 92.982531 -179.038441)
			(xy 92.953065 -179.084291) (xy 92.917374 -179.125482) (xy 92.876183 -179.161173) (xy 92.830333 -179.190639)
			(xy 92.780756 -179.213281) (xy 92.728461 -179.228636) (xy 92.674513 -179.236392) (xy 92.620011 -179.236392)
			(xy 92.566063 -179.228636) (xy 92.513768 -179.213281) (xy 92.464191 -179.190639) (xy 92.418341 -179.161173)
			(xy 92.37715 -179.125482) (xy 92.341459 -179.084291) (xy 92.311993 -179.038441) (xy 92.289351 -178.988864)
			(xy 92.273996 -178.936569) (xy 92.26624 -178.882621) (xy 92.265754 -178.85537) (xy 92.00685 -178.85537)
			(xy 92.000852 -178.875798) (xy 91.978212 -178.925377) (xy 91.948746 -178.97123) (xy 91.913056 -179.012424)
			(xy 91.871867 -179.048119) (xy 91.826018 -179.077589) (xy 91.776441 -179.100236) (xy 91.724146 -179.115596)
			(xy 91.670198 -179.123359) (xy 91.642946 -179.123848) (xy 91.61771 -179.123468) (xy 91.567676 -179.116844)
			(xy 91.518956 -179.103666) (xy 91.472404 -179.084165) (xy 91.450414 -179.071778) (xy 91.440762 -179.065936)
			(xy 91.418664 -179.063904) (xy 91.324176 -179.097432) (xy 91.308174 -179.112926) (xy 91.30411 -179.12334)
			(xy 91.293443 -179.150129) (xy 91.26515 -179.20037) (xy 91.229616 -179.245779) (xy 91.187649 -179.28532)
			(xy 91.140208 -179.318092) (xy 91.088373 -179.343348) (xy 91.033327 -179.360511) (xy 90.976324 -179.369192)
			(xy 90.947494 -179.36972) (xy 90.920243 -179.369228) (xy 90.866296 -179.361471) (xy 90.814002 -179.346116)
			(xy 90.764426 -179.323475) (xy 90.718576 -179.294009) (xy 90.677386 -179.258318) (xy 90.641695 -179.217129)
			(xy 90.612228 -179.171279) (xy 90.589587 -179.121703) (xy 90.57423 -179.06941) (xy 90.566473 -179.015463)
			(xy 90.565986 -178.988212) (xy 90.566628 -178.956648) (xy 90.577023 -178.894383) (xy 90.597515 -178.834674)
			(xy 90.61196 -178.806602) (xy 90.616786 -178.797712) (xy 90.618818 -178.778154) (xy 90.593164 -178.690016)
			(xy 90.580718 -178.674522) (xy 90.571828 -178.669442) (xy 90.546724 -178.654899) (xy 90.50084 -178.619396)
			(xy 90.460864 -178.577351) (xy 90.427719 -178.529737) (xy 90.402168 -178.477651) (xy 90.384803 -178.422295)
			(xy 90.376024 -178.364948) (xy 90.375486 -178.33594) (xy 89.665048 -178.33594) (xy 89.665048 -179.385468)
			(xy 89.665395 -179.395516) (xy 89.672999 -179.414112) (xy 89.67978 -179.421536) (xy 90.047572 -179.789328)
			(xy 93.02445 -179.789328) (xy 93.028521 -179.733706) (xy 93.040647 -179.679269) (xy 93.06057 -179.627178)
			(xy 93.087866 -179.578543) (xy 93.121952 -179.5344) (xy 93.162101 -179.495691) (xy 93.207459 -179.46324)
			(xy 93.257059 -179.437739) (xy 93.309843 -179.419732) (xy 93.364686 -179.409602) (xy 93.42042 -179.407565)
			(xy 93.475857 -179.413665) (xy 93.529814 -179.427771) (xy 93.581143 -179.449583) (xy 93.628749 -179.478637)
			(xy 93.671617 -179.514312) (xy 93.708834 -179.555849) (xy 93.739607 -179.602362) (xy 93.763279 -179.652859)
			(xy 93.779347 -179.706266) (xy 93.787467 -179.761442) (xy 93.787976 -179.789328) (xy 93.787467 -179.817214)
			(xy 93.779347 -179.87239) (xy 93.763279 -179.925797) (xy 93.739607 -179.976294) (xy 93.708834 -180.022807)
			(xy 93.671617 -180.064344) (xy 93.628749 -180.100019) (xy 93.581143 -180.129073) (xy 93.529814 -180.150885)
			(xy 93.475857 -180.164991) (xy 93.42042 -180.171091) (xy 93.364686 -180.169054) (xy 93.309843 -180.158924)
			(xy 93.257059 -180.140917) (xy 93.207459 -180.115416) (xy 93.162101 -180.082965) (xy 93.121952 -180.044256)
			(xy 93.087866 -180.000113) (xy 93.06057 -179.951478) (xy 93.040647 -179.899387) (xy 93.028521 -179.84495)
			(xy 93.02445 -179.789328) (xy 90.047572 -179.789328) (xy 90.536776 -180.278532) (xy 90.54344 -180.285954)
			(xy 90.551024 -180.304383) (xy 90.551508 -180.314346) (xy 90.551508 -181.666388) (xy 93.983302 -181.666388)
			(xy 93.98381 -181.638478) (xy 93.991944 -181.583254) (xy 94.008037 -181.529804) (xy 94.031746 -181.479269)
			(xy 94.062564 -181.432728) (xy 94.080838 -181.411626) (xy 94.087188 -181.404514) (xy 94.093792 -181.387242)
			(xy 94.093792 -181.30012) (xy 94.087188 -181.282848) (xy 94.080838 -181.275736) (xy 94.062546 -181.254648)
			(xy 94.031722 -181.208106) (xy 94.008011 -181.157568) (xy 93.991918 -181.104114) (xy 93.983786 -181.048886)
			(xy 93.983302 -181.020974) (xy 93.983788 -180.993723) (xy 93.991544 -180.939775) (xy 94.006899 -180.88748)
			(xy 94.029541 -180.837903) (xy 94.059007 -180.792053) (xy 94.094698 -180.750862) (xy 94.135889 -180.715171)
			(xy 94.181739 -180.685705) (xy 94.231316 -180.663063) (xy 94.283611 -180.647708) (xy 94.337559 -180.639952)
			(xy 94.392061 -180.639952) (xy 94.446009 -180.647708) (xy 94.498304 -180.663063) (xy 94.547881 -180.685705)
			(xy 94.593731 -180.715171) (xy 94.634922 -180.750862) (xy 94.670613 -180.792053) (xy 94.700079 -180.837903)
			(xy 94.722721 -180.88748) (xy 94.738076 -180.939775) (xy 94.745832 -180.993723) (xy 94.746318 -181.020974)
			(xy 94.745868 -181.048886) (xy 94.737722 -181.104114) (xy 94.721617 -181.157565) (xy 94.697895 -181.208099)
			(xy 94.667063 -181.254637) (xy 94.648782 -181.275736) (xy 94.642432 -181.282848) (xy 94.635828 -181.30012)
			(xy 94.635828 -181.387242) (xy 94.642432 -181.404514) (xy 94.648782 -181.411626) (xy 94.667044 -181.432739)
			(xy 94.697874 -181.479274) (xy 94.721593 -181.529805) (xy 94.737693 -181.583253) (xy 94.745831 -181.638478)
			(xy 94.746318 -181.666388) (xy 94.745832 -181.693639) (xy 94.738076 -181.747587) (xy 94.722721 -181.799882)
			(xy 94.700079 -181.849459) (xy 94.670613 -181.895309) (xy 94.634922 -181.9365) (xy 94.593731 -181.972191)
			(xy 94.547881 -182.001657) (xy 94.498304 -182.024299) (xy 94.446009 -182.039654) (xy 94.392061 -182.04741)
			(xy 94.337559 -182.04741) (xy 94.283611 -182.039654) (xy 94.231316 -182.024299) (xy 94.181739 -182.001657)
			(xy 94.135889 -181.972191) (xy 94.094698 -181.9365) (xy 94.059007 -181.895309) (xy 94.029541 -181.849459)
			(xy 94.006899 -181.799882) (xy 93.991544 -181.747587) (xy 93.983788 -181.693639) (xy 93.983302 -181.666388)
			(xy 90.551508 -181.666388) (xy 90.551508 -182.34533) (xy 90.551136 -182.369306) (xy 90.54363 -182.416668)
			(xy 90.528807 -182.462272) (xy 90.507032 -182.504996) (xy 90.478841 -182.543787) (xy 90.444929 -182.57769)
			(xy 90.406131 -182.605871) (xy 90.363402 -182.627636) (xy 90.317794 -182.642447) (xy 90.27043 -182.649942)
			(xy 90.246454 -182.650384) (xy 88.66886 -182.650384) (xy 88.65743 -182.653178) (xy 88.652096 -182.655972)
			(xy 88.630646 -182.666349) (xy 88.585313 -182.681026) (xy 88.538252 -182.688496) (xy 88.514428 -182.688992)
			(xy 87.385652 -182.688992) (xy 87.375648 -182.688528) (xy 87.357186 -182.68081) (xy 87.349838 -182.674006)
			(xy 86.948518 -182.272686) (xy 86.941775 -182.265298) (xy 86.934065 -182.246861) (xy 86.933532 -182.236872)
			(xy 86.933532 -181.256178) (xy 86.933166 -181.246132) (xy 86.925576 -181.227535) (xy 86.9188 -181.22011)
			(xy 86.285832 -180.587142) (xy 86.279157 -180.579727) (xy 86.271579 -180.561293) (xy 86.2711 -180.551328)
			(xy 86.2711 -177.200052) (xy 86.270674 -177.189982) (xy 86.262957 -177.171383) (xy 86.256114 -177.163984)
			(xy 86.159086 -177.066956) (xy 86.151601 -177.060268) (xy 86.133045 -177.052674) (xy 86.123018 -177.052224)
			(xy 82.399886 -177.052224) (xy 82.375881 -177.051777) (xy 82.328467 -177.044228) (xy 82.28282 -177.029349)
			(xy 82.240064 -177.007508) (xy 82.201255 -176.979242) (xy 82.183986 -176.962562) (xy 82.183986 -176.962308)
			(xy 81.87436 -176.652682) (xy 81.86697 -176.64583) (xy 81.848363 -176.638118) (xy 81.838292 -176.637696)
			(xy 81.09839 -176.637696) (xy 81.088317 -176.638091) (xy 81.069718 -176.64583) (xy 81.062322 -176.652682)
			(xy 81.02346 -176.691544) (xy 81.016759 -176.69902) (xy 81.009173 -176.717583) (xy 81.008728 -176.727612)
			(xy 81.008728 -178.404012) (xy 81.978246 -178.404012) (xy 81.978732 -178.376761) (xy 81.986488 -178.322813)
			(xy 82.001843 -178.270518) (xy 82.024485 -178.220941) (xy 82.053951 -178.175091) (xy 82.089642 -178.1339)
			(xy 82.130833 -178.098209) (xy 82.176683 -178.068743) (xy 82.22626 -178.046101) (xy 82.278555 -178.030746)
			(xy 82.332503 -178.02299) (xy 82.387005 -178.02299) (xy 82.440953 -178.030746) (xy 82.493248 -178.046101)
			(xy 82.542825 -178.068743) (xy 82.588675 -178.098209) (xy 82.629866 -178.1339) (xy 82.665557 -178.175091)
			(xy 82.695023 -178.220941) (xy 82.717665 -178.270518) (xy 82.73302 -178.322813) (xy 82.740776 -178.376761)
			(xy 82.741262 -178.404012) (xy 82.740596 -178.435575) (xy 82.730212 -178.49784) (xy 82.709729 -178.557549)
			(xy 82.695288 -178.585622) (xy 82.690462 -178.594512) (xy 82.68843 -178.61407) (xy 82.714084 -178.702208)
			(xy 82.72653 -178.717702) (xy 82.73542 -178.722782) (xy 82.742786 -178.726846) (xy 82.752438 -178.732688)
			(xy 82.774536 -178.73472) (xy 82.869024 -178.701192) (xy 82.885026 -178.685698) (xy 82.88909 -178.675284)
			(xy 82.899769 -178.6485) (xy 82.928059 -178.598258) (xy 82.963592 -178.552849) (xy 83.005556 -178.513307)
			(xy 83.052996 -178.480534) (xy 83.104829 -178.455277) (xy 83.159874 -178.438113) (xy 83.216876 -178.429432)
			(xy 83.245706 -178.428904) (xy 83.272958 -178.429366) (xy 83.326907 -178.437124) (xy 83.379202 -178.45248)
			(xy 83.42878 -178.475122) (xy 83.474631 -178.504589) (xy 83.515822 -178.540282) (xy 83.551514 -178.581473)
			(xy 83.580981 -178.627325) (xy 83.603622 -178.676903) (xy 83.618978 -178.729199) (xy 83.626734 -178.783148)
			(xy 83.626734 -178.837652) (xy 83.618978 -178.891601) (xy 83.609628 -178.923442) (xy 83.868514 -178.923442)
			(xy 83.869022 -178.895968) (xy 83.876908 -178.841589) (xy 83.892523 -178.788907) (xy 83.915543 -178.739014)
			(xy 83.94549 -178.692944) (xy 83.963256 -178.671982) (xy 83.969352 -178.66487) (xy 83.975702 -178.647852)
			(xy 83.975702 -178.562) (xy 83.969352 -178.544982) (xy 83.963256 -178.53787) (xy 83.94549 -178.51691)
			(xy 83.915567 -178.470827) (xy 83.892555 -178.420932) (xy 83.87693 -178.368255) (xy 83.869013 -178.313882)
			(xy 83.868514 -178.28641) (xy 83.869 -178.259159) (xy 83.876756 -178.205211) (xy 83.892111 -178.152916)
			(xy 83.914753 -178.103339) (xy 83.944219 -178.057489) (xy 83.97991 -178.016298) (xy 84.021101 -177.980607)
			(xy 84.066951 -177.951141) (xy 84.116528 -177.928499) (xy 84.168823 -177.913144) (xy 84.222771 -177.905388)
			(xy 84.277273 -177.905388) (xy 84.331221 -177.913144) (xy 84.383516 -177.928499) (xy 84.433093 -177.951141)
			(xy 84.478943 -177.980607) (xy 84.520134 -178.016298) (xy 84.555825 -178.057489) (xy 84.585291 -178.103339)
			(xy 84.607933 -178.152916) (xy 84.623288 -178.205211) (xy 84.631044 -178.259159) (xy 84.63153 -178.28641)
			(xy 84.631042 -178.313884) (xy 84.62315 -178.368264) (xy 84.607529 -178.420946) (xy 84.584505 -178.470839)
			(xy 84.554555 -178.516908) (xy 84.536788 -178.53787) (xy 84.530692 -178.544982) (xy 84.524342 -178.562)
			(xy 84.524342 -178.647852) (xy 84.530692 -178.66487) (xy 84.536788 -178.671982) (xy 84.554523 -178.692968)
			(xy 84.584452 -178.739043) (xy 84.607471 -178.788931) (xy 84.623104 -178.841603) (xy 84.631027 -178.895971)
			(xy 84.63153 -178.923442) (xy 84.631044 -178.950693) (xy 84.629411 -178.96205) (xy 85.20633 -178.96205)
			(xy 85.210401 -178.906428) (xy 85.222527 -178.851991) (xy 85.24245 -178.7999) (xy 85.269746 -178.751265)
			(xy 85.303832 -178.707122) (xy 85.343981 -178.668413) (xy 85.389339 -178.635962) (xy 85.438939 -178.610461)
			(xy 85.491723 -178.592454) (xy 85.546566 -178.582324) (xy 85.6023 -178.580287) (xy 85.657737 -178.586387)
			(xy 85.711694 -178.600493) (xy 85.763023 -178.622305) (xy 85.810629 -178.651359) (xy 85.853497 -178.687034)
			(xy 85.890714 -178.728571) (xy 85.921487 -178.775084) (xy 85.945159 -178.825581) (xy 85.961227 -178.878988)
			(xy 85.969347 -178.934164) (xy 85.969856 -178.96205) (xy 85.969347 -178.989936) (xy 85.961227 -179.045112)
			(xy 85.945159 -179.098519) (xy 85.921487 -179.149016) (xy 85.890714 -179.195529) (xy 85.853497 -179.237066)
			(xy 85.810629 -179.272741) (xy 85.763023 -179.301795) (xy 85.711694 -179.323607) (xy 85.657737 -179.337713)
			(xy 85.6023 -179.343813) (xy 85.546566 -179.341776) (xy 85.491723 -179.331646) (xy 85.438939 -179.313639)
			(xy 85.389339 -179.288138) (xy 85.343981 -179.255687) (xy 85.303832 -179.216978) (xy 85.269746 -179.172835)
			(xy 85.24245 -179.1242) (xy 85.222527 -179.072109) (xy 85.210401 -179.017672) (xy 85.20633 -178.96205)
			(xy 84.629411 -178.96205) (xy 84.623288 -179.004641) (xy 84.607933 -179.056936) (xy 84.585291 -179.106513)
			(xy 84.555825 -179.152363) (xy 84.520134 -179.193554) (xy 84.478943 -179.229245) (xy 84.433093 -179.258711)
			(xy 84.383516 -179.281353) (xy 84.331221 -179.296708) (xy 84.277273 -179.304464) (xy 84.222771 -179.304464)
			(xy 84.168823 -179.296708) (xy 84.116528 -179.281353) (xy 84.066951 -179.258711) (xy 84.021101 -179.229245)
			(xy 83.97991 -179.193554) (xy 83.944219 -179.152363) (xy 83.914753 -179.106513) (xy 83.892111 -179.056936)
			(xy 83.876756 -179.004641) (xy 83.869 -178.950693) (xy 83.868514 -178.923442) (xy 83.609628 -178.923442)
			(xy 83.603622 -178.943897) (xy 83.580981 -178.993475) (xy 83.551514 -179.039327) (xy 83.515822 -179.080518)
			(xy 83.474631 -179.116211) (xy 83.42878 -179.145678) (xy 83.379202 -179.16832) (xy 83.326907 -179.183676)
			(xy 83.272958 -179.191434) (xy 83.245706 -179.19192) (xy 83.220471 -179.191518) (xy 83.170437 -179.184901)
			(xy 83.121717 -179.171729) (xy 83.075165 -179.152234) (xy 83.053174 -179.13985) (xy 83.043522 -179.134008)
			(xy 83.021424 -179.131976) (xy 82.926936 -179.165504) (xy 82.910934 -179.180998) (xy 82.90687 -179.191412)
			(xy 82.896139 -179.218173) (xy 82.867855 -179.268413) (xy 82.83233 -179.313822) (xy 82.790373 -179.353365)
			(xy 82.742941 -179.38614) (xy 82.691115 -179.411401) (xy 82.636077 -179.428571) (xy 82.579081 -179.437259)
			(xy 82.550254 -179.437792) (xy 82.523001 -179.437365) (xy 82.46905 -179.429602) (xy 82.416753 -179.41424)
			(xy 82.367175 -179.391592) (xy 82.321324 -179.36212) (xy 82.280134 -179.326422) (xy 82.244443 -179.285226)
			(xy 82.214978 -179.239371) (xy 82.192338 -179.189788) (xy 82.176985 -179.137489) (xy 82.169231 -179.083537)
			(xy 82.168746 -179.056284) (xy 82.169409 -179.024721) (xy 82.179794 -178.962456) (xy 82.200279 -178.902747)
			(xy 82.21472 -178.874674) (xy 82.219546 -178.865784) (xy 82.221578 -178.846226) (xy 82.195924 -178.758088)
			(xy 82.183478 -178.742594) (xy 82.174588 -178.737514) (xy 82.149462 -178.723006) (xy 82.10358 -178.687496)
			(xy 82.063607 -178.645445) (xy 82.030465 -178.597824) (xy 82.004918 -178.545733) (xy 81.987557 -178.490372)
			(xy 81.978782 -178.433021) (xy 81.978246 -178.404012) (xy 81.008728 -178.404012) (xy 81.008728 -179.156868)
			(xy 81.00908 -179.166915) (xy 81.016681 -179.185511) (xy 81.02346 -179.192936) (xy 81.687924 -179.8574)
			(xy 84.62721 -179.8574) (xy 84.631281 -179.801778) (xy 84.643407 -179.747341) (xy 84.66333 -179.69525)
			(xy 84.690626 -179.646615) (xy 84.724712 -179.602472) (xy 84.764861 -179.563763) (xy 84.810219 -179.531312)
			(xy 84.859819 -179.505811) (xy 84.912603 -179.487804) (xy 84.967446 -179.477674) (xy 85.02318 -179.475637)
			(xy 85.078617 -179.481737) (xy 85.132574 -179.495843) (xy 85.183903 -179.517655) (xy 85.231509 -179.546709)
			(xy 85.274377 -179.582384) (xy 85.311594 -179.623921) (xy 85.342367 -179.670434) (xy 85.366039 -179.720931)
			(xy 85.382107 -179.774338) (xy 85.390227 -179.829514) (xy 85.390736 -179.8574) (xy 85.390227 -179.885286)
			(xy 85.382107 -179.940462) (xy 85.366039 -179.993869) (xy 85.342367 -180.044366) (xy 85.311594 -180.090879)
			(xy 85.274377 -180.132416) (xy 85.231509 -180.168091) (xy 85.183903 -180.197145) (xy 85.132574 -180.218957)
			(xy 85.078617 -180.233063) (xy 85.02318 -180.239163) (xy 84.967446 -180.237126) (xy 84.912603 -180.226996)
			(xy 84.859819 -180.208989) (xy 84.810219 -180.183488) (xy 84.764861 -180.151037) (xy 84.724712 -180.112328)
			(xy 84.690626 -180.068185) (xy 84.66333 -180.01955) (xy 84.643407 -179.967459) (xy 84.631281 -179.913022)
			(xy 84.62721 -179.8574) (xy 81.687924 -179.8574) (xy 82.142838 -180.312314) (xy 82.149589 -180.319696)
			(xy 82.157292 -180.338138) (xy 82.157824 -180.348128) (xy 82.157824 -181.73446) (xy 85.586062 -181.73446)
			(xy 85.586538 -181.706549) (xy 85.594677 -181.651322) (xy 85.610777 -181.597872) (xy 85.634494 -181.547337)
			(xy 85.66532 -181.500798) (xy 85.683598 -181.479698) (xy 85.689948 -181.472586) (xy 85.696552 -181.455314)
			(xy 85.696552 -181.368192) (xy 85.689948 -181.35092) (xy 85.683598 -181.343808) (xy 85.665302 -181.322723)
			(xy 85.634477 -181.276181) (xy 85.610765 -181.225642) (xy 85.594673 -181.172188) (xy 85.586544 -181.116958)
			(xy 85.586062 -181.089046) (xy 85.586548 -181.061795) (xy 85.594304 -181.007847) (xy 85.609659 -180.955552)
			(xy 85.632301 -180.905975) (xy 85.661767 -180.860125) (xy 85.697458 -180.818934) (xy 85.738649 -180.783243)
			(xy 85.784499 -180.753777) (xy 85.834076 -180.731135) (xy 85.886371 -180.71578) (xy 85.940319 -180.708024)
			(xy 85.994821 -180.708024) (xy 86.048769 -180.71578) (xy 86.101064 -180.731135) (xy 86.150641 -180.753777)
			(xy 86.196491 -180.783243) (xy 86.237682 -180.818934) (xy 86.273373 -180.860125) (xy 86.302839 -180.905975)
			(xy 86.325481 -180.955552) (xy 86.340836 -181.007847) (xy 86.348592 -181.061795) (xy 86.349078 -181.089046)
			(xy 86.348596 -181.116957) (xy 86.340456 -181.172183) (xy 86.324357 -181.225633) (xy 86.300643 -181.276167)
			(xy 86.269818 -181.322707) (xy 86.251542 -181.343808) (xy 86.245192 -181.35092) (xy 86.238588 -181.368192)
			(xy 86.238588 -181.455314) (xy 86.245192 -181.472586) (xy 86.251542 -181.479698) (xy 86.2698 -181.500814)
			(xy 86.300629 -181.547349) (xy 86.324347 -181.597879) (xy 86.340449 -181.651327) (xy 86.348589 -181.70655)
			(xy 86.349078 -181.73446) (xy 86.348592 -181.761711) (xy 86.340836 -181.815659) (xy 86.325481 -181.867954)
			(xy 86.302839 -181.917531) (xy 86.273373 -181.963381) (xy 86.237682 -182.004572) (xy 86.196491 -182.040263)
			(xy 86.150641 -182.069729) (xy 86.101064 -182.092371) (xy 86.048769 -182.107726) (xy 85.994821 -182.115482)
			(xy 85.940319 -182.115482) (xy 85.886371 -182.107726) (xy 85.834076 -182.092371) (xy 85.784499 -182.069729)
			(xy 85.738649 -182.040263) (xy 85.697458 -182.004572) (xy 85.661767 -181.963381) (xy 85.632301 -181.917531)
			(xy 85.609659 -181.867954) (xy 85.594304 -181.815659) (xy 85.586548 -181.761711) (xy 85.586062 -181.73446)
			(xy 82.157824 -181.73446) (xy 82.157824 -182.413402) (xy 82.157409 -182.437389) (xy 82.149899 -182.484773)
			(xy 82.135066 -182.530397) (xy 82.113273 -182.573137) (xy 82.08506 -182.611938) (xy 82.051121 -182.645846)
			(xy 82.012292 -182.674023) (xy 81.969532 -182.695775) (xy 81.923894 -182.710566) (xy 81.876504 -182.718031)
			(xy 81.852516 -182.718456) (xy 80.287622 -182.718456) (xy 80.280728 -182.718668) (xy 80.267456 -182.722411)
			(xy 80.26146 -182.725822) (xy 80.237568 -182.739449) (xy 80.186094 -182.758816) (xy 80.131986 -182.768666)
			(xy 80.104488 -182.769256) (xy 78.349094 -182.769256) (xy 78.344216 -182.769165) (xy 78.334628 -182.76737)
			(xy 78.330044 -182.7657) (xy 78.234286 -182.726838) (xy 78.229455 -182.724758) (xy 78.220749 -182.718858)
			(xy 78.217014 -182.715154) (xy 78.181708 -182.678578) (xy 78.180946 -182.67807) (xy 78.107032 -182.604156)
			(xy 78.090425 -182.586837) (xy 78.062235 -182.548013) (xy 78.040457 -182.505261) (xy 78.025625 -182.459632)
			(xy 78.018105 -182.412245) (xy 78.017624 -182.388256) (xy 78.017624 -177.314352) (xy 78.018121 -177.304387)
			(xy 78.025682 -177.285952) (xy 78.032356 -177.278538) (xy 78.46822 -176.842674) (xy 78.47491 -176.83519)
			(xy 78.482503 -176.816633) (xy 78.482952 -176.806606) (xy 78.482952 -175.567594) (xy 78.482573 -175.557549)
			(xy 78.474991 -175.538953) (xy 78.46822 -175.531526) (xy 78.032356 -175.095662) (xy 78.025693 -175.088238)
			(xy 78.018107 -175.069811) (xy 78.017624 -175.059848) (xy 78.017624 -172.439584) (xy 78.017227 -172.429511)
			(xy 78.009488 -172.410913) (xy 78.002638 -172.403516) (xy 77.517752 -171.91863) (xy 77.510324 -171.911825)
			(xy 77.491746 -171.904084) (xy 77.481684 -171.903644) (xy 74.4093 -171.903644) (xy 74.385304 -171.903187)
			(xy 74.337896 -171.895721) (xy 74.292247 -171.880912) (xy 74.249486 -171.859125) (xy 74.210672 -171.8309)
			(xy 74.1934 -171.814236) (xy 74.1934 -171.813982) (xy 73.371456 -170.992038) (xy 73.364061 -170.985192)
			(xy 73.345458 -170.977474) (xy 73.335388 -170.977052) (xy 73.015094 -170.977052) (xy 73.005023 -170.97746)
			(xy 72.986424 -170.985191) (xy 72.979026 -170.992038) (xy 72.97674 -170.994324) (xy 72.970045 -171.001804)
			(xy 72.962456 -171.020364) (xy 72.962008 -171.030392) (xy 72.962008 -173.285912) (xy 73.654666 -173.285912)
			(xy 73.655152 -173.258661) (xy 73.662908 -173.204713) (xy 73.678263 -173.152418) (xy 73.700905 -173.102841)
			(xy 73.730371 -173.056991) (xy 73.766062 -173.0158) (xy 73.807253 -172.980109) (xy 73.853103 -172.950643)
			(xy 73.90268 -172.928001) (xy 73.954975 -172.912646) (xy 74.008923 -172.90489) (xy 74.063425 -172.90489)
			(xy 74.117373 -172.912646) (xy 74.169668 -172.928001) (xy 74.219245 -172.950643) (xy 74.265095 -172.980109)
			(xy 74.306286 -173.0158) (xy 74.341977 -173.056991) (xy 74.371443 -173.102841) (xy 74.394085 -173.152418)
			(xy 74.40944 -173.204713) (xy 74.417196 -173.258661) (xy 74.417682 -173.285912) (xy 74.417014 -173.317474)
			(xy 74.40663 -173.379739) (xy 74.386148 -173.439449) (xy 74.371708 -173.467522) (xy 74.366882 -173.476412)
			(xy 74.36485 -173.49597) (xy 74.390504 -173.584108) (xy 74.40295 -173.599602) (xy 74.41184 -173.604682)
			(xy 74.419206 -173.608746) (xy 74.428858 -173.614588) (xy 74.450956 -173.61662) (xy 74.545444 -173.583092)
			(xy 74.561446 -173.567598) (xy 74.56551 -173.557184) (xy 74.576173 -173.530393) (xy 74.604465 -173.480151)
			(xy 74.639999 -173.43474) (xy 74.681966 -173.395199) (xy 74.729408 -173.362426) (xy 74.781244 -173.337171)
			(xy 74.836291 -173.320009) (xy 74.893296 -173.311331) (xy 74.922126 -173.310804) (xy 74.949377 -173.311268)
			(xy 75.003324 -173.319027) (xy 75.055617 -173.334385) (xy 75.105192 -173.357029) (xy 75.151041 -173.386496)
			(xy 75.192229 -173.422189) (xy 75.227919 -173.46338) (xy 75.257384 -173.509231) (xy 75.280024 -173.558808)
			(xy 75.295378 -173.611102) (xy 75.303134 -173.665049) (xy 75.303134 -173.719551) (xy 75.295378 -173.773498)
			(xy 75.286028 -173.805342) (xy 75.544934 -173.805342) (xy 75.545437 -173.777868) (xy 75.553323 -173.723489)
			(xy 75.568939 -173.670806) (xy 75.59196 -173.620913) (xy 75.621909 -173.574844) (xy 75.639676 -173.553882)
			(xy 75.645772 -173.54677) (xy 75.652122 -173.529752) (xy 75.652122 -173.4439) (xy 75.645772 -173.426882)
			(xy 75.639676 -173.41977) (xy 75.621913 -173.398807) (xy 75.591989 -173.352725) (xy 75.568976 -173.302831)
			(xy 75.55335 -173.250154) (xy 75.545433 -173.195782) (xy 75.544934 -173.16831) (xy 75.54542 -173.141059)
			(xy 75.553176 -173.087111) (xy 75.568531 -173.034816) (xy 75.591173 -172.985239) (xy 75.620639 -172.939389)
			(xy 75.65633 -172.898198) (xy 75.697521 -172.862507) (xy 75.743371 -172.833041) (xy 75.792948 -172.810399)
			(xy 75.845243 -172.795044) (xy 75.899191 -172.787288) (xy 75.953693 -172.787288) (xy 76.007641 -172.795044)
			(xy 76.059936 -172.810399) (xy 76.109513 -172.833041) (xy 76.155363 -172.862507) (xy 76.196554 -172.898198)
			(xy 76.232245 -172.939389) (xy 76.261711 -172.985239) (xy 76.284353 -173.034816) (xy 76.299708 -173.087111)
			(xy 76.307464 -173.141059) (xy 76.30795 -173.16831) (xy 76.307482 -173.195785) (xy 76.299587 -173.250166)
			(xy 76.283964 -173.302849) (xy 76.260935 -173.352742) (xy 76.230978 -173.398809) (xy 76.213208 -173.41977)
			(xy 76.207112 -173.426882) (xy 76.200762 -173.4439) (xy 76.200762 -173.529752) (xy 76.207112 -173.54677)
			(xy 76.213208 -173.553882) (xy 76.230946 -173.574865) (xy 76.260874 -173.620941) (xy 76.283892 -173.67083)
			(xy 76.299524 -173.723502) (xy 76.307447 -173.777871) (xy 76.30795 -173.805342) (xy 76.307464 -173.832593)
			(xy 76.305831 -173.84395) (xy 76.88275 -173.84395) (xy 76.886821 -173.788328) (xy 76.898947 -173.733891)
			(xy 76.91887 -173.6818) (xy 76.946166 -173.633165) (xy 76.980252 -173.589022) (xy 77.020401 -173.550313)
			(xy 77.065759 -173.517862) (xy 77.115359 -173.492361) (xy 77.168143 -173.474354) (xy 77.222986 -173.464224)
			(xy 77.27872 -173.462187) (xy 77.334157 -173.468287) (xy 77.388114 -173.482393) (xy 77.439443 -173.504205)
			(xy 77.487049 -173.533259) (xy 77.529917 -173.568934) (xy 77.567134 -173.610471) (xy 77.597907 -173.656984)
			(xy 77.621579 -173.707481) (xy 77.637647 -173.760888) (xy 77.645767 -173.816064) (xy 77.646276 -173.84395)
			(xy 77.645767 -173.871836) (xy 77.637647 -173.927012) (xy 77.621579 -173.980419) (xy 77.597907 -174.030916)
			(xy 77.567134 -174.077429) (xy 77.529917 -174.118966) (xy 77.487049 -174.154641) (xy 77.439443 -174.183695)
			(xy 77.388114 -174.205507) (xy 77.334157 -174.219613) (xy 77.27872 -174.225713) (xy 77.222986 -174.223676)
			(xy 77.168143 -174.213546) (xy 77.115359 -174.195539) (xy 77.065759 -174.170038) (xy 77.020401 -174.137587)
			(xy 76.980252 -174.098878) (xy 76.946166 -174.054735) (xy 76.91887 -174.0061) (xy 76.898947 -173.954009)
			(xy 76.886821 -173.899572) (xy 76.88275 -173.84395) (xy 76.305831 -173.84395) (xy 76.299708 -173.886541)
			(xy 76.284353 -173.938836) (xy 76.261711 -173.988413) (xy 76.232245 -174.034263) (xy 76.196554 -174.075454)
			(xy 76.155363 -174.111145) (xy 76.109513 -174.140611) (xy 76.059936 -174.163253) (xy 76.007641 -174.178608)
			(xy 75.953693 -174.186364) (xy 75.899191 -174.186364) (xy 75.845243 -174.178608) (xy 75.792948 -174.163253)
			(xy 75.743371 -174.140611) (xy 75.697521 -174.111145) (xy 75.65633 -174.075454) (xy 75.620639 -174.034263)
			(xy 75.591173 -173.988413) (xy 75.568531 -173.938836) (xy 75.553176 -173.886541) (xy 75.54542 -173.832593)
			(xy 75.544934 -173.805342) (xy 75.286028 -173.805342) (xy 75.280024 -173.825792) (xy 75.257384 -173.875369)
			(xy 75.227919 -173.92122) (xy 75.192229 -173.962411) (xy 75.151041 -173.998104) (xy 75.105192 -174.027571)
			(xy 75.055617 -174.050215) (xy 75.003324 -174.065573) (xy 74.949377 -174.073332) (xy 74.922126 -174.07382)
			(xy 74.89689 -174.073453) (xy 74.846855 -174.066825) (xy 74.798134 -174.053644) (xy 74.751584 -174.034139)
			(xy 74.729594 -174.02175) (xy 74.719942 -174.015908) (xy 74.697844 -174.013876) (xy 74.603356 -174.047404)
			(xy 74.587354 -174.062898) (xy 74.58329 -174.073312) (xy 74.572625 -174.100102) (xy 74.544334 -174.150345)
			(xy 74.5088 -174.195755) (xy 74.466833 -174.235297) (xy 74.419391 -174.268069) (xy 74.367556 -174.293325)
			(xy 74.312508 -174.310487) (xy 74.255504 -174.319165) (xy 74.226674 -174.319692) (xy 74.199421 -174.319246)
			(xy 74.145471 -174.311486) (xy 74.093175 -174.296127) (xy 74.043597 -174.273481) (xy 73.997745 -174.244011)
			(xy 73.956555 -174.208315) (xy 73.920864 -174.167121) (xy 73.891399 -174.121267) (xy 73.868759 -174.071686)
			(xy 73.853405 -174.019388) (xy 73.845651 -173.965437) (xy 73.845166 -173.938184) (xy 73.845839 -173.906622)
			(xy 73.856221 -173.844357) (xy 73.876701 -173.784648) (xy 73.89114 -173.756574) (xy 73.895966 -173.747684)
			(xy 73.897998 -173.728126) (xy 73.872344 -173.639988) (xy 73.859898 -173.624494) (xy 73.851008 -173.619414)
			(xy 73.825887 -173.604898) (xy 73.780004 -173.56939) (xy 73.74003 -173.527341) (xy 73.706886 -173.479721)
			(xy 73.681339 -173.427631) (xy 73.663977 -173.372272) (xy 73.655202 -173.314921) (xy 73.654666 -173.285912)
			(xy 72.962008 -173.285912) (xy 72.962008 -174.358808) (xy 72.962397 -174.368851) (xy 72.969972 -174.387447)
			(xy 72.97674 -174.394876) (xy 73.321164 -174.7393) (xy 76.30363 -174.7393) (xy 76.307701 -174.683678)
			(xy 76.319827 -174.629241) (xy 76.33975 -174.57715) (xy 76.367046 -174.528515) (xy 76.401132 -174.484372)
			(xy 76.441281 -174.445663) (xy 76.486639 -174.413212) (xy 76.536239 -174.387711) (xy 76.589023 -174.369704)
			(xy 76.643866 -174.359574) (xy 76.6996 -174.357537) (xy 76.755037 -174.363637) (xy 76.808994 -174.377743)
			(xy 76.860323 -174.399555) (xy 76.907929 -174.428609) (xy 76.950797 -174.464284) (xy 76.988014 -174.505821)
			(xy 77.018787 -174.552334) (xy 77.042459 -174.602831) (xy 77.058527 -174.656238) (xy 77.066647 -174.711414)
			(xy 77.067156 -174.7393) (xy 77.066647 -174.767186) (xy 77.058527 -174.822362) (xy 77.042459 -174.875769)
			(xy 77.018787 -174.926266) (xy 76.988014 -174.972779) (xy 76.950797 -175.014316) (xy 76.907929 -175.049991)
			(xy 76.860323 -175.079045) (xy 76.808994 -175.100857) (xy 76.755037 -175.114963) (xy 76.6996 -175.121063)
			(xy 76.643866 -175.119026) (xy 76.589023 -175.108896) (xy 76.536239 -175.090889) (xy 76.486639 -175.065388)
			(xy 76.441281 -175.032937) (xy 76.401132 -174.994228) (xy 76.367046 -174.950085) (xy 76.33975 -174.90145)
			(xy 76.319827 -174.849359) (xy 76.307701 -174.794922) (xy 76.30363 -174.7393) (xy 73.321164 -174.7393)
			(xy 73.819258 -175.237394) (xy 73.825989 -175.244792) (xy 73.833706 -175.263221) (xy 73.834244 -175.273208)
			(xy 73.834244 -176.61636) (xy 77.262482 -176.61636) (xy 77.262953 -176.588448) (xy 77.271093 -176.533222)
			(xy 77.287194 -176.479771) (xy 77.310911 -176.429236) (xy 77.341739 -176.382697) (xy 77.360018 -176.361598)
			(xy 77.366368 -176.354486) (xy 77.372972 -176.337214) (xy 77.372972 -176.250092) (xy 77.366368 -176.23282)
			(xy 77.360018 -176.225708) (xy 77.341725 -176.204621) (xy 77.310899 -176.158079) (xy 77.287187 -176.107542)
			(xy 77.271094 -176.054087) (xy 77.262964 -175.998858) (xy 77.262482 -175.970946) (xy 77.262968 -175.943695)
			(xy 77.270724 -175.889747) (xy 77.286079 -175.837452) (xy 77.308721 -175.787875) (xy 77.338187 -175.742025)
			(xy 77.373878 -175.700834) (xy 77.415069 -175.665143) (xy 77.460919 -175.635677) (xy 77.510496 -175.613035)
			(xy 77.562791 -175.59768) (xy 77.616739 -175.589924) (xy 77.671241 -175.589924) (xy 77.725189 -175.59768)
			(xy 77.777484 -175.613035) (xy 77.827061 -175.635677) (xy 77.872911 -175.665143) (xy 77.914102 -175.700834)
			(xy 77.949793 -175.742025) (xy 77.979259 -175.787875) (xy 78.001901 -175.837452) (xy 78.017256 -175.889747)
			(xy 78.025012 -175.943695) (xy 78.025498 -175.970946) (xy 78.025011 -175.998857) (xy 78.016871 -176.054082)
			(xy 78.000773 -176.107532) (xy 77.97706 -176.158066) (xy 77.946238 -176.204607) (xy 77.927962 -176.225708)
			(xy 77.921612 -176.23282) (xy 77.915008 -176.250092) (xy 77.915008 -176.337214) (xy 77.921612 -176.354486)
			(xy 77.927962 -176.361598) (xy 77.946223 -176.382711) (xy 77.977051 -176.429247) (xy 78.000768 -176.479778)
			(xy 78.016869 -176.533226) (xy 78.025009 -176.58845) (xy 78.025498 -176.61636) (xy 78.025012 -176.643611)
			(xy 78.017256 -176.697559) (xy 78.001901 -176.749854) (xy 77.979259 -176.799431) (xy 77.949793 -176.845281)
			(xy 77.914102 -176.886472) (xy 77.872911 -176.922163) (xy 77.827061 -176.951629) (xy 77.777484 -176.974271)
			(xy 77.725189 -176.989626) (xy 77.671241 -176.997382) (xy 77.616739 -176.997382) (xy 77.562791 -176.989626)
			(xy 77.510496 -176.974271) (xy 77.460919 -176.951629) (xy 77.415069 -176.922163) (xy 77.373878 -176.886472)
			(xy 77.338187 -176.845281) (xy 77.308721 -176.799431) (xy 77.286079 -176.749854) (xy 77.270724 -176.697559)
			(xy 77.262968 -176.643611) (xy 77.262482 -176.61636) (xy 73.834244 -176.61636) (xy 73.834244 -177.295302)
			(xy 73.833809 -177.319288) (xy 73.8263 -177.36667) (xy 73.811467 -177.412292) (xy 73.789677 -177.455031)
			(xy 73.761466 -177.493832) (xy 73.727529 -177.527739) (xy 73.688703 -177.555916) (xy 73.645946 -177.577669)
			(xy 73.600311 -177.592462) (xy 73.552923 -177.59993) (xy 73.528936 -177.600356) (xy 71.937626 -177.600356)
			(xy 71.927466 -177.605182) (xy 71.907116 -177.614363) (xy 71.864399 -177.627339) (xy 71.820247 -177.63395)
			(xy 71.797926 -177.634392) (xy 70.013576 -177.634392) (xy 70.008686 -177.634247) (xy 69.999093 -177.632334)
			(xy 69.994526 -177.630582) (xy 69.898768 -177.59172) (xy 69.893944 -177.589625) (xy 69.885234 -177.583735)
			(xy 69.881496 -177.580036) (xy 69.84619 -177.54346) (xy 69.845428 -177.542952) (xy 69.725032 -177.422556)
			(xy 69.708425 -177.405237) (xy 69.680235 -177.366413) (xy 69.658457 -177.323661) (xy 69.643625 -177.278032)
			(xy 69.636105 -177.230645) (xy 69.635624 -177.206656) (xy 69.635624 -168.856914) (xy 69.636102 -168.846947)
			(xy 69.643677 -168.828512) (xy 69.650356 -168.8211) (xy 70.09638 -168.375076) (xy 70.103077 -168.367598)
			(xy 70.110664 -168.349036) (xy 70.111112 -168.339008) (xy 70.111112 -166.852092) (xy 70.110744 -166.842046)
			(xy 70.103156 -166.823449) (xy 70.09638 -166.816024) (xy 69.650356 -166.37) (xy 69.64371 -166.362563)
			(xy 69.636114 -166.344146) (xy 69.635624 -166.334186) (xy 69.635624 -163.732464) (xy 69.635172 -163.722458)
			(xy 69.627448 -163.703995) (xy 69.620638 -163.69665) (xy 69.302122 -163.37788) (xy 69.294656 -163.371167)
			(xy 69.276085 -163.363587) (xy 69.266054 -163.363148) (xy 65.92951 -163.363148) (xy 65.905504 -163.362708)
			(xy 65.858089 -163.35516) (xy 65.812441 -163.340281) (xy 65.769685 -163.318438) (xy 65.730878 -163.290168)
			(xy 65.71361 -163.273486) (xy 65.4304 -162.990276) (xy 65.422961 -162.983633) (xy 65.404546 -162.976035)
			(xy 65.394586 -162.975544) (xy 64.552576 -162.975544) (xy 64.542531 -162.975915) (xy 64.523934 -162.983502)
			(xy 64.516508 -162.990276) (xy 64.51092 -162.995864) (xy 64.504205 -163.003328) (xy 64.496629 -163.021901)
			(xy 64.496188 -163.031932) (xy 64.496188 -164.588698) (xy 65.341246 -164.588698) (xy 65.341732 -164.561447)
			(xy 65.349488 -164.507499) (xy 65.364843 -164.455204) (xy 65.387485 -164.405627) (xy 65.416951 -164.359777)
			(xy 65.452642 -164.318586) (xy 65.493833 -164.282895) (xy 65.539683 -164.253429) (xy 65.58926 -164.230787)
			(xy 65.641555 -164.215432) (xy 65.695503 -164.207676) (xy 65.750005 -164.207676) (xy 65.803953 -164.215432)
			(xy 65.856248 -164.230787) (xy 65.905825 -164.253429) (xy 65.951675 -164.282895) (xy 65.992866 -164.318586)
			(xy 66.028557 -164.359777) (xy 66.058023 -164.405627) (xy 66.080665 -164.455204) (xy 66.09602 -164.507499)
			(xy 66.103776 -164.561447) (xy 66.104262 -164.588698) (xy 66.10363 -164.620262) (xy 66.093232 -164.682528)
			(xy 66.072735 -164.742237) (xy 66.058288 -164.770308) (xy 66.053462 -164.779198) (xy 66.05143 -164.798756)
			(xy 66.077084 -164.886894) (xy 66.08953 -164.902388) (xy 66.09842 -164.907468) (xy 66.105786 -164.911532)
			(xy 66.115438 -164.917374) (xy 66.137536 -164.919406) (xy 66.232024 -164.885878) (xy 66.248026 -164.870384)
			(xy 66.25209 -164.85997) (xy 66.262762 -164.833183) (xy 66.291054 -164.782942) (xy 66.326587 -164.737533)
			(xy 66.368553 -164.697991) (xy 66.415994 -164.665219) (xy 66.467828 -164.639963) (xy 66.522874 -164.622799)
			(xy 66.579876 -164.614118) (xy 66.608706 -164.61359) (xy 66.635957 -164.61408) (xy 66.689904 -164.621837)
			(xy 66.742197 -164.637193) (xy 66.791774 -164.659834) (xy 66.837623 -164.689301) (xy 66.878812 -164.724992)
			(xy 66.914503 -164.766182) (xy 66.943969 -164.812032) (xy 66.966609 -164.861608) (xy 66.981964 -164.913902)
			(xy 66.98972 -164.967849) (xy 66.98972 -165.022351) (xy 66.981964 -165.076298) (xy 66.972618 -165.108128)
			(xy 67.231514 -165.108128) (xy 67.232013 -165.080654) (xy 67.239902 -165.026275) (xy 67.255519 -164.973592)
			(xy 67.27854 -164.923699) (xy 67.30849 -164.87763) (xy 67.326256 -164.856668) (xy 67.332352 -164.849556)
			(xy 67.338702 -164.832538) (xy 67.338702 -164.746686) (xy 67.332352 -164.729668) (xy 67.326256 -164.722556)
			(xy 67.308484 -164.701601) (xy 67.278561 -164.655517) (xy 67.255551 -164.60562) (xy 67.239927 -164.552942)
			(xy 67.232012 -164.498569) (xy 67.231514 -164.471096) (xy 67.232 -164.443845) (xy 67.239756 -164.389897)
			(xy 67.255111 -164.337602) (xy 67.277753 -164.288025) (xy 67.307219 -164.242175) (xy 67.34291 -164.200984)
			(xy 67.384101 -164.165293) (xy 67.429951 -164.135827) (xy 67.479528 -164.113185) (xy 67.531823 -164.09783)
			(xy 67.585771 -164.090074) (xy 67.640273 -164.090074) (xy 67.694221 -164.09783) (xy 67.746516 -164.113185)
			(xy 67.796093 -164.135827) (xy 67.841943 -164.165293) (xy 67.883134 -164.200984) (xy 67.918825 -164.242175)
			(xy 67.948291 -164.288025) (xy 67.970933 -164.337602) (xy 67.986288 -164.389897) (xy 67.994044 -164.443845)
			(xy 67.99453 -164.471096) (xy 67.994034 -164.49857) (xy 67.986143 -164.552949) (xy 67.970525 -164.605631)
			(xy 67.947503 -164.655524) (xy 67.917554 -164.701593) (xy 67.899788 -164.722556) (xy 67.893692 -164.729668)
			(xy 67.887342 -164.746686) (xy 67.887342 -164.832538) (xy 67.893692 -164.849556) (xy 67.899788 -164.856668)
			(xy 67.917516 -164.877659) (xy 67.947447 -164.923733) (xy 67.970467 -164.97362) (xy 67.986101 -165.02629)
			(xy 67.994026 -165.080658) (xy 67.99453 -165.108128) (xy 67.994044 -165.135379) (xy 67.992411 -165.146736)
			(xy 68.56933 -165.146736) (xy 68.573401 -165.091114) (xy 68.585527 -165.036677) (xy 68.60545 -164.984586)
			(xy 68.632746 -164.935951) (xy 68.666832 -164.891808) (xy 68.706981 -164.853099) (xy 68.752339 -164.820648)
			(xy 68.801939 -164.795147) (xy 68.854723 -164.77714) (xy 68.909566 -164.76701) (xy 68.9653 -164.764973)
			(xy 69.020737 -164.771073) (xy 69.074694 -164.785179) (xy 69.126023 -164.806991) (xy 69.173629 -164.836045)
			(xy 69.216497 -164.87172) (xy 69.253714 -164.913257) (xy 69.284487 -164.95977) (xy 69.308159 -165.010267)
			(xy 69.324227 -165.063674) (xy 69.332347 -165.11885) (xy 69.332856 -165.146736) (xy 69.332347 -165.174622)
			(xy 69.324227 -165.229798) (xy 69.308159 -165.283205) (xy 69.284487 -165.333702) (xy 69.253714 -165.380215)
			(xy 69.216497 -165.421752) (xy 69.173629 -165.457427) (xy 69.126023 -165.486481) (xy 69.074694 -165.508293)
			(xy 69.020737 -165.522399) (xy 68.9653 -165.528499) (xy 68.909566 -165.526462) (xy 68.854723 -165.516332)
			(xy 68.801939 -165.498325) (xy 68.752339 -165.472824) (xy 68.706981 -165.440373) (xy 68.666832 -165.401664)
			(xy 68.632746 -165.357521) (xy 68.60545 -165.308886) (xy 68.585527 -165.256795) (xy 68.573401 -165.202358)
			(xy 68.56933 -165.146736) (xy 67.992411 -165.146736) (xy 67.986288 -165.189327) (xy 67.970933 -165.241622)
			(xy 67.948291 -165.291199) (xy 67.918825 -165.337049) (xy 67.883134 -165.37824) (xy 67.841943 -165.413931)
			(xy 67.796093 -165.443397) (xy 67.746516 -165.466039) (xy 67.694221 -165.481394) (xy 67.640273 -165.48915)
			(xy 67.585771 -165.48915) (xy 67.531823 -165.481394) (xy 67.479528 -165.466039) (xy 67.429951 -165.443397)
			(xy 67.384101 -165.413931) (xy 67.34291 -165.37824) (xy 67.307219 -165.337049) (xy 67.277753 -165.291199)
			(xy 67.255111 -165.241622) (xy 67.239756 -165.189327) (xy 67.232 -165.135379) (xy 67.231514 -165.108128)
			(xy 66.972618 -165.108128) (xy 66.966609 -165.128592) (xy 66.943969 -165.178168) (xy 66.914503 -165.224018)
			(xy 66.878812 -165.265208) (xy 66.837623 -165.300899) (xy 66.791774 -165.330366) (xy 66.742197 -165.353007)
			(xy 66.689904 -165.368363) (xy 66.635957 -165.37612) (xy 66.608706 -165.376606) (xy 66.583471 -165.376206)
			(xy 66.533437 -165.369588) (xy 66.484717 -165.356416) (xy 66.438165 -165.33692) (xy 66.416174 -165.324536)
			(xy 66.406522 -165.318694) (xy 66.384424 -165.316662) (xy 66.289936 -165.35019) (xy 66.273934 -165.365684)
			(xy 66.26987 -165.376098) (xy 66.259131 -165.402856) (xy 66.230849 -165.453096) (xy 66.195325 -165.498506)
			(xy 66.15337 -165.538049) (xy 66.105939 -165.570825) (xy 66.054114 -165.596086) (xy 65.999076 -165.613257)
			(xy 65.942081 -165.621945) (xy 65.913254 -165.622478) (xy 65.886 -165.622065) (xy 65.832048 -165.614301)
			(xy 65.77975 -165.598939) (xy 65.730171 -165.57629) (xy 65.684319 -165.546816) (xy 65.643129 -165.511117)
			(xy 65.607438 -165.46992) (xy 65.577973 -165.424062) (xy 65.555335 -165.374478) (xy 65.539982 -165.322177)
			(xy 65.53223 -165.268224) (xy 65.531746 -165.24097) (xy 65.532404 -165.209407) (xy 65.542791 -165.147142)
			(xy 65.563278 -165.087432) (xy 65.57772 -165.05936) (xy 65.582546 -165.05047) (xy 65.584578 -165.030912)
			(xy 65.558924 -164.942774) (xy 65.546478 -164.92728) (xy 65.537588 -164.9222) (xy 65.5125 -164.907631)
			(xy 65.466618 -164.87213) (xy 65.426643 -164.830089) (xy 65.393497 -164.782479) (xy 65.367944 -164.730398)
			(xy 65.350574 -164.675047) (xy 65.341788 -164.617704) (xy 65.341246 -164.588698) (xy 64.496188 -164.588698)
			(xy 64.496188 -165.499288) (xy 64.496514 -165.509338) (xy 64.504131 -165.527935) (xy 64.51092 -165.535356)
			(xy 65.01765 -166.042086) (xy 67.99021 -166.042086) (xy 67.994281 -165.986464) (xy 68.006407 -165.932027)
			(xy 68.02633 -165.879936) (xy 68.053626 -165.831301) (xy 68.087712 -165.787158) (xy 68.127861 -165.748449)
			(xy 68.173219 -165.715998) (xy 68.222819 -165.690497) (xy 68.275603 -165.67249) (xy 68.330446 -165.66236)
			(xy 68.38618 -165.660323) (xy 68.441617 -165.666423) (xy 68.495574 -165.680529) (xy 68.546903 -165.702341)
			(xy 68.594509 -165.731395) (xy 68.637377 -165.76707) (xy 68.674594 -165.808607) (xy 68.705367 -165.85512)
			(xy 68.729039 -165.905617) (xy 68.745107 -165.959024) (xy 68.753227 -166.0142) (xy 68.753736 -166.042086)
			(xy 68.753227 -166.069972) (xy 68.745107 -166.125148) (xy 68.729039 -166.178555) (xy 68.705367 -166.229052)
			(xy 68.674594 -166.275565) (xy 68.637377 -166.317102) (xy 68.594509 -166.352777) (xy 68.546903 -166.381831)
			(xy 68.495574 -166.403643) (xy 68.441617 -166.417749) (xy 68.38618 -166.423849) (xy 68.330446 -166.421812)
			(xy 68.275603 -166.411682) (xy 68.222819 -166.393675) (xy 68.173219 -166.368174) (xy 68.127861 -166.335723)
			(xy 68.087712 -166.297014) (xy 68.053626 -166.252871) (xy 68.02633 -166.204236) (xy 68.006407 -166.152145)
			(xy 67.994281 -166.097708) (xy 67.99021 -166.042086) (xy 65.01765 -166.042086) (xy 65.505838 -166.530274)
			(xy 65.512571 -166.53767) (xy 65.520285 -166.556101) (xy 65.520824 -166.566088) (xy 65.520824 -167.919146)
			(xy 68.949062 -167.919146) (xy 68.949529 -167.891234) (xy 68.957671 -167.836008) (xy 68.973773 -167.782557)
			(xy 68.997491 -167.732023) (xy 69.028319 -167.685484) (xy 69.046598 -167.664384) (xy 69.052948 -167.657272)
			(xy 69.059552 -167.64) (xy 69.059552 -167.552878) (xy 69.052948 -167.535606) (xy 69.046598 -167.528494)
			(xy 69.028343 -167.507376) (xy 68.997512 -167.460842) (xy 68.973792 -167.410313) (xy 68.957691 -167.356865)
			(xy 68.94955 -167.301642) (xy 68.949062 -167.273732) (xy 68.949548 -167.246481) (xy 68.957304 -167.192533)
			(xy 68.972659 -167.140238) (xy 68.995301 -167.090661) (xy 69.024767 -167.044811) (xy 69.060458 -167.00362)
			(xy 69.101649 -166.967929) (xy 69.147499 -166.938463) (xy 69.197076 -166.915821) (xy 69.249371 -166.900466)
			(xy 69.303319 -166.89271) (xy 69.357821 -166.89271) (xy 69.411769 -166.900466) (xy 69.464064 -166.915821)
			(xy 69.513641 -166.938463) (xy 69.559491 -166.967929) (xy 69.600682 -167.00362) (xy 69.636373 -167.044811)
			(xy 69.665839 -167.090661) (xy 69.688481 -167.140238) (xy 69.703836 -167.192533) (xy 69.711592 -167.246481)
			(xy 69.712078 -167.273732) (xy 69.711587 -167.301643) (xy 69.70345 -167.356868) (xy 69.687353 -167.410318)
			(xy 69.66364 -167.460853) (xy 69.632818 -167.507393) (xy 69.614542 -167.528494) (xy 69.608192 -167.535606)
			(xy 69.601588 -167.552878) (xy 69.601588 -167.64) (xy 69.608192 -167.657272) (xy 69.614542 -167.664384)
			(xy 69.63284 -167.685466) (xy 69.663664 -167.73201) (xy 69.687374 -167.782549) (xy 69.703466 -167.836004)
			(xy 69.711595 -167.891234) (xy 69.712078 -167.919146) (xy 69.711592 -167.946397) (xy 69.703836 -168.000345)
			(xy 69.688481 -168.05264) (xy 69.665839 -168.102217) (xy 69.636373 -168.148067) (xy 69.600682 -168.189258)
			(xy 69.559491 -168.224949) (xy 69.513641 -168.254415) (xy 69.464064 -168.277057) (xy 69.411769 -168.292412)
			(xy 69.357821 -168.300168) (xy 69.303319 -168.300168) (xy 69.249371 -168.292412) (xy 69.197076 -168.277057)
			(xy 69.147499 -168.254415) (xy 69.101649 -168.224949) (xy 69.060458 -168.189258) (xy 69.024767 -168.148067)
			(xy 68.995301 -168.102217) (xy 68.972659 -168.05264) (xy 68.957304 -168.000345) (xy 68.949548 -167.946397)
			(xy 68.949062 -167.919146) (xy 65.520824 -167.919146) (xy 65.520824 -168.596818) (xy 65.52038 -168.620823)
			(xy 65.51283 -168.668237) (xy 65.49795 -168.713885) (xy 65.476108 -168.75664) (xy 65.447842 -168.795449)
			(xy 65.431162 -168.812718) (xy 65.430146 -168.813734) (xy 65.412881 -168.830415) (xy 65.374063 -168.858662)
			(xy 65.331305 -168.880489) (xy 65.285659 -168.895359) (xy 65.238249 -168.902906) (xy 65.214246 -168.903396)
			(xy 63.639192 -168.903396) (xy 63.626746 -168.906444) (xy 63.621158 -168.909492) (xy 63.598501 -168.921435)
			(xy 63.550178 -168.938397) (xy 63.499698 -168.947032) (xy 63.474092 -168.947592) (xy 60.578492 -168.947592)
			(xy 60.56849 -168.947107) (xy 60.550028 -168.939404) (xy 60.542678 -168.932606) (xy 60.110878 -168.500806)
			(xy 60.104138 -168.493415) (xy 60.096428 -168.47498) (xy 60.095892 -168.464992) (xy 50.480722 -168.464992)
			(xy 50.480722 -178.18608) (xy 50.481194 -178.195952) (xy 50.488655 -178.214232) (xy 50.4952 -178.22164)
			(xy 50.495454 -178.221894) (xy 51.778154 -179.504594) (xy 51.778662 -179.505102) (xy 51.786041 -179.511688)
			(xy 51.804341 -179.519143) (xy 51.814222 -179.51958) (xy 67.92087 -179.51958) (xy 67.930935 -179.520015)
			(xy 67.949523 -179.527745) (xy 67.956938 -179.534566) (xy 76.804012 -188.38164) (xy 113.076736 -188.38164)
			(xy 113.077217 -188.35427) (xy 113.08503 -188.300091) (xy 113.100515 -188.247588) (xy 113.123354 -188.197841)
			(xy 113.153076 -188.151874) (xy 113.170716 -188.130942) (xy 113.176812 -188.12383) (xy 113.183162 -188.106812)
			(xy 113.183162 -188.021468) (xy 113.176812 -188.00445) (xy 113.170716 -187.997338) (xy 113.153115 -187.976373)
			(xy 113.123389 -187.930411) (xy 113.100542 -187.88067) (xy 113.085043 -187.828173) (xy 113.077211 -187.773999)
			(xy 113.077207 -187.719262) (xy 113.085031 -187.665086) (xy 113.100521 -187.612587) (xy 113.12336 -187.562842)
			(xy 113.153079 -187.516875) (xy 113.170716 -187.495942) (xy 113.176812 -187.48883) (xy 113.183162 -187.471812)
			(xy 113.183162 -187.386468) (xy 113.176812 -187.36945) (xy 113.170716 -187.362338) (xy 113.153115 -187.341373)
			(xy 113.123389 -187.295411) (xy 113.100542 -187.24567) (xy 113.085043 -187.193173) (xy 113.077211 -187.138999)
			(xy 113.077207 -187.084262) (xy 113.085031 -187.030086) (xy 113.100521 -186.977587) (xy 113.12336 -186.927842)
			(xy 113.153079 -186.881875) (xy 113.170716 -186.860942) (xy 113.176812 -186.85383) (xy 113.183162 -186.836812)
			(xy 113.183162 -186.751468) (xy 113.176812 -186.73445) (xy 113.170716 -186.727338) (xy 113.153115 -186.706373)
			(xy 113.123389 -186.660411) (xy 113.100542 -186.61067) (xy 113.085043 -186.558173) (xy 113.077211 -186.503999)
			(xy 113.077207 -186.449262) (xy 113.085031 -186.395086) (xy 113.100521 -186.342587) (xy 113.12336 -186.292842)
			(xy 113.153079 -186.246875) (xy 113.170716 -186.225942) (xy 113.176812 -186.21883) (xy 113.183162 -186.201812)
			(xy 113.183162 -186.116468) (xy 113.176812 -186.09945) (xy 113.170716 -186.092338) (xy 113.153115 -186.071373)
			(xy 113.123389 -186.025411) (xy 113.100542 -185.97567) (xy 113.085043 -185.923173) (xy 113.077211 -185.868999)
			(xy 113.077207 -185.814262) (xy 113.085031 -185.760086) (xy 113.100521 -185.707587) (xy 113.12336 -185.657842)
			(xy 113.153079 -185.611875) (xy 113.170716 -185.590942) (xy 113.176812 -185.58383) (xy 113.183162 -185.566812)
			(xy 113.183162 -185.481468) (xy 113.176812 -185.46445) (xy 113.170716 -185.457338) (xy 113.153115 -185.436373)
			(xy 113.123389 -185.390411) (xy 113.100542 -185.34067) (xy 113.085043 -185.288173) (xy 113.077211 -185.233999)
			(xy 113.077207 -185.179262) (xy 113.085031 -185.125086) (xy 113.100521 -185.072587) (xy 113.12336 -185.022842)
			(xy 113.153079 -184.976875) (xy 113.170716 -184.955942) (xy 113.176812 -184.94883) (xy 113.183162 -184.931812)
			(xy 113.183162 -184.846468) (xy 113.176812 -184.82945) (xy 113.170716 -184.822338) (xy 113.153084 -184.8014)
			(xy 113.12337 -184.755429) (xy 113.100533 -184.705683) (xy 113.08504 -184.653184) (xy 113.077211 -184.599009)
			(xy 113.076736 -184.57164) (xy 113.077279 -184.542473) (xy 113.086176 -184.484823) (xy 113.103752 -184.429201)
			(xy 113.129598 -184.376906) (xy 113.163111 -184.32916) (xy 113.182908 -184.307734) (xy 113.189766 -184.300368)
			(xy 113.196878 -184.282588) (xy 113.196878 -184.192164) (xy 113.189766 -184.174384) (xy 113.182908 -184.167018)
			(xy 113.163125 -184.145584) (xy 113.12964 -184.097826) (xy 113.103808 -184.045531) (xy 113.086229 -183.989916)
			(xy 113.077311 -183.932275) (xy 113.076736 -183.903112) (xy 113.077167 -183.875857) (xy 113.084923 -183.821903)
			(xy 113.10028 -183.769602) (xy 113.122924 -183.720019) (xy 113.152395 -183.674164) (xy 113.188092 -183.63297)
			(xy 113.229289 -183.597276) (xy 113.275147 -183.567809) (xy 113.324732 -183.545169) (xy 113.377034 -183.529816)
			(xy 113.430989 -183.522064) (xy 113.458244 -183.521604) (xy 113.485613 -183.522102) (xy 113.539791 -183.529912)
			(xy 113.592294 -183.545393) (xy 113.642041 -183.568228) (xy 113.688009 -183.597946) (xy 113.708942 -183.615584)
			(xy 113.716054 -183.62168) (xy 113.733072 -183.62803) (xy 113.818416 -183.62803) (xy 113.835434 -183.62168)
			(xy 113.842546 -183.615584) (xy 113.863479 -183.597943) (xy 113.909447 -183.568219) (xy 113.959193 -183.545373)
			(xy 114.011695 -183.529877) (xy 114.065873 -183.522048) (xy 114.120615 -183.522048) (xy 114.174793 -183.529877)
			(xy 114.227295 -183.545373) (xy 114.277041 -183.568219) (xy 114.323009 -183.597943) (xy 114.343942 -183.615584)
			(xy 114.351054 -183.62168) (xy 114.368072 -183.62803) (xy 114.453416 -183.62803) (xy 114.470434 -183.62168)
			(xy 114.477546 -183.615584) (xy 114.498486 -183.597954) (xy 114.544457 -183.568242) (xy 114.594202 -183.545404)
			(xy 114.646701 -183.529911) (xy 114.700875 -183.52208) (xy 114.728244 -183.521604) (xy 114.755497 -183.522037)
			(xy 114.809447 -183.5298) (xy 114.861744 -183.545161) (xy 114.911322 -183.567808) (xy 114.957173 -183.59728)
			(xy 114.998363 -183.632977) (xy 115.034053 -183.674172) (xy 115.063519 -183.720027) (xy 115.086159 -183.769609)
			(xy 115.101512 -183.821908) (xy 115.109267 -183.875859) (xy 115.109752 -183.903112) (xy 117.089936 -183.903112)
			(xy 117.090367 -183.875857) (xy 117.098123 -183.821903) (xy 117.11348 -183.769602) (xy 117.136124 -183.720019)
			(xy 117.165595 -183.674164) (xy 117.201292 -183.63297) (xy 117.242489 -183.597276) (xy 117.288347 -183.567809)
			(xy 117.337932 -183.545169) (xy 117.390234 -183.529816) (xy 117.444189 -183.522064) (xy 117.471444 -183.521604)
			(xy 117.498813 -183.522102) (xy 117.552991 -183.529912) (xy 117.605494 -183.545393) (xy 117.655241 -183.568228)
			(xy 117.701209 -183.597946) (xy 117.722142 -183.615584) (xy 117.729254 -183.62168) (xy 117.746272 -183.62803)
			(xy 117.831616 -183.62803) (xy 117.848634 -183.62168) (xy 117.855746 -183.615584) (xy 117.876679 -183.597943)
			(xy 117.922647 -183.568219) (xy 117.972393 -183.545373) (xy 118.024895 -183.529877) (xy 118.079073 -183.522048)
			(xy 118.133815 -183.522048) (xy 118.187993 -183.529877) (xy 118.240495 -183.545373) (xy 118.290241 -183.568219)
			(xy 118.336209 -183.597943) (xy 118.357142 -183.615584) (xy 118.364254 -183.62168) (xy 118.381272 -183.62803)
			(xy 118.466616 -183.62803) (xy 118.483634 -183.62168) (xy 118.490746 -183.615584) (xy 118.511686 -183.597954)
			(xy 118.557657 -183.568242) (xy 118.607402 -183.545404) (xy 118.659901 -183.529911) (xy 118.714075 -183.52208)
			(xy 118.741444 -183.521604) (xy 118.768697 -183.522037) (xy 118.822647 -183.5298) (xy 118.874944 -183.545161)
			(xy 118.924522 -183.567808) (xy 118.970373 -183.59728) (xy 119.011563 -183.632977) (xy 119.047253 -183.674172)
			(xy 119.076719 -183.720027) (xy 119.099359 -183.769609) (xy 119.114712 -183.821908) (xy 119.122467 -183.875859)
			(xy 119.122952 -183.903112) (xy 119.122414 -183.93223) (xy 119.113567 -183.989791) (xy 119.09608 -184.045341)
			(xy 119.070359 -184.09759) (xy 119.037002 -184.145327) (xy 119.017288 -184.166764) (xy 119.01043 -184.173876)
			(xy 119.003318 -184.19191) (xy 119.003318 -184.28208) (xy 119.010684 -184.300114) (xy 119.017542 -184.307226)
			(xy 119.037386 -184.328688) (xy 119.070982 -184.376519) (xy 119.096891 -184.428914) (xy 119.114505 -184.484647)
			(xy 119.123413 -184.542415) (xy 119.123968 -184.57164) (xy 119.123559 -184.598894) (xy 119.115796 -184.652847)
			(xy 119.100434 -184.705145) (xy 119.077785 -184.754725) (xy 119.048311 -184.800577) (xy 119.012612 -184.841768)
			(xy 118.971413 -184.877459) (xy 118.925555 -184.906924) (xy 118.87597 -184.929562) (xy 118.823668 -184.944913)
			(xy 118.769714 -184.952665) (xy 118.74246 -184.953148) (xy 118.716175 -184.952671) (xy 118.664099 -184.945476)
			(xy 118.613504 -184.931202) (xy 118.565348 -184.910117) (xy 118.520541 -184.882622) (xy 118.479933 -184.849236)
			(xy 118.46179 -184.830212) (xy 118.454779 -184.823327) (xy 118.43702 -184.814961) (xy 118.427246 -184.813956)
			(xy 118.373906 -184.811162) (xy 118.366286 -184.818274) (xy 118.366286 -184.871614) (xy 118.366778 -184.881428)
			(xy 118.374219 -184.899592) (xy 118.380764 -184.90692) (xy 118.400949 -184.928409) (xy 118.435092 -184.976472)
			(xy 118.461436 -185.029214) (xy 118.479354 -185.08538) (xy 118.48842 -185.143634) (xy 118.488968 -185.173112)
			(xy 118.488556 -185.200367) (xy 118.480797 -185.254322) (xy 118.465437 -185.306623) (xy 118.44279 -185.356206)
			(xy 118.413317 -185.402061) (xy 118.377618 -185.443255) (xy 118.336419 -185.478948) (xy 118.29056 -185.508415)
			(xy 118.240974 -185.531055) (xy 118.188671 -185.546408) (xy 118.134715 -185.55416) (xy 118.10746 -185.55462)
			(xy 118.077984 -185.554037) (xy 118.019733 -185.544978) (xy 117.963569 -185.527065) (xy 117.910829 -185.500725)
			(xy 117.862769 -185.466586) (xy 117.841268 -185.446416) (xy 117.833937 -185.439877) (xy 117.815774 -185.432434)
			(xy 117.805962 -185.431938) (xy 117.752622 -185.431938) (xy 117.745764 -185.439304) (xy 117.73923 -185.446639)
			(xy 117.731786 -185.464799) (xy 117.731286 -185.47461) (xy 117.731286 -185.506614) (xy 117.731778 -185.516428)
			(xy 117.739219 -185.534592) (xy 117.745764 -185.54192) (xy 117.765949 -185.563409) (xy 117.800092 -185.611472)
			(xy 117.826436 -185.664214) (xy 117.844354 -185.72038) (xy 117.85342 -185.778634) (xy 117.853968 -185.808112)
			(xy 117.853482 -185.835363) (xy 117.845726 -185.889311) (xy 117.830371 -185.941606) (xy 117.807729 -185.991183)
			(xy 117.778263 -186.037033) (xy 117.742572 -186.078224) (xy 117.701381 -186.113915) (xy 117.655531 -186.143381)
			(xy 117.605954 -186.166023) (xy 117.553659 -186.181378) (xy 117.499711 -186.189134) (xy 117.445209 -186.189134)
			(xy 117.391261 -186.181378) (xy 117.338966 -186.166023) (xy 117.289389 -186.143381) (xy 117.243539 -186.113915)
			(xy 117.202348 -186.078224) (xy 117.166657 -186.037033) (xy 117.137191 -185.991183) (xy 117.114549 -185.941606)
			(xy 117.099194 -185.889311) (xy 117.091438 -185.835363) (xy 117.090952 -185.808112) (xy 117.091412 -185.780741)
			(xy 117.09923 -185.726562) (xy 117.114719 -185.674058) (xy 117.137563 -185.624311) (xy 117.167289 -185.578345)
			(xy 117.184932 -185.557414) (xy 117.191028 -185.550302) (xy 117.197378 -185.533284) (xy 117.197378 -185.44794)
			(xy 117.191028 -185.430922) (xy 117.184932 -185.42381) (xy 117.167303 -185.402868) (xy 117.137577 -185.356902)
			(xy 117.114731 -185.307157) (xy 117.099233 -185.254656) (xy 117.091404 -185.200479) (xy 117.091402 -185.145739)
			(xy 117.09923 -185.091561) (xy 117.114724 -185.03906) (xy 117.137568 -184.989314) (xy 117.167292 -184.943347)
			(xy 117.184932 -184.922414) (xy 117.191028 -184.915302) (xy 117.197378 -184.898284) (xy 117.197378 -184.81294)
			(xy 117.191028 -184.795922) (xy 117.184932 -184.78881) (xy 117.167289 -184.767881) (xy 117.137577 -184.721908)
			(xy 117.114741 -184.67216) (xy 117.099251 -184.619658) (xy 117.091425 -184.565481) (xy 117.090952 -184.538112)
			(xy 117.091455 -184.510814) (xy 117.099223 -184.456774) (xy 117.114618 -184.404394) (xy 117.137324 -184.354744)
			(xy 117.166878 -184.308839) (xy 117.184424 -184.287922) (xy 117.190774 -184.28081) (xy 117.19687 -184.263792)
			(xy 117.19687 -184.178194) (xy 117.19052 -184.16143) (xy 117.184424 -184.154318) (xy 117.166722 -184.133347)
			(xy 117.136841 -184.087318) (xy 117.113872 -184.037479) (xy 117.098289 -183.98486) (xy 117.090415 -183.930551)
			(xy 117.089936 -183.903112) (xy 115.109752 -183.903112) (xy 115.109287 -183.930412) (xy 115.101512 -183.984454)
			(xy 115.08611 -184.036836) (xy 115.063395 -184.086485) (xy 115.033831 -184.132387) (xy 115.01628 -184.153302)
			(xy 115.00993 -184.160414) (xy 115.003834 -184.177432) (xy 115.003834 -184.26303) (xy 115.010184 -184.279794)
			(xy 115.01628 -184.286906) (xy 115.033993 -184.307868) (xy 115.063873 -184.353899) (xy 115.08684 -184.403741)
			(xy 115.10242 -184.456361) (xy 115.110291 -184.510673) (xy 115.110768 -184.538112) (xy 115.110317 -184.565483)
			(xy 115.102497 -184.619663) (xy 115.087004 -184.672166) (xy 115.064159 -184.721913) (xy 115.034431 -184.767879)
			(xy 115.016788 -184.78881) (xy 115.010692 -184.795922) (xy 115.004342 -184.81294) (xy 115.004342 -184.898284)
			(xy 115.010692 -184.915302) (xy 115.016788 -184.922414) (xy 115.03444 -184.943338) (xy 115.064163 -184.989307)
			(xy 115.087007 -185.039055) (xy 115.102501 -185.091558) (xy 115.110329 -185.145738) (xy 115.110327 -185.20048)
			(xy 115.102498 -185.254659) (xy 115.087 -185.307162) (xy 115.064154 -185.356909) (xy 115.034429 -185.402877)
			(xy 115.016788 -185.42381) (xy 115.010692 -185.430922) (xy 115.004342 -185.44794) (xy 115.004342 -185.533284)
			(xy 115.010692 -185.550302) (xy 115.016788 -185.557414) (xy 115.03444 -185.578338) (xy 115.064163 -185.624307)
			(xy 115.087007 -185.674055) (xy 115.102501 -185.726558) (xy 115.110329 -185.780738) (xy 115.110327 -185.83548)
			(xy 115.102498 -185.889659) (xy 115.087 -185.942162) (xy 115.064154 -185.991909) (xy 115.034429 -186.037877)
			(xy 115.016788 -186.05881) (xy 115.010692 -186.065922) (xy 115.004342 -186.08294) (xy 115.004342 -186.168284)
			(xy 115.010692 -186.185302) (xy 115.016788 -186.192414) (xy 115.034398 -186.213369) (xy 115.064115 -186.259335)
			(xy 115.086957 -186.309077) (xy 115.102454 -186.361573) (xy 115.11029 -186.415744) (xy 115.110768 -186.443112)
			(xy 115.110228 -186.472337) (xy 115.101304 -186.530102) (xy 115.083683 -186.585833) (xy 115.057774 -186.638227)
			(xy 115.024184 -186.686062) (xy 115.004342 -186.707526) (xy 114.997484 -186.714638) (xy 114.990118 -186.732672)
			(xy 114.990118 -186.822842) (xy 114.99723 -186.840876) (xy 115.004088 -186.847988) (xy 115.023818 -186.869411)
			(xy 115.057171 -186.917152) (xy 115.082886 -186.969405) (xy 115.100366 -187.024958) (xy 115.109206 -187.082521)
			(xy 115.109752 -187.11164) (xy 115.109262 -187.13901) (xy 115.101452 -187.193188) (xy 115.085969 -187.245691)
			(xy 115.063132 -187.295439) (xy 115.033412 -187.341406) (xy 115.015772 -187.362338) (xy 115.009676 -187.36945)
			(xy 115.003326 -187.386468) (xy 115.003326 -187.471812) (xy 115.009676 -187.48883) (xy 115.015772 -187.495942)
			(xy 115.033452 -187.516843) (xy 115.063175 -187.562816) (xy 115.086018 -187.612568) (xy 115.101511 -187.665075)
			(xy 115.109336 -187.719258) (xy 115.109332 -187.774003) (xy 115.101499 -187.828184) (xy 115.085997 -187.880689)
			(xy 115.063146 -187.930437) (xy 115.033416 -187.976405) (xy 115.015772 -187.997338) (xy 115.009676 -188.00445)
			(xy 115.003326 -188.021468) (xy 115.003326 -188.106812) (xy 115.009676 -188.12383) (xy 115.015772 -188.130942)
			(xy 115.033393 -188.151889) (xy 115.063109 -188.197857) (xy 115.085948 -188.247601) (xy 115.101444 -188.300098)
			(xy 115.109276 -188.354272) (xy 115.109752 -188.38164) (xy 115.10926 -188.40889) (xy 115.101499 -188.462835)
			(xy 115.086141 -188.515127) (xy 115.063498 -188.564702) (xy 115.034032 -188.61055) (xy 114.998341 -188.651738)
			(xy 114.957153 -188.687429) (xy 114.911305 -188.716896) (xy 114.861731 -188.739539) (xy 114.809439 -188.754898)
			(xy 114.755494 -188.762659) (xy 114.728244 -188.763148) (xy 114.700874 -188.762669) (xy 114.646695 -188.754856)
			(xy 114.594192 -188.739371) (xy 114.544444 -188.716532) (xy 114.498478 -188.686809) (xy 114.477546 -188.669168)
			(xy 114.470434 -188.663072) (xy 114.453416 -188.656722) (xy 114.368072 -188.656722) (xy 114.351054 -188.663072)
			(xy 114.343942 -188.669168) (xy 114.323009 -188.686809) (xy 114.277041 -188.716533) (xy 114.227295 -188.739379)
			(xy 114.174793 -188.754875) (xy 114.120615 -188.762704) (xy 114.065873 -188.762704) (xy 114.011695 -188.754875)
			(xy 113.959193 -188.739379) (xy 113.909447 -188.716533) (xy 113.863479 -188.686809) (xy 113.842546 -188.669168)
			(xy 113.835434 -188.663072) (xy 113.818416 -188.656722) (xy 113.733072 -188.656722) (xy 113.716054 -188.663072)
			(xy 113.708942 -188.669168) (xy 113.688001 -188.686796) (xy 113.642031 -188.716511) (xy 113.592286 -188.739349)
			(xy 113.539787 -188.754843) (xy 113.485613 -188.762673) (xy 113.458244 -188.763148) (xy 113.430994 -188.762604)
			(xy 113.377048 -188.754854) (xy 113.324754 -188.739506) (xy 113.275177 -188.716871) (xy 113.229325 -188.687411)
			(xy 113.188133 -188.651726) (xy 113.152439 -188.610542) (xy 113.122969 -188.564697) (xy 113.100324 -188.515125)
			(xy 113.084964 -188.462834) (xy 113.077202 -188.40889) (xy 113.076736 -188.38164) (xy 76.804012 -188.38164)
			(xy 78.645766 -190.223394) (xy 78.646274 -190.223902) (xy 78.653654 -190.230487) (xy 78.671954 -190.237937)
			(xy 78.681834 -190.23838)
		)
		(stroke
			(width 0)
			(type solid)
		)
		(fill yes)
		(layer "In13.Cu")
		(net "GND")
	)
	(gr_poly
		(pts
			(xy 291.90061 -371.562884) (xy 291.900864 -371.54231) (xy 291.901808 -371.515377) (xy 291.910341 -371.462166)
			(xy 291.926276 -371.410685) (xy 291.949299 -371.36196) (xy 291.978949 -371.316959) (xy 292.014637 -371.276579)
			(xy 292.055653 -371.241623) (xy 292.10118 -371.212786) (xy 292.150312 -371.190644) (xy 292.202071 -371.175637)
			(xy 292.255427 -371.168063) (xy 292.282372 -371.16766) (xy 292.310343 -371.168129) (xy 292.365691 -371.176263)
			(xy 292.419254 -371.192404) (xy 292.46988 -371.216205) (xy 292.516481 -371.247155) (xy 292.558054 -371.284587)
			(xy 292.57625 -371.305836) (xy 292.576504 -371.306344) (xy 292.584342 -371.31479) (xy 292.605368 -371.32416)
			(xy 292.61689 -371.324378) (xy 292.709092 -371.321584) (xy 292.72992 -371.310408) (xy 292.736778 -371.300756)
			(xy 292.752227 -371.28016) (xy 292.78777 -371.242911) (xy 292.827996 -371.210776) (xy 292.872176 -371.18434)
			(xy 292.919509 -371.164081) (xy 292.969135 -371.150367) (xy 293.020153 -371.143447) (xy 293.045896 -371.143022)
			(xy 293.074524 -371.143535) (xy 293.131137 -371.152094) (xy 293.185835 -371.169019) (xy 293.237387 -371.193931)
			(xy 293.284637 -371.226269) (xy 293.326521 -371.265307) (xy 293.362099 -371.310168) (xy 293.390572 -371.359843)
			(xy 293.411298 -371.413216) (xy 293.423813 -371.469088) (xy 293.426388 -371.497606) (xy 293.426388 -371.49786)
			(xy 293.427483 -371.507293) (xy 293.435694 -371.524401) (xy 293.44239 -371.531134) (xy 293.49319 -371.578378)
			(xy 293.500481 -371.584662) (xy 293.518371 -371.591717) (xy 293.527988 -371.592094) (xy 294.41648 -371.592094)
			(xy 294.424675 -371.591788) (xy 294.440224 -371.58661) (xy 294.44696 -371.581934) (xy 294.453564 -371.577108)
			(xy 294.462454 -371.5639) (xy 294.464994 -371.555772) (xy 294.473265 -371.529937) (xy 294.496093 -371.480728)
			(xy 294.525657 -371.435246) (xy 294.561363 -371.394409) (xy 294.602491 -371.359038) (xy 294.648213 -371.329846)
			(xy 294.697607 -371.307422) (xy 294.749678 -371.292216) (xy 294.803377 -371.284536) (xy 294.857623 -371.284536)
			(xy 294.911322 -371.292216) (xy 294.963393 -371.307422) (xy 295.012787 -371.329846) (xy 295.058509 -371.359038)
			(xy 295.099637 -371.394409) (xy 295.135343 -371.435246) (xy 295.164907 -371.480728) (xy 295.187735 -371.529937)
			(xy 295.196006 -371.555772) (xy 295.196006 -371.556026) (xy 295.198603 -371.56375) (xy 295.207929 -371.577101)
			(xy 295.214294 -371.582188) (xy 295.220644 -371.587014) (xy 295.236138 -371.592094) (xy 295.322498 -371.592094)
			(xy 295.330392 -371.591759) (xy 295.345399 -371.586842) (xy 295.351962 -371.582442) (xy 295.358058 -371.578124)
			(xy 295.367456 -371.565424) (xy 295.37025 -371.557296) (xy 295.379589 -371.530846) (xy 295.404928 -371.480802)
			(xy 295.43732 -371.435008) (xy 295.476069 -371.394451) (xy 295.520338 -371.360004) (xy 295.569174 -371.33241)
			(xy 295.621524 -371.312264) (xy 295.676259 -371.3) (xy 295.7322 -371.295882) (xy 295.788141 -371.3)
			(xy 295.842876 -371.312264) (xy 295.895226 -371.33241) (xy 295.944062 -371.360004) (xy 295.988331 -371.394451)
			(xy 296.02708 -371.435008) (xy 296.059472 -371.480802) (xy 296.084811 -371.530846) (xy 296.09415 -371.557296)
			(xy 296.094404 -371.557804) (xy 296.097164 -371.565281) (xy 296.106617 -371.578105) (xy 296.112946 -371.58295)
			(xy 296.119042 -371.587268) (xy 296.133774 -371.592094) (xy 297.256708 -371.592094) (xy 297.26636 -371.591078)
			(xy 297.273604 -371.58945) (xy 297.286772 -371.582608) (xy 297.292268 -371.577616) (xy 298.268898 -370.600986)
			(xy 298.276292 -370.59413) (xy 298.294891 -370.586381) (xy 298.304966 -370.586) (xy 299.473874 -370.586)
			(xy 299.476414 -370.586) (xy 299.486509 -370.585068) (xy 299.504778 -370.576319) (xy 299.518215 -370.561162)
			(xy 299.52188 -370.55171) (xy 299.5549 -370.455698) (xy 299.558456 -370.445284) (xy 299.553884 -370.430044)
			(xy 299.551383 -370.422631) (xy 299.542577 -370.409709) (xy 299.536612 -370.404644) (xy 299.536358 -370.40439)
			(xy 299.513868 -370.386203) (xy 299.474119 -370.344189) (xy 299.441167 -370.296656) (xy 299.415769 -370.244694)
			(xy 299.398507 -370.189493) (xy 299.389775 -370.132319) (xy 299.389292 -370.1034) (xy 299.389778 -370.076149)
			(xy 299.397534 -370.022201) (xy 299.412889 -369.969906) (xy 299.435531 -369.920329) (xy 299.464997 -369.874479)
			(xy 299.500688 -369.833288) (xy 299.541879 -369.797597) (xy 299.587729 -369.768131) (xy 299.637306 -369.745489)
			(xy 299.689601 -369.730134) (xy 299.743549 -369.722378) (xy 299.798051 -369.722378) (xy 299.851999 -369.730134)
			(xy 299.904294 -369.745489) (xy 299.953871 -369.768131) (xy 299.999721 -369.797597) (xy 300.040912 -369.833288)
			(xy 300.076603 -369.874479) (xy 300.106069 -369.920329) (xy 300.128711 -369.969906) (xy 300.144066 -370.022201)
			(xy 300.151822 -370.076149) (xy 300.152308 -370.1034) (xy 300.151774 -370.132317) (xy 300.143047 -370.189488)
			(xy 300.125793 -370.244688) (xy 300.100408 -370.296652) (xy 300.067471 -370.344191) (xy 300.027739 -370.386215)
			(xy 300.005242 -370.40439) (xy 300.004988 -370.404644) (xy 299.999033 -370.409714) (xy 299.990247 -370.422643)
			(xy 299.987716 -370.430044) (xy 299.983144 -370.445284) (xy 299.9867 -370.455698) (xy 300.01972 -370.55171)
			(xy 300.023434 -370.561129) (xy 300.036886 -370.57624) (xy 300.055109 -370.585026) (xy 300.065186 -370.586)
			(xy 301.957994 -370.586) (xy 301.96409 -370.584476) (xy 302.039907 -370.566229) (xy 302.192949 -370.536201)
			(xy 302.347265 -370.513615) (xy 302.502493 -370.498524) (xy 302.65827 -370.490964) (xy 302.73625 -370.490496)
			(xy 306.497482 -370.490496) (xy 306.506339 -370.490073) (xy 306.522975 -370.483975) (xy 306.529994 -370.478558)
			(xy 307.028088 -369.980464) (xy 307.05877 -369.950455) (xy 307.124514 -369.895275) (xy 307.194792 -369.846001)
			(xy 307.269076 -369.803001) (xy 307.307742 -369.784376) (xy 307.323998 -369.776756) (xy 307.339746 -369.745006)
			(xy 307.314346 -369.630706) (xy 307.311327 -369.619576) (xy 307.297054 -369.601491) (xy 307.276334 -369.591419)
			(xy 307.264816 -369.590828) (xy 304.838354 -369.590828) (xy 304.80979 -369.590272) (xy 304.753364 -369.581344)
			(xy 304.699029 -369.5637) (xy 304.648123 -369.537774) (xy 304.601899 -369.504204) (xy 304.581306 -369.484402)
			(xy 304.463958 -369.367054) (xy 304.458878 -369.361974) (xy 303.10836 -368.01171) (xy 303.102518 -368.00663)
			(xy 303.094136 -368.000534) (xy 303.068644 -367.986095) (xy 303.022025 -367.950615) (xy 302.981373 -367.90843)
			(xy 302.947644 -367.86053) (xy 302.921628 -367.808039) (xy 302.903938 -367.752189) (xy 302.894987 -367.694292)
			(xy 302.894492 -367.665) (xy 302.894996 -367.637264) (xy 302.903041 -367.582377) (xy 302.918945 -367.529232)
			(xy 302.942375 -367.47895) (xy 302.972837 -367.432589) (xy 303.009688 -367.391125) (xy 303.052153 -367.355432)
			(xy 303.099338 -367.326262) (xy 303.150248 -367.30423) (xy 303.203812 -367.289799) (xy 303.231296 -367.286032)
			(xy 303.24552 -367.284508) (xy 303.276 -367.283238) (xy 303.30537 -367.283778) (xy 303.363415 -367.292778)
			(xy 303.419397 -367.310564) (xy 303.471992 -367.336718) (xy 303.51996 -367.370621) (xy 303.562167 -367.411473)
			(xy 303.597616 -367.458309) (xy 303.612042 -367.483898) (xy 303.613835 -367.487073) (xy 303.618172 -367.492934)
			(xy 303.620678 -367.495582) (xy 304.851562 -368.726466) (xy 304.858962 -368.733306) (xy 304.877561 -368.741024)
			(xy 304.88763 -368.741452) (xy 304.98542 -368.741452) (xy 304.995461 -368.741023) (xy 305.014004 -368.733308)
			(xy 305.028165 -368.719069) (xy 305.03241 -368.709956) (xy 305.038506 -368.695732) (xy 305.03241 -368.66576)
			(xy 303.106328 -366.739424) (xy 303.103701 -366.736893) (xy 303.097837 -366.732552) (xy 303.094644 -366.730788)
			(xy 303.069103 -366.716361) (xy 303.022387 -366.680888) (xy 302.981647 -366.638687) (xy 302.947841 -366.590751)
			(xy 302.921765 -366.538209) (xy 302.904032 -366.482296) (xy 302.895061 -366.424329) (xy 302.894492 -366.395)
			(xy 302.894978 -366.367749) (xy 302.902734 -366.313801) (xy 302.918089 -366.261506) (xy 302.940731 -366.211929)
			(xy 302.970197 -366.166079) (xy 303.005888 -366.124888) (xy 303.047079 -366.089197) (xy 303.092929 -366.059731)
			(xy 303.142506 -366.037089) (xy 303.194801 -366.021734) (xy 303.248749 -366.013978) (xy 303.276 -366.013492)
			(xy 303.30533 -366.014029) (xy 303.363299 -366.023003) (xy 303.419212 -366.04074) (xy 303.471754 -366.066822)
			(xy 303.519688 -366.100636) (xy 303.561884 -366.141384) (xy 303.597349 -366.188109) (xy 303.611788 -366.213644)
			(xy 303.613577 -366.216822) (xy 303.617906 -366.22269) (xy 303.620424 -366.225328) (xy 304.755436 -367.3602)
			(xy 310.183782 -367.3602) (xy 310.187853 -367.304578) (xy 310.199979 -367.250141) (xy 310.219902 -367.19805)
			(xy 310.247198 -367.149415) (xy 310.281284 -367.105272) (xy 310.321433 -367.066563) (xy 310.366791 -367.034112)
			(xy 310.416391 -367.008611) (xy 310.469175 -366.990604) (xy 310.524018 -366.980474) (xy 310.579752 -366.978437)
			(xy 310.635189 -366.984537) (xy 310.689146 -366.998643) (xy 310.740475 -367.020455) (xy 310.788081 -367.049509)
			(xy 310.830949 -367.085184) (xy 310.868166 -367.126721) (xy 310.898939 -367.173234) (xy 310.922611 -367.223731)
			(xy 310.938679 -367.277138) (xy 310.946799 -367.332314) (xy 310.947308 -367.3602) (xy 310.946799 -367.388086)
			(xy 310.938679 -367.443262) (xy 310.922611 -367.496669) (xy 310.898939 -367.547166) (xy 310.868166 -367.593679)
			(xy 310.830949 -367.635216) (xy 310.788081 -367.670891) (xy 310.740475 -367.699945) (xy 310.689146 -367.721757)
			(xy 310.635189 -367.735863) (xy 310.579752 -367.741963) (xy 310.524018 -367.739926) (xy 310.469175 -367.729796)
			(xy 310.416391 -367.711789) (xy 310.366791 -367.686288) (xy 310.321433 -367.653837) (xy 310.281284 -367.615128)
			(xy 310.247198 -367.570985) (xy 310.219902 -367.52235) (xy 310.199979 -367.470259) (xy 310.187853 -367.415822)
			(xy 310.183782 -367.3602) (xy 304.755436 -367.3602) (xy 305.672744 -368.277394) (xy 305.680145 -368.284234)
			(xy 305.698743 -368.291954) (xy 305.708812 -368.29238) (xy 309.462678 -368.29238) (xy 309.4743 -368.291807)
			(xy 309.495193 -368.281619) (xy 309.50281 -368.272822) (xy 309.559452 -368.199924) (xy 309.564024 -368.177318)
			(xy 309.562754 -368.171984) (xy 309.556442 -368.147384) (xy 309.549688 -368.097048) (xy 309.549292 -368.071654)
			(xy 309.549292 -368.0714) (xy 309.549778 -368.044149) (xy 309.557534 -367.990201) (xy 309.572889 -367.937906)
			(xy 309.595531 -367.888329) (xy 309.624997 -367.842479) (xy 309.660688 -367.801288) (xy 309.701879 -367.765597)
			(xy 309.747729 -367.736131) (xy 309.797306 -367.713489) (xy 309.849601 -367.698134) (xy 309.903549 -367.690378)
			(xy 309.9308 -367.689892) (xy 309.957844 -367.690363) (xy 310.011389 -367.698002) (xy 310.063318 -367.713127)
			(xy 310.112591 -367.735435) (xy 310.158219 -367.764478) (xy 310.199288 -367.799675) (xy 310.234974 -367.840319)
			(xy 310.264562 -367.885596) (xy 310.287459 -367.934598) (xy 310.303205 -367.986342) (xy 310.311486 -368.039792)
			(xy 310.312308 -368.066828) (xy 310.312308 -368.079782) (xy 310.318404 -368.090704) (xy 310.321519 -368.095995)
			(xy 310.32986 -368.105) (xy 310.334914 -368.108484) (xy 310.354218 -368.121184) (xy 310.365015 -368.127518)
			(xy 310.389906 -368.129907) (xy 310.401716 -368.125756) (xy 310.996584 -367.879122) (xy 311.001145 -367.877111)
			(xy 311.009453 -367.871605) (xy 311.013094 -367.8682) (xy 311.52465 -367.356898) (xy 311.531578 -367.34938)
			(xy 311.539301 -367.330472) (xy 311.538999 -367.310049) (xy 311.535318 -367.30051) (xy 311.519062 -367.26368)
			(xy 311.515734 -367.256734) (xy 311.505653 -367.2451) (xy 311.49925 -367.24082) (xy 311.4929 -367.23701)
			(xy 311.47893 -367.2332) (xy 311.470802 -367.233454) (xy 311.4548 -367.233708) (xy 311.427549 -367.233222)
			(xy 311.373601 -367.225466) (xy 311.321306 -367.210111) (xy 311.271729 -367.187469) (xy 311.225879 -367.158003)
			(xy 311.184688 -367.122312) (xy 311.148997 -367.081121) (xy 311.119531 -367.035271) (xy 311.096889 -366.985694)
			(xy 311.081534 -366.933399) (xy 311.073778 -366.879451) (xy 311.073778 -366.824949) (xy 311.081534 -366.771001)
			(xy 311.096889 -366.718706) (xy 311.119531 -366.669129) (xy 311.148997 -366.623279) (xy 311.184688 -366.582088)
			(xy 311.225879 -366.546397) (xy 311.271729 -366.516931) (xy 311.321306 -366.494289) (xy 311.373601 -366.478934)
			(xy 311.427549 -366.471178) (xy 311.482051 -366.471178) (xy 311.535999 -366.478934) (xy 311.588294 -366.494289)
			(xy 311.637871 -366.516931) (xy 311.683721 -366.546397) (xy 311.724912 -366.582088) (xy 311.760603 -366.623279)
			(xy 311.790069 -366.669129) (xy 311.812711 -366.718706) (xy 311.828066 -366.771001) (xy 311.835822 -366.824949)
			(xy 311.836308 -366.8522) (xy 311.836054 -366.868202) (xy 311.836054 -366.868456) (xy 311.836028 -366.875951)
			(xy 311.839917 -366.890418) (xy 311.843674 -366.896904) (xy 311.847738 -366.903508) (xy 311.858914 -366.91316)
			(xy 311.90311 -366.932718) (xy 311.912648 -366.936383) (xy 311.933063 -366.936643) (xy 311.951983 -366.92897)
			(xy 311.959498 -366.92205) (xy 312.107326 -366.774222) (xy 312.121259 -366.760634) (xy 312.15155 -366.736196)
			(xy 312.167778 -366.725454) (xy 312.17584 -366.719761) (xy 312.187231 -366.703666) (xy 312.191717 -366.684465)
			(xy 312.190638 -366.674654) (xy 312.185558 -366.644174) (xy 312.18451 -366.638395) (xy 312.180144 -366.627495)
			(xy 312.176922 -366.622584) (xy 312.173366 -366.617758) (xy 312.164476 -366.609884) (xy 312.158888 -366.60709)
			(xy 312.135893 -366.594722) (xy 312.09321 -366.564649) (xy 312.055022 -366.529042) (xy 312.02204 -366.488565)
			(xy 311.994879 -366.443973) (xy 311.974045 -366.396097) (xy 311.959927 -366.345829) (xy 311.952788 -366.294106)
			(xy 311.952386 -366.268) (xy 311.952795 -366.242744) (xy 311.959459 -366.192672) (xy 311.972671 -366.143918)
			(xy 311.992199 -366.097333) (xy 312.017702 -366.053731) (xy 312.032904 -366.033558) (xy 312.037222 -366.02797)
			(xy 312.042556 -366.014762) (xy 312.043318 -366.00765) (xy 312.043832 -366.000534) (xy 312.041395 -365.986481)
			(xy 312.038492 -365.979964) (xy 312.000392 -365.902494) (xy 311.998106 -365.897414) (xy 311.99349 -365.889301)
			(xy 311.979624 -365.87683) (xy 311.962218 -365.870136) (xy 311.952894 -365.869728) (xy 311.526936 -365.869728)
			(xy 311.517211 -365.870203) (xy 311.499178 -365.877504) (xy 311.491884 -365.883952) (xy 311.001918 -366.374172)
			(xy 310.900572 -366.475518) (xy 310.887356 -366.488119) (xy 310.857018 -366.50843) (xy 310.823305 -366.522444)
			(xy 310.787508 -366.529623) (xy 310.769254 -366.530128) (xy 304.494946 -366.530128) (xy 304.476687 -366.529685)
			(xy 304.440879 -366.522508) (xy 304.407161 -366.50848) (xy 304.376829 -366.488141) (xy 304.363628 -366.475518)
			(xy 304.197004 -366.30864) (xy 303.40046 -365.512096) (xy 303.39583 -365.507764) (xy 303.384907 -365.501332)
			(xy 303.37887 -365.499396) (xy 303.372774 -365.497618) (xy 303.360836 -365.49711) (xy 303.354232 -365.49838)
			(xy 303.334896 -365.502168) (xy 303.295702 -365.50624) (xy 303.276 -365.506508) (xy 303.248749 -365.506022)
			(xy 303.194801 -365.498266) (xy 303.142506 -365.482911) (xy 303.092929 -365.460269) (xy 303.047079 -365.430803)
			(xy 303.005888 -365.395112) (xy 302.970197 -365.353921) (xy 302.940731 -365.308071) (xy 302.918089 -365.258494)
			(xy 302.902734 -365.206199) (xy 302.894978 -365.152251) (xy 302.894978 -365.097749) (xy 302.902734 -365.043801)
			(xy 302.918089 -364.991506) (xy 302.940731 -364.941929) (xy 302.970197 -364.896079) (xy 303.005888 -364.854888)
			(xy 303.047079 -364.819197) (xy 303.092929 -364.789731) (xy 303.142506 -364.767089) (xy 303.194801 -364.751734)
			(xy 303.248749 -364.743978) (xy 303.303251 -364.743978) (xy 303.357199 -364.751734) (xy 303.409494 -364.767089)
			(xy 303.459071 -364.789731) (xy 303.504921 -364.819197) (xy 303.546112 -364.854888) (xy 303.581803 -364.896079)
			(xy 303.611269 -364.941929) (xy 303.633911 -364.991506) (xy 303.649266 -365.043801) (xy 303.657022 -365.097749)
			(xy 303.657508 -365.125) (xy 305.190142 -365.125) (xy 305.194213 -365.069378) (xy 305.206339 -365.014941)
			(xy 305.226262 -364.96285) (xy 305.253558 -364.914215) (xy 305.287644 -364.870072) (xy 305.327793 -364.831363)
			(xy 305.373151 -364.798912) (xy 305.422751 -364.773411) (xy 305.475535 -364.755404) (xy 305.530378 -364.745274)
			(xy 305.586112 -364.743237) (xy 305.641549 -364.749337) (xy 305.695506 -364.763443) (xy 305.746835 -364.785255)
			(xy 305.794441 -364.814309) (xy 305.837309 -364.849984) (xy 305.874526 -364.891521) (xy 305.905299 -364.938034)
			(xy 305.928971 -364.988531) (xy 305.945039 -365.041938) (xy 305.953159 -365.097114) (xy 305.953668 -365.125)
			(xy 305.953159 -365.152886) (xy 305.945039 -365.208062) (xy 305.928971 -365.261469) (xy 305.905299 -365.311966)
			(xy 305.874526 -365.358479) (xy 305.837309 -365.400016) (xy 305.794441 -365.435691) (xy 305.746835 -365.464745)
			(xy 305.695506 -365.486557) (xy 305.641549 -365.500663) (xy 305.586112 -365.506763) (xy 305.530378 -365.504726)
			(xy 305.475535 -365.494596) (xy 305.422751 -365.476589) (xy 305.373151 -365.451088) (xy 305.327793 -365.418637)
			(xy 305.287644 -365.379928) (xy 305.253558 -365.335785) (xy 305.226262 -365.28715) (xy 305.206339 -365.235059)
			(xy 305.194213 -365.180622) (xy 305.190142 -365.125) (xy 303.657508 -365.125) (xy 303.657255 -365.14464)
			(xy 303.653187 -365.183709) (xy 303.64938 -365.202978) (xy 303.64938 -365.203486) (xy 303.64684 -365.215932)
			(xy 303.650396 -365.22787) (xy 303.652353 -365.233899) (xy 303.65877 -365.244827) (xy 303.663096 -365.24946)
			(xy 304.557176 -366.14354) (xy 304.564533 -366.150188) (xy 304.582833 -366.157771) (xy 304.592736 -366.158272)
			(xy 307.0606 -366.158272) (xy 307.06968 -366.157911) (xy 307.086695 -366.151572) (xy 307.100404 -366.139664)
			(xy 307.10505 -366.131856) (xy 307.146198 -366.048036) (xy 307.149128 -366.041525) (xy 307.151591 -366.027467)
			(xy 307.151024 -366.02035) (xy 307.150262 -366.013238) (xy 307.144928 -366.00003) (xy 307.14061 -365.994442)
			(xy 307.125414 -365.974265) (xy 307.099909 -365.930666) (xy 307.080383 -365.884081) (xy 307.067177 -365.835327)
			(xy 307.060522 -365.785256) (xy 307.060092 -365.76) (xy 307.060578 -365.732749) (xy 307.068334 -365.678801)
			(xy 307.083689 -365.626506) (xy 307.106331 -365.576929) (xy 307.135797 -365.531079) (xy 307.171488 -365.489888)
			(xy 307.212679 -365.454197) (xy 307.258529 -365.424731) (xy 307.308106 -365.402089) (xy 307.360401 -365.386734)
			(xy 307.414349 -365.378978) (xy 307.468851 -365.378978) (xy 307.522799 -365.386734) (xy 307.575094 -365.402089)
			(xy 307.624671 -365.424731) (xy 307.670521 -365.454197) (xy 307.711712 -365.489888) (xy 307.747403 -365.531079)
			(xy 307.776869 -365.576929) (xy 307.799511 -365.626506) (xy 307.814866 -365.678801) (xy 307.822622 -365.732749)
			(xy 307.823108 -365.76) (xy 307.822699 -365.785256) (xy 307.816035 -365.835328) (xy 307.802823 -365.884082)
			(xy 307.783295 -365.930667) (xy 307.757791 -365.974268) (xy 307.74259 -365.994442) (xy 307.738272 -366.00003)
			(xy 307.732938 -366.013238) (xy 307.732176 -366.02035) (xy 307.731662 -366.027466) (xy 307.734099 -366.041519)
			(xy 307.737002 -366.048036) (xy 307.775102 -366.125506) (xy 307.777388 -366.130586) (xy 307.782003 -366.138699)
			(xy 307.795869 -366.151172) (xy 307.813276 -366.157868) (xy 307.8226 -366.158272) (xy 308.24932 -366.158272)
			(xy 308.259399 -366.157847) (xy 308.277995 -366.150073) (xy 308.292131 -366.135705) (xy 308.29631 -366.126522)
			(xy 308.331616 -366.039146) (xy 308.334213 -366.031947) (xy 308.335512 -366.016706) (xy 308.334156 -366.009174)
			(xy 308.332378 -366.002062) (xy 308.32552 -365.989362) (xy 308.319678 -365.983774) (xy 308.301571 -365.96574)
			(xy 308.269856 -365.925669) (xy 308.243776 -365.881721) (xy 308.2238 -365.834684) (xy 308.210284 -365.7854)
			(xy 308.203472 -365.734752) (xy 308.203092 -365.7092) (xy 308.203578 -365.681949) (xy 308.211334 -365.628001)
			(xy 308.226689 -365.575706) (xy 308.249331 -365.526129) (xy 308.278797 -365.480279) (xy 308.314488 -365.439088)
			(xy 308.355679 -365.403397) (xy 308.401529 -365.373931) (xy 308.451106 -365.351289) (xy 308.503401 -365.335934)
			(xy 308.557349 -365.328178) (xy 308.611851 -365.328178) (xy 308.665799 -365.335934) (xy 308.718094 -365.351289)
			(xy 308.767671 -365.373931) (xy 308.813521 -365.403397) (xy 308.854712 -365.439088) (xy 308.868673 -365.4552)
			(xy 309.96458 -365.4552) (xy 309.968651 -365.399578) (xy 309.980777 -365.345141) (xy 310.0007 -365.29305)
			(xy 310.027996 -365.244415) (xy 310.062082 -365.200272) (xy 310.102231 -365.161563) (xy 310.147589 -365.129112)
			(xy 310.197189 -365.103611) (xy 310.249973 -365.085604) (xy 310.304816 -365.075474) (xy 310.36055 -365.073437)
			(xy 310.415987 -365.079537) (xy 310.469944 -365.093643) (xy 310.521273 -365.115455) (xy 310.568879 -365.144509)
			(xy 310.611747 -365.180184) (xy 310.648964 -365.221721) (xy 310.679737 -365.268234) (xy 310.703409 -365.318731)
			(xy 310.719477 -365.372138) (xy 310.727597 -365.427314) (xy 310.728106 -365.4552) (xy 310.727597 -365.483086)
			(xy 310.719477 -365.538262) (xy 310.703409 -365.591669) (xy 310.679737 -365.642166) (xy 310.648964 -365.688679)
			(xy 310.611747 -365.730216) (xy 310.568879 -365.765891) (xy 310.521273 -365.794945) (xy 310.469944 -365.816757)
			(xy 310.415987 -365.830863) (xy 310.36055 -365.836963) (xy 310.304816 -365.834926) (xy 310.249973 -365.824796)
			(xy 310.197189 -365.806789) (xy 310.147589 -365.781288) (xy 310.102231 -365.748837) (xy 310.062082 -365.710128)
			(xy 310.027996 -365.665985) (xy 310.0007 -365.61735) (xy 309.980777 -365.565259) (xy 309.968651 -365.510822)
			(xy 309.96458 -365.4552) (xy 308.868673 -365.4552) (xy 308.890403 -365.480279) (xy 308.919869 -365.526129)
			(xy 308.942511 -365.575706) (xy 308.957866 -365.628001) (xy 308.965622 -365.681949) (xy 308.966108 -365.7092)
			(xy 308.965699 -365.734751) (xy 308.958881 -365.785395) (xy 308.945367 -365.834677) (xy 308.925399 -365.881715)
			(xy 308.899334 -365.925668) (xy 308.867637 -365.965751) (xy 308.849522 -365.983774) (xy 308.849268 -365.984028)
			(xy 308.844112 -365.989343) (xy 308.836872 -366.002253) (xy 308.835044 -366.009428) (xy 308.83352 -366.017048)
			(xy 308.83479 -366.032034) (xy 308.87289 -366.126522) (xy 308.87708 -366.135689) (xy 308.891243 -366.150007)
			(xy 308.909812 -366.157806) (xy 308.91988 -366.158272) (xy 310.671464 -366.158272) (xy 310.681189 -366.157797)
			(xy 310.699222 -366.150496) (xy 310.706516 -366.144048) (xy 311.196482 -365.653828) (xy 311.297828 -365.552482)
			(xy 311.311044 -365.539881) (xy 311.341382 -365.51957) (xy 311.375095 -365.505556) (xy 311.410892 -365.498377)
			(xy 311.429146 -365.497872) (xy 313.306206 -365.497872) (xy 313.324467 -365.498311) (xy 313.36028 -365.50548)
			(xy 313.394004 -365.519501) (xy 313.424343 -365.539836) (xy 313.437524 -365.552482) (xy 313.453526 -365.568738)
			(xy 313.454034 -365.569246) (xy 313.533028 -365.64824) (xy 313.540388 -365.65488) (xy 313.558688 -365.662444)
			(xy 313.568588 -365.662972) (xy 316.42431 -365.662972) (xy 316.43462 -365.662505) (xy 316.453578 -365.654396)
			(xy 316.467792 -365.639459) (xy 316.471808 -365.629952) (xy 316.481206 -365.603028) (xy 316.4842 -365.591034)
			(xy 316.479811 -365.566746) (xy 316.472824 -365.556546) (xy 316.466474 -365.55045) (xy 315.398658 -364.482634)
			(xy 315.394542 -364.47953) (xy 315.385325 -364.474912) (xy 315.38037 -364.47349) (xy 315.367162 -364.471712)
			(xy 312.11393 -364.471712) (xy 312.089403 -364.471213) (xy 312.040956 -364.463514) (xy 311.994305 -364.448347)
			(xy 311.950593 -364.426083) (xy 311.910892 -364.39727) (xy 311.893204 -364.380272) (xy 311.74563 -364.232698)
			(xy 311.73674 -364.225586) (xy 311.733067 -364.223364) (xy 311.725153 -364.220037) (xy 311.720992 -364.218982)
			(xy 311.709562 -364.217712) (xy 308.55412 -364.217712) (xy 308.54269 -364.218982) (xy 308.533531 -364.221485)
			(xy 308.517861 -364.232181) (xy 308.51221 -364.23981) (xy 308.464712 -364.308644) (xy 308.461349 -364.313761)
			(xy 308.456971 -364.325193) (xy 308.456076 -364.33125) (xy 308.454552 -364.343442) (xy 308.45887 -364.355126)
			(xy 308.45887 -364.355634) (xy 308.470332 -364.388037) (xy 308.482722 -364.455638) (xy 308.483508 -364.49)
			(xy 308.483022 -364.517251) (xy 308.475266 -364.571199) (xy 308.459911 -364.623494) (xy 308.437269 -364.673071)
			(xy 308.407803 -364.718921) (xy 308.386073 -364.744) (xy 309.370982 -364.744) (xy 309.375053 -364.688378)
			(xy 309.387179 -364.633941) (xy 309.407102 -364.58185) (xy 309.434398 -364.533215) (xy 309.468484 -364.489072)
			(xy 309.508633 -364.450363) (xy 309.553991 -364.417912) (xy 309.603591 -364.392411) (xy 309.656375 -364.374404)
			(xy 309.711218 -364.364274) (xy 309.766952 -364.362237) (xy 309.822389 -364.368337) (xy 309.876346 -364.382443)
			(xy 309.927675 -364.404255) (xy 309.975281 -364.433309) (xy 310.018149 -364.468984) (xy 310.055366 -364.510521)
			(xy 310.086139 -364.557034) (xy 310.109811 -364.607531) (xy 310.125879 -364.660938) (xy 310.133999 -364.716114)
			(xy 310.134508 -364.744) (xy 310.133999 -364.771886) (xy 310.125879 -364.827062) (xy 310.109811 -364.880469)
			(xy 310.086139 -364.930966) (xy 310.055366 -364.977479) (xy 310.0256 -365.0107) (xy 314.463682 -365.0107)
			(xy 314.467753 -364.955078) (xy 314.479879 -364.900641) (xy 314.499802 -364.84855) (xy 314.527098 -364.799915)
			(xy 314.561184 -364.755772) (xy 314.601333 -364.717063) (xy 314.646691 -364.684612) (xy 314.696291 -364.659111)
			(xy 314.749075 -364.641104) (xy 314.803918 -364.630974) (xy 314.859652 -364.628937) (xy 314.915089 -364.635037)
			(xy 314.969046 -364.649143) (xy 315.020375 -364.670955) (xy 315.067981 -364.700009) (xy 315.110849 -364.735684)
			(xy 315.148066 -364.777221) (xy 315.178839 -364.823734) (xy 315.202511 -364.874231) (xy 315.218579 -364.927638)
			(xy 315.226699 -364.982814) (xy 315.227208 -365.0107) (xy 315.226699 -365.038586) (xy 315.218579 -365.093762)
			(xy 315.202511 -365.147169) (xy 315.178839 -365.197666) (xy 315.148066 -365.244179) (xy 315.110849 -365.285716)
			(xy 315.067981 -365.321391) (xy 315.020375 -365.350445) (xy 314.969046 -365.372257) (xy 314.915089 -365.386363)
			(xy 314.859652 -365.392463) (xy 314.803918 -365.390426) (xy 314.749075 -365.380296) (xy 314.696291 -365.362289)
			(xy 314.646691 -365.336788) (xy 314.601333 -365.304337) (xy 314.561184 -365.265628) (xy 314.527098 -365.221485)
			(xy 314.499802 -365.17285) (xy 314.479879 -365.120759) (xy 314.467753 -365.066322) (xy 314.463682 -365.0107)
			(xy 310.0256 -365.0107) (xy 310.018149 -365.019016) (xy 309.975281 -365.054691) (xy 309.927675 -365.083745)
			(xy 309.876346 -365.105557) (xy 309.822389 -365.119663) (xy 309.766952 -365.125763) (xy 309.711218 -365.123726)
			(xy 309.656375 -365.113596) (xy 309.603591 -365.095589) (xy 309.553991 -365.070088) (xy 309.508633 -365.037637)
			(xy 309.468484 -364.998928) (xy 309.434398 -364.954785) (xy 309.407102 -364.90615) (xy 309.387179 -364.854059)
			(xy 309.375053 -364.799622) (xy 309.370982 -364.744) (xy 308.386073 -364.744) (xy 308.372112 -364.760112)
			(xy 308.330921 -364.795803) (xy 308.285071 -364.825269) (xy 308.235494 -364.847911) (xy 308.183199 -364.863266)
			(xy 308.129251 -364.871022) (xy 308.102 -364.871508) (xy 308.102 -364.871762) (xy 308.075534 -364.871271)
			(xy 308.023118 -364.863888) (xy 307.972222 -364.849344) (xy 307.923819 -364.82792) (xy 307.901086 -364.814358)
			(xy 307.900578 -364.814358) (xy 307.900324 -364.814104) (xy 307.894717 -364.810918) (xy 307.882373 -364.807194)
			(xy 307.87594 -364.806738) (xy 307.862986 -364.80623) (xy 307.773324 -364.852458) (xy 307.767558 -364.855678)
			(xy 307.757793 -364.864562) (xy 307.75402 -364.869984) (xy 307.746908 -364.880906) (xy 307.746146 -364.894368)
			(xy 307.743857 -364.92309) (xy 307.731721 -364.979415) (xy 307.711255 -365.033276) (xy 307.682924 -365.083446)
			(xy 307.647372 -365.128787) (xy 307.605406 -365.168267) (xy 307.557982 -365.200988) (xy 307.506177 -365.226207)
			(xy 307.451169 -365.243351) (xy 307.394209 -365.252029) (xy 307.3654 -365.252508) (xy 307.338149 -365.252022)
			(xy 307.284201 -365.244266) (xy 307.231906 -365.228911) (xy 307.182329 -365.206269) (xy 307.136479 -365.176803)
			(xy 307.095288 -365.141112) (xy 307.059597 -365.099921) (xy 307.030131 -365.054071) (xy 307.007489 -365.004494)
			(xy 306.992134 -364.952199) (xy 306.984378 -364.898251) (xy 306.984378 -364.843749) (xy 306.992134 -364.789801)
			(xy 307.007489 -364.737506) (xy 307.030131 -364.687929) (xy 307.059597 -364.642079) (xy 307.095288 -364.600888)
			(xy 307.136479 -364.565197) (xy 307.182329 -364.535731) (xy 307.231906 -364.513089) (xy 307.284201 -364.497734)
			(xy 307.338149 -364.489978) (xy 307.3654 -364.489492) (xy 307.3654 -364.489238) (xy 307.391866 -364.489729)
			(xy 307.444282 -364.497112) (xy 307.495178 -364.511656) (xy 307.543581 -364.53308) (xy 307.566314 -364.546642)
			(xy 307.566822 -364.546642) (xy 307.567076 -364.546896) (xy 307.572683 -364.550082) (xy 307.585027 -364.553806)
			(xy 307.59146 -364.554262) (xy 307.604414 -364.55477) (xy 307.694076 -364.508542) (xy 307.699842 -364.505322)
			(xy 307.709607 -364.496438) (xy 307.71338 -364.491016) (xy 307.720492 -364.480094) (xy 307.721254 -364.466632)
			(xy 307.723568 -364.438218) (xy 307.735557 -364.382487) (xy 307.74513 -364.355634) (xy 307.74513 -364.355126)
			(xy 307.745384 -364.354872) (xy 307.747242 -364.349161) (xy 307.748532 -364.337224) (xy 307.747924 -364.33125)
			(xy 307.7464 -364.318804) (xy 307.69179 -364.23981) (xy 307.686112 -364.232208) (xy 307.670455 -364.221512)
			(xy 307.66131 -364.218982) (xy 307.64988 -364.217712) (xy 307.11013 -364.217712) (xy 307.085603 -364.217213)
			(xy 307.037156 -364.209514) (xy 306.990505 -364.194347) (xy 306.946793 -364.172083) (xy 306.907092 -364.14327)
			(xy 306.889404 -364.126272) (xy 306.325778 -363.562646) (xy 306.318381 -363.555798) (xy 306.299782 -363.548064)
			(xy 306.28971 -363.54766) (xy 305.869594 -363.54766) (xy 305.856866 -363.54837) (xy 305.834492 -363.560514)
			(xy 305.826922 -363.570774) (xy 305.773328 -363.653324) (xy 305.771296 -363.678724) (xy 305.77663 -363.690662)
			(xy 305.787221 -363.715327) (xy 305.80215 -363.766887) (xy 305.809691 -363.820033) (xy 305.810158 -363.846872)
			(xy 305.809672 -363.874123) (xy 305.801916 -363.928071) (xy 305.786561 -363.980366) (xy 305.763919 -364.029943)
			(xy 305.734453 -364.075793) (xy 305.698762 -364.116984) (xy 305.657571 -364.152675) (xy 305.611721 -364.182141)
			(xy 305.562144 -364.204783) (xy 305.509849 -364.220138) (xy 305.455901 -364.227894) (xy 305.401399 -364.227894)
			(xy 305.347451 -364.220138) (xy 305.295156 -364.204783) (xy 305.245579 -364.182141) (xy 305.199729 -364.152675)
			(xy 305.158538 -364.116984) (xy 305.122847 -364.075793) (xy 305.093381 -364.029943) (xy 305.070739 -363.980366)
			(xy 305.055384 -363.928071) (xy 305.047628 -363.874123) (xy 305.047142 -363.846872) (xy 305.047731 -363.817097)
			(xy 305.057042 -363.758278) (xy 305.065684 -363.729778) (xy 305.068882 -363.717584) (xy 305.06434 -363.692819)
			(xy 305.057048 -363.682534) (xy 305.03935 -363.659393) (xy 305.010452 -363.608811) (xy 304.989592 -363.554419)
			(xy 304.98288 -363.52607) (xy 304.980378 -363.516605) (xy 304.969404 -363.500412) (xy 304.961544 -363.494574)
			(xy 304.948997 -363.485937) (xy 304.925463 -363.466597) (xy 304.914554 -363.455966) (xy 304.142902 -362.684314)
			(xy 304.135504 -362.677466) (xy 304.116906 -362.669729) (xy 304.106834 -362.669328) (xy 302.6918 -362.669328)
			(xy 302.667209 -362.668871) (xy 302.618632 -362.661175) (xy 302.571858 -362.645972) (xy 302.52804 -362.623638)
			(xy 302.488255 -362.594722) (xy 302.470566 -362.577634) (xy 302.45304 -362.559854) (xy 302.44034 -362.552996)
			(xy 302.432974 -362.551472) (xy 302.404962 -362.544855) (xy 302.351188 -362.524332) (xy 302.301107 -362.495963)
			(xy 302.255858 -362.460393) (xy 302.216465 -362.418428) (xy 302.183825 -362.371021) (xy 302.158678 -362.319248)
			(xy 302.141594 -362.264285) (xy 302.132961 -362.207379) (xy 302.132492 -362.1786) (xy 302.132978 -362.151349)
			(xy 302.140734 -362.097401) (xy 302.156089 -362.045106) (xy 302.178731 -361.995529) (xy 302.208197 -361.949679)
			(xy 302.243888 -361.908488) (xy 302.285079 -361.872797) (xy 302.330929 -361.843331) (xy 302.380506 -361.820689)
			(xy 302.432801 -361.805334) (xy 302.486749 -361.797578) (xy 302.514 -361.797092) (xy 302.514254 -361.797092)
			(xy 302.54147 -361.797551) (xy 302.595349 -361.805293) (xy 302.647577 -361.820626) (xy 302.697091 -361.843236)
			(xy 302.720248 -361.857544) (xy 302.726852 -361.861862) (xy 302.733456 -361.86364) (xy 302.747426 -361.865672)
			(xy 302.797972 -361.865672) (xy 302.809656 -361.864402) (xy 302.816948 -361.862408) (xy 302.829999 -361.854795)
			(xy 302.83531 -361.849416) (xy 302.886618 -361.789726) (xy 302.889984 -361.785593) (xy 302.895098 -361.776243)
			(xy 302.896778 -361.771184) (xy 302.899826 -361.761278) (xy 302.898048 -361.748832) (xy 302.896359 -361.735754)
			(xy 302.894583 -361.709441) (xy 302.894492 -361.696254) (xy 302.894492 -361.694476) (xy 302.895081 -361.667296)
			(xy 302.903014 -361.613513) (xy 302.9185 -361.561401) (xy 302.941228 -361.512015) (xy 302.970736 -361.466356)
			(xy 303.006426 -361.425347) (xy 303.047577 -361.389821) (xy 303.093354 -361.360495) (xy 303.14283 -361.337966)
			(xy 303.195004 -361.322687) (xy 303.248818 -361.31497) (xy 303.276 -361.314492) (xy 303.302459 -361.314943)
			(xy 303.354869 -361.322253) (xy 303.405767 -361.336732) (xy 303.454177 -361.358103) (xy 303.476914 -361.371642)
			(xy 303.48301 -361.375452) (xy 303.502568 -361.38104) (xy 303.516538 -361.383072) (xy 304.06594 -361.383072)
			(xy 304.078431 -361.382385) (xy 304.100428 -361.370534) (xy 304.10785 -361.360466) (xy 304.154078 -361.28452)
			(xy 304.157264 -361.278913) (xy 304.160989 -361.266569) (xy 304.161444 -361.260136) (xy 304.161952 -361.247182)
			(xy 304.155856 -361.235244) (xy 304.142582 -361.208136) (xy 304.123801 -361.150776) (xy 304.114269 -361.091178)
			(xy 304.113692 -361.061) (xy 304.114178 -361.033749) (xy 304.121934 -360.979801) (xy 304.137289 -360.927506)
			(xy 304.159931 -360.877929) (xy 304.189397 -360.832079) (xy 304.225088 -360.790888) (xy 304.266279 -360.755197)
			(xy 304.312129 -360.725731) (xy 304.361706 -360.703089) (xy 304.414001 -360.687734) (xy 304.467949 -360.679978)
			(xy 304.522451 -360.679978) (xy 304.576399 -360.687734) (xy 304.628694 -360.703089) (xy 304.678271 -360.725731)
			(xy 304.724121 -360.755197) (xy 304.765312 -360.790888) (xy 304.801003 -360.832079) (xy 304.830469 -360.877929)
			(xy 304.853111 -360.927506) (xy 304.868466 -360.979801) (xy 304.876222 -361.033749) (xy 304.876708 -361.061)
			(xy 304.876139 -361.09118) (xy 304.866631 -361.150785) (xy 304.847836 -361.208143) (xy 304.834544 -361.235244)
			(xy 304.831757 -361.24114) (xy 304.828927 -361.253868) (xy 304.828956 -361.26039) (xy 304.829464 -361.273344)
			(xy 304.88255 -361.360466) (xy 304.890024 -361.370473) (xy 304.911992 -361.382298) (xy 304.92446 -361.383072)
			(xy 305.04892 -361.383072) (xy 305.05767 -361.382672) (xy 305.074122 -361.376701) (xy 305.0876 -361.365535)
			(xy 305.092354 -361.35818) (xy 305.095656 -361.352338) (xy 305.13655 -361.282234) (xy 305.139749 -361.276436)
			(xy 305.143364 -361.263702) (xy 305.143662 -361.257088) (xy 305.143662 -361.24388) (xy 305.137058 -361.231942)
			(xy 305.125465 -361.210477) (xy 305.10722 -361.165232) (xy 305.094886 -361.118032) (xy 305.088665 -361.069645)
			(xy 305.08829 -361.045252) (xy 305.088779 -361.018003) (xy 305.096541 -360.96406) (xy 305.1119 -360.911771)
			(xy 305.134544 -360.8622) (xy 305.164012 -360.816355) (xy 305.199703 -360.775171) (xy 305.240892 -360.739484)
			(xy 305.28674 -360.710022) (xy 305.336314 -360.687384) (xy 305.388605 -360.672031) (xy 305.442549 -360.664276)
			(xy 305.469798 -360.663744) (xy 305.497746 -360.66424) (xy 305.553042 -360.672412) (xy 305.606554 -360.688565)
			(xy 305.657135 -360.712356) (xy 305.703703 -360.743273) (xy 305.74526 -360.780655) (xy 305.780917 -360.823702)
			(xy 305.80991 -360.871492) (xy 305.831618 -360.923001) (xy 305.845576 -360.977126) (xy 305.84902 -361.004866)
			(xy 305.850294 -361.013339) (xy 305.857708 -361.028774) (xy 305.863498 -361.035092) (xy 305.883931 -361.056642)
			(xy 305.918546 -361.104893) (xy 305.945269 -361.157923) (xy 305.963457 -361.214452) (xy 305.972669 -361.273117)
			(xy 305.972797 -361.279948) (xy 314.255656 -361.279948) (xy 314.259727 -361.224326) (xy 314.271853 -361.169889)
			(xy 314.291776 -361.117798) (xy 314.319072 -361.069163) (xy 314.353158 -361.02502) (xy 314.393307 -360.986311)
			(xy 314.438665 -360.95386) (xy 314.488265 -360.928359) (xy 314.541049 -360.910352) (xy 314.595892 -360.900222)
			(xy 314.651626 -360.898185) (xy 314.707063 -360.904285) (xy 314.76102 -360.918391) (xy 314.812349 -360.940203)
			(xy 314.859955 -360.969257) (xy 314.902823 -361.004932) (xy 314.94004 -361.046469) (xy 314.970813 -361.092982)
			(xy 314.994485 -361.143479) (xy 315.010553 -361.196886) (xy 315.018673 -361.252062) (xy 315.019182 -361.279948)
			(xy 315.018673 -361.307834) (xy 315.010553 -361.36301) (xy 314.994485 -361.416417) (xy 314.970813 -361.466914)
			(xy 314.94004 -361.513427) (xy 314.902823 -361.554964) (xy 314.859955 -361.590639) (xy 314.846717 -361.598718)
			(xy 321.434966 -361.598718) (xy 321.439037 -361.543096) (xy 321.451163 -361.488659) (xy 321.471086 -361.436568)
			(xy 321.498382 -361.387933) (xy 321.532468 -361.34379) (xy 321.572617 -361.305081) (xy 321.617975 -361.27263)
			(xy 321.667575 -361.247129) (xy 321.720359 -361.229122) (xy 321.775202 -361.218992) (xy 321.830936 -361.216955)
			(xy 321.886373 -361.223055) (xy 321.94033 -361.237161) (xy 321.991659 -361.258973) (xy 322.039265 -361.288027)
			(xy 322.082133 -361.323702) (xy 322.11935 -361.365239) (xy 322.150123 -361.411752) (xy 322.173795 -361.462249)
			(xy 322.189863 -361.515656) (xy 322.197983 -361.570832) (xy 322.198492 -361.598718) (xy 322.197983 -361.626604)
			(xy 322.189863 -361.68178) (xy 322.173795 -361.735187) (xy 322.150123 -361.785684) (xy 322.11935 -361.832197)
			(xy 322.082133 -361.873734) (xy 322.039265 -361.909409) (xy 321.991659 -361.938463) (xy 321.94033 -361.960275)
			(xy 321.886373 -361.974381) (xy 321.830936 -361.980481) (xy 321.775202 -361.978444) (xy 321.720359 -361.968314)
			(xy 321.667575 -361.950307) (xy 321.617975 -361.924806) (xy 321.572617 -361.892355) (xy 321.532468 -361.853646)
			(xy 321.498382 -361.809503) (xy 321.471086 -361.760868) (xy 321.451163 -361.708777) (xy 321.439037 -361.65434)
			(xy 321.434966 -361.598718) (xy 314.846717 -361.598718) (xy 314.812349 -361.619693) (xy 314.76102 -361.641505)
			(xy 314.707063 -361.655611) (xy 314.651626 -361.661711) (xy 314.595892 -361.659674) (xy 314.541049 -361.649544)
			(xy 314.488265 -361.631537) (xy 314.438665 -361.606036) (xy 314.393307 -361.573585) (xy 314.353158 -361.534876)
			(xy 314.319072 -361.490733) (xy 314.291776 -361.442098) (xy 314.271853 -361.390007) (xy 314.259727 -361.33557)
			(xy 314.255656 -361.279948) (xy 305.972797 -361.279948) (xy 305.973226 -361.302808) (xy 305.97281 -361.328424)
			(xy 305.965948 -361.379195) (xy 305.952348 -361.428589) (xy 305.932254 -361.475716) (xy 305.906031 -361.519728)
			(xy 305.890422 -361.540044) (xy 305.885138 -361.5473) (xy 305.879543 -361.564343) (xy 305.8795 -361.573318)
			(xy 305.880262 -361.60329) (xy 305.88101 -361.612887) (xy 305.888711 -361.630514) (xy 305.895248 -361.63758)
			(xy 307.04663 -362.788962) (xy 320.244722 -362.788962) (xy 320.248793 -362.73334) (xy 320.260919 -362.678903)
			(xy 320.280842 -362.626812) (xy 320.308138 -362.578177) (xy 320.342224 -362.534034) (xy 320.382373 -362.495325)
			(xy 320.427731 -362.462874) (xy 320.477331 -362.437373) (xy 320.530115 -362.419366) (xy 320.584958 -362.409236)
			(xy 320.640692 -362.407199) (xy 320.696129 -362.413299) (xy 320.750086 -362.427405) (xy 320.801415 -362.449217)
			(xy 320.849021 -362.478271) (xy 320.891889 -362.513946) (xy 320.929106 -362.555483) (xy 320.959879 -362.601996)
			(xy 320.983551 -362.652493) (xy 320.999619 -362.7059) (xy 321.007739 -362.761076) (xy 321.008248 -362.788962)
			(xy 321.007739 -362.816848) (xy 320.999619 -362.872024) (xy 320.983551 -362.925431) (xy 320.959879 -362.975928)
			(xy 320.929106 -363.022441) (xy 320.891889 -363.063978) (xy 320.849021 -363.099653) (xy 320.801415 -363.128707)
			(xy 320.750086 -363.150519) (xy 320.696129 -363.164625) (xy 320.640692 -363.170725) (xy 320.584958 -363.168688)
			(xy 320.530115 -363.158558) (xy 320.477331 -363.140551) (xy 320.427731 -363.11505) (xy 320.382373 -363.082599)
			(xy 320.342224 -363.04389) (xy 320.308138 -362.999747) (xy 320.280842 -362.951112) (xy 320.260919 -362.899021)
			(xy 320.248793 -362.844584) (xy 320.244722 -362.788962) (xy 307.04663 -362.788962) (xy 307.404008 -363.14634)
			(xy 307.411367 -363.152983) (xy 307.429667 -363.160554) (xy 307.439568 -363.161072) (xy 312.039 -363.161072)
			(xy 312.063591 -363.161529) (xy 312.112168 -363.169225) (xy 312.158942 -363.184428) (xy 312.20276 -363.206762)
			(xy 312.242545 -363.235678) (xy 312.246036 -363.23905) (xy 318.698878 -363.23905) (xy 318.702949 -363.183428)
			(xy 318.715075 -363.128991) (xy 318.734998 -363.0769) (xy 318.762294 -363.028265) (xy 318.79638 -362.984122)
			(xy 318.836529 -362.945413) (xy 318.881887 -362.912962) (xy 318.931487 -362.887461) (xy 318.984271 -362.869454)
			(xy 319.039114 -362.859324) (xy 319.094848 -362.857287) (xy 319.150285 -362.863387) (xy 319.204242 -362.877493)
			(xy 319.255571 -362.899305) (xy 319.303177 -362.928359) (xy 319.346045 -362.964034) (xy 319.383262 -363.005571)
			(xy 319.414035 -363.052084) (xy 319.437707 -363.102581) (xy 319.453775 -363.155988) (xy 319.461895 -363.211164)
			(xy 319.462404 -363.23905) (xy 319.461895 -363.266936) (xy 319.453775 -363.322112) (xy 319.437707 -363.375519)
			(xy 319.414035 -363.426016) (xy 319.383262 -363.472529) (xy 319.346045 -363.514066) (xy 319.303177 -363.549741)
			(xy 319.255571 -363.578795) (xy 319.204242 -363.600607) (xy 319.150285 -363.614713) (xy 319.094848 -363.620813)
			(xy 319.039114 -363.618776) (xy 318.984271 -363.608646) (xy 318.931487 -363.590639) (xy 318.881887 -363.565138)
			(xy 318.836529 -363.532687) (xy 318.79638 -363.493978) (xy 318.762294 -363.449835) (xy 318.734998 -363.4012)
			(xy 318.715075 -363.349109) (xy 318.702949 -363.294672) (xy 318.698878 -363.23905) (xy 312.246036 -363.23905)
			(xy 312.260234 -363.252766) (xy 312.407808 -363.40034) (xy 312.415167 -363.406983) (xy 312.433467 -363.414554)
			(xy 312.443368 -363.415072) (xy 315.6966 -363.415072) (xy 315.721191 -363.415529) (xy 315.769768 -363.423225)
			(xy 315.816542 -363.438428) (xy 315.86036 -363.460762) (xy 315.900145 -363.489678) (xy 315.917834 -363.506766)
			(xy 316.981332 -364.570264) (xy 316.988688 -364.576912) (xy 317.00699 -364.584486) (xy 317.016892 -364.584996)
			(xy 318.708786 -364.584996) (xy 318.720228 -364.584299) (xy 318.740807 -364.574272) (xy 318.74841 -364.565692)
			(xy 318.749172 -364.56493) (xy 318.79794 -364.501938) (xy 318.801384 -364.497202) (xy 318.806257 -364.486557)
			(xy 318.807592 -364.480856) (xy 318.809878 -364.469934) (xy 318.80683 -364.458504) (xy 318.801194 -364.435033)
			(xy 318.795206 -364.387136) (xy 318.794892 -364.363) (xy 318.795378 -364.335749) (xy 318.803134 -364.281801)
			(xy 318.818489 -364.229506) (xy 318.841131 -364.179929) (xy 318.870597 -364.134079) (xy 318.906288 -364.092888)
			(xy 318.947479 -364.057197) (xy 318.993329 -364.027731) (xy 319.042906 -364.005089) (xy 319.095201 -363.989734)
			(xy 319.149149 -363.981978) (xy 319.203651 -363.981978) (xy 319.257599 -363.989734) (xy 319.309894 -364.005089)
			(xy 319.359471 -364.027731) (xy 319.405321 -364.057197) (xy 319.446512 -364.092888) (xy 319.482203 -364.134079)
			(xy 319.511669 -364.179929) (xy 319.534311 -364.229506) (xy 319.549666 -364.281801) (xy 319.557422 -364.335749)
			(xy 319.557908 -364.363) (xy 319.557584 -364.387135) (xy 319.551594 -364.435031) (xy 319.54597 -364.458504)
			(xy 319.542922 -364.469934) (xy 319.545208 -364.480856) (xy 319.546494 -364.486575) (xy 319.551366 -364.497232)
			(xy 319.55486 -364.501938) (xy 319.603628 -364.56493) (xy 319.60439 -364.565692) (xy 319.611915 -364.574369)
			(xy 319.632543 -364.584419) (xy 319.644014 -364.584996) (xy 320.269108 -364.584996) (xy 320.279006 -364.584475)
			(xy 320.297298 -364.576892) (xy 320.304668 -364.570264) (xy 323.628766 -361.246166) (xy 323.646467 -361.22909)
			(xy 323.686243 -361.200163) (xy 323.730058 -361.177822) (xy 323.776831 -361.16262) (xy 323.825409 -361.154932)
			(xy 323.85 -361.154472) (xy 326.809862 -361.154472) (xy 326.823832 -361.15244) (xy 326.84339 -361.146852)
			(xy 326.849486 -361.143042) (xy 326.872222 -361.129502) (xy 326.920634 -361.108136) (xy 326.971532 -361.093661)
			(xy 327.023942 -361.086353) (xy 327.0504 -361.085892) (xy 327.077651 -361.086378) (xy 327.131599 -361.094134)
			(xy 327.183894 -361.109489) (xy 327.233471 -361.132131) (xy 327.279321 -361.161597) (xy 327.320512 -361.197288)
			(xy 327.356203 -361.238479) (xy 327.385669 -361.284329) (xy 327.408311 -361.333906) (xy 327.423666 -361.386201)
			(xy 327.431422 -361.440149) (xy 327.431908 -361.4674) (xy 327.431363 -361.496171) (xy 327.422684 -361.553056)
			(xy 327.414636 -361.580684) (xy 327.414636 -361.581192) (xy 327.41108 -361.592622) (xy 327.412858 -361.604052)
			(xy 327.414043 -361.610003) (xy 327.4188 -361.621162) (xy 327.422256 -361.62615) (xy 327.47077 -361.691936)
			(xy 327.477454 -361.700202) (xy 327.495833 -361.710833) (xy 327.50633 -361.71251) (xy 327.511918 -361.712764)
			(xy 328.574146 -361.712764) (xy 328.598674 -361.713261) (xy 328.647123 -361.720957) (xy 328.693777 -361.73612)
			(xy 328.737493 -361.75838) (xy 328.777198 -361.78719) (xy 328.794872 -361.804204) (xy 328.92238 -361.931712)
			(xy 329.240642 -362.24972) (xy 329.251818 -362.258356) (xy 329.257152 -362.26115) (xy 329.265026 -362.262928)
			(xy 329.293038 -362.269545) (xy 329.346812 -362.290068) (xy 329.396893 -362.318437) (xy 329.442142 -362.354007)
			(xy 329.481535 -362.395972) (xy 329.514175 -362.443379) (xy 329.539322 -362.495152) (xy 329.556406 -362.550115)
			(xy 329.565039 -362.607021) (xy 329.565508 -362.6358) (xy 329.565022 -362.663051) (xy 329.557266 -362.716999)
			(xy 329.541911 -362.769294) (xy 329.519269 -362.818871) (xy 329.489803 -362.864721) (xy 329.454112 -362.905912)
			(xy 329.412921 -362.941603) (xy 329.367071 -362.971069) (xy 329.317494 -362.993711) (xy 329.265199 -363.009066)
			(xy 329.211251 -363.016822) (xy 329.184 -363.017308) (xy 329.15523 -363.016777) (xy 329.098343 -363.008124)
			(xy 329.043401 -362.991027) (xy 328.991648 -362.965875) (xy 328.944258 -362.933239) (xy 328.902305 -362.893857)
			(xy 328.86674 -362.848623) (xy 328.83837 -362.798563) (xy 328.817837 -362.74481) (xy 328.811128 -362.716826)
			(xy 328.80935 -362.708952) (xy 328.806302 -362.703364) (xy 328.804506 -362.700249) (xy 328.800175 -362.69451)
			(xy 328.797666 -362.691934) (xy 328.45883 -362.353098) (xy 328.44994 -362.345986) (xy 328.446267 -362.343764)
			(xy 328.438353 -362.340437) (xy 328.434192 -362.339382) (xy 328.422762 -362.338112) (xy 327.50252 -362.338112)
			(xy 327.49109 -362.339382) (xy 327.481931 -362.341885) (xy 327.466261 -362.352581) (xy 327.46061 -362.36021)
			(xy 327.413112 -362.429044) (xy 327.409749 -362.434161) (xy 327.405371 -362.445593) (xy 327.404476 -362.45165)
			(xy 327.402952 -362.463842) (xy 327.40727 -362.475526) (xy 327.40727 -362.476034) (xy 327.418732 -362.508437)
			(xy 327.431122 -362.576038) (xy 327.431908 -362.6104) (xy 327.431422 -362.637651) (xy 327.423666 -362.691599)
			(xy 327.408311 -362.743894) (xy 327.385669 -362.793471) (xy 327.356203 -362.839321) (xy 327.320512 -362.880512)
			(xy 327.279321 -362.916203) (xy 327.233471 -362.945669) (xy 327.183894 -362.968311) (xy 327.131599 -362.983666)
			(xy 327.077651 -362.991422) (xy 327.0504 -362.991908) (xy 327.023926 -362.991462) (xy 326.971485 -362.984154)
			(xy 326.920558 -362.969665) (xy 326.872125 -362.948272) (xy 326.827115 -362.920388) (xy 326.786393 -362.886547)
			(xy 326.750742 -362.8474) (xy 326.73544 -362.825792) (xy 326.730614 -362.818934) (xy 326.69988 -362.802424)
			(xy 326.69425 -362.799604) (xy 326.682044 -362.79653) (xy 326.67575 -362.796328) (xy 324.061836 -362.796328)
			(xy 324.051935 -362.796842) (xy 324.033634 -362.804416) (xy 324.026276 -362.81106) (xy 323.612036 -363.225334)
			(xy 356.693976 -363.225334) (xy 356.698047 -363.169712) (xy 356.710173 -363.115275) (xy 356.730096 -363.063184)
			(xy 356.757392 -363.014549) (xy 356.791478 -362.970406) (xy 356.831627 -362.931697) (xy 356.876985 -362.899246)
			(xy 356.926585 -362.873745) (xy 356.979369 -362.855738) (xy 357.034212 -362.845608) (xy 357.089946 -362.843571)
			(xy 357.145383 -362.849671) (xy 357.19934 -362.863777) (xy 357.250669 -362.885589) (xy 357.298275 -362.914643)
			(xy 357.341143 -362.950318) (xy 357.37836 -362.991855) (xy 357.409133 -363.038368) (xy 357.432805 -363.088865)
			(xy 357.448873 -363.142272) (xy 357.456993 -363.197448) (xy 357.457502 -363.225334) (xy 357.456993 -363.25322)
			(xy 357.448873 -363.308396) (xy 357.432805 -363.361803) (xy 357.409133 -363.4123) (xy 357.37836 -363.458813)
			(xy 357.341143 -363.50035) (xy 357.298275 -363.536025) (xy 357.250669 -363.565079) (xy 357.19934 -363.586891)
			(xy 357.145383 -363.600997) (xy 357.089946 -363.607097) (xy 357.034212 -363.60506) (xy 356.979369 -363.59493)
			(xy 356.926585 -363.576923) (xy 356.876985 -363.551422) (xy 356.831627 -363.518971) (xy 356.791478 -363.480262)
			(xy 356.757392 -363.436119) (xy 356.730096 -363.387484) (xy 356.710173 -363.335393) (xy 356.698047 -363.280956)
			(xy 356.693976 -363.225334) (xy 323.612036 -363.225334) (xy 320.968624 -365.868966) (xy 320.96195 -365.876367)
			(xy 320.954367 -365.894776) (xy 320.95438 -365.914686) (xy 320.957702 -365.924084) (xy 320.963544 -365.938562)
			(xy 320.989198 -365.95558) (xy 321.468242 -365.95558) (xy 321.478308 -365.955149) (xy 321.4969 -365.947421)
			(xy 321.50431 -365.940594) (xy 323.886576 -363.558328) (xy 323.889107 -363.555701) (xy 323.893448 -363.549837)
			(xy 323.895212 -363.546644) (xy 323.909639 -363.521103) (xy 323.945112 -363.474387) (xy 323.987313 -363.433647)
			(xy 324.035249 -363.399841) (xy 324.087791 -363.373765) (xy 324.143704 -363.356032) (xy 324.201671 -363.347061)
			(xy 324.231 -363.346492) (xy 324.256952 -363.34693) (xy 324.308377 -363.353971) (xy 324.358372 -363.367922)
			(xy 324.406012 -363.388526) (xy 324.450416 -363.415403) (xy 324.490765 -363.448054) (xy 324.526311 -363.485876)
			(xy 324.556398 -363.528171) (xy 324.56882 -363.550962) (xy 324.57263 -363.55782) (xy 324.581012 -363.566202)
			(xy 324.588144 -363.571789) (xy 324.605149 -363.578002) (xy 324.623254 -363.57793) (xy 324.64021 -363.571581)
			(xy 324.647306 -363.565948) (xy 324.660006 -363.552994) (xy 324.663562 -363.546644) (xy 324.663816 -363.546136)
			(xy 324.678256 -363.520647) (xy 324.713737 -363.474032) (xy 324.755923 -363.433386) (xy 324.803824 -363.399663)
			(xy 324.856316 -363.373654) (xy 324.912164 -363.35597) (xy 324.970059 -363.347027) (xy 324.99935 -363.346492)
			(xy 325.027089 -363.346993) (xy 325.081981 -363.355031) (xy 325.135131 -363.370931) (xy 325.18542 -363.394358)
			(xy 325.231787 -363.424818) (xy 325.273257 -363.46167) (xy 325.308955 -363.504136) (xy 325.33813 -363.551323)
			(xy 325.360166 -363.602237) (xy 325.373521 -363.6518) (xy 326.693782 -363.6518) (xy 326.697853 -363.596178)
			(xy 326.709979 -363.541741) (xy 326.729902 -363.48965) (xy 326.757198 -363.441015) (xy 326.791284 -363.396872)
			(xy 326.831433 -363.358163) (xy 326.876791 -363.325712) (xy 326.926391 -363.300211) (xy 326.979175 -363.282204)
			(xy 327.034018 -363.272074) (xy 327.089752 -363.270037) (xy 327.145189 -363.276137) (xy 327.199146 -363.290243)
			(xy 327.250475 -363.312055) (xy 327.298081 -363.341109) (xy 327.340949 -363.376784) (xy 327.378166 -363.418321)
			(xy 327.408939 -363.464834) (xy 327.432611 -363.515331) (xy 327.448679 -363.568738) (xy 327.456799 -363.623914)
			(xy 327.457308 -363.6518) (xy 327.709782 -363.6518) (xy 327.713853 -363.596178) (xy 327.725979 -363.541741)
			(xy 327.745902 -363.48965) (xy 327.773198 -363.441015) (xy 327.807284 -363.396872) (xy 327.847433 -363.358163)
			(xy 327.892791 -363.325712) (xy 327.942391 -363.300211) (xy 327.995175 -363.282204) (xy 328.050018 -363.272074)
			(xy 328.105752 -363.270037) (xy 328.161189 -363.276137) (xy 328.215146 -363.290243) (xy 328.266475 -363.312055)
			(xy 328.314081 -363.341109) (xy 328.356949 -363.376784) (xy 328.394166 -363.418321) (xy 328.424939 -363.464834)
			(xy 328.448611 -363.515331) (xy 328.464679 -363.568738) (xy 328.472799 -363.623914) (xy 328.473308 -363.6518)
			(xy 328.472799 -363.679686) (xy 328.464679 -363.734862) (xy 328.448611 -363.788269) (xy 328.424939 -363.838766)
			(xy 328.394166 -363.885279) (xy 328.356949 -363.926816) (xy 328.314081 -363.962491) (xy 328.266475 -363.991545)
			(xy 328.215146 -364.013357) (xy 328.161189 -364.027463) (xy 328.105752 -364.033563) (xy 328.050018 -364.031526)
			(xy 327.995175 -364.021396) (xy 327.942391 -364.003389) (xy 327.892791 -363.977888) (xy 327.847433 -363.945437)
			(xy 327.807284 -363.906728) (xy 327.773198 -363.862585) (xy 327.745902 -363.81395) (xy 327.725979 -363.761859)
			(xy 327.713853 -363.707422) (xy 327.709782 -363.6518) (xy 327.457308 -363.6518) (xy 327.456799 -363.679686)
			(xy 327.448679 -363.734862) (xy 327.432611 -363.788269) (xy 327.408939 -363.838766) (xy 327.378166 -363.885279)
			(xy 327.340949 -363.926816) (xy 327.298081 -363.962491) (xy 327.250475 -363.991545) (xy 327.199146 -364.013357)
			(xy 327.145189 -364.027463) (xy 327.089752 -364.033563) (xy 327.034018 -364.031526) (xy 326.979175 -364.021396)
			(xy 326.926391 -364.003389) (xy 326.876791 -363.977888) (xy 326.831433 -363.945437) (xy 326.791284 -363.906728)
			(xy 326.757198 -363.862585) (xy 326.729902 -363.81395) (xy 326.709979 -363.761859) (xy 326.697853 -363.707422)
			(xy 326.693782 -363.6518) (xy 325.373521 -363.6518) (xy 325.3746 -363.655804) (xy 325.378318 -363.683296)
			(xy 325.379842 -363.69752) (xy 325.381112 -363.728) (xy 325.380567 -363.757171) (xy 325.371707 -363.814836)
			(xy 325.354177 -363.870482) (xy 325.328385 -363.922813) (xy 325.294932 -363.970611) (xy 325.254597 -364.012763)
			(xy 325.208319 -364.048289) (xy 325.182992 -364.062772) (xy 325.180198 -364.064296) (xy 325.172832 -364.06963)
			(xy 325.16699 -364.07471) (xy 322.235068 -367.006632) (xy 322.215473 -367.025486) (xy 322.171709 -367.057755)
			(xy 322.12363 -367.083155) (xy 322.072308 -367.101119) (xy 322.018884 -367.111247) (xy 321.991736 -367.112804)
			(xy 316.103762 -367.112804) (xy 316.098116 -367.11293) (xy 316.087093 -367.115368) (xy 316.081918 -367.11763)
			(xy 316.078686 -367.119273) (xy 316.072687 -367.123347) (xy 316.06998 -367.125758) (xy 315.452506 -367.742978)
			(xy 315.431901 -367.762764) (xy 315.385671 -367.796314) (xy 315.334766 -367.822227) (xy 315.280437 -367.839868)
			(xy 315.224019 -367.848803) (xy 315.195458 -367.849404) (xy 312.854848 -367.849404) (xy 312.844782 -367.849837)
			(xy 312.826192 -367.857565) (xy 312.81878 -367.86439) (xy 312.0009 -368.68227) (xy 311.991094 -368.691966)
			(xy 311.970242 -368.710018) (xy 311.959244 -368.718338) (xy 311.941389 -368.731067) (xy 311.903183 -368.752588)
			(xy 311.883044 -368.761264) (xy 311.254648 -369.02136) (xy 311.246177 -369.025381) (xy 311.232662 -369.038357)
			(xy 311.2247 -369.055316) (xy 311.22335 -369.074003) (xy 311.225692 -369.083082) (xy 311.230772 -369.099846)
			(xy 311.23128 -369.101878) (xy 311.248044 -369.111784) (xy 311.256311 -369.116269) (xy 311.274815 -369.119545)
			(xy 311.284112 -369.118134) (xy 312.775092 -368.821462) (xy 313.160836 -368.745244) (xy 313.933661 -368.599738)
			(xy 314.707937 -368.462161) (xy 315.483582 -368.332529) (xy 316.260516 -368.210854) (xy 317.038656 -368.097151)
			(xy 317.81792 -367.991429) (xy 318.598228 -367.893702) (xy 319.379496 -367.803978) (xy 320.161643 -367.722268)
			(xy 320.944586 -367.64858) (xy 321.728244 -367.582922) (xy 322.512534 -367.5253) (xy 323.297373 -367.475721)
			(xy 324.082679 -367.434189) (xy 324.868369 -367.40071) (xy 325.654361 -367.375287) (xy 326.440573 -367.357922)
			(xy 327.226922 -367.348618) (xy 327.620122 -367.3475) (xy 356.785672 -367.3475) (xy 356.795736 -367.347064)
			(xy 356.814322 -367.339331) (xy 356.82174 -367.332514) (xy 361.00258 -363.151928) (xy 361.028457 -363.12683)
			(xy 361.085366 -363.082577) (xy 361.147326 -363.045727) (xy 361.180126 -363.03077) (xy 361.184412 -363.028757)
			(xy 361.192209 -363.023386) (xy 361.19562 -363.020102) (xy 362.796582 -361.41914) (xy 362.799868 -361.415731)
			(xy 362.80524 -361.407933) (xy 362.80725 -361.403646) (xy 362.822193 -361.370839) (xy 362.859045 -361.308878)
			(xy 362.903298 -361.251967) (xy 362.928408 -361.2261) (xy 365.370872 -358.783382) (xy 365.377719 -358.775984)
			(xy 365.385451 -358.757386) (xy 365.385858 -358.747314) (xy 365.385858 -334.875378) (xy 365.385769 -334.870358)
			(xy 365.383856 -334.860504) (xy 365.382048 -334.85582) (xy 364.618524 -333.012034) (xy 364.616514 -333.007472)
			(xy 364.611011 -332.999162) (xy 364.607602 -332.995524) (xy 359.480612 -327.868534) (xy 359.474104 -327.862449)
			(xy 359.457996 -327.854863) (xy 359.440263 -327.853261) (xy 359.423056 -327.857837) (xy 359.415588 -327.862692)
			(xy 359.391507 -327.878743) (xy 359.339524 -327.904171) (xy 359.2843 -327.921467) (xy 359.227098 -327.930236)
			(xy 359.198164 -327.930764) (xy 359.19791 -327.930764) (xy 359.170658 -327.930301) (xy 359.116708 -327.922545)
			(xy 359.064412 -327.90719) (xy 359.014833 -327.884547) (xy 358.968982 -327.855079) (xy 358.927792 -327.819384)
			(xy 358.892101 -327.778191) (xy 358.862637 -327.732337) (xy 358.839998 -327.682756) (xy 358.824648 -327.630459)
			(xy 358.816896 -327.576508) (xy 358.816402 -327.549256) (xy 358.816402 -327.549002) (xy 358.816933 -327.520065)
			(xy 358.82567 -327.462856) (xy 358.842959 -327.407626) (xy 358.868402 -327.355646) (xy 358.884474 -327.331578)
			(xy 358.889213 -327.324062) (xy 358.893736 -327.306893) (xy 358.892138 -327.28921) (xy 358.88461 -327.27313)
			(xy 358.878632 -327.266554) (xy 358.535986 -326.923908) (xy 358.528587 -326.917063) (xy 358.509989 -326.909332)
			(xy 358.499918 -326.908922) (xy 354.775262 -326.908922) (xy 354.763191 -326.909589) (xy 354.741707 -326.920596)
			(xy 354.734114 -326.930004) (xy 354.713032 -326.95642) (xy 354.712778 -326.956674) (xy 354.707191 -326.96376)
			(xy 354.700943 -326.980677) (xy 354.700586 -326.989694) (xy 354.700586 -327.05675) (xy 354.700954 -327.065763)
			(xy 354.707212 -327.082669) (xy 354.712778 -327.08977) (xy 354.713032 -327.090024) (xy 354.730673 -327.110956)
			(xy 354.760398 -327.156922) (xy 354.783242 -327.206668) (xy 354.798738 -327.259169) (xy 354.806564 -327.313347)
			(xy 354.806562 -327.368087) (xy 354.798731 -327.422264) (xy 354.783231 -327.474763) (xy 354.760382 -327.524507)
			(xy 354.730653 -327.570471) (xy 354.713032 -327.59142) (xy 354.713032 -327.591674) (xy 354.712778 -327.591674)
			(xy 354.707191 -327.59876) (xy 354.700943 -327.615677) (xy 354.700586 -327.624694) (xy 354.700586 -327.69175)
			(xy 354.700954 -327.700763) (xy 354.707212 -327.717669) (xy 354.712778 -327.72477) (xy 354.713032 -327.725024)
			(xy 354.730671 -327.745956) (xy 354.760392 -327.791924) (xy 354.78323 -327.841671) (xy 354.798716 -327.894174)
			(xy 354.80653 -327.948352) (xy 354.807012 -327.975722) (xy 354.806525 -328.002972) (xy 354.798766 -328.056918)
			(xy 354.783409 -328.10921) (xy 354.760766 -328.158785) (xy 354.7313 -328.204633) (xy 354.695608 -328.245821)
			(xy 354.654418 -328.28151) (xy 354.608569 -328.310975) (xy 354.558993 -328.333615) (xy 354.5067 -328.34897)
			(xy 354.452754 -328.356726) (xy 354.425504 -328.35723) (xy 354.398134 -328.356758) (xy 354.343957 -328.348934)
			(xy 354.291454 -328.333445) (xy 354.241705 -328.31061) (xy 354.195731 -328.280898) (xy 354.174806 -328.26325)
			(xy 354.174552 -328.26325) (xy 354.174552 -328.262996) (xy 354.167467 -328.257404) (xy 354.150551 -328.251145)
			(xy 354.141532 -328.250804) (xy 354.074476 -328.250804) (xy 354.065461 -328.251168) (xy 354.048551 -328.257421)
			(xy 354.041456 -328.262996) (xy 354.041202 -328.26325) (xy 354.020269 -328.280891) (xy 353.974301 -328.310615)
			(xy 353.924555 -328.333461) (xy 353.872053 -328.348957) (xy 353.817875 -328.356786) (xy 353.763133 -328.356786)
			(xy 353.708955 -328.348957) (xy 353.656453 -328.333461) (xy 353.606707 -328.310615) (xy 353.560739 -328.280891)
			(xy 353.539806 -328.26325) (xy 353.539552 -328.26325) (xy 353.539552 -328.262996) (xy 353.532467 -328.257404)
			(xy 353.515551 -328.251145) (xy 353.506532 -328.250804) (xy 353.439476 -328.250804) (xy 353.430461 -328.251168)
			(xy 353.413551 -328.257421) (xy 353.406456 -328.262996) (xy 353.406202 -328.26325) (xy 353.385272 -328.280894)
			(xy 353.339306 -328.310624) (xy 353.28956 -328.333471) (xy 353.237056 -328.348963) (xy 353.182875 -328.356783)
			(xy 353.155504 -328.35723) (xy 353.128252 -328.356745) (xy 353.074303 -328.348989) (xy 353.022006 -328.333634)
			(xy 352.972427 -328.310993) (xy 352.926575 -328.281528) (xy 352.885382 -328.245836) (xy 352.849688 -328.204646)
			(xy 352.820219 -328.158796) (xy 352.797575 -328.109218) (xy 352.782217 -328.056923) (xy 352.774457 -328.002974)
			(xy 352.773996 -327.975722) (xy 352.774521 -327.947232) (xy 352.782984 -327.890885) (xy 352.799724 -327.836421)
			(xy 352.824371 -327.785048) (xy 352.856376 -327.737907) (xy 352.875342 -327.716642) (xy 352.881946 -327.70953)
			(xy 352.888804 -327.692004) (xy 352.888804 -327.603612) (xy 352.881946 -327.586086) (xy 352.875342 -327.578974)
			(xy 352.856396 -327.557692) (xy 352.824379 -327.51056) (xy 352.799726 -327.459192) (xy 352.782985 -327.40473)
			(xy 352.774529 -327.348383) (xy 352.773996 -327.319894) (xy 352.774468 -327.292524) (xy 352.782293 -327.238346)
			(xy 352.79778 -327.185843) (xy 352.820613 -327.136092) (xy 352.850322 -327.090116) (xy 352.867976 -327.069196)
			(xy 352.867976 -327.068942) (xy 352.86823 -327.068942) (xy 352.873819 -327.061856) (xy 352.880071 -327.044939)
			(xy 352.880422 -327.035922) (xy 352.880422 -326.968866) (xy 352.880057 -326.959852) (xy 352.873803 -326.942941)
			(xy 352.86823 -326.935846) (xy 352.867976 -326.935592) (xy 352.860864 -326.927464) (xy 352.853266 -326.919174)
			(xy 352.832975 -326.909539) (xy 352.821748 -326.908922) (xy 350.74606 -326.908922) (xy 350.734816 -326.909496)
			(xy 350.714493 -326.919114) (xy 350.706944 -326.927464) (xy 350.700086 -326.935338) (xy 350.699578 -326.935846)
			(xy 350.693987 -326.942931) (xy 350.68773 -326.959848) (xy 350.687386 -326.968866) (xy 350.687386 -327.035922)
			(xy 350.687749 -327.044937) (xy 350.694 -327.061849) (xy 350.699578 -327.068942) (xy 350.699832 -327.069196)
			(xy 350.717473 -327.090128) (xy 350.747197 -327.136095) (xy 350.770039 -327.185842) (xy 350.785528 -327.238345)
			(xy 350.793347 -327.292524) (xy 350.793812 -327.319894) (xy 350.793285 -327.348383) (xy 350.784821 -327.404729)
			(xy 350.768079 -327.459193) (xy 350.743432 -327.510564) (xy 350.711425 -327.557704) (xy 350.692466 -327.578974)
			(xy 350.685862 -327.586086) (xy 350.679004 -327.603612) (xy 350.679004 -327.692004) (xy 350.685862 -327.70953)
			(xy 350.692466 -327.716642) (xy 350.711417 -327.737923) (xy 350.743443 -327.785052) (xy 350.768107 -327.836419)
			(xy 350.784859 -327.890883) (xy 350.793328 -327.947231) (xy 350.793812 -327.975722) (xy 350.793325 -328.002972)
			(xy 350.785566 -328.056918) (xy 350.770209 -328.10921) (xy 350.747566 -328.158785) (xy 350.7181 -328.204633)
			(xy 350.682408 -328.245821) (xy 350.641218 -328.28151) (xy 350.595369 -328.310975) (xy 350.545793 -328.333615)
			(xy 350.4935 -328.34897) (xy 350.439554 -328.356726) (xy 350.412304 -328.35723) (xy 350.384934 -328.356758)
			(xy 350.330757 -328.348934) (xy 350.278254 -328.333445) (xy 350.228505 -328.31061) (xy 350.182531 -328.280898)
			(xy 350.161606 -328.26325) (xy 350.161352 -328.26325) (xy 350.161352 -328.262996) (xy 350.154267 -328.257404)
			(xy 350.137351 -328.251145) (xy 350.128332 -328.250804) (xy 350.061276 -328.250804) (xy 350.052261 -328.251168)
			(xy 350.035351 -328.257421) (xy 350.028256 -328.262996) (xy 350.028002 -328.26325) (xy 350.007069 -328.280891)
			(xy 349.961101 -328.310615) (xy 349.911355 -328.333461) (xy 349.858853 -328.348957) (xy 349.804675 -328.356786)
			(xy 349.749933 -328.356786) (xy 349.695755 -328.348957) (xy 349.643253 -328.333461) (xy 349.593507 -328.310615)
			(xy 349.547539 -328.280891) (xy 349.526606 -328.26325) (xy 349.526352 -328.26325) (xy 349.526352 -328.262996)
			(xy 349.519267 -328.257404) (xy 349.502351 -328.251145) (xy 349.493332 -328.250804) (xy 349.426276 -328.250804)
			(xy 349.417261 -328.251168) (xy 349.400351 -328.257421) (xy 349.393256 -328.262996) (xy 349.393002 -328.26325)
			(xy 349.372072 -328.280894) (xy 349.326106 -328.310624) (xy 349.27636 -328.333471) (xy 349.223856 -328.348963)
			(xy 349.169675 -328.356783) (xy 349.142304 -328.35723) (xy 349.115052 -328.356745) (xy 349.061103 -328.348989)
			(xy 349.008806 -328.333634) (xy 348.959227 -328.310993) (xy 348.913375 -328.281528) (xy 348.872182 -328.245836)
			(xy 348.836488 -328.204646) (xy 348.807019 -328.158796) (xy 348.784375 -328.109218) (xy 348.769017 -328.056923)
			(xy 348.761257 -328.002974) (xy 348.760796 -327.975722) (xy 348.761273 -327.948354) (xy 348.769107 -327.894181)
			(xy 348.784602 -327.841684) (xy 348.807442 -327.79194) (xy 348.837155 -327.745971) (xy 348.854776 -327.725024)
			(xy 348.854776 -327.72477) (xy 348.85503 -327.72477) (xy 348.860608 -327.717681) (xy 348.866836 -327.700764)
			(xy 348.867222 -327.69175) (xy 348.867222 -327.624694) (xy 348.866862 -327.615678) (xy 348.860615 -327.598761)
			(xy 348.85503 -327.591674) (xy 348.854776 -327.59142) (xy 348.837132 -327.570488) (xy 348.8074 -327.524521)
			(xy 348.784549 -327.474774) (xy 348.769047 -327.42227) (xy 348.761215 -327.368089) (xy 348.761213 -327.313344)
			(xy 348.76904 -327.259162) (xy 348.784537 -327.206657) (xy 348.807384 -327.156908) (xy 348.837112 -327.110938)
			(xy 348.854776 -327.090024) (xy 348.854776 -327.08977) (xy 348.85503 -327.08977) (xy 348.860608 -327.082681)
			(xy 348.866836 -327.065764) (xy 348.867222 -327.05675) (xy 348.867222 -326.989694) (xy 348.866862 -326.980678)
			(xy 348.860615 -326.963761) (xy 348.85503 -326.956674) (xy 348.854776 -326.95642) (xy 348.833694 -326.930004)
			(xy 348.826082 -326.920621) (xy 348.804608 -326.909618) (xy 348.792546 -326.908922) (xy 345.364562 -326.908922)
			(xy 345.35745 -326.901556) (xy 345.347798 -326.897746) (xy 345.343231 -326.895991) (xy 345.333639 -326.894072)
			(xy 345.328748 -326.893936) (xy 319.59423 -326.893936) (xy 319.585537 -326.894277) (xy 319.56916 -326.900114)
			(xy 319.562226 -326.905366) (xy 319.558416 -326.908668) (xy 318.617854 -327.84923) (xy 318.615071 -327.852131)
			(xy 318.610351 -327.858638) (xy 318.608456 -327.862184) (xy 318.608202 -327.862692) (xy 318.605641 -327.868253)
			(xy 318.602943 -327.880192) (xy 318.602868 -327.886314) (xy 318.603122 -327.89876) (xy 318.609472 -327.91019)
			(xy 318.621141 -327.931662) (xy 318.639489 -327.976958) (xy 318.651889 -328.024229) (xy 318.658139 -328.072699)
			(xy 318.658494 -328.097134) (xy 318.658005 -328.124383) (xy 318.650245 -328.178326) (xy 318.634887 -328.230616)
			(xy 318.612243 -328.280188) (xy 318.582776 -328.326033) (xy 318.547084 -328.367218) (xy 318.505895 -328.402905)
			(xy 318.460046 -328.432366) (xy 318.410471 -328.455003) (xy 318.35818 -328.470355) (xy 318.304235 -328.478109)
			(xy 318.276986 -328.478642) (xy 318.276732 -328.478642) (xy 318.245019 -328.477988) (xy 318.182472 -328.467464)
			(xy 318.122517 -328.446765) (xy 318.09436 -328.43216) (xy 318.089788 -328.42962) (xy 318.064896 -328.423016)
			(xy 318.058951 -328.423206) (xy 318.047399 -328.42603) (xy 318.042036 -328.428604) (xy 318.034924 -328.43216)
			(xy 311.304686 -335.162398) (xy 311.297287 -335.169242) (xy 311.278689 -335.176972) (xy 311.268618 -335.177384)
			(xy 264.214356 -335.177384) (xy 264.204289 -335.177815) (xy 264.185695 -335.185538) (xy 264.178288 -335.19237)
			(xy 262.932164 -336.438494) (xy 262.92531 -336.445889) (xy 262.917563 -336.464488) (xy 262.917178 -336.474562)
			(xy 262.917178 -336.650076) (xy 314.281312 -336.650076) (xy 314.28181 -336.622166) (xy 314.289946 -336.566941)
			(xy 314.306042 -336.513491) (xy 314.329753 -336.462956) (xy 314.360573 -336.416415) (xy 314.378848 -336.395314)
			(xy 314.384745 -336.388137) (xy 314.391394 -336.370811) (xy 314.391802 -336.361532) (xy 314.391802 -336.283808)
			(xy 314.385198 -336.266536) (xy 314.378848 -336.259424) (xy 314.360552 -336.23834) (xy 314.329729 -336.191796)
			(xy 314.306018 -336.141258) (xy 314.289925 -336.087803) (xy 314.281795 -336.032574) (xy 314.281312 -336.004662)
			(xy 314.281798 -335.977411) (xy 314.289554 -335.923463) (xy 314.304909 -335.871168) (xy 314.327551 -335.821591)
			(xy 314.357017 -335.775741) (xy 314.392708 -335.73455) (xy 314.433899 -335.698859) (xy 314.479749 -335.669393)
			(xy 314.529326 -335.646751) (xy 314.581621 -335.631396) (xy 314.635569 -335.62364) (xy 314.690071 -335.62364)
			(xy 314.744019 -335.631396) (xy 314.796314 -335.646751) (xy 314.845891 -335.669393) (xy 314.891741 -335.698859)
			(xy 314.932932 -335.73455) (xy 314.968623 -335.775741) (xy 314.998089 -335.821591) (xy 315.020731 -335.871168)
			(xy 315.036086 -335.923463) (xy 315.043842 -335.977411) (xy 315.044328 -336.004662) (xy 315.043868 -336.032574)
			(xy 315.035725 -336.087801) (xy 315.019621 -336.141252) (xy 314.995902 -336.191786) (xy 314.965071 -336.238325)
			(xy 314.946792 -336.259424) (xy 314.940884 -336.266593) (xy 314.93424 -336.283925) (xy 314.933838 -336.293206)
			(xy 314.933838 -336.37093) (xy 314.940442 -336.388202) (xy 314.946792 -336.395314) (xy 314.965049 -336.416431)
			(xy 314.99588 -336.462964) (xy 315.0196 -336.513494) (xy 315.035701 -336.566942) (xy 315.04384 -336.622166)
			(xy 315.044328 -336.650076) (xy 315.043842 -336.677327) (xy 315.036086 -336.731275) (xy 315.020731 -336.78357)
			(xy 314.998089 -336.833147) (xy 314.968623 -336.878997) (xy 314.932932 -336.920188) (xy 314.891741 -336.955879)
			(xy 314.845891 -336.985345) (xy 314.796314 -337.007987) (xy 314.744019 -337.023342) (xy 314.690071 -337.031098)
			(xy 314.635569 -337.031098) (xy 314.581621 -337.023342) (xy 314.529326 -337.007987) (xy 314.479749 -336.985345)
			(xy 314.433899 -336.955879) (xy 314.392708 -336.920188) (xy 314.357017 -336.878997) (xy 314.327551 -336.833147)
			(xy 314.304909 -336.78357) (xy 314.289554 -336.731275) (xy 314.281798 -336.677327) (xy 314.281312 -336.650076)
			(xy 262.917178 -336.650076) (xy 262.917178 -337.881722) (xy 315.239144 -337.881722) (xy 315.243215 -337.8261)
			(xy 315.255341 -337.771663) (xy 315.275264 -337.719572) (xy 315.30256 -337.670937) (xy 315.336646 -337.626794)
			(xy 315.376795 -337.588085) (xy 315.422153 -337.555634) (xy 315.471753 -337.530133) (xy 315.524537 -337.512126)
			(xy 315.57938 -337.501996) (xy 315.635114 -337.499959) (xy 315.690551 -337.506059) (xy 315.744508 -337.520165)
			(xy 315.795837 -337.541977) (xy 315.843443 -337.571031) (xy 315.886311 -337.606706) (xy 315.923528 -337.648243)
			(xy 315.954301 -337.694756) (xy 315.977973 -337.745253) (xy 315.994041 -337.79866) (xy 316.002161 -337.853836)
			(xy 316.00267 -337.881722) (xy 316.002161 -337.909608) (xy 315.994041 -337.964784) (xy 315.977973 -338.018191)
			(xy 315.954301 -338.068688) (xy 315.923528 -338.115201) (xy 315.886311 -338.156738) (xy 315.843443 -338.192413)
			(xy 315.795837 -338.221467) (xy 315.744508 -338.243279) (xy 315.690551 -338.257385) (xy 315.635114 -338.263485)
			(xy 315.57938 -338.261448) (xy 315.524537 -338.251318) (xy 315.471753 -338.233311) (xy 315.422153 -338.20781)
			(xy 315.376795 -338.175359) (xy 315.336646 -338.13665) (xy 315.30256 -338.092507) (xy 315.275264 -338.043872)
			(xy 315.255341 -337.991781) (xy 315.243215 -337.937344) (xy 315.239144 -337.881722) (xy 262.917178 -337.881722)
			(xy 262.917178 -338.777072) (xy 314.660024 -338.777072) (xy 314.664095 -338.72145) (xy 314.676221 -338.667013)
			(xy 314.696144 -338.614922) (xy 314.72344 -338.566287) (xy 314.757526 -338.522144) (xy 314.797675 -338.483435)
			(xy 314.843033 -338.450984) (xy 314.892633 -338.425483) (xy 314.945417 -338.407476) (xy 315.00026 -338.397346)
			(xy 315.055994 -338.395309) (xy 315.111431 -338.401409) (xy 315.165388 -338.415515) (xy 315.216717 -338.437327)
			(xy 315.264323 -338.466381) (xy 315.307191 -338.502056) (xy 315.344408 -338.543593) (xy 315.375181 -338.590106)
			(xy 315.398853 -338.640603) (xy 315.414921 -338.69401) (xy 315.423041 -338.749186) (xy 315.42355 -338.777072)
			(xy 315.423041 -338.804958) (xy 315.414921 -338.860134) (xy 315.398853 -338.913541) (xy 315.375181 -338.964038)
			(xy 315.344408 -339.010551) (xy 315.307191 -339.052088) (xy 315.264323 -339.087763) (xy 315.216717 -339.116817)
			(xy 315.165388 -339.138629) (xy 315.111431 -339.152735) (xy 315.055994 -339.158835) (xy 315.00026 -339.156798)
			(xy 314.945417 -339.146668) (xy 314.892633 -339.128661) (xy 314.843033 -339.10316) (xy 314.797675 -339.070709)
			(xy 314.757526 -339.032) (xy 314.72344 -338.987857) (xy 314.696144 -338.939222) (xy 314.676221 -338.887131)
			(xy 314.664095 -338.832694) (xy 314.660024 -338.777072) (xy 262.917178 -338.777072) (xy 262.917178 -339.452712)
			(xy 315.99886 -339.452712) (xy 315.999363 -339.425238) (xy 316.007253 -339.37086) (xy 316.022869 -339.318178)
			(xy 316.04589 -339.268285) (xy 316.075837 -339.222215) (xy 316.093602 -339.201252) (xy 316.093856 -339.200998)
			(xy 316.099456 -339.193921) (xy 316.105693 -339.176997) (xy 316.106048 -339.167978) (xy 316.106048 -339.100414)
			(xy 316.105695 -339.091396) (xy 316.099446 -339.074479) (xy 316.093856 -339.067394) (xy 316.093348 -339.066886)
			(xy 316.075619 -339.045936) (xy 316.045735 -338.999905) (xy 316.022767 -338.950061) (xy 316.007191 -338.897436)
			(xy 315.99933 -338.843121) (xy 315.99886 -338.81568) (xy 315.999346 -338.788429) (xy 316.007102 -338.734481)
			(xy 316.022457 -338.682186) (xy 316.045099 -338.632609) (xy 316.074565 -338.586759) (xy 316.110256 -338.545568)
			(xy 316.151447 -338.509877) (xy 316.197297 -338.480411) (xy 316.246874 -338.457769) (xy 316.299169 -338.442414)
			(xy 316.353117 -338.434658) (xy 316.407619 -338.434658) (xy 316.461567 -338.442414) (xy 316.513862 -338.457769)
			(xy 316.563439 -338.480411) (xy 316.609289 -338.509877) (xy 316.65048 -338.545568) (xy 316.686171 -338.586759)
			(xy 316.715637 -338.632609) (xy 316.738279 -338.682186) (xy 316.753634 -338.734481) (xy 316.76139 -338.788429)
			(xy 316.761876 -338.81568) (xy 316.761384 -338.843154) (xy 316.753494 -338.897534) (xy 316.737876 -338.950217)
			(xy 316.73523 -338.95595) (xy 317.003688 -338.95595) (xy 317.003688 -338.90145) (xy 317.011444 -338.847505)
			(xy 317.026798 -338.795213) (xy 317.049437 -338.745639) (xy 317.078901 -338.69979) (xy 317.11459 -338.658601)
			(xy 317.155777 -338.622911) (xy 317.201624 -338.593445) (xy 317.251198 -338.570804) (xy 317.30349 -338.555447)
			(xy 317.357434 -338.547689) (xy 317.384684 -338.547202) (xy 317.384938 -338.547202) (xy 317.410142 -338.54759)
			(xy 317.46011 -338.554234) (xy 317.508765 -338.567414) (xy 317.555254 -338.586899) (xy 317.577216 -338.599272)
			(xy 317.587122 -338.605114) (xy 317.608966 -338.607146) (xy 317.703708 -338.573618) (xy 317.719456 -338.558124)
			(xy 317.72352 -338.54771) (xy 317.734188 -338.520921) (xy 317.762478 -338.470677) (xy 317.798011 -338.425266)
			(xy 317.839977 -338.385723) (xy 317.887418 -338.352951) (xy 317.939254 -338.327695) (xy 317.994301 -338.310533)
			(xy 318.051306 -338.301856) (xy 318.080136 -338.30133) (xy 318.107392 -338.301722) (xy 318.161347 -338.309484)
			(xy 318.213649 -338.324847) (xy 318.263231 -338.347496) (xy 318.309086 -338.376972) (xy 318.35028 -338.412673)
			(xy 318.385973 -338.453873) (xy 318.415439 -338.499734) (xy 318.438079 -338.549321) (xy 318.453431 -338.601625)
			(xy 318.461184 -338.655582) (xy 318.461644 -338.682838) (xy 318.460991 -338.714401) (xy 318.450602 -338.776667)
			(xy 318.430113 -338.836376) (xy 318.41567 -338.864448) (xy 318.410844 -338.873338) (xy 318.408812 -338.892896)
			(xy 318.431672 -338.971382) (xy 318.434901 -338.980811) (xy 318.447324 -338.996369) (xy 318.455802 -339.001608)
			(xy 318.480891 -339.016175) (xy 318.526773 -339.051676) (xy 318.566749 -339.093717) (xy 318.599895 -339.141327)
			(xy 318.625448 -339.193409) (xy 318.642817 -339.24876) (xy 318.651603 -339.306104) (xy 318.652144 -339.33511)
			(xy 318.651658 -339.362361) (xy 318.643902 -339.416309) (xy 318.628547 -339.468604) (xy 318.605905 -339.518181)
			(xy 318.576439 -339.564031) (xy 318.540748 -339.605222) (xy 318.499557 -339.640913) (xy 318.453707 -339.670379)
			(xy 318.40413 -339.693021) (xy 318.351835 -339.708376) (xy 318.297887 -339.716132) (xy 318.243385 -339.716132)
			(xy 318.189437 -339.708376) (xy 318.137142 -339.693021) (xy 318.087565 -339.670379) (xy 318.041715 -339.640913)
			(xy 318.000524 -339.605222) (xy 317.964833 -339.564031) (xy 317.935367 -339.518181) (xy 317.912725 -339.468604)
			(xy 317.89737 -339.416309) (xy 317.889614 -339.362361) (xy 317.889128 -339.33511) (xy 317.889764 -339.303546)
			(xy 317.900161 -339.24128) (xy 317.920656 -339.181572) (xy 317.935102 -339.1535) (xy 317.939928 -339.14461)
			(xy 317.94196 -339.125052) (xy 317.9191 -339.046566) (xy 317.915865 -339.037141) (xy 317.903445 -339.021583)
			(xy 317.89497 -339.01634) (xy 317.887604 -339.012276) (xy 317.877698 -339.006434) (xy 317.855854 -339.004402)
			(xy 317.761112 -339.03793) (xy 317.745364 -339.053424) (xy 317.7413 -339.063838) (xy 317.730641 -339.09063)
			(xy 317.702347 -339.140872) (xy 317.666811 -339.186281) (xy 317.624844 -339.225822) (xy 317.577401 -339.258593)
			(xy 317.525566 -339.283849) (xy 317.470518 -339.301011) (xy 317.413514 -339.30969) (xy 317.384684 -339.310218)
			(xy 317.357434 -339.309711) (xy 317.30349 -339.301953) (xy 317.251198 -339.286596) (xy 317.201624 -339.263955)
			(xy 317.155777 -339.234489) (xy 317.11459 -339.198799) (xy 317.078901 -339.15761) (xy 317.049437 -339.111761)
			(xy 317.026798 -339.062187) (xy 317.011444 -339.009895) (xy 317.003688 -338.95595) (xy 316.73523 -338.95595)
			(xy 316.714852 -339.000109) (xy 316.684901 -339.046178) (xy 316.667134 -339.06714) (xy 316.66688 -339.067394)
			(xy 316.661288 -339.074476) (xy 316.655045 -339.091396) (xy 316.654688 -339.100414) (xy 316.654688 -339.167978)
			(xy 316.655058 -339.176993) (xy 316.661297 -339.19391) (xy 316.66688 -339.200998) (xy 316.667388 -339.201506)
			(xy 316.685118 -339.222455) (xy 316.715002 -339.268487) (xy 316.737969 -339.318331) (xy 316.753544 -339.370956)
			(xy 316.761405 -339.425271) (xy 316.761876 -339.452712) (xy 316.76139 -339.479963) (xy 316.753634 -339.533911)
			(xy 316.738279 -339.586206) (xy 316.715637 -339.635783) (xy 316.686171 -339.681633) (xy 316.65048 -339.722824)
			(xy 316.609289 -339.758515) (xy 316.563439 -339.787981) (xy 316.513862 -339.810623) (xy 316.461567 -339.825978)
			(xy 316.407619 -339.833734) (xy 316.353117 -339.833734) (xy 316.299169 -339.825978) (xy 316.246874 -339.810623)
			(xy 316.197297 -339.787981) (xy 316.151447 -339.758515) (xy 316.110256 -339.722824) (xy 316.074565 -339.681633)
			(xy 316.045099 -339.635783) (xy 316.022457 -339.586206) (xy 316.007102 -339.533911) (xy 315.999346 -339.479963)
			(xy 315.99886 -339.452712) (xy 262.917178 -339.452712) (xy 262.917178 -348.37116) (xy 271.357598 -348.37116)
			(xy 271.358065 -348.343248) (xy 271.366205 -348.288021) (xy 271.382307 -348.23457) (xy 271.406025 -348.184036)
			(xy 271.436855 -348.137497) (xy 271.455134 -348.116398) (xy 271.461036 -348.109224) (xy 271.467683 -348.091896)
			(xy 271.468088 -348.082616) (xy 271.468088 -348.004892) (xy 271.461484 -347.98762) (xy 271.455134 -347.980508)
			(xy 271.436828 -347.959432) (xy 271.406007 -347.912886) (xy 271.382298 -347.862345) (xy 271.366208 -347.808889)
			(xy 271.35808 -347.753659) (xy 271.357598 -347.725746) (xy 271.358084 -347.698495) (xy 271.36584 -347.644547)
			(xy 271.381195 -347.592252) (xy 271.403837 -347.542675) (xy 271.433303 -347.496825) (xy 271.468994 -347.455634)
			(xy 271.510185 -347.419943) (xy 271.556035 -347.390477) (xy 271.605612 -347.367835) (xy 271.657907 -347.35248)
			(xy 271.711855 -347.344724) (xy 271.766357 -347.344724) (xy 271.820305 -347.35248) (xy 271.8726 -347.367835)
			(xy 271.922177 -347.390477) (xy 271.968027 -347.419943) (xy 272.009218 -347.455634) (xy 272.044909 -347.496825)
			(xy 272.074375 -347.542675) (xy 272.097017 -347.592252) (xy 272.112372 -347.644547) (xy 272.120128 -347.698495)
			(xy 272.120614 -347.725746) (xy 272.120148 -347.753658) (xy 272.112007 -347.808885) (xy 272.095905 -347.862336)
			(xy 272.072186 -347.91287) (xy 272.041357 -347.959409) (xy 272.023078 -347.980508) (xy 272.017175 -347.987681)
			(xy 272.010528 -348.005009) (xy 272.010124 -348.01429) (xy 272.010124 -348.092014) (xy 272.016728 -348.109286)
			(xy 272.023078 -348.116398) (xy 272.041326 -348.137523) (xy 272.072158 -348.184054) (xy 272.09588 -348.234582)
			(xy 272.111983 -348.288028) (xy 272.120125 -348.34325) (xy 272.120614 -348.37116) (xy 272.120128 -348.398411)
			(xy 272.112372 -348.452359) (xy 272.097017 -348.504654) (xy 272.074375 -348.554231) (xy 272.044909 -348.600081)
			(xy 272.009218 -348.641272) (xy 271.968027 -348.676963) (xy 271.922177 -348.706429) (xy 271.8726 -348.729071)
			(xy 271.820305 -348.744426) (xy 271.766357 -348.752182) (xy 271.711855 -348.752182) (xy 271.657907 -348.744426)
			(xy 271.605612 -348.729071) (xy 271.556035 -348.706429) (xy 271.510185 -348.676963) (xy 271.468994 -348.641272)
			(xy 271.433303 -348.600081) (xy 271.403837 -348.554231) (xy 271.381195 -348.504654) (xy 271.36584 -348.452359)
			(xy 271.358084 -348.398411) (xy 271.357598 -348.37116) (xy 262.917178 -348.37116) (xy 262.917178 -349.088456)
			(xy 275.551392 -349.088456) (xy 275.551392 -346.994988) (xy 275.551757 -346.984942) (xy 275.559347 -346.966345)
			(xy 275.566124 -346.95892) (xy 275.729954 -346.79509) (xy 275.737375 -346.788276) (xy 275.755958 -346.780542)
			(xy 275.766022 -346.780104) (xy 278.952452 -346.780104) (xy 278.962522 -346.780527) (xy 278.981122 -346.788246)
			(xy 278.98852 -346.79509) (xy 279.194514 -347.001084) (xy 279.201341 -347.008494) (xy 279.209068 -347.027086)
			(xy 279.2095 -347.037152) (xy 279.2095 -348.211394) (xy 279.209902 -348.221466) (xy 279.217636 -348.240066)
			(xy 279.224486 -348.247462) (xy 279.466802 -348.489778) (xy 279.474555 -348.496783) (xy 279.493938 -348.504517)
			(xy 279.514798 -348.503909) (xy 279.52446 -348.499938) (xy 279.625552 -348.452186) (xy 279.6413 -348.424246)
			(xy 279.639776 -348.408244) (xy 279.637998 -348.371668) (xy 279.637998 -348.37116) (xy 279.638465 -348.343248)
			(xy 279.646605 -348.288021) (xy 279.662707 -348.23457) (xy 279.686425 -348.184036) (xy 279.717255 -348.137497)
			(xy 279.735534 -348.116398) (xy 279.741436 -348.109224) (xy 279.748083 -348.091896) (xy 279.748488 -348.082616)
			(xy 279.748488 -348.004892) (xy 279.741884 -347.98762) (xy 279.735534 -347.980508) (xy 279.717228 -347.959432)
			(xy 279.686407 -347.912886) (xy 279.662698 -347.862345) (xy 279.646608 -347.808889) (xy 279.63848 -347.753659)
			(xy 279.637998 -347.725746) (xy 279.638484 -347.698495) (xy 279.64624 -347.644547) (xy 279.661595 -347.592252)
			(xy 279.684237 -347.542675) (xy 279.713703 -347.496825) (xy 279.749394 -347.455634) (xy 279.790585 -347.419943)
			(xy 279.836435 -347.390477) (xy 279.886012 -347.367835) (xy 279.938307 -347.35248) (xy 279.992255 -347.344724)
			(xy 280.046757 -347.344724) (xy 280.100705 -347.35248) (xy 280.153 -347.367835) (xy 280.202577 -347.390477)
			(xy 280.248427 -347.419943) (xy 280.289618 -347.455634) (xy 280.325309 -347.496825) (xy 280.354775 -347.542675)
			(xy 280.377417 -347.592252) (xy 280.392772 -347.644547) (xy 280.400528 -347.698495) (xy 280.401014 -347.725746)
			(xy 280.400548 -347.753658) (xy 280.392407 -347.808885) (xy 280.376305 -347.862336) (xy 280.352586 -347.91287)
			(xy 280.321757 -347.959409) (xy 280.303478 -347.980508) (xy 280.297575 -347.987681) (xy 280.290928 -348.005009)
			(xy 280.290524 -348.01429) (xy 280.290524 -348.092014) (xy 280.297128 -348.109286) (xy 280.303478 -348.116398)
			(xy 280.321726 -348.137523) (xy 280.352558 -348.184054) (xy 280.37628 -348.234582) (xy 280.392383 -348.288028)
			(xy 280.400525 -348.34325) (xy 280.401014 -348.37116) (xy 280.400508 -348.398412) (xy 280.392756 -348.452361)
			(xy 280.377405 -348.504657) (xy 280.354768 -348.554237) (xy 280.325305 -348.60009) (xy 280.289616 -348.641283)
			(xy 280.248427 -348.676977) (xy 280.202577 -348.706446) (xy 280.153001 -348.729089) (xy 280.100706 -348.744446)
			(xy 280.046758 -348.752204) (xy 280.019506 -348.752668) (xy 279.994888 -348.752288) (xy 279.946064 -348.745925)
			(xy 279.898466 -348.73333) (xy 279.852885 -348.714713) (xy 279.831292 -348.702884) (xy 279.831038 -348.702884)
			(xy 279.823193 -348.698893) (xy 279.805855 -348.695947) (xy 279.788545 -348.699059) (xy 279.780746 -348.703138)
			(xy 279.7048 -348.747334) (xy 279.697254 -348.752052) (xy 279.685808 -348.765666) (xy 279.679729 -348.782382)
			(xy 279.6794 -348.791276) (xy 279.6794 -349.602806) (xy 280.59583 -349.602806) (xy 280.599901 -349.547184)
			(xy 280.612027 -349.492747) (xy 280.63195 -349.440656) (xy 280.659246 -349.392021) (xy 280.693332 -349.347878)
			(xy 280.733481 -349.309169) (xy 280.778839 -349.276718) (xy 280.828439 -349.251217) (xy 280.881223 -349.23321)
			(xy 280.936066 -349.22308) (xy 280.9918 -349.221043) (xy 281.047237 -349.227143) (xy 281.101194 -349.241249)
			(xy 281.152523 -349.263061) (xy 281.200129 -349.292115) (xy 281.242997 -349.32779) (xy 281.280214 -349.369327)
			(xy 281.310987 -349.41584) (xy 281.334659 -349.466337) (xy 281.350727 -349.519744) (xy 281.358847 -349.57492)
			(xy 281.359356 -349.602806) (xy 281.358847 -349.630692) (xy 281.350727 -349.685868) (xy 281.334659 -349.739275)
			(xy 281.310987 -349.789772) (xy 281.280214 -349.836285) (xy 281.242997 -349.877822) (xy 281.200129 -349.913497)
			(xy 281.152523 -349.942551) (xy 281.101194 -349.964363) (xy 281.047237 -349.978469) (xy 280.9918 -349.984569)
			(xy 280.936066 -349.982532) (xy 280.881223 -349.972402) (xy 280.828439 -349.954395) (xy 280.778839 -349.928894)
			(xy 280.733481 -349.896443) (xy 280.693332 -349.857734) (xy 280.659246 -349.813591) (xy 280.63195 -349.764956)
			(xy 280.612027 -349.712865) (xy 280.599901 -349.658428) (xy 280.59583 -349.602806) (xy 279.6794 -349.602806)
			(xy 279.6794 -350.498156) (xy 280.01671 -350.498156) (xy 280.020781 -350.442534) (xy 280.032907 -350.388097)
			(xy 280.05283 -350.336006) (xy 280.080126 -350.287371) (xy 280.114212 -350.243228) (xy 280.154361 -350.204519)
			(xy 280.199719 -350.172068) (xy 280.249319 -350.146567) (xy 280.302103 -350.12856) (xy 280.356946 -350.11843)
			(xy 280.41268 -350.116393) (xy 280.468117 -350.122493) (xy 280.522074 -350.136599) (xy 280.573403 -350.158411)
			(xy 280.621009 -350.187465) (xy 280.663877 -350.22314) (xy 280.701094 -350.264677) (xy 280.731867 -350.31119)
			(xy 280.755539 -350.361687) (xy 280.771607 -350.415094) (xy 280.779727 -350.47027) (xy 280.780236 -350.498156)
			(xy 280.779727 -350.526042) (xy 280.771607 -350.581218) (xy 280.755539 -350.634625) (xy 280.731867 -350.685122)
			(xy 280.701094 -350.731635) (xy 280.663877 -350.773172) (xy 280.621009 -350.808847) (xy 280.573403 -350.837901)
			(xy 280.522074 -350.859713) (xy 280.468117 -350.873819) (xy 280.41268 -350.879919) (xy 280.356946 -350.877882)
			(xy 280.302103 -350.867752) (xy 280.249319 -350.849745) (xy 280.199719 -350.824244) (xy 280.154361 -350.791793)
			(xy 280.114212 -350.753084) (xy 280.080126 -350.708941) (xy 280.05283 -350.660306) (xy 280.032907 -350.608215)
			(xy 280.020781 -350.553778) (xy 280.01671 -350.498156) (xy 279.6794 -350.498156) (xy 279.6794 -351.173796)
			(xy 281.355546 -351.173796) (xy 281.356019 -351.146321) (xy 281.363912 -351.09194) (xy 281.379535 -351.039257)
			(xy 281.402563 -350.989365) (xy 281.432518 -350.943297) (xy 281.450288 -350.922336) (xy 281.450542 -350.922082)
			(xy 281.456147 -350.915008) (xy 281.462382 -350.898082) (xy 281.462734 -350.889062) (xy 281.462734 -350.821498)
			(xy 281.46237 -350.812482) (xy 281.456126 -350.795565) (xy 281.450542 -350.788478) (xy 281.450034 -350.78797)
			(xy 281.432296 -350.767028) (xy 281.402413 -350.720994) (xy 281.379447 -350.671148) (xy 281.363874 -350.618522)
			(xy 281.356015 -350.564205) (xy 281.355546 -350.536764) (xy 281.356032 -350.509513) (xy 281.363788 -350.455565)
			(xy 281.379143 -350.40327) (xy 281.401785 -350.353693) (xy 281.431251 -350.307843) (xy 281.466942 -350.266652)
			(xy 281.508133 -350.230961) (xy 281.553983 -350.201495) (xy 281.60356 -350.178853) (xy 281.655855 -350.163498)
			(xy 281.709803 -350.155742) (xy 281.764305 -350.155742) (xy 281.818253 -350.163498) (xy 281.870548 -350.178853)
			(xy 281.920125 -350.201495) (xy 281.965975 -350.230961) (xy 282.007166 -350.266652) (xy 282.042857 -350.307843)
			(xy 282.072323 -350.353693) (xy 282.094965 -350.40327) (xy 282.11032 -350.455565) (xy 282.118076 -350.509513)
			(xy 282.118562 -350.536764) (xy 282.118064 -350.564238) (xy 282.110176 -350.618618) (xy 282.094559 -350.6713)
			(xy 282.091906 -350.67705) (xy 282.360372 -350.67705) (xy 282.360372 -350.62255) (xy 282.368128 -350.568604)
			(xy 282.383481 -350.516311) (xy 282.406121 -350.466735) (xy 282.435585 -350.420885) (xy 282.471274 -350.379695)
			(xy 282.512461 -350.344003) (xy 282.558308 -350.314535) (xy 282.607882 -350.291892) (xy 282.660174 -350.276534)
			(xy 282.71412 -350.268774) (xy 282.74137 -350.268286) (xy 282.741624 -350.268286) (xy 282.766828 -350.268669)
			(xy 282.816797 -350.275312) (xy 282.865452 -350.288494) (xy 282.911941 -350.307982) (xy 282.933902 -350.320356)
			(xy 282.943808 -350.326198) (xy 282.965652 -350.32823) (xy 283.060394 -350.294702) (xy 283.076142 -350.279208)
			(xy 283.080206 -350.268794) (xy 283.090877 -350.242007) (xy 283.119168 -350.191764) (xy 283.154701 -350.146354)
			(xy 283.196666 -350.106811) (xy 283.244107 -350.074039) (xy 283.295942 -350.048783) (xy 283.350989 -350.03162)
			(xy 283.407992 -350.022941) (xy 283.436822 -350.022414) (xy 283.464075 -350.022857) (xy 283.518025 -350.030617)
			(xy 283.570322 -350.045977) (xy 283.619901 -350.068622) (xy 283.665752 -350.098092) (xy 283.706943 -350.133788)
			(xy 283.742634 -350.174983) (xy 283.772099 -350.220838) (xy 283.794739 -350.270419) (xy 283.810092 -350.322718)
			(xy 283.817846 -350.376669) (xy 283.81833 -350.403922) (xy 283.81766 -350.435484) (xy 283.807276 -350.497749)
			(xy 283.786795 -350.557459) (xy 283.772356 -350.585532) (xy 283.76753 -350.594422) (xy 283.765498 -350.61398)
			(xy 283.788358 -350.692466) (xy 283.791598 -350.70189) (xy 283.804013 -350.717451) (xy 283.812488 -350.722692)
			(xy 283.837611 -350.737205) (xy 283.883494 -350.772714) (xy 283.923468 -350.814763) (xy 283.956612 -350.862383)
			(xy 283.982159 -350.914474) (xy 283.99952 -350.969834) (xy 284.008295 -351.027185) (xy 284.00883 -351.056194)
			(xy 284.008344 -351.083445) (xy 284.000588 -351.137393) (xy 283.985233 -351.189688) (xy 283.962591 -351.239265)
			(xy 283.933125 -351.285115) (xy 283.897434 -351.326306) (xy 283.856243 -351.361997) (xy 283.810393 -351.391463)
			(xy 283.760816 -351.414105) (xy 283.708521 -351.42946) (xy 283.654573 -351.437216) (xy 283.600071 -351.437216)
			(xy 283.546123 -351.42946) (xy 283.493828 -351.414105) (xy 283.444251 -351.391463) (xy 283.398401 -351.361997)
			(xy 283.35721 -351.326306) (xy 283.321519 -351.285115) (xy 283.292053 -351.239265) (xy 283.269411 -351.189688)
			(xy 283.254056 -351.137393) (xy 283.2463 -351.083445) (xy 283.245814 -351.056194) (xy 283.246485 -351.024632)
			(xy 283.256867 -350.962367) (xy 283.277349 -350.902657) (xy 283.291788 -350.874584) (xy 283.296614 -350.865694)
			(xy 283.298646 -350.846136) (xy 283.275786 -350.76765) (xy 283.272563 -350.75822) (xy 283.260134 -350.742664)
			(xy 283.251656 -350.737424) (xy 283.24429 -350.73336) (xy 283.234384 -350.727518) (xy 283.21254 -350.725486)
			(xy 283.117798 -350.759014) (xy 283.10205 -350.774508) (xy 283.097986 -350.784922) (xy 283.08733 -350.811715)
			(xy 283.059037 -350.861958) (xy 283.023501 -350.907368) (xy 282.981533 -350.94691) (xy 282.93409 -350.979681)
			(xy 282.882254 -351.004936) (xy 282.827205 -351.022098) (xy 282.770201 -351.030775) (xy 282.74137 -351.031302)
			(xy 282.71412 -351.030826) (xy 282.660174 -351.023066) (xy 282.607882 -351.007708) (xy 282.558308 -350.985065)
			(xy 282.512461 -350.955597) (xy 282.471274 -350.919905) (xy 282.435585 -350.878715) (xy 282.406121 -350.832865)
			(xy 282.383481 -350.783289) (xy 282.368128 -350.730996) (xy 282.360372 -350.67705) (xy 282.091906 -350.67705)
			(xy 282.071537 -350.721193) (xy 282.041587 -350.767262) (xy 282.02382 -350.788224) (xy 282.023566 -350.788478)
			(xy 282.017979 -350.795564) (xy 282.011734 -350.812481) (xy 282.011374 -350.821498) (xy 282.011374 -350.889062)
			(xy 282.011755 -350.898076) (xy 282.017986 -350.914993) (xy 282.023566 -350.922082) (xy 282.024074 -350.92259)
			(xy 282.041795 -350.943547) (xy 282.07168 -350.989576) (xy 282.094649 -351.039419) (xy 282.110227 -351.092042)
			(xy 282.11809 -351.146356) (xy 282.118562 -351.173796) (xy 282.118076 -351.201047) (xy 282.11032 -351.254995)
			(xy 282.094965 -351.30729) (xy 282.072323 -351.356867) (xy 282.042857 -351.402717) (xy 282.007166 -351.443908)
			(xy 281.965975 -351.479599) (xy 281.920125 -351.509065) (xy 281.870548 -351.531707) (xy 281.818253 -351.547062)
			(xy 281.764305 -351.554818) (xy 281.709803 -351.554818) (xy 281.655855 -351.547062) (xy 281.60356 -351.531707)
			(xy 281.553983 -351.509065) (xy 281.508133 -351.479599) (xy 281.466942 -351.443908) (xy 281.431251 -351.402717)
			(xy 281.401785 -351.356867) (xy 281.379143 -351.30729) (xy 281.363788 -351.254995) (xy 281.356032 -351.201047)
			(xy 281.355546 -351.173796) (xy 279.6794 -351.173796) (xy 279.6794 -351.798382) (xy 279.679808 -351.808454)
			(xy 279.687538 -351.827053) (xy 279.694386 -351.83445) (xy 280.226008 -352.365818) (xy 280.233409 -352.372656)
			(xy 280.252008 -352.380376) (xy 280.262076 -352.380804) (xy 284.528768 -352.380804) (xy 284.538839 -352.380387)
			(xy 284.557438 -352.372663) (xy 284.564836 -352.365818) (xy 284.720538 -352.210116) (xy 284.727369 -352.202709)
			(xy 284.735093 -352.184115) (xy 284.735524 -352.174048) (xy 284.735524 -350.072452) (xy 284.735091 -350.062383)
			(xy 284.727378 -350.043784) (xy 284.720538 -350.036384) (xy 283.846778 -349.16237) (xy 283.839929 -349.154977)
			(xy 283.832215 -349.136372) (xy 283.831792 -349.126302) (xy 283.831792 -347.007688) (xy 283.832157 -346.997642)
			(xy 283.839747 -346.979045) (xy 283.846524 -346.97162) (xy 284.033214 -346.78493) (xy 284.040619 -346.778096)
			(xy 284.059214 -346.770372) (xy 284.069282 -346.769944) (xy 287.182052 -346.769944) (xy 287.19212 -346.770383)
			(xy 287.210719 -346.778093) (xy 287.21812 -346.78493) (xy 287.525714 -347.092524) (xy 287.532559 -347.09992)
			(xy 287.540275 -347.118522) (xy 287.5407 -347.128592) (xy 287.5407 -348.305374) (xy 287.541113 -348.315445)
			(xy 287.548839 -348.334044) (xy 287.555686 -348.341442) (xy 287.585385 -348.37116) (xy 287.943798 -348.37116)
			(xy 287.944265 -348.343248) (xy 287.952405 -348.288021) (xy 287.968507 -348.23457) (xy 287.992225 -348.184036)
			(xy 288.023055 -348.137497) (xy 288.041334 -348.116398) (xy 288.047236 -348.109224) (xy 288.053883 -348.091896)
			(xy 288.054288 -348.082616) (xy 288.054288 -348.004892) (xy 288.047684 -347.98762) (xy 288.041334 -347.980508)
			(xy 288.023028 -347.959432) (xy 287.992207 -347.912886) (xy 287.968498 -347.862345) (xy 287.952408 -347.808889)
			(xy 287.94428 -347.753659) (xy 287.943798 -347.725746) (xy 287.944284 -347.698495) (xy 287.95204 -347.644547)
			(xy 287.967395 -347.592252) (xy 287.990037 -347.542675) (xy 288.019503 -347.496825) (xy 288.055194 -347.455634)
			(xy 288.096385 -347.419943) (xy 288.142235 -347.390477) (xy 288.191812 -347.367835) (xy 288.244107 -347.35248)
			(xy 288.298055 -347.344724) (xy 288.352557 -347.344724) (xy 288.406505 -347.35248) (xy 288.4588 -347.367835)
			(xy 288.508377 -347.390477) (xy 288.554227 -347.419943) (xy 288.595418 -347.455634) (xy 288.631109 -347.496825)
			(xy 288.660575 -347.542675) (xy 288.683217 -347.592252) (xy 288.698572 -347.644547) (xy 288.706328 -347.698495)
			(xy 288.706814 -347.725746) (xy 288.706348 -347.753658) (xy 288.698207 -347.808885) (xy 288.682105 -347.862336)
			(xy 288.658386 -347.91287) (xy 288.627557 -347.959409) (xy 288.609278 -347.980508) (xy 288.603375 -347.987681)
			(xy 288.596728 -348.005009) (xy 288.596324 -348.01429) (xy 288.596324 -348.092014) (xy 288.602928 -348.109286)
			(xy 288.609278 -348.116398) (xy 288.627526 -348.137523) (xy 288.658358 -348.184054) (xy 288.68208 -348.234582)
			(xy 288.698183 -348.288028) (xy 288.706325 -348.34325) (xy 288.706814 -348.37116) (xy 288.706328 -348.398411)
			(xy 288.698572 -348.452359) (xy 288.683217 -348.504654) (xy 288.660575 -348.554231) (xy 288.631109 -348.600081)
			(xy 288.595418 -348.641272) (xy 288.554227 -348.676963) (xy 288.508377 -348.706429) (xy 288.4588 -348.729071)
			(xy 288.406505 -348.744426) (xy 288.352557 -348.752182) (xy 288.298055 -348.752182) (xy 288.244107 -348.744426)
			(xy 288.191812 -348.729071) (xy 288.142235 -348.706429) (xy 288.096385 -348.676963) (xy 288.055194 -348.641272)
			(xy 288.019503 -348.600081) (xy 287.990037 -348.554231) (xy 287.967395 -348.504654) (xy 287.95204 -348.452359)
			(xy 287.944284 -348.398411) (xy 287.943798 -348.37116) (xy 287.585385 -348.37116) (xy 287.944814 -348.730824)
			(xy 287.951659 -348.73822) (xy 287.959375 -348.756822) (xy 287.9598 -348.766892) (xy 287.9598 -349.602806)
			(xy 288.90163 -349.602806) (xy 288.905701 -349.547184) (xy 288.917827 -349.492747) (xy 288.93775 -349.440656)
			(xy 288.965046 -349.392021) (xy 288.999132 -349.347878) (xy 289.039281 -349.309169) (xy 289.084639 -349.276718)
			(xy 289.134239 -349.251217) (xy 289.187023 -349.23321) (xy 289.241866 -349.22308) (xy 289.2976 -349.221043)
			(xy 289.353037 -349.227143) (xy 289.406994 -349.241249) (xy 289.458323 -349.263061) (xy 289.505929 -349.292115)
			(xy 289.548797 -349.32779) (xy 289.586014 -349.369327) (xy 289.616787 -349.41584) (xy 289.640459 -349.466337)
			(xy 289.656527 -349.519744) (xy 289.664647 -349.57492) (xy 289.665156 -349.602806) (xy 289.664647 -349.630692)
			(xy 289.656527 -349.685868) (xy 289.640459 -349.739275) (xy 289.616787 -349.789772) (xy 289.586014 -349.836285)
			(xy 289.548797 -349.877822) (xy 289.505929 -349.913497) (xy 289.458323 -349.942551) (xy 289.406994 -349.964363)
			(xy 289.353037 -349.978469) (xy 289.2976 -349.984569) (xy 289.241866 -349.982532) (xy 289.187023 -349.972402)
			(xy 289.134239 -349.954395) (xy 289.084639 -349.928894) (xy 289.039281 -349.896443) (xy 288.999132 -349.857734)
			(xy 288.965046 -349.813591) (xy 288.93775 -349.764956) (xy 288.917827 -349.712865) (xy 288.905701 -349.658428)
			(xy 288.90163 -349.602806) (xy 287.9598 -349.602806) (xy 287.9598 -350.498156) (xy 288.32251 -350.498156)
			(xy 288.326581 -350.442534) (xy 288.338707 -350.388097) (xy 288.35863 -350.336006) (xy 288.385926 -350.287371)
			(xy 288.420012 -350.243228) (xy 288.460161 -350.204519) (xy 288.505519 -350.172068) (xy 288.555119 -350.146567)
			(xy 288.607903 -350.12856) (xy 288.662746 -350.11843) (xy 288.71848 -350.116393) (xy 288.773917 -350.122493)
			(xy 288.827874 -350.136599) (xy 288.879203 -350.158411) (xy 288.926809 -350.187465) (xy 288.969677 -350.22314)
			(xy 289.006894 -350.264677) (xy 289.037667 -350.31119) (xy 289.061339 -350.361687) (xy 289.077407 -350.415094)
			(xy 289.085527 -350.47027) (xy 289.086036 -350.498156) (xy 289.085527 -350.526042) (xy 289.077407 -350.581218)
			(xy 289.061339 -350.634625) (xy 289.037667 -350.685122) (xy 289.006894 -350.731635) (xy 288.969677 -350.773172)
			(xy 288.926809 -350.808847) (xy 288.879203 -350.837901) (xy 288.827874 -350.859713) (xy 288.773917 -350.873819)
			(xy 288.71848 -350.879919) (xy 288.662746 -350.877882) (xy 288.607903 -350.867752) (xy 288.555119 -350.849745)
			(xy 288.505519 -350.824244) (xy 288.460161 -350.791793) (xy 288.420012 -350.753084) (xy 288.385926 -350.708941)
			(xy 288.35863 -350.660306) (xy 288.338707 -350.608215) (xy 288.326581 -350.553778) (xy 288.32251 -350.498156)
			(xy 287.9598 -350.498156) (xy 287.9598 -351.173796) (xy 289.661346 -351.173796) (xy 289.661819 -351.146321)
			(xy 289.669712 -351.09194) (xy 289.685335 -351.039257) (xy 289.708363 -350.989365) (xy 289.738318 -350.943297)
			(xy 289.756088 -350.922336) (xy 289.756342 -350.922082) (xy 289.761947 -350.915008) (xy 289.768182 -350.898082)
			(xy 289.768534 -350.889062) (xy 289.768534 -350.821498) (xy 289.76817 -350.812482) (xy 289.761926 -350.795565)
			(xy 289.756342 -350.788478) (xy 289.755834 -350.78797) (xy 289.738096 -350.767028) (xy 289.708213 -350.720994)
			(xy 289.685247 -350.671148) (xy 289.669674 -350.618522) (xy 289.661815 -350.564205) (xy 289.661346 -350.536764)
			(xy 289.661832 -350.509513) (xy 289.669588 -350.455565) (xy 289.684943 -350.40327) (xy 289.707585 -350.353693)
			(xy 289.737051 -350.307843) (xy 289.772742 -350.266652) (xy 289.813933 -350.230961) (xy 289.859783 -350.201495)
			(xy 289.90936 -350.178853) (xy 289.961655 -350.163498) (xy 290.015603 -350.155742) (xy 290.070105 -350.155742)
			(xy 290.124053 -350.163498) (xy 290.176348 -350.178853) (xy 290.225925 -350.201495) (xy 290.271775 -350.230961)
			(xy 290.312966 -350.266652) (xy 290.348657 -350.307843) (xy 290.378123 -350.353693) (xy 290.400765 -350.40327)
			(xy 290.41612 -350.455565) (xy 290.423876 -350.509513) (xy 290.424362 -350.536764) (xy 290.423864 -350.564238)
			(xy 290.415976 -350.618618) (xy 290.400359 -350.6713) (xy 290.397706 -350.67705) (xy 290.666172 -350.67705)
			(xy 290.666172 -350.62255) (xy 290.673928 -350.568604) (xy 290.689281 -350.516311) (xy 290.711921 -350.466735)
			(xy 290.741385 -350.420885) (xy 290.777074 -350.379695) (xy 290.818261 -350.344003) (xy 290.864108 -350.314535)
			(xy 290.913682 -350.291892) (xy 290.965974 -350.276534) (xy 291.01992 -350.268774) (xy 291.04717 -350.268286)
			(xy 291.047424 -350.268286) (xy 291.072628 -350.268669) (xy 291.122597 -350.275312) (xy 291.171252 -350.288494)
			(xy 291.217741 -350.307982) (xy 291.239702 -350.320356) (xy 291.249608 -350.326198) (xy 291.271452 -350.32823)
			(xy 291.366194 -350.294702) (xy 291.381942 -350.279208) (xy 291.386006 -350.268794) (xy 291.396677 -350.242007)
			(xy 291.424968 -350.191764) (xy 291.460501 -350.146354) (xy 291.502466 -350.106811) (xy 291.549907 -350.074039)
			(xy 291.601742 -350.048783) (xy 291.656789 -350.03162) (xy 291.713792 -350.022941) (xy 291.742622 -350.022414)
			(xy 291.769875 -350.022857) (xy 291.823825 -350.030617) (xy 291.876122 -350.045977) (xy 291.925701 -350.068622)
			(xy 291.971552 -350.098092) (xy 292.012743 -350.133788) (xy 292.048434 -350.174983) (xy 292.077899 -350.220838)
			(xy 292.100539 -350.270419) (xy 292.115892 -350.322718) (xy 292.123646 -350.376669) (xy 292.12413 -350.403922)
			(xy 292.12346 -350.435484) (xy 292.113076 -350.497749) (xy 292.092595 -350.557459) (xy 292.078156 -350.585532)
			(xy 292.07333 -350.594422) (xy 292.071298 -350.61398) (xy 292.094158 -350.692466) (xy 292.097398 -350.70189)
			(xy 292.109813 -350.717451) (xy 292.118288 -350.722692) (xy 292.143411 -350.737205) (xy 292.189294 -350.772714)
			(xy 292.229268 -350.814763) (xy 292.262412 -350.862383) (xy 292.287959 -350.914474) (xy 292.30532 -350.969834)
			(xy 292.314095 -351.027185) (xy 292.31463 -351.056194) (xy 292.314144 -351.083445) (xy 292.306388 -351.137393)
			(xy 292.291033 -351.189688) (xy 292.268391 -351.239265) (xy 292.238925 -351.285115) (xy 292.203234 -351.326306)
			(xy 292.162043 -351.361997) (xy 292.116193 -351.391463) (xy 292.066616 -351.414105) (xy 292.014321 -351.42946)
			(xy 291.960373 -351.437216) (xy 291.905871 -351.437216) (xy 291.851923 -351.42946) (xy 291.799628 -351.414105)
			(xy 291.750051 -351.391463) (xy 291.704201 -351.361997) (xy 291.66301 -351.326306) (xy 291.627319 -351.285115)
			(xy 291.597853 -351.239265) (xy 291.575211 -351.189688) (xy 291.559856 -351.137393) (xy 291.5521 -351.083445)
			(xy 291.551614 -351.056194) (xy 291.552285 -351.024632) (xy 291.562667 -350.962367) (xy 291.583149 -350.902657)
			(xy 291.597588 -350.874584) (xy 291.602414 -350.865694) (xy 291.604446 -350.846136) (xy 291.581586 -350.76765)
			(xy 291.578363 -350.75822) (xy 291.565934 -350.742664) (xy 291.557456 -350.737424) (xy 291.55009 -350.73336)
			(xy 291.540184 -350.727518) (xy 291.51834 -350.725486) (xy 291.423598 -350.759014) (xy 291.40785 -350.774508)
			(xy 291.403786 -350.784922) (xy 291.39313 -350.811715) (xy 291.364837 -350.861958) (xy 291.329301 -350.907368)
			(xy 291.287333 -350.94691) (xy 291.23989 -350.979681) (xy 291.188054 -351.004936) (xy 291.133005 -351.022098)
			(xy 291.076001 -351.030775) (xy 291.04717 -351.031302) (xy 291.01992 -351.030826) (xy 290.965974 -351.023066)
			(xy 290.913682 -351.007708) (xy 290.864108 -350.985065) (xy 290.818261 -350.955597) (xy 290.777074 -350.919905)
			(xy 290.741385 -350.878715) (xy 290.711921 -350.832865) (xy 290.689281 -350.783289) (xy 290.673928 -350.730996)
			(xy 290.666172 -350.67705) (xy 290.397706 -350.67705) (xy 290.377337 -350.721193) (xy 290.347387 -350.767262)
			(xy 290.32962 -350.788224) (xy 290.329366 -350.788478) (xy 290.323779 -350.795564) (xy 290.317534 -350.812481)
			(xy 290.317174 -350.821498) (xy 290.317174 -350.889062) (xy 290.317555 -350.898076) (xy 290.323786 -350.914993)
			(xy 290.329366 -350.922082) (xy 290.329874 -350.92259) (xy 290.347595 -350.943547) (xy 290.37748 -350.989576)
			(xy 290.400449 -351.039419) (xy 290.416027 -351.092042) (xy 290.42389 -351.146356) (xy 290.424362 -351.173796)
			(xy 290.423876 -351.201047) (xy 290.41612 -351.254995) (xy 290.400765 -351.30729) (xy 290.378123 -351.356867)
			(xy 290.348657 -351.402717) (xy 290.312966 -351.443908) (xy 290.271775 -351.479599) (xy 290.225925 -351.509065)
			(xy 290.176348 -351.531707) (xy 290.124053 -351.547062) (xy 290.070105 -351.554818) (xy 290.015603 -351.554818)
			(xy 289.961655 -351.547062) (xy 289.90936 -351.531707) (xy 289.859783 -351.509065) (xy 289.813933 -351.479599)
			(xy 289.772742 -351.443908) (xy 289.737051 -351.402717) (xy 289.707585 -351.356867) (xy 289.684943 -351.30729)
			(xy 289.669588 -351.254995) (xy 289.661832 -351.201047) (xy 289.661346 -351.173796) (xy 287.9598 -351.173796)
			(xy 287.9598 -351.737422) (xy 287.960187 -351.747496) (xy 287.967932 -351.766095) (xy 287.974786 -351.77349)
			(xy 288.663888 -352.462338) (xy 288.671294 -352.469171) (xy 288.689889 -352.476894) (xy 288.699956 -352.477324)
			(xy 292.68928 -352.477324) (xy 292.699351 -352.476908) (xy 292.71795 -352.469183) (xy 292.725348 -352.462338)
			(xy 293.008558 -352.179128) (xy 293.015372 -352.171707) (xy 293.023108 -352.153124) (xy 293.023544 -352.14306)
			(xy 293.023544 -350.067372) (xy 293.023148 -350.057299) (xy 293.015408 -350.038701) (xy 293.008558 -350.031304)
			(xy 292.152578 -349.17507) (xy 292.145729 -349.167677) (xy 292.138015 -349.149072) (xy 292.137592 -349.139002)
			(xy 292.137592 -346.977208) (xy 292.137915 -346.967157) (xy 292.145534 -346.94856) (xy 292.152324 -346.94114)
			(xy 292.328854 -346.76461) (xy 292.336277 -346.757799) (xy 292.354859 -346.750062) (xy 292.364922 -346.749624)
			(xy 295.4401 -346.749624) (xy 295.45017 -346.750043) (xy 295.468768 -346.757768) (xy 295.476168 -346.76461)
			(xy 295.803574 -347.092016) (xy 295.81041 -347.09942) (xy 295.818133 -347.118016) (xy 295.81856 -347.128084)
			(xy 295.81856 -348.252034) (xy 295.818952 -348.262107) (xy 295.826694 -348.280706) (xy 295.833546 -348.288102)
			(xy 295.916556 -348.37116) (xy 296.300398 -348.37116) (xy 296.300865 -348.343248) (xy 296.309005 -348.288021)
			(xy 296.325107 -348.23457) (xy 296.348825 -348.184036) (xy 296.379655 -348.137497) (xy 296.397934 -348.116398)
			(xy 296.403836 -348.109224) (xy 296.410483 -348.091896) (xy 296.410888 -348.082616) (xy 296.410888 -348.004892)
			(xy 296.404284 -347.98762) (xy 296.397934 -347.980508) (xy 296.379628 -347.959432) (xy 296.348807 -347.912886)
			(xy 296.325098 -347.862345) (xy 296.309008 -347.808889) (xy 296.30088 -347.753659) (xy 296.300398 -347.725746)
			(xy 296.300884 -347.698495) (xy 296.30864 -347.644547) (xy 296.323995 -347.592252) (xy 296.346637 -347.542675)
			(xy 296.376103 -347.496825) (xy 296.411794 -347.455634) (xy 296.452985 -347.419943) (xy 296.498835 -347.390477)
			(xy 296.548412 -347.367835) (xy 296.600707 -347.35248) (xy 296.654655 -347.344724) (xy 296.709157 -347.344724)
			(xy 296.763105 -347.35248) (xy 296.8154 -347.367835) (xy 296.864977 -347.390477) (xy 296.910827 -347.419943)
			(xy 296.952018 -347.455634) (xy 296.987709 -347.496825) (xy 297.017175 -347.542675) (xy 297.039817 -347.592252)
			(xy 297.055172 -347.644547) (xy 297.062928 -347.698495) (xy 297.063414 -347.725746) (xy 297.062948 -347.753658)
			(xy 297.054807 -347.808885) (xy 297.038705 -347.862336) (xy 297.014986 -347.91287) (xy 296.984157 -347.959409)
			(xy 296.965878 -347.980508) (xy 296.959975 -347.987681) (xy 296.953328 -348.005009) (xy 296.952924 -348.01429)
			(xy 296.952924 -348.092014) (xy 296.959528 -348.109286) (xy 296.965878 -348.116398) (xy 296.984126 -348.137523)
			(xy 297.014958 -348.184054) (xy 297.03868 -348.234582) (xy 297.054783 -348.288028) (xy 297.062925 -348.34325)
			(xy 297.063414 -348.37116) (xy 297.062928 -348.398411) (xy 297.055172 -348.452359) (xy 297.039817 -348.504654)
			(xy 297.017175 -348.554231) (xy 296.987709 -348.600081) (xy 296.952018 -348.641272) (xy 296.910827 -348.676963)
			(xy 296.864977 -348.706429) (xy 296.8154 -348.729071) (xy 296.763105 -348.744426) (xy 296.709157 -348.752182)
			(xy 296.654655 -348.752182) (xy 296.600707 -348.744426) (xy 296.548412 -348.729071) (xy 296.498835 -348.706429)
			(xy 296.452985 -348.676963) (xy 296.411794 -348.641272) (xy 296.376103 -348.600081) (xy 296.346637 -348.554231)
			(xy 296.323995 -348.504654) (xy 296.30864 -348.452359) (xy 296.300884 -348.398411) (xy 296.300398 -348.37116)
			(xy 295.916556 -348.37116) (xy 296.276014 -348.730824) (xy 296.282859 -348.73822) (xy 296.290575 -348.756822)
			(xy 296.291 -348.766892) (xy 296.291 -349.602806) (xy 297.25823 -349.602806) (xy 297.262301 -349.547184)
			(xy 297.274427 -349.492747) (xy 297.29435 -349.440656) (xy 297.321646 -349.392021) (xy 297.355732 -349.347878)
			(xy 297.395881 -349.309169) (xy 297.441239 -349.276718) (xy 297.490839 -349.251217) (xy 297.543623 -349.23321)
			(xy 297.598466 -349.22308) (xy 297.6542 -349.221043) (xy 297.709637 -349.227143) (xy 297.763594 -349.241249)
			(xy 297.814923 -349.263061) (xy 297.862529 -349.292115) (xy 297.905397 -349.32779) (xy 297.942614 -349.369327)
			(xy 297.973387 -349.41584) (xy 297.997059 -349.466337) (xy 298.013127 -349.519744) (xy 298.021247 -349.57492)
			(xy 298.021756 -349.602806) (xy 298.021247 -349.630692) (xy 298.013127 -349.685868) (xy 297.997059 -349.739275)
			(xy 297.973387 -349.789772) (xy 297.942614 -349.836285) (xy 297.905397 -349.877822) (xy 297.862529 -349.913497)
			(xy 297.814923 -349.942551) (xy 297.763594 -349.964363) (xy 297.709637 -349.978469) (xy 297.6542 -349.984569)
			(xy 297.598466 -349.982532) (xy 297.543623 -349.972402) (xy 297.490839 -349.954395) (xy 297.441239 -349.928894)
			(xy 297.395881 -349.896443) (xy 297.355732 -349.857734) (xy 297.321646 -349.813591) (xy 297.29435 -349.764956)
			(xy 297.274427 -349.712865) (xy 297.262301 -349.658428) (xy 297.25823 -349.602806) (xy 296.291 -349.602806)
			(xy 296.291 -350.498156) (xy 296.67911 -350.498156) (xy 296.683181 -350.442534) (xy 296.695307 -350.388097)
			(xy 296.71523 -350.336006) (xy 296.742526 -350.287371) (xy 296.776612 -350.243228) (xy 296.816761 -350.204519)
			(xy 296.862119 -350.172068) (xy 296.911719 -350.146567) (xy 296.964503 -350.12856) (xy 297.019346 -350.11843)
			(xy 297.07508 -350.116393) (xy 297.130517 -350.122493) (xy 297.184474 -350.136599) (xy 297.235803 -350.158411)
			(xy 297.283409 -350.187465) (xy 297.326277 -350.22314) (xy 297.363494 -350.264677) (xy 297.394267 -350.31119)
			(xy 297.417939 -350.361687) (xy 297.434007 -350.415094) (xy 297.442127 -350.47027) (xy 297.442636 -350.498156)
			(xy 297.442127 -350.526042) (xy 297.434007 -350.581218) (xy 297.417939 -350.634625) (xy 297.394267 -350.685122)
			(xy 297.363494 -350.731635) (xy 297.326277 -350.773172) (xy 297.283409 -350.808847) (xy 297.235803 -350.837901)
			(xy 297.184474 -350.859713) (xy 297.130517 -350.873819) (xy 297.07508 -350.879919) (xy 297.019346 -350.877882)
			(xy 296.964503 -350.867752) (xy 296.911719 -350.849745) (xy 296.862119 -350.824244) (xy 296.816761 -350.791793)
			(xy 296.776612 -350.753084) (xy 296.742526 -350.708941) (xy 296.71523 -350.660306) (xy 296.695307 -350.608215)
			(xy 296.683181 -350.553778) (xy 296.67911 -350.498156) (xy 296.291 -350.498156) (xy 296.291 -351.173796)
			(xy 298.017946 -351.173796) (xy 298.018419 -351.146321) (xy 298.026312 -351.09194) (xy 298.041935 -351.039257)
			(xy 298.064963 -350.989365) (xy 298.094918 -350.943297) (xy 298.112688 -350.922336) (xy 298.112942 -350.922082)
			(xy 298.118547 -350.915008) (xy 298.124782 -350.898082) (xy 298.125134 -350.889062) (xy 298.125134 -350.821498)
			(xy 298.12477 -350.812482) (xy 298.118526 -350.795565) (xy 298.112942 -350.788478) (xy 298.112434 -350.78797)
			(xy 298.094696 -350.767028) (xy 298.064813 -350.720994) (xy 298.041847 -350.671148) (xy 298.026274 -350.618522)
			(xy 298.018415 -350.564205) (xy 298.017946 -350.536764) (xy 298.018432 -350.509513) (xy 298.026188 -350.455565)
			(xy 298.041543 -350.40327) (xy 298.064185 -350.353693) (xy 298.093651 -350.307843) (xy 298.129342 -350.266652)
			(xy 298.170533 -350.230961) (xy 298.216383 -350.201495) (xy 298.26596 -350.178853) (xy 298.318255 -350.163498)
			(xy 298.372203 -350.155742) (xy 298.426705 -350.155742) (xy 298.480653 -350.163498) (xy 298.532948 -350.178853)
			(xy 298.582525 -350.201495) (xy 298.628375 -350.230961) (xy 298.669566 -350.266652) (xy 298.705257 -350.307843)
			(xy 298.734723 -350.353693) (xy 298.757365 -350.40327) (xy 298.77272 -350.455565) (xy 298.780476 -350.509513)
			(xy 298.780962 -350.536764) (xy 298.780464 -350.564238) (xy 298.772576 -350.618618) (xy 298.756959 -350.6713)
			(xy 298.754306 -350.67705) (xy 299.022772 -350.67705) (xy 299.022772 -350.62255) (xy 299.030528 -350.568604)
			(xy 299.045881 -350.516311) (xy 299.068521 -350.466735) (xy 299.097985 -350.420885) (xy 299.133674 -350.379695)
			(xy 299.174861 -350.344003) (xy 299.220708 -350.314535) (xy 299.270282 -350.291892) (xy 299.322574 -350.276534)
			(xy 299.37652 -350.268774) (xy 299.40377 -350.268286) (xy 299.404024 -350.268286) (xy 299.429228 -350.268669)
			(xy 299.479197 -350.275312) (xy 299.527852 -350.288494) (xy 299.574341 -350.307982) (xy 299.596302 -350.320356)
			(xy 299.606208 -350.326198) (xy 299.628052 -350.32823) (xy 299.722794 -350.294702) (xy 299.738542 -350.279208)
			(xy 299.742606 -350.268794) (xy 299.753277 -350.242007) (xy 299.781568 -350.191764) (xy 299.817101 -350.146354)
			(xy 299.859066 -350.106811) (xy 299.906507 -350.074039) (xy 299.958342 -350.048783) (xy 300.013389 -350.03162)
			(xy 300.070392 -350.022941) (xy 300.099222 -350.022414) (xy 300.126475 -350.022857) (xy 300.180425 -350.030617)
			(xy 300.232722 -350.045977) (xy 300.282301 -350.068622) (xy 300.328152 -350.098092) (xy 300.369343 -350.133788)
			(xy 300.405034 -350.174983) (xy 300.434499 -350.220838) (xy 300.457139 -350.270419) (xy 300.472492 -350.322718)
			(xy 300.480246 -350.376669) (xy 300.48073 -350.403922) (xy 300.48006 -350.435484) (xy 300.469676 -350.497749)
			(xy 300.449195 -350.557459) (xy 300.434756 -350.585532) (xy 300.42993 -350.594422) (xy 300.427898 -350.61398)
			(xy 300.450758 -350.692466) (xy 300.453998 -350.70189) (xy 300.466413 -350.717451) (xy 300.474888 -350.722692)
			(xy 300.500011 -350.737205) (xy 300.545894 -350.772714) (xy 300.585868 -350.814763) (xy 300.619012 -350.862383)
			(xy 300.644559 -350.914474) (xy 300.66192 -350.969834) (xy 300.670695 -351.027185) (xy 300.67123 -351.056194)
			(xy 300.670744 -351.083445) (xy 300.662988 -351.137393) (xy 300.647633 -351.189688) (xy 300.624991 -351.239265)
			(xy 300.595525 -351.285115) (xy 300.559834 -351.326306) (xy 300.518643 -351.361997) (xy 300.472793 -351.391463)
			(xy 300.423216 -351.414105) (xy 300.370921 -351.42946) (xy 300.316973 -351.437216) (xy 300.262471 -351.437216)
			(xy 300.208523 -351.42946) (xy 300.156228 -351.414105) (xy 300.106651 -351.391463) (xy 300.060801 -351.361997)
			(xy 300.01961 -351.326306) (xy 299.983919 -351.285115) (xy 299.954453 -351.239265) (xy 299.931811 -351.189688)
			(xy 299.916456 -351.137393) (xy 299.9087 -351.083445) (xy 299.908214 -351.056194) (xy 299.908885 -351.024632)
			(xy 299.919267 -350.962367) (xy 299.939749 -350.902657) (xy 299.954188 -350.874584) (xy 299.959014 -350.865694)
			(xy 299.961046 -350.846136) (xy 299.938186 -350.76765) (xy 299.934963 -350.75822) (xy 299.922534 -350.742664)
			(xy 299.914056 -350.737424) (xy 299.90669 -350.73336) (xy 299.896784 -350.727518) (xy 299.87494 -350.725486)
			(xy 299.780198 -350.759014) (xy 299.76445 -350.774508) (xy 299.760386 -350.784922) (xy 299.74973 -350.811715)
			(xy 299.721437 -350.861958) (xy 299.685901 -350.907368) (xy 299.643933 -350.94691) (xy 299.59649 -350.979681)
			(xy 299.544654 -351.004936) (xy 299.489605 -351.022098) (xy 299.432601 -351.030775) (xy 299.40377 -351.031302)
			(xy 299.37652 -351.030826) (xy 299.322574 -351.023066) (xy 299.270282 -351.007708) (xy 299.220708 -350.985065)
			(xy 299.174861 -350.955597) (xy 299.133674 -350.919905) (xy 299.097985 -350.878715) (xy 299.068521 -350.832865)
			(xy 299.045881 -350.783289) (xy 299.030528 -350.730996) (xy 299.022772 -350.67705) (xy 298.754306 -350.67705)
			(xy 298.733937 -350.721193) (xy 298.703987 -350.767262) (xy 298.68622 -350.788224) (xy 298.685966 -350.788478)
			(xy 298.680379 -350.795564) (xy 298.674134 -350.812481) (xy 298.673774 -350.821498) (xy 298.673774 -350.889062)
			(xy 298.674155 -350.898076) (xy 298.680386 -350.914993) (xy 298.685966 -350.922082) (xy 298.686474 -350.92259)
			(xy 298.704195 -350.943547) (xy 298.73408 -350.989576) (xy 298.757049 -351.039419) (xy 298.772627 -351.092042)
			(xy 298.78049 -351.146356) (xy 298.780962 -351.173796) (xy 298.780476 -351.201047) (xy 298.77272 -351.254995)
			(xy 298.757365 -351.30729) (xy 298.734723 -351.356867) (xy 298.705257 -351.402717) (xy 298.669566 -351.443908)
			(xy 298.628375 -351.479599) (xy 298.582525 -351.509065) (xy 298.532948 -351.531707) (xy 298.480653 -351.547062)
			(xy 298.426705 -351.554818) (xy 298.372203 -351.554818) (xy 298.318255 -351.547062) (xy 298.26596 -351.531707)
			(xy 298.216383 -351.509065) (xy 298.170533 -351.479599) (xy 298.129342 -351.443908) (xy 298.093651 -351.402717)
			(xy 298.064185 -351.356867) (xy 298.041543 -351.30729) (xy 298.026188 -351.254995) (xy 298.018432 -351.201047)
			(xy 298.017946 -351.173796) (xy 296.291 -351.173796) (xy 296.291 -351.701862) (xy 296.291419 -351.711933)
			(xy 296.299141 -351.730532) (xy 296.305986 -351.73793) (xy 296.949368 -352.381058) (xy 296.95679 -352.387871)
			(xy 296.975372 -352.395608) (xy 296.985436 -352.396044) (xy 301.1551 -352.396044) (xy 301.165171 -352.395633)
			(xy 301.18377 -352.387904) (xy 301.191168 -352.381058) (xy 301.380398 -352.191828) (xy 301.387218 -352.184412)
			(xy 301.394949 -352.165825) (xy 301.395384 -352.15576) (xy 301.395384 -350.041972) (xy 301.394978 -350.031901)
			(xy 301.387244 -350.013303) (xy 301.380398 -350.005904) (xy 300.509178 -349.13443) (xy 300.502355 -349.127016)
			(xy 300.494626 -349.108427) (xy 300.494192 -349.098362) (xy 300.494192 -346.949268) (xy 300.494546 -346.939221)
			(xy 300.502144 -346.920623) (xy 300.508924 -346.9132) (xy 300.682914 -346.73921) (xy 300.690316 -346.732373)
			(xy 300.708914 -346.724651) (xy 300.718982 -346.724224) (xy 303.869852 -346.724224) (xy 303.879919 -346.724668)
			(xy 303.898518 -346.732375) (xy 303.90592 -346.73921) (xy 304.183034 -347.016324) (xy 304.189882 -347.023718)
			(xy 304.197596 -347.042322) (xy 304.19802 -347.052392) (xy 304.19802 -348.267274) (xy 304.198454 -348.277342)
			(xy 304.206168 -348.295941) (xy 304.213006 -348.303342) (xy 304.280783 -348.37116) (xy 304.631598 -348.37116)
			(xy 304.632065 -348.343248) (xy 304.640205 -348.288021) (xy 304.656307 -348.23457) (xy 304.680025 -348.184036)
			(xy 304.710855 -348.137497) (xy 304.729134 -348.116398) (xy 304.735036 -348.109224) (xy 304.741683 -348.091896)
			(xy 304.742088 -348.082616) (xy 304.742088 -348.004892) (xy 304.735484 -347.98762) (xy 304.729134 -347.980508)
			(xy 304.710828 -347.959432) (xy 304.680007 -347.912886) (xy 304.656298 -347.862345) (xy 304.640208 -347.808889)
			(xy 304.63208 -347.753659) (xy 304.631598 -347.725746) (xy 304.632084 -347.698495) (xy 304.63984 -347.644547)
			(xy 304.655195 -347.592252) (xy 304.677837 -347.542675) (xy 304.707303 -347.496825) (xy 304.742994 -347.455634)
			(xy 304.784185 -347.419943) (xy 304.830035 -347.390477) (xy 304.879612 -347.367835) (xy 304.931907 -347.35248)
			(xy 304.985855 -347.344724) (xy 305.040357 -347.344724) (xy 305.094305 -347.35248) (xy 305.1466 -347.367835)
			(xy 305.196177 -347.390477) (xy 305.242027 -347.419943) (xy 305.283218 -347.455634) (xy 305.318909 -347.496825)
			(xy 305.348375 -347.542675) (xy 305.371017 -347.592252) (xy 305.386372 -347.644547) (xy 305.394128 -347.698495)
			(xy 305.394614 -347.725746) (xy 305.394148 -347.753658) (xy 305.386007 -347.808885) (xy 305.369905 -347.862336)
			(xy 305.346186 -347.91287) (xy 305.315357 -347.959409) (xy 305.297078 -347.980508) (xy 305.291175 -347.987681)
			(xy 305.284528 -348.005009) (xy 305.284124 -348.01429) (xy 305.284124 -348.092014) (xy 305.290728 -348.109286)
			(xy 305.297078 -348.116398) (xy 305.315326 -348.137523) (xy 305.346158 -348.184054) (xy 305.36988 -348.234582)
			(xy 305.385983 -348.288028) (xy 305.394125 -348.34325) (xy 305.394614 -348.37116) (xy 305.394128 -348.398411)
			(xy 305.386372 -348.452359) (xy 305.371017 -348.504654) (xy 305.348375 -348.554231) (xy 305.318909 -348.600081)
			(xy 305.283218 -348.641272) (xy 305.242027 -348.676963) (xy 305.196177 -348.706429) (xy 305.1466 -348.729071)
			(xy 305.094305 -348.744426) (xy 305.040357 -348.752182) (xy 304.985855 -348.752182) (xy 304.931907 -348.744426)
			(xy 304.879612 -348.729071) (xy 304.830035 -348.706429) (xy 304.784185 -348.676963) (xy 304.742994 -348.641272)
			(xy 304.707303 -348.600081) (xy 304.677837 -348.554231) (xy 304.655195 -348.504654) (xy 304.63984 -348.452359)
			(xy 304.632084 -348.398411) (xy 304.631598 -348.37116) (xy 304.280783 -348.37116) (xy 304.632614 -348.723204)
			(xy 304.63945 -348.730607) (xy 304.647172 -348.749204) (xy 304.6476 -348.759272) (xy 304.6476 -349.602806)
			(xy 305.58943 -349.602806) (xy 305.593501 -349.547184) (xy 305.605627 -349.492747) (xy 305.62555 -349.440656)
			(xy 305.652846 -349.392021) (xy 305.686932 -349.347878) (xy 305.727081 -349.309169) (xy 305.772439 -349.276718)
			(xy 305.822039 -349.251217) (xy 305.874823 -349.23321) (xy 305.929666 -349.22308) (xy 305.9854 -349.221043)
			(xy 306.040837 -349.227143) (xy 306.094794 -349.241249) (xy 306.146123 -349.263061) (xy 306.193729 -349.292115)
			(xy 306.236597 -349.32779) (xy 306.273814 -349.369327) (xy 306.304587 -349.41584) (xy 306.328259 -349.466337)
			(xy 306.343564 -349.517208) (xy 308.859936 -349.517208) (xy 308.859936 -347.28785) (xy 308.860356 -347.263877)
			(xy 308.86786 -347.216523) (xy 308.88269 -347.170929) (xy 308.90448 -347.128221) (xy 308.932692 -347.089455)
			(xy 308.949344 -347.072204) (xy 309.19166 -346.830142) (xy 309.192168 -346.829634) (xy 309.227474 -346.793312)
			(xy 309.231219 -346.789571) (xy 309.23992 -346.783547) (xy 309.244746 -346.781374) (xy 309.340504 -346.742766)
			(xy 309.34507 -346.741007) (xy 309.354663 -346.739092) (xy 309.359554 -346.738956) (xy 313.644534 -346.738956)
			(xy 313.668507 -346.73938) (xy 313.715861 -346.746882) (xy 313.761455 -346.761711) (xy 313.804163 -346.7835)
			(xy 313.842929 -346.811712) (xy 313.86018 -346.828364) (xy 314.950094 -347.918278) (xy 314.957504 -347.925105)
			(xy 314.976096 -347.932833) (xy 314.986162 -347.933264) (xy 319.450212 -347.933264) (xy 319.460283 -347.932854)
			(xy 319.478881 -347.925124) (xy 319.48628 -347.918278) (xy 321.22237 -346.182188) (xy 321.229203 -346.174783)
			(xy 321.236928 -346.156188) (xy 321.237356 -346.14612) (xy 321.237356 -343.551764) (xy 321.236961 -343.541691)
			(xy 321.22922 -343.523093) (xy 321.22237 -343.515696) (xy 320.128392 -342.421464) (xy 320.127884 -342.420956)
			(xy 320.091308 -342.38565) (xy 320.087623 -342.381901) (xy 320.081741 -342.37319) (xy 320.079624 -342.368378)
			(xy 320.040762 -342.27262) (xy 320.03901 -342.268052) (xy 320.03709 -342.25846) (xy 320.036952 -342.25357)
			(xy 320.036952 -340.791546) (xy 320.036515 -340.781478) (xy 320.028804 -340.762879) (xy 320.021966 -340.755478)
			(xy 319.467738 -340.200996) (xy 319.46723 -340.200488) (xy 319.430908 -340.165182) (xy 319.427158 -340.161445)
			(xy 319.421139 -340.152739) (xy 319.41897 -340.14791) (xy 319.380362 -340.052152) (xy 319.378618 -340.047581)
			(xy 319.376693 -340.037992) (xy 319.376552 -340.033102) (xy 319.376552 -338.319872) (xy 319.376154 -338.309799)
			(xy 319.368415 -338.291201) (xy 319.361566 -338.283804) (xy 318.564768 -337.487006) (xy 318.56426 -337.486498)
			(xy 318.527684 -337.451192) (xy 318.524016 -337.447427) (xy 318.518123 -337.438728) (xy 318.516 -337.43392)
			(xy 318.477138 -337.338162) (xy 318.475373 -337.333598) (xy 318.473461 -337.324003) (xy 318.473328 -337.319112)
			(xy 318.473328 -335.36001) (xy 318.473453 -335.355119) (xy 318.475379 -335.345526) (xy 318.477138 -335.34096)
			(xy 318.516 -335.245202) (xy 318.518094 -335.240378) (xy 318.523985 -335.231668) (xy 318.527684 -335.22793)
			(xy 318.56426 -335.192624) (xy 318.564768 -335.192116) (xy 318.619124 -335.137506) (xy 318.636409 -335.120846)
			(xy 318.675221 -335.092595) (xy 318.717974 -335.070764) (xy 318.763615 -335.055888) (xy 318.811022 -335.048336)
			(xy 318.835024 -335.047844) (xy 321.776598 -335.047844) (xy 321.800604 -335.048281) (xy 321.848019 -335.05583)
			(xy 321.893667 -335.07071) (xy 321.936422 -335.092554) (xy 321.97523 -335.120823) (xy 321.992498 -335.137506)
			(xy 322.120514 -335.265776) (xy 322.121022 -335.266284) (xy 322.157344 -335.30159) (xy 322.161095 -335.305326)
			(xy 322.167112 -335.314033) (xy 322.169282 -335.318862) (xy 322.20789 -335.41462) (xy 322.209651 -335.419185)
			(xy 322.211565 -335.428779) (xy 322.2117 -335.43367) (xy 322.2117 -336.588354) (xy 322.212123 -336.598424)
			(xy 322.219843 -336.617023) (xy 322.226686 -336.624422) (xy 322.245228 -336.642964) (xy 322.636896 -336.642964)
			(xy 322.637366 -336.615052) (xy 322.645505 -336.559825) (xy 322.661606 -336.506374) (xy 322.685324 -336.45584)
			(xy 322.716153 -336.409301) (xy 322.734432 -336.388202) (xy 322.740332 -336.381027) (xy 322.74698 -336.3637)
			(xy 322.747386 -336.35442) (xy 322.747386 -336.276696) (xy 322.740782 -336.259424) (xy 322.734432 -336.252312)
			(xy 322.716127 -336.231235) (xy 322.685306 -336.184689) (xy 322.661597 -336.134149) (xy 322.645507 -336.080693)
			(xy 322.637378 -336.025463) (xy 322.636896 -335.99755) (xy 322.637382 -335.970299) (xy 322.645138 -335.916351)
			(xy 322.660493 -335.864056) (xy 322.683135 -335.814479) (xy 322.712601 -335.768629) (xy 322.748292 -335.727438)
			(xy 322.789483 -335.691747) (xy 322.835333 -335.662281) (xy 322.88491 -335.639639) (xy 322.937205 -335.624284)
			(xy 322.991153 -335.616528) (xy 323.045655 -335.616528) (xy 323.099603 -335.624284) (xy 323.151898 -335.639639)
			(xy 323.201475 -335.662281) (xy 323.247325 -335.691747) (xy 323.288516 -335.727438) (xy 323.324207 -335.768629)
			(xy 323.353673 -335.814479) (xy 323.376315 -335.864056) (xy 323.39167 -335.916351) (xy 323.399426 -335.970299)
			(xy 323.399912 -335.99755) (xy 323.399449 -336.025462) (xy 323.391307 -336.080689) (xy 323.375205 -336.13414)
			(xy 323.351485 -336.184674) (xy 323.320655 -336.231213) (xy 323.302376 -336.252312) (xy 323.296471 -336.259483)
			(xy 323.289825 -336.276813) (xy 323.289422 -336.286094) (xy 323.289422 -336.363818) (xy 323.296026 -336.38109)
			(xy 323.302376 -336.388202) (xy 323.320625 -336.409326) (xy 323.351457 -336.455857) (xy 323.375179 -336.506385)
			(xy 323.391282 -336.559832) (xy 323.399423 -336.615054) (xy 323.399912 -336.642964) (xy 323.399426 -336.670215)
			(xy 323.39167 -336.724163) (xy 323.376315 -336.776458) (xy 323.353673 -336.826035) (xy 323.324207 -336.871885)
			(xy 323.288516 -336.913076) (xy 323.247325 -336.948767) (xy 323.201475 -336.978233) (xy 323.151898 -337.000875)
			(xy 323.099603 -337.01623) (xy 323.045655 -337.023986) (xy 322.991153 -337.023986) (xy 322.937205 -337.01623)
			(xy 322.88491 -337.000875) (xy 322.835333 -336.978233) (xy 322.789483 -336.948767) (xy 322.748292 -336.913076)
			(xy 322.712601 -336.871885) (xy 322.683135 -336.826035) (xy 322.660493 -336.776458) (xy 322.645138 -336.724163)
			(xy 322.637382 -336.670215) (xy 322.636896 -336.642964) (xy 322.245228 -336.642964) (xy 322.567808 -336.965544)
			(xy 322.568316 -336.966052) (xy 322.604892 -337.001358) (xy 322.608578 -337.005105) (xy 322.61446 -337.013818)
			(xy 322.616576 -337.01863) (xy 322.655438 -337.114388) (xy 322.657192 -337.118955) (xy 322.659111 -337.128547)
			(xy 322.659248 -337.133438) (xy 322.659248 -337.87461) (xy 323.594728 -337.87461) (xy 323.598799 -337.818988)
			(xy 323.610925 -337.764551) (xy 323.630848 -337.71246) (xy 323.658144 -337.663825) (xy 323.69223 -337.619682)
			(xy 323.732379 -337.580973) (xy 323.777737 -337.548522) (xy 323.827337 -337.523021) (xy 323.880121 -337.505014)
			(xy 323.934964 -337.494884) (xy 323.990698 -337.492847) (xy 324.046135 -337.498947) (xy 324.100092 -337.513053)
			(xy 324.151421 -337.534865) (xy 324.199027 -337.563919) (xy 324.241895 -337.599594) (xy 324.279112 -337.641131)
			(xy 324.309885 -337.687644) (xy 324.333557 -337.738141) (xy 324.349625 -337.791548) (xy 324.357745 -337.846724)
			(xy 324.358254 -337.87461) (xy 324.357745 -337.902496) (xy 324.349625 -337.957672) (xy 324.333557 -338.011079)
			(xy 324.309885 -338.061576) (xy 324.279112 -338.108089) (xy 324.241895 -338.149626) (xy 324.199027 -338.185301)
			(xy 324.151421 -338.214355) (xy 324.100092 -338.236167) (xy 324.046135 -338.250273) (xy 323.990698 -338.256373)
			(xy 323.934964 -338.254336) (xy 323.880121 -338.244206) (xy 323.827337 -338.226199) (xy 323.777737 -338.200698)
			(xy 323.732379 -338.168247) (xy 323.69223 -338.129538) (xy 323.658144 -338.085395) (xy 323.630848 -338.03676)
			(xy 323.610925 -337.984669) (xy 323.598799 -337.930232) (xy 323.594728 -337.87461) (xy 322.659248 -337.87461)
			(xy 322.659248 -338.76996) (xy 323.015608 -338.76996) (xy 323.019679 -338.714338) (xy 323.031805 -338.659901)
			(xy 323.051728 -338.60781) (xy 323.079024 -338.559175) (xy 323.11311 -338.515032) (xy 323.153259 -338.476323)
			(xy 323.198617 -338.443872) (xy 323.248217 -338.418371) (xy 323.301001 -338.400364) (xy 323.355844 -338.390234)
			(xy 323.411578 -338.388197) (xy 323.467015 -338.394297) (xy 323.520972 -338.408403) (xy 323.572301 -338.430215)
			(xy 323.619907 -338.459269) (xy 323.662775 -338.494944) (xy 323.699992 -338.536481) (xy 323.730765 -338.582994)
			(xy 323.754437 -338.633491) (xy 323.770505 -338.686898) (xy 323.778625 -338.742074) (xy 323.779134 -338.76996)
			(xy 323.778625 -338.797846) (xy 323.770505 -338.853022) (xy 323.754437 -338.906429) (xy 323.730765 -338.956926)
			(xy 323.699992 -339.003439) (xy 323.662775 -339.044976) (xy 323.619907 -339.080651) (xy 323.572301 -339.109705)
			(xy 323.520972 -339.131517) (xy 323.467015 -339.145623) (xy 323.411578 -339.151723) (xy 323.355844 -339.149686)
			(xy 323.301001 -339.139556) (xy 323.248217 -339.121549) (xy 323.198617 -339.096048) (xy 323.153259 -339.063597)
			(xy 323.11311 -339.024888) (xy 323.079024 -338.980745) (xy 323.051728 -338.93211) (xy 323.031805 -338.880019)
			(xy 323.019679 -338.825582) (xy 323.015608 -338.76996) (xy 322.659248 -338.76996) (xy 322.659248 -339.4456)
			(xy 324.354444 -339.4456) (xy 324.35492 -339.418125) (xy 324.362812 -339.363744) (xy 324.378434 -339.311061)
			(xy 324.401462 -339.261169) (xy 324.431417 -339.215101) (xy 324.449186 -339.19414) (xy 324.44944 -339.193886)
			(xy 324.455043 -339.186811) (xy 324.461279 -339.169885) (xy 324.461632 -339.160866) (xy 324.461632 -339.093302)
			(xy 324.461267 -339.084286) (xy 324.455024 -339.06737) (xy 324.44944 -339.060282) (xy 324.448932 -339.059774)
			(xy 324.431195 -339.03883) (xy 324.401312 -338.992797) (xy 324.378346 -338.942952) (xy 324.362772 -338.890326)
			(xy 324.354914 -338.836009) (xy 324.354444 -338.808568) (xy 324.35493 -338.781317) (xy 324.362686 -338.727369)
			(xy 324.378041 -338.675074) (xy 324.400683 -338.625497) (xy 324.430149 -338.579647) (xy 324.46584 -338.538456)
			(xy 324.507031 -338.502765) (xy 324.552881 -338.473299) (xy 324.602458 -338.450657) (xy 324.654753 -338.435302)
			(xy 324.708701 -338.427546) (xy 324.763203 -338.427546) (xy 324.817151 -338.435302) (xy 324.869446 -338.450657)
			(xy 324.919023 -338.473299) (xy 324.964873 -338.502765) (xy 325.006064 -338.538456) (xy 325.041755 -338.579647)
			(xy 325.071221 -338.625497) (xy 325.093863 -338.675074) (xy 325.109218 -338.727369) (xy 325.116974 -338.781317)
			(xy 325.11746 -338.808568) (xy 325.116965 -338.836042) (xy 325.109076 -338.890422) (xy 325.093459 -338.943105)
			(xy 325.090808 -338.94885) (xy 325.359276 -338.94885) (xy 325.359276 -338.89435) (xy 325.367031 -338.840405)
			(xy 325.382385 -338.788112) (xy 325.405024 -338.738537) (xy 325.434487 -338.692688) (xy 325.470176 -338.651498)
			(xy 325.511362 -338.615807) (xy 325.557209 -338.586339) (xy 325.606782 -338.563696) (xy 325.659074 -338.548338)
			(xy 325.713018 -338.540578) (xy 325.740268 -338.54009) (xy 325.740522 -338.54009) (xy 325.765726 -338.540473)
			(xy 325.815695 -338.547117) (xy 325.86435 -338.560298) (xy 325.910839 -338.579786) (xy 325.9328 -338.59216)
			(xy 325.942706 -338.598002) (xy 325.96455 -338.600034) (xy 326.059292 -338.566506) (xy 326.07504 -338.551012)
			(xy 326.079104 -338.540598) (xy 326.089779 -338.513812) (xy 326.118069 -338.46357) (xy 326.153601 -338.418159)
			(xy 326.195566 -338.378617) (xy 326.243007 -338.345844) (xy 326.294841 -338.320588) (xy 326.349887 -338.303424)
			(xy 326.40689 -338.294745) (xy 326.43572 -338.294218) (xy 326.462975 -338.294636) (xy 326.516928 -338.302397)
			(xy 326.569229 -338.317757) (xy 326.618811 -338.340403) (xy 326.664665 -338.369876) (xy 326.705858 -338.405574)
			(xy 326.741552 -338.446772) (xy 326.771019 -338.49263) (xy 326.793659 -338.542214) (xy 326.809013 -338.594517)
			(xy 326.816767 -338.648471) (xy 326.817228 -338.675726) (xy 326.81656 -338.707288) (xy 326.806176 -338.769553)
			(xy 326.785693 -338.829263) (xy 326.771254 -338.857336) (xy 326.766428 -338.866226) (xy 326.764396 -338.885784)
			(xy 326.787256 -338.96427) (xy 326.790496 -338.973694) (xy 326.802911 -338.989255) (xy 326.811386 -338.994496)
			(xy 326.83651 -339.009007) (xy 326.882393 -339.044516) (xy 326.922368 -339.086566) (xy 326.955511 -339.134186)
			(xy 326.981058 -339.186277) (xy 326.998419 -339.241637) (xy 327.007193 -339.298989) (xy 327.007728 -339.327998)
			(xy 327.007242 -339.355249) (xy 326.999486 -339.409197) (xy 326.984131 -339.461492) (xy 326.961489 -339.511069)
			(xy 326.932023 -339.556919) (xy 326.896332 -339.59811) (xy 326.855141 -339.633801) (xy 326.809291 -339.663267)
			(xy 326.759714 -339.685909) (xy 326.707419 -339.701264) (xy 326.653471 -339.70902) (xy 326.598969 -339.70902)
			(xy 326.545021 -339.701264) (xy 326.492726 -339.685909) (xy 326.443149 -339.663267) (xy 326.397299 -339.633801)
			(xy 326.356108 -339.59811) (xy 326.320417 -339.556919) (xy 326.290951 -339.511069) (xy 326.268309 -339.461492)
			(xy 326.252954 -339.409197) (xy 326.245198 -339.355249) (xy 326.244712 -339.327998) (xy 326.245385 -339.296436)
			(xy 326.255766 -339.234171) (xy 326.276247 -339.174461) (xy 326.290686 -339.146388) (xy 326.295512 -339.137498)
			(xy 326.297544 -339.11794) (xy 326.274684 -339.039454) (xy 326.27146 -339.030024) (xy 326.259032 -339.014468)
			(xy 326.250554 -339.009228) (xy 326.243188 -339.005164) (xy 326.233282 -338.999322) (xy 326.211438 -338.99729)
			(xy 326.116696 -339.030818) (xy 326.100948 -339.046312) (xy 326.096884 -339.056726) (xy 326.086232 -339.083521)
			(xy 326.057938 -339.133764) (xy 326.022402 -339.179173) (xy 325.980433 -339.218715) (xy 325.93299 -339.251486)
			(xy 325.881153 -339.276741) (xy 325.826104 -339.293902) (xy 325.769099 -339.30258) (xy 325.740268 -339.303106)
			(xy 325.713018 -339.302622) (xy 325.659074 -339.294862) (xy 325.606782 -339.279504) (xy 325.557209 -339.256861)
			(xy 325.511362 -339.227393) (xy 325.470176 -339.191702) (xy 325.434487 -339.150512) (xy 325.405024 -339.104663)
			(xy 325.382385 -339.055088) (xy 325.367031 -339.002795) (xy 325.359276 -338.94885) (xy 325.090808 -338.94885)
			(xy 325.070436 -338.992998) (xy 325.040485 -339.039066) (xy 325.022718 -339.060028) (xy 325.022464 -339.060282)
			(xy 325.016875 -339.067367) (xy 325.010631 -339.084285) (xy 325.010272 -339.093302) (xy 325.010272 -339.160866)
			(xy 325.010651 -339.16988) (xy 325.016884 -339.186797) (xy 325.022464 -339.193886) (xy 325.022972 -339.194394)
			(xy 325.040694 -339.215349) (xy 325.070579 -339.261379) (xy 325.093548 -339.311222) (xy 325.109125 -339.363845)
			(xy 325.116988 -339.41816) (xy 325.11746 -339.4456) (xy 325.116974 -339.472851) (xy 325.109218 -339.526799)
			(xy 325.093863 -339.579094) (xy 325.071221 -339.628671) (xy 325.041755 -339.674521) (xy 325.006064 -339.715712)
			(xy 324.964873 -339.751403) (xy 324.919023 -339.780869) (xy 324.869446 -339.803511) (xy 324.817151 -339.818866)
			(xy 324.763203 -339.826622) (xy 324.708701 -339.826622) (xy 324.654753 -339.818866) (xy 324.602458 -339.803511)
			(xy 324.552881 -339.780869) (xy 324.507031 -339.751403) (xy 324.46584 -339.715712) (xy 324.430149 -339.674521)
			(xy 324.400683 -339.628671) (xy 324.378041 -339.579094) (xy 324.362686 -339.526799) (xy 324.35493 -339.472851)
			(xy 324.354444 -339.4456) (xy 322.659248 -339.4456) (xy 322.659248 -340.068662) (xy 322.659681 -340.078731)
			(xy 322.667395 -340.097329) (xy 322.674234 -340.10473) (xy 323.21881 -340.649306) (xy 323.226212 -340.656144)
			(xy 323.24481 -340.663865) (xy 323.254878 -340.664292) (xy 327.479914 -340.664292) (xy 327.489958 -340.663906)
			(xy 327.508554 -340.656328) (xy 327.515982 -340.64956) (xy 327.710546 -340.454996) (xy 327.717387 -340.447597)
			(xy 327.725105 -340.428997) (xy 327.725532 -340.418928) (xy 327.725532 -338.294472) (xy 327.725139 -338.284399)
			(xy 327.717398 -338.2658) (xy 327.710546 -338.258404) (xy 326.920352 -337.46821) (xy 326.919844 -337.467702)
			(xy 326.883268 -337.432396) (xy 326.879599 -337.428632) (xy 326.873707 -337.419932) (xy 326.871584 -337.415124)
			(xy 326.832722 -337.319366) (xy 326.830958 -337.314802) (xy 326.829045 -337.305207) (xy 326.828912 -337.300316)
			(xy 326.828912 -335.28381) (xy 326.829038 -335.278919) (xy 326.830964 -335.269326) (xy 326.832722 -335.26476)
			(xy 326.871584 -335.169002) (xy 326.873681 -335.164179) (xy 326.87957 -335.155469) (xy 326.883268 -335.15173)
			(xy 326.91959 -335.116678) (xy 326.920606 -335.115662) (xy 326.928988 -335.107026) (xy 326.946293 -335.090387)
			(xy 326.985098 -335.062133) (xy 327.027846 -335.040297) (xy 327.073484 -335.025417) (xy 327.120887 -335.01786)
			(xy 327.144888 -335.017364) (xy 330.171806 -335.017364) (xy 330.181878 -335.01777) (xy 330.200476 -335.025502)
			(xy 330.207874 -335.03235) (xy 330.545694 -335.370424) (xy 330.552536 -335.377822) (xy 330.560255 -335.396423)
			(xy 330.56068 -335.406492) (xy 330.56068 -336.583782) (xy 330.561094 -336.593853) (xy 330.56882 -336.612452)
			(xy 330.575666 -336.61985) (xy 330.584302 -336.628486) (xy 330.994512 -336.628486) (xy 330.995016 -336.600576)
			(xy 331.003151 -336.545351) (xy 331.019245 -336.491901) (xy 331.042954 -336.441367) (xy 331.073774 -336.394825)
			(xy 331.092048 -336.373724) (xy 331.09794 -336.366544) (xy 331.104593 -336.349221) (xy 331.105002 -336.339942)
			(xy 331.105002 -336.262218) (xy 331.098398 -336.244946) (xy 331.092048 -336.237834) (xy 331.073756 -336.216746)
			(xy 331.042933 -336.170204) (xy 331.019221 -336.119666) (xy 331.003127 -336.066212) (xy 330.994996 -336.010984)
			(xy 330.994512 -335.983072) (xy 330.994998 -335.955821) (xy 331.002754 -335.901873) (xy 331.018109 -335.849578)
			(xy 331.040751 -335.800001) (xy 331.070217 -335.754151) (xy 331.105908 -335.71296) (xy 331.147099 -335.677269)
			(xy 331.192949 -335.647803) (xy 331.242526 -335.625161) (xy 331.294821 -335.609806) (xy 331.348769 -335.60205)
			(xy 331.403271 -335.60205) (xy 331.457219 -335.609806) (xy 331.509514 -335.625161) (xy 331.559091 -335.647803)
			(xy 331.604941 -335.677269) (xy 331.646132 -335.71296) (xy 331.681823 -335.754151) (xy 331.711289 -335.800001)
			(xy 331.733931 -335.849578) (xy 331.749286 -335.901873) (xy 331.757042 -335.955821) (xy 331.757528 -335.983072)
			(xy 331.757074 -336.010984) (xy 331.748929 -336.066211) (xy 331.732825 -336.119663) (xy 331.709103 -336.170197)
			(xy 331.678272 -336.216735) (xy 331.659992 -336.237834) (xy 331.65408 -336.245) (xy 331.647438 -336.262334)
			(xy 331.647038 -336.271616) (xy 331.647038 -336.34934) (xy 331.653642 -336.366612) (xy 331.659992 -336.373724)
			(xy 331.678254 -336.394837) (xy 331.709084 -336.441371) (xy 331.732803 -336.491903) (xy 331.748903 -336.545351)
			(xy 331.757041 -336.600576) (xy 331.757528 -336.628486) (xy 331.757042 -336.655737) (xy 331.749286 -336.709685)
			(xy 331.733931 -336.76198) (xy 331.711289 -336.811557) (xy 331.681823 -336.857407) (xy 331.646132 -336.898598)
			(xy 331.604941 -336.934289) (xy 331.559091 -336.963755) (xy 331.509514 -336.986397) (xy 331.457219 -337.001752)
			(xy 331.403271 -337.009508) (xy 331.348769 -337.009508) (xy 331.294821 -337.001752) (xy 331.242526 -336.986397)
			(xy 331.192949 -336.963755) (xy 331.147099 -336.934289) (xy 331.105908 -336.898598) (xy 331.070217 -336.857407)
			(xy 331.040751 -336.811557) (xy 331.018109 -336.76198) (xy 331.002754 -336.709685) (xy 330.994998 -336.655737)
			(xy 330.994512 -336.628486) (xy 330.584302 -336.628486) (xy 330.82992 -336.874104) (xy 330.830428 -336.874612)
			(xy 330.867004 -336.909918) (xy 330.870684 -336.913671) (xy 330.876569 -336.922379) (xy 330.878688 -336.92719)
			(xy 330.91755 -337.022948) (xy 330.91929 -337.02752) (xy 330.921218 -337.037109) (xy 330.92136 -337.041998)
			(xy 330.92136 -337.860132) (xy 331.952344 -337.860132) (xy 331.956415 -337.80451) (xy 331.968541 -337.750073)
			(xy 331.988464 -337.697982) (xy 332.01576 -337.649347) (xy 332.049846 -337.605204) (xy 332.089995 -337.566495)
			(xy 332.135353 -337.534044) (xy 332.184953 -337.508543) (xy 332.237737 -337.490536) (xy 332.29258 -337.480406)
			(xy 332.348314 -337.478369) (xy 332.403751 -337.484469) (xy 332.457708 -337.498575) (xy 332.509037 -337.520387)
			(xy 332.556643 -337.549441) (xy 332.599511 -337.585116) (xy 332.636728 -337.626653) (xy 332.667501 -337.673166)
			(xy 332.691173 -337.723663) (xy 332.707241 -337.77707) (xy 332.715361 -337.832246) (xy 332.71587 -337.860132)
			(xy 332.715361 -337.888018) (xy 332.707241 -337.943194) (xy 332.691173 -337.996601) (xy 332.667501 -338.047098)
			(xy 332.636728 -338.093611) (xy 332.599511 -338.135148) (xy 332.556643 -338.170823) (xy 332.509037 -338.199877)
			(xy 332.457708 -338.221689) (xy 332.403751 -338.235795) (xy 332.348314 -338.241895) (xy 332.29258 -338.239858)
			(xy 332.237737 -338.229728) (xy 332.184953 -338.211721) (xy 332.135353 -338.18622) (xy 332.089995 -338.153769)
			(xy 332.049846 -338.11506) (xy 332.01576 -338.070917) (xy 331.988464 -338.022282) (xy 331.968541 -337.970191)
			(xy 331.956415 -337.915754) (xy 331.952344 -337.860132) (xy 330.92136 -337.860132) (xy 330.92136 -338.755482)
			(xy 331.373224 -338.755482) (xy 331.377295 -338.69986) (xy 331.389421 -338.645423) (xy 331.409344 -338.593332)
			(xy 331.43664 -338.544697) (xy 331.470726 -338.500554) (xy 331.510875 -338.461845) (xy 331.556233 -338.429394)
			(xy 331.605833 -338.403893) (xy 331.658617 -338.385886) (xy 331.71346 -338.375756) (xy 331.769194 -338.373719)
			(xy 331.824631 -338.379819) (xy 331.878588 -338.393925) (xy 331.929917 -338.415737) (xy 331.977523 -338.444791)
			(xy 332.020391 -338.480466) (xy 332.057608 -338.522003) (xy 332.088381 -338.568516) (xy 332.112053 -338.619013)
			(xy 332.128121 -338.67242) (xy 332.136241 -338.727596) (xy 332.13675 -338.755482) (xy 332.136241 -338.783368)
			(xy 332.128121 -338.838544) (xy 332.112053 -338.891951) (xy 332.088381 -338.942448) (xy 332.057608 -338.988961)
			(xy 332.020391 -339.030498) (xy 331.977523 -339.066173) (xy 331.929917 -339.095227) (xy 331.878588 -339.117039)
			(xy 331.824631 -339.131145) (xy 331.769194 -339.137245) (xy 331.71346 -339.135208) (xy 331.658617 -339.125078)
			(xy 331.605833 -339.107071) (xy 331.556233 -339.08157) (xy 331.510875 -339.049119) (xy 331.470726 -339.01041)
			(xy 331.43664 -338.966267) (xy 331.409344 -338.917632) (xy 331.389421 -338.865541) (xy 331.377295 -338.811104)
			(xy 331.373224 -338.755482) (xy 330.92136 -338.755482) (xy 330.92136 -339.431122) (xy 332.71206 -339.431122)
			(xy 332.712569 -339.403648) (xy 332.720457 -339.34927) (xy 332.736072 -339.296588) (xy 332.759092 -339.246695)
			(xy 332.789037 -339.200625) (xy 332.806802 -339.179662) (xy 332.807056 -339.179408) (xy 332.812652 -339.172328)
			(xy 332.818892 -339.155406) (xy 332.819248 -339.146388) (xy 332.819248 -339.078824) (xy 332.818891 -339.069807)
			(xy 332.812645 -339.052889) (xy 332.807056 -339.045804) (xy 332.806548 -339.045296) (xy 332.788824 -339.024342)
			(xy 332.758939 -338.978312) (xy 332.73597 -338.928469) (xy 332.720393 -338.875845) (xy 332.712531 -338.821531)
			(xy 332.71206 -338.79409) (xy 332.712546 -338.766839) (xy 332.720302 -338.712891) (xy 332.735657 -338.660596)
			(xy 332.758299 -338.611019) (xy 332.787765 -338.565169) (xy 332.823456 -338.523978) (xy 332.864647 -338.488287)
			(xy 332.910497 -338.458821) (xy 332.960074 -338.436179) (xy 333.012369 -338.420824) (xy 333.066317 -338.413068)
			(xy 333.120819 -338.413068) (xy 333.174767 -338.420824) (xy 333.227062 -338.436179) (xy 333.276639 -338.458821)
			(xy 333.322489 -338.488287) (xy 333.36368 -338.523978) (xy 333.399371 -338.565169) (xy 333.428837 -338.611019)
			(xy 333.451479 -338.660596) (xy 333.466834 -338.712891) (xy 333.47459 -338.766839) (xy 333.475076 -338.79409)
			(xy 333.47459 -338.821565) (xy 333.466699 -338.875945) (xy 333.451079 -338.928627) (xy 333.448438 -338.934349)
			(xy 333.716898 -338.934349) (xy 333.716898 -338.879851) (xy 333.724654 -338.825908) (xy 333.740007 -338.773617)
			(xy 333.762646 -338.724043) (xy 333.792109 -338.678196) (xy 333.827797 -338.637009) (xy 333.868983 -338.601319)
			(xy 333.914829 -338.571854) (xy 333.964402 -338.549213) (xy 334.016692 -338.533857) (xy 334.070635 -338.526099)
			(xy 334.097884 -338.525612) (xy 334.098138 -338.525612) (xy 334.123342 -338.525999) (xy 334.17331 -338.532643)
			(xy 334.221965 -338.545823) (xy 334.268454 -338.565309) (xy 334.290416 -338.577682) (xy 334.300322 -338.583524)
			(xy 334.322166 -338.585556) (xy 334.416908 -338.552028) (xy 334.432656 -338.536534) (xy 334.43672 -338.52612)
			(xy 334.447394 -338.499334) (xy 334.475682 -338.449089) (xy 334.511214 -338.403678) (xy 334.553179 -338.364135)
			(xy 334.60062 -338.331361) (xy 334.652455 -338.306106) (xy 334.707502 -338.288944) (xy 334.764506 -338.280266)
			(xy 334.793336 -338.27974) (xy 334.820592 -338.280122) (xy 334.874548 -338.287885) (xy 334.926851 -338.303248)
			(xy 334.976434 -338.325898) (xy 335.02229 -338.355374) (xy 335.063483 -338.391076) (xy 335.099176 -338.432278)
			(xy 335.128642 -338.47814) (xy 335.151282 -338.527728) (xy 335.166633 -338.580034) (xy 335.174384 -338.633992)
			(xy 335.174844 -338.661248) (xy 335.174195 -338.692811) (xy 335.163804 -338.755077) (xy 335.143314 -338.814786)
			(xy 335.12887 -338.842858) (xy 335.124044 -338.851748) (xy 335.122012 -338.871306) (xy 335.144872 -338.949792)
			(xy 335.148097 -338.959222) (xy 335.160523 -338.97478) (xy 335.169002 -338.980018) (xy 335.194096 -338.994578)
			(xy 335.239978 -339.03008) (xy 335.279953 -339.072122) (xy 335.313099 -339.119734) (xy 335.338651 -339.171817)
			(xy 335.356019 -339.227169) (xy 335.364803 -339.284513) (xy 335.365344 -339.31352) (xy 335.364858 -339.340771)
			(xy 335.357102 -339.394719) (xy 335.341747 -339.447014) (xy 335.319105 -339.496591) (xy 335.289639 -339.542441)
			(xy 335.253948 -339.583632) (xy 335.212757 -339.619323) (xy 335.166907 -339.648789) (xy 335.11733 -339.671431)
			(xy 335.065035 -339.686786) (xy 335.011087 -339.694542) (xy 334.956585 -339.694542) (xy 334.902637 -339.686786)
			(xy 334.850342 -339.671431) (xy 334.800765 -339.648789) (xy 334.754915 -339.619323) (xy 334.713724 -339.583632)
			(xy 334.678033 -339.542441) (xy 334.648567 -339.496591) (xy 334.625925 -339.447014) (xy 334.61057 -339.394719)
			(xy 334.602814 -339.340771) (xy 334.602328 -339.31352) (xy 334.602968 -339.281956) (xy 334.613363 -339.21969)
			(xy 334.633857 -339.159982) (xy 334.648302 -339.13191) (xy 334.653128 -339.12302) (xy 334.65516 -339.103462)
			(xy 334.6323 -339.024976) (xy 334.629061 -339.015552) (xy 334.616644 -338.999993) (xy 334.60817 -338.99475)
			(xy 334.600804 -338.990686) (xy 334.590898 -338.984844) (xy 334.569054 -338.982812) (xy 334.474312 -339.01634)
			(xy 334.458564 -339.031834) (xy 334.4545 -339.042248) (xy 334.443846 -339.069042) (xy 334.415551 -339.119284)
			(xy 334.380014 -339.164692) (xy 334.338046 -339.204233) (xy 334.290603 -339.237004) (xy 334.238767 -339.262259)
			(xy 334.183719 -339.279421) (xy 334.126715 -339.2881) (xy 334.097884 -339.288628) (xy 334.070635 -339.288101)
			(xy 334.016692 -339.280343) (xy 333.964402 -339.264987) (xy 333.914829 -339.242346) (xy 333.868983 -339.212881)
			(xy 333.827797 -339.177191) (xy 333.792109 -339.136004) (xy 333.762646 -339.090157) (xy 333.740007 -339.040583)
			(xy 333.724654 -338.988292) (xy 333.716898 -338.934349) (xy 333.448438 -338.934349) (xy 333.428054 -338.97852)
			(xy 333.398102 -339.024588) (xy 333.380334 -339.04555) (xy 333.38008 -339.045804) (xy 333.374483 -339.052884)
			(xy 333.368243 -339.069806) (xy 333.367888 -339.078824) (xy 333.367888 -339.146388) (xy 333.368253 -339.155404)
			(xy 333.374495 -339.172321) (xy 333.38008 -339.179408) (xy 333.380588 -339.179916) (xy 333.398323 -339.200861)
			(xy 333.428206 -339.246894) (xy 333.451172 -339.296739) (xy 333.466746 -339.349365) (xy 333.474606 -339.403681)
			(xy 333.475076 -339.431122) (xy 333.47459 -339.458373) (xy 333.466834 -339.512321) (xy 333.451479 -339.564616)
			(xy 333.428837 -339.614193) (xy 333.399371 -339.660043) (xy 333.36368 -339.701234) (xy 333.322489 -339.736925)
			(xy 333.276639 -339.766391) (xy 333.227062 -339.789033) (xy 333.174767 -339.804388) (xy 333.120819 -339.812144)
			(xy 333.066317 -339.812144) (xy 333.012369 -339.804388) (xy 332.960074 -339.789033) (xy 332.910497 -339.766391)
			(xy 332.864647 -339.736925) (xy 332.823456 -339.701234) (xy 332.787765 -339.660043) (xy 332.758299 -339.614193)
			(xy 332.735657 -339.564616) (xy 332.720302 -339.512321) (xy 332.712546 -339.458373) (xy 332.71206 -339.431122)
			(xy 330.92136 -339.431122) (xy 330.92136 -339.913214) (xy 330.921762 -339.923286) (xy 330.929497 -339.941885)
			(xy 330.936346 -339.949282) (xy 331.61859 -340.631526) (xy 331.625996 -340.638358) (xy 331.644591 -340.646082)
			(xy 331.654658 -340.646512) (xy 335.841594 -340.646512) (xy 335.851639 -340.646137) (xy 335.870236 -340.638554)
			(xy 335.877662 -340.63178) (xy 336.046826 -340.462616) (xy 336.053655 -340.455208) (xy 336.061381 -340.436615)
			(xy 336.061812 -340.426548) (xy 336.061812 -338.228432) (xy 336.061393 -338.218362) (xy 336.05367 -338.199763)
			(xy 336.046826 -338.192364) (xy 335.277968 -337.423506) (xy 335.27746 -337.422998) (xy 335.240884 -337.387692)
			(xy 335.237216 -337.383927) (xy 335.231323 -337.375228) (xy 335.2292 -337.37042) (xy 335.190338 -337.274662)
			(xy 335.188573 -337.270098) (xy 335.186661 -337.260503) (xy 335.186528 -337.255612) (xy 335.186528 -335.251044)
			(xy 335.186662 -335.246153) (xy 335.188582 -335.236561) (xy 335.190338 -335.231994) (xy 335.2292 -335.136236)
			(xy 335.231302 -335.131415) (xy 335.237187 -335.122704) (xy 335.240884 -335.118964) (xy 335.277206 -335.083912)
			(xy 335.278222 -335.082896) (xy 335.303876 -335.056988) (xy 335.321155 -335.040375) (xy 335.35994 -335.012213)
			(xy 335.402644 -334.990448) (xy 335.448223 -334.975615) (xy 335.495557 -334.968076) (xy 335.519522 -334.96758)
			(xy 338.444586 -334.96758) (xy 338.468558 -334.968028) (xy 338.515912 -334.975523) (xy 338.561506 -334.990345)
			(xy 338.604214 -335.01213) (xy 338.642981 -335.040337) (xy 338.660232 -335.056988) (xy 338.815934 -335.212944)
			(xy 338.816442 -335.213452) (xy 338.852764 -335.248758) (xy 338.856511 -335.252497) (xy 338.862531 -335.261202)
			(xy 338.864702 -335.26603) (xy 338.90331 -335.361788) (xy 338.905063 -335.366355) (xy 338.906982 -335.375948)
			(xy 338.90712 -335.380838) (xy 338.90712 -336.558382) (xy 338.90755 -336.568451) (xy 338.915267 -336.587049)
			(xy 338.922106 -336.59445) (xy 339.006942 -336.679286) (xy 339.325712 -336.679286) (xy 339.326216 -336.651376)
			(xy 339.334351 -336.596151) (xy 339.350445 -336.542701) (xy 339.374154 -336.492167) (xy 339.404974 -336.445625)
			(xy 339.423248 -336.424524) (xy 339.42914 -336.417344) (xy 339.435793 -336.400021) (xy 339.436202 -336.390742)
			(xy 339.436202 -336.313018) (xy 339.429598 -336.295746) (xy 339.423248 -336.288634) (xy 339.404956 -336.267546)
			(xy 339.374133 -336.221004) (xy 339.350421 -336.170466) (xy 339.334327 -336.117012) (xy 339.326196 -336.061784)
			(xy 339.325712 -336.033872) (xy 339.326198 -336.006621) (xy 339.333954 -335.952673) (xy 339.349309 -335.900378)
			(xy 339.371951 -335.850801) (xy 339.401417 -335.804951) (xy 339.437108 -335.76376) (xy 339.478299 -335.728069)
			(xy 339.524149 -335.698603) (xy 339.573726 -335.675961) (xy 339.626021 -335.660606) (xy 339.679969 -335.65285)
			(xy 339.734471 -335.65285) (xy 339.788419 -335.660606) (xy 339.840714 -335.675961) (xy 339.890291 -335.698603)
			(xy 339.936141 -335.728069) (xy 339.977332 -335.76376) (xy 340.013023 -335.804951) (xy 340.042489 -335.850801)
			(xy 340.065131 -335.900378) (xy 340.080486 -335.952673) (xy 340.088242 -336.006621) (xy 340.088728 -336.033872)
			(xy 340.088274 -336.061784) (xy 340.080129 -336.117011) (xy 340.064025 -336.170463) (xy 340.040303 -336.220997)
			(xy 340.009472 -336.267535) (xy 339.991192 -336.288634) (xy 339.98528 -336.2958) (xy 339.978638 -336.313134)
			(xy 339.978238 -336.322416) (xy 339.978238 -336.40014) (xy 339.984842 -336.417412) (xy 339.991192 -336.424524)
			(xy 340.009454 -336.445637) (xy 340.040284 -336.492171) (xy 340.064003 -336.542703) (xy 340.080103 -336.596151)
			(xy 340.088241 -336.651376) (xy 340.088728 -336.679286) (xy 340.088242 -336.706537) (xy 340.080486 -336.760485)
			(xy 340.065131 -336.81278) (xy 340.042489 -336.862357) (xy 340.013023 -336.908207) (xy 339.977332 -336.949398)
			(xy 339.936141 -336.985089) (xy 339.890291 -337.014555) (xy 339.840714 -337.037197) (xy 339.788419 -337.052552)
			(xy 339.734471 -337.060308) (xy 339.679969 -337.060308) (xy 339.626021 -337.052552) (xy 339.573726 -337.037197)
			(xy 339.524149 -337.014555) (xy 339.478299 -336.985089) (xy 339.437108 -336.949398) (xy 339.401417 -336.908207)
			(xy 339.371951 -336.862357) (xy 339.349309 -336.81278) (xy 339.333954 -336.760485) (xy 339.326198 -336.706537)
			(xy 339.325712 -336.679286) (xy 339.006942 -336.679286) (xy 339.18652 -336.858864) (xy 339.187028 -336.859372)
			(xy 339.223604 -336.894678) (xy 339.227276 -336.898438) (xy 339.233166 -336.907141) (xy 339.235288 -336.91195)
			(xy 339.27415 -337.007708) (xy 339.275906 -337.012274) (xy 339.277824 -337.021867) (xy 339.27796 -337.026758)
			(xy 339.27796 -337.910932) (xy 340.283544 -337.910932) (xy 340.287615 -337.85531) (xy 340.299741 -337.800873)
			(xy 340.319664 -337.748782) (xy 340.34696 -337.700147) (xy 340.381046 -337.656004) (xy 340.421195 -337.617295)
			(xy 340.466553 -337.584844) (xy 340.516153 -337.559343) (xy 340.568937 -337.541336) (xy 340.62378 -337.531206)
			(xy 340.679514 -337.529169) (xy 340.734951 -337.535269) (xy 340.788908 -337.549375) (xy 340.840237 -337.571187)
			(xy 340.887843 -337.600241) (xy 340.930711 -337.635916) (xy 340.967928 -337.677453) (xy 340.998701 -337.723966)
			(xy 341.022373 -337.774463) (xy 341.038441 -337.82787) (xy 341.046561 -337.883046) (xy 341.04707 -337.910932)
			(xy 341.046561 -337.938818) (xy 341.038441 -337.993994) (xy 341.022373 -338.047401) (xy 340.998701 -338.097898)
			(xy 340.967928 -338.144411) (xy 340.930711 -338.185948) (xy 340.887843 -338.221623) (xy 340.840237 -338.250677)
			(xy 340.788908 -338.272489) (xy 340.734951 -338.286595) (xy 340.679514 -338.292695) (xy 340.62378 -338.290658)
			(xy 340.568937 -338.280528) (xy 340.516153 -338.262521) (xy 340.466553 -338.23702) (xy 340.421195 -338.204569)
			(xy 340.381046 -338.16586) (xy 340.34696 -338.121717) (xy 340.319664 -338.073082) (xy 340.299741 -338.020991)
			(xy 340.287615 -337.966554) (xy 340.283544 -337.910932) (xy 339.27796 -337.910932) (xy 339.27796 -338.806282)
			(xy 339.704424 -338.806282) (xy 339.708495 -338.75066) (xy 339.720621 -338.696223) (xy 339.740544 -338.644132)
			(xy 339.76784 -338.595497) (xy 339.801926 -338.551354) (xy 339.842075 -338.512645) (xy 339.887433 -338.480194)
			(xy 339.937033 -338.454693) (xy 339.989817 -338.436686) (xy 340.04466 -338.426556) (xy 340.100394 -338.424519)
			(xy 340.155831 -338.430619) (xy 340.209788 -338.444725) (xy 340.261117 -338.466537) (xy 340.308723 -338.495591)
			(xy 340.351591 -338.531266) (xy 340.388808 -338.572803) (xy 340.419581 -338.619316) (xy 340.443253 -338.669813)
			(xy 340.459321 -338.72322) (xy 340.467441 -338.778396) (xy 340.46795 -338.806282) (xy 340.467441 -338.834168)
			(xy 340.459321 -338.889344) (xy 340.443253 -338.942751) (xy 340.419581 -338.993248) (xy 340.388808 -339.039761)
			(xy 340.351591 -339.081298) (xy 340.308723 -339.116973) (xy 340.261117 -339.146027) (xy 340.209788 -339.167839)
			(xy 340.155831 -339.181945) (xy 340.100394 -339.188045) (xy 340.04466 -339.186008) (xy 339.989817 -339.175878)
			(xy 339.937033 -339.157871) (xy 339.887433 -339.13237) (xy 339.842075 -339.099919) (xy 339.801926 -339.06121)
			(xy 339.76784 -339.017067) (xy 339.740544 -338.968432) (xy 339.720621 -338.916341) (xy 339.708495 -338.861904)
			(xy 339.704424 -338.806282) (xy 339.27796 -338.806282) (xy 339.27796 -339.481922) (xy 341.04326 -339.481922)
			(xy 341.043769 -339.454448) (xy 341.051657 -339.40007) (xy 341.067272 -339.347388) (xy 341.090292 -339.297495)
			(xy 341.120237 -339.251425) (xy 341.138002 -339.230462) (xy 341.138256 -339.230208) (xy 341.143852 -339.223128)
			(xy 341.150092 -339.206206) (xy 341.150448 -339.197188) (xy 341.150448 -339.129624) (xy 341.150091 -339.120607)
			(xy 341.143845 -339.103689) (xy 341.138256 -339.096604) (xy 341.137748 -339.096096) (xy 341.120024 -339.075142)
			(xy 341.090139 -339.029112) (xy 341.06717 -338.979269) (xy 341.051593 -338.926645) (xy 341.043731 -338.872331)
			(xy 341.04326 -338.84489) (xy 341.043746 -338.817639) (xy 341.051502 -338.763691) (xy 341.066857 -338.711396)
			(xy 341.089499 -338.661819) (xy 341.118965 -338.615969) (xy 341.154656 -338.574778) (xy 341.195847 -338.539087)
			(xy 341.241697 -338.509621) (xy 341.291274 -338.486979) (xy 341.343569 -338.471624) (xy 341.397517 -338.463868)
			(xy 341.452019 -338.463868) (xy 341.505967 -338.471624) (xy 341.558262 -338.486979) (xy 341.607839 -338.509621)
			(xy 341.653689 -338.539087) (xy 341.69488 -338.574778) (xy 341.730571 -338.615969) (xy 341.760037 -338.661819)
			(xy 341.782679 -338.711396) (xy 341.798034 -338.763691) (xy 341.80579 -338.817639) (xy 341.806276 -338.84489)
			(xy 341.80579 -338.872365) (xy 341.797899 -338.926745) (xy 341.782279 -338.979427) (xy 341.779638 -338.985149)
			(xy 342.048098 -338.985149) (xy 342.048098 -338.930651) (xy 342.055854 -338.876708) (xy 342.071207 -338.824417)
			(xy 342.093846 -338.774843) (xy 342.123309 -338.728996) (xy 342.158997 -338.687809) (xy 342.200183 -338.652119)
			(xy 342.246029 -338.622654) (xy 342.295602 -338.600013) (xy 342.347892 -338.584657) (xy 342.401835 -338.576899)
			(xy 342.429084 -338.576412) (xy 342.429338 -338.576412) (xy 342.454542 -338.576799) (xy 342.50451 -338.583443)
			(xy 342.553165 -338.596623) (xy 342.599654 -338.616109) (xy 342.621616 -338.628482) (xy 342.631522 -338.634324)
			(xy 342.653366 -338.636356) (xy 342.748108 -338.602828) (xy 342.763856 -338.587334) (xy 342.76792 -338.57692)
			(xy 342.778594 -338.550134) (xy 342.806882 -338.499889) (xy 342.842414 -338.454478) (xy 342.884379 -338.414935)
			(xy 342.93182 -338.382161) (xy 342.983655 -338.356906) (xy 343.038702 -338.339744) (xy 343.095706 -338.331066)
			(xy 343.124536 -338.33054) (xy 343.151792 -338.330922) (xy 343.205748 -338.338685) (xy 343.258051 -338.354048)
			(xy 343.307634 -338.376698) (xy 343.35349 -338.406174) (xy 343.394683 -338.441876) (xy 343.430376 -338.483078)
			(xy 343.459842 -338.52894) (xy 343.482482 -338.578528) (xy 343.497833 -338.630834) (xy 343.505584 -338.684792)
			(xy 343.506044 -338.712048) (xy 343.505395 -338.743611) (xy 343.495004 -338.805877) (xy 343.474514 -338.865586)
			(xy 343.46007 -338.893658) (xy 343.455244 -338.902548) (xy 343.453212 -338.922106) (xy 343.476072 -339.000592)
			(xy 343.479297 -339.010022) (xy 343.491723 -339.02558) (xy 343.500202 -339.030818) (xy 343.525296 -339.045378)
			(xy 343.571178 -339.08088) (xy 343.611153 -339.122922) (xy 343.644299 -339.170534) (xy 343.669851 -339.222617)
			(xy 343.687219 -339.277969) (xy 343.696003 -339.335313) (xy 343.696544 -339.36432) (xy 343.696058 -339.391571)
			(xy 343.688302 -339.445519) (xy 343.672947 -339.497814) (xy 343.650305 -339.547391) (xy 343.620839 -339.593241)
			(xy 343.585148 -339.634432) (xy 343.543957 -339.670123) (xy 343.498107 -339.699589) (xy 343.44853 -339.722231)
			(xy 343.396235 -339.737586) (xy 343.342287 -339.745342) (xy 343.287785 -339.745342) (xy 343.233837 -339.737586)
			(xy 343.181542 -339.722231) (xy 343.131965 -339.699589) (xy 343.086115 -339.670123) (xy 343.044924 -339.634432)
			(xy 343.009233 -339.593241) (xy 342.979767 -339.547391) (xy 342.957125 -339.497814) (xy 342.94177 -339.445519)
			(xy 342.934014 -339.391571) (xy 342.933528 -339.36432) (xy 342.934168 -339.332756) (xy 342.944563 -339.27049)
			(xy 342.965057 -339.210782) (xy 342.979502 -339.18271) (xy 342.984328 -339.17382) (xy 342.98636 -339.154262)
			(xy 342.9635 -339.075776) (xy 342.960261 -339.066352) (xy 342.947844 -339.050793) (xy 342.93937 -339.04555)
			(xy 342.932004 -339.041486) (xy 342.922098 -339.035644) (xy 342.900254 -339.033612) (xy 342.805512 -339.06714)
			(xy 342.789764 -339.082634) (xy 342.7857 -339.093048) (xy 342.775046 -339.119842) (xy 342.746751 -339.170084)
			(xy 342.711214 -339.215492) (xy 342.669246 -339.255033) (xy 342.621803 -339.287804) (xy 342.569967 -339.313059)
			(xy 342.514919 -339.330221) (xy 342.457915 -339.3389) (xy 342.429084 -339.339428) (xy 342.401835 -339.338901)
			(xy 342.347892 -339.331143) (xy 342.295602 -339.315787) (xy 342.246029 -339.293146) (xy 342.200183 -339.263681)
			(xy 342.158997 -339.227991) (xy 342.123309 -339.186804) (xy 342.093846 -339.140957) (xy 342.071207 -339.091383)
			(xy 342.055854 -339.039092) (xy 342.048098 -338.985149) (xy 341.779638 -338.985149) (xy 341.759254 -339.02932)
			(xy 341.729302 -339.075388) (xy 341.711534 -339.09635) (xy 341.71128 -339.096604) (xy 341.705683 -339.103684)
			(xy 341.699443 -339.120606) (xy 341.699088 -339.129624) (xy 341.699088 -339.197188) (xy 341.699453 -339.206204)
			(xy 341.705695 -339.223121) (xy 341.71128 -339.230208) (xy 341.711788 -339.230716) (xy 341.729523 -339.251661)
			(xy 341.759406 -339.297694) (xy 341.782372 -339.347539) (xy 341.797946 -339.400165) (xy 341.805806 -339.454481)
			(xy 341.806276 -339.481922) (xy 341.80579 -339.509173) (xy 341.798034 -339.563121) (xy 341.782679 -339.615416)
			(xy 341.760037 -339.664993) (xy 341.730571 -339.710843) (xy 341.69488 -339.752034) (xy 341.653689 -339.787725)
			(xy 341.607839 -339.817191) (xy 341.558262 -339.839833) (xy 341.505967 -339.855188) (xy 341.452019 -339.862944)
			(xy 341.397517 -339.862944) (xy 341.343569 -339.855188) (xy 341.291274 -339.839833) (xy 341.241697 -339.817191)
			(xy 341.195847 -339.787725) (xy 341.154656 -339.752034) (xy 341.118965 -339.710843) (xy 341.089499 -339.664993)
			(xy 341.066857 -339.615416) (xy 341.051502 -339.563121) (xy 341.043746 -339.509173) (xy 341.04326 -339.481922)
			(xy 339.27796 -339.481922) (xy 339.27796 -339.908134) (xy 339.278352 -339.918207) (xy 339.286094 -339.936806)
			(xy 339.292946 -339.944202) (xy 340.01837 -340.669626) (xy 340.025783 -340.676449) (xy 340.044373 -340.684178)
			(xy 340.054438 -340.684612) (xy 344.315034 -340.684612) (xy 344.325081 -340.684258) (xy 344.343679 -340.67666)
			(xy 344.351102 -340.66988) (xy 344.405966 -340.615016) (xy 344.412787 -340.6076) (xy 344.420519 -340.589013)
			(xy 344.420952 -340.578948) (xy 344.420952 -338.398612) (xy 344.420533 -338.388542) (xy 344.412809 -338.369943)
			(xy 344.405966 -338.362544) (xy 343.609168 -337.565746) (xy 343.60866 -337.565238) (xy 343.572084 -337.529932)
			(xy 343.568405 -337.526178) (xy 343.562519 -337.517471) (xy 343.5604 -337.51266) (xy 343.521538 -337.416902)
			(xy 343.519784 -337.412335) (xy 343.517865 -337.402743) (xy 343.517728 -337.397852) (xy 343.517728 -335.335118)
			(xy 343.517855 -335.330227) (xy 343.51978 -335.320634) (xy 343.521538 -335.316068) (xy 343.5604 -335.22031)
			(xy 343.562496 -335.215487) (xy 343.568386 -335.206777) (xy 343.572084 -335.203038) (xy 343.608406 -335.167986)
			(xy 343.609422 -335.16697) (xy 343.631012 -335.145126) (xy 343.64829 -335.128457) (xy 343.687102 -335.100202)
			(xy 343.729856 -335.078366) (xy 343.775499 -335.063488) (xy 343.822909 -335.055933) (xy 343.846912 -335.055464)
			(xy 347.27769 -335.055464) (xy 347.282719 -335.055625) (xy 347.292568 -335.05768) (xy 347.297248 -335.059528)
			(xy 347.390974 -335.098644) (xy 347.395469 -335.100673) (xy 347.403658 -335.106166) (xy 347.40723 -335.109566)
			(xy 347.58122 -335.28381) (xy 347.581728 -335.284318) (xy 347.618304 -335.319624) (xy 347.621985 -335.323376)
			(xy 347.62787 -335.332085) (xy 347.629988 -335.336896) (xy 347.66885 -335.432654) (xy 347.670592 -335.437226)
			(xy 347.672519 -335.446814) (xy 347.67266 -335.451704) (xy 347.67266 -339.983572) (xy 347.672205 -340.007577)
			(xy 347.664661 -340.054991) (xy 347.649785 -340.100639) (xy 347.627945 -340.143395) (xy 347.599679 -340.182203)
			(xy 347.582998 -340.199472) (xy 347.235526 -340.54669) (xy 347.228702 -340.554103) (xy 347.220972 -340.572692)
			(xy 347.22054 -340.582758) (xy 347.22054 -341.58936) (xy 347.60154 -341.58936) (xy 347.602021 -341.561449)
			(xy 347.610161 -341.506223) (xy 347.626259 -341.452773) (xy 347.649974 -341.402238) (xy 347.680799 -341.355698)
			(xy 347.699076 -341.334598) (xy 347.704971 -341.327419) (xy 347.711624 -341.310095) (xy 347.71203 -341.300816)
			(xy 347.71203 -341.223092) (xy 347.705426 -341.20582) (xy 347.699076 -341.198708) (xy 347.680777 -341.177626)
			(xy 347.649953 -341.131083) (xy 347.626242 -341.080543) (xy 347.610151 -341.027088) (xy 347.602022 -340.971858)
			(xy 347.60154 -340.943946) (xy 347.602026 -340.916695) (xy 347.609782 -340.862747) (xy 347.625137 -340.810452)
			(xy 347.647779 -340.760875) (xy 347.677245 -340.715025) (xy 347.712936 -340.673834) (xy 347.754127 -340.638143)
			(xy 347.799977 -340.608677) (xy 347.849554 -340.586035) (xy 347.901849 -340.57068) (xy 347.955797 -340.562924)
			(xy 348.010299 -340.562924) (xy 348.064247 -340.57068) (xy 348.116542 -340.586035) (xy 348.166119 -340.608677)
			(xy 348.211969 -340.638143) (xy 348.25316 -340.673834) (xy 348.288851 -340.715025) (xy 348.318317 -340.760875)
			(xy 348.340959 -340.810452) (xy 348.356314 -340.862747) (xy 348.36407 -340.916695) (xy 348.364556 -340.943946)
			(xy 348.364079 -340.971857) (xy 348.355939 -341.027083) (xy 348.339839 -341.080534) (xy 348.316123 -341.131068)
			(xy 348.285297 -341.177608) (xy 348.26702 -341.198708) (xy 348.261122 -341.205885) (xy 348.254471 -341.22321)
			(xy 348.254066 -341.23249) (xy 348.254066 -341.310214) (xy 348.26067 -341.327486) (xy 348.26702 -341.334598)
			(xy 348.285274 -341.355717) (xy 348.316105 -341.40225) (xy 348.339824 -341.45278) (xy 348.355926 -341.506227)
			(xy 348.364067 -341.56145) (xy 348.364556 -341.58936) (xy 348.36407 -341.616611) (xy 348.356314 -341.670559)
			(xy 348.340959 -341.722854) (xy 348.318317 -341.772431) (xy 348.288851 -341.818281) (xy 348.25316 -341.859472)
			(xy 348.211969 -341.895163) (xy 348.166119 -341.924629) (xy 348.116542 -341.947271) (xy 348.064247 -341.962626)
			(xy 348.010299 -341.970382) (xy 347.955797 -341.970382) (xy 347.901849 -341.962626) (xy 347.849554 -341.947271)
			(xy 347.799977 -341.924629) (xy 347.754127 -341.895163) (xy 347.712936 -341.859472) (xy 347.677245 -341.818281)
			(xy 347.647779 -341.772431) (xy 347.625137 -341.722854) (xy 347.609782 -341.670559) (xy 347.602026 -341.616611)
			(xy 347.60154 -341.58936) (xy 347.22054 -341.58936) (xy 347.22054 -342.161368) (xy 347.220972 -342.171437)
			(xy 347.228687 -342.190035) (xy 347.235526 -342.197436) (xy 347.377766 -342.339676) (xy 347.378274 -342.340184)
			(xy 347.414596 -342.37549) (xy 347.418341 -342.379231) (xy 347.424363 -342.387934) (xy 347.426534 -342.392762)
			(xy 347.465142 -342.48852) (xy 347.466905 -342.493084) (xy 347.468818 -342.502679) (xy 347.468952 -342.50757)
			(xy 347.468952 -342.821006) (xy 348.559372 -342.821006) (xy 348.563443 -342.765384) (xy 348.575569 -342.710947)
			(xy 348.595492 -342.658856) (xy 348.622788 -342.610221) (xy 348.656874 -342.566078) (xy 348.697023 -342.527369)
			(xy 348.742381 -342.494918) (xy 348.791981 -342.469417) (xy 348.844765 -342.45141) (xy 348.899608 -342.44128)
			(xy 348.955342 -342.439243) (xy 349.010779 -342.445343) (xy 349.064736 -342.459449) (xy 349.116065 -342.481261)
			(xy 349.163671 -342.510315) (xy 349.206539 -342.54599) (xy 349.243756 -342.587527) (xy 349.274529 -342.63404)
			(xy 349.298201 -342.684537) (xy 349.314269 -342.737944) (xy 349.322389 -342.79312) (xy 349.322898 -342.821006)
			(xy 349.322389 -342.848892) (xy 349.314269 -342.904068) (xy 349.298201 -342.957475) (xy 349.274529 -343.007972)
			(xy 349.243756 -343.054485) (xy 349.206539 -343.096022) (xy 349.163671 -343.131697) (xy 349.116065 -343.160751)
			(xy 349.064736 -343.182563) (xy 349.010779 -343.196669) (xy 348.955342 -343.202769) (xy 348.899608 -343.200732)
			(xy 348.844765 -343.190602) (xy 348.791981 -343.172595) (xy 348.742381 -343.147094) (xy 348.697023 -343.114643)
			(xy 348.656874 -343.075934) (xy 348.622788 -343.031791) (xy 348.595492 -342.983156) (xy 348.575569 -342.931065)
			(xy 348.563443 -342.876628) (xy 348.559372 -342.821006) (xy 347.468952 -342.821006) (xy 347.468952 -343.716356)
			(xy 347.980252 -343.716356) (xy 347.984323 -343.660734) (xy 347.996449 -343.606297) (xy 348.016372 -343.554206)
			(xy 348.043668 -343.505571) (xy 348.077754 -343.461428) (xy 348.117903 -343.422719) (xy 348.163261 -343.390268)
			(xy 348.212861 -343.364767) (xy 348.265645 -343.34676) (xy 348.320488 -343.33663) (xy 348.376222 -343.334593)
			(xy 348.431659 -343.340693) (xy 348.485616 -343.354799) (xy 348.536945 -343.376611) (xy 348.584551 -343.405665)
			(xy 348.627419 -343.44134) (xy 348.664636 -343.482877) (xy 348.695409 -343.52939) (xy 348.719081 -343.579887)
			(xy 348.735149 -343.633294) (xy 348.743269 -343.68847) (xy 348.743778 -343.716356) (xy 348.743269 -343.744242)
			(xy 348.735149 -343.799418) (xy 348.719081 -343.852825) (xy 348.695409 -343.903322) (xy 348.664636 -343.949835)
			(xy 348.627419 -343.991372) (xy 348.584551 -344.027047) (xy 348.536945 -344.056101) (xy 348.485616 -344.077913)
			(xy 348.431659 -344.092019) (xy 348.376222 -344.098119) (xy 348.320488 -344.096082) (xy 348.265645 -344.085952)
			(xy 348.212861 -344.067945) (xy 348.163261 -344.042444) (xy 348.117903 -344.009993) (xy 348.077754 -343.971284)
			(xy 348.043668 -343.927141) (xy 348.016372 -343.878506) (xy 347.996449 -343.826415) (xy 347.984323 -343.771978)
			(xy 347.980252 -343.716356) (xy 347.468952 -343.716356) (xy 347.468952 -344.391996) (xy 349.319088 -344.391996)
			(xy 349.319575 -344.364521) (xy 349.327467 -344.310142) (xy 349.343087 -344.25746) (xy 349.366112 -344.207567)
			(xy 349.396063 -344.161498) (xy 349.41383 -344.140536) (xy 349.414084 -344.140282) (xy 349.419682 -344.133203)
			(xy 349.425923 -344.116281) (xy 349.426276 -344.107262) (xy 349.426276 -344.039698) (xy 349.425925 -344.03068)
			(xy 349.419674 -344.013763) (xy 349.414084 -344.006678) (xy 349.413576 -344.00617) (xy 349.395829 -343.985235)
			(xy 349.365949 -343.939199) (xy 349.342986 -343.889351) (xy 349.327414 -343.836723) (xy 349.319557 -343.782406)
			(xy 349.319088 -343.754964) (xy 349.319574 -343.727713) (xy 349.32733 -343.673765) (xy 349.342685 -343.62147)
			(xy 349.365327 -343.571893) (xy 349.394793 -343.526043) (xy 349.430484 -343.484852) (xy 349.471675 -343.449161)
			(xy 349.517525 -343.419695) (xy 349.567102 -343.397053) (xy 349.619397 -343.381698) (xy 349.673345 -343.373942)
			(xy 349.727847 -343.373942) (xy 349.781795 -343.381698) (xy 349.83409 -343.397053) (xy 349.883667 -343.419695)
			(xy 349.929517 -343.449161) (xy 349.970708 -343.484852) (xy 350.006399 -343.526043) (xy 350.035865 -343.571893)
			(xy 350.058507 -343.62147) (xy 350.073862 -343.673765) (xy 350.081618 -343.727713) (xy 350.082104 -343.754964)
			(xy 350.081596 -343.782438) (xy 350.073709 -343.836816) (xy 350.058094 -343.889498) (xy 350.055438 -343.895254)
			(xy 350.323849 -343.895254) (xy 350.323849 -343.840746) (xy 350.331607 -343.786793) (xy 350.346964 -343.734494)
			(xy 350.369607 -343.684912) (xy 350.399077 -343.639058) (xy 350.434772 -343.597864) (xy 350.475967 -343.56217)
			(xy 350.521823 -343.532702) (xy 350.571405 -343.510059) (xy 350.623705 -343.494704) (xy 350.677658 -343.486949)
			(xy 350.704912 -343.486486) (xy 350.705166 -343.486486) (xy 350.730369 -343.486894) (xy 350.780337 -343.49353)
			(xy 350.828992 -343.506704) (xy 350.875482 -343.526185) (xy 350.897444 -343.538556) (xy 350.90735 -343.544398)
			(xy 350.929194 -343.54643) (xy 351.023936 -343.512902) (xy 351.039684 -343.497408) (xy 351.043748 -343.486994)
			(xy 351.054468 -343.460228) (xy 351.082752 -343.409987) (xy 351.118279 -343.364577) (xy 351.160237 -343.325035)
			(xy 351.207671 -343.29226) (xy 351.259499 -343.267) (xy 351.314539 -343.249831) (xy 351.371536 -343.241145)
			(xy 351.400364 -343.240614) (xy 351.427617 -343.241089) (xy 351.481569 -343.248842) (xy 351.533868 -343.264194)
			(xy 351.583449 -343.286834) (xy 351.629303 -343.3163) (xy 351.670497 -343.351993) (xy 351.706191 -343.393185)
			(xy 351.735659 -343.439039) (xy 351.758301 -343.488619) (xy 351.773656 -343.540918) (xy 351.78141 -343.594869)
			(xy 351.781872 -343.622122) (xy 351.781209 -343.653685) (xy 351.770824 -343.71595) (xy 351.750339 -343.775659)
			(xy 351.735898 -343.803732) (xy 351.731072 -343.812622) (xy 351.72904 -343.83218) (xy 351.7519 -343.910666)
			(xy 351.755162 -343.920081) (xy 351.767562 -343.935645) (xy 351.77603 -343.940892) (xy 351.801163 -343.955389)
			(xy 351.847044 -343.990902) (xy 351.887016 -344.032955) (xy 351.920157 -344.080578) (xy 351.945703 -344.132671)
			(xy 351.963063 -344.188032) (xy 351.971837 -344.245384) (xy 351.972372 -344.274394) (xy 351.971886 -344.301645)
			(xy 351.96413 -344.355593) (xy 351.948775 -344.407888) (xy 351.926133 -344.457465) (xy 351.896667 -344.503315)
			(xy 351.860976 -344.544506) (xy 351.819785 -344.580197) (xy 351.773935 -344.609663) (xy 351.724358 -344.632305)
			(xy 351.672063 -344.64766) (xy 351.618115 -344.655416) (xy 351.563613 -344.655416) (xy 351.509665 -344.64766)
			(xy 351.45737 -344.632305) (xy 351.407793 -344.609663) (xy 351.361943 -344.580197) (xy 351.320752 -344.544506)
			(xy 351.285061 -344.503315) (xy 351.255595 -344.457465) (xy 351.232953 -344.407888) (xy 351.217598 -344.355593)
			(xy 351.209842 -344.301645) (xy 351.209356 -344.274394) (xy 351.210022 -344.242831) (xy 351.220406 -344.180566)
			(xy 351.240889 -344.120857) (xy 351.25533 -344.092784) (xy 351.260156 -344.083894) (xy 351.262188 -344.064336)
			(xy 351.239328 -343.98585) (xy 351.236126 -343.97641) (xy 351.223683 -343.960858) (xy 351.215198 -343.955624)
			(xy 351.207832 -343.95156) (xy 351.197926 -343.945718) (xy 351.176082 -343.943686) (xy 351.08134 -343.977214)
			(xy 351.065592 -343.992708) (xy 351.061528 -344.003122) (xy 351.050837 -344.0299) (xy 351.022548 -344.080142)
			(xy 350.987017 -344.125551) (xy 350.945054 -344.165093) (xy 350.897616 -344.197866) (xy 350.845785 -344.223124)
			(xy 350.790741 -344.24029) (xy 350.733741 -344.248972) (xy 350.704912 -344.249502) (xy 350.677658 -344.249051)
			(xy 350.623705 -344.241296) (xy 350.571405 -344.225941) (xy 350.521823 -344.203298) (xy 350.475967 -344.17383)
			(xy 350.434772 -344.138136) (xy 350.399077 -344.096942) (xy 350.369607 -344.051088) (xy 350.346964 -344.001506)
			(xy 350.331607 -343.949207) (xy 350.323849 -343.895254) (xy 350.055438 -343.895254) (xy 350.035074 -343.939392)
			(xy 350.005127 -343.985461) (xy 349.987362 -344.006424) (xy 349.987108 -344.006678) (xy 349.981525 -344.013767)
			(xy 349.975276 -344.030682) (xy 349.974916 -344.039698) (xy 349.974916 -344.107262) (xy 349.975288 -344.116277)
			(xy 349.981525 -344.133195) (xy 349.987108 -344.140282) (xy 349.987616 -344.14079) (xy 350.005343 -344.161741)
			(xy 350.035226 -344.207773) (xy 350.058193 -344.257617) (xy 350.07377 -344.310241) (xy 350.081632 -344.364555)
			(xy 350.082104 -344.391996) (xy 350.081618 -344.419247) (xy 350.073862 -344.473195) (xy 350.058507 -344.52549)
			(xy 350.035865 -344.575067) (xy 350.006399 -344.620917) (xy 349.970708 -344.662108) (xy 349.929517 -344.697799)
			(xy 349.883667 -344.727265) (xy 349.83409 -344.749907) (xy 349.781795 -344.765262) (xy 349.727847 -344.773018)
			(xy 349.673345 -344.773018) (xy 349.619397 -344.765262) (xy 349.567102 -344.749907) (xy 349.517525 -344.727265)
			(xy 349.471675 -344.697799) (xy 349.430484 -344.662108) (xy 349.394793 -344.620917) (xy 349.365327 -344.575067)
			(xy 349.342685 -344.52549) (xy 349.32733 -344.473195) (xy 349.319574 -344.419247) (xy 349.319088 -344.391996)
			(xy 347.468952 -344.391996) (xy 347.468952 -345.264994) (xy 347.469367 -345.275065) (xy 347.477094 -345.293663)
			(xy 347.483938 -345.301062) (xy 347.856048 -345.672918) (xy 347.86347 -345.67973) (xy 347.882053 -345.687465)
			(xy 347.892116 -345.687904) (xy 352.371914 -345.687904) (xy 352.381987 -345.687511) (xy 352.400586 -345.67977)
			(xy 352.407982 -345.672918) (xy 352.676206 -345.404948) (xy 352.683018 -345.397526) (xy 352.690754 -345.378944)
			(xy 352.691192 -345.36888) (xy 352.691192 -343.290652) (xy 352.690741 -343.280586) (xy 352.683038 -343.261987)
			(xy 352.676206 -343.254584) (xy 351.884996 -342.463374) (xy 351.884488 -342.462866) (xy 351.847912 -342.42756)
			(xy 351.844229 -342.423809) (xy 351.838346 -342.415099) (xy 351.836228 -342.410288) (xy 351.797366 -342.31453)
			(xy 351.795617 -342.309961) (xy 351.793695 -342.30037) (xy 351.793556 -342.29548) (xy 351.793556 -340.357968)
			(xy 351.794031 -340.333964) (xy 351.80157 -340.28655) (xy 351.816441 -340.240902) (xy 351.838277 -340.198146)
			(xy 351.866539 -340.159337) (xy 351.883218 -340.142068) (xy 351.940876 -340.084664) (xy 351.941384 -340.084156)
			(xy 351.97669 -340.04758) (xy 351.980457 -340.043915) (xy 351.989155 -340.03802) (xy 351.993962 -340.035896)
			(xy 352.08972 -339.997034) (xy 352.094285 -339.995274) (xy 352.103879 -339.993359) (xy 352.10877 -339.993224)
			(xy 356.604824 -339.993224) (xy 356.62883 -339.993651) (xy 356.676246 -340.001203) (xy 356.721894 -340.016086)
			(xy 356.764649 -340.037932) (xy 356.803456 -340.066203) (xy 356.820724 -340.082886) (xy 357.208328 -340.470744)
			(xy 357.208836 -340.471252) (xy 357.245412 -340.506558) (xy 357.249089 -340.510314) (xy 357.254976 -340.51902)
			(xy 357.257096 -340.52383) (xy 357.295958 -340.619588) (xy 357.297709 -340.624156) (xy 357.29963 -340.633748)
			(xy 357.299768 -340.638638) (xy 357.299768 -351.938336) (xy 357.299288 -351.96234) (xy 357.291749 -352.009753)
			(xy 357.276879 -352.055401) (xy 357.255045 -352.098157) (xy 357.226784 -352.136966) (xy 357.210106 -352.154236)
			(xy 353.125278 -356.23881) (xy 353.12477 -356.239318) (xy 353.089464 -356.27564) (xy 353.085736 -356.279399)
			(xy 353.077023 -356.285412) (xy 353.072192 -356.287578) (xy 352.976434 -356.326186) (xy 352.971864 -356.327932)
			(xy 352.962274 -356.329856) (xy 352.957384 -356.329996) (xy 350.825308 -356.329996) (xy 350.820417 -356.330123)
			(xy 350.810824 -356.332048) (xy 350.806258 -356.333806) (xy 350.70796 -356.37343) (xy 350.703398 -356.375198)
			(xy 350.693802 -356.377107) (xy 350.68891 -356.37724) (xy 319.398904 -356.37724) (xy 319.374932 -356.376793)
			(xy 319.327579 -356.369297) (xy 319.281985 -356.354474) (xy 319.239277 -356.332689) (xy 319.200509 -356.304482)
			(xy 319.183258 -356.287832) (xy 314.16625 -351.27057) (xy 314.15883 -351.263755) (xy 314.140246 -351.256022)
			(xy 314.130182 -351.255584) (xy 310.647588 -351.255584) (xy 310.623582 -351.255147) (xy 310.576167 -351.247597)
			(xy 310.53052 -351.232717) (xy 310.487764 -351.210873) (xy 310.448957 -351.182604) (xy 310.431688 -351.165922)
			(xy 308.951122 -349.685102) (xy 308.950614 -349.684594) (xy 308.914292 -349.649288) (xy 308.910541 -349.645552)
			(xy 308.904523 -349.636845) (xy 308.902354 -349.632016) (xy 308.863746 -349.536258) (xy 308.86198 -349.531695)
			(xy 308.860069 -349.522099) (xy 308.859936 -349.517208) (xy 306.343564 -349.517208) (xy 306.344327 -349.519744)
			(xy 306.352447 -349.57492) (xy 306.352956 -349.602806) (xy 306.352447 -349.630692) (xy 306.344327 -349.685868)
			(xy 306.328259 -349.739275) (xy 306.304587 -349.789772) (xy 306.273814 -349.836285) (xy 306.236597 -349.877822)
			(xy 306.193729 -349.913497) (xy 306.146123 -349.942551) (xy 306.094794 -349.964363) (xy 306.040837 -349.978469)
			(xy 305.9854 -349.984569) (xy 305.929666 -349.982532) (xy 305.874823 -349.972402) (xy 305.822039 -349.954395)
			(xy 305.772439 -349.928894) (xy 305.727081 -349.896443) (xy 305.686932 -349.857734) (xy 305.652846 -349.813591)
			(xy 305.62555 -349.764956) (xy 305.605627 -349.712865) (xy 305.593501 -349.658428) (xy 305.58943 -349.602806)
			(xy 304.6476 -349.602806) (xy 304.6476 -350.498156) (xy 305.01031 -350.498156) (xy 305.014381 -350.442534)
			(xy 305.026507 -350.388097) (xy 305.04643 -350.336006) (xy 305.073726 -350.287371) (xy 305.107812 -350.243228)
			(xy 305.147961 -350.204519) (xy 305.193319 -350.172068) (xy 305.242919 -350.146567) (xy 305.295703 -350.12856)
			(xy 305.350546 -350.11843) (xy 305.40628 -350.116393) (xy 305.461717 -350.122493) (xy 305.515674 -350.136599)
			(xy 305.567003 -350.158411) (xy 305.614609 -350.187465) (xy 305.657477 -350.22314) (xy 305.694694 -350.264677)
			(xy 305.725467 -350.31119) (xy 305.749139 -350.361687) (xy 305.765207 -350.415094) (xy 305.773327 -350.47027)
			(xy 305.773836 -350.498156) (xy 305.773327 -350.526042) (xy 305.765207 -350.581218) (xy 305.749139 -350.634625)
			(xy 305.725467 -350.685122) (xy 305.694694 -350.731635) (xy 305.657477 -350.773172) (xy 305.614609 -350.808847)
			(xy 305.567003 -350.837901) (xy 305.515674 -350.859713) (xy 305.461717 -350.873819) (xy 305.40628 -350.879919)
			(xy 305.350546 -350.877882) (xy 305.295703 -350.867752) (xy 305.242919 -350.849745) (xy 305.193319 -350.824244)
			(xy 305.147961 -350.791793) (xy 305.107812 -350.753084) (xy 305.073726 -350.708941) (xy 305.04643 -350.660306)
			(xy 305.026507 -350.608215) (xy 305.014381 -350.553778) (xy 305.01031 -350.498156) (xy 304.6476 -350.498156)
			(xy 304.6476 -351.173796) (xy 306.349146 -351.173796) (xy 306.349619 -351.146321) (xy 306.357512 -351.09194)
			(xy 306.373135 -351.039257) (xy 306.396163 -350.989365) (xy 306.426118 -350.943297) (xy 306.443888 -350.922336)
			(xy 306.444142 -350.922082) (xy 306.449747 -350.915008) (xy 306.455982 -350.898082) (xy 306.456334 -350.889062)
			(xy 306.456334 -350.821498) (xy 306.45597 -350.812482) (xy 306.449726 -350.795565) (xy 306.444142 -350.788478)
			(xy 306.443634 -350.78797) (xy 306.425896 -350.767028) (xy 306.396013 -350.720994) (xy 306.373047 -350.671148)
			(xy 306.357474 -350.618522) (xy 306.349615 -350.564205) (xy 306.349146 -350.536764) (xy 306.349632 -350.509513)
			(xy 306.357388 -350.455565) (xy 306.372743 -350.40327) (xy 306.395385 -350.353693) (xy 306.424851 -350.307843)
			(xy 306.460542 -350.266652) (xy 306.501733 -350.230961) (xy 306.547583 -350.201495) (xy 306.59716 -350.178853)
			(xy 306.649455 -350.163498) (xy 306.703403 -350.155742) (xy 306.757905 -350.155742) (xy 306.811853 -350.163498)
			(xy 306.864148 -350.178853) (xy 306.913725 -350.201495) (xy 306.959575 -350.230961) (xy 307.000766 -350.266652)
			(xy 307.036457 -350.307843) (xy 307.065923 -350.353693) (xy 307.088565 -350.40327) (xy 307.10392 -350.455565)
			(xy 307.111676 -350.509513) (xy 307.112162 -350.536764) (xy 307.111664 -350.564238) (xy 307.103776 -350.618618)
			(xy 307.088159 -350.6713) (xy 307.085506 -350.67705) (xy 307.353972 -350.67705) (xy 307.353972 -350.62255)
			(xy 307.361728 -350.568604) (xy 307.377081 -350.516311) (xy 307.399721 -350.466735) (xy 307.429185 -350.420885)
			(xy 307.464874 -350.379695) (xy 307.506061 -350.344003) (xy 307.551908 -350.314535) (xy 307.601482 -350.291892)
			(xy 307.653774 -350.276534) (xy 307.70772 -350.268774) (xy 307.73497 -350.268286) (xy 307.735224 -350.268286)
			(xy 307.760428 -350.268669) (xy 307.810397 -350.275312) (xy 307.859052 -350.288494) (xy 307.905541 -350.307982)
			(xy 307.927502 -350.320356) (xy 307.937408 -350.326198) (xy 307.959252 -350.32823) (xy 308.053994 -350.294702)
			(xy 308.069742 -350.279208) (xy 308.073806 -350.268794) (xy 308.084477 -350.242007) (xy 308.112768 -350.191764)
			(xy 308.148301 -350.146354) (xy 308.190266 -350.106811) (xy 308.237707 -350.074039) (xy 308.289542 -350.048783)
			(xy 308.344589 -350.03162) (xy 308.401592 -350.022941) (xy 308.430422 -350.022414) (xy 308.457675 -350.022857)
			(xy 308.511625 -350.030617) (xy 308.563922 -350.045977) (xy 308.613501 -350.068622) (xy 308.659352 -350.098092)
			(xy 308.700543 -350.133788) (xy 308.736234 -350.174983) (xy 308.765699 -350.220838) (xy 308.788339 -350.270419)
			(xy 308.803692 -350.322718) (xy 308.811446 -350.376669) (xy 308.81193 -350.403922) (xy 308.81126 -350.435484)
			(xy 308.800876 -350.497749) (xy 308.780395 -350.557459) (xy 308.765956 -350.585532) (xy 308.76113 -350.594422)
			(xy 308.759098 -350.61398) (xy 308.781958 -350.692466) (xy 308.785198 -350.70189) (xy 308.797613 -350.717451)
			(xy 308.806088 -350.722692) (xy 308.831211 -350.737205) (xy 308.877094 -350.772714) (xy 308.917068 -350.814763)
			(xy 308.950212 -350.862383) (xy 308.975759 -350.914474) (xy 308.99312 -350.969834) (xy 309.001895 -351.027185)
			(xy 309.00243 -351.056194) (xy 309.001944 -351.083445) (xy 308.994188 -351.137393) (xy 308.978833 -351.189688)
			(xy 308.956191 -351.239265) (xy 308.926725 -351.285115) (xy 308.891034 -351.326306) (xy 308.849843 -351.361997)
			(xy 308.803993 -351.391463) (xy 308.754416 -351.414105) (xy 308.702121 -351.42946) (xy 308.648173 -351.437216)
			(xy 308.593671 -351.437216) (xy 308.539723 -351.42946) (xy 308.487428 -351.414105) (xy 308.437851 -351.391463)
			(xy 308.392001 -351.361997) (xy 308.35081 -351.326306) (xy 308.315119 -351.285115) (xy 308.285653 -351.239265)
			(xy 308.263011 -351.189688) (xy 308.247656 -351.137393) (xy 308.2399 -351.083445) (xy 308.239414 -351.056194)
			(xy 308.240085 -351.024632) (xy 308.250467 -350.962367) (xy 308.270949 -350.902657) (xy 308.285388 -350.874584)
			(xy 308.290214 -350.865694) (xy 308.292246 -350.846136) (xy 308.269386 -350.76765) (xy 308.266163 -350.75822)
			(xy 308.253734 -350.742664) (xy 308.245256 -350.737424) (xy 308.23789 -350.73336) (xy 308.227984 -350.727518)
			(xy 308.20614 -350.725486) (xy 308.111398 -350.759014) (xy 308.09565 -350.774508) (xy 308.091586 -350.784922)
			(xy 308.08093 -350.811715) (xy 308.052637 -350.861958) (xy 308.017101 -350.907368) (xy 307.975133 -350.94691)
			(xy 307.92769 -350.979681) (xy 307.875854 -351.004936) (xy 307.820805 -351.022098) (xy 307.763801 -351.030775)
			(xy 307.73497 -351.031302) (xy 307.70772 -351.030826) (xy 307.653774 -351.023066) (xy 307.601482 -351.007708)
			(xy 307.551908 -350.985065) (xy 307.506061 -350.955597) (xy 307.464874 -350.919905) (xy 307.429185 -350.878715)
			(xy 307.399721 -350.832865) (xy 307.377081 -350.783289) (xy 307.361728 -350.730996) (xy 307.353972 -350.67705)
			(xy 307.085506 -350.67705) (xy 307.065137 -350.721193) (xy 307.035187 -350.767262) (xy 307.01742 -350.788224)
			(xy 307.017166 -350.788478) (xy 307.011579 -350.795564) (xy 307.005334 -350.812481) (xy 307.004974 -350.821498)
			(xy 307.004974 -350.889062) (xy 307.005355 -350.898076) (xy 307.011586 -350.914993) (xy 307.017166 -350.922082)
			(xy 307.017674 -350.92259) (xy 307.035395 -350.943547) (xy 307.06528 -350.989576) (xy 307.088249 -351.039419)
			(xy 307.103827 -351.092042) (xy 307.11169 -351.146356) (xy 307.112162 -351.173796) (xy 307.111676 -351.201047)
			(xy 307.10392 -351.254995) (xy 307.088565 -351.30729) (xy 307.065923 -351.356867) (xy 307.036457 -351.402717)
			(xy 307.000766 -351.443908) (xy 306.959575 -351.479599) (xy 306.913725 -351.509065) (xy 306.864148 -351.531707)
			(xy 306.811853 -351.547062) (xy 306.757905 -351.554818) (xy 306.703403 -351.554818) (xy 306.649455 -351.547062)
			(xy 306.59716 -351.531707) (xy 306.547583 -351.509065) (xy 306.501733 -351.479599) (xy 306.460542 -351.443908)
			(xy 306.424851 -351.402717) (xy 306.395385 -351.356867) (xy 306.372743 -351.30729) (xy 306.357388 -351.254995)
			(xy 306.349632 -351.201047) (xy 306.349146 -351.173796) (xy 304.6476 -351.173796) (xy 304.6476 -352.933)
			(xy 314.527182 -352.933) (xy 314.531253 -352.877378) (xy 314.543379 -352.822941) (xy 314.563302 -352.77085)
			(xy 314.590598 -352.722215) (xy 314.624684 -352.678072) (xy 314.664833 -352.639363) (xy 314.710191 -352.606912)
			(xy 314.759791 -352.581411) (xy 314.812575 -352.563404) (xy 314.867418 -352.553274) (xy 314.923152 -352.551237)
			(xy 314.978589 -352.557337) (xy 315.032546 -352.571443) (xy 315.083875 -352.593255) (xy 315.131481 -352.622309)
			(xy 315.174349 -352.657984) (xy 315.211566 -352.699521) (xy 315.242339 -352.746034) (xy 315.266011 -352.796531)
			(xy 315.282079 -352.849938) (xy 315.290199 -352.905114) (xy 315.290708 -352.933) (xy 315.290199 -352.960886)
			(xy 315.282079 -353.016062) (xy 315.266011 -353.069469) (xy 315.242339 -353.119966) (xy 315.211566 -353.166479)
			(xy 315.174349 -353.208016) (xy 315.131481 -353.243691) (xy 315.083875 -353.272745) (xy 315.032546 -353.294557)
			(xy 314.978589 -353.308663) (xy 314.923152 -353.314763) (xy 314.867418 -353.312726) (xy 314.812575 -353.302596)
			(xy 314.759791 -353.284589) (xy 314.710191 -353.259088) (xy 314.664833 -353.226637) (xy 314.624684 -353.187928)
			(xy 314.590598 -353.143785) (xy 314.563302 -353.09515) (xy 314.543379 -353.043059) (xy 314.531253 -352.988622)
			(xy 314.527182 -352.933) (xy 304.6476 -352.933) (xy 304.6476 -353.441762) (xy 304.647181 -353.451833)
			(xy 304.639459 -353.470432) (xy 304.632614 -353.47783) (xy 304.510694 -353.59975) (xy 307.212492 -353.59975)
			(xy 307.212978 -353.572499) (xy 307.220734 -353.518551) (xy 307.236089 -353.466256) (xy 307.258731 -353.416679)
			(xy 307.288197 -353.370829) (xy 307.323888 -353.329638) (xy 307.365079 -353.293947) (xy 307.410929 -353.264481)
			(xy 307.460506 -353.241839) (xy 307.512801 -353.226484) (xy 307.566749 -353.218728) (xy 307.621251 -353.218728)
			(xy 307.675199 -353.226484) (xy 307.727494 -353.241839) (xy 307.777071 -353.264481) (xy 307.822921 -353.293947)
			(xy 307.864112 -353.329638) (xy 307.899803 -353.370829) (xy 307.929269 -353.416679) (xy 307.951911 -353.466256)
			(xy 307.967266 -353.518551) (xy 307.975022 -353.572499) (xy 307.975168 -353.5807) (xy 309.409082 -353.5807)
			(xy 309.413153 -353.525078) (xy 309.425279 -353.470641) (xy 309.445202 -353.41855) (xy 309.472498 -353.369915)
			(xy 309.506584 -353.325772) (xy 309.546733 -353.287063) (xy 309.592091 -353.254612) (xy 309.641691 -353.229111)
			(xy 309.694475 -353.211104) (xy 309.749318 -353.200974) (xy 309.805052 -353.198937) (xy 309.860489 -353.205037)
			(xy 309.914446 -353.219143) (xy 309.965775 -353.240955) (xy 310.013381 -353.270009) (xy 310.056249 -353.305684)
			(xy 310.093466 -353.347221) (xy 310.121901 -353.3902) (xy 311.733182 -353.3902) (xy 311.737253 -353.334578)
			(xy 311.749379 -353.280141) (xy 311.769302 -353.22805) (xy 311.796598 -353.179415) (xy 311.830684 -353.135272)
			(xy 311.870833 -353.096563) (xy 311.916191 -353.064112) (xy 311.965791 -353.038611) (xy 312.018575 -353.020604)
			(xy 312.073418 -353.010474) (xy 312.129152 -353.008437) (xy 312.184589 -353.014537) (xy 312.238546 -353.028643)
			(xy 312.289875 -353.050455) (xy 312.337481 -353.079509) (xy 312.380349 -353.115184) (xy 312.417566 -353.156721)
			(xy 312.448339 -353.203234) (xy 312.472011 -353.253731) (xy 312.488079 -353.307138) (xy 312.496199 -353.362314)
			(xy 312.496244 -353.3648) (xy 313.409582 -353.3648) (xy 313.413653 -353.309178) (xy 313.425779 -353.254741)
			(xy 313.445702 -353.20265) (xy 313.472998 -353.154015) (xy 313.507084 -353.109872) (xy 313.547233 -353.071163)
			(xy 313.592591 -353.038712) (xy 313.642191 -353.013211) (xy 313.694975 -352.995204) (xy 313.749818 -352.985074)
			(xy 313.805552 -352.983037) (xy 313.860989 -352.989137) (xy 313.914946 -353.003243) (xy 313.966275 -353.025055)
			(xy 314.013881 -353.054109) (xy 314.056749 -353.089784) (xy 314.093966 -353.131321) (xy 314.124739 -353.177834)
			(xy 314.148411 -353.228331) (xy 314.164479 -353.281738) (xy 314.172599 -353.336914) (xy 314.173108 -353.3648)
			(xy 314.172599 -353.392686) (xy 314.164479 -353.447862) (xy 314.148411 -353.501269) (xy 314.124739 -353.551766)
			(xy 314.093966 -353.598279) (xy 314.056749 -353.639816) (xy 314.013881 -353.675491) (xy 313.966275 -353.704545)
			(xy 313.914946 -353.726357) (xy 313.860989 -353.740463) (xy 313.805552 -353.746563) (xy 313.749818 -353.744526)
			(xy 313.694975 -353.734396) (xy 313.642191 -353.716389) (xy 313.592591 -353.690888) (xy 313.547233 -353.658437)
			(xy 313.507084 -353.619728) (xy 313.472998 -353.575585) (xy 313.445702 -353.52695) (xy 313.425779 -353.474859)
			(xy 313.413653 -353.420422) (xy 313.409582 -353.3648) (xy 312.496244 -353.3648) (xy 312.496708 -353.3902)
			(xy 312.496199 -353.418086) (xy 312.488079 -353.473262) (xy 312.472011 -353.526669) (xy 312.448339 -353.577166)
			(xy 312.417566 -353.623679) (xy 312.380349 -353.665216) (xy 312.337481 -353.700891) (xy 312.289875 -353.729945)
			(xy 312.238546 -353.751757) (xy 312.184589 -353.765863) (xy 312.129152 -353.771963) (xy 312.073418 -353.769926)
			(xy 312.018575 -353.759796) (xy 311.965791 -353.741789) (xy 311.916191 -353.716288) (xy 311.870833 -353.683837)
			(xy 311.830684 -353.645128) (xy 311.796598 -353.600985) (xy 311.769302 -353.55235) (xy 311.749379 -353.500259)
			(xy 311.737253 -353.445822) (xy 311.733182 -353.3902) (xy 310.121901 -353.3902) (xy 310.124239 -353.393734)
			(xy 310.147911 -353.444231) (xy 310.163979 -353.497638) (xy 310.172099 -353.552814) (xy 310.172608 -353.5807)
			(xy 310.172099 -353.608586) (xy 310.163979 -353.663762) (xy 310.147911 -353.717169) (xy 310.124239 -353.767666)
			(xy 310.093466 -353.814179) (xy 310.056249 -353.855716) (xy 310.013381 -353.891391) (xy 309.965775 -353.920445)
			(xy 309.914446 -353.942257) (xy 309.888653 -353.949) (xy 310.564782 -353.949) (xy 310.568853 -353.893378)
			(xy 310.580979 -353.838941) (xy 310.600902 -353.78685) (xy 310.628198 -353.738215) (xy 310.662284 -353.694072)
			(xy 310.702433 -353.655363) (xy 310.747791 -353.622912) (xy 310.797391 -353.597411) (xy 310.850175 -353.579404)
			(xy 310.905018 -353.569274) (xy 310.960752 -353.567237) (xy 311.016189 -353.573337) (xy 311.070146 -353.587443)
			(xy 311.121475 -353.609255) (xy 311.169081 -353.638309) (xy 311.211949 -353.673984) (xy 311.249166 -353.715521)
			(xy 311.279939 -353.762034) (xy 311.303611 -353.812531) (xy 311.319679 -353.865938) (xy 311.327799 -353.921114)
			(xy 311.328308 -353.949) (xy 311.327799 -353.976886) (xy 311.319679 -354.032062) (xy 311.303611 -354.085469)
			(xy 311.279939 -354.135966) (xy 311.249166 -354.182479) (xy 311.211949 -354.224016) (xy 311.169081 -354.259691)
			(xy 311.121475 -354.288745) (xy 311.070146 -354.310557) (xy 311.016189 -354.324663) (xy 310.960752 -354.330763)
			(xy 310.905018 -354.328726) (xy 310.850175 -354.318596) (xy 310.797391 -354.300589) (xy 310.747791 -354.275088)
			(xy 310.702433 -354.242637) (xy 310.662284 -354.203928) (xy 310.628198 -354.159785) (xy 310.600902 -354.11115)
			(xy 310.580979 -354.059059) (xy 310.568853 -354.004622) (xy 310.564782 -353.949) (xy 309.888653 -353.949)
			(xy 309.860489 -353.956363) (xy 309.805052 -353.962463) (xy 309.749318 -353.960426) (xy 309.694475 -353.950296)
			(xy 309.641691 -353.932289) (xy 309.592091 -353.906788) (xy 309.546733 -353.874337) (xy 309.506584 -353.835628)
			(xy 309.472498 -353.791485) (xy 309.445202 -353.74285) (xy 309.425279 -353.690759) (xy 309.413153 -353.636322)
			(xy 309.409082 -353.5807) (xy 307.975168 -353.5807) (xy 307.975508 -353.59975) (xy 307.974903 -353.628935)
			(xy 307.966012 -353.686624) (xy 307.948445 -353.742289) (xy 307.922611 -353.794631) (xy 307.889112 -353.842432)
			(xy 307.848729 -353.884578) (xy 307.825902 -353.902772) (xy 307.815264 -353.911392) (xy 307.798733 -353.933209)
			(xy 307.788603 -353.958638) (xy 307.785606 -353.985847) (xy 307.789959 -354.012871) (xy 307.801346 -354.037763)
			(xy 307.818946 -354.058727) (xy 307.829966 -354.066856) (xy 307.851369 -354.082218) (xy 307.89017 -354.117855)
			(xy 307.923701 -354.158491) (xy 307.951324 -354.203352) (xy 307.972514 -354.251586) (xy 307.986869 -354.302276)
			(xy 307.994115 -354.354458) (xy 307.994558 -354.3808) (xy 307.994072 -354.408051) (xy 307.986316 -354.461999)
			(xy 307.980326 -354.4824) (xy 312.977782 -354.4824) (xy 312.981853 -354.426778) (xy 312.993979 -354.372341)
			(xy 313.013902 -354.32025) (xy 313.041198 -354.271615) (xy 313.075284 -354.227472) (xy 313.115433 -354.188763)
			(xy 313.160791 -354.156312) (xy 313.210391 -354.130811) (xy 313.263175 -354.112804) (xy 313.318018 -354.102674)
			(xy 313.373752 -354.100637) (xy 313.429189 -354.106737) (xy 313.483146 -354.120843) (xy 313.534475 -354.142655)
			(xy 313.582081 -354.171709) (xy 313.624949 -354.207384) (xy 313.662166 -354.248921) (xy 313.692939 -354.295434)
			(xy 313.716611 -354.345931) (xy 313.732679 -354.399338) (xy 313.740799 -354.454514) (xy 313.740844 -354.457)
			(xy 314.120782 -354.457) (xy 314.124853 -354.401378) (xy 314.136979 -354.346941) (xy 314.156902 -354.29485)
			(xy 314.184198 -354.246215) (xy 314.218284 -354.202072) (xy 314.258433 -354.163363) (xy 314.303791 -354.130912)
			(xy 314.353391 -354.105411) (xy 314.406175 -354.087404) (xy 314.461018 -354.077274) (xy 314.516752 -354.075237)
			(xy 314.572189 -354.081337) (xy 314.626146 -354.095443) (xy 314.677475 -354.117255) (xy 314.725081 -354.146309)
			(xy 314.767949 -354.181984) (xy 314.805166 -354.223521) (xy 314.835939 -354.270034) (xy 314.859611 -354.320531)
			(xy 314.875679 -354.373938) (xy 314.883799 -354.429114) (xy 314.884308 -354.457) (xy 314.883799 -354.484886)
			(xy 314.875679 -354.540062) (xy 314.859611 -354.593469) (xy 314.835939 -354.643966) (xy 314.805166 -354.690479)
			(xy 314.767949 -354.732016) (xy 314.725081 -354.767691) (xy 314.677475 -354.796745) (xy 314.626146 -354.818557)
			(xy 314.572189 -354.832663) (xy 314.516752 -354.838763) (xy 314.461018 -354.836726) (xy 314.406175 -354.826596)
			(xy 314.353391 -354.808589) (xy 314.303791 -354.783088) (xy 314.258433 -354.750637) (xy 314.218284 -354.711928)
			(xy 314.184198 -354.667785) (xy 314.156902 -354.61915) (xy 314.136979 -354.567059) (xy 314.124853 -354.512622)
			(xy 314.120782 -354.457) (xy 313.740844 -354.457) (xy 313.741308 -354.4824) (xy 313.740799 -354.510286)
			(xy 313.732679 -354.565462) (xy 313.716611 -354.618869) (xy 313.692939 -354.669366) (xy 313.662166 -354.715879)
			(xy 313.624949 -354.757416) (xy 313.582081 -354.793091) (xy 313.534475 -354.822145) (xy 313.483146 -354.843957)
			(xy 313.429189 -354.858063) (xy 313.373752 -354.864163) (xy 313.318018 -354.862126) (xy 313.263175 -354.851996)
			(xy 313.210391 -354.833989) (xy 313.160791 -354.808488) (xy 313.115433 -354.776037) (xy 313.075284 -354.737328)
			(xy 313.041198 -354.693185) (xy 313.013902 -354.64455) (xy 312.993979 -354.592459) (xy 312.981853 -354.538022)
			(xy 312.977782 -354.4824) (xy 307.980326 -354.4824) (xy 307.970961 -354.514294) (xy 307.948319 -354.563871)
			(xy 307.918853 -354.609721) (xy 307.883162 -354.650912) (xy 307.841971 -354.686603) (xy 307.796121 -354.716069)
			(xy 307.746544 -354.738711) (xy 307.694249 -354.754066) (xy 307.640301 -354.761822) (xy 307.585799 -354.761822)
			(xy 307.531851 -354.754066) (xy 307.479556 -354.738711) (xy 307.429979 -354.716069) (xy 307.384129 -354.686603)
			(xy 307.342938 -354.650912) (xy 307.307247 -354.609721) (xy 307.277781 -354.563871) (xy 307.255139 -354.514294)
			(xy 307.239784 -354.461999) (xy 307.232028 -354.408051) (xy 307.231542 -354.3808) (xy 307.232092 -354.351613)
			(xy 307.240992 -354.29392) (xy 307.258568 -354.238254) (xy 307.284413 -354.185911) (xy 307.317922 -354.138112)
			(xy 307.358316 -354.095969) (xy 307.381148 -354.077778) (xy 307.391729 -354.069096) (xy 307.408252 -354.047292)
			(xy 307.41838 -354.021877) (xy 307.421381 -353.994684) (xy 307.417041 -353.967672) (xy 307.405672 -353.942789)
			(xy 307.388092 -353.921826) (xy 307.377084 -353.913694) (xy 307.355646 -353.898378) (xy 307.316848 -353.862732)
			(xy 307.283322 -353.822087) (xy 307.255704 -353.777219) (xy 307.234519 -353.728978) (xy 307.220171 -353.678281)
			(xy 307.212932 -353.626094) (xy 307.212492 -353.59975) (xy 304.510694 -353.59975) (xy 304.047398 -354.063046)
			(xy 304.039998 -354.069886) (xy 304.021398 -354.077604) (xy 304.01133 -354.078032) (xy 303.187354 -354.078032)
			(xy 303.177287 -354.078477) (xy 303.158688 -354.086183) (xy 303.151286 -354.093018) (xy 302.6664 -354.578158)
			(xy 302.658989 -354.584985) (xy 302.640398 -354.592713) (xy 302.630332 -354.593144) (xy 300.618398 -354.593144)
			(xy 300.608354 -354.593527) (xy 300.589757 -354.601106) (xy 300.58233 -354.607876) (xy 300.546262 -354.643944)
			(xy 300.539405 -354.65133) (xy 300.531696 -354.66994) (xy 300.531276 -354.680012) (xy 300.531276 -354.711)
			(xy 302.969166 -354.711) (xy 302.973237 -354.655378) (xy 302.985363 -354.600941) (xy 303.005286 -354.54885)
			(xy 303.032582 -354.500215) (xy 303.066668 -354.456072) (xy 303.106817 -354.417363) (xy 303.152175 -354.384912)
			(xy 303.201775 -354.359411) (xy 303.254559 -354.341404) (xy 303.309402 -354.331274) (xy 303.365136 -354.329237)
			(xy 303.420573 -354.335337) (xy 303.47453 -354.349443) (xy 303.525859 -354.371255) (xy 303.573465 -354.400309)
			(xy 303.616333 -354.435984) (xy 303.65355 -354.477521) (xy 303.684323 -354.524034) (xy 303.707995 -354.574531)
			(xy 303.724063 -354.627938) (xy 303.732183 -354.683114) (xy 303.732692 -354.711) (xy 303.732183 -354.738886)
			(xy 303.724063 -354.794062) (xy 303.707995 -354.847469) (xy 303.684323 -354.897966) (xy 303.65355 -354.944479)
			(xy 303.616333 -354.986016) (xy 303.573465 -355.021691) (xy 303.525859 -355.050745) (xy 303.47453 -355.072557)
			(xy 303.420573 -355.086663) (xy 303.365136 -355.092763) (xy 303.309402 -355.090726) (xy 303.254559 -355.080596)
			(xy 303.201775 -355.062589) (xy 303.152175 -355.037088) (xy 303.106817 -355.004637) (xy 303.066668 -354.965928)
			(xy 303.032582 -354.921785) (xy 303.005286 -354.87315) (xy 302.985363 -354.821059) (xy 302.973237 -354.766622)
			(xy 302.969166 -354.711) (xy 300.531276 -354.711) (xy 300.531276 -358.14) (xy 302.876458 -358.14)
			(xy 302.876978 -358.11275) (xy 302.884733 -358.058806) (xy 302.900087 -358.006514) (xy 302.922725 -357.956939)
			(xy 302.952189 -357.91109) (xy 302.987876 -357.8699) (xy 303.029063 -357.834209) (xy 303.074909 -357.804742)
			(xy 303.124482 -357.782099) (xy 303.176772 -357.766741) (xy 303.230716 -357.75898) (xy 303.257966 -357.758492)
			(xy 303.286438 -357.75901) (xy 303.342749 -357.767477) (xy 303.397174 -357.784229) (xy 303.423066 -357.796084)
			(xy 303.428146 -357.798624) (xy 303.439322 -357.801164) (xy 305.010312 -357.801164) (xy 305.018862 -357.800868)
			(xy 305.035006 -357.795233) (xy 305.048393 -357.784594) (xy 305.053238 -357.777542) (xy 305.106324 -357.693722)
			(xy 305.107848 -357.668068) (xy 305.10226 -357.65613) (xy 305.090697 -357.63052) (xy 305.074409 -357.576742)
			(xy 305.066179 -357.521157) (xy 305.065684 -357.493062) (xy 305.066446 -357.468678) (xy 305.067208 -357.458264)
			(xy 305.060096 -357.438452) (xy 305.002184 -357.37673) (xy 304.99466 -357.369501) (xy 304.975522 -357.361237)
			(xy 304.9651 -357.360728) (xy 303.484788 -357.360728) (xy 303.477676 -357.36276) (xy 303.451228 -357.3701)
			(xy 303.396915 -357.378011) (xy 303.369472 -357.378508) (xy 303.368964 -357.378508) (xy 303.341714 -357.37802)
			(xy 303.287771 -357.370259) (xy 303.23548 -357.354901) (xy 303.185907 -357.332258) (xy 303.140062 -357.30279)
			(xy 303.098876 -357.267099) (xy 303.063188 -357.22591) (xy 303.033725 -357.180061) (xy 303.011087 -357.130486)
			(xy 302.995733 -357.078194) (xy 302.987978 -357.02425) (xy 302.987978 -356.96975) (xy 302.995733 -356.915806)
			(xy 303.011087 -356.863514) (xy 303.033725 -356.813939) (xy 303.063188 -356.76809) (xy 303.098876 -356.726901)
			(xy 303.140062 -356.69121) (xy 303.185907 -356.661742) (xy 303.23548 -356.639099) (xy 303.287771 -356.623741)
			(xy 303.341714 -356.61598) (xy 303.368964 -356.615492) (xy 303.369472 -356.615492) (xy 303.396915 -356.61598)
			(xy 303.45123 -356.623892) (xy 303.477676 -356.63124) (xy 303.484788 -356.633272) (xy 305.8668 -356.633272)
			(xy 305.895373 -356.633846) (xy 305.951807 -356.642839) (xy 306.006141 -356.660543) (xy 306.057042 -356.686521)
			(xy 306.103256 -356.720135) (xy 306.123848 -356.739952) (xy 306.716938 -357.333042) (xy 306.724326 -357.339897)
			(xy 306.742935 -357.347607) (xy 306.753006 -357.348028) (xy 312.307478 -357.348028) (xy 312.319644 -357.347364)
			(xy 312.341266 -357.336206) (xy 312.34888 -357.326692) (xy 312.396886 -357.259128) (xy 312.40334 -357.248843)
			(xy 312.406785 -357.224841) (xy 312.40349 -357.213154) (xy 312.40349 -357.2129) (xy 312.394149 -357.184072)
			(xy 312.384055 -357.124325) (xy 312.383424 -357.094028) (xy 312.383424 -356.144068) (xy 312.383036 -356.133994)
			(xy 312.375291 -356.115395) (xy 312.368438 -356.108) (xy 312.20537 -355.944932) (xy 312.198552 -355.93868)
			(xy 312.181712 -355.931059) (xy 312.163266 -355.929892) (xy 312.154316 -355.932232) (xy 312.054494 -355.963474)
			(xy 312.035952 -355.984556) (xy 312.033412 -355.998526) (xy 312.028328 -356.024091) (xy 312.012089 -356.073621)
			(xy 311.98925 -356.120474) (xy 311.960236 -356.163777) (xy 311.925589 -356.202719) (xy 311.885957 -356.236575)
			(xy 311.864248 -356.251002) (xy 311.857231 -356.255859) (xy 311.846683 -356.269263) (xy 311.841154 -356.285398)
			(xy 311.84088 -356.293928) (xy 311.84088 -356.379272) (xy 311.841175 -356.387794) (xy 311.846736 -356.403905)
			(xy 311.857257 -356.417314) (xy 311.864248 -356.422198) (xy 311.886918 -356.437316) (xy 311.928113 -356.472982)
			(xy 311.96381 -356.51415) (xy 311.993282 -356.559981) (xy 312.015928 -356.609542) (xy 312.031286 -356.661821)
			(xy 312.039044 -356.715755) (xy 312.039508 -356.743) (xy 312.039022 -356.770251) (xy 312.031266 -356.824199)
			(xy 312.015911 -356.876494) (xy 311.993269 -356.926071) (xy 311.963803 -356.971921) (xy 311.928112 -357.013112)
			(xy 311.886921 -357.048803) (xy 311.841071 -357.078269) (xy 311.791494 -357.100911) (xy 311.739199 -357.116266)
			(xy 311.685251 -357.124022) (xy 311.630749 -357.124022) (xy 311.576801 -357.116266) (xy 311.524506 -357.100911)
			(xy 311.474929 -357.078269) (xy 311.429079 -357.048803) (xy 311.387888 -357.013112) (xy 311.352197 -356.971921)
			(xy 311.322731 -356.926071) (xy 311.300089 -356.876494) (xy 311.284734 -356.824199) (xy 311.276978 -356.770251)
			(xy 311.276492 -356.743) (xy 311.276989 -356.715757) (xy 311.284746 -356.661825) (xy 311.3001 -356.609547)
			(xy 311.32274 -356.559987) (xy 311.352205 -356.514154) (xy 311.387894 -356.472982) (xy 311.42908 -356.437311)
			(xy 311.451752 -356.422198) (xy 311.458769 -356.417341) (xy 311.469317 -356.403937) (xy 311.474846 -356.387802)
			(xy 311.47512 -356.379272) (xy 311.47512 -356.293928) (xy 311.474825 -356.285406) (xy 311.469264 -356.269295)
			(xy 311.458743 -356.255886) (xy 311.451752 -356.251002) (xy 311.429082 -356.235884) (xy 311.387887 -356.200218)
			(xy 311.35219 -356.15905) (xy 311.322718 -356.113219) (xy 311.300072 -356.063658) (xy 311.284714 -356.011379)
			(xy 311.276956 -355.957445) (xy 311.276492 -355.9302) (xy 311.276873 -355.904529) (xy 311.283766 -355.853652)
			(xy 311.297414 -355.804157) (xy 311.317572 -355.756937) (xy 311.343874 -355.712844) (xy 311.375848 -355.672673)
			(xy 311.394094 -355.65461) (xy 311.401714 -355.647244) (xy 311.409842 -355.628448) (xy 311.409842 -355.61778)
			(xy 311.40933 -355.607776) (xy 311.401671 -355.589292) (xy 311.387527 -355.575141) (xy 311.369046 -355.567475)
			(xy 311.359042 -355.56698) (xy 311.285636 -355.56698) (xy 311.275566 -355.567403) (xy 311.256967 -355.575123)
			(xy 311.249568 -355.581966) (xy 310.372252 -356.459282) (xy 310.35163 -356.479053) (xy 310.305414 -356.512628)
			(xy 310.254516 -356.53856) (xy 310.200187 -356.556212) (xy 310.143766 -356.565148) (xy 310.115204 -356.565708)
			(xy 308.329838 -356.565708) (xy 308.301277 -356.565108) (xy 308.244859 -356.556173) (xy 308.19053 -356.538532)
			(xy 308.139625 -356.512618) (xy 308.093395 -356.479068) (xy 308.07279 -356.459282) (xy 307.582824 -355.96957)
			(xy 307.575413 -355.962744) (xy 307.556822 -355.955017) (xy 307.546756 -355.954584) (xy 303.710848 -355.954584)
			(xy 303.7008 -355.95493) (xy 303.682203 -355.962533) (xy 303.67478 -355.969316) (xy 303.614836 -356.02926)
			(xy 303.611534 -356.035864) (xy 303.597102 -356.061358) (xy 303.561616 -356.107968) (xy 303.519426 -356.148611)
			(xy 303.471524 -356.182332) (xy 303.419033 -356.208341) (xy 303.363185 -356.226027) (xy 303.305291 -356.234975)
			(xy 303.276 -356.235508) (xy 303.248749 -356.235022) (xy 303.194801 -356.227266) (xy 303.142506 -356.211911)
			(xy 303.092929 -356.189269) (xy 303.047079 -356.159803) (xy 303.005888 -356.124112) (xy 302.970197 -356.082921)
			(xy 302.940731 -356.037071) (xy 302.918089 -355.987494) (xy 302.902734 -355.935199) (xy 302.894978 -355.881251)
			(xy 302.894492 -355.854) (xy 302.894987 -355.824708) (xy 302.903938 -355.766811) (xy 302.921628 -355.710961)
			(xy 302.947644 -355.65847) (xy 302.981373 -355.61057) (xy 303.022025 -355.568385) (xy 303.068644 -355.532905)
			(xy 303.094136 -355.518466) (xy 303.097325 -355.516694) (xy 303.103191 -355.512359) (xy 303.10582 -355.50983)
			(xy 303.282096 -355.333808) (xy 303.302676 -355.313975) (xy 303.348885 -355.280347) (xy 303.399787 -355.254362)
			(xy 303.454128 -355.236661) (xy 303.510569 -355.227679) (xy 303.539144 -355.227128) (xy 307.71846 -355.227128)
			(xy 307.747032 -355.227711) (xy 307.803467 -355.2367) (xy 307.857802 -355.2544) (xy 307.908703 -355.280377)
			(xy 307.954917 -355.313991) (xy 307.961784 -355.3206) (xy 309.370982 -355.3206) (xy 309.375053 -355.264978)
			(xy 309.387179 -355.210541) (xy 309.407102 -355.15845) (xy 309.434398 -355.109815) (xy 309.468484 -355.065672)
			(xy 309.508633 -355.026963) (xy 309.553991 -354.994512) (xy 309.603591 -354.969011) (xy 309.656375 -354.951004)
			(xy 309.711218 -354.940874) (xy 309.766952 -354.938837) (xy 309.822389 -354.944937) (xy 309.876346 -354.959043)
			(xy 309.927675 -354.980855) (xy 309.975281 -355.009909) (xy 310.018149 -355.045584) (xy 310.055366 -355.087121)
			(xy 310.086139 -355.133634) (xy 310.109811 -355.184131) (xy 310.125879 -355.237538) (xy 310.133999 -355.292714)
			(xy 310.134508 -355.3206) (xy 310.133999 -355.348486) (xy 310.125879 -355.403662) (xy 310.109811 -355.457069)
			(xy 310.086139 -355.507566) (xy 310.055366 -355.554079) (xy 310.018149 -355.595616) (xy 309.975281 -355.631291)
			(xy 309.927675 -355.660345) (xy 309.876346 -355.682157) (xy 309.822389 -355.696263) (xy 309.766952 -355.702363)
			(xy 309.711218 -355.700326) (xy 309.656375 -355.690196) (xy 309.603591 -355.672189) (xy 309.553991 -355.646688)
			(xy 309.508633 -355.614237) (xy 309.468484 -355.575528) (xy 309.434398 -355.531385) (xy 309.407102 -355.48275)
			(xy 309.387179 -355.430659) (xy 309.375053 -355.376222) (xy 309.370982 -355.3206) (xy 307.961784 -355.3206)
			(xy 307.975508 -355.333808) (xy 308.465474 -355.823774) (xy 308.472892 -355.830591) (xy 308.491477 -355.838325)
			(xy 308.501542 -355.83876) (xy 309.9435 -355.83876) (xy 309.953571 -355.838345) (xy 309.972169 -355.830618)
			(xy 309.979568 -355.823774) (xy 310.856884 -354.946458) (xy 310.87748 -354.926659) (xy 310.923704 -354.89309)
			(xy 310.97461 -354.867165) (xy 311.028943 -354.849519) (xy 311.085368 -354.84059) (xy 311.113932 -354.840032)
			(xy 311.97804 -354.840032) (xy 312.006603 -354.840571) (xy 312.063025 -354.849519) (xy 312.117355 -354.867174)
			(xy 312.168259 -354.893102) (xy 312.214486 -354.926666) (xy 312.235088 -354.946458) (xy 313.003946 -355.715316)
			(xy 313.023761 -355.735897) (xy 313.057327 -355.782125) (xy 313.080992 -355.8286) (xy 314.196982 -355.8286)
			(xy 314.201053 -355.772978) (xy 314.213179 -355.718541) (xy 314.233102 -355.66645) (xy 314.260398 -355.617815)
			(xy 314.294484 -355.573672) (xy 314.334633 -355.534963) (xy 314.379991 -355.502512) (xy 314.429591 -355.477011)
			(xy 314.482375 -355.459004) (xy 314.537218 -355.448874) (xy 314.592952 -355.446837) (xy 314.648389 -355.452937)
			(xy 314.702346 -355.467043) (xy 314.753675 -355.488855) (xy 314.801281 -355.517909) (xy 314.844149 -355.553584)
			(xy 314.881366 -355.595121) (xy 314.912139 -355.641634) (xy 314.935811 -355.692131) (xy 314.951879 -355.745538)
			(xy 314.959999 -355.800714) (xy 314.960508 -355.8286) (xy 314.959999 -355.856486) (xy 314.951879 -355.911662)
			(xy 314.935811 -355.965069) (xy 314.912139 -356.015566) (xy 314.881366 -356.062079) (xy 314.844149 -356.103616)
			(xy 314.801281 -356.139291) (xy 314.753675 -356.168345) (xy 314.702346 -356.190157) (xy 314.648389 -356.204263)
			(xy 314.592952 -356.210363) (xy 314.537218 -356.208326) (xy 314.482375 -356.198196) (xy 314.429591 -356.180189)
			(xy 314.379991 -356.154688) (xy 314.334633 -356.122237) (xy 314.294484 -356.083528) (xy 314.260398 -356.039385)
			(xy 314.233102 -355.99075) (xy 314.213179 -355.938659) (xy 314.201053 -355.884222) (xy 314.196982 -355.8286)
			(xy 313.080992 -355.8286) (xy 313.08325 -355.833035) (xy 313.100891 -355.887372) (xy 313.109817 -355.943799)
			(xy 313.110372 -355.972364) (xy 313.110372 -356.7176) (xy 313.282582 -356.7176) (xy 313.286653 -356.661978)
			(xy 313.298779 -356.607541) (xy 313.318702 -356.55545) (xy 313.345998 -356.506815) (xy 313.380084 -356.462672)
			(xy 313.420233 -356.423963) (xy 313.465591 -356.391512) (xy 313.515191 -356.366011) (xy 313.567975 -356.348004)
			(xy 313.622818 -356.337874) (xy 313.678552 -356.335837) (xy 313.733989 -356.341937) (xy 313.787946 -356.356043)
			(xy 313.839275 -356.377855) (xy 313.886881 -356.406909) (xy 313.929749 -356.442584) (xy 313.966966 -356.484121)
			(xy 313.970194 -356.489) (xy 315.670182 -356.489) (xy 315.674253 -356.433378) (xy 315.686379 -356.378941)
			(xy 315.706302 -356.32685) (xy 315.733598 -356.278215) (xy 315.767684 -356.234072) (xy 315.807833 -356.195363)
			(xy 315.853191 -356.162912) (xy 315.902791 -356.137411) (xy 315.955575 -356.119404) (xy 316.010418 -356.109274)
			(xy 316.066152 -356.107237) (xy 316.121589 -356.113337) (xy 316.175546 -356.127443) (xy 316.226875 -356.149255)
			(xy 316.274481 -356.178309) (xy 316.317349 -356.213984) (xy 316.354566 -356.255521) (xy 316.385339 -356.302034)
			(xy 316.409011 -356.352531) (xy 316.425079 -356.405938) (xy 316.433199 -356.461114) (xy 316.43336 -356.46995)
			(xy 317.016382 -356.46995) (xy 317.020453 -356.414328) (xy 317.032579 -356.359891) (xy 317.052502 -356.3078)
			(xy 317.079798 -356.259165) (xy 317.113884 -356.215022) (xy 317.154033 -356.176313) (xy 317.199391 -356.143862)
			(xy 317.248991 -356.118361) (xy 317.301775 -356.100354) (xy 317.356618 -356.090224) (xy 317.412352 -356.088187)
			(xy 317.467789 -356.094287) (xy 317.521746 -356.108393) (xy 317.573075 -356.130205) (xy 317.620681 -356.159259)
			(xy 317.663549 -356.194934) (xy 317.700766 -356.236471) (xy 317.731539 -356.282984) (xy 317.755211 -356.333481)
			(xy 317.771279 -356.386888) (xy 317.779399 -356.442064) (xy 317.779908 -356.46995) (xy 317.779399 -356.497836)
			(xy 317.771279 -356.553012) (xy 317.755211 -356.606419) (xy 317.731539 -356.656916) (xy 317.700766 -356.703429)
			(xy 317.663549 -356.744966) (xy 317.620681 -356.780641) (xy 317.573075 -356.809695) (xy 317.521746 -356.831507)
			(xy 317.467789 -356.845613) (xy 317.412352 -356.851713) (xy 317.356618 -356.849676) (xy 317.301775 -356.839546)
			(xy 317.248991 -356.821539) (xy 317.199391 -356.796038) (xy 317.154033 -356.763587) (xy 317.113884 -356.724878)
			(xy 317.079798 -356.680735) (xy 317.052502 -356.6321) (xy 317.032579 -356.580009) (xy 317.020453 -356.525572)
			(xy 317.016382 -356.46995) (xy 316.43336 -356.46995) (xy 316.433708 -356.489) (xy 316.433199 -356.516886)
			(xy 316.425079 -356.572062) (xy 316.409011 -356.625469) (xy 316.385339 -356.675966) (xy 316.354566 -356.722479)
			(xy 316.317349 -356.764016) (xy 316.274481 -356.799691) (xy 316.226875 -356.828745) (xy 316.175546 -356.850557)
			(xy 316.121589 -356.864663) (xy 316.066152 -356.870763) (xy 316.010418 -356.868726) (xy 315.955575 -356.858596)
			(xy 315.902791 -356.840589) (xy 315.853191 -356.815088) (xy 315.807833 -356.782637) (xy 315.767684 -356.743928)
			(xy 315.733598 -356.699785) (xy 315.706302 -356.65115) (xy 315.686379 -356.599059) (xy 315.674253 -356.544622)
			(xy 315.670182 -356.489) (xy 313.970194 -356.489) (xy 313.997739 -356.530634) (xy 314.021411 -356.581131)
			(xy 314.037479 -356.634538) (xy 314.045599 -356.689714) (xy 314.046108 -356.7176) (xy 314.045599 -356.745486)
			(xy 314.037479 -356.800662) (xy 314.021411 -356.854069) (xy 313.997739 -356.904566) (xy 313.966966 -356.951079)
			(xy 313.929749 -356.992616) (xy 313.886881 -357.028291) (xy 313.839275 -357.057345) (xy 313.787946 -357.079157)
			(xy 313.733989 -357.093263) (xy 313.678552 -357.099363) (xy 313.622818 -357.097326) (xy 313.567975 -357.087196)
			(xy 313.515191 -357.069189) (xy 313.465591 -357.043688) (xy 313.420233 -357.011237) (xy 313.380084 -356.972528)
			(xy 313.345998 -356.928385) (xy 313.318702 -356.87975) (xy 313.298779 -356.827659) (xy 313.286653 -356.773222)
			(xy 313.282582 -356.7176) (xy 313.110372 -356.7176) (xy 313.110372 -356.921816) (xy 313.11077 -356.931889)
			(xy 313.118508 -356.950487) (xy 313.125358 -356.957884) (xy 313.370214 -357.202486) (xy 313.377617 -357.209323)
			(xy 313.396214 -357.217045) (xy 313.406282 -357.217472) (xy 326.8472 -357.217472) (xy 326.875773 -357.218046)
			(xy 326.932207 -357.227039) (xy 326.986541 -357.244743) (xy 327.037442 -357.270721) (xy 327.083656 -357.304335)
			(xy 327.104248 -357.324152) (xy 328.882378 -359.102152) (xy 335.533238 -359.102152) (xy 335.533763 -359.074042)
			(xy 335.542002 -359.018429) (xy 335.558308 -358.964625) (xy 335.582329 -358.913795) (xy 335.613546 -358.867038)
			(xy 335.632044 -358.845866) (xy 335.637923 -358.838814) (xy 335.644683 -358.821756) (xy 335.645252 -358.812592)
			(xy 335.646522 -358.745536) (xy 335.646309 -358.736408) (xy 335.64018 -358.719223) (xy 335.634584 -358.712008)
			(xy 335.63433 -358.711754) (xy 335.61724 -358.690976) (xy 335.58848 -358.645509) (xy 335.566395 -358.596451)
			(xy 335.551422 -358.544777) (xy 335.54386 -358.491512) (xy 335.543398 -358.464612) (xy 335.543867 -358.437359)
			(xy 335.551622 -358.383408) (xy 335.566977 -358.33111) (xy 335.589618 -358.28153) (xy 335.619086 -358.235676)
			(xy 335.654779 -358.194483) (xy 335.695971 -358.158789) (xy 335.741824 -358.129321) (xy 335.791404 -358.106679)
			(xy 335.843702 -358.091323) (xy 335.897653 -358.083567) (xy 335.924906 -358.083104) (xy 335.953823 -358.083617)
			(xy 336.010995 -358.092347) (xy 336.066194 -358.109606) (xy 336.118155 -358.134998) (xy 336.165689 -358.167943)
			(xy 336.207706 -358.207684) (xy 336.225896 -358.23017) (xy 336.233503 -358.238977) (xy 336.254404 -358.249158)
			(xy 336.266028 -358.249728) (xy 336.345784 -358.249728) (xy 336.357417 -358.24919) (xy 336.378328 -358.239003)
			(xy 336.385916 -358.23017) (xy 336.402669 -358.209387) (xy 336.441023 -358.172257) (xy 336.484177 -358.140835)
			(xy 336.531291 -358.115736) (xy 336.581443 -358.09745) (xy 336.633654 -358.086333) (xy 336.686906 -358.082603)
			(xy 336.740158 -358.086333) (xy 336.792369 -358.09745) (xy 336.842521 -358.115736) (xy 336.889635 -358.140835)
			(xy 336.932789 -358.172257) (xy 336.971143 -358.209387) (xy 336.987896 -358.23017) (xy 336.995503 -358.238977)
			(xy 337.016404 -358.249158) (xy 337.028028 -358.249728) (xy 337.107784 -358.249728) (xy 337.119417 -358.24919)
			(xy 337.140328 -358.239003) (xy 337.147916 -358.23017) (xy 337.16609 -358.207673) (xy 337.208115 -358.16794)
			(xy 337.255653 -358.135003) (xy 337.307618 -358.109617) (xy 337.362818 -358.092364) (xy 337.419989 -358.083638)
			(xy 337.448906 -358.083104) (xy 337.477834 -358.083626) (xy 337.535025 -358.092383) (xy 337.590236 -358.109678)
			(xy 337.642201 -358.135116) (xy 337.689727 -358.168113) (xy 337.731722 -358.207911) (xy 337.749896 -358.230424)
			(xy 337.757008 -358.239568) (xy 337.777582 -358.249728) (xy 337.880452 -358.250998) (xy 337.90128 -358.241346)
			(xy 337.908646 -358.232456) (xy 337.915758 -358.224074) (xy 337.916012 -358.22382) (xy 337.921598 -358.216733)
			(xy 337.927845 -358.199816) (xy 337.928204 -358.1908) (xy 337.928204 -358.123744) (xy 337.927825 -358.114729)
			(xy 337.921593 -358.097812) (xy 337.916012 -358.090724) (xy 337.915758 -358.090724) (xy 337.915758 -358.09047)
			(xy 337.898131 -358.069528) (xy 337.868419 -358.023557) (xy 337.845581 -357.973812) (xy 337.830087 -357.921314)
			(xy 337.822254 -357.86714) (xy 337.821778 -357.839772) (xy 337.822252 -357.812521) (xy 337.830012 -357.758573)
			(xy 337.84537 -357.706279) (xy 337.868013 -357.656703) (xy 337.897481 -357.610853) (xy 337.933174 -357.569664)
			(xy 337.974364 -357.533973) (xy 338.020215 -357.504506) (xy 338.069792 -357.481865) (xy 338.122087 -357.466509)
			(xy 338.176035 -357.458751) (xy 338.203286 -357.458264) (xy 338.232204 -357.458768) (xy 338.289377 -357.467497)
			(xy 338.344577 -357.484756) (xy 338.396539 -357.51015) (xy 338.444072 -357.543097) (xy 338.486087 -357.582842)
			(xy 338.504276 -357.60533) (xy 338.511898 -357.614121) (xy 338.532788 -357.624312) (xy 338.544408 -357.624888)
			(xy 338.624164 -357.624888) (xy 338.635799 -357.624376) (xy 338.656709 -357.614168) (xy 338.664296 -357.60533)
			(xy 338.681049 -357.584547) (xy 338.719403 -357.547417) (xy 338.762557 -357.515995) (xy 338.809671 -357.490896)
			(xy 338.859823 -357.47261) (xy 338.912034 -357.461493) (xy 338.965286 -357.457763) (xy 339.018538 -357.461493)
			(xy 339.070749 -357.47261) (xy 339.120901 -357.490896) (xy 339.168015 -357.515995) (xy 339.211169 -357.547417)
			(xy 339.249523 -357.584547) (xy 339.266276 -357.60533) (xy 339.273898 -357.614121) (xy 339.294788 -357.624312)
			(xy 339.306408 -357.624888) (xy 339.386164 -357.624888) (xy 339.397799 -357.624376) (xy 339.418709 -357.614168)
			(xy 339.426296 -357.60533) (xy 339.444497 -357.582855) (xy 339.486514 -357.543118) (xy 339.534046 -357.510177)
			(xy 339.586006 -357.484787) (xy 339.641202 -357.467529) (xy 339.69837 -357.458799) (xy 339.727286 -357.458264)
			(xy 339.754536 -357.458791) (xy 339.80848 -357.466545) (xy 339.860773 -357.481897) (xy 339.910348 -357.504534)
			(xy 339.956197 -357.533997) (xy 339.997386 -357.569684) (xy 340.033078 -357.610869) (xy 340.062545 -357.656715)
			(xy 340.085188 -357.706288) (xy 340.100546 -357.758579) (xy 340.108306 -357.812522) (xy 340.108794 -357.839772)
			(xy 340.108313 -357.867142) (xy 340.100499 -357.92132) (xy 340.085013 -357.973823) (xy 340.062175 -358.02357)
			(xy 340.032454 -358.069538) (xy 340.030165 -358.072254) (xy 340.314959 -358.072254) (xy 340.314959 -358.017746)
			(xy 340.322717 -357.963791) (xy 340.338075 -357.911491) (xy 340.360721 -357.861908) (xy 340.390192 -357.816054)
			(xy 340.42589 -357.77486) (xy 340.467087 -357.739167) (xy 340.512945 -357.709701) (xy 340.56253 -357.687061)
			(xy 340.614833 -357.671708) (xy 340.668787 -357.663956) (xy 340.696042 -357.663496) (xy 340.723411 -357.663997)
			(xy 340.777589 -357.671807) (xy 340.830091 -357.687288) (xy 340.879839 -357.710121) (xy 340.925807 -357.739838)
			(xy 340.94674 -357.757476) (xy 340.946994 -357.75773) (xy 340.954076 -357.763324) (xy 340.970996 -357.769565)
			(xy 340.980014 -357.769922) (xy 341.04707 -357.769922) (xy 341.056085 -357.769546) (xy 341.073002 -357.763311)
			(xy 341.08009 -357.75773) (xy 341.08009 -357.757476) (xy 341.080344 -357.757476) (xy 341.101277 -357.739835)
			(xy 341.147245 -357.710111) (xy 341.196991 -357.687265) (xy 341.249493 -357.671769) (xy 341.303671 -357.66394)
			(xy 341.358413 -357.66394) (xy 341.412591 -357.671769) (xy 341.465093 -357.687265) (xy 341.514839 -357.710111)
			(xy 341.560807 -357.739835) (xy 341.58174 -357.757476) (xy 341.581994 -357.75773) (xy 341.589076 -357.763324)
			(xy 341.605996 -357.769565) (xy 341.615014 -357.769922) (xy 341.68207 -357.769922) (xy 341.691085 -357.769546)
			(xy 341.708002 -357.763311) (xy 341.71509 -357.75773) (xy 341.71509 -357.757476) (xy 341.715344 -357.757476)
			(xy 341.736277 -357.739835) (xy 341.782245 -357.710111) (xy 341.831991 -357.687265) (xy 341.884493 -357.671769)
			(xy 341.938671 -357.66394) (xy 341.993413 -357.66394) (xy 342.047591 -357.671769) (xy 342.100093 -357.687265)
			(xy 342.149839 -357.710111) (xy 342.195807 -357.739835) (xy 342.21674 -357.757476) (xy 342.216994 -357.75773)
			(xy 342.224076 -357.763324) (xy 342.240996 -357.769565) (xy 342.250014 -357.769922) (xy 342.31707 -357.769922)
			(xy 342.326085 -357.769546) (xy 342.343002 -357.763311) (xy 342.35009 -357.75773) (xy 342.35009 -357.757476)
			(xy 342.350344 -357.757476) (xy 342.371283 -357.739846) (xy 342.417254 -357.710134) (xy 342.467 -357.687296)
			(xy 342.519499 -357.671803) (xy 342.573673 -357.663972) (xy 342.601042 -357.663496) (xy 342.628292 -357.663977)
			(xy 342.682235 -357.671738) (xy 342.734526 -357.687097) (xy 342.784098 -357.709741) (xy 342.829944 -357.739209)
			(xy 342.871129 -357.7749) (xy 342.906817 -357.81609) (xy 342.936279 -357.861939) (xy 342.958918 -357.911514)
			(xy 342.974271 -357.963806) (xy 342.982026 -358.01775) (xy 342.982026 -358.07225) (xy 342.974271 -358.126194)
			(xy 342.958918 -358.178486) (xy 342.936279 -358.228061) (xy 342.906817 -358.27391) (xy 342.871129 -358.3151)
			(xy 342.829944 -358.350791) (xy 342.784098 -358.380259) (xy 342.734526 -358.402903) (xy 342.682235 -358.418262)
			(xy 342.628292 -358.426023) (xy 342.601042 -358.426512) (xy 342.573673 -358.426018) (xy 342.519495 -358.418207)
			(xy 342.466992 -358.402724) (xy 342.417245 -358.379888) (xy 342.371277 -358.35017) (xy 342.350344 -358.332532)
			(xy 342.35009 -358.332278) (xy 342.343012 -358.326679) (xy 342.326089 -358.32044) (xy 342.31707 -358.320086)
			(xy 342.250014 -358.320086) (xy 342.240998 -358.320453) (xy 342.224081 -358.326694) (xy 342.216994 -358.332278)
			(xy 342.21674 -358.332532) (xy 342.195807 -358.350173) (xy 342.149839 -358.379897) (xy 342.100093 -358.402743)
			(xy 342.047591 -358.418239) (xy 341.993413 -358.426068) (xy 341.938671 -358.426068) (xy 341.884493 -358.418239)
			(xy 341.831991 -358.402743) (xy 341.782245 -358.379897) (xy 341.736277 -358.350173) (xy 341.715344 -358.332532)
			(xy 341.71509 -358.332278) (xy 341.708012 -358.326679) (xy 341.691089 -358.32044) (xy 341.68207 -358.320086)
			(xy 341.615014 -358.320086) (xy 341.605998 -358.320453) (xy 341.589081 -358.326694) (xy 341.581994 -358.332278)
			(xy 341.581994 -358.332532) (xy 341.58174 -358.332532) (xy 341.560807 -358.350173) (xy 341.514839 -358.379897)
			(xy 341.465093 -358.402743) (xy 341.412591 -358.418239) (xy 341.358413 -358.426068) (xy 341.303671 -358.426068)
			(xy 341.249493 -358.418239) (xy 341.196991 -358.402743) (xy 341.147245 -358.379897) (xy 341.101277 -358.350173)
			(xy 341.080344 -358.332532) (xy 341.08009 -358.332278) (xy 341.073012 -358.326679) (xy 341.056089 -358.32044)
			(xy 341.04707 -358.320086) (xy 340.980014 -358.320086) (xy 340.970998 -358.320453) (xy 340.954081 -358.326694)
			(xy 340.946994 -358.332278) (xy 340.946994 -358.332532) (xy 340.94674 -358.332532) (xy 340.925808 -358.350171)
			(xy 340.879835 -358.379882) (xy 340.830087 -358.402717) (xy 340.777587 -358.418208) (xy 340.723411 -358.426037)
			(xy 340.696042 -358.426512) (xy 340.668787 -358.426044) (xy 340.614833 -358.418292) (xy 340.56253 -358.402939)
			(xy 340.512945 -358.380299) (xy 340.467087 -358.350833) (xy 340.42589 -358.31514) (xy 340.390192 -358.273946)
			(xy 340.360721 -358.228092) (xy 340.338075 -358.178509) (xy 340.322717 -358.126209) (xy 340.314959 -358.072254)
			(xy 340.030165 -358.072254) (xy 340.014814 -358.09047) (xy 340.01456 -358.090724) (xy 340.008952 -358.097796)
			(xy 340.002719 -358.114724) (xy 340.002368 -358.123744) (xy 340.002368 -358.1908) (xy 340.002732 -358.199816)
			(xy 340.008976 -358.216733) (xy 340.01456 -358.22382) (xy 340.014814 -358.22382) (xy 340.014814 -358.224074)
			(xy 340.032457 -358.245003) (xy 340.062167 -358.290977) (xy 340.085002 -358.340725) (xy 340.100493 -358.393227)
			(xy 340.10832 -358.447403) (xy 340.108794 -358.474772) (xy 340.1083 -358.502884) (xy 340.100057 -358.558499)
			(xy 340.083744 -358.612304) (xy 340.059716 -358.663133) (xy 340.02849 -358.709888) (xy 340.009988 -358.731058)
			(xy 340.004144 -358.738135) (xy 339.997362 -358.755174) (xy 339.99678 -358.764332) (xy 339.99551 -358.831388)
			(xy 339.995753 -358.840513) (xy 340.00186 -358.857699) (xy 340.007448 -358.864916) (xy 340.007702 -358.86517)
			(xy 340.024793 -358.885948) (xy 340.053555 -358.931414) (xy 340.075641 -358.980471) (xy 340.090613 -359.032146)
			(xy 340.098173 -359.085412) (xy 340.098634 -359.112312) (xy 340.098109 -359.141265) (xy 340.089351 -359.198505)
			(xy 340.072036 -359.253762) (xy 340.046565 -359.305765) (xy 340.013522 -359.353319) (xy 339.993986 -359.374694)
			(xy 339.987128 -359.38206) (xy 339.980016 -359.400348) (xy 339.981286 -359.491534) (xy 339.98916 -359.509822)
			(xy 339.996018 -359.51668) (xy 340.004582 -359.525305) (xy 340.020722 -359.543481) (xy 340.028276 -359.553002)
			(xy 340.035903 -359.561789) (xy 340.056789 -359.571983) (xy 340.068408 -359.57256) (xy 340.148418 -359.57256)
			(xy 340.159989 -359.572014) (xy 340.180761 -359.561803) (xy 340.188296 -359.553002) (xy 340.206705 -359.530327)
			(xy 340.249229 -359.490296) (xy 340.29736 -359.457215) (xy 340.323424 -359.444036) (xy 340.323678 -359.443782)
			(xy 340.332647 -359.438858) (xy 340.34602 -359.423399) (xy 340.349586 -359.41381) (xy 340.375494 -359.3338)
			(xy 340.373462 -359.313226) (xy 340.368382 -359.304082) (xy 340.353844 -359.27595) (xy 340.333234 -359.216076)
			(xy 340.322781 -359.153624) (xy 340.322154 -359.121964) (xy 340.322644 -359.094714) (xy 340.330405 -359.040768)
			(xy 340.345762 -358.988476) (xy 340.368405 -358.938901) (xy 340.397871 -358.893052) (xy 340.433562 -358.851864)
			(xy 340.474751 -358.816173) (xy 340.520599 -358.786706) (xy 340.570174 -358.764063) (xy 340.622466 -358.748705)
			(xy 340.676412 -358.740944) (xy 340.703662 -358.740456) (xy 340.731032 -358.740931) (xy 340.785211 -358.748744)
			(xy 340.837715 -358.764231) (xy 340.887462 -358.787071) (xy 340.933429 -358.816795) (xy 340.95436 -358.834436)
			(xy 340.954614 -358.83469) (xy 340.961693 -358.840287) (xy 340.978616 -358.846528) (xy 340.987634 -358.846882)
			(xy 341.05469 -358.846882) (xy 341.063707 -358.846524) (xy 341.080624 -358.840278) (xy 341.08771 -358.83469)
			(xy 341.08771 -358.834436) (xy 341.087964 -358.834436) (xy 341.108897 -358.816795) (xy 341.154865 -358.787071)
			(xy 341.204611 -358.764225) (xy 341.257113 -358.748729) (xy 341.311291 -358.7409) (xy 341.366033 -358.7409)
			(xy 341.420211 -358.748729) (xy 341.472713 -358.764225) (xy 341.522459 -358.787071) (xy 341.568427 -358.816795)
			(xy 341.58936 -358.834436) (xy 341.589614 -358.83469) (xy 341.596693 -358.840287) (xy 341.613616 -358.846528)
			(xy 341.622634 -358.846882) (xy 341.68969 -358.846882) (xy 341.698707 -358.846524) (xy 341.715624 -358.840278)
			(xy 341.72271 -358.83469) (xy 341.72271 -358.834436) (xy 341.722964 -358.834436) (xy 341.743897 -358.816795)
			(xy 341.789865 -358.787071) (xy 341.839611 -358.764225) (xy 341.892113 -358.748729) (xy 341.946291 -358.7409)
			(xy 342.001033 -358.7409) (xy 342.055211 -358.748729) (xy 342.107713 -358.764225) (xy 342.157459 -358.787071)
			(xy 342.203427 -358.816795) (xy 342.22436 -358.834436) (xy 342.224614 -358.83469) (xy 342.231693 -358.840287)
			(xy 342.248616 -358.846528) (xy 342.257634 -358.846882) (xy 342.32469 -358.846882) (xy 342.333707 -358.846524)
			(xy 342.350624 -358.840278) (xy 342.35771 -358.83469) (xy 342.35771 -358.834436) (xy 342.357964 -358.834436)
			(xy 342.378903 -358.816806) (xy 342.424874 -358.787091) (xy 342.474619 -358.764253) (xy 342.527118 -358.74876)
			(xy 342.581293 -358.740931) (xy 342.608662 -358.740456) (xy 342.635912 -358.740991) (xy 342.689859 -358.748741)
			(xy 342.742153 -358.764091) (xy 342.791731 -358.786726) (xy 342.837582 -358.816187) (xy 342.878774 -358.851873)
			(xy 342.914469 -358.893058) (xy 342.943938 -358.938904) (xy 342.966583 -358.988477) (xy 342.981943 -359.040769)
			(xy 342.989704 -359.094714) (xy 342.99017 -359.121964) (xy 342.989735 -359.147938) (xy 342.982694 -359.199406)
			(xy 342.968738 -359.249444) (xy 342.948123 -359.297126) (xy 342.935052 -359.319576) (xy 342.929718 -359.328212)
			(xy 342.92667 -359.348278) (xy 342.946736 -359.428034) (xy 342.949522 -359.437723) (xy 342.961444 -359.453963)
			(xy 342.96985 -359.45953) (xy 342.970104 -359.45953) (xy 342.990317 -359.47195) (xy 343.027799 -359.501031)
			(xy 343.061396 -359.534525) (xy 343.076276 -359.553002) (xy 343.083903 -359.561789) (xy 343.104789 -359.571983)
			(xy 343.116408 -359.57256) (xy 343.196164 -359.57256) (xy 343.207801 -359.572057) (xy 343.228711 -359.561844)
			(xy 343.236296 -359.553002) (xy 343.243109 -359.544383) (xy 343.257596 -359.527862) (xy 343.265252 -359.519982)
			(xy 343.265506 -359.519728) (xy 343.272057 -359.512325) (xy 343.279515 -359.494041) (xy 343.279984 -359.484168)
			(xy 343.279984 -359.413048) (xy 343.279533 -359.403169) (xy 343.272088 -359.384869) (xy 343.265506 -359.377488)
			(xy 343.265252 -359.377234) (xy 343.244854 -359.3557) (xy 343.210314 -359.307482) (xy 343.183653 -359.254498)
			(xy 343.165516 -359.198027) (xy 343.156339 -359.139428) (xy 343.155778 -359.109772) (xy 343.156209 -359.0824)
			(xy 343.164032 -359.028219) (xy 343.179528 -358.975715) (xy 343.202379 -358.925968) (xy 343.232112 -358.880004)
			(xy 343.249758 -358.859074) (xy 343.250012 -358.85882) (xy 343.255598 -358.851733) (xy 343.261845 -358.834816)
			(xy 343.262204 -358.8258) (xy 343.262204 -358.758744) (xy 343.261825 -358.749729) (xy 343.255593 -358.732812)
			(xy 343.250012 -358.725724) (xy 343.249758 -358.725724) (xy 343.249758 -358.72547) (xy 343.232089 -358.70456)
			(xy 343.202363 -358.658589) (xy 343.179517 -358.608839) (xy 343.164022 -358.556333) (xy 343.156195 -358.502151)
			(xy 343.156198 -358.447407) (xy 343.164031 -358.393225) (xy 343.179532 -358.340721) (xy 343.202383 -358.290974)
			(xy 343.232114 -358.245006) (xy 343.249758 -358.224074) (xy 343.250012 -358.22382) (xy 343.255598 -358.216733)
			(xy 343.261845 -358.199816) (xy 343.262204 -358.1908) (xy 343.262204 -358.123744) (xy 343.261825 -358.114729)
			(xy 343.255593 -358.097812) (xy 343.250012 -358.090724) (xy 343.249758 -358.090724) (xy 343.249758 -358.09047)
			(xy 343.232131 -358.069528) (xy 343.202419 -358.023557) (xy 343.179581 -357.973812) (xy 343.164087 -357.921314)
			(xy 343.156254 -357.86714) (xy 343.155778 -357.839772) (xy 343.156252 -357.812521) (xy 343.164012 -357.758573)
			(xy 343.17937 -357.706279) (xy 343.202013 -357.656703) (xy 343.231481 -357.610853) (xy 343.267174 -357.569664)
			(xy 343.308364 -357.533973) (xy 343.354215 -357.504506) (xy 343.403792 -357.481865) (xy 343.456087 -357.466509)
			(xy 343.510035 -357.458751) (xy 343.537286 -357.458264) (xy 343.566204 -357.458768) (xy 343.623377 -357.467497)
			(xy 343.678577 -357.484756) (xy 343.730539 -357.51015) (xy 343.778072 -357.543097) (xy 343.820087 -357.582842)
			(xy 343.838276 -357.60533) (xy 343.845898 -357.614121) (xy 343.866788 -357.624312) (xy 343.878408 -357.624888)
			(xy 343.958164 -357.624888) (xy 343.969799 -357.624376) (xy 343.990709 -357.614168) (xy 343.998296 -357.60533)
			(xy 344.015049 -357.584547) (xy 344.053403 -357.547417) (xy 344.096557 -357.515995) (xy 344.143671 -357.490896)
			(xy 344.193823 -357.47261) (xy 344.246034 -357.461493) (xy 344.299286 -357.457763) (xy 344.352538 -357.461493)
			(xy 344.404749 -357.47261) (xy 344.454901 -357.490896) (xy 344.502015 -357.515995) (xy 344.545169 -357.547417)
			(xy 344.583523 -357.584547) (xy 344.600276 -357.60533) (xy 344.607898 -357.614121) (xy 344.628788 -357.624312)
			(xy 344.640408 -357.624888) (xy 344.720164 -357.624888) (xy 344.731799 -357.624376) (xy 344.752709 -357.614168)
			(xy 344.760296 -357.60533) (xy 344.778497 -357.582855) (xy 344.820514 -357.543118) (xy 344.868046 -357.510177)
			(xy 344.920006 -357.484787) (xy 344.975202 -357.467529) (xy 345.03237 -357.458799) (xy 345.061286 -357.458264)
			(xy 345.088536 -357.458791) (xy 345.14248 -357.466545) (xy 345.194773 -357.481897) (xy 345.244348 -357.504534)
			(xy 345.290197 -357.533997) (xy 345.331386 -357.569684) (xy 345.367078 -357.610869) (xy 345.396545 -357.656715)
			(xy 345.419188 -357.706288) (xy 345.434546 -357.758579) (xy 345.442306 -357.812522) (xy 345.442794 -357.839772)
			(xy 345.442313 -357.867142) (xy 345.434499 -357.92132) (xy 345.419013 -357.973823) (xy 345.396175 -358.02357)
			(xy 345.366454 -358.069538) (xy 345.348814 -358.09047) (xy 345.34856 -358.090724) (xy 345.342952 -358.097796)
			(xy 345.336719 -358.114724) (xy 345.336368 -358.123744) (xy 345.336368 -358.1908) (xy 345.336732 -358.199816)
			(xy 345.342976 -358.216733) (xy 345.34856 -358.22382) (xy 345.348814 -358.22382) (xy 345.348814 -358.224074)
			(xy 345.366426 -358.24503) (xy 345.396148 -358.290995) (xy 345.418993 -358.340737) (xy 345.43449 -358.393235)
			(xy 345.44232 -358.44741) (xy 345.442323 -358.502148) (xy 345.434499 -358.556323) (xy 345.419008 -358.608823)
			(xy 345.396169 -358.658568) (xy 345.366451 -358.704536) (xy 345.348814 -358.72547) (xy 345.34856 -358.725724)
			(xy 345.342952 -358.732796) (xy 345.336719 -358.749724) (xy 345.336368 -358.758744) (xy 345.336368 -358.8258)
			(xy 345.336732 -358.834816) (xy 345.342976 -358.851733) (xy 345.34856 -358.85882) (xy 345.348814 -358.85882)
			(xy 345.348814 -358.859074) (xy 345.366457 -358.880003) (xy 345.396167 -358.925977) (xy 345.419002 -358.975725)
			(xy 345.434493 -359.028227) (xy 345.44232 -359.082403) (xy 345.442794 -359.109772) (xy 345.442239 -359.139428)
			(xy 345.433051 -359.198023) (xy 345.414908 -359.254492) (xy 345.388247 -359.307474) (xy 345.35371 -359.355693)
			(xy 345.33332 -359.377234) (xy 345.333066 -359.377488) (xy 345.326505 -359.384883) (xy 345.319054 -359.403173)
			(xy 345.318588 -359.413048) (xy 345.318588 -359.484168) (xy 345.319038 -359.494047) (xy 345.326485 -359.512347)
			(xy 345.333066 -359.519728) (xy 345.33332 -359.519982) (xy 345.353721 -359.541514) (xy 345.388262 -359.589732)
			(xy 345.414922 -359.642716) (xy 345.433059 -359.699188) (xy 345.442234 -359.757787) (xy 345.442794 -359.787444)
			(xy 345.442363 -359.814697) (xy 345.4346 -359.868647) (xy 345.419239 -359.920944) (xy 345.396592 -359.970522)
			(xy 345.367119 -360.016373) (xy 345.331422 -360.057563) (xy 345.290227 -360.093254) (xy 345.244371 -360.122719)
			(xy 345.19479 -360.145359) (xy 345.142491 -360.160713) (xy 345.088539 -360.168467) (xy 345.061286 -360.168952)
			(xy 345.03237 -360.16839) (xy 344.975201 -360.159673) (xy 344.920002 -360.142424) (xy 344.86804 -360.117041)
			(xy 344.820505 -360.084104) (xy 344.778487 -360.044369) (xy 344.760296 -360.021886) (xy 344.752683 -360.013085)
			(xy 344.731787 -360.002899) (xy 344.720164 -360.002328) (xy 344.640154 -360.002328) (xy 344.628589 -360.00292)
			(xy 344.607817 -360.013098) (xy 344.600276 -360.021886) (xy 344.588084 -360.036618) (xy 344.582312 -360.043912)
			(xy 344.575915 -360.061358) (xy 344.575638 -360.070654) (xy 344.576908 -360.147616) (xy 344.58402 -360.164888)
			(xy 344.59037 -360.171746) (xy 344.609152 -360.193) (xy 344.640937 -360.239972) (xy 344.66541 -360.291136)
			(xy 344.682032 -360.345362) (xy 344.690434 -360.401452) (xy 344.690954 -360.42981) (xy 344.690954 -360.430064)
			(xy 344.690388 -360.457312) (xy 344.682638 -360.511255) (xy 344.66729 -360.563545) (xy 344.644656 -360.613119)
			(xy 344.615198 -360.658967) (xy 344.579515 -360.700157) (xy 344.538333 -360.735849) (xy 344.492491 -360.765317)
			(xy 344.442922 -360.787961) (xy 344.390635 -360.803321) (xy 344.336694 -360.811083) (xy 344.309446 -360.811572)
			(xy 344.28053 -360.811031) (xy 344.223359 -360.802308) (xy 344.16816 -360.785056) (xy 344.116198 -360.759668)
			(xy 344.068664 -360.726728) (xy 344.026646 -360.68699) (xy 344.008456 -360.664506) (xy 344.000857 -360.65569)
			(xy 343.97995 -360.645511) (xy 343.968324 -360.644948) (xy 343.888568 -360.644948) (xy 343.876933 -360.645466)
			(xy 343.856023 -360.655668) (xy 343.848436 -360.664506) (xy 343.836244 -360.679492) (xy 343.830148 -360.686604)
			(xy 343.823544 -360.703876) (xy 343.82456 -360.780584) (xy 343.825098 -360.789722) (xy 343.831721 -360.806772)
			(xy 343.837514 -360.813858) (xy 343.837768 -360.814112) (xy 343.856251 -360.835263) (xy 343.887441 -360.881978)
			(xy 343.911455 -360.932756) (xy 343.927775 -360.986503) (xy 343.936051 -361.04206) (xy 343.936574 -361.070144)
			(xy 343.936163 -361.097398) (xy 343.9284 -361.15135) (xy 343.913037 -361.203648) (xy 343.890388 -361.253228)
			(xy 343.860914 -361.29908) (xy 343.825215 -361.34027) (xy 343.784017 -361.375961) (xy 343.738159 -361.405426)
			(xy 343.688575 -361.428064) (xy 343.636274 -361.443416) (xy 343.58232 -361.451169) (xy 343.555066 -361.451652)
			(xy 343.52615 -361.451104) (xy 343.468979 -361.442384) (xy 343.41378 -361.425133) (xy 343.361818 -361.399747)
			(xy 343.314284 -361.366807) (xy 343.272267 -361.32707) (xy 343.254076 -361.304586) (xy 343.246472 -361.295776)
			(xy 343.225569 -361.285594) (xy 343.213944 -361.285028) (xy 343.134188 -361.285028) (xy 343.122556 -361.285565)
			(xy 343.101646 -361.295754) (xy 343.094056 -361.304586) (xy 343.077303 -361.325369) (xy 343.038949 -361.362499)
			(xy 342.995795 -361.393921) (xy 342.948681 -361.41902) (xy 342.898529 -361.437306) (xy 342.846318 -361.448423)
			(xy 342.793066 -361.452153) (xy 342.739814 -361.448423) (xy 342.687603 -361.437306) (xy 342.637451 -361.41902)
			(xy 342.590337 -361.393921) (xy 342.547183 -361.362499) (xy 342.508829 -361.325369) (xy 342.492076 -361.304586)
			(xy 342.484472 -361.295776) (xy 342.463569 -361.285594) (xy 342.451944 -361.285028) (xy 342.372188 -361.285028)
			(xy 342.360556 -361.285565) (xy 342.339646 -361.295754) (xy 342.332056 -361.304586) (xy 342.315303 -361.325369)
			(xy 342.276949 -361.362499) (xy 342.233795 -361.393921) (xy 342.186681 -361.41902) (xy 342.136529 -361.437306)
			(xy 342.084318 -361.448423) (xy 342.031066 -361.452153) (xy 341.977814 -361.448423) (xy 341.925603 -361.437306)
			(xy 341.875451 -361.41902) (xy 341.828337 -361.393921) (xy 341.785183 -361.362499) (xy 341.746829 -361.325369)
			(xy 341.730076 -361.304586) (xy 341.722472 -361.295776) (xy 341.701569 -361.285594) (xy 341.689944 -361.285028)
			(xy 341.610188 -361.285028) (xy 341.598556 -361.285565) (xy 341.577646 -361.295754) (xy 341.570056 -361.304586)
			(xy 341.553303 -361.325369) (xy 341.514949 -361.362499) (xy 341.471795 -361.393921) (xy 341.424681 -361.41902)
			(xy 341.374529 -361.437306) (xy 341.322318 -361.448423) (xy 341.269066 -361.452153) (xy 341.215814 -361.448423)
			(xy 341.163603 -361.437306) (xy 341.113451 -361.41902) (xy 341.066337 -361.393921) (xy 341.023183 -361.362499)
			(xy 340.984829 -361.325369) (xy 340.968076 -361.304586) (xy 340.960472 -361.295776) (xy 340.939569 -361.285594)
			(xy 340.927944 -361.285028) (xy 340.848188 -361.285028) (xy 340.836556 -361.285565) (xy 340.815646 -361.295754)
			(xy 340.808056 -361.304586) (xy 340.791303 -361.325369) (xy 340.752949 -361.362499) (xy 340.709795 -361.393921)
			(xy 340.662681 -361.41902) (xy 340.612529 -361.437306) (xy 340.560318 -361.448423) (xy 340.507066 -361.452153)
			(xy 340.453814 -361.448423) (xy 340.401603 -361.437306) (xy 340.351451 -361.41902) (xy 340.304337 -361.393921)
			(xy 340.261183 -361.362499) (xy 340.222829 -361.325369) (xy 340.206076 -361.304586) (xy 340.198472 -361.295776)
			(xy 340.177569 -361.285594) (xy 340.165944 -361.285028) (xy 340.086188 -361.285028) (xy 340.074556 -361.285565)
			(xy 340.053646 -361.295754) (xy 340.046056 -361.304586) (xy 340.029303 -361.325369) (xy 339.990949 -361.362499)
			(xy 339.947795 -361.393921) (xy 339.900681 -361.41902) (xy 339.850529 -361.437306) (xy 339.798318 -361.448423)
			(xy 339.745066 -361.452153) (xy 339.691814 -361.448423) (xy 339.639603 -361.437306) (xy 339.589451 -361.41902)
			(xy 339.542337 -361.393921) (xy 339.499183 -361.362499) (xy 339.460829 -361.325369) (xy 339.444076 -361.304586)
			(xy 339.436472 -361.295776) (xy 339.415569 -361.285594) (xy 339.403944 -361.285028) (xy 339.324188 -361.285028)
			(xy 339.312556 -361.285565) (xy 339.291646 -361.295754) (xy 339.284056 -361.304586) (xy 339.267303 -361.325369)
			(xy 339.228949 -361.362499) (xy 339.185795 -361.393921) (xy 339.138681 -361.41902) (xy 339.088529 -361.437306)
			(xy 339.036318 -361.448423) (xy 338.983066 -361.452153) (xy 338.929814 -361.448423) (xy 338.877603 -361.437306)
			(xy 338.827451 -361.41902) (xy 338.780337 -361.393921) (xy 338.737183 -361.362499) (xy 338.698829 -361.325369)
			(xy 338.682076 -361.304586) (xy 338.674472 -361.295776) (xy 338.653569 -361.285594) (xy 338.641944 -361.285028)
			(xy 338.562188 -361.285028) (xy 338.550556 -361.285565) (xy 338.529646 -361.295754) (xy 338.522056 -361.304586)
			(xy 338.503886 -361.327088) (xy 338.461863 -361.366822) (xy 338.414323 -361.39976) (xy 338.362358 -361.425145)
			(xy 338.307156 -361.442397) (xy 338.249983 -361.45112) (xy 338.221066 -361.451652) (xy 338.192139 -361.451095)
			(xy 338.134949 -361.442348) (xy 338.079737 -361.425061) (xy 338.027772 -361.399629) (xy 337.980246 -361.366638)
			(xy 337.93825 -361.326844) (xy 337.920076 -361.304332) (xy 337.912964 -361.295188) (xy 337.89239 -361.285028)
			(xy 337.78952 -361.283758) (xy 337.768692 -361.29341) (xy 337.761326 -361.3023) (xy 337.743109 -361.323664)
			(xy 337.701484 -361.361338) (xy 337.654786 -361.392503) (xy 337.604023 -361.416485) (xy 337.550294 -361.432766)
			(xy 337.494757 -361.440995) (xy 337.466686 -361.441492) (xy 337.437771 -361.440915) (xy 337.380603 -361.432199)
			(xy 337.325405 -361.414953) (xy 337.273443 -361.389572) (xy 337.225907 -361.356639) (xy 337.183888 -361.316907)
			(xy 337.165696 -361.294426) (xy 337.158093 -361.285615) (xy 337.137189 -361.275436) (xy 337.125564 -361.274868)
			(xy 337.045808 -361.274868) (xy 337.034175 -361.275402) (xy 337.013264 -361.285592) (xy 337.005676 -361.294426)
			(xy 336.988923 -361.315209) (xy 336.950569 -361.352339) (xy 336.907415 -361.383761) (xy 336.860301 -361.40886)
			(xy 336.810149 -361.427146) (xy 336.757938 -361.438263) (xy 336.704686 -361.441993) (xy 336.651434 -361.438263)
			(xy 336.599223 -361.427146) (xy 336.549071 -361.40886) (xy 336.501957 -361.383761) (xy 336.458803 -361.352339)
			(xy 336.420449 -361.315209) (xy 336.403696 -361.294426) (xy 336.396093 -361.285615) (xy 336.375189 -361.275436)
			(xy 336.363564 -361.274868) (xy 336.283808 -361.274868) (xy 336.272175 -361.275402) (xy 336.251264 -361.285592)
			(xy 336.243676 -361.294426) (xy 336.225505 -361.316926) (xy 336.18348 -361.356659) (xy 336.135941 -361.389596)
			(xy 336.083976 -361.414981) (xy 336.028775 -361.432234) (xy 335.971603 -361.440959) (xy 335.942686 -361.441492)
			(xy 335.915432 -361.441058) (xy 335.861479 -361.433299) (xy 335.80918 -361.41794) (xy 335.759598 -361.395295)
			(xy 335.713745 -361.365824) (xy 335.672552 -361.330127) (xy 335.636858 -361.288931) (xy 335.607391 -361.243075)
			(xy 335.584749 -361.193492) (xy 335.569395 -361.141191) (xy 335.56164 -361.087238) (xy 335.561178 -361.059984)
			(xy 335.561178 -361.05973) (xy 335.561644 -361.03256) (xy 335.569349 -360.978769) (xy 335.584623 -360.92662)
			(xy 335.607154 -360.877171) (xy 335.636485 -360.831427) (xy 335.653888 -360.810556) (xy 335.659984 -360.803444)
			(xy 335.666588 -360.786172) (xy 335.665572 -360.709464) (xy 335.665074 -360.700321) (xy 335.658425 -360.683271)
			(xy 335.652618 -360.67619) (xy 335.652364 -360.675936) (xy 335.633861 -360.654801) (xy 335.602673 -360.608082)
			(xy 335.578663 -360.5573) (xy 335.562347 -360.50355) (xy 335.554077 -360.44799) (xy 335.553558 -360.419904)
			(xy 335.554016 -360.392735) (xy 335.561743 -360.338949) (xy 335.577025 -360.286804) (xy 335.599554 -360.237356)
			(xy 335.628874 -360.191607) (xy 335.646268 -360.17073) (xy 335.652069 -360.163456) (xy 335.658447 -360.145995)
			(xy 335.658714 -360.136694) (xy 335.657444 -360.059732) (xy 335.650332 -360.04246) (xy 335.643982 -360.035602)
			(xy 335.625167 -360.014376) (xy 335.593389 -359.967395) (xy 335.568923 -359.916224) (xy 335.552309 -359.861992)
			(xy 335.543914 -359.805898) (xy 335.543398 -359.777538) (xy 335.543398 -359.777284) (xy 335.543939 -359.748332)
			(xy 335.552696 -359.691093) (xy 335.570008 -359.635837) (xy 335.595475 -359.583834) (xy 335.628512 -359.536279)
			(xy 335.648046 -359.514902) (xy 335.654904 -359.507536) (xy 335.662016 -359.489248) (xy 335.660746 -359.398062)
			(xy 335.652872 -359.379774) (xy 335.646014 -359.372916) (xy 335.625019 -359.351305) (xy 335.589452 -359.302673)
			(xy 335.561974 -359.249053) (xy 335.54327 -359.191779) (xy 335.533803 -359.132277) (xy 335.533238 -359.102152)
			(xy 328.882378 -359.102152) (xy 330.57338 -360.79303) (xy 330.576034 -360.79553) (xy 330.581892 -360.799869)
			(xy 330.585064 -360.801666) (xy 330.610558 -360.816098) (xy 330.657168 -360.851584) (xy 330.697811 -360.893774)
			(xy 330.731532 -360.941676) (xy 330.757541 -360.994167) (xy 330.775227 -361.050015) (xy 330.784175 -361.107909)
			(xy 330.784708 -361.1372) (xy 330.784222 -361.164451) (xy 330.776466 -361.218399) (xy 330.761111 -361.270694)
			(xy 330.738469 -361.320271) (xy 330.709003 -361.366121) (xy 330.673312 -361.407312) (xy 330.632121 -361.443003)
			(xy 330.586271 -361.472469) (xy 330.536694 -361.495111) (xy 330.484399 -361.510466) (xy 330.430451 -361.518222)
			(xy 330.4032 -361.518708) (xy 330.376456 -361.518236) (xy 330.323494 -361.510746) (xy 330.272099 -361.495929)
			(xy 330.22328 -361.474073) (xy 330.177993 -361.44561) (xy 330.13713 -361.411096) (xy 330.118974 -361.391454)
			(xy 330.118974 -361.3912) (xy 330.111411 -361.383749) (xy 330.091986 -361.375229) (xy 330.081382 -361.37469)
			(xy 330.081128 -361.37469) (xy 330.07111 -361.375142) (xy 330.052595 -361.382801) (xy 330.038423 -361.396964)
			(xy 330.03075 -361.415472) (xy 330.030328 -361.42549) (xy 330.030328 -361.448096) (xy 330.030748 -361.458166)
			(xy 330.038472 -361.476764) (xy 330.045314 -361.484164) (xy 330.85786 -362.296964) (xy 330.864464 -362.300266)
			(xy 330.889958 -362.314698) (xy 330.936568 -362.350184) (xy 330.977211 -362.392374) (xy 331.010932 -362.440276)
			(xy 331.036941 -362.492767) (xy 331.054627 -362.548615) (xy 331.063575 -362.606509) (xy 331.064108 -362.6358)
			(xy 331.063622 -362.663051) (xy 331.055866 -362.716999) (xy 331.040511 -362.769294) (xy 331.017869 -362.818871)
			(xy 330.988403 -362.864721) (xy 330.952712 -362.905912) (xy 330.911521 -362.941603) (xy 330.865671 -362.971069)
			(xy 330.816094 -362.993711) (xy 330.763799 -363.009066) (xy 330.709851 -363.016822) (xy 330.6826 -363.017308)
			(xy 330.653308 -363.016813) (xy 330.595411 -363.007862) (xy 330.539561 -362.990172) (xy 330.48707 -362.964156)
			(xy 330.43917 -362.930427) (xy 330.396985 -362.889775) (xy 330.361505 -362.843156) (xy 330.347066 -362.817664)
			(xy 330.345294 -362.814475) (xy 330.340959 -362.808609) (xy 330.33843 -362.80598) (xy 329.409552 -361.876848)
			(xy 329.3897 -361.856286) (xy 329.356072 -361.810072) (xy 329.33009 -361.759166) (xy 329.312394 -361.704821)
			(xy 329.303419 -361.648376) (xy 329.302872 -361.6198) (xy 329.302872 -361.61091) (xy 329.302192 -361.599692)
			(xy 329.292599 -361.579402) (xy 329.28433 -361.571794) (xy 329.215242 -361.514898) (xy 329.19289 -361.50931)
			(xy 329.181714 -361.511596) (xy 329.163419 -361.514941) (xy 329.126397 -361.518507) (xy 329.1078 -361.518708)
			(xy 329.078508 -361.518213) (xy 329.020611 -361.509262) (xy 328.964761 -361.491572) (xy 328.91227 -361.465556)
			(xy 328.86437 -361.431827) (xy 328.822185 -361.391175) (xy 328.786705 -361.344556) (xy 328.772266 -361.319064)
			(xy 328.768964 -361.31246) (xy 326.330564 -358.874314) (xy 326.323169 -358.867468) (xy 326.304566 -358.859751)
			(xy 326.294496 -358.859328) (xy 318.765682 -358.859328) (xy 318.754753 -358.859831) (xy 318.734878 -358.868933)
			(xy 318.727328 -358.876854) (xy 318.66967 -358.943402) (xy 318.663574 -358.96423) (xy 318.665098 -358.975152)
			(xy 318.666871 -358.98848) (xy 318.668779 -359.015301) (xy 318.668908 -359.028746) (xy 318.668908 -359.029)
			(xy 318.668422 -359.056251) (xy 318.660666 -359.110199) (xy 318.645311 -359.162494) (xy 318.622669 -359.212071)
			(xy 318.593203 -359.257921) (xy 318.557512 -359.299112) (xy 318.516321 -359.334803) (xy 318.470471 -359.364269)
			(xy 318.420894 -359.386911) (xy 318.368599 -359.402266) (xy 318.314651 -359.410022) (xy 318.260149 -359.410022)
			(xy 318.206201 -359.402266) (xy 318.153906 -359.386911) (xy 318.104329 -359.364269) (xy 318.058479 -359.334803)
			(xy 318.017288 -359.299112) (xy 317.981597 -359.257921) (xy 317.952131 -359.212071) (xy 317.929489 -359.162494)
			(xy 317.914134 -359.110199) (xy 317.906378 -359.056251) (xy 317.905892 -359.029) (xy 317.905892 -359.028746)
			(xy 317.906013 -359.015301) (xy 317.907919 -358.988479) (xy 317.909702 -358.975152) (xy 317.911226 -358.96423)
			(xy 317.90513 -358.943402) (xy 317.847472 -358.876854) (xy 317.839908 -358.868952) (xy 317.820042 -358.859857)
			(xy 317.809118 -358.859328) (xy 312.799222 -358.859328) (xy 312.77065 -358.85874) (xy 312.714217 -358.84975)
			(xy 312.659882 -358.83205) (xy 312.608981 -358.806075) (xy 312.562766 -358.772464) (xy 312.542174 -358.752648)
			(xy 312.332624 -358.543098) (xy 312.32521 -358.536276) (xy 312.306621 -358.528546) (xy 312.296556 -358.528112)
			(xy 305.98999 -358.528112) (xy 305.978142 -358.528721) (xy 305.956951 -358.539323) (xy 305.94935 -358.548432)
			(xy 305.893216 -358.622854) (xy 305.889152 -358.646222) (xy 305.892454 -358.657906) (xy 305.899324 -358.683521)
			(xy 305.906715 -358.736037) (xy 305.907186 -358.762554) (xy 305.907186 -358.763316) (xy 305.9067 -358.790567)
			(xy 305.898944 -358.844515) (xy 305.883589 -358.89681) (xy 305.860947 -358.946387) (xy 305.831481 -358.992237)
			(xy 305.79579 -359.033428) (xy 305.754599 -359.069119) (xy 305.708749 -359.098585) (xy 305.659172 -359.121227)
			(xy 305.606877 -359.136582) (xy 305.552929 -359.144338) (xy 305.498427 -359.144338) (xy 305.444479 -359.136582)
			(xy 305.392184 -359.121227) (xy 305.342607 -359.098585) (xy 305.296757 -359.069119) (xy 305.255566 -359.033428)
			(xy 305.219875 -358.992237) (xy 305.190409 -358.946387) (xy 305.167767 -358.89681) (xy 305.152412 -358.844515)
			(xy 305.144656 -358.790567) (xy 305.14417 -358.763316) (xy 305.14417 -358.762554) (xy 305.144655 -358.736039)
			(xy 305.152049 -358.683525) (xy 305.158902 -358.657906) (xy 305.162204 -358.646222) (xy 305.15814 -358.622854)
			(xy 305.102006 -358.548432) (xy 305.094416 -358.539313) (xy 305.073215 -358.528724) (xy 305.061366 -358.528112)
			(xy 303.28235 -358.528112) (xy 303.256859 -358.527675) (xy 303.20638 -358.520531) (xy 303.181766 -358.513888)
			(xy 303.17821 -358.513126) (xy 303.1501 -358.506627) (xy 303.096145 -358.486194) (xy 303.04588 -358.457872)
			(xy 303.000451 -358.422306) (xy 302.960893 -358.380308) (xy 302.928108 -358.332834) (xy 302.902842 -358.280965)
			(xy 302.885671 -358.225885) (xy 302.876987 -358.168847) (xy 302.876458 -358.14) (xy 300.531276 -358.14)
			(xy 300.531276 -359.283) (xy 302.893982 -359.283) (xy 302.898053 -359.227378) (xy 302.910179 -359.172941)
			(xy 302.930102 -359.12085) (xy 302.957398 -359.072215) (xy 302.991484 -359.028072) (xy 303.031633 -358.989363)
			(xy 303.076991 -358.956912) (xy 303.126591 -358.931411) (xy 303.179375 -358.913404) (xy 303.234218 -358.903274)
			(xy 303.289952 -358.901237) (xy 303.345389 -358.907337) (xy 303.399346 -358.921443) (xy 303.450675 -358.943255)
			(xy 303.498281 -358.972309) (xy 303.541149 -359.007984) (xy 303.578366 -359.049521) (xy 303.609139 -359.096034)
			(xy 303.632811 -359.146531) (xy 303.648879 -359.199938) (xy 303.656999 -359.255114) (xy 303.657508 -359.283)
			(xy 303.656999 -359.310886) (xy 303.648879 -359.366062) (xy 303.632811 -359.419469) (xy 303.609139 -359.469966)
			(xy 303.578366 -359.516479) (xy 303.541149 -359.558016) (xy 303.498281 -359.593691) (xy 303.450675 -359.622745)
			(xy 303.399346 -359.644557) (xy 303.345389 -359.658663) (xy 303.289952 -359.664763) (xy 303.234218 -359.662726)
			(xy 303.179375 -359.652596) (xy 303.126591 -359.634589) (xy 303.076991 -359.609088) (xy 303.031633 -359.576637)
			(xy 302.991484 -359.537928) (xy 302.957398 -359.493785) (xy 302.930102 -359.44515) (xy 302.910179 -359.393059)
			(xy 302.898053 -359.338622) (xy 302.893982 -359.283) (xy 300.531276 -359.283) (xy 300.531276 -359.377234)
			(xy 300.530875 -359.387306) (xy 300.523138 -359.405904) (xy 300.51629 -359.413302) (xy 299.917866 -360.011726)
			(xy 299.910475 -360.018577) (xy 299.891869 -360.02629) (xy 299.881798 -360.026712) (xy 276.96033 -360.026712)
			(xy 276.950259 -360.026294) (xy 276.93166 -360.018571) (xy 276.924262 -360.011726) (xy 276.46249 -359.550208)
			(xy 276.45566 -359.5428) (xy 276.447935 -359.524207) (xy 276.447504 -359.51414) (xy 276.447504 -350.085152)
			(xy 276.447077 -350.075082) (xy 276.43936 -350.056483) (xy 276.432518 -350.049084) (xy 275.573998 -349.19031)
			(xy 275.56717 -349.182901) (xy 275.559443 -349.164309) (xy 275.559012 -349.154242) (xy 275.559012 -349.106744)
			(xy 275.551392 -349.088456) (xy 262.917178 -349.088456) (xy 262.917178 -349.602806) (xy 272.31543 -349.602806)
			(xy 272.319501 -349.547184) (xy 272.331627 -349.492747) (xy 272.35155 -349.440656) (xy 272.378846 -349.392021)
			(xy 272.412932 -349.347878) (xy 272.453081 -349.309169) (xy 272.498439 -349.276718) (xy 272.548039 -349.251217)
			(xy 272.600823 -349.23321) (xy 272.655666 -349.22308) (xy 272.7114 -349.221043) (xy 272.766837 -349.227143)
			(xy 272.820794 -349.241249) (xy 272.872123 -349.263061) (xy 272.919729 -349.292115) (xy 272.962597 -349.32779)
			(xy 272.999814 -349.369327) (xy 273.030587 -349.41584) (xy 273.054259 -349.466337) (xy 273.070327 -349.519744)
			(xy 273.078447 -349.57492) (xy 273.078956 -349.602806) (xy 273.078447 -349.630692) (xy 273.070327 -349.685868)
			(xy 273.054259 -349.739275) (xy 273.030587 -349.789772) (xy 272.999814 -349.836285) (xy 272.962597 -349.877822)
			(xy 272.919729 -349.913497) (xy 272.872123 -349.942551) (xy 272.820794 -349.964363) (xy 272.766837 -349.978469)
			(xy 272.7114 -349.984569) (xy 272.655666 -349.982532) (xy 272.600823 -349.972402) (xy 272.548039 -349.954395)
			(xy 272.498439 -349.928894) (xy 272.453081 -349.896443) (xy 272.412932 -349.857734) (xy 272.378846 -349.813591)
			(xy 272.35155 -349.764956) (xy 272.331627 -349.712865) (xy 272.319501 -349.658428) (xy 272.31543 -349.602806)
			(xy 262.917178 -349.602806) (xy 262.917178 -350.32061) (xy 262.917602 -350.33068) (xy 262.925317 -350.349284)
			(xy 262.932164 -350.356678) (xy 263.073642 -350.498156) (xy 271.73631 -350.498156) (xy 271.740381 -350.442534)
			(xy 271.752507 -350.388097) (xy 271.77243 -350.336006) (xy 271.799726 -350.287371) (xy 271.833812 -350.243228)
			(xy 271.873961 -350.204519) (xy 271.919319 -350.172068) (xy 271.968919 -350.146567) (xy 272.021703 -350.12856)
			(xy 272.076546 -350.11843) (xy 272.13228 -350.116393) (xy 272.187717 -350.122493) (xy 272.241674 -350.136599)
			(xy 272.293003 -350.158411) (xy 272.340609 -350.187465) (xy 272.383477 -350.22314) (xy 272.420694 -350.264677)
			(xy 272.451467 -350.31119) (xy 272.475139 -350.361687) (xy 272.491207 -350.415094) (xy 272.499327 -350.47027)
			(xy 272.499836 -350.498156) (xy 272.499327 -350.526042) (xy 272.491207 -350.581218) (xy 272.475139 -350.634625)
			(xy 272.451467 -350.685122) (xy 272.420694 -350.731635) (xy 272.383477 -350.773172) (xy 272.340609 -350.808847)
			(xy 272.293003 -350.837901) (xy 272.241674 -350.859713) (xy 272.187717 -350.873819) (xy 272.13228 -350.879919)
			(xy 272.076546 -350.877882) (xy 272.021703 -350.867752) (xy 271.968919 -350.849745) (xy 271.919319 -350.824244)
			(xy 271.873961 -350.791793) (xy 271.833812 -350.753084) (xy 271.799726 -350.708941) (xy 271.77243 -350.660306)
			(xy 271.752507 -350.608215) (xy 271.740381 -350.553778) (xy 271.73631 -350.498156) (xy 263.073642 -350.498156)
			(xy 263.749282 -351.173796) (xy 273.075146 -351.173796) (xy 273.075619 -351.146321) (xy 273.083512 -351.09194)
			(xy 273.099135 -351.039257) (xy 273.122163 -350.989365) (xy 273.152118 -350.943297) (xy 273.169888 -350.922336)
			(xy 273.170142 -350.922082) (xy 273.175747 -350.915008) (xy 273.181982 -350.898082) (xy 273.182334 -350.889062)
			(xy 273.182334 -350.821498) (xy 273.18197 -350.812482) (xy 273.175726 -350.795565) (xy 273.170142 -350.788478)
			(xy 273.169634 -350.78797) (xy 273.151896 -350.767028) (xy 273.122013 -350.720994) (xy 273.099047 -350.671148)
			(xy 273.083474 -350.618522) (xy 273.075615 -350.564205) (xy 273.075146 -350.536764) (xy 273.075632 -350.509513)
			(xy 273.083388 -350.455565) (xy 273.098743 -350.40327) (xy 273.121385 -350.353693) (xy 273.150851 -350.307843)
			(xy 273.186542 -350.266652) (xy 273.227733 -350.230961) (xy 273.273583 -350.201495) (xy 273.32316 -350.178853)
			(xy 273.375455 -350.163498) (xy 273.429403 -350.155742) (xy 273.483905 -350.155742) (xy 273.537853 -350.163498)
			(xy 273.590148 -350.178853) (xy 273.639725 -350.201495) (xy 273.685575 -350.230961) (xy 273.726766 -350.266652)
			(xy 273.762457 -350.307843) (xy 273.791923 -350.353693) (xy 273.814565 -350.40327) (xy 273.82992 -350.455565)
			(xy 273.837676 -350.509513) (xy 273.838162 -350.536764) (xy 273.837664 -350.564238) (xy 273.829776 -350.618618)
			(xy 273.814159 -350.6713) (xy 273.811506 -350.67705) (xy 274.079972 -350.67705) (xy 274.079972 -350.62255)
			(xy 274.087728 -350.568604) (xy 274.103081 -350.516311) (xy 274.125721 -350.466735) (xy 274.155185 -350.420885)
			(xy 274.190874 -350.379695) (xy 274.232061 -350.344003) (xy 274.277908 -350.314535) (xy 274.327482 -350.291892)
			(xy 274.379774 -350.276534) (xy 274.43372 -350.268774) (xy 274.46097 -350.268286) (xy 274.461224 -350.268286)
			(xy 274.486428 -350.268669) (xy 274.536397 -350.275312) (xy 274.585052 -350.288494) (xy 274.631541 -350.307982)
			(xy 274.653502 -350.320356) (xy 274.663408 -350.326198) (xy 274.685252 -350.32823) (xy 274.779994 -350.294702)
			(xy 274.795742 -350.279208) (xy 274.799806 -350.268794) (xy 274.810477 -350.242007) (xy 274.838768 -350.191764)
			(xy 274.874301 -350.146354) (xy 274.916266 -350.106811) (xy 274.963707 -350.074039) (xy 275.015542 -350.048783)
			(xy 275.070589 -350.03162) (xy 275.127592 -350.022941) (xy 275.156422 -350.022414) (xy 275.183675 -350.022857)
			(xy 275.237625 -350.030617) (xy 275.289922 -350.045977) (xy 275.339501 -350.068622) (xy 275.385352 -350.098092)
			(xy 275.426543 -350.133788) (xy 275.462234 -350.174983) (xy 275.491699 -350.220838) (xy 275.514339 -350.270419)
			(xy 275.529692 -350.322718) (xy 275.537446 -350.376669) (xy 275.53793 -350.403922) (xy 275.53726 -350.435484)
			(xy 275.526876 -350.497749) (xy 275.506395 -350.557459) (xy 275.491956 -350.585532) (xy 275.48713 -350.594422)
			(xy 275.485098 -350.61398) (xy 275.507958 -350.692466) (xy 275.511198 -350.70189) (xy 275.523613 -350.717451)
			(xy 275.532088 -350.722692) (xy 275.557211 -350.737205) (xy 275.603094 -350.772714) (xy 275.643068 -350.814763)
			(xy 275.676212 -350.862383) (xy 275.701759 -350.914474) (xy 275.71912 -350.969834) (xy 275.727895 -351.027185)
			(xy 275.72843 -351.056194) (xy 275.727944 -351.083445) (xy 275.720188 -351.137393) (xy 275.704833 -351.189688)
			(xy 275.682191 -351.239265) (xy 275.652725 -351.285115) (xy 275.617034 -351.326306) (xy 275.575843 -351.361997)
			(xy 275.529993 -351.391463) (xy 275.480416 -351.414105) (xy 275.428121 -351.42946) (xy 275.374173 -351.437216)
			(xy 275.319671 -351.437216) (xy 275.265723 -351.42946) (xy 275.213428 -351.414105) (xy 275.163851 -351.391463)
			(xy 275.118001 -351.361997) (xy 275.07681 -351.326306) (xy 275.041119 -351.285115) (xy 275.011653 -351.239265)
			(xy 274.989011 -351.189688) (xy 274.973656 -351.137393) (xy 274.9659 -351.083445) (xy 274.965414 -351.056194)
			(xy 274.966085 -351.024632) (xy 274.976467 -350.962367) (xy 274.996949 -350.902657) (xy 275.011388 -350.874584)
			(xy 275.016214 -350.865694) (xy 275.018246 -350.846136) (xy 274.995386 -350.76765) (xy 274.992163 -350.75822)
			(xy 274.979734 -350.742664) (xy 274.971256 -350.737424) (xy 274.96389 -350.73336) (xy 274.953984 -350.727518)
			(xy 274.93214 -350.725486) (xy 274.837398 -350.759014) (xy 274.82165 -350.774508) (xy 274.817586 -350.784922)
			(xy 274.80693 -350.811715) (xy 274.778637 -350.861958) (xy 274.743101 -350.907368) (xy 274.701133 -350.94691)
			(xy 274.65369 -350.979681) (xy 274.601854 -351.004936) (xy 274.546805 -351.022098) (xy 274.489801 -351.030775)
			(xy 274.46097 -351.031302) (xy 274.43372 -351.030826) (xy 274.379774 -351.023066) (xy 274.327482 -351.007708)
			(xy 274.277908 -350.985065) (xy 274.232061 -350.955597) (xy 274.190874 -350.919905) (xy 274.155185 -350.878715)
			(xy 274.125721 -350.832865) (xy 274.103081 -350.783289) (xy 274.087728 -350.730996) (xy 274.079972 -350.67705)
			(xy 273.811506 -350.67705) (xy 273.791137 -350.721193) (xy 273.761187 -350.767262) (xy 273.74342 -350.788224)
			(xy 273.743166 -350.788478) (xy 273.737579 -350.795564) (xy 273.731334 -350.812481) (xy 273.730974 -350.821498)
			(xy 273.730974 -350.889062) (xy 273.731355 -350.898076) (xy 273.737586 -350.914993) (xy 273.743166 -350.922082)
			(xy 273.743674 -350.92259) (xy 273.761395 -350.943547) (xy 273.79128 -350.989576) (xy 273.814249 -351.039419)
			(xy 273.829827 -351.092042) (xy 273.83769 -351.146356) (xy 273.838162 -351.173796) (xy 273.837676 -351.201047)
			(xy 273.82992 -351.254995) (xy 273.814565 -351.30729) (xy 273.791923 -351.356867) (xy 273.762457 -351.402717)
			(xy 273.726766 -351.443908) (xy 273.685575 -351.479599) (xy 273.639725 -351.509065) (xy 273.590148 -351.531707)
			(xy 273.537853 -351.547062) (xy 273.483905 -351.554818) (xy 273.429403 -351.554818) (xy 273.375455 -351.547062)
			(xy 273.32316 -351.531707) (xy 273.273583 -351.509065) (xy 273.227733 -351.479599) (xy 273.186542 -351.443908)
			(xy 273.150851 -351.402717) (xy 273.121385 -351.356867) (xy 273.098743 -351.30729) (xy 273.083388 -351.254995)
			(xy 273.075632 -351.201047) (xy 273.075146 -351.173796) (xy 263.749282 -351.173796) (xy 266.63269 -354.057204)
			(xy 266.640088 -354.064052) (xy 266.658686 -354.071789) (xy 266.668758 -354.07219) (xy 273.499072 -354.07219)
			(xy 273.509137 -354.072626) (xy 273.527723 -354.080357) (xy 273.53514 -354.087176) (xy 275.505418 -356.057454)
			(xy 275.512265 -356.064851) (xy 275.519993 -356.083451) (xy 275.520404 -356.093522) (xy 275.520404 -360.02976)
			(xy 305.24145 -360.02976) (xy 305.245521 -359.974138) (xy 305.257647 -359.919701) (xy 305.27757 -359.86761)
			(xy 305.304866 -359.818975) (xy 305.338952 -359.774832) (xy 305.379101 -359.736123) (xy 305.424459 -359.703672)
			(xy 305.474059 -359.678171) (xy 305.526843 -359.660164) (xy 305.581686 -359.650034) (xy 305.63742 -359.647997)
			(xy 305.692857 -359.654097) (xy 305.746814 -359.668203) (xy 305.798143 -359.690015) (xy 305.845749 -359.719069)
			(xy 305.888617 -359.754744) (xy 305.925834 -359.796281) (xy 305.956607 -359.842794) (xy 305.980279 -359.893291)
			(xy 305.996347 -359.946698) (xy 306.004467 -360.001874) (xy 306.004976 -360.02976) (xy 306.004467 -360.057646)
			(xy 305.996347 -360.112822) (xy 305.980279 -360.166229) (xy 305.956607 -360.216726) (xy 305.925834 -360.263239)
			(xy 305.888617 -360.304776) (xy 305.845749 -360.340451) (xy 305.798143 -360.369505) (xy 305.746814 -360.391317)
			(xy 305.703533 -360.402632) (xy 313.480448 -360.402632) (xy 313.484519 -360.34701) (xy 313.496645 -360.292573)
			(xy 313.516568 -360.240482) (xy 313.543864 -360.191847) (xy 313.57795 -360.147704) (xy 313.618099 -360.108995)
			(xy 313.663457 -360.076544) (xy 313.713057 -360.051043) (xy 313.765841 -360.033036) (xy 313.820684 -360.022906)
			(xy 313.876418 -360.020869) (xy 313.931855 -360.026969) (xy 313.985812 -360.041075) (xy 314.037141 -360.062887)
			(xy 314.084747 -360.091941) (xy 314.127615 -360.127616) (xy 314.164832 -360.169153) (xy 314.195605 -360.215666)
			(xy 314.219277 -360.266163) (xy 314.226252 -360.289348) (xy 314.38545 -360.289348) (xy 314.389521 -360.233726)
			(xy 314.401647 -360.179289) (xy 314.42157 -360.127198) (xy 314.448866 -360.078563) (xy 314.482952 -360.03442)
			(xy 314.523101 -359.995711) (xy 314.568459 -359.96326) (xy 314.618059 -359.937759) (xy 314.670843 -359.919752)
			(xy 314.725686 -359.909622) (xy 314.78142 -359.907585) (xy 314.836857 -359.913685) (xy 314.853362 -359.918)
			(xy 319.046858 -359.918) (xy 319.050929 -359.862378) (xy 319.063055 -359.807941) (xy 319.082978 -359.75585)
			(xy 319.110274 -359.707215) (xy 319.14436 -359.663072) (xy 319.184509 -359.624363) (xy 319.229867 -359.591912)
			(xy 319.279467 -359.566411) (xy 319.332251 -359.548404) (xy 319.387094 -359.538274) (xy 319.442828 -359.536237)
			(xy 319.498265 -359.542337) (xy 319.552222 -359.556443) (xy 319.603551 -359.578255) (xy 319.651157 -359.607309)
			(xy 319.694025 -359.642984) (xy 319.731242 -359.684521) (xy 319.762015 -359.731034) (xy 319.785687 -359.781531)
			(xy 319.801755 -359.834938) (xy 319.809875 -359.890114) (xy 319.810384 -359.918) (xy 319.809875 -359.945886)
			(xy 319.801755 -360.001062) (xy 319.785687 -360.054469) (xy 319.762015 -360.104966) (xy 319.731242 -360.151479)
			(xy 319.694025 -360.193016) (xy 319.651157 -360.228691) (xy 319.603551 -360.257745) (xy 319.552222 -360.279557)
			(xy 319.498265 -360.293663) (xy 319.442828 -360.299763) (xy 319.387094 -360.297726) (xy 319.332251 -360.287596)
			(xy 319.279467 -360.269589) (xy 319.229867 -360.244088) (xy 319.184509 -360.211637) (xy 319.14436 -360.172928)
			(xy 319.110274 -360.128785) (xy 319.082978 -360.08015) (xy 319.063055 -360.028059) (xy 319.050929 -359.973622)
			(xy 319.046858 -359.918) (xy 314.853362 -359.918) (xy 314.890814 -359.927791) (xy 314.942143 -359.949603)
			(xy 314.989749 -359.978657) (xy 315.032617 -360.014332) (xy 315.069834 -360.055869) (xy 315.100607 -360.102382)
			(xy 315.124279 -360.152879) (xy 315.140347 -360.206286) (xy 315.148467 -360.261462) (xy 315.148976 -360.289348)
			(xy 315.148467 -360.317234) (xy 315.14188 -360.361992) (xy 322.46265 -360.361992) (xy 322.466721 -360.30637)
			(xy 322.478847 -360.251933) (xy 322.49877 -360.199842) (xy 322.526066 -360.151207) (xy 322.560152 -360.107064)
			(xy 322.600301 -360.068355) (xy 322.645659 -360.035904) (xy 322.695259 -360.010403) (xy 322.748043 -359.992396)
			(xy 322.802886 -359.982266) (xy 322.85862 -359.980229) (xy 322.914057 -359.986329) (xy 322.968014 -360.000435)
			(xy 323.019343 -360.022247) (xy 323.066949 -360.051301) (xy 323.109817 -360.086976) (xy 323.147034 -360.128513)
			(xy 323.177807 -360.175026) (xy 323.201479 -360.225523) (xy 323.217547 -360.27893) (xy 323.225667 -360.334106)
			(xy 323.226176 -360.361992) (xy 323.225667 -360.389878) (xy 323.217547 -360.445054) (xy 323.201479 -360.498461)
			(xy 323.177807 -360.548958) (xy 323.147034 -360.595471) (xy 323.109817 -360.637008) (xy 323.066949 -360.672683)
			(xy 323.019343 -360.701737) (xy 322.968014 -360.723549) (xy 322.914057 -360.737655) (xy 322.85862 -360.743755)
			(xy 322.802886 -360.741718) (xy 322.748043 -360.731588) (xy 322.695259 -360.713581) (xy 322.645659 -360.68808)
			(xy 322.600301 -360.655629) (xy 322.560152 -360.61692) (xy 322.526066 -360.572777) (xy 322.49877 -360.524142)
			(xy 322.478847 -360.472051) (xy 322.466721 -360.417614) (xy 322.46265 -360.361992) (xy 315.14188 -360.361992)
			(xy 315.140347 -360.37241) (xy 315.124279 -360.425817) (xy 315.100607 -360.476314) (xy 315.069834 -360.522827)
			(xy 315.032617 -360.564364) (xy 314.989749 -360.600039) (xy 314.942143 -360.629093) (xy 314.890814 -360.650905)
			(xy 314.836857 -360.665011) (xy 314.78142 -360.671111) (xy 314.725686 -360.669074) (xy 314.670843 -360.658944)
			(xy 314.618059 -360.640937) (xy 314.568459 -360.615436) (xy 314.523101 -360.582985) (xy 314.482952 -360.544276)
			(xy 314.448866 -360.500133) (xy 314.42157 -360.451498) (xy 314.401647 -360.399407) (xy 314.389521 -360.34497)
			(xy 314.38545 -360.289348) (xy 314.226252 -360.289348) (xy 314.235345 -360.31957) (xy 314.243465 -360.374746)
			(xy 314.243974 -360.402632) (xy 314.243465 -360.430518) (xy 314.235345 -360.485694) (xy 314.219277 -360.539101)
			(xy 314.195605 -360.589598) (xy 314.164832 -360.636111) (xy 314.127615 -360.677648) (xy 314.084747 -360.713323)
			(xy 314.037141 -360.742377) (xy 313.985812 -360.764189) (xy 313.931855 -360.778295) (xy 313.876418 -360.784395)
			(xy 313.820684 -360.782358) (xy 313.765841 -360.772228) (xy 313.713057 -360.754221) (xy 313.663457 -360.72872)
			(xy 313.618099 -360.696269) (xy 313.57795 -360.65756) (xy 313.543864 -360.613417) (xy 313.516568 -360.564782)
			(xy 313.496645 -360.512691) (xy 313.484519 -360.458254) (xy 313.480448 -360.402632) (xy 305.703533 -360.402632)
			(xy 305.692857 -360.405423) (xy 305.63742 -360.411523) (xy 305.581686 -360.409486) (xy 305.526843 -360.399356)
			(xy 305.474059 -360.381349) (xy 305.424459 -360.355848) (xy 305.379101 -360.323397) (xy 305.338952 -360.284688)
			(xy 305.304866 -360.240545) (xy 305.27757 -360.19191) (xy 305.257647 -360.139819) (xy 305.245521 -360.085382)
			(xy 305.24145 -360.02976) (xy 275.520404 -360.02976) (xy 275.520404 -361.565952) (xy 285.209742 -361.565952)
			(xy 285.21011 -361.538696) (xy 285.217875 -361.484739) (xy 285.23324 -361.432436) (xy 285.255892 -361.382852)
			(xy 285.285369 -361.336997) (xy 285.321073 -361.295803) (xy 285.362276 -361.26011) (xy 285.408138 -361.230645)
			(xy 285.457728 -361.208006) (xy 285.510035 -361.192654) (xy 285.563994 -361.184903) (xy 285.59125 -361.184444)
			(xy 285.61862 -361.184929) (xy 285.672798 -361.19274) (xy 285.725302 -361.208224) (xy 285.775049 -361.231062)
			(xy 285.821016 -361.260784) (xy 285.841948 -361.278424) (xy 285.842202 -361.278678) (xy 285.849277 -361.284281)
			(xy 285.866203 -361.290516) (xy 285.875222 -361.29087) (xy 285.942278 -361.29087) (xy 285.951295 -361.290509)
			(xy 285.968212 -361.284265) (xy 285.975298 -361.278678) (xy 285.975298 -361.278424) (xy 285.975552 -361.278424)
			(xy 285.996494 -361.260798) (xy 286.042464 -361.231083) (xy 286.092209 -361.208244) (xy 286.144707 -361.19275)
			(xy 286.198881 -361.184919) (xy 286.22625 -361.184444) (xy 286.252898 -361.184913) (xy 286.305674 -361.192349)
			(xy 286.356902 -361.207056) (xy 286.405586 -361.228747) (xy 286.450777 -361.257001) (xy 286.491599 -361.291268)
			(xy 286.527255 -361.330882) (xy 286.557053 -361.375071) (xy 286.56915 -361.39882) (xy 286.57423 -361.409234)
			(xy 286.592264 -361.423458) (xy 286.692594 -361.446064) (xy 286.714946 -361.440984) (xy 286.72409 -361.433618)
			(xy 286.744487 -361.417796) (xy 286.788733 -361.391204) (xy 286.836157 -361.370812) (xy 286.885894 -361.356991)
			(xy 286.937039 -361.349993) (xy 286.96285 -361.349544) (xy 286.99022 -361.350029) (xy 287.044398 -361.35784)
			(xy 287.096902 -361.373324) (xy 287.146649 -361.396162) (xy 287.192616 -361.425884) (xy 287.213548 -361.443524)
			(xy 287.213802 -361.443778) (xy 287.220877 -361.449381) (xy 287.237803 -361.455616) (xy 287.246822 -361.45597)
			(xy 287.313878 -361.45597) (xy 287.322895 -361.455609) (xy 287.339812 -361.449365) (xy 287.346898 -361.443778)
			(xy 287.346898 -361.443524) (xy 287.347152 -361.443524) (xy 287.368085 -361.425883) (xy 287.414053 -361.396159)
			(xy 287.463799 -361.373313) (xy 287.516301 -361.357817) (xy 287.570479 -361.349988) (xy 287.625221 -361.349988)
			(xy 287.679399 -361.357817) (xy 287.731901 -361.373313) (xy 287.781647 -361.396159) (xy 287.827615 -361.425883)
			(xy 287.848548 -361.443524) (xy 287.848802 -361.443778) (xy 287.855877 -361.449381) (xy 287.872803 -361.455616)
			(xy 287.881822 -361.45597) (xy 287.948878 -361.45597) (xy 287.957895 -361.455609) (xy 287.974812 -361.449365)
			(xy 287.981898 -361.443778) (xy 287.981898 -361.443524) (xy 287.982152 -361.443524) (xy 288.003085 -361.425883)
			(xy 288.049053 -361.396159) (xy 288.098799 -361.373313) (xy 288.151301 -361.357817) (xy 288.205479 -361.349988)
			(xy 288.260221 -361.349988) (xy 288.314399 -361.357817) (xy 288.366901 -361.373313) (xy 288.416647 -361.396159)
			(xy 288.462615 -361.425883) (xy 288.483548 -361.443524) (xy 288.483802 -361.443778) (xy 288.490877 -361.449381)
			(xy 288.507803 -361.455616) (xy 288.516822 -361.45597) (xy 288.583878 -361.45597) (xy 288.592895 -361.455609)
			(xy 288.609812 -361.449365) (xy 288.616898 -361.443778) (xy 288.616898 -361.443524) (xy 288.617152 -361.443524)
			(xy 288.638094 -361.425898) (xy 288.684064 -361.396183) (xy 288.733809 -361.373344) (xy 288.786307 -361.35785)
			(xy 288.840481 -361.350019) (xy 288.86785 -361.349544) (xy 288.893663 -361.35) (xy 288.944816 -361.356964)
			(xy 288.994561 -361.370771) (xy 289.041985 -361.391168) (xy 289.086222 -361.417781) (xy 289.10661 -361.433618)
			(xy 289.115754 -361.440984) (xy 289.138106 -361.446064) (xy 289.238436 -361.423458) (xy 289.25647 -361.409234)
			(xy 289.26155 -361.39882) (xy 289.273615 -361.375051) (xy 289.303402 -361.330844) (xy 289.339054 -361.291217)
			(xy 289.379878 -361.256941) (xy 289.425077 -361.228684) (xy 289.473771 -361.206996) (xy 289.525011 -361.192301)
			(xy 289.577797 -361.184885) (xy 289.60445 -361.184444) (xy 289.63182 -361.184929) (xy 289.685998 -361.19274)
			(xy 289.738502 -361.208224) (xy 289.788249 -361.231062) (xy 289.834216 -361.260784) (xy 289.855148 -361.278424)
			(xy 289.855402 -361.278678) (xy 289.862477 -361.284281) (xy 289.879403 -361.290516) (xy 289.888422 -361.29087)
			(xy 289.955478 -361.29087) (xy 289.964495 -361.290509) (xy 289.981412 -361.284265) (xy 289.988498 -361.278678)
			(xy 289.988498 -361.278424) (xy 289.988752 -361.278424) (xy 290.009694 -361.260798) (xy 290.055664 -361.231083)
			(xy 290.105409 -361.208244) (xy 290.157907 -361.19275) (xy 290.212081 -361.184919) (xy 290.23945 -361.184444)
			(xy 290.265295 -361.184875) (xy 290.316511 -361.19186) (xy 290.366315 -361.205696) (xy 290.413795 -361.226128)
			(xy 290.458082 -361.252783) (xy 290.498365 -361.285173) (xy 290.533907 -361.322705) (xy 290.54933 -361.343448)
			(xy 290.556442 -361.353354) (xy 290.57727 -361.364276) (xy 290.670742 -361.366562) (xy 290.682634 -361.366187)
			(xy 290.704096 -361.355993) (xy 290.71189 -361.347004) (xy 290.73011 -361.324759) (xy 290.772036 -361.285413)
			(xy 290.819395 -361.25281) (xy 290.871113 -361.227688) (xy 290.926017 -361.210617) (xy 290.982862 -361.201984)
			(xy 291.01161 -361.201462) (xy 291.03886 -361.201968) (xy 291.092806 -361.209725) (xy 291.145098 -361.22508)
			(xy 291.194673 -361.24772) (xy 291.240522 -361.277185) (xy 291.28086 -361.312136) (xy 295.410886 -361.312136)
			(xy 295.410886 -361.22744) (xy 295.418937 -361.143126) (xy 295.434966 -361.05996) (xy 295.458827 -360.978693)
			(xy 295.490306 -360.900063) (xy 295.529117 -360.824782) (xy 295.574907 -360.75353) (xy 295.627263 -360.686954)
			(xy 295.685711 -360.625656) (xy 295.749721 -360.570191) (xy 295.818713 -360.521062) (xy 295.892063 -360.478713)
			(xy 295.969106 -360.443529) (xy 296.049145 -360.415827) (xy 296.131454 -360.395859) (xy 296.215289 -360.383806)
			(xy 296.29989 -360.379776) (xy 296.384491 -360.383806) (xy 296.468326 -360.395859) (xy 296.550635 -360.415827)
			(xy 296.630674 -360.443529) (xy 296.707717 -360.478713) (xy 296.781067 -360.521062) (xy 296.850059 -360.570191)
			(xy 296.914069 -360.625656) (xy 296.917448 -360.6292) (xy 301.369982 -360.6292) (xy 301.374053 -360.573578)
			(xy 301.386179 -360.519141) (xy 301.406102 -360.46705) (xy 301.433398 -360.418415) (xy 301.467484 -360.374272)
			(xy 301.507633 -360.335563) (xy 301.552991 -360.303112) (xy 301.602591 -360.277611) (xy 301.655375 -360.259604)
			(xy 301.710218 -360.249474) (xy 301.765952 -360.247437) (xy 301.821389 -360.253537) (xy 301.875346 -360.267643)
			(xy 301.926675 -360.289455) (xy 301.974281 -360.318509) (xy 302.017149 -360.354184) (xy 302.054366 -360.395721)
			(xy 302.085139 -360.442234) (xy 302.108811 -360.492731) (xy 302.124879 -360.546138) (xy 302.132999 -360.601314)
			(xy 302.133508 -360.6292) (xy 302.132999 -360.657086) (xy 302.124879 -360.712262) (xy 302.108811 -360.765669)
			(xy 302.085139 -360.816166) (xy 302.054366 -360.862679) (xy 302.017149 -360.904216) (xy 301.974281 -360.939891)
			(xy 301.926675 -360.968945) (xy 301.875346 -360.990757) (xy 301.821389 -361.004863) (xy 301.765952 -361.010963)
			(xy 301.710218 -361.008926) (xy 301.655375 -360.998796) (xy 301.602591 -360.980789) (xy 301.552991 -360.955288)
			(xy 301.507633 -360.922837) (xy 301.467484 -360.884128) (xy 301.433398 -360.839985) (xy 301.406102 -360.79135)
			(xy 301.386179 -360.739259) (xy 301.374053 -360.684822) (xy 301.369982 -360.6292) (xy 296.917448 -360.6292)
			(xy 296.972517 -360.686954) (xy 297.024873 -360.75353) (xy 297.070663 -360.824782) (xy 297.109474 -360.900063)
			(xy 297.140953 -360.978693) (xy 297.164814 -361.05996) (xy 297.180843 -361.143126) (xy 297.188894 -361.22744)
			(xy 297.189398 -361.269788) (xy 297.188894 -361.312136) (xy 297.180843 -361.39645) (xy 297.176959 -361.4166)
			(xy 300.099982 -361.4166) (xy 300.104053 -361.360978) (xy 300.116179 -361.306541) (xy 300.136102 -361.25445)
			(xy 300.163398 -361.205815) (xy 300.197484 -361.161672) (xy 300.237633 -361.122963) (xy 300.282991 -361.090512)
			(xy 300.332591 -361.065011) (xy 300.385375 -361.047004) (xy 300.440218 -361.036874) (xy 300.495952 -361.034837)
			(xy 300.551389 -361.040937) (xy 300.605346 -361.055043) (xy 300.656675 -361.076855) (xy 300.704281 -361.105909)
			(xy 300.747149 -361.141584) (xy 300.784366 -361.183121) (xy 300.815139 -361.229634) (xy 300.838811 -361.280131)
			(xy 300.854879 -361.333538) (xy 300.862999 -361.388714) (xy 300.863508 -361.4166) (xy 300.862999 -361.444486)
			(xy 300.854879 -361.499662) (xy 300.838811 -361.553069) (xy 300.815139 -361.603566) (xy 300.784366 -361.650079)
			(xy 300.747149 -361.691616) (xy 300.704281 -361.727291) (xy 300.656675 -361.756345) (xy 300.605346 -361.778157)
			(xy 300.551389 -361.792263) (xy 300.495952 -361.798363) (xy 300.440218 -361.796326) (xy 300.385375 -361.786196)
			(xy 300.332591 -361.768189) (xy 300.282991 -361.742688) (xy 300.237633 -361.710237) (xy 300.197484 -361.671528)
			(xy 300.163398 -361.627385) (xy 300.136102 -361.57875) (xy 300.116179 -361.526659) (xy 300.104053 -361.472222)
			(xy 300.099982 -361.4166) (xy 297.176959 -361.4166) (xy 297.164814 -361.479616) (xy 297.140953 -361.560883)
			(xy 297.109474 -361.639513) (xy 297.070663 -361.714794) (xy 297.024873 -361.786046) (xy 296.972517 -361.852622)
			(xy 296.914069 -361.91392) (xy 296.850059 -361.969385) (xy 296.781067 -362.018514) (xy 296.707717 -362.060863)
			(xy 296.630674 -362.096047) (xy 296.550635 -362.123749) (xy 296.468326 -362.143717) (xy 296.384491 -362.15577)
			(xy 296.29989 -362.159801) (xy 296.215289 -362.15577) (xy 296.131454 -362.143717) (xy 296.049145 -362.123749)
			(xy 295.969106 -362.096047) (xy 295.892063 -362.060863) (xy 295.818713 -362.018514) (xy 295.749721 -361.969385)
			(xy 295.685711 -361.91392) (xy 295.627263 -361.852622) (xy 295.574907 -361.786046) (xy 295.529117 -361.714794)
			(xy 295.490306 -361.639513) (xy 295.458827 -361.560883) (xy 295.434966 -361.479616) (xy 295.418937 -361.39645)
			(xy 295.410886 -361.312136) (xy 291.28086 -361.312136) (xy 291.281712 -361.312874) (xy 291.317403 -361.354062)
			(xy 291.34687 -361.399909) (xy 291.369513 -361.449483) (xy 291.38487 -361.501775) (xy 291.39263 -361.55572)
			(xy 291.393118 -361.58297) (xy 291.3926 -361.612245) (xy 291.383625 -361.670104) (xy 291.365911 -361.725911)
			(xy 291.339876 -361.778355) (xy 291.306131 -361.826203) (xy 291.286184 -361.847638) (xy 291.28593 -361.847892)
			(xy 291.279472 -361.855393) (xy 291.27228 -361.873813) (xy 291.27196 -361.883706) (xy 291.27323 -361.955334)
			(xy 291.273846 -361.965192) (xy 291.281543 -361.98336) (xy 291.288216 -361.99064) (xy 291.28847 -361.990894)
			(xy 291.30629 -362.008912) (xy 291.33752 -362.048822) (xy 291.36319 -362.092515) (xy 291.38285 -362.139223)
			(xy 291.396152 -362.188122) (xy 291.402863 -362.238352) (xy 291.403278 -362.26369) (xy 291.402811 -362.29106)
			(xy 291.394995 -362.34524) (xy 291.379506 -362.397743) (xy 291.356664 -362.44749) (xy 291.326939 -362.493456)
			(xy 291.309298 -362.514388) (xy 291.309044 -362.514642) (xy 291.303469 -362.521736) (xy 291.297217 -362.538647)
			(xy 291.296852 -362.547662) (xy 291.296852 -362.614718) (xy 291.297189 -362.623737) (xy 291.303449 -362.640654)
			(xy 291.309044 -362.647738) (xy 291.309298 -362.647738) (xy 291.309298 -362.647992) (xy 291.326928 -362.668933)
			(xy 291.356651 -362.7149) (xy 291.379496 -362.764645) (xy 291.394992 -362.817146) (xy 291.39815 -362.839)
			(xy 300.582582 -362.839) (xy 300.586653 -362.783378) (xy 300.598779 -362.728941) (xy 300.618702 -362.67685)
			(xy 300.645998 -362.628215) (xy 300.680084 -362.584072) (xy 300.720233 -362.545363) (xy 300.765591 -362.512912)
			(xy 300.815191 -362.487411) (xy 300.867975 -362.469404) (xy 300.922818 -362.459274) (xy 300.978552 -362.457237)
			(xy 301.033989 -362.463337) (xy 301.087946 -362.477443) (xy 301.139275 -362.499255) (xy 301.186881 -362.528309)
			(xy 301.229749 -362.563984) (xy 301.266966 -362.605521) (xy 301.297739 -362.652034) (xy 301.321411 -362.702531)
			(xy 301.337479 -362.755938) (xy 301.345599 -362.811114) (xy 301.346108 -362.839) (xy 301.345599 -362.866886)
			(xy 301.337479 -362.922062) (xy 301.321411 -362.975469) (xy 301.297739 -363.025966) (xy 301.266966 -363.072479)
			(xy 301.229749 -363.114016) (xy 301.186881 -363.149691) (xy 301.139275 -363.178745) (xy 301.087946 -363.200557)
			(xy 301.033989 -363.214663) (xy 300.978552 -363.220763) (xy 300.922818 -363.218726) (xy 300.867975 -363.208596)
			(xy 300.815191 -363.190589) (xy 300.765591 -363.165088) (xy 300.720233 -363.132637) (xy 300.680084 -363.093928)
			(xy 300.645998 -363.049785) (xy 300.618702 -363.00115) (xy 300.598779 -362.949059) (xy 300.586653 -362.894622)
			(xy 300.582582 -362.839) (xy 291.39815 -362.839) (xy 291.402821 -362.871323) (xy 291.402822 -362.926062)
			(xy 291.394995 -362.98024) (xy 291.379501 -363.032741) (xy 291.356658 -363.082487) (xy 291.326937 -363.128455)
			(xy 291.309298 -363.149388) (xy 291.309044 -363.149642) (xy 291.303469 -363.156736) (xy 291.297217 -363.173647)
			(xy 291.296852 -363.182662) (xy 291.296852 -363.249718) (xy 291.297189 -363.258737) (xy 291.303449 -363.275654)
			(xy 291.309044 -363.282738) (xy 291.309298 -363.282738) (xy 291.309298 -363.282992) (xy 291.326928 -363.303933)
			(xy 291.356651 -363.3499) (xy 291.379496 -363.399645) (xy 291.394992 -363.452146) (xy 291.402821 -363.506323)
			(xy 291.402822 -363.561062) (xy 291.394995 -363.61524) (xy 291.379501 -363.667741) (xy 291.356658 -363.717487)
			(xy 291.326937 -363.763455) (xy 291.309298 -363.784388) (xy 291.309044 -363.784642) (xy 291.303469 -363.791736)
			(xy 291.297217 -363.808647) (xy 291.296852 -363.817662) (xy 291.296852 -363.884718) (xy 291.297189 -363.893737)
			(xy 291.303449 -363.910654) (xy 291.309044 -363.917738) (xy 291.309298 -363.917738) (xy 291.309298 -363.917992)
			(xy 291.326946 -363.938917) (xy 291.356657 -363.984891) (xy 291.379491 -364.034641) (xy 291.39498 -364.087143)
			(xy 291.402805 -364.14132) (xy 291.403278 -364.16869) (xy 291.402835 -364.195944) (xy 291.395079 -364.249897)
			(xy 291.379723 -364.302197) (xy 291.357079 -364.351779) (xy 291.327609 -364.397634) (xy 291.291913 -364.438828)
			(xy 291.250718 -364.474521) (xy 291.204862 -364.503989) (xy 291.155278 -364.52663) (xy 291.102978 -364.541983)
			(xy 291.049024 -364.549737) (xy 291.02177 -364.550198) (xy 290.995926 -364.549734) (xy 290.944713 -364.542753)
			(xy 290.89491 -364.528922) (xy 290.847431 -364.508494) (xy 290.803143 -364.481845) (xy 290.762859 -364.44946)
			(xy 290.727315 -364.411934) (xy 290.71189 -364.391194) (xy 290.704778 -364.381288) (xy 290.68395 -364.370366)
			(xy 290.590478 -364.36808) (xy 290.578585 -364.368452) (xy 290.557122 -364.378647) (xy 290.54933 -364.387638)
			(xy 290.531166 -364.40993) (xy 290.489227 -364.449271) (xy 290.441856 -364.481868) (xy 290.390127 -364.506981)
			(xy 290.335214 -364.524042) (xy 290.278361 -364.532664) (xy 290.24961 -364.53318) (xy 290.22224 -364.532713)
			(xy 290.168061 -364.524896) (xy 290.115557 -364.509408) (xy 290.06581 -364.486566) (xy 290.019844 -364.456841)
			(xy 289.998912 -364.4392) (xy 289.998658 -364.438946) (xy 289.991564 -364.433371) (xy 289.974653 -364.427119)
			(xy 289.965638 -364.426754) (xy 289.898582 -364.426754) (xy 289.889563 -364.427091) (xy 289.872646 -364.433351)
			(xy 289.865562 -364.438946) (xy 289.865562 -364.4392) (xy 289.865308 -364.4392) (xy 289.844384 -364.456849)
			(xy 289.798409 -364.486559) (xy 289.748659 -364.509393) (xy 289.696157 -364.524882) (xy 289.64198 -364.532707)
			(xy 289.61461 -364.53318) (xy 289.587035 -364.532714) (xy 289.532462 -364.524763) (xy 289.479602 -364.509038)
			(xy 289.429556 -364.485868) (xy 289.383366 -364.455735) (xy 289.341996 -364.419267) (xy 289.32378 -364.39856)
			(xy 289.316239 -364.390469) (xy 289.296217 -364.381125) (xy 289.285172 -364.380526) (xy 289.207448 -364.380526)
			(xy 289.196401 -364.381113) (xy 289.176379 -364.390464) (xy 289.16884 -364.39856) (xy 289.150602 -364.419247)
			(xy 289.10924 -364.455721) (xy 289.063056 -364.485857) (xy 289.013013 -364.509027) (xy 288.960155 -364.524748)
			(xy 288.905583 -364.532693) (xy 288.87801 -364.53318) (xy 288.85064 -364.532713) (xy 288.796461 -364.524896)
			(xy 288.743957 -364.509408) (xy 288.69421 -364.486566) (xy 288.648244 -364.456841) (xy 288.627312 -364.4392)
			(xy 288.627058 -364.438946) (xy 288.619964 -364.433371) (xy 288.603053 -364.427119) (xy 288.594038 -364.426754)
			(xy 288.526982 -364.426754) (xy 288.517963 -364.427091) (xy 288.501046 -364.433351) (xy 288.493962 -364.438946)
			(xy 288.493962 -364.4392) (xy 288.493708 -364.4392) (xy 288.472775 -364.456841) (xy 288.426807 -364.486565)
			(xy 288.377061 -364.509411) (xy 288.324559 -364.524907) (xy 288.270381 -364.532736) (xy 288.215639 -364.532736)
			(xy 288.161461 -364.524907) (xy 288.108959 -364.509411) (xy 288.059213 -364.486565) (xy 288.013245 -364.456841)
			(xy 287.992312 -364.4392) (xy 287.992058 -364.438946) (xy 287.984964 -364.433371) (xy 287.968053 -364.427119)
			(xy 287.959038 -364.426754) (xy 287.891982 -364.426754) (xy 287.882963 -364.427091) (xy 287.866046 -364.433351)
			(xy 287.858962 -364.438946) (xy 287.858962 -364.4392) (xy 287.858708 -364.4392) (xy 287.837775 -364.456841)
			(xy 287.791807 -364.486565) (xy 287.742061 -364.509411) (xy 287.689559 -364.524907) (xy 287.635381 -364.532736)
			(xy 287.580639 -364.532736) (xy 287.526461 -364.524907) (xy 287.473959 -364.509411) (xy 287.424213 -364.486565)
			(xy 287.378245 -364.456841) (xy 287.357312 -364.4392) (xy 287.357058 -364.438946) (xy 287.349964 -364.433371)
			(xy 287.333053 -364.427119) (xy 287.324038 -364.426754) (xy 287.256982 -364.426754) (xy 287.247963 -364.427091)
			(xy 287.231046 -364.433351) (xy 287.223962 -364.438946) (xy 287.223962 -364.4392) (xy 287.223708 -364.4392)
			(xy 287.202784 -364.456849) (xy 287.156809 -364.486559) (xy 287.107059 -364.509393) (xy 287.054557 -364.524882)
			(xy 287.00038 -364.532707) (xy 286.97301 -364.53318) (xy 286.945435 -364.532714) (xy 286.890862 -364.524763)
			(xy 286.838002 -364.509038) (xy 286.787956 -364.485868) (xy 286.741766 -364.455735) (xy 286.700396 -364.419267)
			(xy 286.68218 -364.39856) (xy 286.674639 -364.390469) (xy 286.654617 -364.381125) (xy 286.643572 -364.380526)
			(xy 286.565848 -364.380526) (xy 286.554801 -364.381113) (xy 286.534779 -364.390464) (xy 286.52724 -364.39856)
			(xy 286.509002 -364.419247) (xy 286.46764 -364.455721) (xy 286.421456 -364.485857) (xy 286.371413 -364.509027)
			(xy 286.318555 -364.524748) (xy 286.263983 -364.532693) (xy 286.23641 -364.53318) (xy 286.20904 -364.532713)
			(xy 286.154861 -364.524896) (xy 286.102357 -364.509408) (xy 286.05261 -364.486566) (xy 286.006644 -364.456841)
			(xy 285.985712 -364.4392) (xy 285.985458 -364.438946) (xy 285.978364 -364.433371) (xy 285.961453 -364.427119)
			(xy 285.952438 -364.426754) (xy 285.885382 -364.426754) (xy 285.876363 -364.427091) (xy 285.859446 -364.433351)
			(xy 285.852362 -364.438946) (xy 285.852362 -364.4392) (xy 285.852108 -364.4392) (xy 285.831184 -364.456849)
			(xy 285.785209 -364.486559) (xy 285.735459 -364.509393) (xy 285.682957 -364.524882) (xy 285.62878 -364.532707)
			(xy 285.60141 -364.53318) (xy 285.574156 -364.532735) (xy 285.520203 -364.524979) (xy 285.467903 -364.509623)
			(xy 285.418321 -364.486979) (xy 285.372467 -364.45751) (xy 285.331273 -364.421814) (xy 285.295579 -364.380619)
			(xy 285.266112 -364.334763) (xy 285.243471 -364.28518) (xy 285.228117 -364.232879) (xy 285.220363 -364.178926)
			(xy 285.219902 -364.151672) (xy 285.220351 -364.124301) (xy 285.228173 -364.070121) (xy 285.243666 -364.017618)
			(xy 285.266511 -363.967871) (xy 285.296239 -363.921905) (xy 285.313882 -363.900974) (xy 285.314136 -363.90072)
			(xy 285.319724 -363.893635) (xy 285.325969 -363.876717) (xy 285.326328 -363.8677) (xy 285.326328 -363.800644)
			(xy 285.325944 -363.79163) (xy 285.319714 -363.774713) (xy 285.314136 -363.767624) (xy 285.313882 -363.767624)
			(xy 285.313882 -363.76737) (xy 285.296216 -363.746459) (xy 285.266496 -363.700486) (xy 285.243655 -363.650736)
			(xy 285.228162 -363.598231) (xy 285.220337 -363.54405) (xy 285.22034 -363.489308) (xy 285.228171 -363.435128)
			(xy 285.243669 -363.382625) (xy 285.266516 -363.332877) (xy 285.296241 -363.286908) (xy 285.313882 -363.265974)
			(xy 285.314136 -363.26572) (xy 285.319724 -363.258635) (xy 285.325969 -363.241717) (xy 285.326328 -363.2327)
			(xy 285.326328 -363.165644) (xy 285.325944 -363.15663) (xy 285.319714 -363.139713) (xy 285.314136 -363.132624)
			(xy 285.313882 -363.132624) (xy 285.313882 -363.13237) (xy 285.296216 -363.111459) (xy 285.266496 -363.065486)
			(xy 285.243655 -363.015736) (xy 285.228162 -362.963231) (xy 285.220337 -362.90905) (xy 285.22034 -362.854308)
			(xy 285.228171 -362.800128) (xy 285.243669 -362.747625) (xy 285.266516 -362.697877) (xy 285.296241 -362.651908)
			(xy 285.313882 -362.630974) (xy 285.314136 -362.63072) (xy 285.319724 -362.623635) (xy 285.325969 -362.606717)
			(xy 285.326328 -362.5977) (xy 285.326328 -362.530644) (xy 285.325944 -362.52163) (xy 285.319714 -362.504713)
			(xy 285.314136 -362.497624) (xy 285.313882 -362.497624) (xy 285.313882 -362.49737) (xy 285.296259 -362.476425)
			(xy 285.266546 -362.430455) (xy 285.243707 -362.380711) (xy 285.228212 -362.328213) (xy 285.220379 -362.27404)
			(xy 285.219902 -362.246672) (xy 285.22044 -362.217398) (xy 285.22941 -362.159539) (xy 285.247118 -362.103732)
			(xy 285.273149 -362.051288) (xy 285.306891 -362.003439) (xy 285.326836 -361.982004) (xy 285.32709 -361.98175)
			(xy 285.333532 -361.974237) (xy 285.340732 -361.955826) (xy 285.34106 -361.945936) (xy 285.33979 -361.874308)
			(xy 285.339198 -361.864447) (xy 285.331484 -361.84628) (xy 285.324804 -361.839002) (xy 285.32455 -361.838748)
			(xy 285.306706 -361.820753) (xy 285.275478 -361.780839) (xy 285.24981 -361.73714) (xy 285.230155 -361.690428)
			(xy 285.216858 -361.641525) (xy 285.210153 -361.591291) (xy 285.209742 -361.565952) (xy 275.520404 -361.565952)
			(xy 275.520404 -362.627672) (xy 275.520841 -362.637736) (xy 275.528574 -362.656321) (xy 275.53539 -362.66374)
			(xy 276.589236 -363.717586) (xy 276.596636 -363.724428) (xy 276.615234 -363.732152) (xy 276.625304 -363.732572)
			(xy 280.889202 -363.732572) (xy 280.899273 -363.732995) (xy 280.917879 -363.740706) (xy 280.92527 -363.747558)
			(xy 281.820112 -364.6424) (xy 300.398432 -364.6424) (xy 300.402503 -364.586778) (xy 300.414629 -364.532341)
			(xy 300.434552 -364.48025) (xy 300.461848 -364.431615) (xy 300.495934 -364.387472) (xy 300.536083 -364.348763)
			(xy 300.581441 -364.316312) (xy 300.631041 -364.290811) (xy 300.683825 -364.272804) (xy 300.738668 -364.262674)
			(xy 300.794402 -364.260637) (xy 300.849839 -364.266737) (xy 300.903796 -364.280843) (xy 300.955125 -364.302655)
			(xy 301.002731 -364.331709) (xy 301.045599 -364.367384) (xy 301.082816 -364.408921) (xy 301.113589 -364.455434)
			(xy 301.137261 -364.505931) (xy 301.153329 -364.559338) (xy 301.161449 -364.614514) (xy 301.161958 -364.6424)
			(xy 301.161449 -364.670286) (xy 301.153329 -364.725462) (xy 301.137261 -364.778869) (xy 301.113589 -364.829366)
			(xy 301.082816 -364.875879) (xy 301.045599 -364.917416) (xy 301.002731 -364.953091) (xy 300.955125 -364.982145)
			(xy 300.903796 -365.003957) (xy 300.849839 -365.018063) (xy 300.794402 -365.024163) (xy 300.738668 -365.022126)
			(xy 300.683825 -365.011996) (xy 300.631041 -364.993989) (xy 300.581441 -364.968488) (xy 300.536083 -364.936037)
			(xy 300.495934 -364.897328) (xy 300.461848 -364.853185) (xy 300.434552 -364.80455) (xy 300.414629 -364.752459)
			(xy 300.402503 -364.698022) (xy 300.398432 -364.6424) (xy 281.820112 -364.6424) (xy 284.394268 -367.216556)
			(xy 294.300313 -367.216556) (xy 294.300313 -367.162044) (xy 294.308071 -367.108087) (xy 294.323429 -367.055783)
			(xy 294.346074 -367.006197) (xy 294.375545 -366.960339) (xy 294.411243 -366.919142) (xy 294.452441 -366.883444)
			(xy 294.498299 -366.853973) (xy 294.547885 -366.831328) (xy 294.600189 -366.81597) (xy 294.654146 -366.808213)
			(xy 294.681402 -366.80775) (xy 294.70908 -366.808243) (xy 294.763854 -366.816248) (xy 294.816895 -366.832092)
			(xy 294.867087 -366.855439) (xy 294.913374 -366.8858) (xy 294.954785 -366.922536) (xy 294.972994 -366.943386)
			(xy 294.98198 -366.953453) (xy 295.004162 -366.968804) (xy 295.029593 -366.977803) (xy 295.056494 -366.979819)
			(xy 295.082982 -366.974712) (xy 295.107205 -366.962839) (xy 295.127468 -366.945031) (xy 295.142353 -366.922533)
			(xy 295.146984 -366.909858) (xy 295.155726 -366.884816) (xy 295.179251 -366.837278) (xy 295.209134 -366.793455)
			(xy 295.244797 -366.754193) (xy 295.285555 -366.720248) (xy 295.33062 -366.692275) (xy 295.379125 -366.670813)
			(xy 295.430135 -366.656275) (xy 295.482667 -366.648941) (xy 295.509188 -366.648492) (xy 295.536441 -366.648955)
			(xy 295.590394 -366.65671) (xy 295.642693 -366.672065) (xy 295.692275 -366.694707) (xy 295.738129 -366.724175)
			(xy 295.779323 -366.759868) (xy 295.815018 -366.801061) (xy 295.844487 -366.846915) (xy 295.867131 -366.896496)
			(xy 295.882487 -366.948795) (xy 295.890245 -367.002747) (xy 295.890245 -367.057253) (xy 295.882487 -367.111205)
			(xy 295.867131 -367.163504) (xy 295.844487 -367.213085) (xy 295.815018 -367.258939) (xy 295.779323 -367.300132)
			(xy 295.738129 -367.335825) (xy 295.692275 -367.365293) (xy 295.642693 -367.387935) (xy 295.590394 -367.40329)
			(xy 295.536441 -367.411045) (xy 295.509188 -367.411508) (xy 295.481511 -367.411002) (xy 295.426738 -367.402996)
			(xy 295.373698 -367.387154) (xy 295.323507 -367.363809) (xy 295.277219 -367.333452) (xy 295.235807 -367.29672)
			(xy 295.217596 -367.275872) (xy 295.208638 -367.265775) (xy 295.186452 -367.250413) (xy 295.161013 -367.241407)
			(xy 295.134103 -367.23939) (xy 295.107605 -367.244501) (xy 295.083376 -367.256384) (xy 295.063112 -367.274205)
			(xy 295.048232 -367.296718) (xy 295.043606 -367.3094) (xy 295.034848 -367.334436) (xy 295.011327 -367.381976)
			(xy 294.981448 -367.4258) (xy 294.945787 -367.465064) (xy 294.905032 -367.49901) (xy 294.859968 -367.526984)
			(xy 294.811463 -367.548446) (xy 294.760454 -367.562984) (xy 294.707922 -367.570317) (xy 294.681402 -367.570766)
			(xy 294.654146 -367.570387) (xy 294.600189 -367.56263) (xy 294.547885 -367.547272) (xy 294.498299 -367.524627)
			(xy 294.452441 -367.495156) (xy 294.411243 -367.459458) (xy 294.375545 -367.418261) (xy 294.346074 -367.372403)
			(xy 294.323429 -367.322817) (xy 294.308071 -367.270513) (xy 294.300313 -367.216556) (xy 284.394268 -367.216556)
			(xy 286.553148 -369.375436) (xy 295.870882 -369.375436) (xy 295.874953 -369.319814) (xy 295.887079 -369.265377)
			(xy 295.907002 -369.213286) (xy 295.934298 -369.164651) (xy 295.968384 -369.120508) (xy 296.008533 -369.081799)
			(xy 296.053891 -369.049348) (xy 296.103491 -369.023847) (xy 296.156275 -369.00584) (xy 296.211118 -368.99571)
			(xy 296.266852 -368.993673) (xy 296.322289 -368.999773) (xy 296.376246 -369.013879) (xy 296.427575 -369.035691)
			(xy 296.475181 -369.064745) (xy 296.518049 -369.10042) (xy 296.555266 -369.141957) (xy 296.586039 -369.18847)
			(xy 296.609711 -369.238967) (xy 296.625779 -369.292374) (xy 296.633899 -369.34755) (xy 296.634408 -369.375436)
			(xy 296.633899 -369.403322) (xy 296.625779 -369.458498) (xy 296.609711 -369.511905) (xy 296.586039 -369.562402)
			(xy 296.555266 -369.608915) (xy 296.518049 -369.650452) (xy 296.475181 -369.686127) (xy 296.427575 -369.715181)
			(xy 296.376246 -369.736993) (xy 296.322289 -369.751099) (xy 296.266852 -369.757199) (xy 296.211118 -369.755162)
			(xy 296.156275 -369.745032) (xy 296.103491 -369.727025) (xy 296.053891 -369.701524) (xy 296.008533 -369.669073)
			(xy 295.968384 -369.630364) (xy 295.934298 -369.586221) (xy 295.907002 -369.537586) (xy 295.887079 -369.485495)
			(xy 295.874953 -369.431058) (xy 295.870882 -369.375436) (xy 286.553148 -369.375436) (xy 287.273746 -370.096034)
			(xy 298.448982 -370.096034) (xy 298.453053 -370.040412) (xy 298.465179 -369.985975) (xy 298.485102 -369.933884)
			(xy 298.512398 -369.885249) (xy 298.546484 -369.841106) (xy 298.586633 -369.802397) (xy 298.631991 -369.769946)
			(xy 298.681591 -369.744445) (xy 298.734375 -369.726438) (xy 298.789218 -369.716308) (xy 298.844952 -369.714271)
			(xy 298.900389 -369.720371) (xy 298.954346 -369.734477) (xy 299.005675 -369.756289) (xy 299.053281 -369.785343)
			(xy 299.096149 -369.821018) (xy 299.133366 -369.862555) (xy 299.164139 -369.909068) (xy 299.187811 -369.959565)
			(xy 299.203879 -370.012972) (xy 299.211999 -370.068148) (xy 299.212508 -370.096034) (xy 299.211999 -370.12392)
			(xy 299.203879 -370.179096) (xy 299.187811 -370.232503) (xy 299.164139 -370.283) (xy 299.133366 -370.329513)
			(xy 299.096149 -370.37105) (xy 299.053281 -370.406725) (xy 299.005675 -370.435779) (xy 298.954346 -370.457591)
			(xy 298.900389 -370.471697) (xy 298.844952 -370.477797) (xy 298.789218 -370.47576) (xy 298.734375 -370.46563)
			(xy 298.681591 -370.447623) (xy 298.631991 -370.422122) (xy 298.586633 -370.389671) (xy 298.546484 -370.350962)
			(xy 298.512398 -370.306819) (xy 298.485102 -370.258184) (xy 298.465179 -370.206093) (xy 298.453053 -370.151656)
			(xy 298.448982 -370.096034) (xy 287.273746 -370.096034) (xy 288.75482 -371.577108) (xy 288.76222 -371.58395)
			(xy 288.780818 -371.591676) (xy 288.790888 -371.592094) (xy 291.870892 -371.592094)
		)
		(stroke
			(width 0)
			(type solid)
		)
		(fill yes)
		(layer "In13.Cu")
		(net "GND")
	)
	(gr_poly
		(pts
			(xy 392.833098 -194.0306) (xy 392.839106 -194.030427) (xy 392.850783 -194.027593) (xy 392.856212 -194.025012)
			(xy 392.859687 -194.023173) (xy 392.866067 -194.018581) (xy 392.868912 -194.015868) (xy 393.503404 -193.381376)
			(xy 393.506107 -193.378523) (xy 393.510694 -193.372142) (xy 393.512548 -193.368676) (xy 393.515136 -193.36325)
			(xy 393.517967 -193.35157) (xy 393.518136 -193.345562) (xy 393.518136 -190.263018) (xy 393.518575 -190.252955)
			(xy 393.526314 -190.234376) (xy 393.533122 -190.22695) (xy 400.691604 -183.068214) (xy 400.695414 -183.059832)
			(xy 400.70711 -183.035696) (xy 400.736268 -182.990679) (xy 400.771442 -182.950189) (xy 400.811939 -182.915023)
			(xy 400.856961 -182.885874) (xy 400.881088 -182.874158) (xy 400.88947 -182.870348) (xy 409.65755 -174.102268)
			(xy 409.664948 -174.095422) (xy 409.683547 -174.087695) (xy 409.693618 -174.087282) (xy 424.015916 -174.087282)
			(xy 424.021927 -174.087119) (xy 424.033612 -174.084301) (xy 424.03903 -174.081694) (xy 424.042504 -174.079854)
			(xy 424.048881 -174.075259) (xy 424.05173 -174.07255) (xy 426.908468 -171.215812) (xy 426.911174 -171.212961)
			(xy 426.915768 -171.206583) (xy 426.917612 -171.203112) (xy 426.92019 -171.197684) (xy 426.923003 -171.186004)
			(xy 426.9232 -171.179998) (xy 426.9232 -156.792422) (xy 426.923029 -156.786413) (xy 426.9202 -156.774734)
			(xy 426.917612 -156.769308) (xy 426.915774 -156.765833) (xy 426.911184 -156.75945) (xy 426.908468 -156.756608)
			(xy 425.347892 -155.196286) (xy 425.340908 -155.189881) (xy 425.323555 -155.1823) (xy 425.31411 -155.181554)
			(xy 425.313856 -155.181554) (xy 425.285237 -155.180045) (xy 425.228905 -155.169511) (xy 425.174783 -155.150669)
			(xy 425.124088 -155.123943) (xy 425.077961 -155.089935) (xy 425.03744 -155.04941) (xy 425.003437 -155.00328)
			(xy 424.976716 -154.952583) (xy 424.95788 -154.898459) (xy 424.947351 -154.842126) (xy 424.94581 -154.813508)
			(xy 424.94581 -154.813254) (xy 424.945044 -154.803813) (xy 424.937467 -154.786466) (xy 424.931078 -154.779472)
			(xy 402.772372 -132.620766) (xy 402.764975 -132.613917) (xy 402.746376 -132.606182) (xy 402.736304 -132.60578)
			(xy 366.434116 -132.60578) (xy 366.424105 -132.606265) (xy 366.405604 -132.613921) (xy 366.391441 -132.628074)
			(xy 366.383772 -132.646569) (xy 366.383316 -132.65658) (xy 366.383316 -134.786624) (xy 371.93931 -134.786624)
			(xy 371.943381 -134.731002) (xy 371.955507 -134.676565) (xy 371.97543 -134.624474) (xy 372.002726 -134.575839)
			(xy 372.036812 -134.531696) (xy 372.076961 -134.492987) (xy 372.122319 -134.460536) (xy 372.171919 -134.435035)
			(xy 372.224703 -134.417028) (xy 372.279546 -134.406898) (xy 372.33528 -134.404861) (xy 372.390717 -134.410961)
			(xy 372.444674 -134.425067) (xy 372.496003 -134.446879) (xy 372.543609 -134.475933) (xy 372.586477 -134.511608)
			(xy 372.623694 -134.553145) (xy 372.654467 -134.599658) (xy 372.678139 -134.650155) (xy 372.694207 -134.703562)
			(xy 372.702327 -134.758738) (xy 372.702836 -134.786624) (xy 374.33326 -134.786624) (xy 374.337331 -134.731002)
			(xy 374.349457 -134.676565) (xy 374.36938 -134.624474) (xy 374.396676 -134.575839) (xy 374.430762 -134.531696)
			(xy 374.470911 -134.492987) (xy 374.516269 -134.460536) (xy 374.565869 -134.435035) (xy 374.618653 -134.417028)
			(xy 374.673496 -134.406898) (xy 374.72923 -134.404861) (xy 374.784667 -134.410961) (xy 374.838624 -134.425067)
			(xy 374.889953 -134.446879) (xy 374.937559 -134.475933) (xy 374.980427 -134.511608) (xy 375.017644 -134.553145)
			(xy 375.048417 -134.599658) (xy 375.072089 -134.650155) (xy 375.088157 -134.703562) (xy 375.096277 -134.758738)
			(xy 375.096786 -134.786624) (xy 375.096591 -134.797292) (xy 393.769848 -134.797292) (xy 393.773919 -134.74167)
			(xy 393.786045 -134.687233) (xy 393.805968 -134.635142) (xy 393.833264 -134.586507) (xy 393.86735 -134.542364)
			(xy 393.907499 -134.503655) (xy 393.952857 -134.471204) (xy 394.002457 -134.445703) (xy 394.055241 -134.427696)
			(xy 394.110084 -134.417566) (xy 394.165818 -134.415529) (xy 394.221255 -134.421629) (xy 394.275212 -134.435735)
			(xy 394.326541 -134.457547) (xy 394.374147 -134.486601) (xy 394.417015 -134.522276) (xy 394.454232 -134.563813)
			(xy 394.485005 -134.610326) (xy 394.508677 -134.660823) (xy 394.524745 -134.71423) (xy 394.532865 -134.769406)
			(xy 394.533374 -134.797292) (xy 394.532865 -134.825178) (xy 394.524745 -134.880354) (xy 394.508677 -134.933761)
			(xy 394.485005 -134.984258) (xy 394.454232 -135.030771) (xy 394.417015 -135.072308) (xy 394.374147 -135.107983)
			(xy 394.326541 -135.137037) (xy 394.275212 -135.158849) (xy 394.221255 -135.172955) (xy 394.165818 -135.179055)
			(xy 394.110084 -135.177018) (xy 394.055241 -135.166888) (xy 394.002457 -135.148881) (xy 393.952857 -135.12338)
			(xy 393.907499 -135.090929) (xy 393.86735 -135.05222) (xy 393.833264 -135.008077) (xy 393.805968 -134.959442)
			(xy 393.786045 -134.907351) (xy 393.773919 -134.852914) (xy 393.769848 -134.797292) (xy 375.096591 -134.797292)
			(xy 375.096277 -134.81451) (xy 375.088157 -134.869686) (xy 375.072089 -134.923093) (xy 375.048417 -134.97359)
			(xy 375.017644 -135.020103) (xy 374.980427 -135.06164) (xy 374.937559 -135.097315) (xy 374.889953 -135.126369)
			(xy 374.838624 -135.148181) (xy 374.784667 -135.162287) (xy 374.72923 -135.168387) (xy 374.673496 -135.16635)
			(xy 374.618653 -135.15622) (xy 374.565869 -135.138213) (xy 374.516269 -135.112712) (xy 374.470911 -135.080261)
			(xy 374.430762 -135.041552) (xy 374.396676 -134.997409) (xy 374.36938 -134.948774) (xy 374.349457 -134.896683)
			(xy 374.337331 -134.842246) (xy 374.33326 -134.786624) (xy 372.702836 -134.786624) (xy 372.702327 -134.81451)
			(xy 372.694207 -134.869686) (xy 372.678139 -134.923093) (xy 372.654467 -134.97359) (xy 372.623694 -135.020103)
			(xy 372.586477 -135.06164) (xy 372.543609 -135.097315) (xy 372.496003 -135.126369) (xy 372.444674 -135.148181)
			(xy 372.390717 -135.162287) (xy 372.33528 -135.168387) (xy 372.279546 -135.16635) (xy 372.224703 -135.15622)
			(xy 372.171919 -135.138213) (xy 372.122319 -135.112712) (xy 372.076961 -135.080261) (xy 372.036812 -135.041552)
			(xy 372.002726 -134.997409) (xy 371.97543 -134.948774) (xy 371.955507 -134.896683) (xy 371.943381 -134.842246)
			(xy 371.93931 -134.786624) (xy 366.383316 -134.786624) (xy 366.383316 -135.66013) (xy 398.415254 -135.66013)
			(xy 398.419325 -135.604508) (xy 398.431451 -135.550071) (xy 398.451374 -135.49798) (xy 398.47867 -135.449345)
			(xy 398.512756 -135.405202) (xy 398.552905 -135.366493) (xy 398.598263 -135.334042) (xy 398.647863 -135.308541)
			(xy 398.700647 -135.290534) (xy 398.75549 -135.280404) (xy 398.811224 -135.278367) (xy 398.866661 -135.284467)
			(xy 398.920618 -135.298573) (xy 398.971947 -135.320385) (xy 399.019553 -135.349439) (xy 399.062421 -135.385114)
			(xy 399.099638 -135.426651) (xy 399.130411 -135.473164) (xy 399.154083 -135.523661) (xy 399.170151 -135.577068)
			(xy 399.178271 -135.632244) (xy 399.17878 -135.66013) (xy 399.178271 -135.688016) (xy 399.170151 -135.743192)
			(xy 399.154083 -135.796599) (xy 399.130411 -135.847096) (xy 399.099638 -135.893609) (xy 399.062421 -135.935146)
			(xy 399.019553 -135.970821) (xy 398.971947 -135.999875) (xy 398.920618 -136.021687) (xy 398.866661 -136.035793)
			(xy 398.811224 -136.041893) (xy 398.75549 -136.039856) (xy 398.700647 -136.029726) (xy 398.647863 -136.011719)
			(xy 398.598263 -135.986218) (xy 398.552905 -135.953767) (xy 398.512756 -135.915058) (xy 398.47867 -135.870915)
			(xy 398.451374 -135.82228) (xy 398.431451 -135.770189) (xy 398.419325 -135.715752) (xy 398.415254 -135.66013)
			(xy 366.383316 -135.66013) (xy 366.383316 -136.519158) (xy 384.87426 -136.519158) (xy 384.878331 -136.463536)
			(xy 384.890457 -136.409099) (xy 384.91038 -136.357008) (xy 384.937676 -136.308373) (xy 384.971762 -136.26423)
			(xy 385.011911 -136.225521) (xy 385.057269 -136.19307) (xy 385.106869 -136.167569) (xy 385.159653 -136.149562)
			(xy 385.214496 -136.139432) (xy 385.27023 -136.137395) (xy 385.325667 -136.143495) (xy 385.379624 -136.157601)
			(xy 385.430953 -136.179413) (xy 385.478559 -136.208467) (xy 385.506087 -136.231376) (xy 405.077928 -136.231376)
			(xy 405.081999 -136.175754) (xy 405.094125 -136.121317) (xy 405.114048 -136.069226) (xy 405.141344 -136.020591)
			(xy 405.17543 -135.976448) (xy 405.215579 -135.937739) (xy 405.260937 -135.905288) (xy 405.310537 -135.879787)
			(xy 405.363321 -135.86178) (xy 405.418164 -135.85165) (xy 405.473898 -135.849613) (xy 405.529335 -135.855713)
			(xy 405.583292 -135.869819) (xy 405.634621 -135.891631) (xy 405.682227 -135.920685) (xy 405.725095 -135.95636)
			(xy 405.762312 -135.997897) (xy 405.793085 -136.04441) (xy 405.816757 -136.094907) (xy 405.832825 -136.148314)
			(xy 405.840945 -136.20349) (xy 405.841454 -136.231376) (xy 405.840945 -136.259262) (xy 405.832825 -136.314438)
			(xy 405.816757 -136.367845) (xy 405.793085 -136.418342) (xy 405.762312 -136.464855) (xy 405.725095 -136.506392)
			(xy 405.682227 -136.542067) (xy 405.634621 -136.571121) (xy 405.583292 -136.592933) (xy 405.529335 -136.607039)
			(xy 405.473898 -136.613139) (xy 405.418164 -136.611102) (xy 405.363321 -136.600972) (xy 405.310537 -136.582965)
			(xy 405.260937 -136.557464) (xy 405.215579 -136.525013) (xy 405.17543 -136.486304) (xy 405.141344 -136.442161)
			(xy 405.114048 -136.393526) (xy 405.094125 -136.341435) (xy 405.081999 -136.286998) (xy 405.077928 -136.231376)
			(xy 385.506087 -136.231376) (xy 385.521427 -136.244142) (xy 385.558644 -136.285679) (xy 385.589417 -136.332192)
			(xy 385.613089 -136.382689) (xy 385.629157 -136.436096) (xy 385.637277 -136.491272) (xy 385.637786 -136.519158)
			(xy 385.637277 -136.547044) (xy 385.629157 -136.60222) (xy 385.613089 -136.655627) (xy 385.589417 -136.706124)
			(xy 385.558644 -136.752637) (xy 385.521427 -136.794174) (xy 385.478559 -136.829849) (xy 385.430953 -136.858903)
			(xy 385.379624 -136.880715) (xy 385.325667 -136.894821) (xy 385.27023 -136.900921) (xy 385.214496 -136.898884)
			(xy 385.159653 -136.888754) (xy 385.106869 -136.870747) (xy 385.057269 -136.845246) (xy 385.011911 -136.812795)
			(xy 384.971762 -136.774086) (xy 384.937676 -136.729943) (xy 384.91038 -136.681308) (xy 384.890457 -136.629217)
			(xy 384.878331 -136.57478) (xy 384.87426 -136.519158) (xy 366.383316 -136.519158) (xy 366.383316 -137.027412)
			(xy 373.67032 -137.027412) (xy 373.674391 -136.97179) (xy 373.686517 -136.917353) (xy 373.70644 -136.865262)
			(xy 373.733736 -136.816627) (xy 373.767822 -136.772484) (xy 373.807971 -136.733775) (xy 373.853329 -136.701324)
			(xy 373.902929 -136.675823) (xy 373.955713 -136.657816) (xy 374.010556 -136.647686) (xy 374.06629 -136.645649)
			(xy 374.121727 -136.651749) (xy 374.175684 -136.665855) (xy 374.227013 -136.687667) (xy 374.274619 -136.716721)
			(xy 374.317487 -136.752396) (xy 374.354704 -136.793933) (xy 374.385477 -136.840446) (xy 374.409149 -136.890943)
			(xy 374.425217 -136.94435) (xy 374.433337 -136.999526) (xy 374.433846 -137.027412) (xy 374.433337 -137.055298)
			(xy 374.42674 -137.100125) (xy 378.717621 -137.100125) (xy 378.717624 -137.045631) (xy 378.725382 -136.991692)
			(xy 378.740737 -136.939406) (xy 378.763377 -136.889837) (xy 378.79284 -136.843995) (xy 378.828528 -136.802812)
			(xy 378.869713 -136.767127) (xy 378.915557 -136.737666) (xy 378.965126 -136.715029) (xy 379.017413 -136.699677)
			(xy 379.071353 -136.691922) (xy 379.125847 -136.691922) (xy 379.179787 -136.699677) (xy 379.232074 -136.715029)
			(xy 379.281643 -136.737666) (xy 379.327487 -136.767127) (xy 379.368672 -136.802812) (xy 379.40436 -136.843995)
			(xy 379.433823 -136.889837) (xy 379.456463 -136.939406) (xy 379.471818 -136.991692) (xy 379.479576 -137.045631)
			(xy 379.480064 -137.072878) (xy 379.480064 -137.073132) (xy 379.479736 -137.095178) (xy 379.474646 -137.138976)
			(xy 379.469904 -137.160508) (xy 379.466856 -137.17397) (xy 379.47473 -137.200386) (xy 379.550676 -137.269474)
			(xy 379.557512 -137.275303) (xy 379.574139 -137.282082) (xy 379.592086 -137.282652) (xy 379.600714 -137.280142)
			(xy 379.600968 -137.280142) (xy 379.630234 -137.271046) (xy 379.690723 -137.261217) (xy 379.721364 -137.260584)
			(xy 379.721618 -137.260584) (xy 379.748869 -137.261061) (xy 379.802817 -137.26882) (xy 379.855111 -137.284177)
			(xy 379.904688 -137.306819) (xy 379.950538 -137.336287) (xy 379.991728 -137.371979) (xy 380.027419 -137.41317)
			(xy 380.055539 -137.456926) (xy 392.339828 -137.456926) (xy 392.343899 -137.401304) (xy 392.356025 -137.346867)
			(xy 392.375948 -137.294776) (xy 392.403244 -137.246141) (xy 392.43733 -137.201998) (xy 392.477479 -137.163289)
			(xy 392.522837 -137.130838) (xy 392.572437 -137.105337) (xy 392.625221 -137.08733) (xy 392.680064 -137.0772)
			(xy 392.735798 -137.075163) (xy 392.791235 -137.081263) (xy 392.845192 -137.095369) (xy 392.896521 -137.117181)
			(xy 392.944127 -137.146235) (xy 392.986995 -137.18191) (xy 393.024212 -137.223447) (xy 393.054985 -137.26996)
			(xy 393.078657 -137.320457) (xy 393.094725 -137.373864) (xy 393.102845 -137.42904) (xy 393.103354 -137.456926)
			(xy 393.102845 -137.484812) (xy 393.094725 -137.539988) (xy 393.078657 -137.593395) (xy 393.054985 -137.643892)
			(xy 393.024212 -137.690405) (xy 392.986995 -137.731942) (xy 392.944127 -137.767617) (xy 392.896521 -137.796671)
			(xy 392.845192 -137.818483) (xy 392.791235 -137.832589) (xy 392.735798 -137.838689) (xy 392.680064 -137.836652)
			(xy 392.625221 -137.826522) (xy 392.572437 -137.808515) (xy 392.522837 -137.783014) (xy 392.477479 -137.750563)
			(xy 392.43733 -137.711854) (xy 392.403244 -137.667711) (xy 392.375948 -137.619076) (xy 392.356025 -137.566985)
			(xy 392.343899 -137.512548) (xy 392.339828 -137.456926) (xy 380.055539 -137.456926) (xy 380.056885 -137.459021)
			(xy 380.079527 -137.508598) (xy 380.094882 -137.560893) (xy 380.10264 -137.614841) (xy 380.103126 -137.642092)
			(xy 380.103028 -137.652912) (xy 380.101757 -137.674515) (xy 380.100586 -137.685272) (xy 380.100035 -137.697457)
			(xy 380.108925 -137.720134) (xy 380.117604 -137.728706) (xy 380.18974 -137.79246) (xy 380.213616 -137.798302)
			(xy 380.225808 -137.795254) (xy 380.248065 -137.790152) (xy 380.2934 -137.78468) (xy 380.316232 -137.784332)
			(xy 380.31674 -137.784332) (xy 380.343987 -137.784821) (xy 380.397926 -137.792582) (xy 380.450211 -137.807939)
			(xy 380.499779 -137.830581) (xy 380.54562 -137.860047) (xy 380.586802 -137.895736) (xy 380.622485 -137.936922)
			(xy 380.651944 -137.982768) (xy 380.674579 -138.032339) (xy 380.687897 -138.077702) (xy 390.700004 -138.077702)
			(xy 390.704075 -138.02208) (xy 390.716201 -137.967643) (xy 390.736124 -137.915552) (xy 390.76342 -137.866917)
			(xy 390.797506 -137.822774) (xy 390.837655 -137.784065) (xy 390.883013 -137.751614) (xy 390.932613 -137.726113)
			(xy 390.985397 -137.708106) (xy 391.04024 -137.697976) (xy 391.095974 -137.695939) (xy 391.151411 -137.702039)
			(xy 391.205368 -137.716145) (xy 391.256697 -137.737957) (xy 391.304303 -137.767011) (xy 391.347171 -137.802686)
			(xy 391.384388 -137.844223) (xy 391.415161 -137.890736) (xy 391.438833 -137.941233) (xy 391.454901 -137.99464)
			(xy 391.457331 -138.011154) (xy 399.242786 -138.011154) (xy 399.246857 -137.955532) (xy 399.258983 -137.901095)
			(xy 399.278906 -137.849004) (xy 399.306202 -137.800369) (xy 399.340288 -137.756226) (xy 399.380437 -137.717517)
			(xy 399.425795 -137.685066) (xy 399.475395 -137.659565) (xy 399.528179 -137.641558) (xy 399.583022 -137.631428)
			(xy 399.638756 -137.629391) (xy 399.694193 -137.635491) (xy 399.74815 -137.649597) (xy 399.799479 -137.671409)
			(xy 399.847085 -137.700463) (xy 399.889953 -137.736138) (xy 399.92717 -137.777675) (xy 399.957943 -137.824188)
			(xy 399.981615 -137.874685) (xy 399.997683 -137.928092) (xy 400.005803 -137.983268) (xy 400.006312 -138.011154)
			(xy 400.005803 -138.03904) (xy 399.997683 -138.094216) (xy 399.981615 -138.147623) (xy 399.957943 -138.19812)
			(xy 399.92717 -138.244633) (xy 399.889953 -138.28617) (xy 399.847085 -138.321845) (xy 399.799479 -138.350899)
			(xy 399.74815 -138.372711) (xy 399.694193 -138.386817) (xy 399.638756 -138.392917) (xy 399.583022 -138.39088)
			(xy 399.528179 -138.38075) (xy 399.475395 -138.362743) (xy 399.425795 -138.337242) (xy 399.380437 -138.304791)
			(xy 399.340288 -138.266082) (xy 399.306202 -138.221939) (xy 399.278906 -138.173304) (xy 399.258983 -138.121213)
			(xy 399.246857 -138.066776) (xy 399.242786 -138.011154) (xy 391.457331 -138.011154) (xy 391.463021 -138.049816)
			(xy 391.46353 -138.077702) (xy 391.463021 -138.105588) (xy 391.454901 -138.160764) (xy 391.438833 -138.214171)
			(xy 391.415161 -138.264668) (xy 391.384388 -138.311181) (xy 391.347171 -138.352718) (xy 391.304303 -138.388393)
			(xy 391.256697 -138.417447) (xy 391.205368 -138.439259) (xy 391.151411 -138.453365) (xy 391.095974 -138.459465)
			(xy 391.04024 -138.457428) (xy 390.985397 -138.447298) (xy 390.932613 -138.429291) (xy 390.883013 -138.40379)
			(xy 390.837655 -138.371339) (xy 390.797506 -138.33263) (xy 390.76342 -138.288487) (xy 390.736124 -138.239852)
			(xy 390.716201 -138.187761) (xy 390.704075 -138.133324) (xy 390.700004 -138.077702) (xy 380.687897 -138.077702)
			(xy 380.68993 -138.084626) (xy 380.697683 -138.138566) (xy 380.697681 -138.19306) (xy 380.689924 -138.247)
			(xy 380.67457 -138.299286) (xy 380.651932 -138.348856) (xy 380.622469 -138.394699) (xy 380.586783 -138.435883)
			(xy 380.545599 -138.471569) (xy 380.499756 -138.501032) (xy 380.450186 -138.52367) (xy 380.3979 -138.539024)
			(xy 380.393005 -138.539728) (xy 381.147572 -138.539728) (xy 381.151643 -138.484106) (xy 381.163769 -138.429669)
			(xy 381.183692 -138.377578) (xy 381.210988 -138.328943) (xy 381.245074 -138.2848) (xy 381.285223 -138.246091)
			(xy 381.330581 -138.21364) (xy 381.380181 -138.188139) (xy 381.432965 -138.170132) (xy 381.487808 -138.160002)
			(xy 381.543542 -138.157965) (xy 381.598979 -138.164065) (xy 381.652936 -138.178171) (xy 381.704265 -138.199983)
			(xy 381.751871 -138.229037) (xy 381.794739 -138.264712) (xy 381.831956 -138.306249) (xy 381.862729 -138.352762)
			(xy 381.886401 -138.403259) (xy 381.902469 -138.456666) (xy 381.910589 -138.511842) (xy 381.911098 -138.539728)
			(xy 381.910589 -138.567614) (xy 381.902469 -138.62279) (xy 381.886401 -138.676197) (xy 381.862729 -138.726694)
			(xy 381.831956 -138.773207) (xy 381.794739 -138.814744) (xy 381.751871 -138.850419) (xy 381.704265 -138.879473)
			(xy 381.652936 -138.901285) (xy 381.598979 -138.915391) (xy 381.543542 -138.921491) (xy 381.487808 -138.919454)
			(xy 381.432965 -138.909324) (xy 381.380181 -138.891317) (xy 381.330581 -138.865816) (xy 381.285223 -138.833365)
			(xy 381.245074 -138.794656) (xy 381.210988 -138.750513) (xy 381.183692 -138.701878) (xy 381.163769 -138.649787)
			(xy 381.151643 -138.59535) (xy 381.147572 -138.539728) (xy 380.393005 -138.539728) (xy 380.34396 -138.546781)
			(xy 380.289466 -138.546783) (xy 380.235526 -138.53903) (xy 380.183239 -138.523679) (xy 380.133668 -138.501044)
			(xy 380.087822 -138.471585) (xy 380.046636 -138.435902) (xy 380.010947 -138.39472) (xy 379.981481 -138.348879)
			(xy 379.958839 -138.299311) (xy 379.943482 -138.247026) (xy 379.935721 -138.193087) (xy 379.935232 -138.16584)
			(xy 379.935333 -138.15502) (xy 379.936601 -138.133417) (xy 379.937772 -138.12266) (xy 379.938285 -138.110477)
			(xy 379.929418 -138.087803) (xy 379.920754 -138.079226) (xy 379.848618 -138.015472) (xy 379.824742 -138.00963)
			(xy 379.81255 -138.012678) (xy 379.790291 -138.017769) (xy 379.744957 -138.023248) (xy 379.722126 -138.0236)
			(xy 379.721618 -138.0236) (xy 379.694365 -138.023128) (xy 379.640414 -138.015373) (xy 379.588116 -138.000019)
			(xy 379.538535 -137.977378) (xy 379.492682 -137.947911) (xy 379.451489 -137.912218) (xy 379.415795 -137.871026)
			(xy 379.386327 -137.825173) (xy 379.363684 -137.775593) (xy 379.348329 -137.723296) (xy 379.340573 -137.669345)
			(xy 379.34011 -137.642092) (xy 379.34011 -137.641838) (xy 379.340434 -137.619792) (xy 379.345527 -137.575994)
			(xy 379.35027 -137.554462) (xy 379.353318 -137.541) (xy 379.345444 -137.514584) (xy 379.269498 -137.445496)
			(xy 379.262626 -137.439715) (xy 379.246018 -137.432925) (xy 379.228085 -137.432332) (xy 379.21946 -137.434828)
			(xy 379.219206 -137.434828) (xy 379.189942 -137.443932) (xy 379.129451 -137.453755) (xy 379.09881 -137.454386)
			(xy 379.098556 -137.454386) (xy 379.071309 -137.453875) (xy 379.01737 -137.446113) (xy 378.965085 -137.430755)
			(xy 378.915518 -137.408113) (xy 378.869677 -137.378647) (xy 378.828496 -137.342957) (xy 378.792814 -137.30177)
			(xy 378.763356 -137.255924) (xy 378.740722 -137.206353) (xy 378.725372 -137.154065) (xy 378.717621 -137.100125)
			(xy 374.42674 -137.100125) (xy 374.425217 -137.110474) (xy 374.409149 -137.163881) (xy 374.385477 -137.214378)
			(xy 374.354704 -137.260891) (xy 374.317487 -137.302428) (xy 374.274619 -137.338103) (xy 374.227013 -137.367157)
			(xy 374.175684 -137.388969) (xy 374.121727 -137.403075) (xy 374.06629 -137.409175) (xy 374.010556 -137.407138)
			(xy 373.955713 -137.397008) (xy 373.902929 -137.379001) (xy 373.853329 -137.3535) (xy 373.807971 -137.321049)
			(xy 373.767822 -137.28234) (xy 373.733736 -137.238197) (xy 373.70644 -137.189562) (xy 373.686517 -137.137471)
			(xy 373.674391 -137.083034) (xy 373.67032 -137.027412) (xy 366.383316 -137.027412) (xy 366.383316 -138.424158)
			(xy 371.38432 -138.424158) (xy 371.388391 -138.368536) (xy 371.400517 -138.314099) (xy 371.42044 -138.262008)
			(xy 371.447736 -138.213373) (xy 371.481822 -138.16923) (xy 371.521971 -138.130521) (xy 371.567329 -138.09807)
			(xy 371.616929 -138.072569) (xy 371.669713 -138.054562) (xy 371.724556 -138.044432) (xy 371.78029 -138.042395)
			(xy 371.835727 -138.048495) (xy 371.889684 -138.062601) (xy 371.941013 -138.084413) (xy 371.988619 -138.113467)
			(xy 372.031487 -138.149142) (xy 372.068704 -138.190679) (xy 372.073186 -138.197453) (xy 375.096236 -138.197453)
			(xy 375.096236 -138.142947) (xy 375.103993 -138.088995) (xy 375.119348 -138.036696) (xy 375.14199 -137.987115)
			(xy 375.171458 -137.941261) (xy 375.207151 -137.900066) (xy 375.248343 -137.864371) (xy 375.294196 -137.834901)
			(xy 375.343776 -137.812256) (xy 375.396073 -137.796897) (xy 375.450025 -137.789137) (xy 375.477278 -137.78865)
			(xy 375.504916 -137.78913) (xy 375.559612 -137.797126) (xy 375.612583 -137.812924) (xy 375.662724 -137.836194)
			(xy 375.708985 -137.866451) (xy 375.7504 -137.903061) (xy 375.786104 -137.94526) (xy 375.815351 -137.992166)
			(xy 375.837529 -138.042799) (xy 375.845324 -138.06932) (xy 375.848626 -138.081766) (xy 375.865898 -138.100054)
			(xy 375.970292 -138.134852) (xy 375.995438 -138.130534) (xy 376.005344 -138.12266) (xy 376.016336 -138.114309)
			(xy 376.039348 -138.099056) (xy 376.051318 -138.09218) (xy 376.051572 -138.09218) (xy 376.059695 -138.087119)
			(xy 376.071697 -138.072229) (xy 376.07494 -138.063224) (xy 376.095768 -137.997438) (xy 376.098269 -137.988288)
			(xy 376.097111 -137.96937) (xy 376.093482 -137.960608) (xy 376.08218 -137.935237) (xy 376.066223 -137.88204)
			(xy 376.058166 -137.827088) (xy 376.057668 -137.799318) (xy 376.058195 -137.772068) (xy 376.065948 -137.718123)
			(xy 376.0813 -137.665831) (xy 376.103937 -137.616255) (xy 376.133399 -137.570406) (xy 376.169087 -137.529216)
			(xy 376.210272 -137.493525) (xy 376.256118 -137.464057) (xy 376.305691 -137.441415) (xy 376.357982 -137.426057)
			(xy 376.411926 -137.418298) (xy 376.439176 -137.41781) (xy 376.463206 -137.418166) (xy 376.510884 -137.424213)
			(xy 376.557425 -137.436202) (xy 376.579892 -137.444734) (xy 376.588528 -137.44829) (xy 376.60707 -137.448544)
			(xy 376.679206 -137.422382) (xy 376.687693 -137.418853) (xy 376.701619 -137.406875) (xy 376.706384 -137.399014)
			(xy 376.706638 -137.399014) (xy 376.706638 -137.398506) (xy 376.721085 -137.373101) (xy 376.756578 -137.326669)
			(xy 376.798733 -137.286189) (xy 376.846565 -137.252607) (xy 376.898956 -137.226708) (xy 376.954683 -137.209096)
			(xy 377.012442 -137.200183) (xy 377.041664 -137.199624) (xy 377.068921 -137.20002) (xy 377.12288 -137.207774)
			(xy 377.175187 -137.223128) (xy 377.224776 -137.245771) (xy 377.270637 -137.27524) (xy 377.311838 -137.310937)
			(xy 377.347538 -137.352134) (xy 377.377012 -137.397993) (xy 377.399659 -137.447579) (xy 377.415018 -137.499885)
			(xy 377.422777 -137.553843) (xy 377.422777 -137.608357) (xy 377.415018 -137.662315) (xy 377.399659 -137.714621)
			(xy 377.377012 -137.764207) (xy 377.347538 -137.810066) (xy 377.314594 -137.848083) (xy 377.700412 -137.848083)
			(xy 377.708165 -137.794125) (xy 377.723517 -137.74182) (xy 377.746157 -137.692232) (xy 377.775624 -137.646371)
			(xy 377.811317 -137.605171) (xy 377.852511 -137.569469) (xy 377.898366 -137.539993) (xy 377.947949 -137.517344)
			(xy 378.000251 -137.501981) (xy 378.054207 -137.494218) (xy 378.108719 -137.494212) (xy 378.162676 -137.501965)
			(xy 378.214981 -137.517317) (xy 378.264569 -137.539958) (xy 378.31043 -137.569424) (xy 378.35163 -137.605118)
			(xy 378.387332 -137.646312) (xy 378.416807 -137.692167) (xy 378.439457 -137.74175) (xy 378.45482 -137.794052)
			(xy 378.462582 -137.848008) (xy 378.463048 -137.875264) (xy 378.463048 -137.884662) (xy 378.462794 -137.895584)
			(xy 378.470922 -137.91565) (xy 378.543312 -137.982452) (xy 378.563886 -137.98931) (xy 378.574554 -137.988294)
			(xy 378.612908 -137.986262) (xy 378.640161 -137.986764) (xy 378.694111 -137.994522) (xy 378.746408 -138.009879)
			(xy 378.795987 -138.032523) (xy 378.841839 -138.061992) (xy 378.88303 -138.097686) (xy 378.918722 -138.13888)
			(xy 378.948188 -138.184734) (xy 378.970829 -138.234314) (xy 378.986183 -138.286612) (xy 378.993938 -138.340563)
			(xy 378.993936 -138.395068) (xy 378.986176 -138.449018) (xy 378.970818 -138.501315) (xy 378.948174 -138.550893)
			(xy 378.918704 -138.596745) (xy 378.883008 -138.637935) (xy 378.841814 -138.673627) (xy 378.79596 -138.703092)
			(xy 378.746379 -138.725732) (xy 378.694081 -138.741084) (xy 378.64013 -138.748838) (xy 378.585625 -138.748835)
			(xy 378.531675 -138.741075) (xy 378.479378 -138.725716) (xy 378.4298 -138.70307) (xy 378.383949 -138.673599)
			(xy 378.342759 -138.637903) (xy 378.307069 -138.596708) (xy 378.277605 -138.550854) (xy 378.254966 -138.501272)
			(xy 378.239614 -138.448974) (xy 378.231861 -138.395023) (xy 378.2314 -138.36777) (xy 378.2314 -138.358372)
			(xy 378.231654 -138.34745) (xy 378.223526 -138.327384) (xy 378.151136 -138.260582) (xy 378.130562 -138.253724)
			(xy 378.119894 -138.25474) (xy 378.08154 -138.256772) (xy 378.054284 -138.256388) (xy 378.000327 -138.248636)
			(xy 377.948021 -138.233283) (xy 377.898434 -138.210644) (xy 377.852573 -138.181177) (xy 377.811372 -138.145484)
			(xy 377.77567 -138.104291) (xy 377.746194 -138.058436) (xy 377.723544 -138.008852) (xy 377.708181 -137.95655)
			(xy 377.700418 -137.902594) (xy 377.700412 -137.848083) (xy 377.314594 -137.848083) (xy 377.311838 -137.851263)
			(xy 377.270637 -137.88696) (xy 377.224776 -137.916429) (xy 377.175187 -137.939072) (xy 377.12288 -137.954426)
			(xy 377.068921 -137.96218) (xy 377.041664 -137.96264) (xy 377.017634 -137.962275) (xy 376.969956 -137.956232)
			(xy 376.923416 -137.944246) (xy 376.900948 -137.935716) (xy 376.892312 -137.93216) (xy 376.87377 -137.931906)
			(xy 376.801634 -137.958068) (xy 376.793145 -137.961594) (xy 376.779219 -137.973573) (xy 376.774456 -137.981436)
			(xy 376.774202 -137.981436) (xy 376.774202 -137.981944) (xy 376.761061 -138.005019) (xy 376.729399 -138.04765)
			(xy 376.692144 -138.085489) (xy 376.650011 -138.11781) (xy 376.627136 -138.131296) (xy 376.626882 -138.131296)
			(xy 376.618776 -138.136379) (xy 376.606763 -138.151253) (xy 376.603514 -138.160252) (xy 376.582686 -138.226038)
			(xy 376.580148 -138.23518) (xy 376.581331 -138.254105) (xy 376.584972 -138.262868) (xy 376.596264 -138.288243)
			(xy 376.612225 -138.341439) (xy 376.620286 -138.396389) (xy 376.620786 -138.424158) (xy 376.620306 -138.451411)
			(xy 376.612554 -138.505362) (xy 376.597202 -138.557661) (xy 376.574563 -138.607243) (xy 376.545097 -138.653097)
			(xy 376.509405 -138.694291) (xy 376.468213 -138.729985) (xy 376.42236 -138.759453) (xy 376.37278 -138.782095)
			(xy 376.320482 -138.797449) (xy 376.266531 -138.805204) (xy 376.239278 -138.805666) (xy 376.211639 -138.805214)
			(xy 376.156943 -138.797212) (xy 376.103971 -138.781409) (xy 376.053831 -138.758135) (xy 376.007571 -138.727875)
			(xy 375.966156 -138.691261) (xy 375.930452 -138.64906) (xy 375.901206 -138.602152) (xy 375.879027 -138.551518)
			(xy 375.871232 -138.524996) (xy 375.86793 -138.51255) (xy 375.850658 -138.494262) (xy 375.746264 -138.459464)
			(xy 375.721118 -138.463782) (xy 375.711212 -138.471656) (xy 375.691075 -138.486752) (xy 375.647602 -138.512108)
			(xy 375.60117 -138.53152) (xy 375.552586 -138.544648) (xy 375.502696 -138.551266) (xy 375.477532 -138.551666)
			(xy 375.477278 -138.551666) (xy 375.450025 -138.551263) (xy 375.396073 -138.543503) (xy 375.343776 -138.528144)
			(xy 375.294196 -138.505499) (xy 375.248343 -138.476029) (xy 375.207151 -138.440334) (xy 375.171458 -138.399139)
			(xy 375.14199 -138.353285) (xy 375.119348 -138.303704) (xy 375.103993 -138.251405) (xy 375.096236 -138.197453)
			(xy 372.073186 -138.197453) (xy 372.099477 -138.237192) (xy 372.123149 -138.287689) (xy 372.139217 -138.341096)
			(xy 372.147337 -138.396272) (xy 372.147846 -138.424158) (xy 372.147337 -138.452044) (xy 372.139217 -138.50722)
			(xy 372.123149 -138.560627) (xy 372.099477 -138.611124) (xy 372.068704 -138.657637) (xy 372.031487 -138.699174)
			(xy 371.988619 -138.734849) (xy 371.941013 -138.763903) (xy 371.889684 -138.785715) (xy 371.835727 -138.799821)
			(xy 371.78029 -138.805921) (xy 371.724556 -138.803884) (xy 371.669713 -138.793754) (xy 371.616929 -138.775747)
			(xy 371.567329 -138.750246) (xy 371.521971 -138.717795) (xy 371.481822 -138.679086) (xy 371.447736 -138.634943)
			(xy 371.42044 -138.586308) (xy 371.400517 -138.534217) (xy 371.388391 -138.47978) (xy 371.38432 -138.424158)
			(xy 366.383316 -138.424158) (xy 366.383316 -139.178792) (xy 373.863614 -139.178792) (xy 373.867685 -139.12317)
			(xy 373.879811 -139.068733) (xy 373.899734 -139.016642) (xy 373.92703 -138.968007) (xy 373.961116 -138.923864)
			(xy 374.001265 -138.885155) (xy 374.046623 -138.852704) (xy 374.096223 -138.827203) (xy 374.149007 -138.809196)
			(xy 374.20385 -138.799066) (xy 374.259584 -138.797029) (xy 374.315021 -138.803129) (xy 374.368978 -138.817235)
			(xy 374.420307 -138.839047) (xy 374.467913 -138.868101) (xy 374.510781 -138.903776) (xy 374.547998 -138.945313)
			(xy 374.578771 -138.991826) (xy 374.602443 -139.042323) (xy 374.618511 -139.09573) (xy 374.622511 -139.122912)
			(xy 375.06732 -139.122912) (xy 375.071391 -139.06729) (xy 375.083517 -139.012853) (xy 375.10344 -138.960762)
			(xy 375.130736 -138.912127) (xy 375.164822 -138.867984) (xy 375.204971 -138.829275) (xy 375.250329 -138.796824)
			(xy 375.299929 -138.771323) (xy 375.352713 -138.753316) (xy 375.407556 -138.743186) (xy 375.46329 -138.741149)
			(xy 375.518727 -138.747249) (xy 375.572684 -138.761355) (xy 375.624013 -138.783167) (xy 375.671619 -138.812221)
			(xy 375.714487 -138.847896) (xy 375.751704 -138.889433) (xy 375.782477 -138.935946) (xy 375.806149 -138.986443)
			(xy 375.822217 -139.03985) (xy 375.830337 -139.095026) (xy 375.830846 -139.122912) (xy 375.830337 -139.150798)
			(xy 375.825133 -139.186158) (xy 384.74726 -139.186158) (xy 384.751331 -139.130536) (xy 384.763457 -139.076099)
			(xy 384.78338 -139.024008) (xy 384.810676 -138.975373) (xy 384.844762 -138.93123) (xy 384.884911 -138.892521)
			(xy 384.930269 -138.86007) (xy 384.979869 -138.834569) (xy 385.032653 -138.816562) (xy 385.087496 -138.806432)
			(xy 385.14323 -138.804395) (xy 385.198667 -138.810495) (xy 385.252624 -138.824601) (xy 385.303953 -138.846413)
			(xy 385.351559 -138.875467) (xy 385.394427 -138.911142) (xy 385.417581 -138.936984) (xy 399.28368 -138.936984)
			(xy 399.287751 -138.881362) (xy 399.299877 -138.826925) (xy 399.3198 -138.774834) (xy 399.347096 -138.726199)
			(xy 399.381182 -138.682056) (xy 399.421331 -138.643347) (xy 399.466689 -138.610896) (xy 399.516289 -138.585395)
			(xy 399.569073 -138.567388) (xy 399.623916 -138.557258) (xy 399.67965 -138.555221) (xy 399.735087 -138.561321)
			(xy 399.789044 -138.575427) (xy 399.840373 -138.597239) (xy 399.887979 -138.626293) (xy 399.930847 -138.661968)
			(xy 399.968064 -138.703505) (xy 399.998837 -138.750018) (xy 400.022509 -138.800515) (xy 400.038577 -138.853922)
			(xy 400.046697 -138.909098) (xy 400.047206 -138.936984) (xy 400.046697 -138.96487) (xy 400.038577 -139.020046)
			(xy 400.022509 -139.073453) (xy 399.998837 -139.12395) (xy 399.968064 -139.170463) (xy 399.930847 -139.212)
			(xy 399.887979 -139.247675) (xy 399.840373 -139.276729) (xy 399.789044 -139.298541) (xy 399.735087 -139.312647)
			(xy 399.67965 -139.318747) (xy 399.623916 -139.31671) (xy 399.569073 -139.30658) (xy 399.516289 -139.288573)
			(xy 399.466689 -139.263072) (xy 399.421331 -139.230621) (xy 399.381182 -139.191912) (xy 399.347096 -139.147769)
			(xy 399.3198 -139.099134) (xy 399.299877 -139.047043) (xy 399.287751 -138.992606) (xy 399.28368 -138.936984)
			(xy 385.417581 -138.936984) (xy 385.431644 -138.952679) (xy 385.462417 -138.999192) (xy 385.486089 -139.049689)
			(xy 385.502157 -139.103096) (xy 385.510277 -139.158272) (xy 385.510786 -139.186158) (xy 385.510277 -139.214044)
			(xy 385.502157 -139.26922) (xy 385.486089 -139.322627) (xy 385.462417 -139.373124) (xy 385.431644 -139.419637)
			(xy 385.394427 -139.461174) (xy 385.351559 -139.496849) (xy 385.303953 -139.525903) (xy 385.252624 -139.547715)
			(xy 385.198667 -139.561821) (xy 385.14323 -139.567921) (xy 385.087496 -139.565884) (xy 385.032653 -139.555754)
			(xy 384.979869 -139.537747) (xy 384.930269 -139.512246) (xy 384.884911 -139.479795) (xy 384.844762 -139.441086)
			(xy 384.810676 -139.396943) (xy 384.78338 -139.348308) (xy 384.763457 -139.296217) (xy 384.751331 -139.24178)
			(xy 384.74726 -139.186158) (xy 375.825133 -139.186158) (xy 375.822217 -139.205974) (xy 375.806149 -139.259381)
			(xy 375.782477 -139.309878) (xy 375.751704 -139.356391) (xy 375.714487 -139.397928) (xy 375.671619 -139.433603)
			(xy 375.624013 -139.462657) (xy 375.572684 -139.484469) (xy 375.518727 -139.498575) (xy 375.46329 -139.504675)
			(xy 375.407556 -139.502638) (xy 375.352713 -139.492508) (xy 375.299929 -139.474501) (xy 375.250329 -139.449)
			(xy 375.204971 -139.416549) (xy 375.164822 -139.37784) (xy 375.130736 -139.333697) (xy 375.10344 -139.285062)
			(xy 375.083517 -139.232971) (xy 375.071391 -139.178534) (xy 375.06732 -139.122912) (xy 374.622511 -139.122912)
			(xy 374.626631 -139.150906) (xy 374.62714 -139.178792) (xy 374.626631 -139.206678) (xy 374.618511 -139.261854)
			(xy 374.602443 -139.315261) (xy 374.578771 -139.365758) (xy 374.547998 -139.412271) (xy 374.510781 -139.453808)
			(xy 374.467913 -139.489483) (xy 374.420307 -139.518537) (xy 374.368978 -139.540349) (xy 374.315021 -139.554455)
			(xy 374.259584 -139.560555) (xy 374.20385 -139.558518) (xy 374.149007 -139.548388) (xy 374.096223 -139.530381)
			(xy 374.046623 -139.50488) (xy 374.001265 -139.472429) (xy 373.961116 -139.43372) (xy 373.92703 -139.389577)
			(xy 373.899734 -139.340942) (xy 373.879811 -139.288851) (xy 373.867685 -139.234414) (xy 373.863614 -139.178792)
			(xy 366.383316 -139.178792) (xy 366.383316 -140.015214) (xy 373.57126 -140.015214) (xy 373.575331 -139.959592)
			(xy 373.587457 -139.905155) (xy 373.60738 -139.853064) (xy 373.634676 -139.804429) (xy 373.668762 -139.760286)
			(xy 373.708911 -139.721577) (xy 373.754269 -139.689126) (xy 373.803869 -139.663625) (xy 373.856653 -139.645618)
			(xy 373.911496 -139.635488) (xy 373.96723 -139.633451) (xy 374.022667 -139.639551) (xy 374.076624 -139.653657)
			(xy 374.127953 -139.675469) (xy 374.175559 -139.704523) (xy 374.188132 -139.714986) (xy 382.423668 -139.714986)
			(xy 382.427739 -139.659364) (xy 382.439865 -139.604927) (xy 382.459788 -139.552836) (xy 382.487084 -139.504201)
			(xy 382.52117 -139.460058) (xy 382.561319 -139.421349) (xy 382.606677 -139.388898) (xy 382.656277 -139.363397)
			(xy 382.709061 -139.34539) (xy 382.763904 -139.33526) (xy 382.819638 -139.333223) (xy 382.875075 -139.339323)
			(xy 382.929032 -139.353429) (xy 382.980361 -139.375241) (xy 383.027967 -139.404295) (xy 383.070835 -139.43997)
			(xy 383.108052 -139.481507) (xy 383.138825 -139.52802) (xy 383.162497 -139.578517) (xy 383.178565 -139.631924)
			(xy 383.186685 -139.6871) (xy 383.187194 -139.714986) (xy 383.186685 -139.742872) (xy 383.178565 -139.798048)
			(xy 383.162497 -139.851455) (xy 383.138825 -139.901952) (xy 383.108052 -139.948465) (xy 383.070835 -139.990002)
			(xy 383.027967 -140.025677) (xy 382.980361 -140.054731) (xy 382.929032 -140.076543) (xy 382.875075 -140.090649)
			(xy 382.819638 -140.096749) (xy 382.763904 -140.094712) (xy 382.709061 -140.084582) (xy 382.656277 -140.066575)
			(xy 382.606677 -140.041074) (xy 382.561319 -140.008623) (xy 382.52117 -139.969914) (xy 382.487084 -139.925771)
			(xy 382.459788 -139.877136) (xy 382.439865 -139.825045) (xy 382.427739 -139.770608) (xy 382.423668 -139.714986)
			(xy 374.188132 -139.714986) (xy 374.218427 -139.740198) (xy 374.255644 -139.781735) (xy 374.286417 -139.828248)
			(xy 374.310089 -139.878745) (xy 374.326157 -139.932152) (xy 374.334277 -139.987328) (xy 374.334786 -140.015214)
			(xy 374.334277 -140.0431) (xy 374.326157 -140.098276) (xy 374.310089 -140.151683) (xy 374.286427 -140.202158)
			(xy 384.767326 -140.202158) (xy 384.771397 -140.146536) (xy 384.783523 -140.092099) (xy 384.803446 -140.040008)
			(xy 384.830742 -139.991373) (xy 384.864828 -139.94723) (xy 384.904977 -139.908521) (xy 384.950335 -139.87607)
			(xy 384.999935 -139.850569) (xy 385.052719 -139.832562) (xy 385.107562 -139.822432) (xy 385.163296 -139.820395)
			(xy 385.218733 -139.826495) (xy 385.27269 -139.840601) (xy 385.324019 -139.862413) (xy 385.371625 -139.891467)
			(xy 385.414493 -139.927142) (xy 385.45171 -139.968679) (xy 385.482483 -140.015192) (xy 385.506155 -140.065689)
			(xy 385.522223 -140.119096) (xy 385.530343 -140.174272) (xy 385.530852 -140.202158) (xy 385.530343 -140.230044)
			(xy 385.522223 -140.28522) (xy 385.506155 -140.338627) (xy 385.482483 -140.389124) (xy 385.45171 -140.435637)
			(xy 385.414493 -140.477174) (xy 385.371625 -140.512849) (xy 385.324019 -140.541903) (xy 385.27269 -140.563715)
			(xy 385.218733 -140.577821) (xy 385.163296 -140.583921) (xy 385.107562 -140.581884) (xy 385.052719 -140.571754)
			(xy 384.999935 -140.553747) (xy 384.950335 -140.528246) (xy 384.904977 -140.495795) (xy 384.864828 -140.457086)
			(xy 384.830742 -140.412943) (xy 384.803446 -140.364308) (xy 384.783523 -140.312217) (xy 384.771397 -140.25778)
			(xy 384.767326 -140.202158) (xy 374.286427 -140.202158) (xy 374.286417 -140.20218) (xy 374.255644 -140.248693)
			(xy 374.218427 -140.29023) (xy 374.175559 -140.325905) (xy 374.127953 -140.354959) (xy 374.076624 -140.376771)
			(xy 374.022667 -140.390877) (xy 373.96723 -140.396977) (xy 373.911496 -140.39494) (xy 373.856653 -140.38481)
			(xy 373.803869 -140.366803) (xy 373.754269 -140.341302) (xy 373.708911 -140.308851) (xy 373.668762 -140.270142)
			(xy 373.634676 -140.225999) (xy 373.60738 -140.177364) (xy 373.587457 -140.125273) (xy 373.575331 -140.070836)
			(xy 373.57126 -140.015214) (xy 366.383316 -140.015214) (xy 366.383316 -140.975334) (xy 371.09273 -140.975334)
			(xy 371.093216 -140.948083) (xy 371.100972 -140.894135) (xy 371.116327 -140.84184) (xy 371.138969 -140.792263)
			(xy 371.168435 -140.746413) (xy 371.204126 -140.705222) (xy 371.245317 -140.669531) (xy 371.291167 -140.640065)
			(xy 371.340744 -140.617423) (xy 371.393039 -140.602068) (xy 371.446987 -140.594312) (xy 371.501489 -140.594312)
			(xy 371.555437 -140.602068) (xy 371.607732 -140.617423) (xy 371.657309 -140.640065) (xy 371.703159 -140.669531)
			(xy 371.74435 -140.705222) (xy 371.780041 -140.746413) (xy 371.809507 -140.792263) (xy 371.832149 -140.84184)
			(xy 371.847504 -140.894135) (xy 371.85526 -140.948083) (xy 371.855746 -140.975334) (xy 371.855138 -141.006232)
			(xy 371.845158 -141.067218) (xy 371.825464 -141.125793) (xy 371.81155 -141.153388) (xy 371.807592 -141.16189)
			(xy 371.805394 -141.180495) (xy 371.810034 -141.198645) (xy 371.82089 -141.213913) (xy 371.836509 -141.224256)
			(xy 371.854804 -141.22829) (xy 371.864128 -141.227302) (xy 371.878329 -141.225278) (xy 371.906934 -141.223116)
			(xy 371.921278 -141.222984) (xy 372.318026 -141.222984) (xy 372.348004 -141.223551) (xy 372.407221 -141.232946)
			(xy 372.46424 -141.251486) (xy 372.517658 -141.278714) (xy 372.566161 -141.313961) (xy 372.587774 -141.334744)
			(xy 373.449342 -142.196566) (xy 373.456738 -142.203412) (xy 373.47534 -142.211129) (xy 373.48541 -142.211552)
			(xy 373.927624 -142.211552) (xy 373.936768 -142.207742) (xy 373.961152 -142.198598) (xy 373.973598 -142.140432)
			(xy 373.975526 -142.12803) (xy 373.96862 -142.103932) (xy 373.96039 -142.094458) (xy 373.940268 -142.072959)
			(xy 373.906201 -142.024934) (xy 373.879915 -141.972245) (xy 373.862036 -141.916143) (xy 373.852987 -141.857961)
			(xy 373.85244 -141.82852) (xy 373.852894 -141.800916) (xy 373.860837 -141.746283) (xy 373.876574 -141.693366)
			(xy 373.899777 -141.643271) (xy 373.929959 -141.597044) (xy 373.966492 -141.555653) (xy 374.008611 -141.519962)
			(xy 374.031764 -141.504924) (xy 374.042087 -141.497686) (xy 374.054605 -141.475834) (xy 374.05564 -141.463268)
			(xy 374.057926 -141.378686) (xy 374.057546 -141.365981) (xy 374.0461 -141.343326) (xy 374.036082 -141.335506)
			(xy 374.014869 -141.320146) (xy 373.976466 -141.284535) (xy 373.943296 -141.244005) (xy 373.91598 -141.199319)
			(xy 373.895034 -141.151317) (xy 373.88085 -141.100901) (xy 373.873696 -141.049019) (xy 373.873268 -141.022832)
			(xy 373.873754 -140.995581) (xy 373.88151 -140.941633) (xy 373.896865 -140.889338) (xy 373.919507 -140.839761)
			(xy 373.948973 -140.793911) (xy 373.984664 -140.75272) (xy 374.025855 -140.717029) (xy 374.071705 -140.687563)
			(xy 374.121282 -140.664921) (xy 374.173577 -140.649566) (xy 374.227525 -140.64181) (xy 374.282027 -140.64181)
			(xy 374.335975 -140.649566) (xy 374.38827 -140.664921) (xy 374.437847 -140.687563) (xy 374.483697 -140.717029)
			(xy 374.524888 -140.75272) (xy 374.560579 -140.793911) (xy 374.571232 -140.810488) (xy 382.559558 -140.810488)
			(xy 382.563629 -140.754866) (xy 382.575755 -140.700429) (xy 382.595678 -140.648338) (xy 382.622974 -140.599703)
			(xy 382.65706 -140.55556) (xy 382.697209 -140.516851) (xy 382.742567 -140.4844) (xy 382.792167 -140.458899)
			(xy 382.844951 -140.440892) (xy 382.899794 -140.430762) (xy 382.955528 -140.428725) (xy 383.010965 -140.434825)
			(xy 383.064922 -140.448931) (xy 383.116251 -140.470743) (xy 383.163857 -140.499797) (xy 383.206725 -140.535472)
			(xy 383.243942 -140.577009) (xy 383.274715 -140.623522) (xy 383.298387 -140.674019) (xy 383.314455 -140.727426)
			(xy 383.322575 -140.782602) (xy 383.323084 -140.810488) (xy 383.322575 -140.838374) (xy 383.314455 -140.89355)
			(xy 383.298387 -140.946957) (xy 383.274715 -140.997454) (xy 383.243942 -141.043967) (xy 383.206725 -141.085504)
			(xy 383.163857 -141.121179) (xy 383.116251 -141.150233) (xy 383.064922 -141.172045) (xy 383.010965 -141.186151)
			(xy 382.955528 -141.192251) (xy 382.899794 -141.190214) (xy 382.844951 -141.180084) (xy 382.792167 -141.162077)
			(xy 382.742567 -141.136576) (xy 382.697209 -141.104125) (xy 382.65706 -141.065416) (xy 382.622974 -141.021273)
			(xy 382.595678 -140.972638) (xy 382.575755 -140.920547) (xy 382.563629 -140.86611) (xy 382.559558 -140.810488)
			(xy 374.571232 -140.810488) (xy 374.590045 -140.839761) (xy 374.612687 -140.889338) (xy 374.628042 -140.941633)
			(xy 374.635798 -140.995581) (xy 374.636284 -141.022832) (xy 374.635828 -141.050436) (xy 374.62789 -141.105071)
			(xy 374.612156 -141.15799) (xy 374.588955 -141.208086) (xy 374.558771 -141.254313) (xy 374.522237 -141.295703)
			(xy 374.505538 -141.309852) (xy 385.56006 -141.309852) (xy 385.564131 -141.25423) (xy 385.576257 -141.199793)
			(xy 385.59618 -141.147702) (xy 385.623476 -141.099067) (xy 385.657562 -141.054924) (xy 385.697711 -141.016215)
			(xy 385.743069 -140.983764) (xy 385.792669 -140.958263) (xy 385.845453 -140.940256) (xy 385.900296 -140.930126)
			(xy 385.95603 -140.928089) (xy 386.011467 -140.934189) (xy 386.065424 -140.948295) (xy 386.116753 -140.970107)
			(xy 386.164359 -140.999161) (xy 386.207227 -141.034836) (xy 386.244444 -141.076373) (xy 386.275217 -141.122886)
			(xy 386.298889 -141.173383) (xy 386.312666 -141.219174) (xy 388.955278 -141.219174) (xy 388.959349 -141.163552)
			(xy 388.971475 -141.109115) (xy 388.991398 -141.057024) (xy 389.018694 -141.008389) (xy 389.05278 -140.964246)
			(xy 389.092929 -140.925537) (xy 389.138287 -140.893086) (xy 389.187887 -140.867585) (xy 389.240671 -140.849578)
			(xy 389.295514 -140.839448) (xy 389.351248 -140.837411) (xy 389.406685 -140.843511) (xy 389.460642 -140.857617)
			(xy 389.511971 -140.879429) (xy 389.559577 -140.908483) (xy 389.602445 -140.944158) (xy 389.639662 -140.985695)
			(xy 389.670435 -141.032208) (xy 389.694107 -141.082705) (xy 389.710175 -141.136112) (xy 389.718295 -141.191288)
			(xy 389.718804 -141.219174) (xy 389.718295 -141.24706) (xy 389.710175 -141.302236) (xy 389.705897 -141.316456)
			(xy 410.132274 -141.316456) (xy 410.136345 -141.260834) (xy 410.148471 -141.206397) (xy 410.168394 -141.154306)
			(xy 410.19569 -141.105671) (xy 410.229776 -141.061528) (xy 410.269925 -141.022819) (xy 410.315283 -140.990368)
			(xy 410.364883 -140.964867) (xy 410.417667 -140.94686) (xy 410.47251 -140.93673) (xy 410.528244 -140.934693)
			(xy 410.583681 -140.940793) (xy 410.637638 -140.954899) (xy 410.688967 -140.976711) (xy 410.736573 -141.005765)
			(xy 410.779441 -141.04144) (xy 410.816658 -141.082977) (xy 410.847431 -141.12949) (xy 410.871103 -141.179987)
			(xy 410.887171 -141.233394) (xy 410.895291 -141.28857) (xy 410.8958 -141.316456) (xy 410.895291 -141.344342)
			(xy 410.887171 -141.399518) (xy 410.871103 -141.452925) (xy 410.847431 -141.503422) (xy 410.816658 -141.549935)
			(xy 410.779441 -141.591472) (xy 410.736573 -141.627147) (xy 410.688967 -141.656201) (xy 410.637638 -141.678013)
			(xy 410.583681 -141.692119) (xy 410.528244 -141.698219) (xy 410.47251 -141.696182) (xy 410.417667 -141.686052)
			(xy 410.364883 -141.668045) (xy 410.315283 -141.642544) (xy 410.269925 -141.610093) (xy 410.229776 -141.571384)
			(xy 410.19569 -141.527241) (xy 410.168394 -141.478606) (xy 410.148471 -141.426515) (xy 410.136345 -141.372078)
			(xy 410.132274 -141.316456) (xy 389.705897 -141.316456) (xy 389.694107 -141.355643) (xy 389.670435 -141.40614)
			(xy 389.639662 -141.452653) (xy 389.602445 -141.49419) (xy 389.559577 -141.529865) (xy 389.511971 -141.558919)
			(xy 389.460642 -141.580731) (xy 389.406685 -141.594837) (xy 389.351248 -141.600937) (xy 389.295514 -141.5989)
			(xy 389.240671 -141.58877) (xy 389.187887 -141.570763) (xy 389.138287 -141.545262) (xy 389.092929 -141.512811)
			(xy 389.05278 -141.474102) (xy 389.018694 -141.429959) (xy 388.991398 -141.381324) (xy 388.971475 -141.329233)
			(xy 388.959349 -141.274796) (xy 388.955278 -141.219174) (xy 386.312666 -141.219174) (xy 386.314957 -141.22679)
			(xy 386.323077 -141.281966) (xy 386.323586 -141.309852) (xy 386.323077 -141.337738) (xy 386.314957 -141.392914)
			(xy 386.298889 -141.446321) (xy 386.275217 -141.496818) (xy 386.244444 -141.543331) (xy 386.207227 -141.584868)
			(xy 386.164359 -141.620543) (xy 386.116753 -141.649597) (xy 386.065424 -141.671409) (xy 386.011467 -141.685515)
			(xy 385.95603 -141.691615) (xy 385.900296 -141.689578) (xy 385.845453 -141.679448) (xy 385.792669 -141.661441)
			(xy 385.743069 -141.63594) (xy 385.697711 -141.603489) (xy 385.657562 -141.56478) (xy 385.623476 -141.520637)
			(xy 385.59618 -141.472002) (xy 385.576257 -141.419911) (xy 385.564131 -141.365474) (xy 385.56006 -141.309852)
			(xy 374.505538 -141.309852) (xy 374.480115 -141.331392) (xy 374.45696 -141.346428) (xy 374.446643 -141.353672)
			(xy 374.434125 -141.37552) (xy 374.433084 -141.388084) (xy 374.430798 -141.472666) (xy 374.431137 -141.485376)
			(xy 374.442611 -141.508031) (xy 374.452642 -141.515846) (xy 374.473838 -141.531228) (xy 374.51224 -141.566837)
			(xy 374.545411 -141.607363) (xy 374.572728 -141.652045) (xy 374.593677 -141.700043) (xy 374.607865 -141.750456)
			(xy 374.615025 -141.802335) (xy 374.615456 -141.82852) (xy 374.615074 -141.854604) (xy 374.607951 -141.906284)
			(xy 374.593855 -141.956511) (xy 374.573048 -142.004351) (xy 374.545918 -142.04891) (xy 374.512972 -142.089358)
			(xy 374.474822 -142.124941) (xy 374.432181 -142.154995) (xy 374.409208 -142.167356) (xy 374.408954 -142.167356)
			(xy 374.399351 -142.173146) (xy 374.385908 -142.191059) (xy 374.383046 -142.2019) (xy 374.36425 -142.290292)
			(xy 374.369838 -142.312644) (xy 374.37695 -142.32128) (xy 374.392879 -142.341747) (xy 374.419674 -142.38615)
			(xy 374.440209 -142.433773) (xy 374.454105 -142.483738) (xy 374.461108 -142.535125) (xy 374.461532 -142.561056)
			(xy 374.460986 -142.591028) (xy 374.451669 -142.650241) (xy 374.446578 -142.665958) (xy 382.22809 -142.665958)
			(xy 382.228538 -142.638717) (xy 382.236293 -142.584791) (xy 382.251641 -142.532516) (xy 382.274268 -142.482955)
			(xy 382.303715 -142.437117) (xy 382.339383 -142.395934) (xy 382.380546 -142.360244) (xy 382.426367 -142.330771)
			(xy 382.475915 -142.308116) (xy 382.528181 -142.292739) (xy 382.582104 -142.284953) (xy 382.609344 -142.28445)
			(xy 382.609852 -142.28445) (xy 382.626108 -142.284704) (xy 382.637538 -142.285212) (xy 382.659382 -142.275814)
			(xy 382.718818 -142.205964) (xy 382.725932 -142.196694) (xy 382.731629 -142.174061) (xy 382.72974 -142.16253)
			(xy 382.726084 -142.143563) (xy 382.722137 -142.105136) (xy 382.721866 -142.085822) (xy 382.721866 -142.08506)
			(xy 382.722352 -142.057809) (xy 382.730108 -142.003861) (xy 382.745463 -141.951566) (xy 382.768105 -141.901989)
			(xy 382.797571 -141.856139) (xy 382.833262 -141.814948) (xy 382.874453 -141.779257) (xy 382.920303 -141.749791)
			(xy 382.96988 -141.727149) (xy 383.022175 -141.711794) (xy 383.076123 -141.704038) (xy 383.130625 -141.704038)
			(xy 383.184573 -141.711794) (xy 383.236868 -141.727149) (xy 383.286445 -141.749791) (xy 383.332295 -141.779257)
			(xy 383.373486 -141.814948) (xy 383.409177 -141.856139) (xy 383.438643 -141.901989) (xy 383.461285 -141.951566)
			(xy 383.47664 -142.003861) (xy 383.484396 -142.057809) (xy 383.484882 -142.08506) (xy 383.484385 -142.1123)
			(xy 383.47664 -142.166226) (xy 383.461302 -142.218502) (xy 383.438682 -142.268064) (xy 383.413639 -142.307056)
			(xy 387.692644 -142.307056) (xy 387.696715 -142.251434) (xy 387.708841 -142.196997) (xy 387.728764 -142.144906)
			(xy 387.75606 -142.096271) (xy 387.790146 -142.052128) (xy 387.830295 -142.013419) (xy 387.875653 -141.980968)
			(xy 387.925253 -141.955467) (xy 387.978037 -141.93746) (xy 388.03288 -141.92733) (xy 388.088614 -141.925293)
			(xy 388.144051 -141.931393) (xy 388.198008 -141.945499) (xy 388.249337 -141.967311) (xy 388.256237 -141.971522)
			(xy 390.700004 -141.971522) (xy 390.704075 -141.9159) (xy 390.716201 -141.861463) (xy 390.736124 -141.809372)
			(xy 390.76342 -141.760737) (xy 390.797506 -141.716594) (xy 390.837655 -141.677885) (xy 390.883013 -141.645434)
			(xy 390.932613 -141.619933) (xy 390.985397 -141.601926) (xy 391.04024 -141.591796) (xy 391.095974 -141.589759)
			(xy 391.151411 -141.595859) (xy 391.205368 -141.609965) (xy 391.256697 -141.631777) (xy 391.304303 -141.660831)
			(xy 391.347171 -141.696506) (xy 391.384388 -141.738043) (xy 391.415161 -141.784556) (xy 391.438833 -141.835053)
			(xy 391.454901 -141.88846) (xy 391.463021 -141.943636) (xy 391.46353 -141.971522) (xy 391.463021 -141.999408)
			(xy 391.454901 -142.054584) (xy 391.438833 -142.107991) (xy 391.415161 -142.158488) (xy 391.384388 -142.205001)
			(xy 391.347171 -142.246538) (xy 391.304303 -142.282213) (xy 391.256697 -142.311267) (xy 391.205368 -142.333079)
			(xy 391.151411 -142.347185) (xy 391.095974 -142.353285) (xy 391.04024 -142.351248) (xy 390.985397 -142.341118)
			(xy 390.932613 -142.323111) (xy 390.883013 -142.29761) (xy 390.837655 -142.265159) (xy 390.797506 -142.22645)
			(xy 390.76342 -142.182307) (xy 390.736124 -142.133672) (xy 390.716201 -142.081581) (xy 390.704075 -142.027144)
			(xy 390.700004 -141.971522) (xy 388.256237 -141.971522) (xy 388.296943 -141.996365) (xy 388.339811 -142.03204)
			(xy 388.377028 -142.073577) (xy 388.407801 -142.12009) (xy 388.431473 -142.170587) (xy 388.447541 -142.223994)
			(xy 388.455661 -142.27917) (xy 388.45617 -142.307056) (xy 388.455661 -142.334942) (xy 388.447541 -142.390118)
			(xy 388.431473 -142.443525) (xy 388.407801 -142.494022) (xy 388.377028 -142.540535) (xy 388.339811 -142.582072)
			(xy 388.296943 -142.617747) (xy 388.249337 -142.646801) (xy 388.198008 -142.668613) (xy 388.144051 -142.682719)
			(xy 388.088614 -142.688819) (xy 388.03288 -142.686782) (xy 387.978037 -142.676652) (xy 387.925253 -142.658645)
			(xy 387.875653 -142.633144) (xy 387.830295 -142.600693) (xy 387.790146 -142.561984) (xy 387.75606 -142.517841)
			(xy 387.728764 -142.469206) (xy 387.708841 -142.417115) (xy 387.696715 -142.362678) (xy 387.692644 -142.307056)
			(xy 383.413639 -142.307056) (xy 383.409241 -142.313903) (xy 383.373578 -142.355088) (xy 383.332418 -142.39078)
			(xy 383.286599 -142.420253) (xy 383.237053 -142.442908) (xy 383.184788 -142.458283) (xy 383.130868 -142.466066)
			(xy 383.103628 -142.466568) (xy 383.10312 -142.466568) (xy 383.086864 -142.466314) (xy 383.075434 -142.465806)
			(xy 383.05359 -142.475204) (xy 382.994154 -142.545054) (xy 382.987027 -142.554316) (xy 382.981339 -142.576956)
			(xy 382.983232 -142.588488) (xy 382.986892 -142.607454) (xy 382.990836 -142.645882) (xy 382.991106 -142.665196)
			(xy 382.991106 -142.665958) (xy 382.990505 -142.695943) (xy 382.983157 -142.742158) (xy 385.5245 -142.742158)
			(xy 385.528571 -142.686536) (xy 385.540697 -142.632099) (xy 385.56062 -142.580008) (xy 385.587916 -142.531373)
			(xy 385.622002 -142.48723) (xy 385.662151 -142.448521) (xy 385.707509 -142.41607) (xy 385.757109 -142.390569)
			(xy 385.809893 -142.372562) (xy 385.864736 -142.362432) (xy 385.92047 -142.360395) (xy 385.975907 -142.366495)
			(xy 386.029864 -142.380601) (xy 386.081193 -142.402413) (xy 386.128799 -142.431467) (xy 386.171667 -142.467142)
			(xy 386.208884 -142.508679) (xy 386.239657 -142.555192) (xy 386.263329 -142.605689) (xy 386.279397 -142.659096)
			(xy 386.287517 -142.714272) (xy 386.288026 -142.742158) (xy 386.287517 -142.770044) (xy 386.279397 -142.82522)
			(xy 386.263329 -142.878627) (xy 386.239657 -142.929124) (xy 386.208884 -142.975637) (xy 386.19687 -142.989046)
			(xy 388.931912 -142.989046) (xy 388.932398 -142.961795) (xy 388.940154 -142.907847) (xy 388.955509 -142.855552)
			(xy 388.978151 -142.805975) (xy 389.007617 -142.760125) (xy 389.043308 -142.718934) (xy 389.084499 -142.683243)
			(xy 389.130349 -142.653777) (xy 389.179926 -142.631135) (xy 389.232221 -142.61578) (xy 389.286169 -142.608024)
			(xy 389.340671 -142.608024) (xy 389.394619 -142.61578) (xy 389.446914 -142.631135) (xy 389.496491 -142.653777)
			(xy 389.542341 -142.683243) (xy 389.583532 -142.718934) (xy 389.611358 -142.751048) (xy 392.29868 -142.751048)
			(xy 392.302751 -142.695426) (xy 392.314877 -142.640989) (xy 392.3348 -142.588898) (xy 392.362096 -142.540263)
			(xy 392.396182 -142.49612) (xy 392.436331 -142.457411) (xy 392.481689 -142.42496) (xy 392.531289 -142.399459)
			(xy 392.584073 -142.381452) (xy 392.638916 -142.371322) (xy 392.69465 -142.369285) (xy 392.750087 -142.375385)
			(xy 392.804044 -142.389491) (xy 392.855373 -142.411303) (xy 392.902979 -142.440357) (xy 392.945847 -142.476032)
			(xy 392.983064 -142.517569) (xy 393.013837 -142.564082) (xy 393.037509 -142.614579) (xy 393.053577 -142.667986)
			(xy 393.061697 -142.723162) (xy 393.062206 -142.751048) (xy 393.061697 -142.778934) (xy 393.053577 -142.83411)
			(xy 393.037509 -142.887517) (xy 393.013837 -142.938014) (xy 392.983064 -142.984527) (xy 392.945847 -143.026064)
			(xy 392.902979 -143.061739) (xy 392.855373 -143.090793) (xy 392.804044 -143.112605) (xy 392.750087 -143.126711)
			(xy 392.69465 -143.132811) (xy 392.638916 -143.130774) (xy 392.584073 -143.120644) (xy 392.531289 -143.102637)
			(xy 392.481689 -143.077136) (xy 392.436331 -143.044685) (xy 392.396182 -143.005976) (xy 392.362096 -142.961833)
			(xy 392.3348 -142.913198) (xy 392.314877 -142.861107) (xy 392.302751 -142.80667) (xy 392.29868 -142.751048)
			(xy 389.611358 -142.751048) (xy 389.619223 -142.760125) (xy 389.648689 -142.805975) (xy 389.671331 -142.855552)
			(xy 389.686686 -142.907847) (xy 389.694442 -142.961795) (xy 389.694928 -142.989046) (xy 389.69442 -143.008096)
			(xy 389.694231 -143.021559) (xy 389.699969 -143.047851) (xy 389.71237 -143.071735) (xy 389.730574 -143.091555)
			(xy 389.75332 -143.105937) (xy 389.779032 -143.113884) (xy 389.792464 -143.114776) (xy 389.819095 -143.116143)
			(xy 389.871619 -143.125347) (xy 389.922349 -143.141777) (xy 389.970296 -143.165112) (xy 390.014525 -143.194899)
			(xy 390.054174 -143.230556) (xy 390.08847 -143.271388) (xy 390.116745 -143.316598) (xy 390.138446 -143.365307)
			(xy 390.153152 -143.416563) (xy 390.160575 -143.469368) (xy 390.161018 -143.49603) (xy 390.160532 -143.523281)
			(xy 390.152776 -143.577229) (xy 390.137421 -143.629524) (xy 390.114779 -143.679101) (xy 390.085313 -143.724951)
			(xy 390.049622 -143.766142) (xy 390.008431 -143.801833) (xy 389.962581 -143.831299) (xy 389.913004 -143.853941)
			(xy 389.860709 -143.869296) (xy 389.806761 -143.877052) (xy 389.752259 -143.877052) (xy 389.698311 -143.869296)
			(xy 389.646016 -143.853941) (xy 389.596439 -143.831299) (xy 389.550589 -143.801833) (xy 389.509398 -143.766142)
			(xy 389.473707 -143.724951) (xy 389.444241 -143.679101) (xy 389.421599 -143.629524) (xy 389.406244 -143.577229)
			(xy 389.398488 -143.523281) (xy 389.398002 -143.49603) (xy 389.39851 -143.47698) (xy 389.398788 -143.463515)
			(xy 389.39304 -143.43721) (xy 389.380624 -143.413318) (xy 389.362401 -143.393496) (xy 389.339635 -143.379119)
			(xy 389.313906 -143.371183) (xy 389.300466 -143.3703) (xy 389.273829 -143.36902) (xy 389.221302 -143.359806)
			(xy 389.170569 -143.343366) (xy 389.122621 -143.32002) (xy 389.078391 -143.290224) (xy 389.038743 -143.254559)
			(xy 389.004448 -143.213719) (xy 388.976175 -143.1685) (xy 388.954476 -143.119785) (xy 388.939773 -143.068522)
			(xy 388.932353 -143.015711) (xy 388.931912 -142.989046) (xy 386.19687 -142.989046) (xy 386.171667 -143.017174)
			(xy 386.128799 -143.052849) (xy 386.081193 -143.081903) (xy 386.029864 -143.103715) (xy 385.975907 -143.117821)
			(xy 385.92047 -143.123921) (xy 385.864736 -143.121884) (xy 385.809893 -143.111754) (xy 385.757109 -143.093747)
			(xy 385.707509 -143.068246) (xy 385.662151 -143.035795) (xy 385.622002 -142.997086) (xy 385.587916 -142.952943)
			(xy 385.56062 -142.904308) (xy 385.540697 -142.852217) (xy 385.528571 -142.79778) (xy 385.5245 -142.742158)
			(xy 382.983157 -142.742158) (xy 382.981088 -142.755171) (xy 382.962541 -142.812202) (xy 382.94945 -142.839186)
			(xy 382.944869 -142.849292) (xy 382.944096 -142.871443) (xy 382.947926 -142.881858) (xy 382.98247 -142.9639)
			(xy 382.999234 -142.978886) (xy 383.009902 -142.982188) (xy 383.035496 -142.990596) (xy 383.084189 -143.013642)
			(xy 383.129157 -143.043308) (xy 383.169505 -143.079004) (xy 383.204431 -143.12002) (xy 383.233242 -143.165541)
			(xy 383.255363 -143.214661) (xy 383.270356 -143.266404) (xy 383.277922 -143.319742) (xy 383.27838 -143.346678)
			(xy 383.277894 -143.373929) (xy 383.270138 -143.427877) (xy 383.254783 -143.480172) (xy 383.232141 -143.529749)
			(xy 383.202675 -143.575599) (xy 383.166984 -143.61679) (xy 383.125793 -143.652481) (xy 383.079943 -143.681947)
			(xy 383.030366 -143.704589) (xy 382.978071 -143.719944) (xy 382.924123 -143.7277) (xy 382.869621 -143.7277)
			(xy 382.815673 -143.719944) (xy 382.763378 -143.704589) (xy 382.713801 -143.681947) (xy 382.667951 -143.652481)
			(xy 382.62676 -143.61679) (xy 382.591069 -143.575599) (xy 382.561603 -143.529749) (xy 382.538961 -143.480172)
			(xy 382.523606 -143.427877) (xy 382.51585 -143.373929) (xy 382.515364 -143.346678) (xy 382.515982 -143.316694)
			(xy 382.525393 -143.257467) (xy 382.543933 -143.200435) (xy 382.55702 -143.17345) (xy 382.561576 -143.163336)
			(xy 382.562363 -143.141193) (xy 382.558544 -143.130778) (xy 382.524 -143.048736) (xy 382.507236 -143.03375)
			(xy 382.496568 -143.030448) (xy 382.470979 -143.022027) (xy 382.422288 -142.99898) (xy 382.377323 -142.969314)
			(xy 382.336976 -142.933619) (xy 382.30205 -142.892605) (xy 382.273239 -142.847087) (xy 382.251116 -142.797969)
			(xy 382.23612 -142.746228) (xy 382.22855 -142.692893) (xy 382.22809 -142.665958) (xy 374.446578 -142.665958)
			(xy 374.433196 -142.707266) (xy 374.406021 -142.760694) (xy 374.370815 -142.809208) (xy 374.350026 -142.830804)
			(xy 374.318276 -142.862554) (xy 374.296681 -142.883265) (xy 374.248257 -142.918408) (xy 374.194942 -142.945561)
			(xy 374.138041 -142.96406) (xy 374.078951 -142.973451) (xy 374.049036 -142.97406) (xy 373.305832 -142.97406)
			(xy 373.275913 -142.973471) (xy 373.216812 -142.964105) (xy 373.159903 -142.945614) (xy 373.106584 -142.918453)
			(xy 373.058168 -142.88329) (xy 373.036592 -142.862554) (xy 372.175024 -142.000986) (xy 372.167611 -141.994162)
			(xy 372.149022 -141.986434) (xy 372.138956 -141.986) (xy 371.921278 -141.986) (xy 371.894033 -141.985511)
			(xy 371.840099 -141.977751) (xy 371.787819 -141.962392) (xy 371.738258 -141.939747) (xy 371.692426 -141.910277)
			(xy 371.651255 -141.874582) (xy 371.615585 -141.83339) (xy 371.586143 -141.78754) (xy 371.563528 -141.737965)
			(xy 371.5482 -141.685676) (xy 371.540472 -141.631737) (xy 371.540024 -141.604492) (xy 371.540531 -141.575127)
			(xy 371.549459 -141.517081) (xy 371.557804 -141.488922) (xy 371.56136 -141.477492) (xy 371.557804 -141.454124)
			(xy 371.49659 -141.368018) (xy 371.475762 -141.356842) (xy 371.463824 -141.356588) (xy 371.437072 -141.355367)
			(xy 371.384267 -141.346461) (xy 371.333228 -141.330254) (xy 371.284959 -141.307065) (xy 371.240409 -141.27735)
			(xy 371.200456 -141.241693) (xy 371.165885 -141.200797) (xy 371.137377 -141.155465) (xy 371.115493 -141.10659)
			(xy 371.100663 -141.055134) (xy 371.093178 -141.002109) (xy 371.09273 -140.975334) (xy 366.383316 -140.975334)
			(xy 366.383316 -142.225014) (xy 366.384078 -142.233904) (xy 366.386364 -142.246858) (xy 366.387634 -142.250668)
			(xy 366.397545 -142.281023) (xy 366.40827 -142.343966) (xy 366.40897 -142.37589) (xy 366.408484 -142.403141)
			(xy 366.400728 -142.457089) (xy 366.391605 -142.488158) (xy 371.53926 -142.488158) (xy 371.543331 -142.432536)
			(xy 371.555457 -142.378099) (xy 371.57538 -142.326008) (xy 371.602676 -142.277373) (xy 371.636762 -142.23323)
			(xy 371.676911 -142.194521) (xy 371.722269 -142.16207) (xy 371.771869 -142.136569) (xy 371.824653 -142.118562)
			(xy 371.879496 -142.108432) (xy 371.93523 -142.106395) (xy 371.990667 -142.112495) (xy 372.044624 -142.126601)
			(xy 372.095953 -142.148413) (xy 372.143559 -142.177467) (xy 372.186427 -142.213142) (xy 372.223644 -142.254679)
			(xy 372.254417 -142.301192) (xy 372.278089 -142.351689) (xy 372.294157 -142.405096) (xy 372.302277 -142.460272)
			(xy 372.302786 -142.488158) (xy 372.302277 -142.516044) (xy 372.294157 -142.57122) (xy 372.278089 -142.624627)
			(xy 372.254417 -142.675124) (xy 372.223644 -142.721637) (xy 372.186427 -142.763174) (xy 372.143559 -142.798849)
			(xy 372.095953 -142.827903) (xy 372.044624 -142.849715) (xy 371.990667 -142.863821) (xy 371.93523 -142.869921)
			(xy 371.879496 -142.867884) (xy 371.824653 -142.857754) (xy 371.771869 -142.839747) (xy 371.722269 -142.814246)
			(xy 371.676911 -142.781795) (xy 371.636762 -142.743086) (xy 371.602676 -142.698943) (xy 371.57538 -142.650308)
			(xy 371.555457 -142.598217) (xy 371.543331 -142.54378) (xy 371.53926 -142.488158) (xy 366.391605 -142.488158)
			(xy 366.385373 -142.509384) (xy 366.362731 -142.558961) (xy 366.333265 -142.604811) (xy 366.297574 -142.646002)
			(xy 366.256383 -142.681693) (xy 366.210533 -142.711159) (xy 366.160956 -142.733801) (xy 366.108661 -142.749156)
			(xy 366.054713 -142.756912) (xy 366.000211 -142.756912) (xy 365.946263 -142.749156) (xy 365.893968 -142.733801)
			(xy 365.844391 -142.711159) (xy 365.798541 -142.681693) (xy 365.75735 -142.646002) (xy 365.721659 -142.604811)
			(xy 365.692193 -142.558961) (xy 365.669551 -142.509384) (xy 365.654196 -142.457089) (xy 365.64644 -142.403141)
			(xy 365.645954 -142.37589) (xy 365.64667 -142.342956) (xy 365.658043 -142.278076) (xy 365.66856 -142.246858)
			(xy 365.671608 -142.238476) (xy 365.671608 -132.65658) (xy 365.671116 -132.646574) (xy 365.663454 -132.628088)
			(xy 365.649302 -132.61394) (xy 365.630814 -132.606281) (xy 365.620808 -132.60578) (xy 362.145072 -132.60578)
			(xy 362.135004 -132.605351) (xy 362.116409 -132.597627) (xy 362.109004 -132.590794) (xy 361.700318 -132.181854)
			(xy 361.692918 -132.175014) (xy 361.674319 -132.167301) (xy 361.66425 -132.166868) (xy 361.611164 -132.166868)
			(xy 361.601209 -132.167402) (xy 361.582825 -132.17506) (xy 361.568706 -132.189107) (xy 361.564428 -132.19811)
			(xy 361.560879 -132.207555) (xy 361.560772 -132.227715) (xy 361.568488 -132.24634) (xy 361.57535 -132.253736)
			(xy 363.817154 -134.495286) (xy 363.824555 -134.502126) (xy 363.843153 -134.509843) (xy 363.853222 -134.510272)
			(xy 364.357666 -134.510272) (xy 364.364937 -134.510045) (xy 364.37888 -134.505919) (xy 364.385098 -134.502144)
			(xy 364.408265 -134.487857) (xy 364.457785 -134.465271) (xy 364.510008 -134.44994) (xy 364.563879 -134.442173)
			(xy 364.591092 -134.441692) (xy 364.5916 -134.441692) (xy 364.618851 -134.442178) (xy 364.672799 -134.449934)
			(xy 364.725094 -134.465289) (xy 364.774671 -134.487931) (xy 364.820521 -134.517397) (xy 364.861712 -134.553088)
			(xy 364.897403 -134.594279) (xy 364.926869 -134.640129) (xy 364.949511 -134.689706) (xy 364.964866 -134.742001)
			(xy 364.972622 -134.795949) (xy 364.972622 -134.850451) (xy 364.964866 -134.904399) (xy 364.949511 -134.956694)
			(xy 364.926869 -135.006271) (xy 364.897403 -135.052121) (xy 364.861712 -135.093312) (xy 364.820521 -135.129003)
			(xy 364.774671 -135.158469) (xy 364.725094 -135.181111) (xy 364.672799 -135.196466) (xy 364.618851 -135.204222)
			(xy 364.5916 -135.204708) (xy 364.591092 -135.204708) (xy 364.563875 -135.204252) (xy 364.509993 -135.196516)
			(xy 364.457762 -135.181189) (xy 364.408244 -135.158583) (xy 364.385098 -135.144256) (xy 364.378847 -135.140556)
			(xy 364.364924 -135.136437) (xy 364.357666 -135.136128) (xy 363.991398 -135.136128) (xy 363.982442 -135.136473)
			(xy 363.965617 -135.142619) (xy 363.951921 -135.154164) (xy 363.947202 -135.161782) (xy 363.903768 -135.238236)
			(xy 363.899593 -135.246159) (xy 363.896546 -135.263793) (xy 363.899796 -135.281392) (xy 363.904022 -135.28929)
			(xy 363.916609 -135.311424) (xy 363.936454 -135.358315) (xy 363.949894 -135.407426) (xy 363.956691 -135.457888)
			(xy 363.957108 -135.483346) (xy 363.957108 -135.483854) (xy 363.956687 -135.509313) (xy 363.949911 -135.559779)
			(xy 363.936474 -135.608893) (xy 363.916614 -135.655779) (xy 363.904022 -135.67791) (xy 363.897164 -135.689848)
			(xy 363.89691 -135.717026) (xy 363.947202 -135.805418) (xy 363.951929 -135.813037) (xy 363.965606 -135.824616)
			(xy 363.982438 -135.830766) (xy 363.991398 -135.831072) (xy 364.465108 -135.831072) (xy 364.47222 -135.830564)
			(xy 364.483142 -135.82904) (xy 364.48619 -135.828024) (xy 364.511871 -135.821157) (xy 364.564513 -135.813759)
			(xy 364.591092 -135.813292) (xy 364.5916 -135.813292) (xy 364.618851 -135.813778) (xy 364.672799 -135.821534)
			(xy 364.725094 -135.836889) (xy 364.774671 -135.859531) (xy 364.820521 -135.888997) (xy 364.861712 -135.924688)
			(xy 364.897403 -135.965879) (xy 364.926869 -136.011729) (xy 364.949511 -136.061306) (xy 364.964866 -136.113601)
			(xy 364.972622 -136.167549) (xy 364.972622 -136.222051) (xy 364.964866 -136.275999) (xy 364.949511 -136.328294)
			(xy 364.926869 -136.377871) (xy 364.897403 -136.423721) (xy 364.861712 -136.464912) (xy 364.820521 -136.500603)
			(xy 364.774671 -136.530069) (xy 364.725094 -136.552711) (xy 364.672799 -136.568066) (xy 364.618851 -136.575822)
			(xy 364.5916 -136.576308) (xy 364.591092 -136.576308) (xy 364.563648 -136.575815) (xy 364.509332 -136.567914)
			(xy 364.482888 -136.56056) (xy 364.475776 -136.558528) (xy 363.991906 -136.558528) (xy 363.979235 -136.559269)
			(xy 363.956969 -136.571389) (xy 363.949488 -136.581642) (xy 363.895894 -136.663684) (xy 363.893862 -136.689084)
			(xy 363.899196 -136.701022) (xy 363.909474 -136.725412) (xy 363.923961 -136.776318) (xy 363.931275 -136.828737)
			(xy 363.931708 -136.8552) (xy 363.931222 -136.882451) (xy 363.923466 -136.936399) (xy 363.908111 -136.988694)
			(xy 363.885469 -137.038271) (xy 363.856003 -137.084121) (xy 363.820312 -137.125312) (xy 363.779121 -137.161003)
			(xy 363.733271 -137.190469) (xy 363.683694 -137.213111) (xy 363.631399 -137.228466) (xy 363.577451 -137.236222)
			(xy 363.5502 -137.236708) (xy 363.549692 -137.236708) (xy 363.522248 -137.236215) (xy 363.467932 -137.228314)
			(xy 363.441488 -137.22096) (xy 363.434376 -137.218928) (xy 363.0676 -137.218928) (xy 363.039024 -137.218381)
			(xy 362.982579 -137.209406) (xy 362.928234 -137.19171) (xy 362.877328 -137.165728) (xy 362.831114 -137.1321)
			(xy 362.810552 -137.112248) (xy 358.004364 -132.306314) (xy 357.996964 -132.299472) (xy 357.978366 -132.291748)
			(xy 357.968296 -132.291328) (xy 343.78519 -132.291328) (xy 343.756614 -132.29078) (xy 343.70017 -132.281804)
			(xy 343.645826 -132.264107) (xy 343.594921 -132.238124) (xy 343.548709 -132.204495) (xy 343.528142 -132.184648)
			(xy 343.525348 -132.181854) (xy 343.517949 -132.17501) (xy 343.49935 -132.167286) (xy 343.48928 -132.166868)
			(xy 342.424512 -132.166868) (xy 342.414441 -132.166446) (xy 342.395837 -132.158731) (xy 342.388444 -132.151882)
			(xy 341.689436 -131.452874) (xy 341.682037 -131.44603) (xy 341.663438 -131.438307) (xy 341.653368 -131.437888)
			(xy 332.537562 -131.437888) (xy 332.527495 -131.438318) (xy 332.508899 -131.44604) (xy 332.501494 -131.452874)
			(xy 331.7875 -132.166868) (xy 331.780103 -132.173718) (xy 331.761505 -132.181457) (xy 331.751432 -132.181854)
			(xy 331.749146 -132.181854) (xy 331.50175 -132.42925) (xy 331.494152 -132.43762) (xy 331.486486 -132.458854)
			(xy 331.487018 -132.470144) (xy 331.49413 -132.543804) (xy 331.495776 -132.554417) (xy 331.50641 -132.573048)
			(xy 331.514704 -132.579872) (xy 331.52334 -132.586222) (xy 331.544168 -132.590794) (xy 331.581252 -132.583174)
			(xy 331.59087 -132.580671) (xy 331.607327 -132.569561) (xy 331.613256 -132.561584) (xy 331.613256 -132.56133)
			(xy 331.628487 -132.539229) (xy 331.664161 -132.499126) (xy 331.705102 -132.464417) (xy 331.750503 -132.435788)
			(xy 331.799468 -132.413804) (xy 331.851031 -132.398898) (xy 331.904173 -132.391364) (xy 331.93101 -132.390896)
			(xy 331.958719 -132.391393) (xy 332.013553 -132.399413) (xy 332.06665 -132.415281) (xy 332.116893 -132.438666)
			(xy 332.163223 -132.469073) (xy 332.204667 -132.505864) (xy 332.240351 -132.548264) (xy 332.269525 -132.595381)
			(xy 332.291575 -132.646224) (xy 332.29931 -132.672836) (xy 332.30185 -132.681726) (xy 332.312772 -132.696712)
			(xy 332.384654 -132.74421) (xy 332.402942 -132.74802) (xy 332.412086 -132.74675) (xy 332.425787 -132.744856)
			(xy 332.453373 -132.742825) (xy 332.467204 -132.742686) (xy 332.494455 -132.743172) (xy 332.548403 -132.750929)
			(xy 332.600697 -132.766284) (xy 332.650275 -132.788926) (xy 332.696125 -132.818392) (xy 332.737315 -132.854083)
			(xy 332.773007 -132.895274) (xy 332.802473 -132.941124) (xy 332.825115 -132.990701) (xy 332.840471 -133.042995)
			(xy 332.848228 -133.096943) (xy 332.848712 -133.124194) (xy 332.848269 -133.150625) (xy 332.840982 -133.202981)
			(xy 332.826533 -133.253828) (xy 332.805199 -133.302193) (xy 332.777389 -133.347147) (xy 332.743636 -133.387829)
			(xy 332.704588 -133.423459) (xy 332.660992 -133.453353) (xy 332.613685 -133.47694) (xy 332.563574 -133.493765)
			(xy 332.511618 -133.503508) (xy 332.485238 -133.505194) (xy 332.484984 -133.505194) (xy 332.475774 -133.506059)
			(xy 332.458854 -133.513497) (xy 332.451964 -133.519672) (xy 332.40345 -133.567678) (xy 332.397185 -133.57447)
			(xy 332.389509 -133.591263) (xy 332.388464 -133.600444) (xy 332.388464 -133.600698) (xy 332.386207 -133.629445)
			(xy 332.374125 -133.685826) (xy 332.353698 -133.739747) (xy 332.325389 -133.789981) (xy 332.289844 -133.835383)
			(xy 332.247872 -133.874919) (xy 332.200429 -133.90769) (xy 332.148595 -133.932949) (xy 332.09355 -133.950121)
			(xy 332.036548 -133.958815) (xy 332.007718 -133.959346) (xy 331.982379 -133.958933) (xy 331.932148 -133.952225)
			(xy 331.883247 -133.938924) (xy 331.836538 -133.919266) (xy 331.792844 -133.893596) (xy 331.752933 -133.862366)
			(xy 331.734922 -133.844538) (xy 331.728318 -133.83768) (xy 331.711046 -133.829806) (xy 331.62367 -133.824472)
			(xy 331.606144 -133.83006) (xy 331.598524 -133.836156) (xy 331.578137 -133.851995) (xy 331.533901 -133.878612)
			(xy 331.486476 -133.899012) (xy 331.436731 -133.912821) (xy 331.385577 -133.919788) (xy 331.359764 -133.92023)
			(xy 331.330756 -133.919693) (xy 331.273408 -133.910914) (xy 331.218051 -133.89355) (xy 331.165964 -133.868)
			(xy 331.118348 -133.834856) (xy 331.076302 -133.794881) (xy 331.040796 -133.748998) (xy 331.026262 -133.723888)
			(xy 331.02169 -133.715506) (xy 331.007466 -133.703568) (xy 330.93406 -133.678676) (xy 330.925168 -133.676095)
			(xy 330.906678 -133.676741) (xy 330.897992 -133.679946) (xy 330.897738 -133.679946) (xy 330.87414 -133.68949)
			(xy 330.825046 -133.702944) (xy 330.7746 -133.709748) (xy 330.749148 -133.710172) (xy 330.74864 -133.710172)
			(xy 330.718515 -133.709606) (xy 330.659013 -133.700139) (xy 330.60174 -133.681434) (xy 330.548121 -133.653956)
			(xy 330.499489 -133.618389) (xy 330.477876 -133.597396) (xy 330.477622 -133.597142) (xy 330.470216 -133.59045)
			(xy 330.451779 -133.582853) (xy 330.441808 -133.58241) (xy 330.369926 -133.582156) (xy 330.359863 -133.582594)
			(xy 330.341283 -133.590334) (xy 330.333858 -133.597142) (xy 328.305668 -135.625332) (xy 360.129072 -135.625332)
			(xy 360.133143 -135.56971) (xy 360.145269 -135.515273) (xy 360.165192 -135.463182) (xy 360.192488 -135.414547)
			(xy 360.226574 -135.370404) (xy 360.266723 -135.331695) (xy 360.312081 -135.299244) (xy 360.361681 -135.273743)
			(xy 360.414465 -135.255736) (xy 360.469308 -135.245606) (xy 360.525042 -135.243569) (xy 360.580479 -135.249669)
			(xy 360.634436 -135.263775) (xy 360.685765 -135.285587) (xy 360.733371 -135.314641) (xy 360.776239 -135.350316)
			(xy 360.813456 -135.391853) (xy 360.844229 -135.438366) (xy 360.867901 -135.488863) (xy 360.883969 -135.54227)
			(xy 360.892089 -135.597446) (xy 360.892598 -135.625332) (xy 360.892089 -135.653218) (xy 360.883969 -135.708394)
			(xy 360.867901 -135.761801) (xy 360.844229 -135.812298) (xy 360.813456 -135.858811) (xy 360.776239 -135.900348)
			(xy 360.733371 -135.936023) (xy 360.685765 -135.965077) (xy 360.634436 -135.986889) (xy 360.580479 -136.000995)
			(xy 360.525042 -136.007095) (xy 360.469308 -136.005058) (xy 360.414465 -135.994928) (xy 360.361681 -135.976921)
			(xy 360.312081 -135.95142) (xy 360.266723 -135.918969) (xy 360.226574 -135.88026) (xy 360.192488 -135.836117)
			(xy 360.165192 -135.787482) (xy 360.145269 -135.735391) (xy 360.133143 -135.680954) (xy 360.129072 -135.625332)
			(xy 328.305668 -135.625332) (xy 327.738486 -136.192514) (xy 327.731632 -136.199909) (xy 327.72389 -136.218508)
			(xy 327.7235 -136.228582) (xy 327.7235 -136.473946) (xy 330.23505 -136.473946) (xy 330.239121 -136.418324)
			(xy 330.251247 -136.363887) (xy 330.27117 -136.311796) (xy 330.298466 -136.263161) (xy 330.332552 -136.219018)
			(xy 330.372701 -136.180309) (xy 330.418059 -136.147858) (xy 330.467659 -136.122357) (xy 330.520443 -136.10435)
			(xy 330.575286 -136.09422) (xy 330.63102 -136.092183) (xy 330.686457 -136.098283) (xy 330.740414 -136.112389)
			(xy 330.791743 -136.134201) (xy 330.839349 -136.163255) (xy 330.882217 -136.19893) (xy 330.919434 -136.240467)
			(xy 330.950207 -136.28698) (xy 330.973879 -136.337477) (xy 330.989947 -136.390884) (xy 330.998067 -136.44606)
			(xy 330.998576 -136.473946) (xy 330.998067 -136.501832) (xy 330.989947 -136.557008) (xy 330.973879 -136.610415)
			(xy 330.950207 -136.660912) (xy 330.919434 -136.707425) (xy 330.882217 -136.748962) (xy 330.839349 -136.784637)
			(xy 330.791743 -136.813691) (xy 330.740414 -136.835503) (xy 330.686457 -136.849609) (xy 330.63102 -136.855709)
			(xy 330.575286 -136.853672) (xy 330.520443 -136.843542) (xy 330.467659 -136.825535) (xy 330.418059 -136.800034)
			(xy 330.372701 -136.767583) (xy 330.332552 -136.728874) (xy 330.298466 -136.684731) (xy 330.27117 -136.636096)
			(xy 330.251247 -136.584005) (xy 330.239121 -136.529568) (xy 330.23505 -136.473946) (xy 327.7235 -136.473946)
			(xy 327.7235 -137.849864) (xy 328.187556 -137.849864) (xy 328.191627 -137.794242) (xy 328.203753 -137.739805)
			(xy 328.223676 -137.687714) (xy 328.250972 -137.639079) (xy 328.285058 -137.594936) (xy 328.325207 -137.556227)
			(xy 328.370565 -137.523776) (xy 328.420165 -137.498275) (xy 328.472949 -137.480268) (xy 328.527792 -137.470138)
			(xy 328.583526 -137.468101) (xy 328.638963 -137.474201) (xy 328.69292 -137.488307) (xy 328.744249 -137.510119)
			(xy 328.791855 -137.539173) (xy 328.834723 -137.574848) (xy 328.87194 -137.616385) (xy 328.902713 -137.662898)
			(xy 328.926385 -137.713395) (xy 328.942453 -137.766802) (xy 328.950573 -137.821978) (xy 328.951082 -137.849864)
			(xy 328.950573 -137.87775) (xy 328.942453 -137.932926) (xy 328.926385 -137.986333) (xy 328.902713 -138.03683)
			(xy 328.87194 -138.083343) (xy 328.834723 -138.12488) (xy 328.791855 -138.160555) (xy 328.744249 -138.189609)
			(xy 328.69292 -138.211421) (xy 328.638963 -138.225527) (xy 328.583526 -138.231627) (xy 328.527792 -138.22959)
			(xy 328.472949 -138.21946) (xy 328.420165 -138.201453) (xy 328.370565 -138.175952) (xy 328.325207 -138.143501)
			(xy 328.285058 -138.104792) (xy 328.250972 -138.060649) (xy 328.223676 -138.012014) (xy 328.203753 -137.959923)
			(xy 328.191627 -137.905486) (xy 328.187556 -137.849864) (xy 327.7235 -137.849864) (xy 327.7235 -140.408152)
			(xy 332.324962 -140.408152) (xy 332.329033 -140.35253) (xy 332.341159 -140.298093) (xy 332.361082 -140.246002)
			(xy 332.388378 -140.197367) (xy 332.422464 -140.153224) (xy 332.462613 -140.114515) (xy 332.507971 -140.082064)
			(xy 332.557571 -140.056563) (xy 332.610355 -140.038556) (xy 332.665198 -140.028426) (xy 332.720932 -140.026389)
			(xy 332.776369 -140.032489) (xy 332.830326 -140.046595) (xy 332.881655 -140.068407) (xy 332.929261 -140.097461)
			(xy 332.972129 -140.133136) (xy 333.009346 -140.174673) (xy 333.040119 -140.221186) (xy 333.063791 -140.271683)
			(xy 333.079859 -140.32509) (xy 333.087979 -140.380266) (xy 333.088488 -140.408152) (xy 333.087979 -140.436038)
			(xy 333.079859 -140.491214) (xy 333.063791 -140.544621) (xy 333.040119 -140.595118) (xy 333.009346 -140.641631)
			(xy 332.972129 -140.683168) (xy 332.929261 -140.718843) (xy 332.881655 -140.747897) (xy 332.830326 -140.769709)
			(xy 332.776369 -140.783815) (xy 332.720932 -140.789915) (xy 332.665198 -140.787878) (xy 332.610355 -140.777748)
			(xy 332.557571 -140.759741) (xy 332.507971 -140.73424) (xy 332.462613 -140.701789) (xy 332.422464 -140.66308)
			(xy 332.388378 -140.618937) (xy 332.361082 -140.570302) (xy 332.341159 -140.518211) (xy 332.329033 -140.463774)
			(xy 332.324962 -140.408152) (xy 327.7235 -140.408152) (xy 327.7235 -142.578074) (xy 328.532234 -142.578074)
			(xy 328.536305 -142.522452) (xy 328.548431 -142.468015) (xy 328.568354 -142.415924) (xy 328.59565 -142.367289)
			(xy 328.629736 -142.323146) (xy 328.669885 -142.284437) (xy 328.715243 -142.251986) (xy 328.764843 -142.226485)
			(xy 328.817627 -142.208478) (xy 328.87247 -142.198348) (xy 328.928204 -142.196311) (xy 328.935138 -142.197074)
			(xy 332.301086 -142.197074) (xy 332.305157 -142.141452) (xy 332.317283 -142.087015) (xy 332.337206 -142.034924)
			(xy 332.364502 -141.986289) (xy 332.398588 -141.942146) (xy 332.438737 -141.903437) (xy 332.484095 -141.870986)
			(xy 332.533695 -141.845485) (xy 332.586479 -141.827478) (xy 332.641322 -141.817348) (xy 332.697056 -141.815311)
			(xy 332.752493 -141.821411) (xy 332.80645 -141.835517) (xy 332.857779 -141.857329) (xy 332.905385 -141.886383)
			(xy 332.948253 -141.922058) (xy 332.98547 -141.963595) (xy 333.016243 -142.010108) (xy 333.039915 -142.060605)
			(xy 333.055983 -142.114012) (xy 333.064103 -142.169188) (xy 333.064612 -142.197074) (xy 333.064103 -142.22496)
			(xy 333.055983 -142.280136) (xy 333.039915 -142.333543) (xy 333.016243 -142.38404) (xy 332.98547 -142.430553)
			(xy 332.948253 -142.47209) (xy 332.905385 -142.507765) (xy 332.857779 -142.536819) (xy 332.80645 -142.558631)
			(xy 332.752493 -142.572737) (xy 332.697056 -142.578837) (xy 332.641322 -142.5768) (xy 332.586479 -142.56667)
			(xy 332.533695 -142.548663) (xy 332.484095 -142.523162) (xy 332.438737 -142.490711) (xy 332.398588 -142.452002)
			(xy 332.364502 -142.407859) (xy 332.337206 -142.359224) (xy 332.317283 -142.307133) (xy 332.305157 -142.252696)
			(xy 332.301086 -142.197074) (xy 328.935138 -142.197074) (xy 328.983641 -142.202411) (xy 329.037598 -142.216517)
			(xy 329.088927 -142.238329) (xy 329.136533 -142.267383) (xy 329.179401 -142.303058) (xy 329.216618 -142.344595)
			(xy 329.247391 -142.391108) (xy 329.271063 -142.441605) (xy 329.287131 -142.495012) (xy 329.295251 -142.550188)
			(xy 329.29576 -142.578074) (xy 329.295251 -142.60596) (xy 329.287131 -142.661136) (xy 329.275822 -142.698724)
			(xy 337.332572 -142.698724) (xy 337.336643 -142.643102) (xy 337.348769 -142.588665) (xy 337.368692 -142.536574)
			(xy 337.395988 -142.487939) (xy 337.430074 -142.443796) (xy 337.470223 -142.405087) (xy 337.515581 -142.372636)
			(xy 337.565181 -142.347135) (xy 337.617965 -142.329128) (xy 337.672808 -142.318998) (xy 337.728542 -142.316961)
			(xy 337.783979 -142.323061) (xy 337.837936 -142.337167) (xy 337.889265 -142.358979) (xy 337.936871 -142.388033)
			(xy 337.979739 -142.423708) (xy 338.016956 -142.465245) (xy 338.047729 -142.511758) (xy 338.071401 -142.562255)
			(xy 338.087469 -142.615662) (xy 338.095589 -142.670838) (xy 338.096098 -142.698724) (xy 338.095589 -142.72661)
			(xy 338.087469 -142.781786) (xy 338.071401 -142.835193) (xy 338.047729 -142.88569) (xy 338.016956 -142.932203)
			(xy 337.979739 -142.97374) (xy 337.936871 -143.009415) (xy 337.889265 -143.038469) (xy 337.837936 -143.060281)
			(xy 337.783979 -143.074387) (xy 337.728542 -143.080487) (xy 337.672808 -143.07845) (xy 337.617965 -143.06832)
			(xy 337.565181 -143.050313) (xy 337.515581 -143.024812) (xy 337.470223 -142.992361) (xy 337.430074 -142.953652)
			(xy 337.395988 -142.909509) (xy 337.368692 -142.860874) (xy 337.348769 -142.808783) (xy 337.336643 -142.754346)
			(xy 337.332572 -142.698724) (xy 329.275822 -142.698724) (xy 329.271063 -142.714543) (xy 329.247391 -142.76504)
			(xy 329.216618 -142.811553) (xy 329.179401 -142.85309) (xy 329.136533 -142.888765) (xy 329.088927 -142.917819)
			(xy 329.037598 -142.939631) (xy 328.983641 -142.953737) (xy 328.928204 -142.959837) (xy 328.87247 -142.9578)
			(xy 328.817627 -142.94767) (xy 328.764843 -142.929663) (xy 328.715243 -142.904162) (xy 328.669885 -142.871711)
			(xy 328.629736 -142.833002) (xy 328.59565 -142.788859) (xy 328.568354 -142.740224) (xy 328.548431 -142.688133)
			(xy 328.536305 -142.633696) (xy 328.532234 -142.578074) (xy 327.7235 -142.578074) (xy 327.7235 -143.504158)
			(xy 373.57126 -143.504158) (xy 373.575331 -143.448536) (xy 373.587457 -143.394099) (xy 373.60738 -143.342008)
			(xy 373.634676 -143.293373) (xy 373.668762 -143.24923) (xy 373.708911 -143.210521) (xy 373.754269 -143.17807)
			(xy 373.803869 -143.152569) (xy 373.856653 -143.134562) (xy 373.911496 -143.124432) (xy 373.96723 -143.122395)
			(xy 374.022667 -143.128495) (xy 374.076624 -143.142601) (xy 374.127953 -143.164413) (xy 374.175559 -143.193467)
			(xy 374.218427 -143.229142) (xy 374.255644 -143.270679) (xy 374.286417 -143.317192) (xy 374.310089 -143.367689)
			(xy 374.326157 -143.421096) (xy 374.334277 -143.476272) (xy 374.334786 -143.504158) (xy 374.334277 -143.532044)
			(xy 374.326157 -143.58722) (xy 374.310089 -143.640627) (xy 374.286417 -143.691124) (xy 374.255644 -143.737637)
			(xy 374.218427 -143.779174) (xy 374.175559 -143.814849) (xy 374.127953 -143.843903) (xy 374.076624 -143.865715)
			(xy 374.022667 -143.879821) (xy 373.96723 -143.885921) (xy 373.911496 -143.883884) (xy 373.856653 -143.873754)
			(xy 373.803869 -143.855747) (xy 373.754269 -143.830246) (xy 373.708911 -143.797795) (xy 373.668762 -143.759086)
			(xy 373.634676 -143.714943) (xy 373.60738 -143.666308) (xy 373.587457 -143.614217) (xy 373.575331 -143.55978)
			(xy 373.57126 -143.504158) (xy 327.7235 -143.504158) (xy 327.7235 -144.520158) (xy 371.53926 -144.520158)
			(xy 371.543331 -144.464536) (xy 371.555457 -144.410099) (xy 371.57538 -144.358008) (xy 371.602676 -144.309373)
			(xy 371.636762 -144.26523) (xy 371.676911 -144.226521) (xy 371.722269 -144.19407) (xy 371.771869 -144.168569)
			(xy 371.824653 -144.150562) (xy 371.879496 -144.140432) (xy 371.93523 -144.138395) (xy 371.990667 -144.144495)
			(xy 372.044624 -144.158601) (xy 372.095953 -144.180413) (xy 372.143559 -144.209467) (xy 372.186427 -144.245142)
			(xy 372.223644 -144.286679) (xy 372.254417 -144.333192) (xy 372.278089 -144.383689) (xy 372.294157 -144.437096)
			(xy 372.302277 -144.492272) (xy 372.302786 -144.520158) (xy 372.302277 -144.548044) (xy 372.294157 -144.60322)
			(xy 372.278089 -144.656627) (xy 372.254417 -144.707124) (xy 372.223644 -144.753637) (xy 372.186427 -144.795174)
			(xy 372.143559 -144.830849) (xy 372.095953 -144.859903) (xy 372.044624 -144.881715) (xy 371.990667 -144.895821)
			(xy 371.93523 -144.901921) (xy 371.879496 -144.899884) (xy 371.824653 -144.889754) (xy 371.771869 -144.871747)
			(xy 371.722269 -144.846246) (xy 371.676911 -144.813795) (xy 371.636762 -144.775086) (xy 371.602676 -144.730943)
			(xy 371.57538 -144.682308) (xy 371.555457 -144.630217) (xy 371.543331 -144.57578) (xy 371.53926 -144.520158)
			(xy 327.7235 -144.520158) (xy 327.7235 -147.904962) (xy 344.785959 -147.904962) (xy 344.789955 -147.743437)
			(xy 344.801934 -147.582308) (xy 344.821868 -147.421968) (xy 344.849706 -147.26281) (xy 344.885381 -147.105224)
			(xy 344.928806 -146.949595) (xy 344.979874 -146.796304) (xy 345.038461 -146.645725) (xy 345.104422 -146.498229)
			(xy 345.177597 -146.354175) (xy 345.257807 -146.213915) (xy 345.344854 -146.077795) (xy 345.438527 -145.946145)
			(xy 345.538596 -145.819289) (xy 345.644816 -145.697537) (xy 345.756927 -145.581187) (xy 345.874654 -145.470524)
			(xy 345.997711 -145.365818) (xy 346.125794 -145.267326) (xy 346.258592 -145.175289) (xy 346.395779 -145.089931)
			(xy 346.53702 -145.011463) (xy 346.681968 -144.940075) (xy 346.830269 -144.875943) (xy 346.981561 -144.819223)
			(xy 347.135472 -144.770055) (xy 347.291626 -144.728558) (xy 347.449642 -144.694835) (xy 347.609132 -144.668967)
			(xy 347.769706 -144.651018) (xy 347.930971 -144.641033) (xy 348.092533 -144.639034) (xy 348.253995 -144.645028)
			(xy 348.414964 -144.659) (xy 348.575045 -144.680915) (xy 348.733847 -144.710719) (xy 348.89098 -144.748341)
			(xy 349.04606 -144.793687) (xy 349.198708 -144.846647) (xy 349.34855 -144.907092) (xy 349.49522 -144.974872)
			(xy 349.596983 -145.028158) (xy 381.31826 -145.028158) (xy 381.322331 -144.972536) (xy 381.334457 -144.918099)
			(xy 381.35438 -144.866008) (xy 381.381676 -144.817373) (xy 381.415762 -144.77323) (xy 381.455911 -144.734521)
			(xy 381.501269 -144.70207) (xy 381.550869 -144.676569) (xy 381.603653 -144.658562) (xy 381.658496 -144.648432)
			(xy 381.71423 -144.646395) (xy 381.769667 -144.652495) (xy 381.823624 -144.666601) (xy 381.874953 -144.688413)
			(xy 381.922559 -144.717467) (xy 381.965427 -144.753142) (xy 382.002644 -144.794679) (xy 382.033417 -144.841192)
			(xy 382.057089 -144.891689) (xy 382.073157 -144.945096) (xy 382.081277 -145.000272) (xy 382.081786 -145.028158)
			(xy 382.081277 -145.056044) (xy 382.073157 -145.11122) (xy 382.057089 -145.164627) (xy 382.033417 -145.215124)
			(xy 382.002644 -145.261637) (xy 381.965427 -145.303174) (xy 381.922559 -145.338849) (xy 381.874953 -145.367903)
			(xy 381.823624 -145.389715) (xy 381.769667 -145.403821) (xy 381.71423 -145.409921) (xy 381.658496 -145.407884)
			(xy 381.603653 -145.397754) (xy 381.550869 -145.379747) (xy 381.501269 -145.354246) (xy 381.455911 -145.321795)
			(xy 381.415762 -145.283086) (xy 381.381676 -145.238943) (xy 381.35438 -145.190308) (xy 381.334457 -145.138217)
			(xy 381.322331 -145.08378) (xy 381.31826 -145.028158) (xy 349.596983 -145.028158) (xy 349.638358 -145.049823)
			(xy 349.777614 -145.131761) (xy 349.912648 -145.220486) (xy 350.043129 -145.31578) (xy 350.168737 -145.41741)
			(xy 350.289166 -145.525128) (xy 350.300333 -145.536158) (xy 371.53926 -145.536158) (xy 371.543331 -145.480536)
			(xy 371.555457 -145.426099) (xy 371.57538 -145.374008) (xy 371.602676 -145.325373) (xy 371.636762 -145.28123)
			(xy 371.676911 -145.242521) (xy 371.722269 -145.21007) (xy 371.771869 -145.184569) (xy 371.824653 -145.166562)
			(xy 371.879496 -145.156432) (xy 371.93523 -145.154395) (xy 371.990667 -145.160495) (xy 372.044624 -145.174601)
			(xy 372.095953 -145.196413) (xy 372.143559 -145.225467) (xy 372.186427 -145.261142) (xy 372.223644 -145.302679)
			(xy 372.254417 -145.349192) (xy 372.278089 -145.399689) (xy 372.294157 -145.453096) (xy 372.302277 -145.508272)
			(xy 372.302786 -145.536158) (xy 372.302277 -145.564044) (xy 372.294157 -145.61922) (xy 372.278089 -145.672627)
			(xy 372.254417 -145.723124) (xy 372.223644 -145.769637) (xy 372.186427 -145.811174) (xy 372.143559 -145.846849)
			(xy 372.095953 -145.875903) (xy 372.044624 -145.897715) (xy 371.990667 -145.911821) (xy 371.93523 -145.917921)
			(xy 371.879496 -145.915884) (xy 371.824653 -145.905754) (xy 371.771869 -145.887747) (xy 371.722269 -145.862246)
			(xy 371.676911 -145.829795) (xy 371.636762 -145.791086) (xy 371.602676 -145.746943) (xy 371.57538 -145.698308)
			(xy 371.555457 -145.646217) (xy 371.543331 -145.59178) (xy 371.53926 -145.536158) (xy 350.300333 -145.536158)
			(xy 350.40412 -145.638669) (xy 350.513319 -145.757756) (xy 350.616495 -145.882098) (xy 350.713396 -146.01139)
			(xy 350.803783 -146.145317) (xy 350.887438 -146.283549) (xy 350.964153 -146.425749) (xy 350.997569 -146.49577)
			(xy 365.860074 -146.49577) (xy 365.864145 -146.440148) (xy 365.876271 -146.385711) (xy 365.896194 -146.33362)
			(xy 365.92349 -146.284985) (xy 365.957576 -146.240842) (xy 365.997725 -146.202133) (xy 366.043083 -146.169682)
			(xy 366.092683 -146.144181) (xy 366.145467 -146.126174) (xy 366.20031 -146.116044) (xy 366.256044 -146.114007)
			(xy 366.311481 -146.120107) (xy 366.365438 -146.134213) (xy 366.416767 -146.156025) (xy 366.464373 -146.185079)
			(xy 366.507241 -146.220754) (xy 366.544458 -146.262291) (xy 366.575231 -146.308804) (xy 366.598903 -146.359301)
			(xy 366.614971 -146.412708) (xy 366.623091 -146.467884) (xy 366.6236 -146.49577) (xy 366.623091 -146.523656)
			(xy 366.618896 -146.552158) (xy 371.53926 -146.552158) (xy 371.543331 -146.496536) (xy 371.555457 -146.442099)
			(xy 371.57538 -146.390008) (xy 371.602676 -146.341373) (xy 371.636762 -146.29723) (xy 371.676911 -146.258521)
			(xy 371.722269 -146.22607) (xy 371.771869 -146.200569) (xy 371.824653 -146.182562) (xy 371.879496 -146.172432)
			(xy 371.93523 -146.170395) (xy 371.990667 -146.176495) (xy 372.044624 -146.190601) (xy 372.095953 -146.212413)
			(xy 372.143559 -146.241467) (xy 372.186427 -146.277142) (xy 372.223644 -146.318679) (xy 372.254417 -146.365192)
			(xy 372.278089 -146.415689) (xy 372.29049 -146.456908) (xy 378.786388 -146.456908) (xy 378.790459 -146.401286)
			(xy 378.802585 -146.346849) (xy 378.822508 -146.294758) (xy 378.849804 -146.246123) (xy 378.88389 -146.20198)
			(xy 378.924039 -146.163271) (xy 378.969397 -146.13082) (xy 379.018997 -146.105319) (xy 379.071781 -146.087312)
			(xy 379.126624 -146.077182) (xy 379.182358 -146.075145) (xy 379.237795 -146.081245) (xy 379.291752 -146.095351)
			(xy 379.343081 -146.117163) (xy 379.390687 -146.146217) (xy 379.420657 -146.171158) (xy 383.09626 -146.171158)
			(xy 383.100331 -146.115536) (xy 383.112457 -146.061099) (xy 383.13238 -146.009008) (xy 383.159676 -145.960373)
			(xy 383.193762 -145.91623) (xy 383.233911 -145.877521) (xy 383.279269 -145.84507) (xy 383.328869 -145.819569)
			(xy 383.381653 -145.801562) (xy 383.436496 -145.791432) (xy 383.49223 -145.789395) (xy 383.547667 -145.795495)
			(xy 383.570973 -145.801588) (xy 399.016726 -145.801588) (xy 399.020797 -145.745966) (xy 399.032923 -145.691529)
			(xy 399.052846 -145.639438) (xy 399.080142 -145.590803) (xy 399.114228 -145.54666) (xy 399.154377 -145.507951)
			(xy 399.199735 -145.4755) (xy 399.249335 -145.449999) (xy 399.302119 -145.431992) (xy 399.356962 -145.421862)
			(xy 399.412696 -145.419825) (xy 399.468133 -145.425925) (xy 399.52209 -145.440031) (xy 399.573419 -145.461843)
			(xy 399.621025 -145.490897) (xy 399.663893 -145.526572) (xy 399.70111 -145.568109) (xy 399.731883 -145.614622)
			(xy 399.755555 -145.665119) (xy 399.771623 -145.718526) (xy 399.779743 -145.773702) (xy 399.780252 -145.801588)
			(xy 399.779743 -145.829474) (xy 399.771623 -145.88465) (xy 399.755555 -145.938057) (xy 399.731883 -145.988554)
			(xy 399.70111 -146.035067) (xy 399.663893 -146.076604) (xy 399.621025 -146.112279) (xy 399.573419 -146.141333)
			(xy 399.52209 -146.163145) (xy 399.468133 -146.177251) (xy 399.412696 -146.183351) (xy 399.356962 -146.181314)
			(xy 399.302119 -146.171184) (xy 399.249335 -146.153177) (xy 399.199735 -146.127676) (xy 399.154377 -146.095225)
			(xy 399.114228 -146.056516) (xy 399.080142 -146.012373) (xy 399.052846 -145.963738) (xy 399.032923 -145.911647)
			(xy 399.020797 -145.85721) (xy 399.016726 -145.801588) (xy 383.570973 -145.801588) (xy 383.601624 -145.809601)
			(xy 383.652953 -145.831413) (xy 383.700559 -145.860467) (xy 383.743427 -145.896142) (xy 383.780644 -145.937679)
			(xy 383.811417 -145.984192) (xy 383.835089 -146.034689) (xy 383.851157 -146.088096) (xy 383.859277 -146.143272)
			(xy 383.859786 -146.171158) (xy 383.859277 -146.199044) (xy 383.851157 -146.25422) (xy 383.835089 -146.307627)
			(xy 383.811417 -146.358124) (xy 383.780644 -146.404637) (xy 383.743427 -146.446174) (xy 383.700559 -146.481849)
			(xy 383.652953 -146.510903) (xy 383.601624 -146.532715) (xy 383.547667 -146.546821) (xy 383.49223 -146.552921)
			(xy 383.436496 -146.550884) (xy 383.381653 -146.540754) (xy 383.328869 -146.522747) (xy 383.279269 -146.497246)
			(xy 383.233911 -146.464795) (xy 383.193762 -146.426086) (xy 383.159676 -146.381943) (xy 383.13238 -146.333308)
			(xy 383.112457 -146.281217) (xy 383.100331 -146.22678) (xy 383.09626 -146.171158) (xy 379.420657 -146.171158)
			(xy 379.433555 -146.181892) (xy 379.470772 -146.223429) (xy 379.501545 -146.269942) (xy 379.525217 -146.320439)
			(xy 379.541285 -146.373846) (xy 379.549405 -146.429022) (xy 379.549914 -146.456908) (xy 379.549405 -146.484794)
			(xy 379.541285 -146.53997) (xy 379.525217 -146.593377) (xy 379.501545 -146.643874) (xy 379.470772 -146.690387)
			(xy 379.438275 -146.726656) (xy 381.080516 -146.726656) (xy 381.084587 -146.671034) (xy 381.096713 -146.616597)
			(xy 381.116636 -146.564506) (xy 381.143932 -146.515871) (xy 381.178018 -146.471728) (xy 381.218167 -146.433019)
			(xy 381.263525 -146.400568) (xy 381.313125 -146.375067) (xy 381.365909 -146.35706) (xy 381.420752 -146.34693)
			(xy 381.476486 -146.344893) (xy 381.531923 -146.350993) (xy 381.58588 -146.365099) (xy 381.637209 -146.386911)
			(xy 381.684815 -146.415965) (xy 381.727683 -146.45164) (xy 381.7649 -146.493177) (xy 381.795673 -146.53969)
			(xy 381.819345 -146.590187) (xy 381.835413 -146.643594) (xy 381.843533 -146.69877) (xy 381.844042 -146.726656)
			(xy 381.843533 -146.754542) (xy 381.835413 -146.809718) (xy 381.819345 -146.863125) (xy 381.795673 -146.913622)
			(xy 381.7649 -146.960135) (xy 381.727683 -147.001672) (xy 381.684815 -147.037347) (xy 381.637209 -147.066401)
			(xy 381.58588 -147.088213) (xy 381.531923 -147.102319) (xy 381.476486 -147.108419) (xy 381.420752 -147.106382)
			(xy 381.365909 -147.096252) (xy 381.313125 -147.078245) (xy 381.263525 -147.052744) (xy 381.218167 -147.020293)
			(xy 381.178018 -146.981584) (xy 381.143932 -146.937441) (xy 381.116636 -146.888806) (xy 381.096713 -146.836715)
			(xy 381.084587 -146.782278) (xy 381.080516 -146.726656) (xy 379.438275 -146.726656) (xy 379.433555 -146.731924)
			(xy 379.390687 -146.767599) (xy 379.343081 -146.796653) (xy 379.291752 -146.818465) (xy 379.237795 -146.832571)
			(xy 379.182358 -146.838671) (xy 379.126624 -146.836634) (xy 379.071781 -146.826504) (xy 379.018997 -146.808497)
			(xy 378.969397 -146.782996) (xy 378.924039 -146.750545) (xy 378.88389 -146.711836) (xy 378.849804 -146.667693)
			(xy 378.822508 -146.619058) (xy 378.802585 -146.566967) (xy 378.790459 -146.51253) (xy 378.786388 -146.456908)
			(xy 372.29049 -146.456908) (xy 372.294157 -146.469096) (xy 372.302277 -146.524272) (xy 372.302786 -146.552158)
			(xy 372.302277 -146.580044) (xy 372.294157 -146.63522) (xy 372.278089 -146.688627) (xy 372.254417 -146.739124)
			(xy 372.223644 -146.785637) (xy 372.186427 -146.827174) (xy 372.143559 -146.862849) (xy 372.095953 -146.891903)
			(xy 372.044624 -146.913715) (xy 371.990667 -146.927821) (xy 371.93523 -146.933921) (xy 371.879496 -146.931884)
			(xy 371.824653 -146.921754) (xy 371.771869 -146.903747) (xy 371.722269 -146.878246) (xy 371.676911 -146.845795)
			(xy 371.636762 -146.807086) (xy 371.602676 -146.762943) (xy 371.57538 -146.714308) (xy 371.555457 -146.662217)
			(xy 371.543331 -146.60778) (xy 371.53926 -146.552158) (xy 366.618896 -146.552158) (xy 366.614971 -146.578832)
			(xy 366.598903 -146.632239) (xy 366.575231 -146.682736) (xy 366.544458 -146.729249) (xy 366.507241 -146.770786)
			(xy 366.464373 -146.806461) (xy 366.416767 -146.835515) (xy 366.365438 -146.857327) (xy 366.311481 -146.871433)
			(xy 366.256044 -146.877533) (xy 366.20031 -146.875496) (xy 366.145467 -146.865366) (xy 366.092683 -146.847359)
			(xy 366.043083 -146.821858) (xy 365.997725 -146.789407) (xy 365.957576 -146.750698) (xy 365.92349 -146.706555)
			(xy 365.896194 -146.65792) (xy 365.876271 -146.605829) (xy 365.864145 -146.551392) (xy 365.860074 -146.49577)
			(xy 350.997569 -146.49577) (xy 351.033743 -146.571569) (xy 351.096036 -146.720652) (xy 351.15088 -146.872633)
			(xy 351.198141 -147.027141) (xy 351.237703 -147.183797) (xy 351.269469 -147.342217) (xy 351.293362 -147.502015)
			(xy 351.299928 -147.568158) (xy 371.53926 -147.568158) (xy 371.543331 -147.512536) (xy 371.555457 -147.458099)
			(xy 371.57538 -147.406008) (xy 371.602676 -147.357373) (xy 371.636762 -147.31323) (xy 371.676911 -147.274521)
			(xy 371.722269 -147.24207) (xy 371.771869 -147.216569) (xy 371.824653 -147.198562) (xy 371.879496 -147.188432)
			(xy 371.93523 -147.186395) (xy 371.990667 -147.192495) (xy 372.044624 -147.206601) (xy 372.095953 -147.228413)
			(xy 372.143559 -147.257467) (xy 372.186427 -147.293142) (xy 372.223644 -147.334679) (xy 372.254417 -147.381192)
			(xy 372.271931 -147.418552) (xy 376.64212 -147.418552) (xy 376.646191 -147.36293) (xy 376.658317 -147.308493)
			(xy 376.67824 -147.256402) (xy 376.705536 -147.207767) (xy 376.739622 -147.163624) (xy 376.779771 -147.124915)
			(xy 376.825129 -147.092464) (xy 376.874729 -147.066963) (xy 376.927513 -147.048956) (xy 376.982356 -147.038826)
			(xy 377.03809 -147.036789) (xy 377.093527 -147.042889) (xy 377.147484 -147.056995) (xy 377.198813 -147.078807)
			(xy 377.246419 -147.107861) (xy 377.289287 -147.143536) (xy 377.326504 -147.185073) (xy 377.357277 -147.231586)
			(xy 377.380949 -147.282083) (xy 377.397017 -147.33549) (xy 377.405137 -147.390666) (xy 377.405646 -147.418552)
			(xy 377.405137 -147.446438) (xy 377.398027 -147.494752) (xy 378.25045 -147.494752) (xy 378.250936 -147.467501)
			(xy 378.258692 -147.413553) (xy 378.274047 -147.361258) (xy 378.296689 -147.311681) (xy 378.326155 -147.265831)
			(xy 378.361846 -147.22464) (xy 378.403037 -147.188949) (xy 378.448887 -147.159483) (xy 378.498464 -147.136841)
			(xy 378.550759 -147.121486) (xy 378.604707 -147.11373) (xy 378.659209 -147.11373) (xy 378.713157 -147.121486)
			(xy 378.765452 -147.136841) (xy 378.815029 -147.159483) (xy 378.860879 -147.188949) (xy 378.90207 -147.22464)
			(xy 378.937761 -147.265831) (xy 378.967227 -147.311681) (xy 378.989869 -147.361258) (xy 379.005224 -147.413553)
			(xy 379.01298 -147.467501) (xy 379.013466 -147.494752) (xy 379.013466 -147.49526) (xy 379.012933 -147.524122)
			(xy 379.004207 -147.581184) (xy 378.98698 -147.636278) (xy 378.973604 -147.663662) (xy 387.813054 -147.663662)
			(xy 387.81702 -147.579131) (xy 387.828885 -147.495344) (xy 387.848543 -147.413035) (xy 387.875823 -147.332929)
			(xy 387.910484 -147.25573) (xy 387.952222 -147.182115) (xy 388.000669 -147.112732) (xy 388.055401 -147.048191)
			(xy 388.115937 -146.989059) (xy 388.181743 -146.935855) (xy 388.252243 -146.889047) (xy 388.326815 -146.849046)
			(xy 388.404806 -146.816204) (xy 388.48553 -146.79081) (xy 388.568277 -146.773087) (xy 388.652319 -146.763189)
			(xy 388.73692 -146.761206) (xy 388.821334 -146.767153) (xy 388.904821 -146.780978) (xy 388.986646 -146.802561)
			(xy 389.06609 -146.831711) (xy 389.142456 -146.868172) (xy 389.215072 -146.911624) (xy 389.2833 -146.961685)
			(xy 389.34654 -147.017915) (xy 389.404237 -147.07982) (xy 389.455884 -147.146856) (xy 389.501026 -147.218433)
			(xy 389.539268 -147.293923) (xy 389.570272 -147.372662) (xy 389.593767 -147.453959) (xy 389.609546 -147.537098)
			(xy 389.61747 -147.62135) (xy 389.617966 -147.663662) (xy 390.353054 -147.663662) (xy 390.35702 -147.579131)
			(xy 390.368885 -147.495344) (xy 390.388543 -147.413035) (xy 390.415823 -147.332929) (xy 390.450484 -147.25573)
			(xy 390.492222 -147.182115) (xy 390.540669 -147.112732) (xy 390.595401 -147.048191) (xy 390.655937 -146.989059)
			(xy 390.721743 -146.935855) (xy 390.792243 -146.889047) (xy 390.866815 -146.849046) (xy 390.944806 -146.816204)
			(xy 391.02553 -146.79081) (xy 391.108277 -146.773087) (xy 391.192319 -146.763189) (xy 391.27692 -146.761206)
			(xy 391.361334 -146.767153) (xy 391.444821 -146.780978) (xy 391.526646 -146.802561) (xy 391.60609 -146.831711)
			(xy 391.682456 -146.868172) (xy 391.755072 -146.911624) (xy 391.8233 -146.961685) (xy 391.88654 -147.017915)
			(xy 391.944237 -147.07982) (xy 391.995884 -147.146856) (xy 392.041026 -147.218433) (xy 392.079268 -147.293923)
			(xy 392.110272 -147.372662) (xy 392.123901 -147.419822) (xy 396.174466 -147.419822) (xy 396.178537 -147.3642)
			(xy 396.190663 -147.309763) (xy 396.210586 -147.257672) (xy 396.237882 -147.209037) (xy 396.271968 -147.164894)
			(xy 396.312117 -147.126185) (xy 396.357475 -147.093734) (xy 396.407075 -147.068233) (xy 396.459859 -147.050226)
			(xy 396.514702 -147.040096) (xy 396.570436 -147.038059) (xy 396.625873 -147.044159) (xy 396.644322 -147.048982)
			(xy 399.016726 -147.048982) (xy 399.020797 -146.99336) (xy 399.032923 -146.938923) (xy 399.052846 -146.886832)
			(xy 399.080142 -146.838197) (xy 399.114228 -146.794054) (xy 399.154377 -146.755345) (xy 399.199735 -146.722894)
			(xy 399.249335 -146.697393) (xy 399.302119 -146.679386) (xy 399.356962 -146.669256) (xy 399.412696 -146.667219)
			(xy 399.468133 -146.673319) (xy 399.52209 -146.687425) (xy 399.573419 -146.709237) (xy 399.621025 -146.738291)
			(xy 399.663893 -146.773966) (xy 399.70111 -146.815503) (xy 399.731883 -146.862016) (xy 399.755555 -146.912513)
			(xy 399.771623 -146.96592) (xy 399.779743 -147.021096) (xy 399.780252 -147.048982) (xy 399.779743 -147.076868)
			(xy 399.771623 -147.132044) (xy 399.755555 -147.185451) (xy 399.731883 -147.235948) (xy 399.70111 -147.282461)
			(xy 399.663893 -147.323998) (xy 399.621025 -147.359673) (xy 399.573419 -147.388727) (xy 399.52209 -147.410539)
			(xy 399.468133 -147.424645) (xy 399.412696 -147.430745) (xy 399.356962 -147.428708) (xy 399.302119 -147.418578)
			(xy 399.249335 -147.400571) (xy 399.199735 -147.37507) (xy 399.154377 -147.342619) (xy 399.114228 -147.30391)
			(xy 399.080142 -147.259767) (xy 399.052846 -147.211132) (xy 399.032923 -147.159041) (xy 399.020797 -147.104604)
			(xy 399.016726 -147.048982) (xy 396.644322 -147.048982) (xy 396.67983 -147.058265) (xy 396.731159 -147.080077)
			(xy 396.778765 -147.109131) (xy 396.821633 -147.144806) (xy 396.85885 -147.186343) (xy 396.889623 -147.232856)
			(xy 396.913295 -147.283353) (xy 396.929363 -147.33676) (xy 396.937483 -147.391936) (xy 396.937992 -147.419822)
			(xy 396.937483 -147.447708) (xy 396.929363 -147.502884) (xy 396.913295 -147.556291) (xy 396.889623 -147.606788)
			(xy 396.85885 -147.653301) (xy 396.821633 -147.694838) (xy 396.778765 -147.730513) (xy 396.731159 -147.759567)
			(xy 396.67983 -147.781379) (xy 396.625873 -147.795485) (xy 396.570436 -147.801585) (xy 396.514702 -147.799548)
			(xy 396.459859 -147.789418) (xy 396.407075 -147.771411) (xy 396.357475 -147.74591) (xy 396.312117 -147.713459)
			(xy 396.271968 -147.67475) (xy 396.237882 -147.630607) (xy 396.210586 -147.581972) (xy 396.190663 -147.529881)
			(xy 396.178537 -147.475444) (xy 396.174466 -147.419822) (xy 392.123901 -147.419822) (xy 392.133767 -147.453959)
			(xy 392.149546 -147.537098) (xy 392.15747 -147.62135) (xy 392.157966 -147.663662) (xy 392.15747 -147.705974)
			(xy 392.149546 -147.790226) (xy 392.133767 -147.873365) (xy 392.110272 -147.954662) (xy 392.079268 -148.033401)
			(xy 392.041026 -148.108891) (xy 391.995884 -148.180468) (xy 391.944237 -148.247504) (xy 391.88654 -148.309409)
			(xy 391.8233 -148.365639) (xy 391.755072 -148.4157) (xy 391.722566 -148.435151) (xy 396.37106 -148.435151)
			(xy 396.37106 -148.380649) (xy 396.378816 -148.326702) (xy 396.39417 -148.274408) (xy 396.416809 -148.22483)
			(xy 396.446274 -148.17898) (xy 396.481963 -148.137788) (xy 396.523151 -148.102095) (xy 396.568999 -148.072627)
			(xy 396.618574 -148.049982) (xy 396.670867 -148.034623) (xy 396.724813 -148.026862) (xy 396.752064 -148.026374)
			(xy 396.779321 -148.026858) (xy 396.833275 -148.034645) (xy 396.885571 -148.050035) (xy 396.935143 -148.072716)
			(xy 396.958312 -148.08708) (xy 396.958566 -148.087334) (xy 396.96629 -148.091888) (xy 396.983796 -148.09573)
			(xy 397.001549 -148.093276) (xy 397.00962 -148.089366) (xy 397.088106 -148.04771) (xy 397.095775 -148.043174)
			(xy 397.107666 -148.029923) (xy 397.114329 -148.013413) (xy 397.11503 -148.00453) (xy 397.11503 -148.004022)
			(xy 397.116159 -147.977253) (xy 397.125045 -147.924417) (xy 397.141239 -147.873345) (xy 397.164422 -147.825043)
			(xy 397.194139 -147.780461) (xy 397.229803 -147.740478) (xy 397.270714 -147.705881) (xy 397.316064 -147.677352)
			(xy 397.364961 -147.655451) (xy 397.416443 -147.64061) (xy 397.469495 -147.633122) (xy 397.496284 -147.632674)
			(xy 397.523534 -147.633193) (xy 397.57748 -147.640947) (xy 397.629773 -147.656299) (xy 397.679348 -147.678937)
			(xy 397.725198 -147.7084) (xy 397.766388 -147.744088) (xy 397.80208 -147.785275) (xy 397.831547 -147.831122)
			(xy 397.854189 -147.880696) (xy 397.869546 -147.932987) (xy 397.877304 -147.986932) (xy 397.877792 -148.014182)
			(xy 398.003776 -148.014182) (xy 398.004262 -147.986931) (xy 398.012018 -147.932983) (xy 398.027373 -147.880688)
			(xy 398.050015 -147.831111) (xy 398.079481 -147.785261) (xy 398.115172 -147.74407) (xy 398.156363 -147.708379)
			(xy 398.202213 -147.678913) (xy 398.25179 -147.656271) (xy 398.304085 -147.640916) (xy 398.358033 -147.63316)
			(xy 398.412535 -147.63316) (xy 398.466483 -147.640916) (xy 398.518778 -147.656271) (xy 398.568355 -147.678913)
			(xy 398.614205 -147.708379) (xy 398.655396 -147.74407) (xy 398.691087 -147.785261) (xy 398.720553 -147.831111)
			(xy 398.743195 -147.880688) (xy 398.75855 -147.932983) (xy 398.759269 -147.937982) (xy 399.016726 -147.937982)
			(xy 399.020797 -147.88236) (xy 399.032923 -147.827923) (xy 399.052846 -147.775832) (xy 399.080142 -147.727197)
			(xy 399.114228 -147.683054) (xy 399.154377 -147.644345) (xy 399.199735 -147.611894) (xy 399.249335 -147.586393)
			(xy 399.302119 -147.568386) (xy 399.356962 -147.558256) (xy 399.412696 -147.556219) (xy 399.468133 -147.562319)
			(xy 399.52209 -147.576425) (xy 399.573419 -147.598237) (xy 399.621025 -147.627291) (xy 399.663893 -147.662966)
			(xy 399.70111 -147.704503) (xy 399.731883 -147.751016) (xy 399.755555 -147.801513) (xy 399.771623 -147.85492)
			(xy 399.779743 -147.910096) (xy 399.780252 -147.937982) (xy 399.779743 -147.965868) (xy 399.771623 -148.021044)
			(xy 399.755555 -148.074451) (xy 399.731883 -148.124948) (xy 399.70111 -148.171461) (xy 399.663893 -148.212998)
			(xy 399.621025 -148.248673) (xy 399.573419 -148.277727) (xy 399.52209 -148.299539) (xy 399.468133 -148.313645)
			(xy 399.412696 -148.319745) (xy 399.356962 -148.317708) (xy 399.302119 -148.307578) (xy 399.249335 -148.289571)
			(xy 399.199735 -148.26407) (xy 399.154377 -148.231619) (xy 399.114228 -148.19291) (xy 399.080142 -148.148767)
			(xy 399.052846 -148.100132) (xy 399.032923 -148.048041) (xy 399.020797 -147.993604) (xy 399.016726 -147.937982)
			(xy 398.759269 -147.937982) (xy 398.766306 -147.986931) (xy 398.766792 -148.014182) (xy 398.766326 -148.041728)
			(xy 398.75841 -148.096247) (xy 398.742727 -148.149059) (xy 398.719603 -148.199062) (xy 398.68952 -148.245215)
			(xy 398.653105 -148.286555) (xy 398.632426 -148.304758) (xy 398.621425 -148.314681) (xy 398.605327 -148.339543)
			(xy 398.59703 -148.367976) (xy 398.597231 -148.397594) (xy 398.605912 -148.425912) (xy 398.622345 -148.450554)
			(xy 398.645152 -148.469452) (xy 398.658588 -148.4757) (xy 398.684099 -148.487036) (xy 398.731775 -148.516077)
			(xy 398.774711 -148.551755) (xy 398.811989 -148.593309) (xy 398.842815 -148.639851) (xy 398.86653 -148.690388)
			(xy 398.882628 -148.743841) (xy 398.890765 -148.79907) (xy 398.891252 -148.826982) (xy 399.016726 -148.826982)
			(xy 399.020797 -148.77136) (xy 399.032923 -148.716923) (xy 399.052846 -148.664832) (xy 399.080142 -148.616197)
			(xy 399.114228 -148.572054) (xy 399.154377 -148.533345) (xy 399.199735 -148.500894) (xy 399.249335 -148.475393)
			(xy 399.302119 -148.457386) (xy 399.356962 -148.447256) (xy 399.412696 -148.445219) (xy 399.468133 -148.451319)
			(xy 399.52209 -148.465425) (xy 399.573419 -148.487237) (xy 399.621025 -148.516291) (xy 399.663893 -148.551966)
			(xy 399.70111 -148.593503) (xy 399.731883 -148.640016) (xy 399.755555 -148.690513) (xy 399.771623 -148.74392)
			(xy 399.779743 -148.799096) (xy 399.780252 -148.826982) (xy 399.779743 -148.854868) (xy 399.771623 -148.910044)
			(xy 399.755555 -148.963451) (xy 399.731883 -149.013948) (xy 399.70111 -149.060461) (xy 399.663893 -149.101998)
			(xy 399.621025 -149.137673) (xy 399.573419 -149.166727) (xy 399.52209 -149.188539) (xy 399.468133 -149.202645)
			(xy 399.412696 -149.208745) (xy 399.356962 -149.206708) (xy 399.302119 -149.196578) (xy 399.249335 -149.178571)
			(xy 399.199735 -149.15307) (xy 399.154377 -149.120619) (xy 399.114228 -149.08191) (xy 399.080142 -149.037767)
			(xy 399.052846 -148.989132) (xy 399.032923 -148.937041) (xy 399.020797 -148.882604) (xy 399.016726 -148.826982)
			(xy 398.891252 -148.826982) (xy 398.890766 -148.854233) (xy 398.88301 -148.908181) (xy 398.867655 -148.960476)
			(xy 398.845013 -149.010053) (xy 398.815547 -149.055903) (xy 398.779856 -149.097094) (xy 398.738665 -149.132785)
			(xy 398.692815 -149.162251) (xy 398.643238 -149.184893) (xy 398.590943 -149.200248) (xy 398.536995 -149.208004)
			(xy 398.482493 -149.208004) (xy 398.428545 -149.200248) (xy 398.37625 -149.184893) (xy 398.326673 -149.162251)
			(xy 398.280823 -149.132785) (xy 398.239632 -149.097094) (xy 398.203941 -149.055903) (xy 398.174475 -149.010053)
			(xy 398.151833 -148.960476) (xy 398.136478 -148.908181) (xy 398.128722 -148.854233) (xy 398.128236 -148.826982)
			(xy 398.128737 -148.799437) (xy 398.136644 -148.744919) (xy 398.15232 -148.692108) (xy 398.175437 -148.642104)
			(xy 398.205514 -148.595951) (xy 398.241925 -148.55461) (xy 398.262602 -148.536406) (xy 398.273524 -148.526404)
			(xy 398.289618 -148.501561) (xy 398.297918 -148.473148) (xy 398.297727 -148.443548) (xy 398.289062 -148.415245)
			(xy 398.272649 -148.390611) (xy 398.249865 -148.371715) (xy 398.23644 -148.365464) (xy 398.210921 -148.354143)
			(xy 398.163243 -148.325102) (xy 398.120306 -148.289422) (xy 398.083027 -148.247867) (xy 398.052202 -148.201322)
			(xy 398.028489 -148.150782) (xy 398.012394 -148.097326) (xy 398.004261 -148.042095) (xy 398.003776 -148.014182)
			(xy 397.877792 -148.014182) (xy 397.877326 -148.041728) (xy 397.86941 -148.096247) (xy 397.853727 -148.149059)
			(xy 397.830603 -148.199062) (xy 397.80052 -148.245215) (xy 397.764105 -148.286555) (xy 397.743426 -148.304758)
			(xy 397.733266 -148.313394) (xy 397.724122 -148.337778) (xy 397.74114 -148.449792) (xy 397.757396 -148.47062)
			(xy 397.769588 -148.4757) (xy 397.795099 -148.487036) (xy 397.842775 -148.516077) (xy 397.885711 -148.551755)
			(xy 397.922989 -148.593309) (xy 397.953815 -148.639851) (xy 397.97753 -148.690388) (xy 397.993628 -148.743841)
			(xy 398.001765 -148.79907) (xy 398.002252 -148.826982) (xy 398.001766 -148.854233) (xy 397.99401 -148.908181)
			(xy 397.978655 -148.960476) (xy 397.956013 -149.010053) (xy 397.926547 -149.055903) (xy 397.890856 -149.097094)
			(xy 397.849665 -149.132785) (xy 397.803815 -149.162251) (xy 397.754238 -149.184893) (xy 397.701943 -149.200248)
			(xy 397.647995 -149.208004) (xy 397.593493 -149.208004) (xy 397.539545 -149.200248) (xy 397.48725 -149.184893)
			(xy 397.437673 -149.162251) (xy 397.391823 -149.132785) (xy 397.350632 -149.097094) (xy 397.314941 -149.055903)
			(xy 397.285475 -149.010053) (xy 397.262833 -148.960476) (xy 397.247478 -148.908181) (xy 397.239722 -148.854233)
			(xy 397.239236 -148.826982) (xy 397.239737 -148.799437) (xy 397.247644 -148.744919) (xy 397.26332 -148.692108)
			(xy 397.286437 -148.642104) (xy 397.316514 -148.595951) (xy 397.352925 -148.55461) (xy 397.373602 -148.536406)
			(xy 397.383762 -148.52777) (xy 397.392906 -148.503386) (xy 397.375888 -148.391372) (xy 397.359632 -148.370544)
			(xy 397.34744 -148.365464) (xy 397.332538 -148.35893) (xy 397.303797 -148.343668) (xy 397.290036 -148.334984)
			(xy 397.289782 -148.33473) (xy 397.282039 -148.330214) (xy 397.264545 -148.326362) (xy 397.246799 -148.328799)
			(xy 397.238728 -148.332698) (xy 397.160242 -148.374354) (xy 397.152577 -148.378895) (xy 397.14069 -148.392146)
			(xy 397.134023 -148.408653) (xy 397.133318 -148.417534) (xy 397.133318 -148.418042) (xy 397.132108 -148.444806)
			(xy 397.123229 -148.497636) (xy 397.107042 -148.548704) (xy 397.083867 -148.597004) (xy 397.054158 -148.641584)
			(xy 397.018502 -148.681566) (xy 396.9776 -148.716164) (xy 396.932258 -148.744696) (xy 396.883369 -148.7666)
			(xy 396.831895 -148.781445) (xy 396.77885 -148.788939) (xy 396.752064 -148.78939) (xy 396.724813 -148.788938)
			(xy 396.670867 -148.781177) (xy 396.618574 -148.765818) (xy 396.568999 -148.743173) (xy 396.523151 -148.713705)
			(xy 396.481963 -148.678012) (xy 396.446274 -148.63682) (xy 396.416809 -148.59097) (xy 396.39417 -148.541392)
			(xy 396.378816 -148.489098) (xy 396.37106 -148.435151) (xy 391.722566 -148.435151) (xy 391.682456 -148.459152)
			(xy 391.60609 -148.495613) (xy 391.526646 -148.524763) (xy 391.444821 -148.546346) (xy 391.361334 -148.560171)
			(xy 391.27692 -148.566118) (xy 391.192319 -148.564135) (xy 391.108277 -148.554237) (xy 391.02553 -148.536514)
			(xy 390.944806 -148.51112) (xy 390.866815 -148.478278) (xy 390.792243 -148.438277) (xy 390.721743 -148.391469)
			(xy 390.655937 -148.338265) (xy 390.595401 -148.279133) (xy 390.540669 -148.214592) (xy 390.492222 -148.145209)
			(xy 390.450484 -148.071594) (xy 390.415823 -147.994395) (xy 390.388543 -147.914289) (xy 390.368885 -147.83198)
			(xy 390.35702 -147.748193) (xy 390.353054 -147.663662) (xy 389.617966 -147.663662) (xy 389.61747 -147.705974)
			(xy 389.609546 -147.790226) (xy 389.593767 -147.873365) (xy 389.570272 -147.954662) (xy 389.539268 -148.033401)
			(xy 389.501026 -148.108891) (xy 389.455884 -148.180468) (xy 389.404237 -148.247504) (xy 389.34654 -148.309409)
			(xy 389.2833 -148.365639) (xy 389.215072 -148.4157) (xy 389.142456 -148.459152) (xy 389.06609 -148.495613)
			(xy 388.986646 -148.524763) (xy 388.904821 -148.546346) (xy 388.821334 -148.560171) (xy 388.73692 -148.566118)
			(xy 388.652319 -148.564135) (xy 388.568277 -148.554237) (xy 388.48553 -148.536514) (xy 388.404806 -148.51112)
			(xy 388.326815 -148.478278) (xy 388.252243 -148.438277) (xy 388.181743 -148.391469) (xy 388.115937 -148.338265)
			(xy 388.055401 -148.279133) (xy 388.000669 -148.214592) (xy 387.952222 -148.145209) (xy 387.910484 -148.071594)
			(xy 387.875823 -147.994395) (xy 387.848543 -147.914289) (xy 387.828885 -147.83198) (xy 387.81702 -147.748193)
			(xy 387.813054 -147.663662) (xy 378.973604 -147.663662) (xy 378.961644 -147.688146) (xy 378.945648 -147.712176)
			(xy 378.93821 -147.723591) (xy 378.929195 -147.749296) (xy 378.927304 -147.776469) (xy 378.932672 -147.803174)
			(xy 378.944916 -147.827507) (xy 378.963162 -147.847732) (xy 378.98611 -147.862406) (xy 378.998988 -147.866862)
			(xy 379.024571 -147.875301) (xy 379.073263 -147.898344) (xy 379.11823 -147.928006) (xy 379.158579 -147.963697)
			(xy 379.193506 -148.004709) (xy 379.222318 -148.050226) (xy 379.244442 -148.099343) (xy 379.259437 -148.151083)
			(xy 379.267007 -148.204417) (xy 379.267466 -148.231352) (xy 379.26698 -148.258603) (xy 379.259224 -148.312551)
			(xy 379.243869 -148.364846) (xy 379.221227 -148.414423) (xy 379.191761 -148.460273) (xy 379.15607 -148.501464)
			(xy 379.114879 -148.537155) (xy 379.069029 -148.566621) (xy 379.019452 -148.589263) (xy 378.967157 -148.604618)
			(xy 378.913209 -148.612374) (xy 378.858707 -148.612374) (xy 378.804759 -148.604618) (xy 378.752464 -148.589263)
			(xy 378.702887 -148.566621) (xy 378.657037 -148.537155) (xy 378.615846 -148.501464) (xy 378.580155 -148.460273)
			(xy 378.550689 -148.414423) (xy 378.528047 -148.364846) (xy 378.512692 -148.312551) (xy 378.504936 -148.258603)
			(xy 378.50445 -148.231352) (xy 378.50445 -148.230844) (xy 378.504982 -148.201982) (xy 378.513708 -148.14492)
			(xy 378.530936 -148.089826) (xy 378.556272 -148.037958) (xy 378.572268 -148.013928) (xy 378.579693 -148.002505)
			(xy 378.588706 -147.976804) (xy 378.590597 -147.949633) (xy 378.585231 -147.92293) (xy 378.57299 -147.8986)
			(xy 378.554747 -147.878375) (xy 378.531804 -147.863699) (xy 378.518928 -147.859242) (xy 378.49335 -147.85079)
			(xy 378.444657 -147.827749) (xy 378.39969 -147.79809) (xy 378.359341 -147.7624) (xy 378.324413 -147.721389)
			(xy 378.2956 -147.675874) (xy 378.273476 -147.626759) (xy 378.25848 -147.57502) (xy 378.25091 -147.521686)
			(xy 378.25045 -147.494752) (xy 377.398027 -147.494752) (xy 377.397017 -147.501614) (xy 377.380949 -147.555021)
			(xy 377.357277 -147.605518) (xy 377.326504 -147.652031) (xy 377.289287 -147.693568) (xy 377.246419 -147.729243)
			(xy 377.198813 -147.758297) (xy 377.147484 -147.780109) (xy 377.093527 -147.794215) (xy 377.03809 -147.800315)
			(xy 376.982356 -147.798278) (xy 376.927513 -147.788148) (xy 376.874729 -147.770141) (xy 376.825129 -147.74464)
			(xy 376.779771 -147.712189) (xy 376.739622 -147.67348) (xy 376.705536 -147.629337) (xy 376.67824 -147.580702)
			(xy 376.658317 -147.528611) (xy 376.646191 -147.474174) (xy 376.64212 -147.418552) (xy 372.271931 -147.418552)
			(xy 372.278089 -147.431689) (xy 372.294157 -147.485096) (xy 372.302277 -147.540272) (xy 372.302786 -147.568158)
			(xy 372.302277 -147.596044) (xy 372.294157 -147.65122) (xy 372.278089 -147.704627) (xy 372.254417 -147.755124)
			(xy 372.223644 -147.801637) (xy 372.186427 -147.843174) (xy 372.143559 -147.878849) (xy 372.095953 -147.907903)
			(xy 372.044624 -147.929715) (xy 371.990667 -147.943821) (xy 371.93523 -147.949921) (xy 371.879496 -147.947884)
			(xy 371.824653 -147.937754) (xy 371.771869 -147.919747) (xy 371.722269 -147.894246) (xy 371.676911 -147.861795)
			(xy 371.636762 -147.823086) (xy 371.602676 -147.778943) (xy 371.57538 -147.730308) (xy 371.555457 -147.678217)
			(xy 371.543331 -147.62378) (xy 371.53926 -147.568158) (xy 351.299928 -147.568158) (xy 351.309324 -147.662799)
			(xy 351.317314 -147.824175) (xy 351.317814 -147.904962) (xy 351.317314 -147.985749) (xy 351.309324 -148.147125)
			(xy 351.293362 -148.307909) (xy 351.283769 -148.372068) (xy 375.095514 -148.372068) (xy 375.099585 -148.316446)
			(xy 375.111711 -148.262009) (xy 375.131634 -148.209918) (xy 375.15893 -148.161283) (xy 375.193016 -148.11714)
			(xy 375.233165 -148.078431) (xy 375.278523 -148.04598) (xy 375.328123 -148.020479) (xy 375.380907 -148.002472)
			(xy 375.43575 -147.992342) (xy 375.491484 -147.990305) (xy 375.546921 -147.996405) (xy 375.600878 -148.010511)
			(xy 375.652207 -148.032323) (xy 375.699813 -148.061377) (xy 375.742681 -148.097052) (xy 375.779898 -148.138589)
			(xy 375.810671 -148.185102) (xy 375.834343 -148.235599) (xy 375.850411 -148.289006) (xy 375.858531 -148.344182)
			(xy 375.85904 -148.372068) (xy 375.858531 -148.399954) (xy 375.850411 -148.45513) (xy 375.834343 -148.508537)
			(xy 375.810671 -148.559034) (xy 375.779898 -148.605547) (xy 375.742681 -148.647084) (xy 375.699813 -148.682759)
			(xy 375.653696 -148.710904) (xy 376.020074 -148.710904) (xy 376.024145 -148.655282) (xy 376.036271 -148.600845)
			(xy 376.056194 -148.548754) (xy 376.08349 -148.500119) (xy 376.117576 -148.455976) (xy 376.157725 -148.417267)
			(xy 376.203083 -148.384816) (xy 376.252683 -148.359315) (xy 376.305467 -148.341308) (xy 376.36031 -148.331178)
			(xy 376.416044 -148.329141) (xy 376.471481 -148.335241) (xy 376.525438 -148.349347) (xy 376.576767 -148.371159)
			(xy 376.624373 -148.400213) (xy 376.667241 -148.435888) (xy 376.704458 -148.477425) (xy 376.735231 -148.523938)
			(xy 376.758903 -148.574435) (xy 376.774971 -148.627842) (xy 376.783091 -148.683018) (xy 376.7836 -148.710904)
			(xy 376.783091 -148.73879) (xy 376.777027 -148.779992) (xy 377.483622 -148.779992) (xy 377.487693 -148.72437)
			(xy 377.499819 -148.669933) (xy 377.519742 -148.617842) (xy 377.547038 -148.569207) (xy 377.581124 -148.525064)
			(xy 377.621273 -148.486355) (xy 377.666631 -148.453904) (xy 377.716231 -148.428403) (xy 377.769015 -148.410396)
			(xy 377.823858 -148.400266) (xy 377.879592 -148.398229) (xy 377.935029 -148.404329) (xy 377.988986 -148.418435)
			(xy 378.040315 -148.440247) (xy 378.087921 -148.469301) (xy 378.130789 -148.504976) (xy 378.168006 -148.546513)
			(xy 378.198779 -148.593026) (xy 378.222451 -148.643523) (xy 378.238519 -148.69693) (xy 378.246639 -148.752106)
			(xy 378.247148 -148.779992) (xy 378.246639 -148.807878) (xy 378.238519 -148.863054) (xy 378.222451 -148.916461)
			(xy 378.198779 -148.966958) (xy 378.168006 -149.013471) (xy 378.130789 -149.055008) (xy 378.087921 -149.090683)
			(xy 378.040315 -149.119737) (xy 377.988986 -149.141549) (xy 377.935029 -149.155655) (xy 377.879592 -149.161755)
			(xy 377.823858 -149.159718) (xy 377.769015 -149.149588) (xy 377.716231 -149.131581) (xy 377.666631 -149.10608)
			(xy 377.621273 -149.073629) (xy 377.581124 -149.03492) (xy 377.547038 -148.990777) (xy 377.519742 -148.942142)
			(xy 377.499819 -148.890051) (xy 377.487693 -148.835614) (xy 377.483622 -148.779992) (xy 376.777027 -148.779992)
			(xy 376.774971 -148.793966) (xy 376.758903 -148.847373) (xy 376.735231 -148.89787) (xy 376.704458 -148.944383)
			(xy 376.667241 -148.98592) (xy 376.624373 -149.021595) (xy 376.576767 -149.050649) (xy 376.525438 -149.072461)
			(xy 376.471481 -149.086567) (xy 376.416044 -149.092667) (xy 376.36031 -149.09063) (xy 376.305467 -149.0805)
			(xy 376.252683 -149.062493) (xy 376.203083 -149.036992) (xy 376.157725 -149.004541) (xy 376.117576 -148.965832)
			(xy 376.08349 -148.921689) (xy 376.056194 -148.873054) (xy 376.036271 -148.820963) (xy 376.024145 -148.766526)
			(xy 376.020074 -148.710904) (xy 375.653696 -148.710904) (xy 375.652207 -148.711813) (xy 375.600878 -148.733625)
			(xy 375.546921 -148.747731) (xy 375.491484 -148.753831) (xy 375.43575 -148.751794) (xy 375.380907 -148.741664)
			(xy 375.328123 -148.723657) (xy 375.278523 -148.698156) (xy 375.233165 -148.665705) (xy 375.193016 -148.626996)
			(xy 375.15893 -148.582853) (xy 375.131634 -148.534218) (xy 375.111711 -148.482127) (xy 375.099585 -148.42769)
			(xy 375.095514 -148.372068) (xy 351.283769 -148.372068) (xy 351.269469 -148.467707) (xy 351.237703 -148.626127)
			(xy 351.198141 -148.782783) (xy 351.15088 -148.937291) (xy 351.096036 -149.089272) (xy 351.033743 -149.238355)
			(xy 350.964153 -149.384175) (xy 350.887438 -149.526375) (xy 350.803783 -149.664607) (xy 350.713396 -149.798534)
			(xy 350.616495 -149.927826) (xy 350.513319 -150.052168) (xy 350.40412 -150.171255) (xy 350.289166 -150.284796)
			(xy 350.168737 -150.392514) (xy 350.043129 -150.494144) (xy 349.912648 -150.589438) (xy 349.777614 -150.678163)
			(xy 349.638358 -150.760101) (xy 349.49522 -150.835052) (xy 349.34855 -150.902832) (xy 349.198708 -150.963277)
			(xy 349.04606 -151.016237) (xy 348.89098 -151.061583) (xy 348.733847 -151.099205) (xy 348.575045 -151.129009)
			(xy 348.414964 -151.150924) (xy 348.253995 -151.164896) (xy 348.092533 -151.17089) (xy 347.930971 -151.168891)
			(xy 347.769706 -151.158906) (xy 347.609132 -151.140957) (xy 347.449642 -151.115089) (xy 347.291626 -151.081366)
			(xy 347.135472 -151.039869) (xy 346.981561 -150.990701) (xy 346.830269 -150.933981) (xy 346.681968 -150.869849)
			(xy 346.53702 -150.798461) (xy 346.395779 -150.719993) (xy 346.258592 -150.634635) (xy 346.125794 -150.542598)
			(xy 345.997711 -150.444106) (xy 345.874654 -150.3394) (xy 345.756927 -150.228737) (xy 345.644816 -150.112387)
			(xy 345.538596 -149.990635) (xy 345.438527 -149.863779) (xy 345.344854 -149.732129) (xy 345.257807 -149.596009)
			(xy 345.177597 -149.455749) (xy 345.104422 -149.311695) (xy 345.038461 -149.164199) (xy 344.979874 -149.01362)
			(xy 344.928806 -148.860329) (xy 344.885381 -148.7047) (xy 344.849706 -148.547114) (xy 344.821868 -148.387956)
			(xy 344.801934 -148.227616) (xy 344.789955 -148.066487) (xy 344.785959 -147.904962) (xy 327.7235 -147.904962)
			(xy 327.7235 -152.278151) (xy 329.15858 -152.278151) (xy 329.15858 -152.223649) (xy 329.166336 -152.169701)
			(xy 329.181691 -152.117407) (xy 329.204332 -152.06783) (xy 329.233798 -152.02198) (xy 329.26949 -151.98079)
			(xy 329.31068 -151.945098) (xy 329.35653 -151.915632) (xy 329.406107 -151.892991) (xy 329.458401 -151.877636)
			(xy 329.512349 -151.86988) (xy 329.5396 -151.869394) (xy 329.568519 -151.869877) (xy 329.625693 -151.878608)
			(xy 329.680894 -151.895871) (xy 329.732857 -151.921269) (xy 329.780389 -151.95422) (xy 329.822403 -151.99397)
			(xy 329.84059 -152.01646) (xy 329.848201 -152.025263) (xy 329.869099 -152.035446) (xy 329.880722 -152.036018)
			(xy 329.960478 -152.036018) (xy 329.972106 -152.035446) (xy 329.993015 -152.02528) (xy 330.00061 -152.01646)
			(xy 330.018785 -151.993963) (xy 330.060809 -151.954231) (xy 330.108348 -151.921295) (xy 330.160312 -151.895909)
			(xy 330.215512 -151.878655) (xy 330.272683 -151.869928) (xy 330.3016 -151.869394) (xy 330.328851 -151.869876)
			(xy 330.382799 -151.877632) (xy 330.435094 -151.892988) (xy 330.484672 -151.915629) (xy 330.530523 -151.945095)
			(xy 330.571713 -151.980787) (xy 330.607405 -152.021977) (xy 330.636871 -152.067828) (xy 330.659512 -152.117406)
			(xy 330.674868 -152.169701) (xy 330.682624 -152.223649) (xy 330.682624 -152.278151) (xy 330.674868 -152.332099)
			(xy 330.659512 -152.384394) (xy 330.636871 -152.433972) (xy 330.607405 -152.479823) (xy 330.571713 -152.521013)
			(xy 330.530523 -152.556705) (xy 330.484672 -152.586171) (xy 330.435094 -152.608812) (xy 330.382799 -152.624168)
			(xy 330.328851 -152.631924) (xy 330.3016 -152.63241) (xy 330.272681 -152.631926) (xy 330.215507 -152.623195)
			(xy 330.160306 -152.605932) (xy 330.108344 -152.580534) (xy 330.060811 -152.547583) (xy 330.018798 -152.507834)
			(xy 330.00061 -152.485344) (xy 329.992998 -152.476542) (xy 329.972101 -152.466358) (xy 329.960478 -152.465786)
			(xy 329.880722 -152.465786) (xy 329.869094 -152.466357) (xy 329.848185 -152.476524) (xy 329.84059 -152.485344)
			(xy 329.822416 -152.507841) (xy 329.780391 -152.547574) (xy 329.732852 -152.58051) (xy 329.680888 -152.605895)
			(xy 329.625688 -152.623149) (xy 329.568517 -152.631876) (xy 329.5396 -152.63241) (xy 329.512349 -152.63192)
			(xy 329.458401 -152.624164) (xy 329.406107 -152.608809) (xy 329.35653 -152.586168) (xy 329.31068 -152.556702)
			(xy 329.26949 -152.52101) (xy 329.233798 -152.47982) (xy 329.204332 -152.43397) (xy 329.181691 -152.384393)
			(xy 329.166336 -152.332099) (xy 329.15858 -152.278151) (xy 327.7235 -152.278151) (xy 327.7235 -155.7274)
			(xy 331.734177 -155.7274) (xy 331.737907 -155.674149) (xy 331.749022 -155.621938) (xy 331.767307 -155.571787)
			(xy 331.792405 -155.524673) (xy 331.823824 -155.481518) (xy 331.860952 -155.443164) (xy 331.881734 -155.42641)
			(xy 331.890532 -155.418795) (xy 331.900719 -155.3979) (xy 331.901292 -155.386278) (xy 331.901292 -155.306522)
			(xy 331.900729 -155.294893) (xy 331.890557 -155.273983) (xy 331.881734 -155.26639) (xy 331.860952 -155.249636)
			(xy 331.823824 -155.211282) (xy 331.792405 -155.168127) (xy 331.767307 -155.121013) (xy 331.749022 -155.070862)
			(xy 331.737907 -155.018651) (xy 331.734177 -154.9654) (xy 331.737907 -154.912149) (xy 331.749022 -154.859938)
			(xy 331.767307 -154.809787) (xy 331.792405 -154.762673) (xy 331.823824 -154.719518) (xy 331.860952 -154.681164)
			(xy 331.881734 -154.66441) (xy 331.890532 -154.656795) (xy 331.900719 -154.6359) (xy 331.901292 -154.624278)
			(xy 331.901292 -154.544522) (xy 331.900729 -154.532893) (xy 331.890557 -154.511983) (xy 331.881734 -154.50439)
			(xy 331.860952 -154.487636) (xy 331.823824 -154.449282) (xy 331.792405 -154.406127) (xy 331.767307 -154.359013)
			(xy 331.749022 -154.308862) (xy 331.737907 -154.256651) (xy 331.734177 -154.2034) (xy 331.737907 -154.150149)
			(xy 331.749022 -154.097938) (xy 331.767307 -154.047787) (xy 331.792405 -154.000673) (xy 331.823824 -153.957518)
			(xy 331.860952 -153.919164) (xy 331.881734 -153.90241) (xy 331.890532 -153.894795) (xy 331.900719 -153.8739)
			(xy 331.901292 -153.862278) (xy 331.901292 -153.782522) (xy 331.900729 -153.770893) (xy 331.890557 -153.749983)
			(xy 331.881734 -153.74239) (xy 331.859253 -153.724196) (xy 331.819516 -153.682178) (xy 331.786576 -153.634644)
			(xy 331.761187 -153.582683) (xy 331.74393 -153.527486) (xy 331.735202 -153.470316) (xy 331.734668 -153.4414)
			(xy 331.735141 -153.413574) (xy 331.743205 -153.358509) (xy 331.759192 -153.305202) (xy 331.782761 -153.254788)
			(xy 331.813411 -153.208336) (xy 331.85049 -153.166836) (xy 331.893211 -153.13117) (xy 331.940664 -153.102095)
			(xy 331.991842 -153.08023) (xy 332.045654 -153.066041) (xy 332.07325 -153.062432) (xy 332.073504 -153.062432)
			(xy 332.08422 -153.060592) (xy 332.102762 -153.049265) (xy 332.109318 -153.040588) (xy 332.159102 -152.967436)
			(xy 332.162658 -152.945592) (xy 332.159864 -152.934924) (xy 332.153701 -152.910559) (xy 332.147074 -152.860739)
			(xy 332.146656 -152.83561) (xy 332.146656 -152.835102) (xy 332.147142 -152.807127) (xy 332.155319 -152.751777)
			(xy 332.171498 -152.698217) (xy 332.195332 -152.647597) (xy 332.21041 -152.624028) (xy 332.215744 -152.616154)
			(xy 332.219554 -152.597866) (xy 332.206346 -152.511252) (xy 332.196948 -152.494742) (xy 332.189582 -152.4889)
			(xy 332.167824 -152.470683) (xy 332.129417 -152.428912) (xy 332.097623 -152.381911) (xy 332.073143 -152.330719)
			(xy 332.056518 -152.276465) (xy 332.048115 -152.220346) (xy 332.047596 -152.191974) (xy 332.048082 -152.164723)
			(xy 332.055838 -152.110775) (xy 332.071193 -152.05848) (xy 332.093835 -152.008903) (xy 332.123301 -151.963053)
			(xy 332.158992 -151.921862) (xy 332.200183 -151.886171) (xy 332.246033 -151.856705) (xy 332.29561 -151.834063)
			(xy 332.347905 -151.818708) (xy 332.401853 -151.810952) (xy 332.456355 -151.810952) (xy 332.510303 -151.818708)
			(xy 332.562598 -151.834063) (xy 332.612175 -151.856705) (xy 332.658025 -151.886171) (xy 332.699216 -151.921862)
			(xy 332.734907 -151.963053) (xy 332.764373 -152.008903) (xy 332.787015 -152.05848) (xy 332.80237 -152.110775)
			(xy 332.810126 -152.164723) (xy 332.810612 -152.191974) (xy 332.81012 -152.219949) (xy 332.801945 -152.275299)
			(xy 332.785768 -152.328859) (xy 332.761936 -152.379479) (xy 332.746858 -152.403048) (xy 332.741524 -152.410922)
			(xy 332.737714 -152.42921) (xy 332.74151 -152.454102) (xy 334.204056 -152.454102) (xy 334.204555 -152.425184)
			(xy 334.213285 -152.368011) (xy 334.230545 -152.312811) (xy 334.25594 -152.260849) (xy 334.288888 -152.213316)
			(xy 334.328634 -152.171301) (xy 334.351122 -152.153112) (xy 334.359918 -152.145494) (xy 334.370107 -152.124601)
			(xy 334.37068 -152.11298) (xy 334.37068 -152.033224) (xy 334.37012 -152.021595) (xy 334.359947 -152.000684)
			(xy 334.351122 -151.993092) (xy 334.328639 -151.9749) (xy 334.288903 -151.932881) (xy 334.255963 -151.885347)
			(xy 334.230575 -151.833385) (xy 334.213319 -151.778188) (xy 334.20459 -151.721018) (xy 334.204056 -151.692102)
			(xy 334.204542 -151.664851) (xy 334.212298 -151.610903) (xy 334.227653 -151.558608) (xy 334.250295 -151.509031)
			(xy 334.279761 -151.463181) (xy 334.315452 -151.42199) (xy 334.356643 -151.386299) (xy 334.402493 -151.356833)
			(xy 334.45207 -151.334191) (xy 334.504365 -151.318836) (xy 334.558313 -151.31108) (xy 334.612815 -151.31108)
			(xy 334.666763 -151.318836) (xy 334.719058 -151.334191) (xy 334.768635 -151.356833) (xy 334.814485 -151.386299)
			(xy 334.855676 -151.42199) (xy 334.891367 -151.463181) (xy 334.920833 -151.509031) (xy 334.943475 -151.558608)
			(xy 334.95883 -151.610903) (xy 334.966586 -151.664851) (xy 334.967072 -151.692102) (xy 334.966566 -151.721019)
			(xy 334.957836 -151.778192) (xy 334.940576 -151.833391) (xy 334.915182 -151.885353) (xy 334.882236 -151.932887)
			(xy 334.842493 -151.974903) (xy 334.820006 -151.993092) (xy 334.811213 -152.000713) (xy 334.801021 -152.021603)
			(xy 334.800448 -152.033224) (xy 334.800448 -152.11298) (xy 334.800996 -152.124611) (xy 334.811177 -152.145522)
			(xy 334.820006 -152.153112) (xy 334.842496 -152.171295) (xy 334.882231 -152.213316) (xy 334.915169 -152.260853)
			(xy 334.940556 -152.312816) (xy 334.957811 -152.368015) (xy 334.966538 -152.425186) (xy 334.967072 -152.454102)
			(xy 336.261456 -152.454102) (xy 336.261955 -152.425184) (xy 336.270685 -152.368011) (xy 336.287945 -152.312811)
			(xy 336.31334 -152.260849) (xy 336.346288 -152.213316) (xy 336.386034 -152.171301) (xy 336.408522 -152.153112)
			(xy 336.417318 -152.145494) (xy 336.427507 -152.124601) (xy 336.42808 -152.11298) (xy 336.42808 -152.033224)
			(xy 336.42752 -152.021595) (xy 336.417347 -152.000684) (xy 336.408522 -151.993092) (xy 336.386039 -151.9749)
			(xy 336.346303 -151.932881) (xy 336.313363 -151.885347) (xy 336.287975 -151.833385) (xy 336.270719 -151.778188)
			(xy 336.26199 -151.721018) (xy 336.261456 -151.692102) (xy 336.261942 -151.664851) (xy 336.269698 -151.610903)
			(xy 336.285053 -151.558608) (xy 336.307695 -151.509031) (xy 336.337161 -151.463181) (xy 336.372852 -151.42199)
			(xy 336.414043 -151.386299) (xy 336.459893 -151.356833) (xy 336.50947 -151.334191) (xy 336.561765 -151.318836)
			(xy 336.615713 -151.31108) (xy 336.670215 -151.31108) (xy 336.724163 -151.318836) (xy 336.776458 -151.334191)
			(xy 336.826035 -151.356833) (xy 336.871885 -151.386299) (xy 336.913076 -151.42199) (xy 336.948767 -151.463181)
			(xy 336.978233 -151.509031) (xy 337.000875 -151.558608) (xy 337.01623 -151.610903) (xy 337.023986 -151.664851)
			(xy 337.024472 -151.692102) (xy 337.023966 -151.721019) (xy 337.015236 -151.778192) (xy 336.997976 -151.833391)
			(xy 336.972582 -151.885353) (xy 336.939636 -151.932887) (xy 336.899893 -151.974903) (xy 336.877406 -151.993092)
			(xy 336.868613 -152.000713) (xy 336.858421 -152.021603) (xy 336.857848 -152.033224) (xy 336.857848 -152.11298)
			(xy 336.858396 -152.124611) (xy 336.868577 -152.145522) (xy 336.877406 -152.153112) (xy 336.899896 -152.171295)
			(xy 336.939631 -152.213316) (xy 336.972569 -152.260853) (xy 336.997956 -152.312816) (xy 337.015211 -152.368015)
			(xy 337.023938 -152.425186) (xy 337.024472 -152.454102) (xy 337.023986 -152.481353) (xy 337.01623 -152.535301)
			(xy 337.000875 -152.587596) (xy 336.978233 -152.637173) (xy 336.948767 -152.683023) (xy 336.913076 -152.724214)
			(xy 336.871885 -152.759905) (xy 336.826035 -152.789371) (xy 336.776458 -152.812013) (xy 336.724163 -152.827368)
			(xy 336.670215 -152.835124) (xy 336.615713 -152.835124) (xy 336.561765 -152.827368) (xy 336.50947 -152.812013)
			(xy 336.459893 -152.789371) (xy 336.414043 -152.759905) (xy 336.372852 -152.724214) (xy 336.337161 -152.683023)
			(xy 336.307695 -152.637173) (xy 336.285053 -152.587596) (xy 336.269698 -152.535301) (xy 336.261942 -152.481353)
			(xy 336.261456 -152.454102) (xy 334.967072 -152.454102) (xy 334.966586 -152.481353) (xy 334.95883 -152.535301)
			(xy 334.943475 -152.587596) (xy 334.920833 -152.637173) (xy 334.891367 -152.683023) (xy 334.855676 -152.724214)
			(xy 334.814485 -152.759905) (xy 334.768635 -152.789371) (xy 334.719058 -152.812013) (xy 334.666763 -152.827368)
			(xy 334.612815 -152.835124) (xy 334.558313 -152.835124) (xy 334.504365 -152.827368) (xy 334.45207 -152.812013)
			(xy 334.402493 -152.789371) (xy 334.356643 -152.759905) (xy 334.315452 -152.724214) (xy 334.279761 -152.683023)
			(xy 334.250295 -152.637173) (xy 334.227653 -152.587596) (xy 334.212298 -152.535301) (xy 334.204542 -152.481353)
			(xy 334.204056 -152.454102) (xy 332.74151 -152.454102) (xy 332.750922 -152.515824) (xy 332.76032 -152.532334)
			(xy 332.767686 -152.538176) (xy 332.789446 -152.556389) (xy 332.82785 -152.598163) (xy 332.859642 -152.645165)
			(xy 332.884121 -152.696358) (xy 332.900747 -152.750612) (xy 332.909152 -152.80673) (xy 332.909672 -152.835102)
			(xy 332.909672 -152.835864) (xy 332.909159 -152.863043) (xy 332.901387 -152.916842) (xy 332.894178 -152.943052)
			(xy 332.89113 -152.952958) (xy 332.89367 -152.973786) (xy 332.940914 -153.055828) (xy 332.957424 -153.06802)
			(xy 332.967584 -153.07056) (xy 332.992446 -153.076951) (xy 333.040293 -153.095547) (xy 333.08521 -153.120398)
			(xy 333.126384 -153.151054) (xy 333.163069 -153.186962) (xy 333.179166 -153.206958) (xy 333.186788 -153.21575)
			(xy 333.207678 -153.225939) (xy 333.219298 -153.226516) (xy 333.299054 -153.226516) (xy 333.310687 -153.225988)
			(xy 333.331596 -153.215791) (xy 333.339186 -153.206958) (xy 333.357374 -153.184472) (xy 333.399396 -153.144739)
			(xy 333.446932 -153.111802) (xy 333.498893 -153.086414) (xy 333.554091 -153.069158) (xy 333.61126 -153.060428)
			(xy 333.640176 -153.059892) (xy 333.667428 -153.060378) (xy 333.721378 -153.068131) (xy 333.773676 -153.083484)
			(xy 333.823256 -153.106124) (xy 333.869109 -153.13559) (xy 333.910302 -153.171281) (xy 333.945996 -153.212472)
			(xy 333.975464 -153.258323) (xy 333.998107 -153.307902) (xy 334.013464 -153.360198) (xy 334.021221 -153.414148)
			(xy 334.021684 -153.4414) (xy 334.021172 -153.470317) (xy 334.012442 -153.527489) (xy 333.995183 -153.582688)
			(xy 333.969791 -153.63465) (xy 333.936846 -153.682184) (xy 333.897104 -153.7242) (xy 333.874618 -153.74239)
			(xy 333.865811 -153.749997) (xy 333.855631 -153.770898) (xy 333.85506 -153.782522) (xy 333.85506 -153.862278)
			(xy 333.855605 -153.87391) (xy 333.865788 -153.894821) (xy 333.874618 -153.90241) (xy 333.895402 -153.919163)
			(xy 333.932535 -153.957515) (xy 333.963958 -154.000669) (xy 333.989059 -154.047783) (xy 334.007346 -154.097935)
			(xy 334.018463 -154.150148) (xy 334.022193 -154.2034) (xy 334.018463 -154.256652) (xy 334.007346 -154.308865)
			(xy 333.989059 -154.359017) (xy 333.963958 -154.406131) (xy 333.932535 -154.449285) (xy 333.895402 -154.487637)
			(xy 333.874618 -154.50439) (xy 333.865811 -154.511997) (xy 333.855631 -154.532898) (xy 333.85506 -154.544522)
			(xy 333.85506 -154.624278) (xy 333.855605 -154.63591) (xy 333.865788 -154.656821) (xy 333.874618 -154.66441)
			(xy 333.895402 -154.681163) (xy 333.932535 -154.719515) (xy 333.963958 -154.762669) (xy 333.989059 -154.809783)
			(xy 334.007346 -154.859935) (xy 334.018463 -154.912148) (xy 334.022193 -154.9654) (xy 334.018463 -155.018652)
			(xy 334.007346 -155.070865) (xy 333.989059 -155.121017) (xy 333.963958 -155.168131) (xy 333.932535 -155.211285)
			(xy 333.895402 -155.249637) (xy 333.874618 -155.26639) (xy 333.865811 -155.273997) (xy 333.855631 -155.294898)
			(xy 333.85506 -155.306522) (xy 333.85506 -155.386278) (xy 333.855605 -155.39791) (xy 333.865788 -155.418821)
			(xy 333.874618 -155.42641) (xy 333.895402 -155.443163) (xy 333.932535 -155.481515) (xy 333.963958 -155.524669)
			(xy 333.989059 -155.571783) (xy 334.007346 -155.621935) (xy 334.018463 -155.674148) (xy 334.022193 -155.7274)
			(xy 334.018463 -155.780652) (xy 334.007346 -155.832865) (xy 333.989059 -155.883017) (xy 333.963958 -155.930131)
			(xy 333.932535 -155.973285) (xy 333.895402 -156.011637) (xy 333.874618 -156.02839) (xy 333.865811 -156.035997)
			(xy 333.855631 -156.056898) (xy 333.85506 -156.068522) (xy 333.85506 -156.148278) (xy 333.855605 -156.15991)
			(xy 333.865788 -156.180821) (xy 333.874618 -156.18841) (xy 333.89711 -156.206591) (xy 333.936844 -156.248613)
			(xy 333.969781 -156.29615) (xy 333.995168 -156.348114) (xy 334.012423 -156.403313) (xy 334.02115 -156.460483)
			(xy 334.021684 -156.4894) (xy 334.021245 -156.516654) (xy 334.013487 -156.570607) (xy 333.99813 -156.622907)
			(xy 333.975486 -156.672488) (xy 333.946015 -156.718343) (xy 333.910319 -156.759536) (xy 333.869123 -156.79523)
			(xy 333.823267 -156.824697) (xy 333.773684 -156.847338) (xy 333.721383 -156.862692) (xy 333.66743 -156.870446)
			(xy 333.640176 -156.870908) (xy 333.611259 -156.87037) (xy 333.554088 -156.86165) (xy 333.498888 -156.844398)
			(xy 333.446925 -156.81901) (xy 333.399391 -156.786068) (xy 333.357375 -156.746328) (xy 333.339186 -156.723842)
			(xy 333.331585 -156.715029) (xy 333.310679 -156.704851) (xy 333.299054 -156.704284) (xy 333.219298 -156.704284)
			(xy 333.207669 -156.704842) (xy 333.186759 -156.715018) (xy 333.179166 -156.723842) (xy 333.162413 -156.744625)
			(xy 333.124059 -156.781755) (xy 333.080905 -156.813177) (xy 333.033791 -156.838276) (xy 332.983639 -156.856562)
			(xy 332.931428 -156.867679) (xy 332.878176 -156.871409) (xy 332.824924 -156.867679) (xy 332.772713 -156.856562)
			(xy 332.722561 -156.838276) (xy 332.675447 -156.813177) (xy 332.632293 -156.781755) (xy 332.593939 -156.744625)
			(xy 332.577186 -156.723842) (xy 332.569585 -156.715029) (xy 332.548679 -156.704851) (xy 332.537054 -156.704284)
			(xy 332.457044 -156.704284) (xy 332.44548 -156.704885) (xy 332.424709 -156.715059) (xy 332.417166 -156.723842)
			(xy 332.410562 -156.73197) (xy 332.401672 -156.742892) (xy 332.397354 -156.770324) (xy 332.44155 -156.87929)
			(xy 332.463902 -156.896054) (xy 332.477618 -156.897578) (xy 332.505239 -156.901191) (xy 332.559102 -156.91539)
			(xy 332.610329 -156.937267) (xy 332.657832 -156.966357) (xy 332.700602 -157.002043) (xy 332.737732 -157.043567)
			(xy 332.768432 -157.090046) (xy 332.79205 -157.140494) (xy 332.808084 -157.193839) (xy 332.816195 -157.248949)
			(xy 332.816708 -157.2768) (xy 332.816225 -157.305719) (xy 332.807493 -157.362893) (xy 332.790231 -157.418094)
			(xy 332.764833 -157.470056) (xy 332.731881 -157.517589) (xy 332.692132 -157.559603) (xy 332.669642 -157.57779)
			(xy 332.66084 -157.585401) (xy 332.650656 -157.606299) (xy 332.650084 -157.617922) (xy 332.650084 -157.697678)
			(xy 332.650656 -157.709306) (xy 332.660822 -157.730215) (xy 332.669642 -157.73781) (xy 332.690425 -157.754563)
			(xy 332.727555 -157.792917) (xy 332.758977 -157.836071) (xy 332.784076 -157.883185) (xy 332.802362 -157.933337)
			(xy 332.813478 -157.985549) (xy 332.817208 -158.0388) (xy 334.466192 -158.0388) (xy 334.469922 -157.985549)
			(xy 334.481038 -157.933337) (xy 334.499324 -157.883185) (xy 334.524423 -157.836071) (xy 334.555845 -157.792917)
			(xy 334.592975 -157.754563) (xy 334.613758 -157.73781) (xy 334.62256 -157.730199) (xy 334.632744 -157.709301)
			(xy 334.633316 -157.697678) (xy 334.633316 -157.617922) (xy 334.632744 -157.606294) (xy 334.622578 -157.585385)
			(xy 334.613758 -157.57779) (xy 334.591261 -157.559615) (xy 334.551529 -157.517591) (xy 334.518592 -157.470052)
			(xy 334.493207 -157.418088) (xy 334.475953 -157.362888) (xy 334.467226 -157.305717) (xy 334.466692 -157.2768)
			(xy 334.467178 -157.249549) (xy 334.474934 -157.195601) (xy 334.490289 -157.143306) (xy 334.512931 -157.093729)
			(xy 334.542397 -157.047879) (xy 334.578088 -157.006688) (xy 334.619279 -156.970997) (xy 334.665129 -156.941531)
			(xy 334.714706 -156.918889) (xy 334.767001 -156.903534) (xy 334.820949 -156.895778) (xy 334.8482 -156.895292)
			(xy 334.877119 -156.895775) (xy 334.934293 -156.904507) (xy 334.989494 -156.921769) (xy 335.041456 -156.947167)
			(xy 335.088989 -156.980119) (xy 335.131003 -157.019868) (xy 335.14919 -157.042358) (xy 335.156801 -157.05116)
			(xy 335.177699 -157.061344) (xy 335.189322 -157.061916) (xy 335.269078 -157.061916) (xy 335.280706 -157.061344)
			(xy 335.301615 -157.051178) (xy 335.30921 -157.042358) (xy 335.327385 -157.019861) (xy 335.369409 -156.980129)
			(xy 335.416948 -156.947192) (xy 335.468912 -156.921807) (xy 335.524112 -156.904553) (xy 335.581283 -156.895826)
			(xy 335.6102 -156.895292) (xy 335.637451 -156.895778) (xy 335.691399 -156.903534) (xy 335.743694 -156.918889)
			(xy 335.793271 -156.941531) (xy 335.839121 -156.970997) (xy 335.880312 -157.006688) (xy 335.916003 -157.047879)
			(xy 335.945469 -157.093729) (xy 335.968111 -157.143306) (xy 335.983466 -157.195601) (xy 335.991222 -157.249549)
			(xy 335.991708 -157.2768) (xy 335.991225 -157.305719) (xy 335.982493 -157.362893) (xy 335.965231 -157.418094)
			(xy 335.939833 -157.470056) (xy 335.906881 -157.517589) (xy 335.867132 -157.559603) (xy 335.844642 -157.57779)
			(xy 335.83584 -157.585401) (xy 335.825656 -157.606299) (xy 335.825084 -157.617922) (xy 335.825084 -157.697678)
			(xy 335.825656 -157.709306) (xy 335.835822 -157.730215) (xy 335.844642 -157.73781) (xy 335.865425 -157.754563)
			(xy 335.902555 -157.792917) (xy 335.933977 -157.836071) (xy 335.959076 -157.883185) (xy 335.977362 -157.933337)
			(xy 335.988478 -157.985549) (xy 335.992208 -158.0388) (xy 335.988478 -158.092051) (xy 335.977362 -158.144263)
			(xy 335.959076 -158.194415) (xy 335.933977 -158.241529) (xy 335.902555 -158.284683) (xy 335.865425 -158.323037)
			(xy 335.844642 -158.33979) (xy 335.83584 -158.347401) (xy 335.825656 -158.368299) (xy 335.825084 -158.379922)
			(xy 335.825084 -158.459678) (xy 335.825656 -158.471306) (xy 335.835822 -158.492215) (xy 335.844642 -158.49981)
			(xy 335.867139 -158.517985) (xy 335.906871 -158.560009) (xy 335.939808 -158.607548) (xy 335.965193 -158.659512)
			(xy 335.982447 -158.714712) (xy 335.991174 -158.771883) (xy 335.991708 -158.8008) (xy 335.991222 -158.828051)
			(xy 335.983466 -158.881999) (xy 335.968111 -158.934294) (xy 335.945469 -158.983871) (xy 335.916003 -159.029721)
			(xy 335.880312 -159.070912) (xy 335.839121 -159.106603) (xy 335.793271 -159.136069) (xy 335.743694 -159.158711)
			(xy 335.691399 -159.174066) (xy 335.637451 -159.181822) (xy 335.6102 -159.182308) (xy 335.581281 -159.181825)
			(xy 335.524107 -159.173093) (xy 335.468906 -159.155831) (xy 335.416944 -159.130433) (xy 335.369411 -159.097481)
			(xy 335.327397 -159.057732) (xy 335.30921 -159.035242) (xy 335.301599 -159.02644) (xy 335.280701 -159.016256)
			(xy 335.269078 -159.015684) (xy 335.189322 -159.015684) (xy 335.177694 -159.016256) (xy 335.156785 -159.026422)
			(xy 335.14919 -159.035242) (xy 335.131015 -159.057739) (xy 335.088991 -159.097471) (xy 335.041452 -159.130408)
			(xy 334.989488 -159.155793) (xy 334.934288 -159.173047) (xy 334.877117 -159.181774) (xy 334.8482 -159.182308)
			(xy 334.820949 -159.181822) (xy 334.767001 -159.174066) (xy 334.714706 -159.158711) (xy 334.665129 -159.136069)
			(xy 334.619279 -159.106603) (xy 334.578088 -159.070912) (xy 334.542397 -159.029721) (xy 334.512931 -158.983871)
			(xy 334.490289 -158.934294) (xy 334.474934 -158.881999) (xy 334.467178 -158.828051) (xy 334.466692 -158.8008)
			(xy 334.467175 -158.771881) (xy 334.475907 -158.714707) (xy 334.493169 -158.659506) (xy 334.518567 -158.607544)
			(xy 334.551519 -158.560011) (xy 334.591268 -158.517997) (xy 334.613758 -158.49981) (xy 334.62256 -158.492199)
			(xy 334.632744 -158.471301) (xy 334.633316 -158.459678) (xy 334.633316 -158.379922) (xy 334.632744 -158.368294)
			(xy 334.622578 -158.347385) (xy 334.613758 -158.33979) (xy 334.592975 -158.323037) (xy 334.555845 -158.284683)
			(xy 334.524423 -158.241529) (xy 334.499324 -158.194415) (xy 334.481038 -158.144263) (xy 334.469922 -158.092051)
			(xy 334.466192 -158.0388) (xy 332.817208 -158.0388) (xy 332.813478 -158.092051) (xy 332.802362 -158.144263)
			(xy 332.784076 -158.194415) (xy 332.758977 -158.241529) (xy 332.727555 -158.284683) (xy 332.690425 -158.323037)
			(xy 332.669642 -158.33979) (xy 332.66084 -158.347401) (xy 332.650656 -158.368299) (xy 332.650084 -158.379922)
			(xy 332.650084 -158.459678) (xy 332.650656 -158.471306) (xy 332.660822 -158.492215) (xy 332.669642 -158.49981)
			(xy 332.692139 -158.517985) (xy 332.731871 -158.560009) (xy 332.764808 -158.607548) (xy 332.790193 -158.659512)
			(xy 332.807447 -158.714712) (xy 332.816174 -158.771883) (xy 332.816708 -158.8008) (xy 332.816222 -158.828051)
			(xy 332.808466 -158.881999) (xy 332.793111 -158.934294) (xy 332.770469 -158.983871) (xy 332.741003 -159.029721)
			(xy 332.705312 -159.070912) (xy 332.664121 -159.106603) (xy 332.618271 -159.136069) (xy 332.568694 -159.158711)
			(xy 332.516399 -159.174066) (xy 332.462451 -159.181822) (xy 332.407949 -159.181822) (xy 332.354001 -159.174066)
			(xy 332.301706 -159.158711) (xy 332.252129 -159.136069) (xy 332.206279 -159.106603) (xy 332.165088 -159.070912)
			(xy 332.129397 -159.029721) (xy 332.099931 -158.983871) (xy 332.077289 -158.934294) (xy 332.061934 -158.881999)
			(xy 332.054178 -158.828051) (xy 332.053692 -158.8008) (xy 332.054175 -158.771881) (xy 332.062907 -158.714707)
			(xy 332.080169 -158.659506) (xy 332.105567 -158.607544) (xy 332.138519 -158.560011) (xy 332.178268 -158.517997)
			(xy 332.200758 -158.49981) (xy 332.20956 -158.492199) (xy 332.219744 -158.471301) (xy 332.220316 -158.459678)
			(xy 332.220316 -158.379922) (xy 332.219744 -158.368294) (xy 332.209578 -158.347385) (xy 332.200758 -158.33979)
			(xy 332.179975 -158.323037) (xy 332.142845 -158.284683) (xy 332.111423 -158.241529) (xy 332.086324 -158.194415)
			(xy 332.068038 -158.144263) (xy 332.056922 -158.092051) (xy 332.053192 -158.0388) (xy 332.056922 -157.985549)
			(xy 332.068038 -157.933337) (xy 332.086324 -157.883185) (xy 332.111423 -157.836071) (xy 332.142845 -157.792917)
			(xy 332.179975 -157.754563) (xy 332.200758 -157.73781) (xy 332.20956 -157.730199) (xy 332.219744 -157.709301)
			(xy 332.220316 -157.697678) (xy 332.220316 -157.617922) (xy 332.219744 -157.606294) (xy 332.209578 -157.585385)
			(xy 332.200758 -157.57779) (xy 332.178261 -157.559615) (xy 332.138529 -157.517591) (xy 332.105592 -157.470052)
			(xy 332.080207 -157.418088) (xy 332.062953 -157.362888) (xy 332.054226 -157.305717) (xy 332.053692 -157.2768)
			(xy 332.054147 -157.250497) (xy 332.061379 -157.198391) (xy 332.075705 -157.147774) (xy 332.096853 -157.099607)
			(xy 332.124422 -157.054805) (xy 332.140814 -157.03423) (xy 332.149704 -157.023308) (xy 332.154022 -156.995876)
			(xy 332.109826 -156.88691) (xy 332.087474 -156.870146) (xy 332.073758 -156.868622) (xy 332.046146 -156.864948)
			(xy 331.992284 -156.850759) (xy 331.941057 -156.828892) (xy 331.893552 -156.79981) (xy 331.85078 -156.764131)
			(xy 331.813649 -156.722614) (xy 331.782948 -156.67614) (xy 331.759328 -156.625696) (xy 331.743292 -156.572355)
			(xy 331.735181 -156.51725) (xy 331.734668 -156.4894) (xy 331.735161 -156.460482) (xy 331.743891 -156.403308)
			(xy 331.761153 -156.348108) (xy 331.786549 -156.296146) (xy 331.819498 -156.248613) (xy 331.859245 -156.206598)
			(xy 331.881734 -156.18841) (xy 331.890532 -156.180795) (xy 331.900719 -156.1599) (xy 331.901292 -156.148278)
			(xy 331.901292 -156.068522) (xy 331.900729 -156.056893) (xy 331.890557 -156.035983) (xy 331.881734 -156.02839)
			(xy 331.860952 -156.011636) (xy 331.823824 -155.973282) (xy 331.792405 -155.930127) (xy 331.767307 -155.883013)
			(xy 331.749022 -155.832862) (xy 331.737907 -155.780651) (xy 331.734177 -155.7274) (xy 327.7235 -155.7274)
			(xy 327.7235 -158.362904) (xy 327.723655 -158.368138) (xy 327.725827 -158.378381) (xy 327.727818 -158.383224)
			(xy 327.767156 -158.474093) (xy 327.839813 -158.658316) (xy 327.9055 -158.845138) (xy 327.964125 -159.034296)
			(xy 328.015605 -159.225521) (xy 328.059867 -159.418545) (xy 328.096848 -159.613096) (xy 328.126497 -159.808897)
			(xy 328.148772 -160.005674) (xy 328.163641 -160.203149) (xy 328.171084 -160.401043) (xy 328.171556 -160.50006)
			(xy 328.171556 -160.500314) (xy 328.171033 -160.60432) (xy 328.169811 -160.635188) (xy 340.000336 -160.635188)
			(xy 340.000336 -151.839422) (xy 340.000764 -151.829353) (xy 340.008482 -151.810755) (xy 340.015322 -151.803354)
			(xy 340.52256 -151.29637) (xy 340.529976 -151.289551) (xy 340.548563 -151.28182) (xy 340.558628 -151.281384)
			(xy 350.19996 -151.281384) (xy 350.210027 -151.280942) (xy 350.228626 -151.273233) (xy 350.236028 -151.266398)
			(xy 352.702622 -148.79955) (xy 352.710026 -148.792715) (xy 352.728622 -148.784991) (xy 352.73869 -148.784564)
			(xy 363.615986 -148.784564) (xy 363.626057 -148.78498) (xy 363.644655 -148.792705) (xy 363.652054 -148.79955)
			(xy 364.231805 -149.379432) (xy 375.095514 -149.379432) (xy 375.099585 -149.32381) (xy 375.111711 -149.269373)
			(xy 375.131634 -149.217282) (xy 375.15893 -149.168647) (xy 375.193016 -149.124504) (xy 375.233165 -149.085795)
			(xy 375.278523 -149.053344) (xy 375.328123 -149.027843) (xy 375.380907 -149.009836) (xy 375.43575 -148.999706)
			(xy 375.491484 -148.997669) (xy 375.546921 -149.003769) (xy 375.600878 -149.017875) (xy 375.652207 -149.039687)
			(xy 375.699813 -149.068741) (xy 375.742681 -149.104416) (xy 375.779898 -149.145953) (xy 375.810671 -149.192466)
			(xy 375.834343 -149.242963) (xy 375.850411 -149.29637) (xy 375.850486 -149.296882) (xy 396.370046 -149.296882)
			(xy 396.374117 -149.24126) (xy 396.386243 -149.186823) (xy 396.406166 -149.134732) (xy 396.433462 -149.086097)
			(xy 396.467548 -149.041954) (xy 396.507697 -149.003245) (xy 396.553055 -148.970794) (xy 396.602655 -148.945293)
			(xy 396.655439 -148.927286) (xy 396.710282 -148.917156) (xy 396.766016 -148.915119) (xy 396.821453 -148.921219)
			(xy 396.87541 -148.935325) (xy 396.926739 -148.957137) (xy 396.974345 -148.986191) (xy 397.017213 -149.021866)
			(xy 397.05443 -149.063403) (xy 397.085203 -149.109916) (xy 397.108875 -149.160413) (xy 397.124943 -149.21382)
			(xy 397.133063 -149.268996) (xy 397.133572 -149.296882) (xy 397.133063 -149.324768) (xy 397.124943 -149.379944)
			(xy 397.108875 -149.433351) (xy 397.085203 -149.483848) (xy 397.05443 -149.530361) (xy 397.017213 -149.571898)
			(xy 396.974345 -149.607573) (xy 396.926739 -149.636627) (xy 396.87541 -149.658439) (xy 396.821453 -149.672545)
			(xy 396.766016 -149.678645) (xy 396.710282 -149.676608) (xy 396.655439 -149.666478) (xy 396.602655 -149.648471)
			(xy 396.553055 -149.62297) (xy 396.507697 -149.590519) (xy 396.467548 -149.55181) (xy 396.433462 -149.507667)
			(xy 396.406166 -149.459032) (xy 396.386243 -149.406941) (xy 396.374117 -149.352504) (xy 396.370046 -149.296882)
			(xy 375.850486 -149.296882) (xy 375.858531 -149.351546) (xy 375.85904 -149.379432) (xy 375.858531 -149.407318)
			(xy 375.850411 -149.462494) (xy 375.834343 -149.515901) (xy 375.810671 -149.566398) (xy 375.779898 -149.612911)
			(xy 375.742681 -149.654448) (xy 375.699813 -149.690123) (xy 375.657442 -149.715982) (xy 397.238726 -149.715982)
			(xy 397.242797 -149.66036) (xy 397.254923 -149.605923) (xy 397.274846 -149.553832) (xy 397.302142 -149.505197)
			(xy 397.336228 -149.461054) (xy 397.376377 -149.422345) (xy 397.421735 -149.389894) (xy 397.471335 -149.364393)
			(xy 397.524119 -149.346386) (xy 397.578962 -149.336256) (xy 397.634696 -149.334219) (xy 397.690133 -149.340319)
			(xy 397.74409 -149.354425) (xy 397.795419 -149.376237) (xy 397.843025 -149.405291) (xy 397.885893 -149.440966)
			(xy 397.92311 -149.482503) (xy 397.953883 -149.529016) (xy 397.977555 -149.579513) (xy 397.993623 -149.63292)
			(xy 398.001743 -149.688096) (xy 398.002252 -149.715982) (xy 398.127726 -149.715982) (xy 398.131797 -149.66036)
			(xy 398.143923 -149.605923) (xy 398.163846 -149.553832) (xy 398.191142 -149.505197) (xy 398.225228 -149.461054)
			(xy 398.265377 -149.422345) (xy 398.310735 -149.389894) (xy 398.360335 -149.364393) (xy 398.413119 -149.346386)
			(xy 398.467962 -149.336256) (xy 398.523696 -149.334219) (xy 398.579133 -149.340319) (xy 398.63309 -149.354425)
			(xy 398.684419 -149.376237) (xy 398.732025 -149.405291) (xy 398.774893 -149.440966) (xy 398.81211 -149.482503)
			(xy 398.842883 -149.529016) (xy 398.866555 -149.579513) (xy 398.882623 -149.63292) (xy 398.890743 -149.688096)
			(xy 398.891252 -149.715982) (xy 399.016726 -149.715982) (xy 399.020797 -149.66036) (xy 399.032923 -149.605923)
			(xy 399.052846 -149.553832) (xy 399.080142 -149.505197) (xy 399.114228 -149.461054) (xy 399.154377 -149.422345)
			(xy 399.199735 -149.389894) (xy 399.249335 -149.364393) (xy 399.302119 -149.346386) (xy 399.356962 -149.336256)
			(xy 399.412696 -149.334219) (xy 399.468133 -149.340319) (xy 399.52209 -149.354425) (xy 399.573419 -149.376237)
			(xy 399.621025 -149.405291) (xy 399.663893 -149.440966) (xy 399.70111 -149.482503) (xy 399.731883 -149.529016)
			(xy 399.755555 -149.579513) (xy 399.771623 -149.63292) (xy 399.779743 -149.688096) (xy 399.780252 -149.715982)
			(xy 399.779743 -149.743868) (xy 399.771623 -149.799044) (xy 399.755555 -149.852451) (xy 399.731883 -149.902948)
			(xy 399.70111 -149.949461) (xy 399.663893 -149.990998) (xy 399.621025 -150.026673) (xy 399.573419 -150.055727)
			(xy 399.52209 -150.077539) (xy 399.468133 -150.091645) (xy 399.412696 -150.097745) (xy 399.356962 -150.095708)
			(xy 399.302119 -150.085578) (xy 399.249335 -150.067571) (xy 399.199735 -150.04207) (xy 399.154377 -150.009619)
			(xy 399.114228 -149.97091) (xy 399.080142 -149.926767) (xy 399.052846 -149.878132) (xy 399.032923 -149.826041)
			(xy 399.020797 -149.771604) (xy 399.016726 -149.715982) (xy 398.891252 -149.715982) (xy 398.890743 -149.743868)
			(xy 398.882623 -149.799044) (xy 398.866555 -149.852451) (xy 398.842883 -149.902948) (xy 398.81211 -149.949461)
			(xy 398.774893 -149.990998) (xy 398.732025 -150.026673) (xy 398.684419 -150.055727) (xy 398.63309 -150.077539)
			(xy 398.579133 -150.091645) (xy 398.523696 -150.097745) (xy 398.467962 -150.095708) (xy 398.413119 -150.085578)
			(xy 398.360335 -150.067571) (xy 398.310735 -150.04207) (xy 398.265377 -150.009619) (xy 398.225228 -149.97091)
			(xy 398.191142 -149.926767) (xy 398.163846 -149.878132) (xy 398.143923 -149.826041) (xy 398.131797 -149.771604)
			(xy 398.127726 -149.715982) (xy 398.002252 -149.715982) (xy 398.001743 -149.743868) (xy 397.993623 -149.799044)
			(xy 397.977555 -149.852451) (xy 397.953883 -149.902948) (xy 397.92311 -149.949461) (xy 397.885893 -149.990998)
			(xy 397.843025 -150.026673) (xy 397.795419 -150.055727) (xy 397.74409 -150.077539) (xy 397.690133 -150.091645)
			(xy 397.634696 -150.097745) (xy 397.578962 -150.095708) (xy 397.524119 -150.085578) (xy 397.471335 -150.067571)
			(xy 397.421735 -150.04207) (xy 397.376377 -150.009619) (xy 397.336228 -149.97091) (xy 397.302142 -149.926767)
			(xy 397.274846 -149.878132) (xy 397.254923 -149.826041) (xy 397.242797 -149.771604) (xy 397.238726 -149.715982)
			(xy 375.657442 -149.715982) (xy 375.652207 -149.719177) (xy 375.600878 -149.740989) (xy 375.546921 -149.755095)
			(xy 375.491484 -149.761195) (xy 375.43575 -149.759158) (xy 375.380907 -149.749028) (xy 375.328123 -149.731021)
			(xy 375.278523 -149.70552) (xy 375.233165 -149.673069) (xy 375.193016 -149.63436) (xy 375.15893 -149.590217)
			(xy 375.131634 -149.541582) (xy 375.111711 -149.489491) (xy 375.099585 -149.435054) (xy 375.095514 -149.379432)
			(xy 364.231805 -149.379432) (xy 364.774226 -149.921976) (xy 364.781052 -149.929387) (xy 364.788779 -149.947978)
			(xy 364.789212 -149.958044) (xy 364.789212 -157.46831) (xy 365.557825 -157.46831) (xy 365.561553 -157.415059)
			(xy 365.572669 -157.362848) (xy 365.590955 -157.312696) (xy 365.616054 -157.265584) (xy 365.647476 -157.22243)
			(xy 365.684607 -157.184079) (xy 365.70539 -157.167326) (xy 365.714174 -157.159696) (xy 365.724371 -157.138813)
			(xy 365.724948 -157.127194) (xy 365.724948 -157.047438) (xy 365.724448 -157.035801) (xy 365.714233 -157.01489)
			(xy 365.70539 -157.007306) (xy 365.684622 -156.990534) (xy 365.647489 -156.952185) (xy 365.616065 -156.909033)
			(xy 365.590963 -156.861922) (xy 365.572675 -156.811771) (xy 365.561556 -156.75956) (xy 365.557825 -156.70631)
			(xy 365.561553 -156.653059) (xy 365.572669 -156.600848) (xy 365.590955 -156.550696) (xy 365.616054 -156.503584)
			(xy 365.647476 -156.46043) (xy 365.684607 -156.422079) (xy 365.70539 -156.405326) (xy 365.714174 -156.397696)
			(xy 365.724371 -156.376813) (xy 365.724948 -156.365194) (xy 365.724948 -156.285438) (xy 365.724448 -156.273801)
			(xy 365.714233 -156.25289) (xy 365.70539 -156.245306) (xy 365.684622 -156.228534) (xy 365.647489 -156.190185)
			(xy 365.616065 -156.147033) (xy 365.590963 -156.099922) (xy 365.572675 -156.049771) (xy 365.561556 -155.99756)
			(xy 365.557825 -155.94431) (xy 365.561553 -155.891059) (xy 365.572669 -155.838848) (xy 365.590955 -155.788696)
			(xy 365.616054 -155.741584) (xy 365.647476 -155.69843) (xy 365.684607 -155.660079) (xy 365.70539 -155.643326)
			(xy 365.714174 -155.635696) (xy 365.724371 -155.614813) (xy 365.724948 -155.603194) (xy 365.724948 -155.523438)
			(xy 365.724448 -155.511801) (xy 365.714233 -155.49089) (xy 365.70539 -155.483306) (xy 365.684622 -155.466534)
			(xy 365.647489 -155.428185) (xy 365.616065 -155.385033) (xy 365.590963 -155.337922) (xy 365.572675 -155.287771)
			(xy 365.561556 -155.23556) (xy 365.557825 -155.18231) (xy 365.561553 -155.129059) (xy 365.572669 -155.076848)
			(xy 365.590955 -155.026696) (xy 365.616054 -154.979584) (xy 365.647476 -154.93643) (xy 365.684607 -154.898079)
			(xy 365.70539 -154.881326) (xy 365.714174 -154.873696) (xy 365.724371 -154.852813) (xy 365.724948 -154.841194)
			(xy 365.724948 -154.761438) (xy 365.724448 -154.749801) (xy 365.714233 -154.72889) (xy 365.70539 -154.721306)
			(xy 365.682907 -154.703114) (xy 365.643173 -154.661094) (xy 365.610234 -154.613559) (xy 365.584845 -154.561598)
			(xy 365.567589 -154.506401) (xy 365.558859 -154.449232) (xy 365.558324 -154.420316) (xy 365.55877 -154.393062)
			(xy 365.566526 -154.339109) (xy 365.581882 -154.286809) (xy 365.604525 -154.237227) (xy 365.633994 -154.191372)
			(xy 365.669689 -154.150178) (xy 365.710885 -154.114484) (xy 365.756741 -154.085017) (xy 365.806324 -154.062376)
			(xy 365.858625 -154.047023) (xy 365.912578 -154.039269) (xy 365.939832 -154.038808) (xy 365.968747 -154.039372)
			(xy 366.025916 -154.048091) (xy 366.081115 -154.06534) (xy 366.133077 -154.090723) (xy 366.180612 -154.123658)
			(xy 366.222631 -154.163392) (xy 366.240822 -154.185874) (xy 366.248417 -154.194693) (xy 366.269327 -154.204867)
			(xy 366.280954 -154.205432) (xy 366.36071 -154.205432) (xy 366.372344 -154.204908) (xy 366.393255 -154.194711)
			(xy 366.400842 -154.185874) (xy 366.417595 -154.165091) (xy 366.455949 -154.127961) (xy 366.499103 -154.096539)
			(xy 366.546217 -154.07144) (xy 366.596369 -154.053154) (xy 366.64858 -154.042037) (xy 366.701832 -154.038307)
			(xy 366.755084 -154.042037) (xy 366.807295 -154.053154) (xy 366.857447 -154.07144) (xy 366.904561 -154.096539)
			(xy 366.947715 -154.127961) (xy 366.986069 -154.165091) (xy 367.002822 -154.185874) (xy 367.010417 -154.194693)
			(xy 367.031327 -154.204867) (xy 367.042954 -154.205432) (xy 367.12271 -154.205432) (xy 367.134344 -154.204908)
			(xy 367.155255 -154.194711) (xy 367.162842 -154.185874) (xy 367.179595 -154.165091) (xy 367.217949 -154.127961)
			(xy 367.261103 -154.096539) (xy 367.308217 -154.07144) (xy 367.358369 -154.053154) (xy 367.41058 -154.042037)
			(xy 367.463832 -154.038307) (xy 367.517084 -154.042037) (xy 367.569295 -154.053154) (xy 367.619447 -154.07144)
			(xy 367.666561 -154.096539) (xy 367.709715 -154.127961) (xy 367.748069 -154.165091) (xy 367.764822 -154.185874)
			(xy 367.772417 -154.194693) (xy 367.793327 -154.204867) (xy 367.804954 -154.205432) (xy 367.88471 -154.205432)
			(xy 367.896344 -154.204908) (xy 367.917255 -154.194711) (xy 367.924842 -154.185874) (xy 367.941595 -154.165091)
			(xy 367.979949 -154.127961) (xy 368.023103 -154.096539) (xy 368.070217 -154.07144) (xy 368.120369 -154.053154)
			(xy 368.17258 -154.042037) (xy 368.225832 -154.038307) (xy 368.279084 -154.042037) (xy 368.331295 -154.053154)
			(xy 368.381447 -154.07144) (xy 368.428561 -154.096539) (xy 368.471715 -154.127961) (xy 368.510069 -154.165091)
			(xy 368.526822 -154.185874) (xy 368.534417 -154.194693) (xy 368.555327 -154.204867) (xy 368.566954 -154.205432)
			(xy 368.64671 -154.205432) (xy 368.658344 -154.204908) (xy 368.679255 -154.194711) (xy 368.686842 -154.185874)
			(xy 368.703595 -154.165091) (xy 368.741949 -154.127961) (xy 368.785103 -154.096539) (xy 368.832217 -154.07144)
			(xy 368.882369 -154.053154) (xy 368.93458 -154.042037) (xy 368.987832 -154.038307) (xy 369.041084 -154.042037)
			(xy 369.093295 -154.053154) (xy 369.143447 -154.07144) (xy 369.190561 -154.096539) (xy 369.233715 -154.127961)
			(xy 369.272069 -154.165091) (xy 369.288822 -154.185874) (xy 369.296417 -154.194693) (xy 369.317327 -154.204867)
			(xy 369.328954 -154.205432) (xy 369.40871 -154.205432) (xy 369.420344 -154.204908) (xy 369.441255 -154.194711)
			(xy 369.448842 -154.185874) (xy 369.465595 -154.165091) (xy 369.503949 -154.127961) (xy 369.547103 -154.096539)
			(xy 369.594217 -154.07144) (xy 369.644369 -154.053154) (xy 369.69658 -154.042037) (xy 369.749832 -154.038307)
			(xy 369.803084 -154.042037) (xy 369.855295 -154.053154) (xy 369.905447 -154.07144) (xy 369.952561 -154.096539)
			(xy 369.995715 -154.127961) (xy 370.034069 -154.165091) (xy 370.050822 -154.185874) (xy 370.058417 -154.194693)
			(xy 370.079327 -154.204867) (xy 370.090954 -154.205432) (xy 370.17071 -154.205432) (xy 370.182344 -154.204908)
			(xy 370.203255 -154.194711) (xy 370.210842 -154.185874) (xy 370.227595 -154.165091) (xy 370.265949 -154.127961)
			(xy 370.309103 -154.096539) (xy 370.356217 -154.07144) (xy 370.406369 -154.053154) (xy 370.45858 -154.042037)
			(xy 370.511832 -154.038307) (xy 370.565084 -154.042037) (xy 370.617295 -154.053154) (xy 370.667447 -154.07144)
			(xy 370.714561 -154.096539) (xy 370.757715 -154.127961) (xy 370.796069 -154.165091) (xy 370.812822 -154.185874)
			(xy 370.820417 -154.194693) (xy 370.841327 -154.204867) (xy 370.852954 -154.205432) (xy 370.93271 -154.205432)
			(xy 370.944344 -154.204908) (xy 370.965255 -154.194711) (xy 370.972842 -154.185874) (xy 370.989595 -154.165091)
			(xy 371.027949 -154.127961) (xy 371.071103 -154.096539) (xy 371.118217 -154.07144) (xy 371.168369 -154.053154)
			(xy 371.22058 -154.042037) (xy 371.273832 -154.038307) (xy 371.327084 -154.042037) (xy 371.379295 -154.053154)
			(xy 371.429447 -154.07144) (xy 371.476561 -154.096539) (xy 371.519715 -154.127961) (xy 371.558069 -154.165091)
			(xy 371.574822 -154.185874) (xy 371.582417 -154.194693) (xy 371.603327 -154.204867) (xy 371.614954 -154.205432)
			(xy 371.69471 -154.205432) (xy 371.706344 -154.204908) (xy 371.727255 -154.194711) (xy 371.734842 -154.185874)
			(xy 371.751595 -154.165091) (xy 371.789949 -154.127961) (xy 371.833103 -154.096539) (xy 371.880217 -154.07144)
			(xy 371.930369 -154.053154) (xy 371.98258 -154.042037) (xy 372.035832 -154.038307) (xy 372.089084 -154.042037)
			(xy 372.141295 -154.053154) (xy 372.191447 -154.07144) (xy 372.238561 -154.096539) (xy 372.281715 -154.127961)
			(xy 372.320069 -154.165091) (xy 372.336822 -154.185874) (xy 372.344417 -154.194693) (xy 372.365327 -154.204867)
			(xy 372.376954 -154.205432) (xy 372.45671 -154.205432) (xy 372.468344 -154.204908) (xy 372.489255 -154.194711)
			(xy 372.496842 -154.185874) (xy 372.515003 -154.163365) (xy 372.55703 -154.123633) (xy 372.604571 -154.090697)
			(xy 372.656538 -154.065314) (xy 372.711741 -154.048063) (xy 372.768914 -154.03934) (xy 372.797832 -154.038808)
			(xy 372.825085 -154.039248) (xy 372.879035 -154.047009) (xy 372.931332 -154.062369) (xy 372.98091 -154.085015)
			(xy 373.026761 -154.114487) (xy 373.067951 -154.150183) (xy 373.103642 -154.191378) (xy 373.133108 -154.237232)
			(xy 373.155747 -154.286813) (xy 373.171101 -154.339112) (xy 373.178855 -154.393063) (xy 373.17934 -154.420316)
			(xy 373.178784 -154.449232) (xy 373.170066 -154.506402) (xy 373.152817 -154.561601) (xy 373.127432 -154.613564)
			(xy 373.094494 -154.661098) (xy 373.054758 -154.703116) (xy 373.032274 -154.721306) (xy 373.02347 -154.728916)
			(xy 373.013285 -154.749815) (xy 373.012716 -154.761438) (xy 373.012716 -154.841194) (xy 373.013267 -154.852824)
			(xy 373.023447 -154.873734) (xy 373.032274 -154.881326) (xy 373.053071 -154.898062) (xy 373.090199 -154.936418)
			(xy 373.121617 -154.979576) (xy 373.146714 -155.026691) (xy 373.164998 -155.076845) (xy 373.176112 -155.129058)
			(xy 373.17984 -155.18231) (xy 373.17611 -155.235562) (xy 373.164992 -155.287774) (xy 373.146706 -155.337927)
			(xy 373.121607 -155.385041) (xy 373.090186 -155.428197) (xy 373.053057 -155.466552) (xy 373.032274 -155.483306)
			(xy 373.02347 -155.490916) (xy 373.013285 -155.511815) (xy 373.012716 -155.523438) (xy 373.012716 -155.603194)
			(xy 373.013267 -155.614824) (xy 373.023447 -155.635734) (xy 373.029025 -155.640532) (xy 378.748036 -155.640532)
			(xy 378.748512 -155.613162) (xy 378.756326 -155.558983) (xy 378.771812 -155.50648) (xy 378.794652 -155.456733)
			(xy 378.824375 -155.410766) (xy 378.842016 -155.389834) (xy 378.84227 -155.38958) (xy 378.847879 -155.382509)
			(xy 378.85411 -155.36558) (xy 378.854462 -155.35656) (xy 378.854462 -155.289504) (xy 378.854111 -155.280486)
			(xy 378.84786 -155.263569) (xy 378.84227 -155.256484) (xy 378.842016 -155.256484) (xy 378.842016 -155.25623)
			(xy 378.824407 -155.235272) (xy 378.794682 -155.189308) (xy 378.771835 -155.139566) (xy 378.756337 -155.087068)
			(xy 378.748506 -155.032893) (xy 378.748502 -154.978155) (xy 378.756327 -154.923979) (xy 378.771818 -154.871479)
			(xy 378.794659 -154.821734) (xy 378.824378 -154.775767) (xy 378.842016 -154.754834) (xy 378.84227 -154.75458)
			(xy 378.847879 -154.747509) (xy 378.85411 -154.73058) (xy 378.854462 -154.72156) (xy 378.854462 -154.654504)
			(xy 378.854111 -154.645486) (xy 378.84786 -154.628569) (xy 378.84227 -154.621484) (xy 378.842016 -154.621484)
			(xy 378.842016 -154.62123) (xy 378.824407 -154.600272) (xy 378.794682 -154.554308) (xy 378.771835 -154.504566)
			(xy 378.756337 -154.452068) (xy 378.748506 -154.397893) (xy 378.748502 -154.343155) (xy 378.756327 -154.288979)
			(xy 378.771818 -154.236479) (xy 378.794659 -154.186734) (xy 378.824378 -154.140767) (xy 378.842016 -154.119834)
			(xy 378.84227 -154.11958) (xy 378.847879 -154.112509) (xy 378.85411 -154.09558) (xy 378.854462 -154.08656)
			(xy 378.854462 -154.019504) (xy 378.854111 -154.010486) (xy 378.84786 -153.993569) (xy 378.84227 -153.986484)
			(xy 378.842016 -153.986484) (xy 378.842016 -153.98623) (xy 378.82438 -153.965295) (xy 378.794667 -153.919324)
			(xy 378.77183 -153.869577) (xy 378.756339 -153.817076) (xy 378.74851 -153.762901) (xy 378.748036 -153.735532)
			(xy 378.748485 -153.708278) (xy 378.756239 -153.654324) (xy 378.771593 -153.602023) (xy 378.794235 -153.55244)
			(xy 378.823704 -153.506585) (xy 378.859399 -153.465391) (xy 378.900595 -153.429697) (xy 378.946451 -153.400229)
			(xy 378.996035 -153.377589) (xy 379.048336 -153.362236) (xy 379.10229 -153.354484) (xy 379.129544 -153.354024)
			(xy 379.15945 -153.35459) (xy 379.218528 -153.363942) (xy 379.275423 -153.382394) (xy 379.328744 -153.409495)
			(xy 379.377186 -153.444582) (xy 379.398784 -153.465276) (xy 379.405642 -153.472134) (xy 379.423422 -153.479754)
			(xy 379.512576 -153.482548) (xy 379.530356 -153.476198) (xy 379.537722 -153.469594) (xy 379.545539 -153.462796)
			(xy 379.561805 -153.449962) (xy 379.570234 -153.44394) (xy 379.570488 -153.44394) (xy 379.579143 -153.437041)
			(xy 379.590074 -153.417822) (xy 379.59157 -153.406856) (xy 379.598428 -153.329386) (xy 379.598866 -153.318223)
			(xy 379.591216 -153.297262) (xy 379.583696 -153.289) (xy 379.562873 -153.267422) (xy 379.527622 -153.218915)
			(xy 379.500396 -153.165488) (xy 379.481867 -153.10846) (xy 379.47249 -153.049234) (xy 379.471936 -153.019252)
			(xy 379.472424 -152.991882) (xy 379.480235 -152.937704) (xy 379.495719 -152.885201) (xy 379.518556 -152.835453)
			(xy 379.548276 -152.789486) (xy 379.565916 -152.768554) (xy 379.56617 -152.7683) (xy 379.571771 -152.761224)
			(xy 379.578007 -152.744299) (xy 379.578362 -152.73528) (xy 379.578362 -152.668224) (xy 379.578002 -152.659207)
			(xy 379.571757 -152.64229) (xy 379.56617 -152.635204) (xy 379.565916 -152.635204) (xy 379.565916 -152.63495)
			(xy 379.548289 -152.614008) (xy 379.518575 -152.568038) (xy 379.495737 -152.518293) (xy 379.480243 -152.465795)
			(xy 379.472411 -152.411621) (xy 379.471936 -152.384252) (xy 379.472333 -152.356998) (xy 379.480097 -152.303044)
			(xy 379.495461 -152.250745) (xy 379.518111 -152.201165) (xy 379.547586 -152.155313) (xy 379.583287 -152.114122)
			(xy 379.624486 -152.078431) (xy 379.670346 -152.048967) (xy 379.719932 -152.026329) (xy 379.772234 -152.010978)
			(xy 379.826189 -152.003227) (xy 379.853444 -152.002744) (xy 379.880814 -152.003232) (xy 379.934992 -152.011043)
			(xy 379.987495 -152.026526) (xy 380.037243 -152.049363) (xy 380.08321 -152.079084) (xy 380.104142 -152.096724)
			(xy 380.104396 -152.096978) (xy 380.111473 -152.102578) (xy 380.128397 -152.108815) (xy 380.137416 -152.10917)
			(xy 380.204472 -152.10917) (xy 380.213488 -152.108806) (xy 380.230406 -152.102564) (xy 380.237492 -152.096978)
			(xy 380.237492 -152.096724) (xy 380.237746 -152.096724) (xy 380.258679 -152.079083) (xy 380.304647 -152.049359)
			(xy 380.354393 -152.026513) (xy 380.406895 -152.011017) (xy 380.461073 -152.003188) (xy 380.515815 -152.003188)
			(xy 380.569993 -152.011017) (xy 380.622495 -152.026513) (xy 380.672241 -152.049359) (xy 380.718209 -152.079083)
			(xy 380.739142 -152.096724) (xy 380.739396 -152.096978) (xy 380.746473 -152.102578) (xy 380.763397 -152.108815)
			(xy 380.772416 -152.10917) (xy 380.839472 -152.10917) (xy 380.848488 -152.108806) (xy 380.865406 -152.102564)
			(xy 380.872492 -152.096978) (xy 380.872492 -152.096724) (xy 380.872746 -152.096724) (xy 380.893679 -152.079083)
			(xy 380.939647 -152.049359) (xy 380.989393 -152.026513) (xy 381.041895 -152.011017) (xy 381.096073 -152.003188)
			(xy 381.150815 -152.003188) (xy 381.204993 -152.011017) (xy 381.257495 -152.026513) (xy 381.307241 -152.049359)
			(xy 381.353209 -152.079083) (xy 381.374142 -152.096724) (xy 381.374396 -152.096978) (xy 381.381473 -152.102578)
			(xy 381.398397 -152.108815) (xy 381.407416 -152.10917) (xy 381.474472 -152.10917) (xy 381.483488 -152.108806)
			(xy 381.500406 -152.102564) (xy 381.507492 -152.096978) (xy 381.507492 -152.096724) (xy 381.507746 -152.096724)
			(xy 381.528691 -152.0791) (xy 381.57466 -152.049385) (xy 381.624404 -152.026546) (xy 381.676902 -152.011052)
			(xy 381.731076 -152.00322) (xy 381.758444 -152.002744) (xy 381.785694 -152.003237) (xy 381.839639 -152.010998)
			(xy 381.891931 -152.026356) (xy 381.941505 -152.048999) (xy 381.987353 -152.078465) (xy 382.028541 -152.114156)
			(xy 382.064232 -152.155344) (xy 382.093699 -152.201191) (xy 382.116342 -152.250765) (xy 382.131701 -152.303057)
			(xy 382.139463 -152.357002) (xy 382.139952 -152.384252) (xy 382.139469 -152.411622) (xy 382.131657 -152.465801)
			(xy 382.116173 -152.518304) (xy 382.093334 -152.568051) (xy 382.063612 -152.614018) (xy 382.045972 -152.63495)
			(xy 382.045718 -152.635204) (xy 382.040126 -152.642287) (xy 382.033882 -152.659206) (xy 382.033526 -152.668224)
			(xy 382.033526 -152.73528) (xy 382.033887 -152.744297) (xy 382.040131 -152.761214) (xy 382.045718 -152.7683)
			(xy 382.045972 -152.7683) (xy 382.045972 -152.768554) (xy 382.063599 -152.789496) (xy 382.093313 -152.835466)
			(xy 382.116152 -152.885211) (xy 382.131646 -152.937709) (xy 382.139477 -152.991883) (xy 382.139952 -153.019252)
			(xy 382.139434 -153.048033) (xy 382.13078 -153.104939) (xy 382.113677 -153.159901) (xy 382.088512 -153.21167)
			(xy 382.055856 -153.259071) (xy 382.016451 -153.30103) (xy 381.97119 -153.336593) (xy 381.946404 -153.35123)
			(xy 381.936752 -153.356818) (xy 381.92329 -153.37536) (xy 381.90805 -153.46426) (xy 381.90673 -153.475491)
			(xy 381.912791 -153.497245) (xy 381.919734 -153.50617) (xy 381.937187 -153.527084) (xy 381.96664 -153.572906)
			(xy 381.989282 -153.622449) (xy 382.004654 -153.674706) (xy 382.012443 -153.728617) (xy 382.012952 -153.755852)
			(xy 382.012469 -153.783222) (xy 382.004657 -153.837401) (xy 381.989173 -153.889904) (xy 381.966334 -153.939651)
			(xy 381.936612 -153.985618) (xy 381.918972 -154.00655) (xy 381.918718 -154.006804) (xy 381.913126 -154.013887)
			(xy 381.906882 -154.030806) (xy 381.906526 -154.039824) (xy 381.906526 -154.10688) (xy 381.906887 -154.115897)
			(xy 381.913131 -154.132814) (xy 381.918718 -154.1399) (xy 381.918972 -154.1399) (xy 381.918972 -154.140154)
			(xy 381.936566 -154.161125) (xy 381.966293 -154.207086) (xy 381.989141 -154.256826) (xy 382.004641 -154.309322)
			(xy 382.012474 -154.363496) (xy 382.012479 -154.418232) (xy 382.004656 -154.472407) (xy 381.989166 -154.524906)
			(xy 381.966327 -154.574651) (xy 381.936609 -154.620617) (xy 381.918972 -154.64155) (xy 381.918718 -154.641804)
			(xy 381.913126 -154.648887) (xy 381.906882 -154.665806) (xy 381.906526 -154.674824) (xy 381.906526 -154.74188)
			(xy 381.906887 -154.750897) (xy 381.913131 -154.767814) (xy 381.918718 -154.7749) (xy 381.918972 -154.7749)
			(xy 381.918972 -154.775154) (xy 381.936566 -154.796125) (xy 381.966293 -154.842086) (xy 381.989141 -154.891826)
			(xy 382.004641 -154.944322) (xy 382.012474 -154.998496) (xy 382.012479 -155.053232) (xy 382.004656 -155.107407)
			(xy 381.989166 -155.159906) (xy 381.966327 -155.209651) (xy 381.936609 -155.255617) (xy 381.918972 -155.27655)
			(xy 381.918718 -155.276804) (xy 381.913126 -155.283887) (xy 381.906882 -155.300806) (xy 381.906526 -155.309824)
			(xy 381.906526 -155.37688) (xy 381.906887 -155.385897) (xy 381.913131 -155.402814) (xy 381.918718 -155.4099)
			(xy 381.918972 -155.4099) (xy 381.918972 -155.410154) (xy 381.936599 -155.431096) (xy 381.966313 -155.477066)
			(xy 381.989152 -155.526811) (xy 382.004646 -155.579309) (xy 382.012477 -155.633483) (xy 382.012952 -155.660852)
			(xy 382.012435 -155.688653) (xy 382.004382 -155.743668) (xy 381.988424 -155.79693) (xy 381.9649 -155.84731)
			(xy 381.934309 -155.89374) (xy 381.897299 -155.935234) (xy 381.8763 -155.95346) (xy 381.86815 -155.961065)
			(xy 381.858649 -155.981196) (xy 381.858012 -155.992322) (xy 381.858012 -156.071824) (xy 381.876046 -156.097732)
			(xy 381.891286 -156.10332) (xy 381.918266 -156.113936) (xy 381.968932 -156.142116) (xy 382.014751 -156.177637)
			(xy 382.054669 -156.21968) (xy 382.087768 -156.267279) (xy 382.113284 -156.319338) (xy 382.130631 -156.374657)
			(xy 382.139409 -156.431964) (xy 382.139952 -156.460952) (xy 382.139469 -156.488322) (xy 382.131657 -156.542501)
			(xy 382.116173 -156.595004) (xy 382.093334 -156.644751) (xy 382.063612 -156.690718) (xy 382.045972 -156.71165)
			(xy 382.045718 -156.711904) (xy 382.040126 -156.718987) (xy 382.033882 -156.735906) (xy 382.033526 -156.744924)
			(xy 382.033526 -156.81198) (xy 382.033887 -156.820997) (xy 382.040131 -156.837914) (xy 382.045718 -156.845)
			(xy 382.045972 -156.845) (xy 382.045972 -156.845254) (xy 382.063599 -156.866196) (xy 382.093313 -156.912166)
			(xy 382.116152 -156.961911) (xy 382.131646 -157.014409) (xy 382.139477 -157.068583) (xy 382.139952 -157.095952)
			(xy 382.1394 -157.123202) (xy 382.131651 -157.177147) (xy 382.116303 -157.229441) (xy 382.093669 -157.279018)
			(xy 382.064211 -157.324869) (xy 382.028526 -157.366061) (xy 381.987343 -157.401755) (xy 381.941499 -157.431225)
			(xy 381.891927 -157.453871) (xy 381.839637 -157.469231) (xy 381.785694 -157.476994) (xy 381.758444 -157.47746)
			(xy 381.731074 -157.476978) (xy 381.676895 -157.469165) (xy 381.624392 -157.453681) (xy 381.574645 -157.430842)
			(xy 381.528678 -157.40112) (xy 381.507746 -157.38348) (xy 381.507492 -157.383226) (xy 381.500418 -157.377621)
			(xy 381.483491 -157.371387) (xy 381.474472 -157.371034) (xy 381.407416 -157.371034) (xy 381.398399 -157.371391)
			(xy 381.381482 -157.377638) (xy 381.374396 -157.383226) (xy 381.374396 -157.38348) (xy 381.374142 -157.38348)
			(xy 381.353209 -157.401121) (xy 381.307241 -157.430845) (xy 381.257495 -157.453691) (xy 381.204993 -157.469187)
			(xy 381.150815 -157.477016) (xy 381.096073 -157.477016) (xy 381.041895 -157.469187) (xy 380.989393 -157.453691)
			(xy 380.939647 -157.430845) (xy 380.893679 -157.401121) (xy 380.872746 -157.38348) (xy 380.872492 -157.383226)
			(xy 380.865418 -157.377621) (xy 380.848491 -157.371387) (xy 380.839472 -157.371034) (xy 380.772416 -157.371034)
			(xy 380.763399 -157.371391) (xy 380.746482 -157.377638) (xy 380.739396 -157.383226) (xy 380.739396 -157.38348)
			(xy 380.739142 -157.38348) (xy 380.718209 -157.401121) (xy 380.672241 -157.430845) (xy 380.622495 -157.453691)
			(xy 380.569993 -157.469187) (xy 380.515815 -157.477016) (xy 380.461073 -157.477016) (xy 380.406895 -157.469187)
			(xy 380.354393 -157.453691) (xy 380.304647 -157.430845) (xy 380.258679 -157.401121) (xy 380.237746 -157.38348)
			(xy 380.237492 -157.383226) (xy 380.230418 -157.377621) (xy 380.213491 -157.371387) (xy 380.204472 -157.371034)
			(xy 380.137416 -157.371034) (xy 380.128399 -157.371391) (xy 380.111482 -157.377638) (xy 380.104396 -157.383226)
			(xy 380.104396 -157.38348) (xy 380.104142 -157.38348) (xy 380.083202 -157.40111) (xy 380.037232 -157.430824)
			(xy 379.987486 -157.453662) (xy 379.934987 -157.469155) (xy 379.880813 -157.476985) (xy 379.853444 -157.47746)
			(xy 379.82354 -157.476843) (xy 379.764464 -157.467504) (xy 379.707569 -157.449064) (xy 379.654247 -157.421974)
			(xy 379.605804 -157.386898) (xy 379.584204 -157.366208) (xy 379.577346 -157.35935) (xy 379.559566 -157.35173)
			(xy 379.470412 -157.348936) (xy 379.452632 -157.355286) (xy 379.445266 -157.36189) (xy 379.424251 -157.37974)
			(xy 379.378064 -157.409851) (xy 379.328024 -157.433002) (xy 379.275173 -157.448711) (xy 379.220612 -157.456652)
			(xy 379.193044 -157.45714) (xy 379.165794 -157.456604) (xy 379.111847 -157.448854) (xy 379.059552 -157.433505)
			(xy 379.009975 -157.41087) (xy 378.964123 -157.381409) (xy 378.92293 -157.345723) (xy 378.887236 -157.304538)
			(xy 378.857767 -157.258692) (xy 378.835122 -157.209119) (xy 378.819762 -157.156827) (xy 378.812002 -157.102882)
			(xy 378.811536 -157.075632) (xy 378.812012 -157.048262) (xy 378.819826 -156.994083) (xy 378.835312 -156.94158)
			(xy 378.858152 -156.891833) (xy 378.887875 -156.845866) (xy 378.905516 -156.824934) (xy 378.90577 -156.82468)
			(xy 378.911379 -156.817609) (xy 378.91761 -156.80068) (xy 378.917962 -156.79166) (xy 378.917962 -156.724604)
			(xy 378.917611 -156.715586) (xy 378.91136 -156.698669) (xy 378.90577 -156.691584) (xy 378.905516 -156.691584)
			(xy 378.905516 -156.69133) (xy 378.88788 -156.670395) (xy 378.858167 -156.624424) (xy 378.83533 -156.574677)
			(xy 378.819839 -156.522176) (xy 378.81201 -156.468001) (xy 378.811536 -156.440632) (xy 378.812066 -156.411956)
			(xy 378.820635 -156.355248) (xy 378.837599 -156.300463) (xy 378.862576 -156.248836) (xy 378.895002 -156.201531)
			(xy 378.934147 -156.159616) (xy 378.956316 -156.14142) (xy 378.966222 -156.133546) (xy 378.976382 -156.110432)
			(xy 378.967492 -156.000704) (xy 378.95403 -155.979622) (xy 378.942854 -155.973272) (xy 378.917936 -155.958648)
			(xy 378.872393 -155.923103) (xy 378.832729 -155.881098) (xy 378.79985 -155.833593) (xy 378.774509 -155.781675)
			(xy 378.757285 -155.72653) (xy 378.74857 -155.669418) (xy 378.748036 -155.640532) (xy 373.029025 -155.640532)
			(xy 373.032274 -155.643326) (xy 373.053071 -155.660062) (xy 373.090199 -155.698418) (xy 373.121617 -155.741576)
			(xy 373.146714 -155.788691) (xy 373.164998 -155.838845) (xy 373.176112 -155.891058) (xy 373.17984 -155.94431)
			(xy 373.17611 -155.997562) (xy 373.164992 -156.049774) (xy 373.146706 -156.099927) (xy 373.121607 -156.147041)
			(xy 373.090186 -156.190197) (xy 373.053057 -156.228552) (xy 373.032274 -156.245306) (xy 373.02347 -156.252916)
			(xy 373.013285 -156.273815) (xy 373.012716 -156.285438) (xy 373.012716 -156.365194) (xy 373.013267 -156.376824)
			(xy 373.023447 -156.397734) (xy 373.032274 -156.405326) (xy 373.053071 -156.422062) (xy 373.090199 -156.460418)
			(xy 373.121617 -156.503576) (xy 373.146714 -156.550691) (xy 373.164998 -156.600845) (xy 373.176112 -156.653058)
			(xy 373.17984 -156.70631) (xy 373.17611 -156.759562) (xy 373.164992 -156.811774) (xy 373.146706 -156.861927)
			(xy 373.121607 -156.909041) (xy 373.090186 -156.952197) (xy 373.053057 -156.990552) (xy 373.032274 -157.007306)
			(xy 373.02347 -157.014916) (xy 373.013285 -157.035815) (xy 373.012716 -157.047438) (xy 373.012716 -157.127194)
			(xy 373.013267 -157.138824) (xy 373.023447 -157.159734) (xy 373.032274 -157.167326) (xy 373.053071 -157.184062)
			(xy 373.090199 -157.222418) (xy 373.121617 -157.265576) (xy 373.146714 -157.312691) (xy 373.164998 -157.362845)
			(xy 373.176112 -157.415058) (xy 373.17984 -157.46831) (xy 373.17611 -157.521562) (xy 373.164992 -157.573774)
			(xy 373.146706 -157.623927) (xy 373.121607 -157.671041) (xy 373.090186 -157.714197) (xy 373.053057 -157.752552)
			(xy 373.032274 -157.769306) (xy 373.02347 -157.776916) (xy 373.013285 -157.797815) (xy 373.012716 -157.809438)
			(xy 373.012716 -157.889194) (xy 373.013267 -157.900824) (xy 373.023447 -157.921734) (xy 373.032274 -157.929326)
			(xy 373.054765 -157.947509) (xy 373.0945 -157.98953) (xy 373.127439 -158.037066) (xy 373.152827 -158.089029)
			(xy 373.170081 -158.144228) (xy 373.178807 -158.201399) (xy 373.17934 -158.230316) (xy 373.178837 -158.257566)
			(xy 373.171079 -158.311512) (xy 373.155724 -158.363804) (xy 373.133083 -158.413379) (xy 373.103618 -158.459228)
			(xy 373.067929 -158.500417) (xy 373.026741 -158.536109) (xy 372.980893 -158.565575) (xy 372.931319 -158.588218)
			(xy 372.879027 -158.603576) (xy 372.825082 -158.611336) (xy 372.797832 -158.611824) (xy 372.768915 -158.611312)
			(xy 372.711742 -158.602585) (xy 372.656542 -158.585328) (xy 372.604579 -158.559936) (xy 372.557046 -158.52699)
			(xy 372.515031 -158.487245) (xy 372.496842 -158.464758) (xy 372.489214 -158.455973) (xy 372.468329 -158.445779)
			(xy 372.45671 -158.4452) (xy 372.376954 -158.4452) (xy 372.365321 -158.445727) (xy 372.344411 -158.455924)
			(xy 372.336822 -158.464758) (xy 372.320069 -158.485541) (xy 372.281715 -158.522671) (xy 372.238561 -158.554093)
			(xy 372.191447 -158.579192) (xy 372.141295 -158.597478) (xy 372.089084 -158.608595) (xy 372.035832 -158.612325)
			(xy 371.98258 -158.608595) (xy 371.930369 -158.597478) (xy 371.880217 -158.579192) (xy 371.833103 -158.554093)
			(xy 371.789949 -158.522671) (xy 371.751595 -158.485541) (xy 371.734842 -158.464758) (xy 371.727214 -158.455973)
			(xy 371.706329 -158.445779) (xy 371.69471 -158.4452) (xy 371.614954 -158.4452) (xy 371.603321 -158.445727)
			(xy 371.582411 -158.455924) (xy 371.574822 -158.464758) (xy 371.556608 -158.487222) (xy 371.514594 -158.526961)
			(xy 371.467065 -158.559903) (xy 371.415108 -158.585295) (xy 371.359914 -158.602555) (xy 371.302747 -158.611287)
			(xy 371.273832 -158.611824) (xy 371.246985 -158.611383) (xy 371.19382 -158.603872) (xy 371.142233 -158.588978)
			(xy 371.093246 -158.566998) (xy 371.047824 -158.538364) (xy 371.006867 -158.503644) (xy 370.971184 -158.463523)
			(xy 370.941481 -158.418794) (xy 370.918343 -158.370342) (xy 370.90985 -158.34487) (xy 370.90985 -158.344616)
			(xy 370.906145 -158.334478) (xy 370.891796 -158.318377) (xy 370.872119 -158.309548) (xy 370.861336 -158.309056)
			(xy 370.430298 -158.309056) (xy 370.422678 -158.311596) (xy 370.394291 -158.320136) (xy 370.335731 -158.329324)
			(xy 370.306092 -158.329884) (xy 370.276456 -158.329298) (xy 370.217897 -158.320116) (xy 370.189506 -158.311596)
			(xy 370.181886 -158.309056) (xy 369.795298 -158.309056) (xy 369.787678 -158.311596) (xy 369.759291 -158.320136)
			(xy 369.700731 -158.329324) (xy 369.671092 -158.329884) (xy 369.641456 -158.329298) (xy 369.582897 -158.320116)
			(xy 369.554506 -158.311596) (xy 369.546886 -158.309056) (xy 369.160298 -158.309056) (xy 369.152678 -158.311596)
			(xy 369.124291 -158.320136) (xy 369.065731 -158.329324) (xy 369.036092 -158.329884) (xy 369.006456 -158.329298)
			(xy 368.947897 -158.320116) (xy 368.919506 -158.311596) (xy 368.911886 -158.309056) (xy 368.525298 -158.309056)
			(xy 368.517678 -158.311596) (xy 368.489291 -158.320136) (xy 368.430731 -158.329324) (xy 368.401092 -158.329884)
			(xy 368.371456 -158.329298) (xy 368.312897 -158.320116) (xy 368.284506 -158.311596) (xy 368.276886 -158.309056)
			(xy 367.876328 -158.309056) (xy 367.865542 -158.309553) (xy 367.845852 -158.31836) (xy 367.831513 -158.334474)
			(xy 367.827814 -158.344616) (xy 367.827814 -158.34487) (xy 367.81935 -158.370349) (xy 367.79619 -158.418787)
			(xy 367.766471 -158.463501) (xy 367.730779 -158.50361) (xy 367.689819 -158.538322) (xy 367.6444 -158.566952)
			(xy 367.595417 -158.588935) (xy 367.543837 -158.603838) (xy 367.490677 -158.611365) (xy 367.463832 -158.611824)
			(xy 367.434915 -158.611312) (xy 367.377742 -158.602585) (xy 367.322542 -158.585328) (xy 367.270579 -158.559936)
			(xy 367.223046 -158.52699) (xy 367.181031 -158.487245) (xy 367.162842 -158.464758) (xy 367.155214 -158.455973)
			(xy 367.134329 -158.445779) (xy 367.12271 -158.4452) (xy 367.042954 -158.4452) (xy 367.031321 -158.445727)
			(xy 367.010411 -158.455924) (xy 367.002822 -158.464758) (xy 366.986069 -158.485541) (xy 366.947715 -158.522671)
			(xy 366.904561 -158.554093) (xy 366.857447 -158.579192) (xy 366.807295 -158.597478) (xy 366.755084 -158.608595)
			(xy 366.701832 -158.612325) (xy 366.64858 -158.608595) (xy 366.596369 -158.597478) (xy 366.546217 -158.579192)
			(xy 366.499103 -158.554093) (xy 366.455949 -158.522671) (xy 366.417595 -158.485541) (xy 366.400842 -158.464758)
			(xy 366.393214 -158.455973) (xy 366.372329 -158.445779) (xy 366.36071 -158.4452) (xy 366.280954 -158.4452)
			(xy 366.269321 -158.445727) (xy 366.248411 -158.455924) (xy 366.240822 -158.464758) (xy 366.222608 -158.487222)
			(xy 366.180594 -158.526961) (xy 366.133065 -158.559903) (xy 366.081108 -158.585295) (xy 366.025914 -158.602555)
			(xy 365.968747 -158.611287) (xy 365.939832 -158.611824) (xy 365.912581 -158.611315) (xy 365.858632 -158.603563)
			(xy 365.806336 -158.588212) (xy 365.756757 -158.565574) (xy 365.710905 -158.536111) (xy 365.669712 -158.500422)
			(xy 365.634018 -158.459234) (xy 365.604549 -158.413385) (xy 365.581905 -158.363809) (xy 365.566547 -158.311515)
			(xy 365.558788 -158.257567) (xy 365.558324 -158.230316) (xy 365.558845 -158.201399) (xy 365.567572 -158.144228)
			(xy 365.584829 -158.089028) (xy 365.61022 -158.037067) (xy 365.643164 -157.989533) (xy 365.682904 -157.947516)
			(xy 365.70539 -157.929326) (xy 365.714174 -157.921696) (xy 365.724371 -157.900813) (xy 365.724948 -157.889194)
			(xy 365.724948 -157.809438) (xy 365.724448 -157.797801) (xy 365.714233 -157.77689) (xy 365.70539 -157.769306)
			(xy 365.684622 -157.752534) (xy 365.647489 -157.714185) (xy 365.616065 -157.671033) (xy 365.590963 -157.623922)
			(xy 365.572675 -157.573771) (xy 365.561556 -157.52156) (xy 365.557825 -157.46831) (xy 364.789212 -157.46831)
			(xy 364.789212 -158.623) (xy 364.789634 -158.63307) (xy 364.797357 -158.651668) (xy 364.804198 -158.659068)
			(xy 365.511842 -159.366458) (xy 365.519238 -159.373303) (xy 365.53784 -159.381021) (xy 365.54791 -159.381444)
			(xy 383.796286 -159.381444) (xy 383.806356 -159.381865) (xy 383.824954 -159.389588) (xy 383.832354 -159.39643)
			(xy 384.332226 -159.896556) (xy 384.339043 -159.903974) (xy 384.346776 -159.92256) (xy 384.347212 -159.932624)
			(xy 384.347212 -167.89146) (xy 384.347391 -167.895524) (xy 385.275836 -167.895524) (xy 385.275836 -151.935688)
			(xy 385.276246 -151.925617) (xy 385.283976 -151.907019) (xy 385.290822 -151.89962) (xy 385.887468 -151.302974)
			(xy 385.894882 -151.296152) (xy 385.913471 -151.288422) (xy 385.923536 -151.287988) (xy 392.805158 -151.287988)
			(xy 392.815228 -151.288412) (xy 392.833827 -151.296131) (xy 392.841226 -151.302974) (xy 394.188696 -152.650444)
			(xy 408.315158 -152.650444) (xy 408.319229 -152.594822) (xy 408.331355 -152.540385) (xy 408.351278 -152.488294)
			(xy 408.378574 -152.439659) (xy 408.41266 -152.395516) (xy 408.452809 -152.356807) (xy 408.498167 -152.324356)
			(xy 408.547767 -152.298855) (xy 408.600551 -152.280848) (xy 408.655394 -152.270718) (xy 408.711128 -152.268681)
			(xy 408.766565 -152.274781) (xy 408.820522 -152.288887) (xy 408.871851 -152.310699) (xy 408.919457 -152.339753)
			(xy 408.962325 -152.375428) (xy 408.99872 -152.416048) (xy 419.022302 -152.416048) (xy 419.022302 -152.361552)
			(xy 419.030058 -152.307609) (xy 419.04541 -152.25532) (xy 419.068048 -152.205747) (xy 419.097511 -152.159901)
			(xy 419.133197 -152.118714) (xy 419.174382 -152.083025) (xy 419.220226 -152.05356) (xy 419.269797 -152.030919)
			(xy 419.322086 -152.015563) (xy 419.376028 -152.007804) (xy 419.403276 -152.007316) (xy 419.432193 -152.007846)
			(xy 419.489364 -152.016571) (xy 419.544562 -152.033827) (xy 419.596524 -152.059216) (xy 419.644058 -152.092158)
			(xy 419.686076 -152.131897) (xy 419.704266 -152.154382) (xy 419.711884 -152.163178) (xy 419.732777 -152.173364)
			(xy 419.744398 -152.17394) (xy 419.824154 -152.17394) (xy 419.835791 -152.173439) (xy 419.856702 -152.163225)
			(xy 419.864286 -152.154382) (xy 419.881039 -152.133599) (xy 419.919393 -152.096469) (xy 419.962547 -152.065047)
			(xy 420.009661 -152.039948) (xy 420.059813 -152.021662) (xy 420.112024 -152.010545) (xy 420.165276 -152.006815)
			(xy 420.218528 -152.010545) (xy 420.270739 -152.021662) (xy 420.320891 -152.039948) (xy 420.368005 -152.065047)
			(xy 420.411159 -152.096469) (xy 420.449513 -152.133599) (xy 420.466266 -152.154382) (xy 420.473884 -152.163178)
			(xy 420.494777 -152.173364) (xy 420.506398 -152.17394) (xy 420.586154 -152.17394) (xy 420.597791 -152.173439)
			(xy 420.618702 -152.163225) (xy 420.626286 -152.154382) (xy 420.643039 -152.133599) (xy 420.681393 -152.096469)
			(xy 420.724547 -152.065047) (xy 420.771661 -152.039948) (xy 420.821813 -152.021662) (xy 420.874024 -152.010545)
			(xy 420.927276 -152.006815) (xy 420.980528 -152.010545) (xy 421.032739 -152.021662) (xy 421.082891 -152.039948)
			(xy 421.130005 -152.065047) (xy 421.173159 -152.096469) (xy 421.211513 -152.133599) (xy 421.228266 -152.154382)
			(xy 421.235884 -152.163178) (xy 421.256777 -152.173364) (xy 421.268398 -152.17394) (xy 421.348154 -152.17394)
			(xy 421.359791 -152.173439) (xy 421.380702 -152.163225) (xy 421.388286 -152.154382) (xy 421.40648 -152.131901)
			(xy 421.4485 -152.092167) (xy 421.496034 -152.059228) (xy 421.547995 -152.033839) (xy 421.603192 -152.016582)
			(xy 421.66036 -152.007852) (xy 421.689276 -152.007316) (xy 421.716532 -152.007729) (xy 421.770489 -152.015484)
			(xy 421.822793 -152.030839) (xy 421.872379 -152.053481) (xy 421.918238 -152.082951) (xy 421.959436 -152.118647)
			(xy 421.995135 -152.159843) (xy 422.024607 -152.2057) (xy 422.047253 -152.255285) (xy 422.062611 -152.307588)
			(xy 422.070369 -152.361544) (xy 422.070369 -152.416056) (xy 422.062611 -152.470012) (xy 422.047253 -152.522315)
			(xy 422.024607 -152.5719) (xy 421.995135 -152.617757) (xy 421.959436 -152.658953) (xy 421.918238 -152.694649)
			(xy 421.872379 -152.724119) (xy 421.822793 -152.746761) (xy 421.770489 -152.762116) (xy 421.716532 -152.769871)
			(xy 421.689276 -152.770332) (xy 421.66036 -152.769785) (xy 421.603189 -152.761065) (xy 421.54799 -152.743815)
			(xy 421.496027 -152.718429) (xy 421.448493 -152.685489) (xy 421.406476 -152.64575) (xy 421.388286 -152.623266)
			(xy 421.380681 -152.614457) (xy 421.359778 -152.604276) (xy 421.348154 -152.603708) (xy 421.268398 -152.603708)
			(xy 421.256767 -152.604257) (xy 421.235857 -152.614439) (xy 421.228266 -152.623266) (xy 421.211513 -152.644049)
			(xy 421.173159 -152.681179) (xy 421.130005 -152.712601) (xy 421.082891 -152.7377) (xy 421.032739 -152.755986)
			(xy 420.980528 -152.767103) (xy 420.927276 -152.770833) (xy 420.874024 -152.767103) (xy 420.821813 -152.755986)
			(xy 420.771661 -152.7377) (xy 420.724547 -152.712601) (xy 420.681393 -152.681179) (xy 420.643039 -152.644049)
			(xy 420.626286 -152.623266) (xy 420.618681 -152.614457) (xy 420.597778 -152.604276) (xy 420.586154 -152.603708)
			(xy 420.506398 -152.603708) (xy 420.494767 -152.604257) (xy 420.473857 -152.614439) (xy 420.466266 -152.623266)
			(xy 420.449513 -152.644049) (xy 420.411159 -152.681179) (xy 420.368005 -152.712601) (xy 420.320891 -152.7377)
			(xy 420.270739 -152.755986) (xy 420.218528 -152.767103) (xy 420.165276 -152.770833) (xy 420.112024 -152.767103)
			(xy 420.059813 -152.755986) (xy 420.009661 -152.7377) (xy 419.962547 -152.712601) (xy 419.919393 -152.681179)
			(xy 419.881039 -152.644049) (xy 419.864286 -152.623266) (xy 419.856681 -152.614457) (xy 419.835778 -152.604276)
			(xy 419.824154 -152.603708) (xy 419.744398 -152.603708) (xy 419.732767 -152.604257) (xy 419.711857 -152.614439)
			(xy 419.704266 -152.623266) (xy 419.686086 -152.645759) (xy 419.644065 -152.685495) (xy 419.596528 -152.718434)
			(xy 419.544564 -152.743821) (xy 419.489364 -152.761075) (xy 419.432193 -152.7698) (xy 419.403276 -152.770332)
			(xy 419.376028 -152.769796) (xy 419.322086 -152.762037) (xy 419.269797 -152.746681) (xy 419.220226 -152.72404)
			(xy 419.174382 -152.694575) (xy 419.133197 -152.658886) (xy 419.097511 -152.617699) (xy 419.068048 -152.571853)
			(xy 419.04541 -152.52228) (xy 419.030058 -152.469991) (xy 419.022302 -152.416048) (xy 408.99872 -152.416048)
			(xy 408.999542 -152.416965) (xy 409.030315 -152.463478) (xy 409.053987 -152.513975) (xy 409.070055 -152.567382)
			(xy 409.078175 -152.622558) (xy 409.078684 -152.650444) (xy 409.078175 -152.67833) (xy 409.070055 -152.733506)
			(xy 409.053987 -152.786913) (xy 409.030315 -152.83741) (xy 408.999542 -152.883923) (xy 408.962325 -152.92546)
			(xy 408.919457 -152.961135) (xy 408.871851 -152.990189) (xy 408.820522 -153.012001) (xy 408.766565 -153.026107)
			(xy 408.711128 -153.032207) (xy 408.655394 -153.03017) (xy 408.600551 -153.02004) (xy 408.547767 -153.002033)
			(xy 408.498167 -152.976532) (xy 408.452809 -152.944081) (xy 408.41266 -152.905372) (xy 408.378574 -152.861229)
			(xy 408.351278 -152.812594) (xy 408.331355 -152.760503) (xy 408.319229 -152.706066) (xy 408.315158 -152.650444)
			(xy 394.188696 -152.650444) (xy 394.704062 -153.16581) (xy 411.48203 -153.16581) (xy 411.486101 -153.110188)
			(xy 411.498227 -153.055751) (xy 411.51815 -153.00366) (xy 411.545446 -152.955025) (xy 411.579532 -152.910882)
			(xy 411.619681 -152.872173) (xy 411.665039 -152.839722) (xy 411.714639 -152.814221) (xy 411.767423 -152.796214)
			(xy 411.822266 -152.786084) (xy 411.878 -152.784047) (xy 411.933437 -152.790147) (xy 411.987394 -152.804253)
			(xy 412.038723 -152.826065) (xy 412.086329 -152.855119) (xy 412.129197 -152.890794) (xy 412.166414 -152.932331)
			(xy 412.197187 -152.978844) (xy 412.220859 -153.029341) (xy 412.236927 -153.082748) (xy 412.245047 -153.137924)
			(xy 412.245556 -153.16581) (xy 412.37103 -153.16581) (xy 412.375101 -153.110188) (xy 412.387227 -153.055751)
			(xy 412.40715 -153.00366) (xy 412.434446 -152.955025) (xy 412.468532 -152.910882) (xy 412.508681 -152.872173)
			(xy 412.554039 -152.839722) (xy 412.603639 -152.814221) (xy 412.656423 -152.796214) (xy 412.711266 -152.786084)
			(xy 412.767 -152.784047) (xy 412.822437 -152.790147) (xy 412.876394 -152.804253) (xy 412.927723 -152.826065)
			(xy 412.975329 -152.855119) (xy 413.018197 -152.890794) (xy 413.055414 -152.932331) (xy 413.086187 -152.978844)
			(xy 413.109859 -153.029341) (xy 413.125927 -153.082748) (xy 413.134047 -153.137924) (xy 413.134556 -153.16581)
			(xy 413.26003 -153.16581) (xy 413.264101 -153.110188) (xy 413.276227 -153.055751) (xy 413.29615 -153.00366)
			(xy 413.323446 -152.955025) (xy 413.357532 -152.910882) (xy 413.397681 -152.872173) (xy 413.443039 -152.839722)
			(xy 413.492639 -152.814221) (xy 413.545423 -152.796214) (xy 413.600266 -152.786084) (xy 413.656 -152.784047)
			(xy 413.711437 -152.790147) (xy 413.765394 -152.804253) (xy 413.816723 -152.826065) (xy 413.864329 -152.855119)
			(xy 413.907197 -152.890794) (xy 413.944414 -152.932331) (xy 413.975187 -152.978844) (xy 413.998859 -153.029341)
			(xy 414.014927 -153.082748) (xy 414.023047 -153.137924) (xy 414.023556 -153.16581) (xy 414.14903 -153.16581)
			(xy 414.153101 -153.110188) (xy 414.165227 -153.055751) (xy 414.18515 -153.00366) (xy 414.212446 -152.955025)
			(xy 414.246532 -152.910882) (xy 414.286681 -152.872173) (xy 414.332039 -152.839722) (xy 414.381639 -152.814221)
			(xy 414.434423 -152.796214) (xy 414.489266 -152.786084) (xy 414.545 -152.784047) (xy 414.600437 -152.790147)
			(xy 414.654394 -152.804253) (xy 414.705723 -152.826065) (xy 414.753329 -152.855119) (xy 414.796197 -152.890794)
			(xy 414.833414 -152.932331) (xy 414.864187 -152.978844) (xy 414.887859 -153.029341) (xy 414.903927 -153.082748)
			(xy 414.912047 -153.137924) (xy 414.912556 -153.16581) (xy 414.912047 -153.193696) (xy 414.903927 -153.248872)
			(xy 414.887859 -153.302279) (xy 414.864187 -153.352776) (xy 414.833414 -153.399289) (xy 414.796197 -153.440826)
			(xy 414.753329 -153.476501) (xy 414.705723 -153.505555) (xy 414.654394 -153.527367) (xy 414.600437 -153.541473)
			(xy 414.545 -153.547573) (xy 414.489266 -153.545536) (xy 414.434423 -153.535406) (xy 414.381639 -153.517399)
			(xy 414.332039 -153.491898) (xy 414.286681 -153.459447) (xy 414.246532 -153.420738) (xy 414.212446 -153.376595)
			(xy 414.18515 -153.32796) (xy 414.165227 -153.275869) (xy 414.153101 -153.221432) (xy 414.14903 -153.16581)
			(xy 414.023556 -153.16581) (xy 414.023047 -153.193696) (xy 414.014927 -153.248872) (xy 413.998859 -153.302279)
			(xy 413.975187 -153.352776) (xy 413.944414 -153.399289) (xy 413.907197 -153.440826) (xy 413.864329 -153.476501)
			(xy 413.816723 -153.505555) (xy 413.765394 -153.527367) (xy 413.711437 -153.541473) (xy 413.656 -153.547573)
			(xy 413.600266 -153.545536) (xy 413.545423 -153.535406) (xy 413.492639 -153.517399) (xy 413.443039 -153.491898)
			(xy 413.397681 -153.459447) (xy 413.357532 -153.420738) (xy 413.323446 -153.376595) (xy 413.29615 -153.32796)
			(xy 413.276227 -153.275869) (xy 413.264101 -153.221432) (xy 413.26003 -153.16581) (xy 413.134556 -153.16581)
			(xy 413.134047 -153.193696) (xy 413.125927 -153.248872) (xy 413.109859 -153.302279) (xy 413.086187 -153.352776)
			(xy 413.055414 -153.399289) (xy 413.018197 -153.440826) (xy 412.975329 -153.476501) (xy 412.927723 -153.505555)
			(xy 412.876394 -153.527367) (xy 412.822437 -153.541473) (xy 412.767 -153.547573) (xy 412.711266 -153.545536)
			(xy 412.656423 -153.535406) (xy 412.603639 -153.517399) (xy 412.554039 -153.491898) (xy 412.508681 -153.459447)
			(xy 412.468532 -153.420738) (xy 412.434446 -153.376595) (xy 412.40715 -153.32796) (xy 412.387227 -153.275869)
			(xy 412.375101 -153.221432) (xy 412.37103 -153.16581) (xy 412.245556 -153.16581) (xy 412.245047 -153.193696)
			(xy 412.236927 -153.248872) (xy 412.220859 -153.302279) (xy 412.197187 -153.352776) (xy 412.166414 -153.399289)
			(xy 412.129197 -153.440826) (xy 412.086329 -153.476501) (xy 412.038723 -153.505555) (xy 411.987394 -153.527367)
			(xy 411.933437 -153.541473) (xy 411.878 -153.547573) (xy 411.822266 -153.545536) (xy 411.767423 -153.535406)
			(xy 411.714639 -153.517399) (xy 411.665039 -153.491898) (xy 411.619681 -153.459447) (xy 411.579532 -153.420738)
			(xy 411.545446 -153.376595) (xy 411.51815 -153.32796) (xy 411.498227 -153.275869) (xy 411.486101 -153.221432)
			(xy 411.48203 -153.16581) (xy 394.704062 -153.16581) (xy 397.02105 -155.482798) (xy 410.680916 -155.482798)
			(xy 410.681427 -155.453881) (xy 410.690157 -155.396709) (xy 410.707416 -155.34151) (xy 410.732809 -155.289548)
			(xy 410.765754 -155.242014) (xy 410.805496 -155.199998) (xy 410.827982 -155.181808) (xy 410.836789 -155.174202)
			(xy 410.84697 -155.1533) (xy 410.84754 -155.141676) (xy 410.84754 -155.06192) (xy 410.846996 -155.050288)
			(xy 410.836813 -155.029377) (xy 410.827982 -155.021788) (xy 410.805489 -155.003608) (xy 410.765755 -154.961586)
			(xy 410.732818 -154.914048) (xy 410.707431 -154.862085) (xy 410.690177 -154.806886) (xy 410.68145 -154.749715)
			(xy 410.680916 -154.720798) (xy 410.681355 -154.694076) (xy 410.688826 -154.641156) (xy 410.703609 -154.589796)
			(xy 410.725413 -154.541001) (xy 410.753813 -154.495726) (xy 410.788252 -154.454857) (xy 410.828056 -154.419193)
			(xy 410.872448 -154.389431) (xy 410.896308 -154.37739) (xy 410.909262 -154.371294) (xy 410.924502 -154.347164)
			(xy 410.926788 -154.242262) (xy 410.926562 -154.233041) (xy 410.920401 -154.215674) (xy 410.908492 -154.201611)
			(xy 410.900626 -154.196796) (xy 410.900626 -154.196542) (xy 410.900118 -154.196542) (xy 410.874667 -154.182092)
			(xy 410.828118 -154.146621) (xy 410.787529 -154.104459) (xy 410.753851 -154.056597) (xy 410.727874 -154.004154)
			(xy 410.710207 -153.94836) (xy 410.701264 -153.890524) (xy 410.700728 -153.861262) (xy 410.701214 -153.834011)
			(xy 410.70897 -153.780063) (xy 410.724325 -153.727768) (xy 410.746967 -153.678191) (xy 410.776433 -153.632341)
			(xy 410.812124 -153.59115) (xy 410.853315 -153.555459) (xy 410.899165 -153.525993) (xy 410.948742 -153.503351)
			(xy 411.001037 -153.487996) (xy 411.054985 -153.48024) (xy 411.109487 -153.48024) (xy 411.163435 -153.487996)
			(xy 411.21573 -153.503351) (xy 411.265307 -153.525993) (xy 411.311157 -153.555459) (xy 411.352348 -153.59115)
			(xy 411.388039 -153.632341) (xy 411.417505 -153.678191) (xy 411.440147 -153.727768) (xy 411.455502 -153.780063)
			(xy 411.463258 -153.834011) (xy 411.463744 -153.861262) (xy 411.463294 -153.887984) (xy 411.455828 -153.940905)
			(xy 411.441048 -153.992265) (xy 411.419247 -154.041061) (xy 411.390848 -154.086337) (xy 411.35641 -154.127206)
			(xy 411.316605 -154.16287) (xy 411.272212 -154.19263) (xy 411.248352 -154.20467) (xy 411.235398 -154.210766)
			(xy 411.220158 -154.234896) (xy 411.217872 -154.339798) (xy 411.218025 -154.349025) (xy 411.224214 -154.366399)
			(xy 411.236154 -154.380457) (xy 411.244034 -154.385264) (xy 411.244034 -154.385518) (xy 411.244542 -154.385518)
			(xy 411.270009 -154.399941) (xy 411.316561 -154.435415) (xy 411.357151 -154.477579) (xy 411.390828 -154.525447)
			(xy 411.416802 -154.577895) (xy 411.434464 -154.633693) (xy 411.4434 -154.691534) (xy 411.443932 -154.720798)
			(xy 411.443438 -154.749716) (xy 411.434708 -154.80689) (xy 411.417447 -154.86209) (xy 411.39205 -154.914052)
			(xy 411.359101 -154.961585) (xy 411.319354 -155.0036) (xy 411.296866 -155.021788) (xy 411.288069 -155.029404)
			(xy 411.277881 -155.050298) (xy 411.277308 -155.06192) (xy 411.277308 -155.141676) (xy 411.277873 -155.153305)
			(xy 411.288043 -155.174215) (xy 411.296866 -155.181808) (xy 411.319346 -155.200003) (xy 411.359083 -155.242021)
			(xy 411.392024 -155.289555) (xy 411.417413 -155.341515) (xy 411.434669 -155.396713) (xy 411.443398 -155.453882)
			(xy 411.443932 -155.482798) (xy 411.443446 -155.510049) (xy 411.43569 -155.563997) (xy 411.431713 -155.57754)
			(xy 415.148268 -155.57754) (xy 415.148789 -155.548623) (xy 415.157514 -155.491451) (xy 415.17477 -155.436251)
			(xy 415.200161 -155.384288) (xy 415.233105 -155.336755) (xy 415.272847 -155.294739) (xy 415.295334 -155.27655)
			(xy 415.304114 -155.268917) (xy 415.314311 -155.248036) (xy 415.314892 -155.236418) (xy 415.314892 -155.156662)
			(xy 415.314363 -155.145029) (xy 415.304167 -155.124119) (xy 415.295334 -155.11653) (xy 415.272872 -155.098313)
			(xy 415.233134 -155.0563) (xy 415.200191 -155.008771) (xy 415.174799 -154.956814) (xy 415.157538 -154.901621)
			(xy 415.148805 -154.844455) (xy 415.148268 -154.81554) (xy 415.148712 -154.788817) (xy 415.156179 -154.735896)
			(xy 415.170959 -154.684535) (xy 415.192761 -154.635739) (xy 415.22116 -154.590464) (xy 415.2556 -154.549594)
			(xy 415.295406 -154.513931) (xy 415.339799 -154.484172) (xy 415.36366 -154.472132) (xy 415.376614 -154.466036)
			(xy 415.391854 -154.441906) (xy 415.39414 -154.337004) (xy 415.393979 -154.327778) (xy 415.387793 -154.310404)
			(xy 415.375856 -154.296346) (xy 415.367978 -154.291538) (xy 415.367978 -154.291284) (xy 415.36747 -154.291284)
			(xy 415.342006 -154.276855) (xy 415.295454 -154.241383) (xy 415.254863 -154.199219) (xy 415.221186 -154.151353)
			(xy 415.195211 -154.098906) (xy 415.177549 -154.043108) (xy 415.168612 -153.985267) (xy 415.16808 -153.956004)
			(xy 415.168566 -153.928753) (xy 415.176322 -153.874805) (xy 415.191677 -153.82251) (xy 415.214319 -153.772933)
			(xy 415.243785 -153.727083) (xy 415.279476 -153.685892) (xy 415.320667 -153.650201) (xy 415.366517 -153.620735)
			(xy 415.416094 -153.598093) (xy 415.468389 -153.582738) (xy 415.522337 -153.574982) (xy 415.576839 -153.574982)
			(xy 415.630787 -153.582738) (xy 415.683082 -153.598093) (xy 415.732659 -153.620735) (xy 415.778509 -153.650201)
			(xy 415.8197 -153.685892) (xy 415.855391 -153.727083) (xy 415.884857 -153.772933) (xy 415.907499 -153.82251)
			(xy 415.922854 -153.874805) (xy 415.93061 -153.928753) (xy 415.931096 -153.956004) (xy 415.930652 -153.982726)
			(xy 415.923181 -154.035646) (xy 415.908398 -154.087005) (xy 415.886595 -154.135799) (xy 415.858196 -154.181074)
			(xy 415.823758 -154.221944) (xy 415.783954 -154.257608) (xy 415.739563 -154.28737) (xy 415.715704 -154.299412)
			(xy 415.70275 -154.305508) (xy 415.68751 -154.329638) (xy 415.685224 -154.43454) (xy 415.685444 -154.443761)
			(xy 415.691606 -154.46113) (xy 415.703519 -154.475192) (xy 415.711386 -154.480006) (xy 415.711386 -154.48026)
			(xy 415.711894 -154.48026) (xy 415.737333 -154.494728) (xy 415.783878 -154.530198) (xy 415.824464 -154.572357)
			(xy 415.858138 -154.620218) (xy 415.884112 -154.672657) (xy 415.901777 -154.728447) (xy 415.910719 -154.78628)
			(xy 415.911284 -154.81554) (xy 415.911053 -154.82755) (xy 419.022278 -154.82755) (xy 419.022278 -154.77305)
			(xy 419.030034 -154.719104) (xy 419.045388 -154.666811) (xy 419.068027 -154.617236) (xy 419.097491 -154.571386)
			(xy 419.13318 -154.530197) (xy 419.174367 -154.494505) (xy 419.220215 -154.465038) (xy 419.269789 -154.442396)
			(xy 419.322081 -154.427039) (xy 419.376026 -154.419279) (xy 419.403276 -154.418792) (xy 419.432194 -154.419293)
			(xy 419.489368 -154.42802) (xy 419.544568 -154.445279) (xy 419.596531 -154.470674) (xy 419.644064 -154.503623)
			(xy 419.686078 -154.543369) (xy 419.704266 -154.565858) (xy 419.711888 -154.57465) (xy 419.732778 -154.584839)
			(xy 419.744398 -154.585416) (xy 419.824154 -154.585416) (xy 419.835787 -154.584888) (xy 419.856696 -154.574691)
			(xy 419.864286 -154.565858) (xy 419.881039 -154.545075) (xy 419.919393 -154.507945) (xy 419.962547 -154.476523)
			(xy 420.009661 -154.451424) (xy 420.059813 -154.433138) (xy 420.112024 -154.422021) (xy 420.165276 -154.418291)
			(xy 420.218528 -154.422021) (xy 420.270739 -154.433138) (xy 420.320891 -154.451424) (xy 420.368005 -154.476523)
			(xy 420.411159 -154.507945) (xy 420.449513 -154.545075) (xy 420.466266 -154.565858) (xy 420.473888 -154.57465)
			(xy 420.494778 -154.584839) (xy 420.506398 -154.585416) (xy 420.586154 -154.585416) (xy 420.597787 -154.584888)
			(xy 420.618696 -154.574691) (xy 420.626286 -154.565858) (xy 420.643039 -154.545075) (xy 420.681393 -154.507945)
			(xy 420.724547 -154.476523) (xy 420.771661 -154.451424) (xy 420.821813 -154.433138) (xy 420.874024 -154.422021)
			(xy 420.927276 -154.418291) (xy 420.980528 -154.422021) (xy 421.032739 -154.433138) (xy 421.082891 -154.451424)
			(xy 421.130005 -154.476523) (xy 421.173159 -154.507945) (xy 421.211513 -154.545075) (xy 421.228266 -154.565858)
			(xy 421.235888 -154.57465) (xy 421.256778 -154.584839) (xy 421.268398 -154.585416) (xy 421.348154 -154.585416)
			(xy 421.359787 -154.584888) (xy 421.380696 -154.574691) (xy 421.388286 -154.565858) (xy 421.406474 -154.543372)
			(xy 421.448496 -154.503639) (xy 421.496032 -154.470702) (xy 421.547993 -154.445314) (xy 421.603191 -154.428058)
			(xy 421.66036 -154.419328) (xy 421.689276 -154.418792) (xy 421.71653 -154.419254) (xy 421.770483 -154.427008)
			(xy 421.822784 -154.442362) (xy 421.872367 -154.465003) (xy 421.918223 -154.49447) (xy 421.959419 -154.530164)
			(xy 421.995115 -154.571357) (xy 422.024586 -154.617212) (xy 422.04723 -154.666793) (xy 422.062587 -154.719093)
			(xy 422.070345 -154.773046) (xy 422.070345 -154.827554) (xy 422.062587 -154.881507) (xy 422.04723 -154.933807)
			(xy 422.024586 -154.983388) (xy 421.995115 -155.029243) (xy 421.959419 -155.070436) (xy 421.918223 -155.10613)
			(xy 421.872367 -155.135597) (xy 421.822784 -155.158238) (xy 421.770483 -155.173592) (xy 421.71653 -155.181346)
			(xy 421.689276 -155.181808) (xy 421.660359 -155.18127) (xy 421.603188 -155.17255) (xy 421.547988 -155.155298)
			(xy 421.496025 -155.12991) (xy 421.448491 -155.096968) (xy 421.406475 -155.057228) (xy 421.388286 -155.034742)
			(xy 421.380685 -155.025929) (xy 421.359779 -155.015751) (xy 421.348154 -155.015184) (xy 421.268398 -155.015184)
			(xy 421.256769 -155.015742) (xy 421.235859 -155.025918) (xy 421.228266 -155.034742) (xy 421.211513 -155.055525)
			(xy 421.173159 -155.092655) (xy 421.130005 -155.124077) (xy 421.082891 -155.149176) (xy 421.032739 -155.167462)
			(xy 420.980528 -155.178579) (xy 420.927276 -155.182309) (xy 420.874024 -155.178579) (xy 420.821813 -155.167462)
			(xy 420.771661 -155.149176) (xy 420.724547 -155.124077) (xy 420.681393 -155.092655) (xy 420.643039 -155.055525)
			(xy 420.626286 -155.034742) (xy 420.618685 -155.025929) (xy 420.597779 -155.015751) (xy 420.586154 -155.015184)
			(xy 420.506398 -155.015184) (xy 420.494769 -155.015742) (xy 420.473859 -155.025918) (xy 420.466266 -155.034742)
			(xy 420.449513 -155.055525) (xy 420.411159 -155.092655) (xy 420.368005 -155.124077) (xy 420.320891 -155.149176)
			(xy 420.270739 -155.167462) (xy 420.218528 -155.178579) (xy 420.165276 -155.182309) (xy 420.112024 -155.178579)
			(xy 420.059813 -155.167462) (xy 420.009661 -155.149176) (xy 419.962547 -155.124077) (xy 419.919393 -155.092655)
			(xy 419.881039 -155.055525) (xy 419.864286 -155.034742) (xy 419.856685 -155.025929) (xy 419.835779 -155.015751)
			(xy 419.824154 -155.015184) (xy 419.744398 -155.015184) (xy 419.732769 -155.015742) (xy 419.711859 -155.025918)
			(xy 419.704266 -155.034742) (xy 419.686105 -155.057251) (xy 419.644078 -155.096982) (xy 419.596536 -155.129917)
			(xy 419.544569 -155.155301) (xy 419.489367 -155.172552) (xy 419.432194 -155.181276) (xy 419.403276 -155.181808)
			(xy 419.376026 -155.181321) (xy 419.322081 -155.173561) (xy 419.269789 -155.158204) (xy 419.220215 -155.135562)
			(xy 419.174367 -155.106095) (xy 419.13318 -155.070403) (xy 419.097491 -155.029214) (xy 419.068027 -154.983364)
			(xy 419.045388 -154.933789) (xy 419.030034 -154.881496) (xy 419.022278 -154.82755) (xy 415.911053 -154.82755)
			(xy 415.910729 -154.844456) (xy 415.902008 -154.901625) (xy 415.884758 -154.956824) (xy 415.859373 -155.008786)
			(xy 415.826436 -155.056321) (xy 415.786701 -155.098339) (xy 415.764218 -155.11653) (xy 415.755393 -155.12412)
			(xy 415.745222 -155.145034) (xy 415.74466 -155.156662) (xy 415.74466 -155.236418) (xy 415.745182 -155.248053)
			(xy 415.755381 -155.268963) (xy 415.764218 -155.27655) (xy 415.786681 -155.294765) (xy 415.826417 -155.33678)
			(xy 415.859358 -155.38431) (xy 415.884749 -155.436267) (xy 415.90201 -155.49146) (xy 415.910745 -155.548625)
			(xy 415.911284 -155.57754) (xy 415.910798 -155.604791) (xy 415.903042 -155.658739) (xy 415.887687 -155.711034)
			(xy 415.865045 -155.760611) (xy 415.835579 -155.806461) (xy 415.799888 -155.847652) (xy 415.758697 -155.883343)
			(xy 415.712847 -155.912809) (xy 415.66327 -155.935451) (xy 415.610975 -155.950806) (xy 415.557027 -155.958562)
			(xy 415.502525 -155.958562) (xy 415.448577 -155.950806) (xy 415.396282 -155.935451) (xy 415.346705 -155.912809)
			(xy 415.300855 -155.883343) (xy 415.259664 -155.847652) (xy 415.223973 -155.806461) (xy 415.194507 -155.760611)
			(xy 415.171865 -155.711034) (xy 415.15651 -155.658739) (xy 415.148754 -155.604791) (xy 415.148268 -155.57754)
			(xy 411.431713 -155.57754) (xy 411.420335 -155.616292) (xy 411.397693 -155.665869) (xy 411.368227 -155.711719)
			(xy 411.332536 -155.75291) (xy 411.291345 -155.788601) (xy 411.245495 -155.818067) (xy 411.195918 -155.840709)
			(xy 411.143623 -155.856064) (xy 411.089675 -155.86382) (xy 411.035173 -155.86382) (xy 410.981225 -155.856064)
			(xy 410.92893 -155.840709) (xy 410.879353 -155.818067) (xy 410.833503 -155.788601) (xy 410.792312 -155.75291)
			(xy 410.756621 -155.711719) (xy 410.727155 -155.665869) (xy 410.704513 -155.616292) (xy 410.689158 -155.563997)
			(xy 410.681402 -155.510049) (xy 410.680916 -155.482798) (xy 397.02105 -155.482798) (xy 397.778986 -156.240734)
			(xy 397.786393 -156.247565) (xy 397.804987 -156.255289) (xy 397.815054 -156.25572) (xy 411.92323 -156.25572)
			(xy 411.92812 -156.255862) (xy 411.937713 -156.257777) (xy 411.94228 -156.25953) (xy 412.042356 -156.30017)
			(xy 412.047012 -156.302196) (xy 412.055458 -156.307828) (xy 412.05912 -156.311346) (xy 412.344616 -156.596842)
			(xy 419.77132 -156.596842) (xy 419.775391 -156.54122) (xy 419.787517 -156.486783) (xy 419.80744 -156.434692)
			(xy 419.834736 -156.386057) (xy 419.868822 -156.341914) (xy 419.908971 -156.303205) (xy 419.954329 -156.270754)
			(xy 420.003929 -156.245253) (xy 420.056713 -156.227246) (xy 420.111556 -156.217116) (xy 420.16729 -156.215079)
			(xy 420.222727 -156.221179) (xy 420.276684 -156.235285) (xy 420.328013 -156.257097) (xy 420.375619 -156.286151)
			(xy 420.418487 -156.321826) (xy 420.455704 -156.363363) (xy 420.486477 -156.409876) (xy 420.510149 -156.460373)
			(xy 420.526217 -156.51378) (xy 420.534337 -156.568956) (xy 420.534846 -156.596842) (xy 420.534337 -156.624728)
			(xy 420.526217 -156.679904) (xy 420.510149 -156.733311) (xy 420.486477 -156.783808) (xy 420.455704 -156.830321)
			(xy 420.418487 -156.871858) (xy 420.375619 -156.907533) (xy 420.328013 -156.936587) (xy 420.276684 -156.958399)
			(xy 420.222727 -156.972505) (xy 420.16729 -156.978605) (xy 420.111556 -156.976568) (xy 420.056713 -156.966438)
			(xy 420.003929 -156.948431) (xy 419.954329 -156.92293) (xy 419.908971 -156.890479) (xy 419.868822 -156.85177)
			(xy 419.834736 -156.807627) (xy 419.80744 -156.758992) (xy 419.787517 -156.706901) (xy 419.775391 -156.652464)
			(xy 419.77132 -156.596842) (xy 412.344616 -156.596842) (xy 412.966408 -157.218634) (xy 417.996114 -157.218634)
			(xy 418.000185 -157.163012) (xy 418.012311 -157.108575) (xy 418.032234 -157.056484) (xy 418.05953 -157.007849)
			(xy 418.093616 -156.963706) (xy 418.133765 -156.924997) (xy 418.179123 -156.892546) (xy 418.228723 -156.867045)
			(xy 418.281507 -156.849038) (xy 418.33635 -156.838908) (xy 418.392084 -156.836871) (xy 418.447521 -156.842971)
			(xy 418.501478 -156.857077) (xy 418.552807 -156.878889) (xy 418.600413 -156.907943) (xy 418.643281 -156.943618)
			(xy 418.680498 -156.985155) (xy 418.711271 -157.031668) (xy 418.734943 -157.082165) (xy 418.751011 -157.135572)
			(xy 418.759131 -157.190748) (xy 418.75964 -157.218634) (xy 418.759131 -157.24652) (xy 418.751011 -157.301696)
			(xy 418.734943 -157.355103) (xy 418.711271 -157.4056) (xy 418.680498 -157.452113) (xy 418.643281 -157.49365)
			(xy 418.600413 -157.529325) (xy 418.552807 -157.558379) (xy 418.501478 -157.580191) (xy 418.447521 -157.594297)
			(xy 418.392084 -157.600397) (xy 418.33635 -157.59836) (xy 418.281507 -157.58823) (xy 418.228723 -157.570223)
			(xy 418.179123 -157.544722) (xy 418.133765 -157.512271) (xy 418.093616 -157.473562) (xy 418.05953 -157.429419)
			(xy 418.032234 -157.380784) (xy 418.012311 -157.328693) (xy 418.000185 -157.274256) (xy 417.996114 -157.218634)
			(xy 412.966408 -157.218634) (xy 413.523938 -157.776164) (xy 413.53076 -157.783578) (xy 413.538489 -157.802167)
			(xy 413.538924 -157.812232) (xy 413.538924 -159.427926) (xy 414.223454 -159.427926) (xy 414.22394 -159.400675)
			(xy 414.231696 -159.346727) (xy 414.247051 -159.294432) (xy 414.269693 -159.244855) (xy 414.299159 -159.199005)
			(xy 414.33485 -159.157814) (xy 414.376041 -159.122123) (xy 414.421891 -159.092657) (xy 414.471468 -159.070015)
			(xy 414.523763 -159.05466) (xy 414.577711 -159.046904) (xy 414.632213 -159.046904) (xy 414.686161 -159.05466)
			(xy 414.738456 -159.070015) (xy 414.788033 -159.092657) (xy 414.833883 -159.122123) (xy 414.875074 -159.157814)
			(xy 414.910765 -159.199005) (xy 414.940231 -159.244855) (xy 414.962873 -159.294432) (xy 414.978228 -159.346727)
			(xy 414.985984 -159.400675) (xy 414.98647 -159.427926) (xy 414.985809 -159.459489) (xy 414.975423 -159.521754)
			(xy 414.954937 -159.581463) (xy 414.940496 -159.609536) (xy 414.93567 -159.618426) (xy 414.933638 -159.637984)
			(xy 414.956498 -159.71647) (xy 414.959759 -159.725885) (xy 414.97216 -159.741449) (xy 414.980628 -159.746696)
			(xy 414.987994 -159.75076) (xy 414.9979 -159.756602) (xy 415.019744 -159.758634) (xy 415.114486 -159.725106)
			(xy 415.130234 -159.709612) (xy 415.134298 -159.699198) (xy 415.144978 -159.672415) (xy 415.173267 -159.622172)
			(xy 415.208799 -159.576762) (xy 415.250763 -159.537219) (xy 415.298203 -159.504446) (xy 415.350036 -159.479189)
			(xy 415.405082 -159.462026) (xy 415.462084 -159.453346) (xy 415.490914 -159.452818) (xy 415.518166 -159.453253)
			(xy 415.572116 -159.461011) (xy 415.624413 -159.476369) (xy 415.673992 -159.499012) (xy 415.719844 -159.528481)
			(xy 415.761035 -159.564175) (xy 415.796727 -159.605368) (xy 415.826194 -159.65122) (xy 415.848836 -159.7008)
			(xy 415.864192 -159.753097) (xy 415.871948 -159.807048) (xy 415.871948 -159.861552) (xy 415.864192 -159.915503)
			(xy 415.854839 -159.947356) (xy 416.113722 -159.947356) (xy 416.114177 -159.91988) (xy 416.122076 -159.865499)
			(xy 416.137703 -159.812816) (xy 416.160735 -159.762924) (xy 416.190693 -159.716857) (xy 416.208464 -159.695896)
			(xy 416.208718 -159.695642) (xy 416.214295 -159.688549) (xy 416.220547 -159.671637) (xy 416.22091 -159.662622)
			(xy 416.22091 -159.595058) (xy 416.220523 -159.586044) (xy 416.214296 -159.569127) (xy 416.208718 -159.562038)
			(xy 416.20821 -159.56153) (xy 416.190496 -159.540568) (xy 416.16061 -159.49454) (xy 416.13764 -159.444699)
			(xy 416.122061 -159.392077) (xy 416.114195 -159.337764) (xy 416.113722 -159.310324) (xy 416.114208 -159.283073)
			(xy 416.121964 -159.229125) (xy 416.137319 -159.17683) (xy 416.159961 -159.127253) (xy 416.189427 -159.081403)
			(xy 416.225118 -159.040212) (xy 416.266309 -159.004521) (xy 416.312159 -158.975055) (xy 416.361736 -158.952413)
			(xy 416.414031 -158.937058) (xy 416.467979 -158.929302) (xy 416.522481 -158.929302) (xy 416.576429 -158.937058)
			(xy 416.628724 -158.952413) (xy 416.678301 -158.975055) (xy 416.724151 -159.004521) (xy 416.765342 -159.040212)
			(xy 416.801033 -159.081403) (xy 416.830499 -159.127253) (xy 416.853141 -159.17683) (xy 416.868496 -159.229125)
			(xy 416.876252 -159.283073) (xy 416.876738 -159.310324) (xy 416.876256 -159.337799) (xy 416.868362 -159.392178)
			(xy 416.85274 -159.44486) (xy 416.829715 -159.494753) (xy 416.799763 -159.540822) (xy 416.781996 -159.561784)
			(xy 416.781742 -159.562038) (xy 416.776168 -159.569133) (xy 416.769915 -159.586044) (xy 416.76955 -159.595058)
			(xy 416.76955 -159.662622) (xy 416.769885 -159.671641) (xy 416.776147 -159.688559) (xy 416.781742 -159.695642)
			(xy 416.78225 -159.69615) (xy 416.799995 -159.717087) (xy 416.829878 -159.763122) (xy 416.852842 -159.812969)
			(xy 416.868414 -159.865596) (xy 416.87627 -159.919914) (xy 416.876738 -159.947356) (xy 416.876252 -159.974607)
			(xy 416.874619 -159.985964) (xy 417.451538 -159.985964) (xy 417.455609 -159.930342) (xy 417.467735 -159.875905)
			(xy 417.487658 -159.823814) (xy 417.514954 -159.775179) (xy 417.54904 -159.731036) (xy 417.589189 -159.692327)
			(xy 417.634547 -159.659876) (xy 417.684147 -159.634375) (xy 417.736931 -159.616368) (xy 417.791774 -159.606238)
			(xy 417.847508 -159.604201) (xy 417.902945 -159.610301) (xy 417.956902 -159.624407) (xy 418.008231 -159.646219)
			(xy 418.055837 -159.675273) (xy 418.098705 -159.710948) (xy 418.135922 -159.752485) (xy 418.166695 -159.798998)
			(xy 418.190367 -159.849495) (xy 418.206435 -159.902902) (xy 418.214555 -159.958078) (xy 418.215064 -159.985964)
			(xy 418.214555 -160.01385) (xy 418.206435 -160.069026) (xy 418.190367 -160.122433) (xy 418.166695 -160.17293)
			(xy 418.135922 -160.219443) (xy 418.098705 -160.26098) (xy 418.055837 -160.296655) (xy 418.008231 -160.325709)
			(xy 417.956902 -160.347521) (xy 417.902945 -160.361627) (xy 417.847508 -160.367727) (xy 417.791774 -160.36569)
			(xy 417.736931 -160.35556) (xy 417.684147 -160.337553) (xy 417.634547 -160.312052) (xy 417.589189 -160.279601)
			(xy 417.54904 -160.240892) (xy 417.514954 -160.196749) (xy 417.487658 -160.148114) (xy 417.467735 -160.096023)
			(xy 417.455609 -160.041586) (xy 417.451538 -159.985964) (xy 416.874619 -159.985964) (xy 416.868496 -160.028555)
			(xy 416.853141 -160.08085) (xy 416.830499 -160.130427) (xy 416.801033 -160.176277) (xy 416.765342 -160.217468)
			(xy 416.724151 -160.253159) (xy 416.678301 -160.282625) (xy 416.628724 -160.305267) (xy 416.576429 -160.320622)
			(xy 416.522481 -160.328378) (xy 416.467979 -160.328378) (xy 416.414031 -160.320622) (xy 416.361736 -160.305267)
			(xy 416.312159 -160.282625) (xy 416.266309 -160.253159) (xy 416.225118 -160.217468) (xy 416.189427 -160.176277)
			(xy 416.159961 -160.130427) (xy 416.137319 -160.08085) (xy 416.121964 -160.028555) (xy 416.114208 -159.974607)
			(xy 416.113722 -159.947356) (xy 415.854839 -159.947356) (xy 415.848836 -159.9678) (xy 415.826194 -160.01738)
			(xy 415.796727 -160.063232) (xy 415.761035 -160.104425) (xy 415.719844 -160.140119) (xy 415.673992 -160.169588)
			(xy 415.624413 -160.192231) (xy 415.572116 -160.207589) (xy 415.518166 -160.215347) (xy 415.490914 -160.215834)
			(xy 415.49066 -160.215834) (xy 415.465456 -160.215456) (xy 415.415487 -160.20881) (xy 415.366832 -160.195628)
			(xy 415.320343 -160.176139) (xy 415.298382 -160.163764) (xy 415.288476 -160.157922) (xy 415.266632 -160.15589)
			(xy 415.17189 -160.189418) (xy 415.156142 -160.204912) (xy 415.152078 -160.215326) (xy 415.141347 -160.242087)
			(xy 415.113063 -160.292327) (xy 415.077537 -160.337735) (xy 415.03558 -160.377277) (xy 414.988148 -160.410052)
			(xy 414.936322 -160.435313) (xy 414.881285 -160.452484) (xy 414.824289 -160.461173) (xy 414.795462 -160.461706)
			(xy 414.76821 -160.461258) (xy 414.714261 -160.453496) (xy 414.661965 -160.438136) (xy 414.612388 -160.41549)
			(xy 414.566537 -160.38602) (xy 414.525347 -160.350324) (xy 414.489656 -160.309131) (xy 414.460191 -160.263277)
			(xy 414.43755 -160.213697) (xy 414.422196 -160.1614) (xy 414.41444 -160.10745) (xy 414.413954 -160.080198)
			(xy 414.414622 -160.048636) (xy 414.425005 -159.98637) (xy 414.445487 -159.926661) (xy 414.459928 -159.898588)
			(xy 414.464754 -159.889698) (xy 414.466786 -159.87014) (xy 414.443926 -159.791654) (xy 414.440723 -159.782215)
			(xy 414.428281 -159.766662) (xy 414.419796 -159.761428) (xy 414.394678 -159.746907) (xy 414.348796 -159.711399)
			(xy 414.308822 -159.66935) (xy 414.275679 -159.621732) (xy 414.250131 -159.569642) (xy 414.232768 -159.514284)
			(xy 414.223991 -159.456935) (xy 414.223454 -159.427926) (xy 413.538924 -159.427926) (xy 413.538924 -160.469072)
			(xy 413.539358 -160.47914) (xy 413.547072 -160.497739) (xy 413.55391 -160.50514) (xy 413.930084 -160.881314)
			(xy 416.872418 -160.881314) (xy 416.876489 -160.825692) (xy 416.888615 -160.771255) (xy 416.908538 -160.719164)
			(xy 416.935834 -160.670529) (xy 416.96992 -160.626386) (xy 417.010069 -160.587677) (xy 417.055427 -160.555226)
			(xy 417.105027 -160.529725) (xy 417.157811 -160.511718) (xy 417.212654 -160.501588) (xy 417.268388 -160.499551)
			(xy 417.323825 -160.505651) (xy 417.377782 -160.519757) (xy 417.429111 -160.541569) (xy 417.476717 -160.570623)
			(xy 417.519585 -160.606298) (xy 417.556802 -160.647835) (xy 417.587575 -160.694348) (xy 417.611247 -160.744845)
			(xy 417.627315 -160.798252) (xy 417.635435 -160.853428) (xy 417.635944 -160.881314) (xy 417.635435 -160.9092)
			(xy 417.627315 -160.964376) (xy 417.611247 -161.017783) (xy 417.587575 -161.06828) (xy 417.556802 -161.114793)
			(xy 417.519585 -161.15633) (xy 417.476717 -161.192005) (xy 417.429111 -161.221059) (xy 417.377782 -161.242871)
			(xy 417.323825 -161.256977) (xy 417.268388 -161.263077) (xy 417.212654 -161.26104) (xy 417.157811 -161.25091)
			(xy 417.105027 -161.232903) (xy 417.055427 -161.207402) (xy 417.010069 -161.174951) (xy 416.96992 -161.136242)
			(xy 416.935834 -161.092099) (xy 416.908538 -161.043464) (xy 416.888615 -160.991373) (xy 416.876489 -160.936936)
			(xy 416.872418 -160.881314) (xy 413.930084 -160.881314) (xy 414.404302 -161.355532) (xy 414.411149 -161.362927)
			(xy 414.418865 -161.38153) (xy 414.419288 -161.3916) (xy 414.419288 -162.758374) (xy 417.83127 -162.758374)
			(xy 417.831752 -162.730463) (xy 417.83989 -162.675237) (xy 417.855988 -162.621786) (xy 417.879703 -162.571252)
			(xy 417.910529 -162.524712) (xy 417.928806 -162.503612) (xy 417.934699 -162.496432) (xy 417.941352 -162.479109)
			(xy 417.94176 -162.46983) (xy 417.94176 -162.392106) (xy 417.935156 -162.374834) (xy 417.928806 -162.367722)
			(xy 417.910518 -162.346631) (xy 417.879692 -162.30009) (xy 417.855978 -162.249554) (xy 417.839884 -162.1961)
			(xy 417.831753 -162.140872) (xy 417.83127 -162.11296) (xy 417.831756 -162.085709) (xy 417.839512 -162.031761)
			(xy 417.854867 -161.979466) (xy 417.877509 -161.929889) (xy 417.906975 -161.884039) (xy 417.942666 -161.842848)
			(xy 417.983857 -161.807157) (xy 418.029707 -161.777691) (xy 418.079284 -161.755049) (xy 418.131579 -161.739694)
			(xy 418.185527 -161.731938) (xy 418.240029 -161.731938) (xy 418.293977 -161.739694) (xy 418.346272 -161.755049)
			(xy 418.395849 -161.777691) (xy 418.441699 -161.807157) (xy 418.48289 -161.842848) (xy 418.518581 -161.884039)
			(xy 418.548047 -161.929889) (xy 418.570689 -161.979466) (xy 418.586044 -162.031761) (xy 418.5938 -162.085709)
			(xy 418.594286 -162.11296) (xy 418.59381 -162.140871) (xy 418.585669 -162.196097) (xy 418.569568 -162.249547)
			(xy 418.545852 -162.300082) (xy 418.515027 -162.346621) (xy 418.49675 -162.367722) (xy 418.490838 -162.374888)
			(xy 418.484197 -162.392222) (xy 418.483796 -162.401504) (xy 418.483796 -162.479228) (xy 418.4904 -162.4965)
			(xy 418.49675 -162.503612) (xy 418.515016 -162.524721) (xy 418.545843 -162.571258) (xy 418.56956 -162.62179)
			(xy 418.58566 -162.675239) (xy 418.593798 -162.730464) (xy 418.594286 -162.758374) (xy 418.5938 -162.785625)
			(xy 418.586044 -162.839573) (xy 418.570689 -162.891868) (xy 418.548047 -162.941445) (xy 418.518581 -162.987295)
			(xy 418.48289 -163.028486) (xy 418.441699 -163.064177) (xy 418.395849 -163.093643) (xy 418.346272 -163.116285)
			(xy 418.293977 -163.13164) (xy 418.240029 -163.139396) (xy 418.185527 -163.139396) (xy 418.131579 -163.13164)
			(xy 418.079284 -163.116285) (xy 418.029707 -163.093643) (xy 417.983857 -163.064177) (xy 417.942666 -163.028486)
			(xy 417.906975 -162.987295) (xy 417.877509 -162.941445) (xy 417.854867 -162.891868) (xy 417.839512 -162.839573)
			(xy 417.831756 -162.785625) (xy 417.83127 -162.758374) (xy 414.419288 -162.758374) (xy 414.419288 -163.56203)
			(xy 414.419145 -163.56692) (xy 414.417231 -163.576513) (xy 414.415478 -163.58108) (xy 414.37433 -163.682934)
			(xy 414.372192 -163.687838) (xy 414.366176 -163.696679) (xy 414.362392 -163.70046) (xy 414.323276 -163.738052)
			(xy 414.320736 -163.740592) (xy 414.283144 -163.779708) (xy 414.279331 -163.783454) (xy 414.270504 -163.789478)
			(xy 414.265618 -163.791646) (xy 414.163764 -163.832794) (xy 414.159201 -163.83456) (xy 414.149605 -163.836471)
			(xy 414.144714 -163.836604) (xy 409.610306 -163.836604) (xy 409.585034 -163.836041) (xy 409.53512 -163.828066)
			(xy 409.487066 -163.812389) (xy 409.442052 -163.789395) (xy 409.401184 -163.75965) (xy 409.382976 -163.742116)
			(xy 409.335986 -163.695126) (xy 409.335478 -163.694618) (xy 409.296616 -163.65728) (xy 409.29286 -163.653476)
			(xy 409.286842 -163.644642) (xy 409.284678 -163.639754) (xy 409.24353 -163.5379) (xy 409.241775 -163.533333)
			(xy 409.239857 -163.523741) (xy 409.23972 -163.51885) (xy 409.23972 -162.730434) (xy 409.239298 -162.720364)
			(xy 409.231577 -162.701765) (xy 409.224734 -162.694366) (xy 409.019756 -162.489134) (xy 409.012361 -162.482287)
			(xy 408.993758 -162.47457) (xy 408.983688 -162.474148) (xy 405.538686 -162.474148) (xy 405.528614 -162.474553)
			(xy 405.510016 -162.482287) (xy 405.502618 -162.489134) (xy 405.267922 -162.724084) (xy 405.261099 -162.731498)
			(xy 405.253369 -162.750086) (xy 405.252936 -162.760152) (xy 405.252936 -164.253926) (xy 405.841454 -164.253926)
			(xy 405.84194 -164.226675) (xy 405.849696 -164.172727) (xy 405.865051 -164.120432) (xy 405.887693 -164.070855)
			(xy 405.917159 -164.025005) (xy 405.95285 -163.983814) (xy 405.994041 -163.948123) (xy 406.039891 -163.918657)
			(xy 406.089468 -163.896015) (xy 406.141763 -163.88066) (xy 406.195711 -163.872904) (xy 406.250213 -163.872904)
			(xy 406.304161 -163.88066) (xy 406.356456 -163.896015) (xy 406.406033 -163.918657) (xy 406.451883 -163.948123)
			(xy 406.493074 -163.983814) (xy 406.528765 -164.025005) (xy 406.558231 -164.070855) (xy 406.580873 -164.120432)
			(xy 406.596228 -164.172727) (xy 406.603984 -164.226675) (xy 406.60447 -164.253926) (xy 406.603809 -164.285489)
			(xy 406.593423 -164.347754) (xy 406.572937 -164.407463) (xy 406.558496 -164.435536) (xy 406.55367 -164.444426)
			(xy 406.551638 -164.463984) (xy 406.574498 -164.54247) (xy 406.577759 -164.551885) (xy 406.59016 -164.567449)
			(xy 406.598628 -164.572696) (xy 406.605994 -164.57676) (xy 406.6159 -164.582602) (xy 406.637744 -164.584634)
			(xy 406.732486 -164.551106) (xy 406.748234 -164.535612) (xy 406.752298 -164.525198) (xy 406.762978 -164.498415)
			(xy 406.791267 -164.448172) (xy 406.826799 -164.402762) (xy 406.868763 -164.363219) (xy 406.916203 -164.330446)
			(xy 406.968036 -164.305189) (xy 407.023082 -164.288026) (xy 407.080084 -164.279346) (xy 407.108914 -164.278818)
			(xy 407.136166 -164.279253) (xy 407.190116 -164.287011) (xy 407.242413 -164.302369) (xy 407.291992 -164.325012)
			(xy 407.337844 -164.354481) (xy 407.379035 -164.390175) (xy 407.414727 -164.431368) (xy 407.444194 -164.47722)
			(xy 407.466836 -164.5268) (xy 407.482192 -164.579097) (xy 407.489948 -164.633048) (xy 407.489948 -164.687552)
			(xy 407.482192 -164.741503) (xy 407.472839 -164.773356) (xy 407.731722 -164.773356) (xy 407.732177 -164.74588)
			(xy 407.740076 -164.691499) (xy 407.755703 -164.638816) (xy 407.778735 -164.588924) (xy 407.808693 -164.542857)
			(xy 407.826464 -164.521896) (xy 407.826718 -164.521642) (xy 407.832295 -164.514549) (xy 407.838547 -164.497637)
			(xy 407.83891 -164.488622) (xy 407.83891 -164.421058) (xy 407.838523 -164.412044) (xy 407.832296 -164.395127)
			(xy 407.826718 -164.388038) (xy 407.82621 -164.38753) (xy 407.808496 -164.366568) (xy 407.77861 -164.32054)
			(xy 407.75564 -164.270699) (xy 407.740061 -164.218077) (xy 407.732195 -164.163764) (xy 407.731722 -164.136324)
			(xy 407.732208 -164.109073) (xy 407.739964 -164.055125) (xy 407.755319 -164.00283) (xy 407.777961 -163.953253)
			(xy 407.807427 -163.907403) (xy 407.843118 -163.866212) (xy 407.884309 -163.830521) (xy 407.930159 -163.801055)
			(xy 407.979736 -163.778413) (xy 408.032031 -163.763058) (xy 408.085979 -163.755302) (xy 408.140481 -163.755302)
			(xy 408.194429 -163.763058) (xy 408.246724 -163.778413) (xy 408.296301 -163.801055) (xy 408.342151 -163.830521)
			(xy 408.383342 -163.866212) (xy 408.419033 -163.907403) (xy 408.448499 -163.953253) (xy 408.471141 -164.00283)
			(xy 408.486496 -164.055125) (xy 408.494252 -164.109073) (xy 408.494738 -164.136324) (xy 408.494256 -164.163799)
			(xy 408.486362 -164.218178) (xy 408.47074 -164.27086) (xy 408.447715 -164.320753) (xy 408.417763 -164.366822)
			(xy 408.399996 -164.387784) (xy 408.399742 -164.388038) (xy 408.394168 -164.395133) (xy 408.387915 -164.412044)
			(xy 408.38755 -164.421058) (xy 408.38755 -164.488622) (xy 408.387885 -164.497641) (xy 408.394147 -164.514559)
			(xy 408.399742 -164.521642) (xy 408.40025 -164.52215) (xy 408.417995 -164.543087) (xy 408.447878 -164.589122)
			(xy 408.470842 -164.638969) (xy 408.486414 -164.691596) (xy 408.49427 -164.745914) (xy 408.494738 -164.773356)
			(xy 408.494252 -164.800607) (xy 408.492619 -164.811964) (xy 409.069538 -164.811964) (xy 409.073609 -164.756342)
			(xy 409.085735 -164.701905) (xy 409.105658 -164.649814) (xy 409.132954 -164.601179) (xy 409.16704 -164.557036)
			(xy 409.207189 -164.518327) (xy 409.252547 -164.485876) (xy 409.302147 -164.460375) (xy 409.354931 -164.442368)
			(xy 409.409774 -164.432238) (xy 409.465508 -164.430201) (xy 409.520945 -164.436301) (xy 409.574902 -164.450407)
			(xy 409.626231 -164.472219) (xy 409.673837 -164.501273) (xy 409.716705 -164.536948) (xy 409.753922 -164.578485)
			(xy 409.784695 -164.624998) (xy 409.808367 -164.675495) (xy 409.824435 -164.728902) (xy 409.832555 -164.784078)
			(xy 409.833064 -164.811964) (xy 409.832555 -164.83985) (xy 409.824435 -164.895026) (xy 409.808367 -164.948433)
			(xy 409.784695 -164.99893) (xy 409.753922 -165.045443) (xy 409.716705 -165.08698) (xy 409.673837 -165.122655)
			(xy 409.626231 -165.151709) (xy 409.574902 -165.173521) (xy 409.520945 -165.187627) (xy 409.465508 -165.193727)
			(xy 409.409774 -165.19169) (xy 409.354931 -165.18156) (xy 409.302147 -165.163553) (xy 409.252547 -165.138052)
			(xy 409.207189 -165.105601) (xy 409.16704 -165.066892) (xy 409.132954 -165.022749) (xy 409.105658 -164.974114)
			(xy 409.085735 -164.922023) (xy 409.073609 -164.867586) (xy 409.069538 -164.811964) (xy 408.492619 -164.811964)
			(xy 408.486496 -164.854555) (xy 408.471141 -164.90685) (xy 408.448499 -164.956427) (xy 408.419033 -165.002277)
			(xy 408.383342 -165.043468) (xy 408.342151 -165.079159) (xy 408.296301 -165.108625) (xy 408.246724 -165.131267)
			(xy 408.194429 -165.146622) (xy 408.140481 -165.154378) (xy 408.085979 -165.154378) (xy 408.032031 -165.146622)
			(xy 407.979736 -165.131267) (xy 407.930159 -165.108625) (xy 407.884309 -165.079159) (xy 407.843118 -165.043468)
			(xy 407.807427 -165.002277) (xy 407.777961 -164.956427) (xy 407.755319 -164.90685) (xy 407.739964 -164.854555)
			(xy 407.732208 -164.800607) (xy 407.731722 -164.773356) (xy 407.472839 -164.773356) (xy 407.466836 -164.7938)
			(xy 407.444194 -164.84338) (xy 407.414727 -164.889232) (xy 407.379035 -164.930425) (xy 407.337844 -164.966119)
			(xy 407.291992 -164.995588) (xy 407.242413 -165.018231) (xy 407.190116 -165.033589) (xy 407.136166 -165.041347)
			(xy 407.108914 -165.041834) (xy 407.10866 -165.041834) (xy 407.083456 -165.041456) (xy 407.033487 -165.03481)
			(xy 406.984832 -165.021628) (xy 406.938343 -165.002139) (xy 406.916382 -164.989764) (xy 406.906476 -164.983922)
			(xy 406.884632 -164.98189) (xy 406.78989 -165.015418) (xy 406.774142 -165.030912) (xy 406.770078 -165.041326)
			(xy 406.759347 -165.068087) (xy 406.731063 -165.118327) (xy 406.695537 -165.163735) (xy 406.65358 -165.203277)
			(xy 406.606148 -165.236052) (xy 406.554322 -165.261313) (xy 406.499285 -165.278484) (xy 406.442289 -165.287173)
			(xy 406.413462 -165.287706) (xy 406.38621 -165.287258) (xy 406.332261 -165.279496) (xy 406.279965 -165.264136)
			(xy 406.230388 -165.24149) (xy 406.184537 -165.21202) (xy 406.143347 -165.176324) (xy 406.107656 -165.135131)
			(xy 406.078191 -165.089277) (xy 406.05555 -165.039697) (xy 406.040196 -164.9874) (xy 406.03244 -164.93345)
			(xy 406.031954 -164.906198) (xy 406.032622 -164.874636) (xy 406.043005 -164.81237) (xy 406.063487 -164.752661)
			(xy 406.077928 -164.724588) (xy 406.082754 -164.715698) (xy 406.084786 -164.69614) (xy 406.061926 -164.617654)
			(xy 406.058723 -164.608215) (xy 406.046281 -164.592662) (xy 406.037796 -164.587428) (xy 406.012678 -164.572907)
			(xy 405.966796 -164.537399) (xy 405.926822 -164.49535) (xy 405.893679 -164.447732) (xy 405.868131 -164.395642)
			(xy 405.850768 -164.340284) (xy 405.841991 -164.282935) (xy 405.841454 -164.253926) (xy 405.252936 -164.253926)
			(xy 405.252936 -165.466776) (xy 405.253365 -165.476845) (xy 405.261082 -165.495443) (xy 405.267922 -165.502844)
			(xy 405.472392 -165.707314) (xy 408.490418 -165.707314) (xy 408.494489 -165.651692) (xy 408.506615 -165.597255)
			(xy 408.526538 -165.545164) (xy 408.553834 -165.496529) (xy 408.58792 -165.452386) (xy 408.628069 -165.413677)
			(xy 408.673427 -165.381226) (xy 408.723027 -165.355725) (xy 408.775811 -165.337718) (xy 408.830654 -165.327588)
			(xy 408.886388 -165.325551) (xy 408.941825 -165.331651) (xy 408.995782 -165.345757) (xy 409.047111 -165.367569)
			(xy 409.094717 -165.396623) (xy 409.137585 -165.432298) (xy 409.174802 -165.473835) (xy 409.205575 -165.520348)
			(xy 409.229247 -165.570845) (xy 409.245315 -165.624252) (xy 409.253435 -165.679428) (xy 409.253944 -165.707314)
			(xy 409.253435 -165.7352) (xy 409.245315 -165.790376) (xy 409.229247 -165.843783) (xy 409.205575 -165.89428)
			(xy 409.174802 -165.940793) (xy 409.137585 -165.98233) (xy 409.094717 -166.018005) (xy 409.047111 -166.047059)
			(xy 408.995782 -166.068871) (xy 408.941825 -166.082977) (xy 408.886388 -166.089077) (xy 408.830654 -166.08704)
			(xy 408.775811 -166.07691) (xy 408.723027 -166.058903) (xy 408.673427 -166.033402) (xy 408.628069 -166.000951)
			(xy 408.58792 -165.962242) (xy 408.553834 -165.918099) (xy 408.526538 -165.869464) (xy 408.506615 -165.817373)
			(xy 408.494489 -165.762936) (xy 408.490418 -165.707314) (xy 405.472392 -165.707314) (xy 406.022302 -166.257224)
			(xy 406.029145 -166.264622) (xy 406.036863 -166.283223) (xy 406.037288 -166.293292) (xy 406.037288 -167.584374)
			(xy 409.44927 -167.584374) (xy 409.449752 -167.556463) (xy 409.45789 -167.501237) (xy 409.473988 -167.447786)
			(xy 409.497703 -167.397252) (xy 409.528529 -167.350712) (xy 409.546806 -167.329612) (xy 409.552699 -167.322432)
			(xy 409.559352 -167.305109) (xy 409.55976 -167.29583) (xy 409.55976 -167.218106) (xy 409.553156 -167.200834)
			(xy 409.546806 -167.193722) (xy 409.528518 -167.172631) (xy 409.497692 -167.12609) (xy 409.473978 -167.075554)
			(xy 409.457884 -167.0221) (xy 409.449753 -166.966872) (xy 409.44927 -166.93896) (xy 409.449756 -166.911709)
			(xy 409.457512 -166.857761) (xy 409.472867 -166.805466) (xy 409.495509 -166.755889) (xy 409.524975 -166.710039)
			(xy 409.560666 -166.668848) (xy 409.601857 -166.633157) (xy 409.647707 -166.603691) (xy 409.697284 -166.581049)
			(xy 409.749579 -166.565694) (xy 409.803527 -166.557938) (xy 409.858029 -166.557938) (xy 409.911977 -166.565694)
			(xy 409.964272 -166.581049) (xy 410.013849 -166.603691) (xy 410.059699 -166.633157) (xy 410.10089 -166.668848)
			(xy 410.136581 -166.710039) (xy 410.166047 -166.755889) (xy 410.188689 -166.805466) (xy 410.204044 -166.857761)
			(xy 410.2118 -166.911709) (xy 410.212286 -166.93896) (xy 410.21181 -166.966871) (xy 410.203669 -167.022097)
			(xy 410.187568 -167.075547) (xy 410.163852 -167.126082) (xy 410.133027 -167.172621) (xy 410.11475 -167.193722)
			(xy 410.108838 -167.200888) (xy 410.102197 -167.218222) (xy 410.101796 -167.227504) (xy 410.101796 -167.305228)
			(xy 410.1084 -167.3225) (xy 410.11475 -167.329612) (xy 410.133016 -167.350721) (xy 410.163843 -167.397258)
			(xy 410.18756 -167.44779) (xy 410.20366 -167.501239) (xy 410.211798 -167.556464) (xy 410.212286 -167.584374)
			(xy 410.2118 -167.611625) (xy 410.204044 -167.665573) (xy 410.188689 -167.717868) (xy 410.166047 -167.767445)
			(xy 410.136581 -167.813295) (xy 410.10089 -167.854486) (xy 410.059699 -167.890177) (xy 410.013849 -167.919643)
			(xy 409.964272 -167.942285) (xy 409.911977 -167.95764) (xy 409.858029 -167.965396) (xy 409.803527 -167.965396)
			(xy 409.749579 -167.95764) (xy 409.697284 -167.942285) (xy 409.647707 -167.919643) (xy 409.601857 -167.890177)
			(xy 409.560666 -167.854486) (xy 409.524975 -167.813295) (xy 409.495509 -167.767445) (xy 409.472867 -167.717868)
			(xy 409.457512 -167.665573) (xy 409.449756 -167.611625) (xy 409.44927 -167.584374) (xy 406.037288 -167.584374)
			(xy 406.037288 -168.263316) (xy 406.036783 -168.288584) (xy 406.028876 -168.338497) (xy 406.013258 -168.386559)
			(xy 405.990315 -168.431586) (xy 405.960611 -168.472471) (xy 405.924877 -168.508205) (xy 405.883993 -168.537911)
			(xy 405.838966 -168.560855) (xy 405.790905 -168.576474) (xy 405.740992 -168.584382) (xy 405.715724 -168.58488)
			(xy 404.17623 -168.58488) (xy 404.169506 -168.58511) (xy 404.156513 -168.588575) (xy 404.150576 -168.591738)
			(xy 404.125806 -168.605503) (xy 404.072633 -168.625083) (xy 404.016855 -168.635055) (xy 403.988524 -168.63568)
			(xy 403.929088 -168.63568) (xy 403.929088 -168.637204) (xy 400.841464 -168.637204) (xy 400.836574 -168.637346)
			(xy 400.826981 -168.639261) (xy 400.822414 -168.641014) (xy 400.804634 -168.648126) (xy 400.800065 -168.649874)
			(xy 400.790474 -168.651796) (xy 400.785584 -168.651936) (xy 399.12925 -168.651936) (xy 399.119182 -168.652378)
			(xy 399.100584 -168.660086) (xy 399.093182 -168.666922) (xy 396.75943 -171.000928) (xy 396.75259 -171.008328)
			(xy 396.744869 -171.026927) (xy 396.744444 -171.036996) (xy 396.744444 -172.831252) (xy 397.517874 -172.831252)
			(xy 397.51836 -172.804001) (xy 397.526116 -172.750053) (xy 397.541471 -172.697758) (xy 397.564113 -172.648181)
			(xy 397.593579 -172.602331) (xy 397.62927 -172.56114) (xy 397.670461 -172.525449) (xy 397.716311 -172.495983)
			(xy 397.765888 -172.473341) (xy 397.818183 -172.457986) (xy 397.872131 -172.45023) (xy 397.926633 -172.45023)
			(xy 397.980581 -172.457986) (xy 398.032876 -172.473341) (xy 398.082453 -172.495983) (xy 398.128303 -172.525449)
			(xy 398.169494 -172.56114) (xy 398.205185 -172.602331) (xy 398.234651 -172.648181) (xy 398.257293 -172.697758)
			(xy 398.272648 -172.750053) (xy 398.280404 -172.804001) (xy 398.28089 -172.831252) (xy 398.280237 -172.862815)
			(xy 398.269847 -172.925081) (xy 398.249359 -172.98479) (xy 398.234916 -173.012862) (xy 398.23009 -173.021752)
			(xy 398.228058 -173.04131) (xy 398.250918 -173.119796) (xy 398.254161 -173.129218) (xy 398.266575 -173.144779)
			(xy 398.275048 -173.150022) (xy 398.282414 -173.154086) (xy 398.29232 -173.159928) (xy 398.314164 -173.16196)
			(xy 398.408906 -173.128432) (xy 398.424654 -173.112938) (xy 398.428718 -173.102524) (xy 398.439395 -173.075739)
			(xy 398.467683 -173.025495) (xy 398.503214 -172.980083) (xy 398.545179 -172.94054) (xy 398.592619 -172.907766)
			(xy 398.644454 -172.88251) (xy 398.6995 -172.865348) (xy 398.756504 -172.85667) (xy 398.785334 -172.856144)
			(xy 398.81258 -172.856728) (xy 398.866517 -172.864488) (xy 398.918801 -172.879844) (xy 398.968368 -172.902484)
			(xy 399.014208 -172.931948) (xy 399.055389 -172.967635) (xy 399.091073 -173.008819) (xy 399.120532 -173.054662)
			(xy 399.143168 -173.10423) (xy 399.158519 -173.156516) (xy 399.166274 -173.210454) (xy 399.166274 -173.264946)
			(xy 399.158519 -173.318884) (xy 399.149183 -173.350682) (xy 399.408142 -173.350682) (xy 399.408607 -173.323206)
			(xy 399.416503 -173.268826) (xy 399.432127 -173.216143) (xy 399.455157 -173.16625) (xy 399.485114 -173.120183)
			(xy 399.502884 -173.099222) (xy 399.503138 -173.098968) (xy 399.508706 -173.091869) (xy 399.514963 -173.074962)
			(xy 399.51533 -173.065948) (xy 399.51533 -172.998384) (xy 399.514974 -172.989367) (xy 399.508725 -172.97245)
			(xy 399.503138 -172.965364) (xy 399.50263 -172.964856) (xy 399.484884 -172.943919) (xy 399.455003 -172.897884)
			(xy 399.432038 -172.848037) (xy 399.416467 -172.795409) (xy 399.40861 -172.741092) (xy 399.408142 -172.71365)
			(xy 399.408628 -172.686399) (xy 399.416384 -172.632451) (xy 399.431739 -172.580156) (xy 399.454381 -172.530579)
			(xy 399.483847 -172.484729) (xy 399.519538 -172.443538) (xy 399.560729 -172.407847) (xy 399.606579 -172.378381)
			(xy 399.656156 -172.355739) (xy 399.708451 -172.340384) (xy 399.762399 -172.332628) (xy 399.816901 -172.332628)
			(xy 399.870849 -172.340384) (xy 399.923144 -172.355739) (xy 399.972721 -172.378381) (xy 400.018571 -172.407847)
			(xy 400.059762 -172.443538) (xy 400.095453 -172.484729) (xy 400.124919 -172.530579) (xy 400.147561 -172.580156)
			(xy 400.162916 -172.632451) (xy 400.170672 -172.686399) (xy 400.171158 -172.71365) (xy 400.170711 -172.741126)
			(xy 400.162811 -172.795508) (xy 400.147183 -172.848191) (xy 400.124149 -172.898083) (xy 400.094188 -172.94415)
			(xy 400.076416 -172.96511) (xy 400.076162 -172.965364) (xy 400.07058 -172.972454) (xy 400.064332 -172.989368)
			(xy 400.06397 -172.998384) (xy 400.06397 -173.065948) (xy 400.064358 -173.074962) (xy 400.070585 -173.091878)
			(xy 400.076162 -173.098968) (xy 400.07667 -173.099476) (xy 400.094384 -173.120438) (xy 400.12427 -173.166466)
			(xy 400.147241 -173.216307) (xy 400.16282 -173.268929) (xy 400.170685 -173.323242) (xy 400.171158 -173.350682)
			(xy 400.170672 -173.377933) (xy 400.169039 -173.38929) (xy 400.745958 -173.38929) (xy 400.750029 -173.333668)
			(xy 400.762155 -173.279231) (xy 400.782078 -173.22714) (xy 400.809374 -173.178505) (xy 400.84346 -173.134362)
			(xy 400.883609 -173.095653) (xy 400.928967 -173.063202) (xy 400.978567 -173.037701) (xy 401.031351 -173.019694)
			(xy 401.086194 -173.009564) (xy 401.141928 -173.007527) (xy 401.197365 -173.013627) (xy 401.251322 -173.027733)
			(xy 401.302651 -173.049545) (xy 401.350257 -173.078599) (xy 401.393125 -173.114274) (xy 401.430342 -173.155811)
			(xy 401.461115 -173.202324) (xy 401.484787 -173.252821) (xy 401.500855 -173.306228) (xy 401.508975 -173.361404)
			(xy 401.509484 -173.38929) (xy 401.508975 -173.417176) (xy 401.500855 -173.472352) (xy 401.484787 -173.525759)
			(xy 401.461115 -173.576256) (xy 401.430342 -173.622769) (xy 401.393125 -173.664306) (xy 401.350257 -173.699981)
			(xy 401.302651 -173.729035) (xy 401.251322 -173.750847) (xy 401.197365 -173.764953) (xy 401.141928 -173.771053)
			(xy 401.086194 -173.769016) (xy 401.031351 -173.758886) (xy 400.978567 -173.740879) (xy 400.928967 -173.715378)
			(xy 400.883609 -173.682927) (xy 400.84346 -173.644218) (xy 400.809374 -173.600075) (xy 400.782078 -173.55144)
			(xy 400.762155 -173.499349) (xy 400.750029 -173.444912) (xy 400.745958 -173.38929) (xy 400.169039 -173.38929)
			(xy 400.162916 -173.431881) (xy 400.147561 -173.484176) (xy 400.124919 -173.533753) (xy 400.095453 -173.579603)
			(xy 400.059762 -173.620794) (xy 400.018571 -173.656485) (xy 399.972721 -173.685951) (xy 399.923144 -173.708593)
			(xy 399.870849 -173.723948) (xy 399.816901 -173.731704) (xy 399.762399 -173.731704) (xy 399.708451 -173.723948)
			(xy 399.656156 -173.708593) (xy 399.606579 -173.685951) (xy 399.560729 -173.656485) (xy 399.519538 -173.620794)
			(xy 399.483847 -173.579603) (xy 399.454381 -173.533753) (xy 399.431739 -173.484176) (xy 399.416384 -173.431881)
			(xy 399.408628 -173.377933) (xy 399.408142 -173.350682) (xy 399.149183 -173.350682) (xy 399.143168 -173.37117)
			(xy 399.120532 -173.420738) (xy 399.091073 -173.466581) (xy 399.055389 -173.507765) (xy 399.014208 -173.543452)
			(xy 398.968368 -173.572916) (xy 398.918801 -173.595556) (xy 398.866517 -173.610912) (xy 398.81258 -173.618672)
			(xy 398.785334 -173.61916) (xy 398.78508 -173.61916) (xy 398.759876 -173.618769) (xy 398.709908 -173.612127)
			(xy 398.661253 -173.598948) (xy 398.614764 -173.579463) (xy 398.592802 -173.56709) (xy 398.582896 -173.561248)
			(xy 398.561052 -173.559216) (xy 398.46631 -173.592744) (xy 398.450562 -173.608238) (xy 398.446498 -173.618652)
			(xy 398.435848 -173.645448) (xy 398.407552 -173.695689) (xy 398.372015 -173.741098) (xy 398.330046 -173.780638)
			(xy 398.282602 -173.813409) (xy 398.230765 -173.838664) (xy 398.175717 -173.855826) (xy 398.118713 -173.864505)
			(xy 398.089882 -173.865032) (xy 398.062631 -173.864539) (xy 398.008685 -173.856781) (xy 397.956392 -173.841424)
			(xy 397.906816 -173.818783) (xy 397.860967 -173.789317) (xy 397.819778 -173.753626) (xy 397.784087 -173.712438)
			(xy 397.75462 -173.666589) (xy 397.731978 -173.617014) (xy 397.716621 -173.564721) (xy 397.708861 -173.510775)
			(xy 397.708374 -173.483524) (xy 397.709022 -173.451961) (xy 397.719415 -173.389695) (xy 397.739905 -173.329986)
			(xy 397.754348 -173.301914) (xy 397.759174 -173.293024) (xy 397.761206 -173.273466) (xy 397.738346 -173.19498)
			(xy 397.735125 -173.185548) (xy 397.722696 -173.169992) (xy 397.714216 -173.164754) (xy 397.689114 -173.150207)
			(xy 397.643231 -173.114704) (xy 397.603256 -173.07266) (xy 397.57011 -173.025046) (xy 397.544559 -172.972961)
			(xy 397.527193 -172.917606) (xy 397.518413 -172.860259) (xy 397.517874 -172.831252) (xy 396.744444 -172.831252)
			(xy 396.744444 -173.790864) (xy 396.744877 -173.800933) (xy 396.752591 -173.819531) (xy 396.75943 -173.826932)
			(xy 397.217138 -174.28464) (xy 400.166838 -174.28464) (xy 400.170909 -174.229018) (xy 400.183035 -174.174581)
			(xy 400.202958 -174.12249) (xy 400.230254 -174.073855) (xy 400.26434 -174.029712) (xy 400.304489 -173.991003)
			(xy 400.349847 -173.958552) (xy 400.399447 -173.933051) (xy 400.452231 -173.915044) (xy 400.507074 -173.904914)
			(xy 400.562808 -173.902877) (xy 400.618245 -173.908977) (xy 400.672202 -173.923083) (xy 400.723531 -173.944895)
			(xy 400.771137 -173.973949) (xy 400.814005 -174.009624) (xy 400.851222 -174.051161) (xy 400.881995 -174.097674)
			(xy 400.905667 -174.148171) (xy 400.921735 -174.201578) (xy 400.929855 -174.256754) (xy 400.930364 -174.28464)
			(xy 400.929855 -174.312526) (xy 400.921735 -174.367702) (xy 400.905667 -174.421109) (xy 400.881995 -174.471606)
			(xy 400.851222 -174.518119) (xy 400.814005 -174.559656) (xy 400.771137 -174.595331) (xy 400.723531 -174.624385)
			(xy 400.672202 -174.646197) (xy 400.618245 -174.660303) (xy 400.562808 -174.666403) (xy 400.507074 -174.664366)
			(xy 400.452231 -174.654236) (xy 400.399447 -174.636229) (xy 400.349847 -174.610728) (xy 400.304489 -174.578277)
			(xy 400.26434 -174.539568) (xy 400.230254 -174.495425) (xy 400.202958 -174.44679) (xy 400.183035 -174.394699)
			(xy 400.170909 -174.340262) (xy 400.166838 -174.28464) (xy 397.217138 -174.28464) (xy 397.698722 -174.766224)
			(xy 397.705568 -174.773619) (xy 397.713284 -174.792222) (xy 397.713708 -174.802292) (xy 397.713708 -176.1617)
			(xy 401.12569 -176.1617) (xy 401.126182 -176.133789) (xy 401.134317 -176.078563) (xy 401.150413 -176.025113)
			(xy 401.174125 -175.974578) (xy 401.204949 -175.928038) (xy 401.223226 -175.906938) (xy 401.229153 -175.899782)
			(xy 401.235785 -175.882441) (xy 401.23618 -175.873156) (xy 401.23618 -175.795432) (xy 401.229576 -175.77816)
			(xy 401.223226 -175.771048) (xy 401.204938 -175.749957) (xy 401.174114 -175.703415) (xy 401.150402 -175.652878)
			(xy 401.134308 -175.599425) (xy 401.126175 -175.544198) (xy 401.12569 -175.516286) (xy 401.126176 -175.489035)
			(xy 401.133932 -175.435087) (xy 401.149287 -175.382792) (xy 401.171929 -175.333215) (xy 401.201395 -175.287365)
			(xy 401.237086 -175.246174) (xy 401.278277 -175.210483) (xy 401.324127 -175.181017) (xy 401.373704 -175.158375)
			(xy 401.425999 -175.14302) (xy 401.479947 -175.135264) (xy 401.534449 -175.135264) (xy 401.588397 -175.14302)
			(xy 401.640692 -175.158375) (xy 401.690269 -175.181017) (xy 401.736119 -175.210483) (xy 401.77731 -175.246174)
			(xy 401.813001 -175.287365) (xy 401.842467 -175.333215) (xy 401.865109 -175.382792) (xy 401.880464 -175.435087)
			(xy 401.88822 -175.489035) (xy 401.888706 -175.516286) (xy 401.888206 -175.544197) (xy 401.880074 -175.599422)
			(xy 401.86398 -175.652873) (xy 401.840269 -175.703408) (xy 401.809446 -175.749948) (xy 401.79117 -175.771048)
			(xy 401.785249 -175.778208) (xy 401.778613 -175.795546) (xy 401.778216 -175.80483) (xy 401.778216 -175.882554)
			(xy 401.78482 -175.899826) (xy 401.79117 -175.906938) (xy 401.809451 -175.928035) (xy 401.840276 -175.974575)
			(xy 401.863989 -176.02511) (xy 401.880085 -176.078562) (xy 401.88822 -176.133789) (xy 401.888706 -176.1617)
			(xy 401.88822 -176.188951) (xy 401.880464 -176.242899) (xy 401.865109 -176.295194) (xy 401.842467 -176.344771)
			(xy 401.813001 -176.390621) (xy 401.77731 -176.431812) (xy 401.736119 -176.467503) (xy 401.690269 -176.496969)
			(xy 401.640692 -176.519611) (xy 401.588397 -176.534966) (xy 401.534449 -176.542722) (xy 401.479947 -176.542722)
			(xy 401.425999 -176.534966) (xy 401.373704 -176.519611) (xy 401.324127 -176.496969) (xy 401.278277 -176.467503)
			(xy 401.237086 -176.431812) (xy 401.201395 -176.390621) (xy 401.171929 -176.344771) (xy 401.149287 -176.295194)
			(xy 401.133932 -176.242899) (xy 401.126176 -176.188951) (xy 401.12569 -176.1617) (xy 397.713708 -176.1617)
			(xy 397.713708 -176.840642) (xy 397.713255 -176.865879) (xy 397.705357 -176.915732) (xy 397.689762 -176.963737)
			(xy 397.666853 -177.008714) (xy 397.637195 -177.049555) (xy 397.601515 -177.085258) (xy 397.560693 -177.114943)
			(xy 397.515731 -177.137881) (xy 397.467737 -177.153508) (xy 397.417889 -177.161438) (xy 397.392652 -177.161952)
			(xy 395.85265 -177.161952) (xy 395.845924 -177.162156) (xy 395.832932 -177.165639) (xy 395.826996 -177.16881)
			(xy 395.802221 -177.182565) (xy 395.749051 -177.202149) (xy 395.693274 -177.212125) (xy 395.664944 -177.212752)
			(xy 395.605508 -177.212752) (xy 395.605508 -177.216816) (xy 392.841226 -177.216816) (xy 392.831155 -177.216399)
			(xy 392.812556 -177.208675) (xy 392.805158 -177.20183) (xy 392.600434 -176.997106) (xy 392.593609 -176.989694)
			(xy 392.585879 -176.971104) (xy 392.585448 -176.961038) (xy 392.585448 -171.707048) (xy 392.585011 -171.69698)
			(xy 392.5773 -171.678381) (xy 392.570462 -171.67098) (xy 390.72693 -169.827702) (xy 390.719513 -169.820883)
			(xy 390.700927 -169.813151) (xy 390.690862 -169.812716) (xy 387.193028 -169.812716) (xy 387.182957 -169.812298)
			(xy 387.164358 -169.804575) (xy 387.15696 -169.79773) (xy 385.290822 -167.931592) (xy 385.283989 -167.924186)
			(xy 385.276264 -167.905592) (xy 385.275836 -167.895524) (xy 384.347391 -167.895524) (xy 384.347655 -167.901527)
			(xy 384.355363 -167.920126) (xy 384.362198 -167.927528) (xy 386.394706 -169.960036) (xy 386.401555 -169.967429)
			(xy 386.409269 -169.986034) (xy 386.409692 -169.996104) (xy 386.409692 -174.64532) (xy 386.410083 -174.655394)
			(xy 386.417825 -174.673993) (xy 386.424678 -174.681388) (xy 388.397242 -176.653698) (xy 388.40408 -176.6611)
			(xy 388.411799 -176.679698) (xy 388.412228 -176.689766) (xy 388.412228 -178.404012) (xy 389.102854 -178.404012)
			(xy 389.10334 -178.376761) (xy 389.111096 -178.322813) (xy 389.126451 -178.270518) (xy 389.149093 -178.220941)
			(xy 389.178559 -178.175091) (xy 389.21425 -178.1339) (xy 389.255441 -178.098209) (xy 389.301291 -178.068743)
			(xy 389.350868 -178.046101) (xy 389.403163 -178.030746) (xy 389.457111 -178.02299) (xy 389.511613 -178.02299)
			(xy 389.565561 -178.030746) (xy 389.617856 -178.046101) (xy 389.667433 -178.068743) (xy 389.713283 -178.098209)
			(xy 389.754474 -178.1339) (xy 389.790165 -178.175091) (xy 389.819631 -178.220941) (xy 389.842273 -178.270518)
			(xy 389.857628 -178.322813) (xy 389.865384 -178.376761) (xy 389.86587 -178.404012) (xy 389.865203 -178.435575)
			(xy 389.854819 -178.49784) (xy 389.834336 -178.557549) (xy 389.819896 -178.585622) (xy 389.81507 -178.594512)
			(xy 389.813038 -178.61407) (xy 389.835898 -178.692556) (xy 389.839125 -178.701985) (xy 389.851551 -178.717541)
			(xy 389.860028 -178.722782) (xy 389.867394 -178.726846) (xy 389.8773 -178.732688) (xy 389.899144 -178.73472)
			(xy 389.993886 -178.701192) (xy 390.009634 -178.685698) (xy 390.013698 -178.675284) (xy 390.024371 -178.648498)
			(xy 390.052662 -178.598255) (xy 390.088195 -178.552845) (xy 390.13016 -178.513303) (xy 390.177601 -178.480531)
			(xy 390.229435 -178.455275) (xy 390.284481 -178.438111) (xy 390.341484 -178.429432) (xy 390.370314 -178.428904)
			(xy 390.397565 -178.429367) (xy 390.451513 -178.437125) (xy 390.503808 -178.452482) (xy 390.553385 -178.475125)
			(xy 390.599235 -178.504592) (xy 390.640425 -178.540285) (xy 390.676116 -178.581476) (xy 390.705582 -178.627327)
			(xy 390.728223 -178.676905) (xy 390.743578 -178.7292) (xy 390.751334 -178.783149) (xy 390.751334 -178.837651)
			(xy 390.743578 -178.8916) (xy 390.734228 -178.923442) (xy 390.993122 -178.923442) (xy 390.993628 -178.895968)
			(xy 391.001514 -178.841589) (xy 391.017129 -178.788907) (xy 391.04015 -178.739014) (xy 391.070098 -178.692944)
			(xy 391.087864 -178.671982) (xy 391.088118 -178.671728) (xy 391.093701 -178.664639) (xy 391.099949 -178.647724)
			(xy 391.10031 -178.638708) (xy 391.10031 -178.571144) (xy 391.09993 -178.562129) (xy 391.093698 -178.545212)
			(xy 391.088118 -178.538124) (xy 391.08761 -178.537616) (xy 391.06989 -178.516659) (xy 391.040005 -178.470629)
			(xy 391.017036 -178.420787) (xy 391.001458 -178.368164) (xy 390.993594 -178.31385) (xy 390.993122 -178.28641)
			(xy 390.993608 -178.259159) (xy 391.001364 -178.205211) (xy 391.016719 -178.152916) (xy 391.039361 -178.103339)
			(xy 391.068827 -178.057489) (xy 391.104518 -178.016298) (xy 391.145709 -177.980607) (xy 391.191559 -177.951141)
			(xy 391.241136 -177.928499) (xy 391.293431 -177.913144) (xy 391.347379 -177.905388) (xy 391.401881 -177.905388)
			(xy 391.455829 -177.913144) (xy 391.508124 -177.928499) (xy 391.557701 -177.951141) (xy 391.603551 -177.980607)
			(xy 391.644742 -178.016298) (xy 391.680433 -178.057489) (xy 391.709899 -178.103339) (xy 391.732541 -178.152916)
			(xy 391.747896 -178.205211) (xy 391.755652 -178.259159) (xy 391.756138 -178.28641) (xy 391.755648 -178.313884)
			(xy 391.747756 -178.368263) (xy 391.732136 -178.420945) (xy 391.709112 -178.470838) (xy 391.679162 -178.516907)
			(xy 391.661396 -178.53787) (xy 391.661142 -178.538124) (xy 391.655532 -178.545195) (xy 391.649301 -178.562124)
			(xy 391.64895 -178.571144) (xy 391.64895 -178.638708) (xy 391.649293 -178.647727) (xy 391.655549 -178.664644)
			(xy 391.661142 -178.671728) (xy 391.66165 -178.672236) (xy 391.679389 -178.693178) (xy 391.709272 -178.739211)
			(xy 391.732238 -178.789057) (xy 391.747811 -178.841684) (xy 391.755669 -178.896001) (xy 391.756138 -178.923442)
			(xy 391.755652 -178.950693) (xy 391.754019 -178.96205) (xy 392.330938 -178.96205) (xy 392.335009 -178.906428)
			(xy 392.347135 -178.851991) (xy 392.367058 -178.7999) (xy 392.394354 -178.751265) (xy 392.42844 -178.707122)
			(xy 392.468589 -178.668413) (xy 392.513947 -178.635962) (xy 392.563547 -178.610461) (xy 392.616331 -178.592454)
			(xy 392.671174 -178.582324) (xy 392.726908 -178.580287) (xy 392.782345 -178.586387) (xy 392.836302 -178.600493)
			(xy 392.887631 -178.622305) (xy 392.935237 -178.651359) (xy 392.978105 -178.687034) (xy 393.015322 -178.728571)
			(xy 393.046095 -178.775084) (xy 393.069767 -178.825581) (xy 393.085835 -178.878988) (xy 393.093955 -178.934164)
			(xy 393.094464 -178.96205) (xy 393.093955 -178.989936) (xy 393.085835 -179.045112) (xy 393.069767 -179.098519)
			(xy 393.046095 -179.149016) (xy 393.015322 -179.195529) (xy 392.978105 -179.237066) (xy 392.935237 -179.272741)
			(xy 392.887631 -179.301795) (xy 392.836302 -179.323607) (xy 392.782345 -179.337713) (xy 392.726908 -179.343813)
			(xy 392.671174 -179.341776) (xy 392.616331 -179.331646) (xy 392.563547 -179.313639) (xy 392.513947 -179.288138)
			(xy 392.468589 -179.255687) (xy 392.42844 -179.216978) (xy 392.394354 -179.172835) (xy 392.367058 -179.1242)
			(xy 392.347135 -179.072109) (xy 392.335009 -179.017672) (xy 392.330938 -178.96205) (xy 391.754019 -178.96205)
			(xy 391.747896 -179.004641) (xy 391.732541 -179.056936) (xy 391.709899 -179.106513) (xy 391.680433 -179.152363)
			(xy 391.644742 -179.193554) (xy 391.603551 -179.229245) (xy 391.557701 -179.258711) (xy 391.508124 -179.281353)
			(xy 391.455829 -179.296708) (xy 391.401881 -179.304464) (xy 391.347379 -179.304464) (xy 391.293431 -179.296708)
			(xy 391.241136 -179.281353) (xy 391.191559 -179.258711) (xy 391.145709 -179.229245) (xy 391.104518 -179.193554)
			(xy 391.068827 -179.152363) (xy 391.039361 -179.106513) (xy 391.016719 -179.056936) (xy 391.001364 -179.004641)
			(xy 390.993608 -178.950693) (xy 390.993122 -178.923442) (xy 390.734228 -178.923442) (xy 390.728223 -178.943895)
			(xy 390.705582 -178.993473) (xy 390.676116 -179.039324) (xy 390.640425 -179.080515) (xy 390.599235 -179.116208)
			(xy 390.553385 -179.145675) (xy 390.503808 -179.168318) (xy 390.451513 -179.183675) (xy 390.397565 -179.191433)
			(xy 390.370314 -179.19192) (xy 390.37006 -179.19192) (xy 390.344855 -179.191543) (xy 390.294887 -179.184898)
			(xy 390.246232 -179.171715) (xy 390.199743 -179.152225) (xy 390.177782 -179.13985) (xy 390.167876 -179.134008)
			(xy 390.146032 -179.131976) (xy 390.05129 -179.165504) (xy 390.035542 -179.180998) (xy 390.031478 -179.191412)
			(xy 390.02074 -179.21817) (xy 389.992457 -179.26841) (xy 389.956933 -179.313819) (xy 389.914977 -179.353362)
			(xy 389.867546 -179.386137) (xy 389.815721 -179.411399) (xy 389.760684 -179.428569) (xy 389.703689 -179.437259)
			(xy 389.674862 -179.437792) (xy 389.647609 -179.437357) (xy 389.593659 -179.429595) (xy 389.541362 -179.414235)
			(xy 389.491784 -179.391588) (xy 389.445933 -179.362116) (xy 389.404742 -179.326419) (xy 389.369051 -179.285224)
			(xy 389.339586 -179.239369) (xy 389.316946 -179.189787) (xy 389.301593 -179.137488) (xy 389.293839 -179.083537)
			(xy 389.293354 -179.056284) (xy 389.294016 -179.024721) (xy 389.304401 -178.962456) (xy 389.324886 -178.902747)
			(xy 389.339328 -178.874674) (xy 389.344154 -178.865784) (xy 389.346186 -178.846226) (xy 389.323326 -178.76774)
			(xy 389.320128 -178.758299) (xy 389.307683 -178.742748) (xy 389.299196 -178.737514) (xy 389.274072 -178.723003)
			(xy 389.22819 -178.687493) (xy 389.188216 -178.645443) (xy 389.155073 -178.597823) (xy 389.129526 -178.545732)
			(xy 389.112165 -178.490372) (xy 389.10339 -178.433021) (xy 389.102854 -178.404012) (xy 388.412228 -178.404012)
			(xy 388.412228 -179.529486) (xy 388.412653 -179.539555) (xy 388.420373 -179.558154) (xy 388.427214 -179.565554)
			(xy 388.71906 -179.8574) (xy 391.751818 -179.8574) (xy 391.755889 -179.801778) (xy 391.768015 -179.747341)
			(xy 391.787938 -179.69525) (xy 391.815234 -179.646615) (xy 391.84932 -179.602472) (xy 391.889469 -179.563763)
			(xy 391.934827 -179.531312) (xy 391.984427 -179.505811) (xy 392.037211 -179.487804) (xy 392.092054 -179.477674)
			(xy 392.147788 -179.475637) (xy 392.203225 -179.481737) (xy 392.257182 -179.495843) (xy 392.308511 -179.517655)
			(xy 392.356117 -179.546709) (xy 392.398985 -179.582384) (xy 392.436202 -179.623921) (xy 392.466975 -179.670434)
			(xy 392.490647 -179.720931) (xy 392.506715 -179.774338) (xy 392.514835 -179.829514) (xy 392.515344 -179.8574)
			(xy 392.514835 -179.885286) (xy 392.506715 -179.940462) (xy 392.490647 -179.993869) (xy 392.466975 -180.044366)
			(xy 392.436202 -180.090879) (xy 392.398985 -180.132416) (xy 392.356117 -180.168091) (xy 392.308511 -180.197145)
			(xy 392.257182 -180.218957) (xy 392.203225 -180.233063) (xy 392.147788 -180.239163) (xy 392.092054 -180.237126)
			(xy 392.037211 -180.226996) (xy 391.984427 -180.208989) (xy 391.934827 -180.183488) (xy 391.889469 -180.151037)
			(xy 391.84932 -180.112328) (xy 391.815234 -180.068185) (xy 391.787938 -180.01955) (xy 391.768015 -179.967459)
			(xy 391.755889 -179.913022) (xy 391.751818 -179.8574) (xy 388.71906 -179.8574) (xy 389.267446 -180.405786)
			(xy 389.274279 -180.413191) (xy 389.282001 -180.431787) (xy 389.282432 -180.441854) (xy 389.282432 -181.73446)
			(xy 392.71067 -181.73446) (xy 392.711144 -181.706549) (xy 392.719284 -181.651322) (xy 392.735384 -181.597871)
			(xy 392.759101 -181.547337) (xy 392.789928 -181.500798) (xy 392.808206 -181.479698) (xy 392.814105 -181.472522)
			(xy 392.820755 -181.455196) (xy 392.82116 -181.445916) (xy 392.82116 -181.368192) (xy 392.814556 -181.35092)
			(xy 392.808206 -181.343808) (xy 392.789911 -181.322722) (xy 392.759086 -181.27618) (xy 392.735374 -181.225642)
			(xy 392.719281 -181.172188) (xy 392.711152 -181.116958) (xy 392.71067 -181.089046) (xy 392.711156 -181.061795)
			(xy 392.718912 -181.007847) (xy 392.734267 -180.955552) (xy 392.756909 -180.905975) (xy 392.786375 -180.860125)
			(xy 392.822066 -180.818934) (xy 392.863257 -180.783243) (xy 392.909107 -180.753777) (xy 392.958684 -180.731135)
			(xy 393.010979 -180.71578) (xy 393.064927 -180.708024) (xy 393.119429 -180.708024) (xy 393.173377 -180.71578)
			(xy 393.225672 -180.731135) (xy 393.275249 -180.753777) (xy 393.321099 -180.783243) (xy 393.36229 -180.818934)
			(xy 393.397981 -180.860125) (xy 393.427447 -180.905975) (xy 393.450089 -180.955552) (xy 393.465444 -181.007847)
			(xy 393.4732 -181.061795) (xy 393.473686 -181.089046) (xy 393.473202 -181.116957) (xy 393.465062 -181.172182)
			(xy 393.448964 -181.225632) (xy 393.42525 -181.276167) (xy 393.394426 -181.322707) (xy 393.37615 -181.343808)
			(xy 393.370244 -181.350978) (xy 393.3636 -181.368309) (xy 393.363196 -181.37759) (xy 393.363196 -181.455314)
			(xy 393.3698 -181.472586) (xy 393.37615 -181.479698) (xy 393.394409 -181.500813) (xy 393.425238 -181.547348)
			(xy 393.448956 -181.597879) (xy 393.465057 -181.651326) (xy 393.473197 -181.70655) (xy 393.473686 -181.73446)
			(xy 393.4732 -181.761711) (xy 393.465444 -181.815659) (xy 393.450089 -181.867954) (xy 393.427447 -181.917531)
			(xy 393.397981 -181.963381) (xy 393.36229 -182.004572) (xy 393.321099 -182.040263) (xy 393.275249 -182.069729)
			(xy 393.225672 -182.092371) (xy 393.173377 -182.107726) (xy 393.119429 -182.115482) (xy 393.064927 -182.115482)
			(xy 393.010979 -182.107726) (xy 392.958684 -182.092371) (xy 392.909107 -182.069729) (xy 392.863257 -182.040263)
			(xy 392.822066 -182.004572) (xy 392.786375 -181.963381) (xy 392.756909 -181.917531) (xy 392.734267 -181.867954)
			(xy 392.718912 -181.815659) (xy 392.711156 -181.761711) (xy 392.71067 -181.73446) (xy 389.282432 -181.73446)
			(xy 389.282432 -182.563262) (xy 389.282005 -182.573331) (xy 389.274287 -182.59193) (xy 389.267446 -182.59933)
			(xy 389.13689 -182.729886) (xy 389.129486 -182.736721) (xy 389.11089 -182.744444) (xy 389.100822 -182.744872)
			(xy 386.013452 -182.744872) (xy 386.003385 -182.744427) (xy 385.984786 -182.736721) (xy 385.977384 -182.729886)
			(xy 385.705858 -182.45836) (xy 385.699002 -182.450973) (xy 385.691293 -182.432363) (xy 385.690872 -182.422292)
			(xy 385.690872 -181.317392) (xy 385.690458 -181.307321) (xy 385.68273 -181.288723) (xy 385.675886 -181.281324)
			(xy 385.068826 -180.67401) (xy 385.062002 -180.666597) (xy 385.054272 -180.648008) (xy 385.05384 -180.637942)
			(xy 385.05384 -177.720752) (xy 385.053403 -177.710684) (xy 385.045692 -177.692085) (xy 385.038854 -177.684684)
			(xy 384.432556 -177.078894) (xy 384.425166 -177.072041) (xy 384.406559 -177.064329) (xy 384.396488 -177.063908)
			(xy 380.346712 -177.063908) (xy 380.336643 -177.064338) (xy 380.318045 -177.072055) (xy 380.310644 -177.078894)
			(xy 380.073154 -177.316384) (xy 380.066322 -177.32379) (xy 380.058599 -177.342385) (xy 380.058168 -177.352452)
			(xy 380.058168 -178.404012) (xy 380.771654 -178.404012) (xy 380.77214 -178.376761) (xy 380.779896 -178.322813)
			(xy 380.795251 -178.270518) (xy 380.817893 -178.220941) (xy 380.847359 -178.175091) (xy 380.88305 -178.1339)
			(xy 380.924241 -178.098209) (xy 380.970091 -178.068743) (xy 381.019668 -178.046101) (xy 381.071963 -178.030746)
			(xy 381.125911 -178.02299) (xy 381.180413 -178.02299) (xy 381.234361 -178.030746) (xy 381.286656 -178.046101)
			(xy 381.336233 -178.068743) (xy 381.382083 -178.098209) (xy 381.423274 -178.1339) (xy 381.458965 -178.175091)
			(xy 381.488431 -178.220941) (xy 381.511073 -178.270518) (xy 381.526428 -178.322813) (xy 381.534184 -178.376761)
			(xy 381.53467 -178.404012) (xy 381.534003 -178.435575) (xy 381.523619 -178.49784) (xy 381.503136 -178.557549)
			(xy 381.488696 -178.585622) (xy 381.48387 -178.594512) (xy 381.481838 -178.61407) (xy 381.504698 -178.692556)
			(xy 381.507925 -178.701985) (xy 381.520351 -178.717541) (xy 381.528828 -178.722782) (xy 381.536194 -178.726846)
			(xy 381.5461 -178.732688) (xy 381.567944 -178.73472) (xy 381.662686 -178.701192) (xy 381.678434 -178.685698)
			(xy 381.682498 -178.675284) (xy 381.693171 -178.648498) (xy 381.721462 -178.598255) (xy 381.756995 -178.552845)
			(xy 381.79896 -178.513303) (xy 381.846401 -178.480531) (xy 381.898235 -178.455275) (xy 381.953281 -178.438111)
			(xy 382.010284 -178.429432) (xy 382.039114 -178.428904) (xy 382.066365 -178.429367) (xy 382.120313 -178.437125)
			(xy 382.172608 -178.452482) (xy 382.222185 -178.475125) (xy 382.268035 -178.504592) (xy 382.309225 -178.540285)
			(xy 382.344916 -178.581476) (xy 382.374382 -178.627327) (xy 382.397023 -178.676905) (xy 382.412378 -178.7292)
			(xy 382.420134 -178.783149) (xy 382.420134 -178.837651) (xy 382.412378 -178.8916) (xy 382.403028 -178.923442)
			(xy 382.661922 -178.923442) (xy 382.662428 -178.895968) (xy 382.670314 -178.841589) (xy 382.685929 -178.788907)
			(xy 382.70895 -178.739014) (xy 382.738898 -178.692944) (xy 382.756664 -178.671982) (xy 382.756918 -178.671728)
			(xy 382.762501 -178.664639) (xy 382.768749 -178.647724) (xy 382.76911 -178.638708) (xy 382.76911 -178.571144)
			(xy 382.76873 -178.562129) (xy 382.762498 -178.545212) (xy 382.756918 -178.538124) (xy 382.75641 -178.537616)
			(xy 382.73869 -178.516659) (xy 382.708805 -178.470629) (xy 382.685836 -178.420787) (xy 382.670258 -178.368164)
			(xy 382.662394 -178.31385) (xy 382.661922 -178.28641) (xy 382.662408 -178.259159) (xy 382.670164 -178.205211)
			(xy 382.685519 -178.152916) (xy 382.708161 -178.103339) (xy 382.737627 -178.057489) (xy 382.773318 -178.016298)
			(xy 382.814509 -177.980607) (xy 382.860359 -177.951141) (xy 382.909936 -177.928499) (xy 382.962231 -177.913144)
			(xy 383.016179 -177.905388) (xy 383.070681 -177.905388) (xy 383.124629 -177.913144) (xy 383.176924 -177.928499)
			(xy 383.226501 -177.951141) (xy 383.272351 -177.980607) (xy 383.313542 -178.016298) (xy 383.349233 -178.057489)
			(xy 383.378699 -178.103339) (xy 383.401341 -178.152916) (xy 383.416696 -178.205211) (xy 383.424452 -178.259159)
			(xy 383.424938 -178.28641) (xy 383.424448 -178.313884) (xy 383.416556 -178.368263) (xy 383.400936 -178.420945)
			(xy 383.377912 -178.470838) (xy 383.347962 -178.516907) (xy 383.330196 -178.53787) (xy 383.329942 -178.538124)
			(xy 383.324332 -178.545195) (xy 383.318101 -178.562124) (xy 383.31775 -178.571144) (xy 383.31775 -178.638708)
			(xy 383.318093 -178.647727) (xy 383.324349 -178.664644) (xy 383.329942 -178.671728) (xy 383.33045 -178.672236)
			(xy 383.348189 -178.693178) (xy 383.378072 -178.739211) (xy 383.401038 -178.789057) (xy 383.416611 -178.841684)
			(xy 383.424469 -178.896001) (xy 383.424938 -178.923442) (xy 383.424452 -178.950693) (xy 383.422819 -178.96205)
			(xy 383.999738 -178.96205) (xy 384.003809 -178.906428) (xy 384.015935 -178.851991) (xy 384.035858 -178.7999)
			(xy 384.063154 -178.751265) (xy 384.09724 -178.707122) (xy 384.137389 -178.668413) (xy 384.182747 -178.635962)
			(xy 384.232347 -178.610461) (xy 384.285131 -178.592454) (xy 384.339974 -178.582324) (xy 384.395708 -178.580287)
			(xy 384.451145 -178.586387) (xy 384.505102 -178.600493) (xy 384.556431 -178.622305) (xy 384.604037 -178.651359)
			(xy 384.646905 -178.687034) (xy 384.684122 -178.728571) (xy 384.714895 -178.775084) (xy 384.738567 -178.825581)
			(xy 384.754635 -178.878988) (xy 384.762755 -178.934164) (xy 384.763264 -178.96205) (xy 384.762755 -178.989936)
			(xy 384.754635 -179.045112) (xy 384.738567 -179.098519) (xy 384.714895 -179.149016) (xy 384.684122 -179.195529)
			(xy 384.646905 -179.237066) (xy 384.604037 -179.272741) (xy 384.556431 -179.301795) (xy 384.505102 -179.323607)
			(xy 384.451145 -179.337713) (xy 384.395708 -179.343813) (xy 384.339974 -179.341776) (xy 384.285131 -179.331646)
			(xy 384.232347 -179.313639) (xy 384.182747 -179.288138) (xy 384.137389 -179.255687) (xy 384.09724 -179.216978)
			(xy 384.063154 -179.172835) (xy 384.035858 -179.1242) (xy 384.015935 -179.072109) (xy 384.003809 -179.017672)
			(xy 383.999738 -178.96205) (xy 383.422819 -178.96205) (xy 383.416696 -179.004641) (xy 383.401341 -179.056936)
			(xy 383.378699 -179.106513) (xy 383.349233 -179.152363) (xy 383.313542 -179.193554) (xy 383.272351 -179.229245)
			(xy 383.226501 -179.258711) (xy 383.176924 -179.281353) (xy 383.124629 -179.296708) (xy 383.070681 -179.304464)
			(xy 383.016179 -179.304464) (xy 382.962231 -179.296708) (xy 382.909936 -179.281353) (xy 382.860359 -179.258711)
			(xy 382.814509 -179.229245) (xy 382.773318 -179.193554) (xy 382.737627 -179.152363) (xy 382.708161 -179.106513)
			(xy 382.685519 -179.056936) (xy 382.670164 -179.004641) (xy 382.662408 -178.950693) (xy 382.661922 -178.923442)
			(xy 382.403028 -178.923442) (xy 382.397023 -178.943895) (xy 382.374382 -178.993473) (xy 382.344916 -179.039324)
			(xy 382.309225 -179.080515) (xy 382.268035 -179.116208) (xy 382.222185 -179.145675) (xy 382.172608 -179.168318)
			(xy 382.120313 -179.183675) (xy 382.066365 -179.191433) (xy 382.039114 -179.19192) (xy 382.03886 -179.19192)
			(xy 382.013655 -179.191543) (xy 381.963687 -179.184898) (xy 381.915032 -179.171715) (xy 381.868543 -179.152225)
			(xy 381.846582 -179.13985) (xy 381.836676 -179.134008) (xy 381.814832 -179.131976) (xy 381.72009 -179.165504)
			(xy 381.704342 -179.180998) (xy 381.700278 -179.191412) (xy 381.68954 -179.21817) (xy 381.661257 -179.26841)
			(xy 381.625733 -179.313819) (xy 381.583777 -179.353362) (xy 381.536346 -179.386137) (xy 381.484521 -179.411399)
			(xy 381.429484 -179.428569) (xy 381.372489 -179.437259) (xy 381.343662 -179.437792) (xy 381.316409 -179.437357)
			(xy 381.262459 -179.429595) (xy 381.210162 -179.414235) (xy 381.160584 -179.391588) (xy 381.114733 -179.362116)
			(xy 381.073542 -179.326419) (xy 381.037851 -179.285224) (xy 381.008386 -179.239369) (xy 380.985746 -179.189787)
			(xy 380.970393 -179.137488) (xy 380.962639 -179.083537) (xy 380.962154 -179.056284) (xy 380.962816 -179.024721)
			(xy 380.973201 -178.962456) (xy 380.993686 -178.902747) (xy 381.008128 -178.874674) (xy 381.012954 -178.865784)
			(xy 381.014986 -178.846226) (xy 380.992126 -178.76774) (xy 380.988928 -178.758299) (xy 380.976483 -178.742748)
			(xy 380.967996 -178.737514) (xy 380.942872 -178.723003) (xy 380.89699 -178.687493) (xy 380.857016 -178.645443)
			(xy 380.823873 -178.597823) (xy 380.798326 -178.545732) (xy 380.780965 -178.490372) (xy 380.77219 -178.433021)
			(xy 380.771654 -178.404012) (xy 380.058168 -178.404012) (xy 380.058168 -179.506626) (xy 380.058562 -179.516699)
			(xy 380.066303 -179.535298) (xy 380.073154 -179.542694) (xy 380.38786 -179.8574) (xy 383.420618 -179.8574)
			(xy 383.424689 -179.801778) (xy 383.436815 -179.747341) (xy 383.456738 -179.69525) (xy 383.484034 -179.646615)
			(xy 383.51812 -179.602472) (xy 383.558269 -179.563763) (xy 383.603627 -179.531312) (xy 383.653227 -179.505811)
			(xy 383.706011 -179.487804) (xy 383.760854 -179.477674) (xy 383.816588 -179.475637) (xy 383.872025 -179.481737)
			(xy 383.925982 -179.495843) (xy 383.977311 -179.517655) (xy 384.024917 -179.546709) (xy 384.067785 -179.582384)
			(xy 384.105002 -179.623921) (xy 384.135775 -179.670434) (xy 384.159447 -179.720931) (xy 384.175515 -179.774338)
			(xy 384.183635 -179.829514) (xy 384.184144 -179.8574) (xy 384.183635 -179.885286) (xy 384.175515 -179.940462)
			(xy 384.159447 -179.993869) (xy 384.135775 -180.044366) (xy 384.105002 -180.090879) (xy 384.067785 -180.132416)
			(xy 384.024917 -180.168091) (xy 383.977311 -180.197145) (xy 383.925982 -180.218957) (xy 383.872025 -180.233063)
			(xy 383.816588 -180.239163) (xy 383.760854 -180.237126) (xy 383.706011 -180.226996) (xy 383.653227 -180.208989)
			(xy 383.603627 -180.183488) (xy 383.558269 -180.151037) (xy 383.51812 -180.112328) (xy 383.484034 -180.068185)
			(xy 383.456738 -180.01955) (xy 383.436815 -179.967459) (xy 383.424689 -179.913022) (xy 383.420618 -179.8574)
			(xy 380.38786 -179.8574) (xy 380.936246 -180.405786) (xy 380.943079 -180.413191) (xy 380.950801 -180.431787)
			(xy 380.951232 -180.441854) (xy 380.951232 -181.73446) (xy 384.37947 -181.73446) (xy 384.379944 -181.706549)
			(xy 384.388084 -181.651322) (xy 384.404184 -181.597871) (xy 384.427901 -181.547337) (xy 384.458728 -181.500798)
			(xy 384.477006 -181.479698) (xy 384.482905 -181.472522) (xy 384.489555 -181.455196) (xy 384.48996 -181.445916)
			(xy 384.48996 -181.368192) (xy 384.483356 -181.35092) (xy 384.477006 -181.343808) (xy 384.458711 -181.322722)
			(xy 384.427886 -181.27618) (xy 384.404174 -181.225642) (xy 384.388081 -181.172188) (xy 384.379952 -181.116958)
			(xy 384.37947 -181.089046) (xy 384.379956 -181.061795) (xy 384.387712 -181.007847) (xy 384.403067 -180.955552)
			(xy 384.425709 -180.905975) (xy 384.455175 -180.860125) (xy 384.490866 -180.818934) (xy 384.532057 -180.783243)
			(xy 384.577907 -180.753777) (xy 384.627484 -180.731135) (xy 384.679779 -180.71578) (xy 384.733727 -180.708024)
			(xy 384.788229 -180.708024) (xy 384.842177 -180.71578) (xy 384.894472 -180.731135) (xy 384.944049 -180.753777)
			(xy 384.989899 -180.783243) (xy 385.03109 -180.818934) (xy 385.066781 -180.860125) (xy 385.096247 -180.905975)
			(xy 385.118889 -180.955552) (xy 385.134244 -181.007847) (xy 385.142 -181.061795) (xy 385.142486 -181.089046)
			(xy 385.142002 -181.116957) (xy 385.133862 -181.172182) (xy 385.117764 -181.225632) (xy 385.09405 -181.276167)
			(xy 385.063226 -181.322707) (xy 385.04495 -181.343808) (xy 385.039044 -181.350978) (xy 385.0324 -181.368309)
			(xy 385.031996 -181.37759) (xy 385.031996 -181.455314) (xy 385.0386 -181.472586) (xy 385.04495 -181.479698)
			(xy 385.063209 -181.500813) (xy 385.094038 -181.547348) (xy 385.117756 -181.597879) (xy 385.133857 -181.651326)
			(xy 385.141997 -181.70655) (xy 385.142486 -181.73446) (xy 385.142 -181.761711) (xy 385.134244 -181.815659)
			(xy 385.118889 -181.867954) (xy 385.096247 -181.917531) (xy 385.066781 -181.963381) (xy 385.03109 -182.004572)
			(xy 384.989899 -182.040263) (xy 384.944049 -182.069729) (xy 384.894472 -182.092371) (xy 384.842177 -182.107726)
			(xy 384.788229 -182.115482) (xy 384.733727 -182.115482) (xy 384.679779 -182.107726) (xy 384.627484 -182.092371)
			(xy 384.577907 -182.069729) (xy 384.532057 -182.040263) (xy 384.490866 -182.004572) (xy 384.455175 -181.963381)
			(xy 384.425709 -181.917531) (xy 384.403067 -181.867954) (xy 384.387712 -181.815659) (xy 384.379956 -181.761711)
			(xy 384.37947 -181.73446) (xy 380.951232 -181.73446) (xy 380.951232 -182.694072) (xy 380.95069 -182.704074)
			(xy 380.943046 -182.722559) (xy 380.928909 -182.736712) (xy 380.910433 -182.744378) (xy 380.900432 -182.744872)
			(xy 377.627896 -182.744872) (xy 377.617826 -182.744456) (xy 377.599227 -182.73673) (xy 377.591828 -182.729886)
			(xy 377.290838 -182.428896) (xy 377.284009 -182.421487) (xy 377.276282 -182.402895) (xy 377.275852 -182.392828)
			(xy 377.275852 -181.243478) (xy 377.275451 -181.233406) (xy 377.267715 -181.214807) (xy 377.260866 -181.20741)
			(xy 376.775726 -180.722016) (xy 376.768904 -180.714601) (xy 376.761173 -180.696013) (xy 376.76074 -180.685948)
			(xy 376.76074 -177.448718) (xy 376.760321 -177.438648) (xy 376.752598 -177.420049) (xy 376.745754 -177.41265)
			(xy 375.691654 -176.35855) (xy 375.684224 -176.351748) (xy 375.665648 -176.344005) (xy 375.655586 -176.343564)
			(xy 372.55577 -176.343564) (xy 372.545697 -176.343957) (xy 372.527098 -176.351698) (xy 372.519702 -176.35855)
			(xy 371.683534 -177.194718) (xy 371.676698 -177.202122) (xy 371.668975 -177.220718) (xy 371.668548 -177.230786)
			(xy 371.668548 -178.404012) (xy 372.368826 -178.404012) (xy 372.369312 -178.376761) (xy 372.377068 -178.322813)
			(xy 372.392423 -178.270518) (xy 372.415065 -178.220941) (xy 372.444531 -178.175091) (xy 372.480222 -178.1339)
			(xy 372.521413 -178.098209) (xy 372.567263 -178.068743) (xy 372.61684 -178.046101) (xy 372.669135 -178.030746)
			(xy 372.723083 -178.02299) (xy 372.777585 -178.02299) (xy 372.831533 -178.030746) (xy 372.883828 -178.046101)
			(xy 372.933405 -178.068743) (xy 372.979255 -178.098209) (xy 373.020446 -178.1339) (xy 373.056137 -178.175091)
			(xy 373.085603 -178.220941) (xy 373.108245 -178.270518) (xy 373.112911 -178.28641) (xy 374.259094 -178.28641)
			(xy 374.25958 -178.259159) (xy 374.267336 -178.205211) (xy 374.282691 -178.152916) (xy 374.305333 -178.103339)
			(xy 374.334799 -178.057489) (xy 374.37049 -178.016298) (xy 374.411681 -177.980607) (xy 374.457531 -177.951141)
			(xy 374.507108 -177.928499) (xy 374.559403 -177.913144) (xy 374.613351 -177.905388) (xy 374.667853 -177.905388)
			(xy 374.721801 -177.913144) (xy 374.774096 -177.928499) (xy 374.823673 -177.951141) (xy 374.869523 -177.980607)
			(xy 374.910714 -178.016298) (xy 374.946405 -178.057489) (xy 374.975871 -178.103339) (xy 374.998513 -178.152916)
			(xy 375.013868 -178.205211) (xy 375.021624 -178.259159) (xy 375.02211 -178.28641) (xy 375.021586 -178.314084)
			(xy 375.013594 -178.36885) (xy 374.997766 -178.421886) (xy 374.974434 -178.472074) (xy 374.944088 -178.51836)
			(xy 374.926098 -178.539394) (xy 374.919748 -178.546506) (xy 374.913144 -178.564286) (xy 374.914668 -178.652424)
			(xy 374.922034 -178.66995) (xy 374.928638 -178.676808) (xy 374.948251 -178.698239) (xy 374.981448 -178.745911)
			(xy 375.007042 -178.798061) (xy 375.024442 -178.853486) (xy 375.033248 -178.910906) (xy 375.033794 -178.939952)
			(xy 375.0334 -178.96205) (xy 375.59691 -178.96205) (xy 375.600981 -178.906428) (xy 375.613107 -178.851991)
			(xy 375.63303 -178.7999) (xy 375.660326 -178.751265) (xy 375.694412 -178.707122) (xy 375.734561 -178.668413)
			(xy 375.779919 -178.635962) (xy 375.829519 -178.610461) (xy 375.882303 -178.592454) (xy 375.937146 -178.582324)
			(xy 375.99288 -178.580287) (xy 376.048317 -178.586387) (xy 376.102274 -178.600493) (xy 376.153603 -178.622305)
			(xy 376.201209 -178.651359) (xy 376.244077 -178.687034) (xy 376.281294 -178.728571) (xy 376.312067 -178.775084)
			(xy 376.335739 -178.825581) (xy 376.351807 -178.878988) (xy 376.359927 -178.934164) (xy 376.360436 -178.96205)
			(xy 376.359927 -178.989936) (xy 376.351807 -179.045112) (xy 376.335739 -179.098519) (xy 376.312067 -179.149016)
			(xy 376.281294 -179.195529) (xy 376.244077 -179.237066) (xy 376.201209 -179.272741) (xy 376.153603 -179.301795)
			(xy 376.102274 -179.323607) (xy 376.048317 -179.337713) (xy 375.99288 -179.343813) (xy 375.937146 -179.341776)
			(xy 375.882303 -179.331646) (xy 375.829519 -179.313639) (xy 375.779919 -179.288138) (xy 375.734561 -179.255687)
			(xy 375.694412 -179.216978) (xy 375.660326 -179.172835) (xy 375.63303 -179.1242) (xy 375.613107 -179.072109)
			(xy 375.600981 -179.017672) (xy 375.59691 -178.96205) (xy 375.0334 -178.96205) (xy 375.033308 -178.967203)
			(xy 375.025552 -179.021151) (xy 375.010197 -179.073446) (xy 374.987555 -179.123023) (xy 374.958089 -179.168873)
			(xy 374.922398 -179.210064) (xy 374.881207 -179.245755) (xy 374.835357 -179.275221) (xy 374.78578 -179.297863)
			(xy 374.733485 -179.313218) (xy 374.679537 -179.320974) (xy 374.625035 -179.320974) (xy 374.571087 -179.313218)
			(xy 374.518792 -179.297863) (xy 374.469215 -179.275221) (xy 374.423365 -179.245755) (xy 374.382174 -179.210064)
			(xy 374.346483 -179.168873) (xy 374.317017 -179.123023) (xy 374.294375 -179.073446) (xy 374.27902 -179.021151)
			(xy 374.271264 -178.967203) (xy 374.270778 -178.939952) (xy 374.271259 -178.912277) (xy 374.279258 -178.857507)
			(xy 374.295095 -178.804471) (xy 374.318438 -178.754283) (xy 374.348794 -178.707999) (xy 374.36679 -178.686968)
			(xy 374.37314 -178.679856) (xy 374.379744 -178.662076) (xy 374.37822 -178.573938) (xy 374.370854 -178.556412)
			(xy 374.36425 -178.549554) (xy 374.344616 -178.528141) (xy 374.311423 -178.480464) (xy 374.285833 -178.428309)
			(xy 374.268437 -178.372881) (xy 374.259637 -178.315457) (xy 374.259094 -178.28641) (xy 373.112911 -178.28641)
			(xy 373.1236 -178.322813) (xy 373.131356 -178.376761) (xy 373.131842 -178.404012) (xy 373.131179 -178.435575)
			(xy 373.120794 -178.49784) (xy 373.100309 -178.557549) (xy 373.085868 -178.585622) (xy 373.081042 -178.594512)
			(xy 373.07901 -178.61407) (xy 373.10187 -178.692556) (xy 373.105071 -178.701996) (xy 373.117514 -178.717548)
			(xy 373.126 -178.722782) (xy 373.133366 -178.726846) (xy 373.143272 -178.732688) (xy 373.165116 -178.73472)
			(xy 373.259858 -178.701192) (xy 373.275606 -178.685698) (xy 373.27967 -178.675284) (xy 373.290366 -178.648508)
			(xy 373.318654 -178.598266) (xy 373.354184 -178.552857) (xy 373.396146 -178.513315) (xy 373.443583 -178.480541)
			(xy 373.495414 -178.455283) (xy 373.550457 -178.438117) (xy 373.607457 -178.429434) (xy 373.636286 -178.428904)
			(xy 373.66354 -178.429342) (xy 373.717495 -178.437098) (xy 373.769796 -178.452453) (xy 373.819379 -178.475095)
			(xy 373.865236 -178.504564) (xy 373.906431 -178.540259) (xy 373.942128 -178.581453) (xy 373.971598 -178.627308)
			(xy 373.994242 -178.676891) (xy 374.009599 -178.729192) (xy 374.017357 -178.783146) (xy 374.017357 -178.837654)
			(xy 374.009599 -178.891608) (xy 373.994242 -178.943909) (xy 373.971598 -178.993492) (xy 373.942128 -179.039347)
			(xy 373.906431 -179.080541) (xy 373.865236 -179.116236) (xy 373.819379 -179.145705) (xy 373.769796 -179.168347)
			(xy 373.717495 -179.183702) (xy 373.66354 -179.191458) (xy 373.636286 -179.19192) (xy 373.636032 -179.19192)
			(xy 373.610829 -179.191512) (xy 373.560861 -179.184876) (xy 373.512206 -179.171702) (xy 373.465716 -179.152221)
			(xy 373.443754 -179.13985) (xy 373.433848 -179.134008) (xy 373.412004 -179.131976) (xy 373.317262 -179.165504)
			(xy 373.301514 -179.180998) (xy 373.29745 -179.191412) (xy 373.286735 -179.21818) (xy 373.25845 -179.268421)
			(xy 373.222922 -179.31383) (xy 373.180963 -179.353373) (xy 373.133528 -179.386147) (xy 373.0817 -179.411407)
			(xy 373.02666 -179.428575) (xy 372.969662 -179.437261) (xy 372.940834 -179.437792) (xy 372.913581 -179.437313)
			(xy 372.85963 -179.42956) (xy 372.807332 -179.414208) (xy 372.75775 -179.391568) (xy 372.711896 -179.362102)
			(xy 372.670703 -179.32641) (xy 372.635009 -179.285218) (xy 372.605541 -179.239365) (xy 372.582899 -179.189785)
			(xy 372.567544 -179.137488) (xy 372.559788 -179.083537) (xy 372.559326 -179.056284) (xy 372.559992 -179.024721)
			(xy 372.570376 -178.962456) (xy 372.590859 -178.902747) (xy 372.6053 -178.874674) (xy 372.610126 -178.865784)
			(xy 372.612158 -178.846226) (xy 372.589298 -178.76774) (xy 372.586074 -178.75831) (xy 372.573646 -178.742755)
			(xy 372.565168 -178.737514) (xy 372.540061 -178.722975) (xy 372.494175 -178.687473) (xy 372.454197 -178.645429)
			(xy 372.421051 -178.597814) (xy 372.395502 -178.545726) (xy 372.378138 -178.490369) (xy 372.369362 -178.43302)
			(xy 372.368826 -178.404012) (xy 371.668548 -178.404012) (xy 371.668548 -179.477416) (xy 371.668952 -179.487488)
			(xy 371.676686 -179.506086) (xy 371.683534 -179.513484) (xy 372.027553 -179.8574) (xy 375.01779 -179.8574)
			(xy 375.021861 -179.801778) (xy 375.033987 -179.747341) (xy 375.05391 -179.69525) (xy 375.081206 -179.646615)
			(xy 375.115292 -179.602472) (xy 375.155441 -179.563763) (xy 375.200799 -179.531312) (xy 375.250399 -179.505811)
			(xy 375.303183 -179.487804) (xy 375.358026 -179.477674) (xy 375.41376 -179.475637) (xy 375.469197 -179.481737)
			(xy 375.523154 -179.495843) (xy 375.574483 -179.517655) (xy 375.622089 -179.546709) (xy 375.664957 -179.582384)
			(xy 375.702174 -179.623921) (xy 375.732947 -179.670434) (xy 375.756619 -179.720931) (xy 375.772687 -179.774338)
			(xy 375.780807 -179.829514) (xy 375.781316 -179.8574) (xy 375.780807 -179.885286) (xy 375.772687 -179.940462)
			(xy 375.756619 -179.993869) (xy 375.732947 -180.044366) (xy 375.702174 -180.090879) (xy 375.664957 -180.132416)
			(xy 375.622089 -180.168091) (xy 375.574483 -180.197145) (xy 375.523154 -180.218957) (xy 375.469197 -180.233063)
			(xy 375.41376 -180.239163) (xy 375.358026 -180.237126) (xy 375.303183 -180.226996) (xy 375.250399 -180.208989)
			(xy 375.200799 -180.183488) (xy 375.155441 -180.151037) (xy 375.115292 -180.112328) (xy 375.081206 -180.068185)
			(xy 375.05391 -180.01955) (xy 375.033987 -179.967459) (xy 375.021861 -179.913022) (xy 375.01779 -179.8574)
			(xy 372.027553 -179.8574) (xy 372.533418 -180.363114) (xy 372.540259 -180.370513) (xy 372.547977 -180.389113)
			(xy 372.548404 -180.399182) (xy 372.548404 -181.73446) (xy 375.976642 -181.73446) (xy 375.977123 -181.706549)
			(xy 375.985262 -181.651323) (xy 376.001361 -181.597873) (xy 376.025076 -181.547338) (xy 376.055901 -181.500798)
			(xy 376.074178 -181.479698) (xy 376.080073 -181.472519) (xy 376.086726 -181.455195) (xy 376.087132 -181.445916)
			(xy 376.087132 -181.368192) (xy 376.080528 -181.35092) (xy 376.074178 -181.343808) (xy 376.055879 -181.322726)
			(xy 376.025055 -181.276182) (xy 376.001344 -181.225643) (xy 375.985253 -181.172188) (xy 375.977124 -181.116958)
			(xy 375.976642 -181.089046) (xy 375.977128 -181.061795) (xy 375.984884 -181.007847) (xy 376.000239 -180.955552)
			(xy 376.022881 -180.905975) (xy 376.052347 -180.860125) (xy 376.088038 -180.818934) (xy 376.129229 -180.783243)
			(xy 376.175079 -180.753777) (xy 376.224656 -180.731135) (xy 376.276951 -180.71578) (xy 376.330899 -180.708024)
			(xy 376.385401 -180.708024) (xy 376.439349 -180.71578) (xy 376.491644 -180.731135) (xy 376.541221 -180.753777)
			(xy 376.587071 -180.783243) (xy 376.628262 -180.818934) (xy 376.663953 -180.860125) (xy 376.693419 -180.905975)
			(xy 376.716061 -180.955552) (xy 376.731416 -181.007847) (xy 376.739172 -181.061795) (xy 376.739658 -181.089046)
			(xy 376.739181 -181.116957) (xy 376.731041 -181.172183) (xy 376.714941 -181.225634) (xy 376.691225 -181.276168)
			(xy 376.660399 -181.322708) (xy 376.642122 -181.343808) (xy 376.636225 -181.350985) (xy 376.629573 -181.36831)
			(xy 376.629168 -181.37759) (xy 376.629168 -181.455314) (xy 376.635772 -181.472586) (xy 376.642122 -181.479698)
			(xy 376.660377 -181.500817) (xy 376.691207 -181.54735) (xy 376.714926 -181.59788) (xy 376.731028 -181.651327)
			(xy 376.739169 -181.70655) (xy 376.739658 -181.73446) (xy 376.739172 -181.761711) (xy 376.731416 -181.815659)
			(xy 376.716061 -181.867954) (xy 376.693419 -181.917531) (xy 376.663953 -181.963381) (xy 376.628262 -182.004572)
			(xy 376.587071 -182.040263) (xy 376.541221 -182.069729) (xy 376.491644 -182.092371) (xy 376.439349 -182.107726)
			(xy 376.385401 -182.115482) (xy 376.330899 -182.115482) (xy 376.276951 -182.107726) (xy 376.224656 -182.092371)
			(xy 376.175079 -182.069729) (xy 376.129229 -182.040263) (xy 376.088038 -182.004572) (xy 376.052347 -181.963381)
			(xy 376.022881 -181.917531) (xy 376.000239 -181.867954) (xy 375.984884 -181.815659) (xy 375.977128 -181.761711)
			(xy 375.976642 -181.73446) (xy 372.548404 -181.73446) (xy 372.548404 -182.667656) (xy 372.547945 -182.677674)
			(xy 372.54029 -182.696189) (xy 372.526129 -182.710363) (xy 372.507622 -182.718035) (xy 372.497604 -182.718456)
			(xy 370.821204 -182.718456) (xy 370.821204 -182.724044) (xy 368.764566 -182.724044) (xy 368.754493 -182.723651)
			(xy 368.735894 -182.715909) (xy 368.728498 -182.709058) (xy 368.330226 -182.310786) (xy 368.323391 -182.303382)
			(xy 368.315668 -182.284786) (xy 368.31524 -182.274718) (xy 368.31524 -177.583592) (xy 368.315651 -177.573521)
			(xy 368.32338 -177.554923) (xy 368.330226 -177.547524) (xy 368.759486 -177.11801) (xy 368.766312 -177.110599)
			(xy 368.774041 -177.092008) (xy 368.774472 -177.081942) (xy 368.774472 -175.647858) (xy 368.774076 -175.637785)
			(xy 368.766336 -175.619187) (xy 368.759486 -175.61179) (xy 368.330226 -175.182276) (xy 368.323387 -175.174875)
			(xy 368.315666 -175.156277) (xy 368.31524 -175.146208) (xy 368.31524 -172.414438) (xy 368.314811 -172.404369)
			(xy 368.307094 -172.38577) (xy 368.300254 -172.37837) (xy 367.327434 -171.40555) (xy 367.32001 -171.398739)
			(xy 367.301429 -171.391001) (xy 367.291366 -171.390564) (xy 364.666022 -171.390564) (xy 364.655952 -171.390984)
			(xy 364.637353 -171.398707) (xy 364.629954 -171.40555) (xy 363.304074 -172.731684) (xy 363.297245 -172.739092)
			(xy 363.289519 -172.757685) (xy 363.289088 -172.767752) (xy 363.289088 -173.431454) (xy 364.007654 -173.431454)
			(xy 364.00814 -173.404203) (xy 364.015896 -173.350255) (xy 364.031251 -173.29796) (xy 364.053893 -173.248383)
			(xy 364.083359 -173.202533) (xy 364.11905 -173.161342) (xy 364.160241 -173.125651) (xy 364.206091 -173.096185)
			(xy 364.255668 -173.073543) (xy 364.307963 -173.058188) (xy 364.361911 -173.050432) (xy 364.416413 -173.050432)
			(xy 364.470361 -173.058188) (xy 364.522656 -173.073543) (xy 364.572233 -173.096185) (xy 364.618083 -173.125651)
			(xy 364.659274 -173.161342) (xy 364.694965 -173.202533) (xy 364.724431 -173.248383) (xy 364.747073 -173.29796)
			(xy 364.751739 -173.313852) (xy 365.897922 -173.313852) (xy 365.898408 -173.286601) (xy 365.906164 -173.232653)
			(xy 365.921519 -173.180358) (xy 365.944161 -173.130781) (xy 365.973627 -173.084931) (xy 366.009318 -173.04374)
			(xy 366.050509 -173.008049) (xy 366.096359 -172.978583) (xy 366.145936 -172.955941) (xy 366.198231 -172.940586)
			(xy 366.252179 -172.93283) (xy 366.306681 -172.93283) (xy 366.360629 -172.940586) (xy 366.412924 -172.955941)
			(xy 366.462501 -172.978583) (xy 366.508351 -173.008049) (xy 366.549542 -173.04374) (xy 366.585233 -173.084931)
			(xy 366.614699 -173.130781) (xy 366.637341 -173.180358) (xy 366.652696 -173.232653) (xy 366.660452 -173.286601)
			(xy 366.660938 -173.313852) (xy 366.66048 -173.340646) (xy 366.65298 -173.393706) (xy 366.638135 -173.445197)
			(xy 366.616237 -173.494106) (xy 366.587715 -173.539473) (xy 366.570768 -173.560232) (xy 366.564672 -173.567344)
			(xy 366.55883 -173.584362) (xy 366.5601 -173.660816) (xy 366.560627 -173.669989) (xy 366.567403 -173.687051)
			(xy 366.573308 -173.69409) (xy 366.591915 -173.715263) (xy 366.623297 -173.762086) (xy 366.647447 -173.813016)
			(xy 366.663841 -173.866946) (xy 366.672122 -173.922701) (xy 366.672622 -173.950884) (xy 366.672136 -173.978135)
			(xy 366.670503 -173.989492) (xy 367.235738 -173.989492) (xy 367.239809 -173.93387) (xy 367.251935 -173.879433)
			(xy 367.271858 -173.827342) (xy 367.299154 -173.778707) (xy 367.33324 -173.734564) (xy 367.373389 -173.695855)
			(xy 367.418747 -173.663404) (xy 367.468347 -173.637903) (xy 367.521131 -173.619896) (xy 367.575974 -173.609766)
			(xy 367.631708 -173.607729) (xy 367.687145 -173.613829) (xy 367.741102 -173.627935) (xy 367.792431 -173.649747)
			(xy 367.840037 -173.678801) (xy 367.882905 -173.714476) (xy 367.920122 -173.756013) (xy 367.950895 -173.802526)
			(xy 367.974567 -173.853023) (xy 367.990635 -173.90643) (xy 367.998755 -173.961606) (xy 367.999264 -173.989492)
			(xy 367.998755 -174.017378) (xy 367.990635 -174.072554) (xy 367.974567 -174.125961) (xy 367.950895 -174.176458)
			(xy 367.920122 -174.222971) (xy 367.882905 -174.264508) (xy 367.840037 -174.300183) (xy 367.792431 -174.329237)
			(xy 367.741102 -174.351049) (xy 367.687145 -174.365155) (xy 367.631708 -174.371255) (xy 367.575974 -174.369218)
			(xy 367.521131 -174.359088) (xy 367.468347 -174.341081) (xy 367.418747 -174.31558) (xy 367.373389 -174.283129)
			(xy 367.33324 -174.24442) (xy 367.299154 -174.200277) (xy 367.271858 -174.151642) (xy 367.251935 -174.099551)
			(xy 367.239809 -174.045114) (xy 367.235738 -173.989492) (xy 366.670503 -173.989492) (xy 366.66438 -174.032083)
			(xy 366.649025 -174.084378) (xy 366.626383 -174.133955) (xy 366.596917 -174.179805) (xy 366.561226 -174.220996)
			(xy 366.520035 -174.256687) (xy 366.474185 -174.286153) (xy 366.424608 -174.308795) (xy 366.372313 -174.32415)
			(xy 366.318365 -174.331906) (xy 366.263863 -174.331906) (xy 366.209915 -174.32415) (xy 366.15762 -174.308795)
			(xy 366.108043 -174.286153) (xy 366.062193 -174.256687) (xy 366.021002 -174.220996) (xy 365.985311 -174.179805)
			(xy 365.955845 -174.133955) (xy 365.933203 -174.084378) (xy 365.917848 -174.032083) (xy 365.910092 -173.978135)
			(xy 365.909606 -173.950884) (xy 365.91004 -173.924089) (xy 365.917547 -173.871028) (xy 365.932399 -173.819538)
			(xy 365.954302 -173.770629) (xy 365.982828 -173.725262) (xy 365.999776 -173.704504) (xy 366.005872 -173.697392)
			(xy 366.011714 -173.680374) (xy 366.010444 -173.60392) (xy 366.00989 -173.594751) (xy 366.003132 -173.577688)
			(xy 365.997236 -173.570646) (xy 365.978637 -173.549467) (xy 365.947256 -173.502644) (xy 365.923105 -173.451715)
			(xy 365.906709 -173.397788) (xy 365.898424 -173.342035) (xy 365.897922 -173.313852) (xy 364.751739 -173.313852)
			(xy 364.762428 -173.350255) (xy 364.770184 -173.404203) (xy 364.77067 -173.431454) (xy 364.77002 -173.463017)
			(xy 364.759629 -173.525283) (xy 364.73914 -173.584992) (xy 364.724696 -173.613064) (xy 364.71987 -173.621954)
			(xy 364.717838 -173.641512) (xy 364.740698 -173.719998) (xy 364.743948 -173.729418) (xy 364.756357 -173.744979)
			(xy 364.764828 -173.750224) (xy 364.772194 -173.754288) (xy 364.7821 -173.76013) (xy 364.803944 -173.762162)
			(xy 364.898686 -173.728634) (xy 364.914434 -173.71314) (xy 364.918498 -173.702726) (xy 364.929193 -173.675949)
			(xy 364.957479 -173.625705) (xy 364.993008 -173.580294) (xy 365.034969 -173.54075) (xy 365.082407 -173.507976)
			(xy 365.134239 -173.482718) (xy 365.189283 -173.465554) (xy 365.246285 -173.456874) (xy 365.275114 -173.456346)
			(xy 365.302361 -173.456925) (xy 365.356301 -173.464682) (xy 365.408588 -173.480037) (xy 365.458157 -173.502676)
			(xy 365.504 -173.532139) (xy 365.545184 -173.567826) (xy 365.580869 -173.609011) (xy 365.610331 -173.654855)
			(xy 365.632968 -173.704425) (xy 365.648321 -173.756713) (xy 365.656076 -173.810653) (xy 365.656076 -173.865147)
			(xy 365.648321 -173.919087) (xy 365.632968 -173.971375) (xy 365.610331 -174.020945) (xy 365.580869 -174.066789)
			(xy 365.545184 -174.107974) (xy 365.504 -174.143661) (xy 365.458157 -174.173124) (xy 365.408588 -174.195763)
			(xy 365.356301 -174.211118) (xy 365.302361 -174.218875) (xy 365.275114 -174.219362) (xy 365.27486 -174.219362)
			(xy 365.249656 -174.21898) (xy 365.199687 -174.212335) (xy 365.151033 -174.199153) (xy 365.104543 -174.179666)
			(xy 365.082582 -174.167292) (xy 365.072676 -174.16145) (xy 365.050832 -174.159418) (xy 364.95609 -174.192946)
			(xy 364.940342 -174.20844) (xy 364.936278 -174.218854) (xy 364.925562 -174.245622) (xy 364.897274 -174.29586)
			(xy 364.861745 -174.341267) (xy 364.819786 -174.380808) (xy 364.772352 -174.413582) (xy 364.720525 -174.438842)
			(xy 364.665486 -174.456012) (xy 364.608489 -174.464701) (xy 364.579662 -174.465234) (xy 364.552411 -174.464758)
			(xy 364.498464 -174.456997) (xy 364.446171 -174.441638) (xy 364.396595 -174.418994) (xy 364.350746 -174.389526)
			(xy 364.309557 -174.353834) (xy 364.273866 -174.312644) (xy 364.2444 -174.266794) (xy 364.221758 -174.217218)
			(xy 364.206401 -174.164924) (xy 364.198642 -174.110977) (xy 364.198154 -174.083726) (xy 364.198793 -174.052162)
			(xy 364.209188 -173.989896) (xy 364.229682 -173.930188) (xy 364.244128 -173.902116) (xy 364.248954 -173.893226)
			(xy 364.250986 -173.873668) (xy 364.228126 -173.795182) (xy 364.224912 -173.785747) (xy 364.212478 -173.770193)
			(xy 364.203996 -173.764956) (xy 364.17889 -173.750415) (xy 364.133008 -173.71491) (xy 364.093034 -173.672865)
			(xy 364.059889 -173.62525) (xy 364.034339 -173.573164) (xy 364.016973 -173.517809) (xy 364.008193 -173.460462)
			(xy 364.007654 -173.431454) (xy 363.289088 -173.431454) (xy 363.289088 -174.49038) (xy 363.2895 -174.500451)
			(xy 363.297228 -174.51905) (xy 363.304074 -174.526448) (xy 363.662468 -174.884842) (xy 366.656618 -174.884842)
			(xy 366.660689 -174.82922) (xy 366.672815 -174.774783) (xy 366.692738 -174.722692) (xy 366.720034 -174.674057)
			(xy 366.75412 -174.629914) (xy 366.794269 -174.591205) (xy 366.839627 -174.558754) (xy 366.889227 -174.533253)
			(xy 366.942011 -174.515246) (xy 366.996854 -174.505116) (xy 367.052588 -174.503079) (xy 367.108025 -174.509179)
			(xy 367.161982 -174.523285) (xy 367.213311 -174.545097) (xy 367.260917 -174.574151) (xy 367.303785 -174.609826)
			(xy 367.341002 -174.651363) (xy 367.371775 -174.697876) (xy 367.395447 -174.748373) (xy 367.411515 -174.80178)
			(xy 367.419635 -174.856956) (xy 367.420144 -174.884842) (xy 367.419635 -174.912728) (xy 367.411515 -174.967904)
			(xy 367.395447 -175.021311) (xy 367.371775 -175.071808) (xy 367.341002 -175.118321) (xy 367.303785 -175.159858)
			(xy 367.260917 -175.195533) (xy 367.213311 -175.224587) (xy 367.161982 -175.246399) (xy 367.108025 -175.260505)
			(xy 367.052588 -175.266605) (xy 366.996854 -175.264568) (xy 366.942011 -175.254438) (xy 366.889227 -175.236431)
			(xy 366.839627 -175.21093) (xy 366.794269 -175.178479) (xy 366.75412 -175.13977) (xy 366.720034 -175.095627)
			(xy 366.692738 -175.046992) (xy 366.672815 -174.994901) (xy 366.660689 -174.940464) (xy 366.656618 -174.884842)
			(xy 363.662468 -174.884842) (xy 364.019084 -175.241458) (xy 364.0265 -175.248278) (xy 364.045087 -175.256011)
			(xy 364.055152 -175.256444) (xy 364.136432 -175.256444) (xy 364.146461 -175.256794) (xy 364.164987 -175.264483)
			(xy 364.17916 -175.278677) (xy 364.186821 -175.297215) (xy 364.187232 -175.307244) (xy 364.187232 -176.761902)
			(xy 367.61547 -176.761902) (xy 367.615969 -176.733991) (xy 367.624103 -176.678766) (xy 367.640197 -176.625316)
			(xy 367.663908 -176.574781) (xy 367.69473 -176.528241) (xy 367.713006 -176.50714) (xy 367.718929 -176.499982)
			(xy 367.725565 -176.482642) (xy 367.72596 -176.473358) (xy 367.72596 -176.395634) (xy 367.719356 -176.378362)
			(xy 367.713006 -176.37125) (xy 367.694731 -176.350148) (xy 367.663903 -176.30361) (xy 367.640187 -176.253076)
			(xy 367.62409 -176.199625) (xy 367.615955 -176.144399) (xy 367.61547 -176.116488) (xy 367.615956 -176.089237)
			(xy 367.623712 -176.035289) (xy 367.639067 -175.982994) (xy 367.661709 -175.933417) (xy 367.691175 -175.887567)
			(xy 367.726866 -175.846376) (xy 367.768057 -175.810685) (xy 367.813907 -175.781219) (xy 367.863484 -175.758577)
			(xy 367.915779 -175.743222) (xy 367.969727 -175.735466) (xy 368.024229 -175.735466) (xy 368.078177 -175.743222)
			(xy 368.130472 -175.758577) (xy 368.180049 -175.781219) (xy 368.225899 -175.810685) (xy 368.26709 -175.846376)
			(xy 368.302781 -175.887567) (xy 368.332247 -175.933417) (xy 368.354889 -175.982994) (xy 368.370244 -176.035289)
			(xy 368.378 -176.089237) (xy 368.378486 -176.116488) (xy 368.377967 -176.144398) (xy 368.369836 -176.199621)
			(xy 368.353746 -176.253071) (xy 368.330039 -176.303606) (xy 368.299223 -176.350148) (xy 368.28095 -176.37125)
			(xy 368.275026 -176.378407) (xy 368.268393 -176.395748) (xy 368.267996 -176.405032) (xy 368.267996 -176.482756)
			(xy 368.2746 -176.500028) (xy 368.28095 -176.50714) (xy 368.299229 -176.528239) (xy 368.330055 -176.574778)
			(xy 368.353769 -176.625313) (xy 368.369865 -176.678764) (xy 368.378 -176.733991) (xy 368.378486 -176.761902)
			(xy 368.378 -176.789153) (xy 368.370244 -176.843101) (xy 368.354889 -176.895396) (xy 368.332247 -176.944973)
			(xy 368.302781 -176.990823) (xy 368.26709 -177.032014) (xy 368.225899 -177.067705) (xy 368.180049 -177.097171)
			(xy 368.130472 -177.119813) (xy 368.078177 -177.135168) (xy 368.024229 -177.142924) (xy 367.969727 -177.142924)
			(xy 367.915779 -177.135168) (xy 367.863484 -177.119813) (xy 367.813907 -177.097171) (xy 367.768057 -177.067705)
			(xy 367.726866 -177.032014) (xy 367.691175 -176.990823) (xy 367.661709 -176.944973) (xy 367.639067 -176.895396)
			(xy 367.623712 -176.843101) (xy 367.615956 -176.789153) (xy 367.61547 -176.761902) (xy 364.187232 -176.761902)
			(xy 364.187232 -177.695352) (xy 364.186742 -177.705366) (xy 364.179094 -177.723876) (xy 364.164943 -177.738049)
			(xy 364.146446 -177.745726) (xy 364.136432 -177.746152) (xy 362.475526 -177.746152) (xy 362.430314 -177.791364)
			(xy 360.45775 -177.791364) (xy 360.447682 -177.790922) (xy 360.429084 -177.783214) (xy 360.421682 -177.776378)
			(xy 360.12501 -177.479706) (xy 360.118181 -177.472297) (xy 360.110455 -177.453705) (xy 360.110024 -177.443638)
			(xy 360.110024 -169.313352) (xy 360.11047 -169.303285) (xy 360.118176 -169.284687) (xy 360.12501 -169.277284)
			(xy 360.613706 -168.788334) (xy 360.620524 -168.780917) (xy 360.628257 -168.762331) (xy 360.628692 -168.752266)
			(xy 360.628692 -167.462454) (xy 360.62824 -167.452388) (xy 360.620538 -167.43379) (xy 360.613706 -167.426386)
			(xy 360.12501 -166.937436) (xy 360.118195 -166.930016) (xy 360.11046 -166.911432) (xy 360.110024 -166.901368)
			(xy 360.110024 -164.323522) (xy 360.109607 -164.313451) (xy 360.101883 -164.294852) (xy 360.095038 -164.287454)
			(xy 358.760776 -162.953446) (xy 358.753373 -162.946609) (xy 358.734776 -162.938886) (xy 358.724708 -162.93846)
			(xy 356.077012 -162.93846) (xy 356.066941 -162.938876) (xy 356.048343 -162.946602) (xy 356.040944 -162.953446)
			(xy 355.013006 -163.98113) (xy 355.006161 -163.988526) (xy 354.998444 -164.007128) (xy 354.99802 -164.017198)
			(xy 354.99802 -165.156134) (xy 355.727254 -165.156134) (xy 355.72774 -165.128883) (xy 355.735496 -165.074935)
			(xy 355.750851 -165.02264) (xy 355.773493 -164.973063) (xy 355.802959 -164.927213) (xy 355.83865 -164.886022)
			(xy 355.879841 -164.850331) (xy 355.925691 -164.820865) (xy 355.975268 -164.798223) (xy 356.027563 -164.782868)
			(xy 356.081511 -164.775112) (xy 356.136013 -164.775112) (xy 356.189961 -164.782868) (xy 356.242256 -164.798223)
			(xy 356.291833 -164.820865) (xy 356.337683 -164.850331) (xy 356.378874 -164.886022) (xy 356.414565 -164.927213)
			(xy 356.444031 -164.973063) (xy 356.466673 -165.02264) (xy 356.482028 -165.074935) (xy 356.489784 -165.128883)
			(xy 356.49027 -165.156134) (xy 356.489612 -165.187697) (xy 356.479225 -165.249962) (xy 356.458738 -165.309671)
			(xy 356.444296 -165.337744) (xy 356.43947 -165.346634) (xy 356.437438 -165.366192) (xy 356.460298 -165.444678)
			(xy 356.463556 -165.454094) (xy 356.475959 -165.469657) (xy 356.484428 -165.474904) (xy 356.491794 -165.478968)
			(xy 356.5017 -165.48481) (xy 356.523544 -165.486842) (xy 356.618286 -165.453314) (xy 356.634034 -165.43782)
			(xy 356.638098 -165.427406) (xy 356.648782 -165.400624) (xy 356.677071 -165.350381) (xy 356.712601 -165.304971)
			(xy 356.754565 -165.265428) (xy 356.802004 -165.232654) (xy 356.853837 -165.207398) (xy 356.908882 -165.190234)
			(xy 356.965884 -165.181554) (xy 356.994714 -165.181026) (xy 357.021967 -165.181445) (xy 357.075918 -165.189204)
			(xy 357.128216 -165.204561) (xy 357.177796 -165.227205) (xy 357.223648 -165.256675) (xy 357.264841 -165.292369)
			(xy 357.300534 -165.333563) (xy 357.330001 -165.379417) (xy 357.352644 -165.428997) (xy 357.367999 -165.481296)
			(xy 357.375756 -165.535247) (xy 357.375756 -165.589753) (xy 357.367999 -165.643704) (xy 357.358645 -165.675564)
			(xy 357.617522 -165.675564) (xy 357.617982 -165.648088) (xy 357.625879 -165.593707) (xy 357.641505 -165.541025)
			(xy 357.664536 -165.491132) (xy 357.694494 -165.445065) (xy 357.712264 -165.424104) (xy 357.712518 -165.42385)
			(xy 357.718092 -165.416755) (xy 357.724346 -165.399845) (xy 357.72471 -165.39083) (xy 357.72471 -165.323266)
			(xy 357.724367 -165.314248) (xy 357.71811 -165.297331) (xy 357.712518 -165.290246) (xy 357.71201 -165.289738)
			(xy 357.6943 -165.268773) (xy 357.664414 -165.222745) (xy 357.641443 -165.172905) (xy 357.625863 -165.120284)
			(xy 357.617996 -165.065972) (xy 357.617522 -165.038532) (xy 357.618008 -165.011281) (xy 357.625764 -164.957333)
			(xy 357.641119 -164.905038) (xy 357.663761 -164.855461) (xy 357.693227 -164.809611) (xy 357.728918 -164.76842)
			(xy 357.770109 -164.732729) (xy 357.815959 -164.703263) (xy 357.865536 -164.680621) (xy 357.917831 -164.665266)
			(xy 357.971779 -164.65751) (xy 358.026281 -164.65751) (xy 358.080229 -164.665266) (xy 358.132524 -164.680621)
			(xy 358.182101 -164.703263) (xy 358.227951 -164.732729) (xy 358.269142 -164.76842) (xy 358.304833 -164.809611)
			(xy 358.334299 -164.855461) (xy 358.356941 -164.905038) (xy 358.372296 -164.957333) (xy 358.380052 -165.011281)
			(xy 358.380538 -165.038532) (xy 358.380062 -165.066007) (xy 358.372166 -165.120387) (xy 358.356543 -165.173069)
			(xy 358.333517 -165.222961) (xy 358.303564 -165.26903) (xy 358.285796 -165.289992) (xy 358.285542 -165.290246)
			(xy 358.279965 -165.297339) (xy 358.273714 -165.314251) (xy 358.27335 -165.323266) (xy 358.27335 -165.39083)
			(xy 358.273682 -165.39985) (xy 358.279946 -165.416767) (xy 358.285542 -165.42385) (xy 358.28605 -165.424358)
			(xy 358.303799 -165.445292) (xy 358.333681 -165.491327) (xy 358.356645 -165.541175) (xy 358.372216 -165.593804)
			(xy 358.380071 -165.648122) (xy 358.380538 -165.675564) (xy 358.380052 -165.702815) (xy 358.372296 -165.756763)
			(xy 358.356941 -165.809058) (xy 358.334299 -165.858635) (xy 358.330831 -165.864032) (xy 358.955338 -165.864032)
			(xy 358.959409 -165.80841) (xy 358.971535 -165.753973) (xy 358.991458 -165.701882) (xy 359.018754 -165.653247)
			(xy 359.05284 -165.609104) (xy 359.092989 -165.570395) (xy 359.138347 -165.537944) (xy 359.187947 -165.512443)
			(xy 359.240731 -165.494436) (xy 359.295574 -165.484306) (xy 359.351308 -165.482269) (xy 359.406745 -165.488369)
			(xy 359.460702 -165.502475) (xy 359.512031 -165.524287) (xy 359.559637 -165.553341) (xy 359.602505 -165.589016)
			(xy 359.639722 -165.630553) (xy 359.670495 -165.677066) (xy 359.694167 -165.727563) (xy 359.710235 -165.78097)
			(xy 359.718355 -165.836146) (xy 359.718864 -165.864032) (xy 359.718355 -165.891918) (xy 359.710235 -165.947094)
			(xy 359.694167 -166.000501) (xy 359.670495 -166.050998) (xy 359.639722 -166.097511) (xy 359.602505 -166.139048)
			(xy 359.559637 -166.174723) (xy 359.512031 -166.203777) (xy 359.460702 -166.225589) (xy 359.406745 -166.239695)
			(xy 359.351308 -166.245795) (xy 359.295574 -166.243758) (xy 359.240731 -166.233628) (xy 359.187947 -166.215621)
			(xy 359.138347 -166.19012) (xy 359.092989 -166.157669) (xy 359.05284 -166.11896) (xy 359.018754 -166.074817)
			(xy 358.991458 -166.026182) (xy 358.971535 -165.974091) (xy 358.959409 -165.919654) (xy 358.955338 -165.864032)
			(xy 358.330831 -165.864032) (xy 358.304833 -165.904485) (xy 358.269142 -165.945676) (xy 358.227951 -165.981367)
			(xy 358.182101 -166.010833) (xy 358.132524 -166.033475) (xy 358.080229 -166.04883) (xy 358.026281 -166.056586)
			(xy 357.971779 -166.056586) (xy 357.917831 -166.04883) (xy 357.865536 -166.033475) (xy 357.815959 -166.010833)
			(xy 357.770109 -165.981367) (xy 357.728918 -165.945676) (xy 357.693227 -165.904485) (xy 357.663761 -165.858635)
			(xy 357.641119 -165.809058) (xy 357.625764 -165.756763) (xy 357.618008 -165.702815) (xy 357.617522 -165.675564)
			(xy 357.358645 -165.675564) (xy 357.352644 -165.696003) (xy 357.330001 -165.745583) (xy 357.300534 -165.791437)
			(xy 357.264841 -165.832631) (xy 357.223648 -165.868325) (xy 357.177796 -165.897795) (xy 357.128216 -165.920439)
			(xy 357.075918 -165.935796) (xy 357.021967 -165.943555) (xy 356.994714 -165.944042) (xy 356.99446 -165.944042)
			(xy 356.969256 -165.943663) (xy 356.919287 -165.937017) (xy 356.870632 -165.923835) (xy 356.824143 -165.904346)
			(xy 356.802182 -165.891972) (xy 356.792276 -165.88613) (xy 356.770432 -165.884098) (xy 356.67569 -165.917626)
			(xy 356.659942 -165.93312) (xy 356.655878 -165.943534) (xy 356.645152 -165.970297) (xy 356.616866 -166.020536)
			(xy 356.581339 -166.065944) (xy 356.539382 -166.105486) (xy 356.491949 -166.138261) (xy 356.440123 -166.163521)
			(xy 356.385085 -166.180692) (xy 356.328089 -166.189381) (xy 356.299262 -166.189914) (xy 356.27201 -166.189458)
			(xy 356.218062 -166.181696) (xy 356.165767 -166.166336) (xy 356.11619 -166.143691) (xy 356.07034 -166.114222)
			(xy 356.02915 -166.078527) (xy 355.993459 -166.037335) (xy 355.963993 -165.991482) (xy 355.941352 -165.941903)
			(xy 355.925997 -165.889607) (xy 355.91824 -165.835658) (xy 355.917754 -165.808406) (xy 355.918386 -165.776842)
			(xy 355.928784 -165.714576) (xy 355.949281 -165.654867) (xy 355.963728 -165.626796) (xy 355.968554 -165.617906)
			(xy 355.970586 -165.598348) (xy 355.947726 -165.519862) (xy 355.94452 -165.510424) (xy 355.93208 -165.494871)
			(xy 355.923596 -165.489636) (xy 355.898482 -165.475109) (xy 355.8526 -165.439602) (xy 355.812625 -165.397554)
			(xy 355.779482 -165.349937) (xy 355.753933 -165.297849) (xy 355.736569 -165.242491) (xy 355.727791 -165.185142)
			(xy 355.727254 -165.156134) (xy 354.99802 -165.156134) (xy 354.99802 -166.200582) (xy 354.99845 -166.210651)
			(xy 355.006167 -166.229249) (xy 355.013006 -166.23665) (xy 355.385986 -166.609522) (xy 358.376218 -166.609522)
			(xy 358.380289 -166.5539) (xy 358.392415 -166.499463) (xy 358.412338 -166.447372) (xy 358.439634 -166.398737)
			(xy 358.47372 -166.354594) (xy 358.513869 -166.315885) (xy 358.559227 -166.283434) (xy 358.608827 -166.257933)
			(xy 358.661611 -166.239926) (xy 358.716454 -166.229796) (xy 358.772188 -166.227759) (xy 358.827625 -166.233859)
			(xy 358.881582 -166.247965) (xy 358.932911 -166.269777) (xy 358.980517 -166.298831) (xy 359.023385 -166.334506)
			(xy 359.060602 -166.376043) (xy 359.091375 -166.422556) (xy 359.115047 -166.473053) (xy 359.131115 -166.52646)
			(xy 359.139235 -166.581636) (xy 359.139744 -166.609522) (xy 359.139235 -166.637408) (xy 359.131115 -166.692584)
			(xy 359.115047 -166.745991) (xy 359.091375 -166.796488) (xy 359.060602 -166.843001) (xy 359.023385 -166.884538)
			(xy 358.980517 -166.920213) (xy 358.932911 -166.949267) (xy 358.881582 -166.971079) (xy 358.827625 -166.985185)
			(xy 358.772188 -166.991285) (xy 358.716454 -166.989248) (xy 358.661611 -166.979118) (xy 358.608827 -166.961111)
			(xy 358.559227 -166.93561) (xy 358.513869 -166.903159) (xy 358.47372 -166.86445) (xy 358.439634 -166.820307)
			(xy 358.412338 -166.771672) (xy 358.392415 -166.719581) (xy 358.380289 -166.665144) (xy 358.376218 -166.609522)
			(xy 355.385986 -166.609522) (xy 355.891846 -167.115236) (xy 355.898701 -167.122624) (xy 355.90641 -167.141233)
			(xy 355.906832 -167.151304) (xy 355.906832 -168.486582) (xy 359.33507 -168.486582) (xy 359.335557 -168.458671)
			(xy 359.343694 -168.403445) (xy 359.359791 -168.349994) (xy 359.383505 -168.29946) (xy 359.414329 -168.25292)
			(xy 359.432606 -168.23182) (xy 359.438495 -168.224637) (xy 359.445151 -168.207316) (xy 359.44556 -168.198038)
			(xy 359.44556 -168.120314) (xy 359.438956 -168.103042) (xy 359.432606 -168.09593) (xy 359.414322 -168.074836)
			(xy 359.383495 -168.028296) (xy 359.359781 -167.97776) (xy 359.343686 -167.924307) (xy 359.335554 -167.86908)
			(xy 359.33507 -167.841168) (xy 359.335556 -167.813917) (xy 359.343312 -167.759969) (xy 359.358667 -167.707674)
			(xy 359.381309 -167.658097) (xy 359.410775 -167.612247) (xy 359.446466 -167.571056) (xy 359.487657 -167.535365)
			(xy 359.533507 -167.505899) (xy 359.583084 -167.483257) (xy 359.635379 -167.467902) (xy 359.689327 -167.460146)
			(xy 359.743829 -167.460146) (xy 359.797777 -167.467902) (xy 359.850072 -167.483257) (xy 359.899649 -167.505899)
			(xy 359.945499 -167.535365) (xy 359.98669 -167.571056) (xy 360.022381 -167.612247) (xy 360.051847 -167.658097)
			(xy 360.074489 -167.707674) (xy 360.089844 -167.759969) (xy 360.0976 -167.813917) (xy 360.098086 -167.841168)
			(xy 360.097615 -167.869079) (xy 360.089472 -167.924305) (xy 360.073371 -167.977756) (xy 360.049654 -168.02829)
			(xy 360.018827 -168.07483) (xy 360.00055 -168.09593) (xy 359.994634 -168.103094) (xy 359.987996 -168.120429)
			(xy 359.987596 -168.129712) (xy 359.987596 -168.207436) (xy 359.9942 -168.224708) (xy 360.00055 -168.23182)
			(xy 360.01882 -168.252926) (xy 360.049647 -168.299464) (xy 360.073363 -168.349997) (xy 360.089461 -168.403446)
			(xy 360.097599 -168.458671) (xy 360.098086 -168.486582) (xy 360.0976 -168.513833) (xy 360.089844 -168.567781)
			(xy 360.074489 -168.620076) (xy 360.051847 -168.669653) (xy 360.022381 -168.715503) (xy 359.98669 -168.756694)
			(xy 359.945499 -168.792385) (xy 359.899649 -168.821851) (xy 359.850072 -168.844493) (xy 359.797777 -168.859848)
			(xy 359.743829 -168.867604) (xy 359.689327 -168.867604) (xy 359.635379 -168.859848) (xy 359.583084 -168.844493)
			(xy 359.533507 -168.821851) (xy 359.487657 -168.792385) (xy 359.446466 -168.756694) (xy 359.410775 -168.715503)
			(xy 359.381309 -168.669653) (xy 359.358667 -168.620076) (xy 359.343312 -168.567781) (xy 359.335556 -168.513833)
			(xy 359.33507 -168.486582) (xy 355.906832 -168.486582) (xy 355.906832 -169.420032) (xy 355.906339 -169.430038)
			(xy 355.898675 -169.448524) (xy 355.884524 -169.462675) (xy 355.866038 -169.470339) (xy 355.856032 -169.470832)
			(xy 354.051616 -169.470832) (xy 354.041547 -169.471257) (xy 354.022948 -169.478977) (xy 354.015548 -169.485818)
			(xy 353.99472 -169.506646) (xy 353.987312 -169.513476) (xy 353.968719 -169.5212) (xy 353.958652 -169.521632)
			(xy 352.06813 -169.521632) (xy 352.05806 -169.521209) (xy 352.039461 -169.513489) (xy 352.032062 -169.506646)
			(xy 351.794826 -169.269156) (xy 351.787978 -169.261762) (xy 351.780262 -169.243158) (xy 351.77984 -169.233088)
			(xy 351.77984 -161.142172) (xy 351.78024 -161.1321) (xy 351.787977 -161.113502) (xy 351.794826 -161.106104)
			(xy 352.381566 -160.51911) (xy 352.388389 -160.511697) (xy 352.39612 -160.493108) (xy 352.396552 -160.483042)
			(xy 352.396552 -159.336232) (xy 352.396122 -159.326163) (xy 352.388406 -159.307564) (xy 352.381566 -159.300164)
			(xy 351.794826 -158.71317) (xy 351.787984 -158.705771) (xy 351.780265 -158.687171) (xy 351.77984 -158.677102)
			(xy 351.77984 -155.49118) (xy 351.779441 -155.481107) (xy 351.771704 -155.462509) (xy 351.764854 -155.455112)
			(xy 351.457006 -155.147518) (xy 351.449596 -155.14069) (xy 351.431004 -155.132963) (xy 351.420938 -155.132532)
			(xy 347.199712 -155.132532) (xy 347.189642 -155.132955) (xy 347.171044 -155.140676) (xy 347.163644 -155.147518)
			(xy 346.743274 -155.567888) (xy 346.736443 -155.575295) (xy 346.728719 -155.593889) (xy 346.728288 -155.603956)
			(xy 346.728288 -156.799534) (xy 347.421454 -156.799534) (xy 347.42194 -156.772283) (xy 347.429696 -156.718335)
			(xy 347.445051 -156.66604) (xy 347.467693 -156.616463) (xy 347.497159 -156.570613) (xy 347.53285 -156.529422)
			(xy 347.574041 -156.493731) (xy 347.619891 -156.464265) (xy 347.669468 -156.441623) (xy 347.721763 -156.426268)
			(xy 347.775711 -156.418512) (xy 347.830213 -156.418512) (xy 347.884161 -156.426268) (xy 347.936456 -156.441623)
			(xy 347.986033 -156.464265) (xy 348.031883 -156.493731) (xy 348.073074 -156.529422) (xy 348.108765 -156.570613)
			(xy 348.138231 -156.616463) (xy 348.160873 -156.66604) (xy 348.165539 -156.681932) (xy 349.311722 -156.681932)
			(xy 349.312208 -156.654681) (xy 349.319964 -156.600733) (xy 349.335319 -156.548438) (xy 349.357961 -156.498861)
			(xy 349.387427 -156.453011) (xy 349.423118 -156.41182) (xy 349.464309 -156.376129) (xy 349.510159 -156.346663)
			(xy 349.559736 -156.324021) (xy 349.612031 -156.308666) (xy 349.665979 -156.30091) (xy 349.720481 -156.30091)
			(xy 349.774429 -156.308666) (xy 349.826724 -156.324021) (xy 349.876301 -156.346663) (xy 349.922151 -156.376129)
			(xy 349.963342 -156.41182) (xy 349.999033 -156.453011) (xy 350.028499 -156.498861) (xy 350.051141 -156.548438)
			(xy 350.066496 -156.600733) (xy 350.074252 -156.654681) (xy 350.074738 -156.681932) (xy 350.074171 -156.711027)
			(xy 350.065334 -156.768541) (xy 350.047854 -156.824042) (xy 350.022138 -156.876241) (xy 349.988784 -156.923922)
			(xy 349.969074 -156.94533) (xy 349.962216 -156.952442) (xy 349.955104 -156.970476) (xy 349.955612 -157.051248)
			(xy 349.956057 -157.060976) (xy 349.963384 -157.079004) (xy 349.969836 -157.0863) (xy 349.989942 -157.107813)
			(xy 350.024011 -157.155835) (xy 350.050299 -157.20852) (xy 350.068182 -157.264619) (xy 350.077236 -157.322798)
			(xy 350.077786 -157.352238) (xy 350.077691 -157.357572) (xy 350.649538 -157.357572) (xy 350.653609 -157.30195)
			(xy 350.665735 -157.247513) (xy 350.685658 -157.195422) (xy 350.712954 -157.146787) (xy 350.74704 -157.102644)
			(xy 350.787189 -157.063935) (xy 350.832547 -157.031484) (xy 350.882147 -157.005983) (xy 350.934931 -156.987976)
			(xy 350.989774 -156.977846) (xy 351.045508 -156.975809) (xy 351.100945 -156.981909) (xy 351.154902 -156.996015)
			(xy 351.206231 -157.017827) (xy 351.253837 -157.046881) (xy 351.296705 -157.082556) (xy 351.333922 -157.124093)
			(xy 351.364695 -157.170606) (xy 351.388367 -157.221103) (xy 351.404435 -157.27451) (xy 351.412555 -157.329686)
			(xy 351.413064 -157.357572) (xy 351.412555 -157.385458) (xy 351.404435 -157.440634) (xy 351.388367 -157.494041)
			(xy 351.364695 -157.544538) (xy 351.333922 -157.591051) (xy 351.296705 -157.632588) (xy 351.253837 -157.668263)
			(xy 351.206231 -157.697317) (xy 351.154902 -157.719129) (xy 351.100945 -157.733235) (xy 351.045508 -157.739335)
			(xy 350.989774 -157.737298) (xy 350.934931 -157.727168) (xy 350.882147 -157.709161) (xy 350.832547 -157.68366)
			(xy 350.787189 -157.651209) (xy 350.74704 -157.6125) (xy 350.712954 -157.568357) (xy 350.685658 -157.519722)
			(xy 350.665735 -157.467631) (xy 350.653609 -157.413194) (xy 350.649538 -157.357572) (xy 350.077691 -157.357572)
			(xy 350.0773 -157.379489) (xy 350.069544 -157.433437) (xy 350.054189 -157.485732) (xy 350.031547 -157.535309)
			(xy 350.002081 -157.581159) (xy 349.96639 -157.62235) (xy 349.925199 -157.658041) (xy 349.879349 -157.687507)
			(xy 349.829772 -157.710149) (xy 349.777477 -157.725504) (xy 349.723529 -157.73326) (xy 349.669027 -157.73326)
			(xy 349.615079 -157.725504) (xy 349.562784 -157.710149) (xy 349.513207 -157.687507) (xy 349.467357 -157.658041)
			(xy 349.426166 -157.62235) (xy 349.390475 -157.581159) (xy 349.361009 -157.535309) (xy 349.338367 -157.485732)
			(xy 349.323012 -157.433437) (xy 349.315256 -157.379489) (xy 349.31477 -157.352238) (xy 349.315343 -157.323144)
			(xy 349.324183 -157.265631) (xy 349.341663 -157.210131) (xy 349.367376 -157.157932) (xy 349.400726 -157.110249)
			(xy 349.420434 -157.08884) (xy 349.427292 -157.081728) (xy 349.434404 -157.063694) (xy 349.433896 -156.982922)
			(xy 349.433413 -156.973198) (xy 349.426112 -156.95517) (xy 349.419672 -156.94787) (xy 349.399553 -156.926369)
			(xy 349.365486 -156.878344) (xy 349.3392 -156.825655) (xy 349.32132 -156.769554) (xy 349.31227 -156.711373)
			(xy 349.311722 -156.681932) (xy 348.165539 -156.681932) (xy 348.176228 -156.718335) (xy 348.183984 -156.772283)
			(xy 348.18447 -156.799534) (xy 348.183812 -156.831097) (xy 348.173425 -156.893362) (xy 348.152938 -156.953071)
			(xy 348.138496 -156.981144) (xy 348.13367 -156.990034) (xy 348.131638 -157.009592) (xy 348.154498 -157.088078)
			(xy 348.157756 -157.097494) (xy 348.170159 -157.113057) (xy 348.178628 -157.118304) (xy 348.185994 -157.122368)
			(xy 348.1959 -157.12821) (xy 348.217744 -157.130242) (xy 348.312486 -157.096714) (xy 348.328234 -157.08122)
			(xy 348.332298 -157.070806) (xy 348.342982 -157.044024) (xy 348.371271 -156.993781) (xy 348.406801 -156.948371)
			(xy 348.448765 -156.908828) (xy 348.496204 -156.876054) (xy 348.548037 -156.850798) (xy 348.603082 -156.833634)
			(xy 348.660084 -156.824954) (xy 348.688914 -156.824426) (xy 348.716167 -156.824845) (xy 348.770118 -156.832604)
			(xy 348.822416 -156.847961) (xy 348.871996 -156.870605) (xy 348.917848 -156.900075) (xy 348.959041 -156.935769)
			(xy 348.994734 -156.976963) (xy 349.024201 -157.022817) (xy 349.046844 -157.072397) (xy 349.062199 -157.124696)
			(xy 349.069956 -157.178647) (xy 349.069956 -157.233153) (xy 349.062199 -157.287104) (xy 349.046844 -157.339403)
			(xy 349.024201 -157.388983) (xy 348.994734 -157.434837) (xy 348.959041 -157.476031) (xy 348.917848 -157.511725)
			(xy 348.871996 -157.541195) (xy 348.822416 -157.563839) (xy 348.770118 -157.579196) (xy 348.716167 -157.586955)
			(xy 348.688914 -157.587442) (xy 348.68866 -157.587442) (xy 348.663456 -157.587063) (xy 348.613487 -157.580417)
			(xy 348.564832 -157.567235) (xy 348.518343 -157.547746) (xy 348.496382 -157.535372) (xy 348.486476 -157.52953)
			(xy 348.464632 -157.527498) (xy 348.36989 -157.561026) (xy 348.354142 -157.57652) (xy 348.350078 -157.586934)
			(xy 348.339352 -157.613697) (xy 348.311066 -157.663936) (xy 348.275539 -157.709344) (xy 348.233582 -157.748886)
			(xy 348.186149 -157.781661) (xy 348.134323 -157.806921) (xy 348.079285 -157.824092) (xy 348.022289 -157.832781)
			(xy 347.993462 -157.833314) (xy 347.96621 -157.832858) (xy 347.912262 -157.825096) (xy 347.859967 -157.809736)
			(xy 347.81039 -157.787091) (xy 347.76454 -157.757622) (xy 347.72335 -157.721927) (xy 347.687659 -157.680735)
			(xy 347.658193 -157.634882) (xy 347.635552 -157.585303) (xy 347.620197 -157.533007) (xy 347.61244 -157.479058)
			(xy 347.611954 -157.451806) (xy 347.612586 -157.420242) (xy 347.622984 -157.357976) (xy 347.643481 -157.298267)
			(xy 347.657928 -157.270196) (xy 347.662754 -157.261306) (xy 347.664786 -157.241748) (xy 347.641926 -157.163262)
			(xy 347.63872 -157.153824) (xy 347.62628 -157.138271) (xy 347.617796 -157.133036) (xy 347.592682 -157.118509)
			(xy 347.5468 -157.083002) (xy 347.506825 -157.040954) (xy 347.473682 -156.993337) (xy 347.448133 -156.941249)
			(xy 347.430769 -156.885891) (xy 347.421991 -156.828542) (xy 347.421454 -156.799534) (xy 346.728288 -156.799534)
			(xy 346.728288 -157.831028) (xy 346.728676 -157.841102) (xy 346.73642 -157.859701) (xy 346.743274 -157.867096)
			(xy 347.1291 -158.252922) (xy 350.070418 -158.252922) (xy 350.074489 -158.1973) (xy 350.086615 -158.142863)
			(xy 350.106538 -158.090772) (xy 350.133834 -158.042137) (xy 350.16792 -157.997994) (xy 350.208069 -157.959285)
			(xy 350.253427 -157.926834) (xy 350.303027 -157.901333) (xy 350.355811 -157.883326) (xy 350.410654 -157.873196)
			(xy 350.466388 -157.871159) (xy 350.521825 -157.877259) (xy 350.575782 -157.891365) (xy 350.627111 -157.913177)
			(xy 350.674717 -157.942231) (xy 350.717585 -157.977906) (xy 350.754802 -158.019443) (xy 350.785575 -158.065956)
			(xy 350.809247 -158.116453) (xy 350.825315 -158.16986) (xy 350.833435 -158.225036) (xy 350.833944 -158.252922)
			(xy 350.833435 -158.280808) (xy 350.825315 -158.335984) (xy 350.809247 -158.389391) (xy 350.785575 -158.439888)
			(xy 350.754802 -158.486401) (xy 350.717585 -158.527938) (xy 350.674717 -158.563613) (xy 350.627111 -158.592667)
			(xy 350.575782 -158.614479) (xy 350.521825 -158.628585) (xy 350.466388 -158.634685) (xy 350.410654 -158.632648)
			(xy 350.355811 -158.622518) (xy 350.303027 -158.604511) (xy 350.253427 -158.57901) (xy 350.208069 -158.546559)
			(xy 350.16792 -158.50785) (xy 350.133834 -158.463707) (xy 350.106538 -158.415072) (xy 350.086615 -158.362981)
			(xy 350.074489 -158.308544) (xy 350.070418 -158.252922) (xy 347.1291 -158.252922) (xy 347.586046 -158.709868)
			(xy 347.592813 -158.717319) (xy 347.600529 -158.735884) (xy 347.601032 -158.745936) (xy 347.601032 -160.129982)
			(xy 351.02927 -160.129982) (xy 351.029757 -160.102071) (xy 351.037894 -160.046845) (xy 351.053991 -159.993394)
			(xy 351.077705 -159.94286) (xy 351.108529 -159.89632) (xy 351.126806 -159.87522) (xy 351.132695 -159.868037)
			(xy 351.139351 -159.850716) (xy 351.13976 -159.841438) (xy 351.13976 -159.763714) (xy 351.133156 -159.746442)
			(xy 351.126806 -159.73933) (xy 351.108522 -159.718236) (xy 351.077695 -159.671696) (xy 351.053981 -159.62116)
			(xy 351.037886 -159.567707) (xy 351.029754 -159.51248) (xy 351.02927 -159.484568) (xy 351.029756 -159.457317)
			(xy 351.037512 -159.403369) (xy 351.052867 -159.351074) (xy 351.075509 -159.301497) (xy 351.104975 -159.255647)
			(xy 351.140666 -159.214456) (xy 351.181857 -159.178765) (xy 351.227707 -159.149299) (xy 351.277284 -159.126657)
			(xy 351.329579 -159.111302) (xy 351.383527 -159.103546) (xy 351.438029 -159.103546) (xy 351.491977 -159.111302)
			(xy 351.544272 -159.126657) (xy 351.593849 -159.149299) (xy 351.639699 -159.178765) (xy 351.68089 -159.214456)
			(xy 351.716581 -159.255647) (xy 351.746047 -159.301497) (xy 351.768689 -159.351074) (xy 351.784044 -159.403369)
			(xy 351.7918 -159.457317) (xy 351.792286 -159.484568) (xy 351.791815 -159.512479) (xy 351.783672 -159.567705)
			(xy 351.767571 -159.621156) (xy 351.743854 -159.67169) (xy 351.713027 -159.71823) (xy 351.69475 -159.73933)
			(xy 351.688834 -159.746494) (xy 351.682196 -159.763829) (xy 351.681796 -159.773112) (xy 351.681796 -159.850836)
			(xy 351.6884 -159.868108) (xy 351.69475 -159.87522) (xy 351.71302 -159.896326) (xy 351.743847 -159.942864)
			(xy 351.767563 -159.993397) (xy 351.783661 -160.046846) (xy 351.791799 -160.102071) (xy 351.792286 -160.129982)
			(xy 351.7918 -160.157233) (xy 351.784044 -160.211181) (xy 351.768689 -160.263476) (xy 351.746047 -160.313053)
			(xy 351.716581 -160.358903) (xy 351.68089 -160.400094) (xy 351.639699 -160.435785) (xy 351.593849 -160.465251)
			(xy 351.544272 -160.487893) (xy 351.491977 -160.503248) (xy 351.438029 -160.511004) (xy 351.383527 -160.511004)
			(xy 351.329579 -160.503248) (xy 351.277284 -160.487893) (xy 351.227707 -160.465251) (xy 351.181857 -160.435785)
			(xy 351.140666 -160.400094) (xy 351.104975 -160.358903) (xy 351.075509 -160.313053) (xy 351.052867 -160.263476)
			(xy 351.037512 -160.211181) (xy 351.029756 -160.157233) (xy 351.02927 -160.129982) (xy 347.601032 -160.129982)
			(xy 347.601032 -161.063432) (xy 347.600539 -161.073438) (xy 347.592875 -161.091924) (xy 347.578724 -161.106075)
			(xy 347.560238 -161.113739) (xy 347.550232 -161.114232) (xy 345.745816 -161.114232) (xy 345.735747 -161.114657)
			(xy 345.717148 -161.122377) (xy 345.709748 -161.129218) (xy 345.68892 -161.150046) (xy 345.681512 -161.156876)
			(xy 345.662919 -161.1646) (xy 345.652852 -161.165032) (xy 340.53018 -161.165032) (xy 340.520107 -161.164635)
			(xy 340.501508 -161.156897) (xy 340.494112 -161.150046) (xy 340.015322 -160.671256) (xy 340.008473 -160.663863)
			(xy 340.000758 -160.645258) (xy 340.000336 -160.635188) (xy 328.169811 -160.635188) (xy 328.162805 -160.812169)
			(xy 328.146385 -161.019531) (xy 328.121801 -161.226085) (xy 328.089089 -161.431509) (xy 328.048301 -161.635482)
			(xy 327.999499 -161.837688) (xy 327.942761 -162.037813) (xy 327.910952 -162.136836) (xy 327.908521 -162.14584)
			(xy 327.909565 -162.164447) (xy 327.917153 -162.181468) (xy 327.923398 -162.188398) (xy 332.579218 -166.844218)
			(xy 335.512662 -166.844218) (xy 335.516733 -166.788596) (xy 335.528859 -166.734159) (xy 335.548782 -166.682068)
			(xy 335.576078 -166.633433) (xy 335.610164 -166.58929) (xy 335.650313 -166.550581) (xy 335.695671 -166.51813)
			(xy 335.745271 -166.492629) (xy 335.798055 -166.474622) (xy 335.852898 -166.464492) (xy 335.908632 -166.462455)
			(xy 335.964069 -166.468555) (xy 336.018026 -166.482661) (xy 336.069355 -166.504473) (xy 336.116961 -166.533527)
			(xy 336.159829 -166.569202) (xy 336.197046 -166.610739) (xy 336.227819 -166.657252) (xy 336.251491 -166.707749)
			(xy 336.267559 -166.761156) (xy 336.275679 -166.816332) (xy 336.275877 -166.8272) (xy 336.583526 -166.8272)
			(xy 336.587597 -166.771578) (xy 336.599723 -166.717141) (xy 336.619646 -166.66505) (xy 336.646942 -166.616415)
			(xy 336.681028 -166.572272) (xy 336.721177 -166.533563) (xy 336.766535 -166.501112) (xy 336.816135 -166.475611)
			(xy 336.868919 -166.457604) (xy 336.923762 -166.447474) (xy 336.979496 -166.445437) (xy 337.034933 -166.451537)
			(xy 337.08889 -166.465643) (xy 337.140219 -166.487455) (xy 337.187825 -166.516509) (xy 337.230693 -166.552184)
			(xy 337.26791 -166.593721) (xy 337.298683 -166.640234) (xy 337.322355 -166.690731) (xy 337.338423 -166.744138)
			(xy 337.346543 -166.799314) (xy 337.347052 -166.8272) (xy 337.346543 -166.855086) (xy 337.338423 -166.910262)
			(xy 337.322355 -166.963669) (xy 337.298683 -167.014166) (xy 337.26791 -167.060679) (xy 337.230693 -167.102216)
			(xy 337.187825 -167.137891) (xy 337.140219 -167.166945) (xy 337.08889 -167.188757) (xy 337.034933 -167.202863)
			(xy 336.979496 -167.208963) (xy 336.923762 -167.206926) (xy 336.868919 -167.196796) (xy 336.816135 -167.178789)
			(xy 336.766535 -167.153288) (xy 336.721177 -167.120837) (xy 336.681028 -167.082128) (xy 336.646942 -167.037985)
			(xy 336.619646 -166.98935) (xy 336.599723 -166.937259) (xy 336.587597 -166.882822) (xy 336.583526 -166.8272)
			(xy 336.275877 -166.8272) (xy 336.276188 -166.844218) (xy 336.275679 -166.872104) (xy 336.267559 -166.92728)
			(xy 336.251491 -166.980687) (xy 336.227819 -167.031184) (xy 336.197046 -167.077697) (xy 336.159829 -167.119234)
			(xy 336.116961 -167.154909) (xy 336.069355 -167.183963) (xy 336.018026 -167.205775) (xy 335.964069 -167.219881)
			(xy 335.908632 -167.225981) (xy 335.852898 -167.223944) (xy 335.798055 -167.213814) (xy 335.745271 -167.195807)
			(xy 335.695671 -167.170306) (xy 335.650313 -167.137855) (xy 335.610164 -167.099146) (xy 335.576078 -167.055003)
			(xy 335.548782 -167.006368) (xy 335.528859 -166.954277) (xy 335.516733 -166.89984) (xy 335.512662 -166.844218)
			(xy 332.579218 -166.844218) (xy 337.736434 -172.001434) (xy 337.743831 -172.008282) (xy 337.76243 -172.016015)
			(xy 337.772502 -172.01642) (xy 340.035642 -172.01642) (xy 340.04441 -172.015969) (xy 340.060874 -172.009906)
			(xy 340.074349 -171.99867) (xy 340.079076 -171.991274) (xy 340.081108 -171.987464) (xy 340.081362 -171.98721)
			(xy 340.095314 -171.95954) (xy 340.130794 -171.908739) (xy 340.151974 -171.886118) (xy 340.15934 -171.878498)
			(xy 340.162896 -171.869862) (xy 340.164607 -171.86529) (xy 340.166398 -171.855694) (xy 340.166452 -171.850812)
			(xy 340.166452 -171.779438) (xy 340.166314 -171.774689) (xy 340.16453 -171.765357) (xy 340.162896 -171.760896)
			(xy 340.15934 -171.751752) (xy 340.151974 -171.744386) (xy 340.131797 -171.722888) (xy 340.097643 -171.674832)
			(xy 340.071289 -171.622093) (xy 340.053364 -171.565927) (xy 340.044294 -171.507672) (xy 340.04377 -171.478194)
			(xy 340.044256 -171.450943) (xy 340.052012 -171.396995) (xy 340.067367 -171.3447) (xy 340.090009 -171.295123)
			(xy 340.119475 -171.249273) (xy 340.155166 -171.208082) (xy 340.196357 -171.172391) (xy 340.242207 -171.142925)
			(xy 340.291784 -171.120283) (xy 340.344079 -171.104928) (xy 340.398027 -171.097172) (xy 340.452529 -171.097172)
			(xy 340.506477 -171.104928) (xy 340.558772 -171.120283) (xy 340.608349 -171.142925) (xy 340.654199 -171.172391)
			(xy 340.69539 -171.208082) (xy 340.731081 -171.249273) (xy 340.760547 -171.295123) (xy 340.783189 -171.3447)
			(xy 340.798544 -171.396995) (xy 340.8063 -171.450943) (xy 340.806786 -171.478194) (xy 340.806246 -171.507565)
			(xy 340.797248 -171.565613) (xy 340.779462 -171.621597) (xy 340.753308 -171.674196) (xy 340.719405 -171.722166)
			(xy 340.699344 -171.743624) (xy 340.698836 -171.744132) (xy 340.695313 -171.747861) (xy 340.689681 -171.756435)
			(xy 340.68766 -171.76115) (xy 340.684104 -171.769786) (xy 340.684104 -171.850812) (xy 340.684197 -171.85569)
			(xy 340.68598 -171.865281) (xy 340.68766 -171.869862) (xy 340.691216 -171.878498) (xy 340.698582 -171.886118)
			(xy 340.719768 -171.908734) (xy 340.755253 -171.959534) (xy 340.769194 -171.98721) (xy 340.769448 -171.987464)
			(xy 340.77148 -171.991274) (xy 340.776217 -171.998669) (xy 340.789668 -172.009938) (xy 340.806142 -172.01598)
			(xy 340.814914 -172.01642) (xy 350.30029 -172.01642) (xy 350.310361 -172.016842) (xy 350.328966 -172.024556)
			(xy 350.336358 -172.031406) (xy 372.32082 -194.015868) (xy 372.323672 -194.018573) (xy 372.330051 -194.023163)
			(xy 372.33352 -194.025012) (xy 372.338947 -194.027597) (xy 372.350626 -194.030425) (xy 372.356634 -194.0306)
		)
		(stroke
			(width 0)
			(type solid)
		)
		(fill yes)
		(layer "In13.Cu")
		(net "GND")
	)
	(gr_poly
		(pts
			(xy 32.32912 -371.705632) (xy 32.33547 -371.69217) (xy 32.347417 -371.668087) (xy 32.377072 -371.623248)
			(xy 32.41273 -371.583019) (xy 32.453686 -371.548197) (xy 32.499127 -371.519472) (xy 32.548152 -371.497416)
			(xy 32.599789 -371.482463) (xy 32.653015 -371.474913) (xy 32.706773 -371.474913) (xy 32.759999 -371.482463)
			(xy 32.811636 -371.497416) (xy 32.860661 -371.519472) (xy 32.906102 -371.548197) (xy 32.947058 -371.583019)
			(xy 32.982716 -371.623248) (xy 33.012371 -371.668087) (xy 33.024318 -371.69217) (xy 33.030668 -371.705632)
			(xy 33.05556 -371.721126) (xy 39.293292 -371.721126) (xy 39.303363 -371.720705) (xy 39.321972 -371.712996)
			(xy 39.32936 -371.70614) (xy 46.864016 -364.171738) (xy 46.871414 -364.16489) (xy 46.890012 -364.157155)
			(xy 46.900084 -364.156752) (xy 51.300634 -364.156752) (xy 51.3107 -364.156321) (xy 51.329291 -364.148593)
			(xy 51.336702 -364.141766) (xy 54.66969 -360.808778) (xy 54.676534 -360.801379) (xy 54.684262 -360.782781)
			(xy 54.684676 -360.77271) (xy 54.684676 -359.489756) (xy 54.685171 -359.479752) (xy 54.692838 -359.461271)
			(xy 54.706988 -359.447126) (xy 54.725472 -359.439467) (xy 54.735476 -359.438956) (xy 96.375728 -359.438956)
			(xy 96.385795 -359.438526) (xy 96.404388 -359.4308) (xy 96.411796 -359.42397) (xy 106.522266 -349.3135)
			(xy 106.529668 -349.306664) (xy 106.548266 -349.298953) (xy 106.558334 -349.298514) (xy 120.010936 -349.298514)
			(xy 120.021004 -349.298085) (xy 120.0396 -349.290363) (xy 120.047004 -349.283528) (xy 120.598692 -348.73184)
			(xy 120.60553 -348.724439) (xy 120.613244 -348.70584) (xy 120.613678 -348.695772) (xy 120.613678 -330.813664)
			(xy 120.613248 -330.803597) (xy 120.605522 -330.785004) (xy 120.598692 -330.777596) (xy 117.64772 -327.826624)
			(xy 117.640318 -327.819788) (xy 117.62172 -327.812078) (xy 117.611652 -327.811638) (xy 111.302546 -327.811638)
			(xy 111.291521 -327.812167) (xy 111.271484 -327.821367) (xy 111.263938 -327.829418) (xy 111.245733 -327.850096)
			(xy 111.20439 -327.886509) (xy 111.158238 -327.916593) (xy 111.108236 -327.939722) (xy 111.055426 -327.955414)
			(xy 111.000908 -327.963343) (xy 110.945816 -327.963343) (xy 110.891298 -327.955414) (xy 110.838488 -327.939722)
			(xy 110.788486 -327.916593) (xy 110.742334 -327.886509) (xy 110.700991 -327.850096) (xy 110.682786 -327.829418)
			(xy 110.675214 -327.821394) (xy 110.655197 -327.812176) (xy 110.644178 -327.811638) (xy 106.9975 -327.811638)
			(xy 106.986751 -327.812114) (xy 106.967145 -327.820932) (xy 106.959654 -327.828656) (xy 106.901742 -327.89368)
			(xy 106.895392 -327.914) (xy 106.896662 -327.925176) (xy 106.897866 -327.936249) (xy 106.899139 -327.958488)
			(xy 106.899202 -327.969626) (xy 106.898714 -327.996876) (xy 106.890955 -328.05082) (xy 106.875597 -328.103112)
			(xy 106.852955 -328.152685) (xy 106.823488 -328.198532) (xy 106.787796 -328.239719) (xy 106.746606 -328.275407)
			(xy 106.700757 -328.30487) (xy 106.651182 -328.327509) (xy 106.598889 -328.342862) (xy 106.544944 -328.350617)
			(xy 106.517694 -328.351134) (xy 106.490324 -328.350662) (xy 106.436148 -328.342836) (xy 106.383646 -328.327346)
			(xy 106.333898 -328.30451) (xy 106.287925 -328.274798) (xy 106.266996 -328.257154) (xy 106.259884 -328.251058)
			(xy 106.242866 -328.244708) (xy 106.157522 -328.244708) (xy 106.140504 -328.251058) (xy 106.133392 -328.257154)
			(xy 106.112459 -328.274795) (xy 106.066491 -328.304519) (xy 106.016745 -328.327365) (xy 105.964243 -328.342861)
			(xy 105.910065 -328.35069) (xy 105.855323 -328.35069) (xy 105.801145 -328.342861) (xy 105.748643 -328.327365)
			(xy 105.698897 -328.304519) (xy 105.652929 -328.274795) (xy 105.631996 -328.257154) (xy 105.624884 -328.251058)
			(xy 105.607866 -328.244708) (xy 105.522522 -328.244708) (xy 105.505504 -328.251058) (xy 105.498392 -328.257154)
			(xy 105.477461 -328.274797) (xy 105.431496 -328.304526) (xy 105.381749 -328.327371) (xy 105.329245 -328.342862)
			(xy 105.275065 -328.350681) (xy 105.247694 -328.351134) (xy 105.220442 -328.350648) (xy 105.166494 -328.342891)
			(xy 105.114198 -328.327535) (xy 105.06462 -328.304894) (xy 105.018769 -328.275428) (xy 104.977577 -328.239737)
			(xy 104.941884 -328.198547) (xy 104.912415 -328.152697) (xy 104.889772 -328.10312) (xy 104.874413 -328.050826)
			(xy 104.866654 -327.996878) (xy 104.866186 -327.969626) (xy 104.866251 -327.958488) (xy 104.867523 -327.936249)
			(xy 104.868726 -327.925176) (xy 104.869996 -327.914) (xy 104.863646 -327.89368) (xy 104.805734 -327.828656)
			(xy 104.798169 -327.821034) (xy 104.77861 -327.812227) (xy 104.767888 -327.811638) (xy 102.955344 -327.811638)
			(xy 102.944238 -327.812204) (xy 102.924092 -327.821562) (xy 102.916482 -327.829672) (xy 102.859078 -327.897744)
			(xy 102.853236 -327.91908) (xy 102.855014 -327.93051) (xy 102.857605 -327.946514) (xy 102.860399 -327.978815)
			(xy 102.860602 -327.995026) (xy 102.860114 -328.022276) (xy 102.852355 -328.07622) (xy 102.836997 -328.128512)
			(xy 102.814355 -328.178085) (xy 102.784888 -328.223932) (xy 102.749196 -328.265119) (xy 102.708006 -328.300807)
			(xy 102.662157 -328.33027) (xy 102.612582 -328.352909) (xy 102.560289 -328.368262) (xy 102.506344 -328.376017)
			(xy 102.479094 -328.376534) (xy 102.451724 -328.376062) (xy 102.397548 -328.368236) (xy 102.345046 -328.352746)
			(xy 102.295298 -328.32991) (xy 102.249325 -328.300198) (xy 102.228396 -328.282554) (xy 102.221284 -328.276458)
			(xy 102.204266 -328.270108) (xy 102.118922 -328.270108) (xy 102.101904 -328.276458) (xy 102.094792 -328.282554)
			(xy 102.073859 -328.300195) (xy 102.027891 -328.329919) (xy 101.978145 -328.352765) (xy 101.925643 -328.368261)
			(xy 101.871465 -328.37609) (xy 101.816723 -328.37609) (xy 101.762545 -328.368261) (xy 101.710043 -328.352765)
			(xy 101.660297 -328.329919) (xy 101.614329 -328.300195) (xy 101.593396 -328.282554) (xy 101.586284 -328.276458)
			(xy 101.569266 -328.270108) (xy 101.483922 -328.270108) (xy 101.466904 -328.276458) (xy 101.459792 -328.282554)
			(xy 101.438861 -328.300197) (xy 101.392896 -328.329926) (xy 101.343149 -328.352771) (xy 101.290645 -328.368262)
			(xy 101.236465 -328.376081) (xy 101.209094 -328.376534) (xy 101.181842 -328.376048) (xy 101.127894 -328.368291)
			(xy 101.075598 -328.352935) (xy 101.02602 -328.330294) (xy 100.980169 -328.300828) (xy 100.938977 -328.265137)
			(xy 100.903284 -328.223947) (xy 100.873815 -328.178097) (xy 100.851172 -328.12852) (xy 100.835813 -328.076226)
			(xy 100.828054 -328.022278) (xy 100.827586 -327.995026) (xy 100.827775 -327.978815) (xy 100.830572 -327.946512)
			(xy 100.833174 -327.93051) (xy 100.834952 -327.91908) (xy 100.82911 -327.897744) (xy 100.771706 -327.829672)
			(xy 100.764113 -327.821544) (xy 100.743954 -327.812209) (xy 100.732844 -327.811638) (xy 65.46215 -327.811638)
			(xy 65.452085 -327.812071) (xy 65.433497 -327.819802) (xy 65.426082 -327.826624) (xy 64.524382 -328.728324)
			(xy 64.51753 -328.73572) (xy 64.509792 -328.754319) (xy 64.509396 -328.764392) (xy 64.509396 -334.777334)
			(xy 64.508966 -334.787401) (xy 64.501243 -334.805996) (xy 64.49441 -334.813402) (xy 63.895224 -335.412588)
			(xy 63.887822 -335.419424) (xy 63.869224 -335.427132) (xy 63.859156 -335.427574) (xy 22.376384 -335.427574)
			(xy 22.366315 -335.427999) (xy 22.347712 -335.435715) (xy 22.340316 -335.44256) (xy 21.275802 -336.507074)
			(xy 21.268967 -336.514477) (xy 21.261259 -336.533075) (xy 21.260816 -336.543142) (xy 21.260816 -336.654902)
			(xy 66.344546 -336.654902) (xy 66.345051 -336.626992) (xy 66.353184 -336.571767) (xy 66.369277 -336.518317)
			(xy 66.392987 -336.467782) (xy 66.423807 -336.421241) (xy 66.442082 -336.40014) (xy 66.448432 -336.393028)
			(xy 66.455036 -336.375756) (xy 66.455036 -336.288634) (xy 66.448432 -336.271362) (xy 66.442082 -336.26425)
			(xy 66.423803 -336.243151) (xy 66.392977 -336.196612) (xy 66.369262 -336.146077) (xy 66.353165 -336.092626)
			(xy 66.345031 -336.037399) (xy 66.344546 -336.009488) (xy 66.345032 -335.982237) (xy 66.352788 -335.928289)
			(xy 66.368143 -335.875994) (xy 66.390785 -335.826417) (xy 66.420251 -335.780567) (xy 66.455942 -335.739376)
			(xy 66.497133 -335.703685) (xy 66.542983 -335.674219) (xy 66.59256 -335.651577) (xy 66.644855 -335.636222)
			(xy 66.698803 -335.628466) (xy 66.753305 -335.628466) (xy 66.807253 -335.636222) (xy 66.859548 -335.651577)
			(xy 66.909125 -335.674219) (xy 66.954975 -335.703685) (xy 66.996166 -335.739376) (xy 67.031857 -335.780567)
			(xy 67.061323 -335.826417) (xy 67.083965 -335.875994) (xy 67.09932 -335.928289) (xy 67.107076 -335.982237)
			(xy 67.107562 -336.009488) (xy 67.107049 -336.037398) (xy 67.098918 -336.092622) (xy 67.082826 -336.146072)
			(xy 67.059118 -336.196607) (xy 67.0283 -336.243149) (xy 67.010026 -336.26425) (xy 67.003676 -336.271362)
			(xy 66.997072 -336.288634) (xy 66.997072 -336.375756) (xy 67.003676 -336.393028) (xy 67.010026 -336.40014)
			(xy 67.028301 -336.421242) (xy 67.059128 -336.46778) (xy 67.082844 -336.518314) (xy 67.098941 -336.571765)
			(xy 67.107076 -336.626991) (xy 67.107562 -336.654902) (xy 67.107076 -336.682153) (xy 67.09932 -336.736101)
			(xy 67.083965 -336.788396) (xy 67.061323 -336.837973) (xy 67.031857 -336.883823) (xy 66.996166 -336.925014)
			(xy 66.954975 -336.960705) (xy 66.911881 -336.9884) (xy 70.726737 -336.9884) (xy 70.730906 -336.93278)
			(xy 70.743318 -336.878402) (xy 70.763696 -336.826482) (xy 70.791586 -336.778179) (xy 70.826364 -336.734573)
			(xy 70.867252 -336.696638) (xy 70.913338 -336.66522) (xy 70.963593 -336.641023) (xy 71.016892 -336.624587)
			(xy 71.072046 -336.616279) (xy 71.099934 -336.615786) (xy 71.126356 -336.616227) (xy 71.178672 -336.623682)
			(xy 71.229411 -336.638451) (xy 71.277555 -336.660238) (xy 71.322139 -336.688607) (xy 71.342504 -336.705448)
			(xy 71.349362 -336.711544) (xy 71.36638 -336.71764) (xy 71.450708 -336.71764) (xy 71.467726 -336.711544)
			(xy 71.474584 -336.705448) (xy 71.49495 -336.688609) (xy 71.539536 -336.660244) (xy 71.58768 -336.638457)
			(xy 71.638417 -336.623686) (xy 71.690732 -336.616226) (xy 71.743576 -336.616226) (xy 71.795891 -336.623686)
			(xy 71.846628 -336.638457) (xy 71.894772 -336.660244) (xy 71.939358 -336.688609) (xy 71.959724 -336.705448)
			(xy 71.966582 -336.711544) (xy 71.9836 -336.71764) (xy 72.067928 -336.71764) (xy 72.084946 -336.711544)
			(xy 72.091804 -336.705448) (xy 72.114863 -336.686472) (xy 72.165817 -336.655339) (xy 72.221092 -336.632749)
			(xy 72.250046 -336.625438) (xy 72.262238 -336.622644) (xy 72.281288 -336.606134) (xy 72.320658 -336.504026)
			(xy 72.31761 -336.47888) (xy 72.310244 -336.468466) (xy 72.294537 -336.444928) (xy 72.269667 -336.3941)
			(xy 72.252765 -336.340098) (xy 72.244219 -336.284161) (xy 72.243696 -336.255868) (xy 72.244216 -336.228245)
			(xy 72.252371 -336.173604) (xy 72.268511 -336.120768) (xy 72.292282 -336.070897) (xy 72.323162 -336.025087)
			(xy 72.360473 -335.984344) (xy 72.381618 -335.966562) (xy 72.390193 -335.959005) (xy 72.399964 -335.938361)
			(xy 72.400414 -335.926938) (xy 72.400414 -335.848198) (xy 72.399824 -335.836812) (xy 72.390056 -335.816242)
			(xy 72.381618 -335.808574) (xy 72.360455 -335.790813) (xy 72.323146 -335.750063) (xy 72.292267 -335.704249)
			(xy 72.268496 -335.654375) (xy 72.252354 -335.601536) (xy 72.244196 -335.546893) (xy 72.243696 -335.519268)
			(xy 72.244217 -335.491383) (xy 72.252529 -335.436236) (xy 72.268967 -335.382944) (xy 72.293165 -335.332698)
			(xy 72.324581 -335.286619) (xy 72.362514 -335.245737) (xy 72.406116 -335.210965) (xy 72.454414 -335.18308)
			(xy 72.506329 -335.162705) (xy 72.5607 -335.150295) (xy 72.616314 -335.146128) (xy 72.671928 -335.150295)
			(xy 72.726299 -335.162705) (xy 72.778214 -335.18308) (xy 72.826512 -335.210965) (xy 72.870114 -335.245737)
			(xy 72.908047 -335.286619) (xy 72.939463 -335.332698) (xy 72.963661 -335.382944) (xy 72.980099 -335.436236)
			(xy 72.988411 -335.491383) (xy 72.988932 -335.519268) (xy 72.988427 -335.546892) (xy 72.980268 -335.601533)
			(xy 72.964124 -335.654369) (xy 72.94035 -335.704239) (xy 72.909468 -335.750049) (xy 72.872155 -335.790792)
			(xy 72.85101 -335.808574) (xy 72.842469 -335.816163) (xy 72.832678 -335.836782) (xy 72.832214 -335.848198)
			(xy 72.832214 -335.926938) (xy 72.832831 -335.938321) (xy 72.842579 -335.958892) (xy 72.85101 -335.966562)
			(xy 72.872148 -335.984351) (xy 72.909458 -336.025096) (xy 72.940339 -336.070905) (xy 72.964114 -336.120773)
			(xy 72.980261 -336.173606) (xy 72.988427 -336.228245) (xy 72.988932 -336.255868) (xy 72.988393 -336.283672)
			(xy 72.980133 -336.338664) (xy 72.963792 -336.391817) (xy 72.939733 -336.441952) (xy 72.90849 -336.487954)
			(xy 72.870758 -336.528802) (xy 72.827373 -336.563589) (xy 72.779301 -336.591541) (xy 72.727608 -336.612039)
			(xy 72.700642 -336.618834) (xy 72.68845 -336.621628) (xy 72.6694 -336.638138) (xy 72.665678 -336.64779)
			(xy 74.70013 -336.64779) (xy 74.700632 -336.61988) (xy 74.708766 -336.564655) (xy 74.724861 -336.511205)
			(xy 74.748571 -336.46067) (xy 74.779391 -336.414129) (xy 74.797666 -336.393028) (xy 74.804016 -336.385916)
			(xy 74.81062 -336.368644) (xy 74.81062 -336.281522) (xy 74.804016 -336.26425) (xy 74.797666 -336.257138)
			(xy 74.779379 -336.236046) (xy 74.748554 -336.189505) (xy 74.724841 -336.138968) (xy 74.708747 -336.085516)
			(xy 74.700614 -336.030288) (xy 74.70013 -336.002376) (xy 74.700616 -335.975125) (xy 74.708372 -335.921177)
			(xy 74.723727 -335.868882) (xy 74.746369 -335.819305) (xy 74.775835 -335.773455) (xy 74.811526 -335.732264)
			(xy 74.852717 -335.696573) (xy 74.898567 -335.667107) (xy 74.948144 -335.644465) (xy 75.000439 -335.62911)
			(xy 75.054387 -335.621354) (xy 75.108889 -335.621354) (xy 75.162837 -335.62911) (xy 75.215132 -335.644465)
			(xy 75.264709 -335.667107) (xy 75.310559 -335.696573) (xy 75.35175 -335.732264) (xy 75.387441 -335.773455)
			(xy 75.416907 -335.819305) (xy 75.439549 -335.868882) (xy 75.454904 -335.921177) (xy 75.46266 -335.975125)
			(xy 75.463146 -336.002376) (xy 75.46263 -336.030286) (xy 75.4545 -336.08551) (xy 75.438409 -336.13896)
			(xy 75.414702 -336.189496) (xy 75.383884 -336.236037) (xy 75.36561 -336.257138) (xy 75.35926 -336.26425)
			(xy 75.352656 -336.281522) (xy 75.352656 -336.368644) (xy 75.35926 -336.385916) (xy 75.36561 -336.393028)
			(xy 75.383877 -336.414137) (xy 75.414706 -336.460673) (xy 75.438423 -336.511205) (xy 75.454522 -336.564654)
			(xy 75.462659 -336.619879) (xy 75.463146 -336.64779) (xy 75.46266 -336.675041) (xy 75.454904 -336.728989)
			(xy 75.439549 -336.781284) (xy 75.416907 -336.830861) (xy 75.387441 -336.876711) (xy 75.35175 -336.917902)
			(xy 75.310559 -336.953593) (xy 75.267446 -336.9813) (xy 79.082325 -336.9813) (xy 79.086494 -336.92568)
			(xy 79.098906 -336.871302) (xy 79.119284 -336.819381) (xy 79.147173 -336.771078) (xy 79.18195 -336.727471)
			(xy 79.222838 -336.689534) (xy 79.268923 -336.658115) (xy 79.319177 -336.633917) (xy 79.372476 -336.617478)
			(xy 79.42763 -336.609168) (xy 79.455518 -336.608674) (xy 79.48194 -336.609127) (xy 79.534255 -336.616579)
			(xy 79.584994 -336.631346) (xy 79.633138 -336.65313) (xy 79.677723 -336.681496) (xy 79.698088 -336.698336)
			(xy 79.704946 -336.704432) (xy 79.721964 -336.710528) (xy 79.806292 -336.710528) (xy 79.82331 -336.704432)
			(xy 79.830168 -336.698336) (xy 79.850534 -336.681497) (xy 79.89512 -336.653132) (xy 79.943264 -336.631345)
			(xy 79.994001 -336.616574) (xy 80.046316 -336.609114) (xy 80.09916 -336.609114) (xy 80.151475 -336.616574)
			(xy 80.202212 -336.631345) (xy 80.250356 -336.653132) (xy 80.294942 -336.681497) (xy 80.315308 -336.698336)
			(xy 80.322166 -336.704432) (xy 80.339184 -336.710528) (xy 80.423512 -336.710528) (xy 80.44053 -336.704432)
			(xy 80.447388 -336.698336) (xy 80.471196 -336.678767) (xy 80.523961 -336.646931) (xy 80.581236 -336.624189)
			(xy 80.611218 -336.617056) (xy 80.623664 -336.614516) (xy 80.642968 -336.597752) (xy 80.6831 -336.49539)
			(xy 80.680052 -336.46999) (xy 80.67294 -336.459576) (xy 80.657025 -336.435937) (xy 80.631775 -336.384853)
			(xy 80.614606 -336.330517) (xy 80.60592 -336.2742) (xy 80.605376 -336.245708) (xy 80.605861 -336.218084)
			(xy 80.614024 -336.163441) (xy 80.630172 -336.110605) (xy 80.653949 -336.060735) (xy 80.684835 -336.014926)
			(xy 80.722151 -335.974183) (xy 80.743298 -335.956402) (xy 80.751852 -335.948824) (xy 80.761635 -335.928196)
			(xy 80.762094 -335.916778) (xy 80.762094 -335.838038) (xy 80.761488 -335.826654) (xy 80.751732 -335.806083)
			(xy 80.743298 -335.798414) (xy 80.72215 -335.780636) (xy 80.684841 -335.739889) (xy 80.653961 -335.694078)
			(xy 80.630187 -335.644208) (xy 80.614042 -335.591372) (xy 80.605879 -335.536732) (xy 80.605376 -335.509108)
			(xy 80.605897 -335.481223) (xy 80.614209 -335.426076) (xy 80.630647 -335.372784) (xy 80.654845 -335.322538)
			(xy 80.686261 -335.276459) (xy 80.724194 -335.235577) (xy 80.767796 -335.200805) (xy 80.816094 -335.17292)
			(xy 80.868009 -335.152545) (xy 80.92238 -335.140135) (xy 80.977994 -335.135968) (xy 81.033608 -335.140135)
			(xy 81.087979 -335.152545) (xy 81.139894 -335.17292) (xy 81.188192 -335.200805) (xy 81.231794 -335.235577)
			(xy 81.269727 -335.276459) (xy 81.301143 -335.322538) (xy 81.325341 -335.372784) (xy 81.341779 -335.426076)
			(xy 81.350091 -335.481223) (xy 81.350612 -335.509108) (xy 81.350142 -335.536733) (xy 81.341977 -335.591376)
			(xy 81.325827 -335.644213) (xy 81.302046 -335.694083) (xy 81.271157 -335.739892) (xy 81.233838 -335.780634)
			(xy 81.21269 -335.798414) (xy 81.204127 -335.805983) (xy 81.194349 -335.826618) (xy 81.193894 -335.838038)
			(xy 81.193894 -335.916778) (xy 81.194495 -335.928162) (xy 81.204255 -335.948733) (xy 81.21269 -335.956402)
			(xy 81.233843 -335.974174) (xy 81.271153 -336.014922) (xy 81.302032 -336.060734) (xy 81.325805 -336.110606)
			(xy 81.341949 -336.163442) (xy 81.35011 -336.218084) (xy 81.350612 -336.245708) (xy 81.350052 -336.273832)
			(xy 81.34161 -336.329444) (xy 81.324904 -336.383154) (xy 81.300313 -336.433743) (xy 81.268398 -336.48006)
			(xy 81.229882 -336.521053) (xy 81.185641 -336.55579) (xy 81.136681 -336.583482) (xy 81.084115 -336.603499)
			(xy 81.056734 -336.609944) (xy 81.044288 -336.612484) (xy 81.024984 -336.629248) (xy 81.023391 -336.633312)
			(xy 83.057746 -336.633312) (xy 83.058257 -336.605402) (xy 83.066389 -336.550177) (xy 83.08248 -336.496727)
			(xy 83.106189 -336.446192) (xy 83.137008 -336.399651) (xy 83.155282 -336.37855) (xy 83.161632 -336.371438)
			(xy 83.168236 -336.354166) (xy 83.168236 -336.267044) (xy 83.161632 -336.249772) (xy 83.155282 -336.24266)
			(xy 83.137008 -336.221557) (xy 83.106181 -336.175019) (xy 83.082465 -336.124486) (xy 83.066367 -336.071035)
			(xy 83.058232 -336.015809) (xy 83.057746 -335.987898) (xy 83.058232 -335.960647) (xy 83.065988 -335.906699)
			(xy 83.081343 -335.854404) (xy 83.103985 -335.804827) (xy 83.133451 -335.758977) (xy 83.169142 -335.717786)
			(xy 83.210333 -335.682095) (xy 83.256183 -335.652629) (xy 83.30576 -335.629987) (xy 83.358055 -335.614632)
			(xy 83.412003 -335.606876) (xy 83.466505 -335.606876) (xy 83.520453 -335.614632) (xy 83.572748 -335.629987)
			(xy 83.622325 -335.652629) (xy 83.668175 -335.682095) (xy 83.709366 -335.717786) (xy 83.745057 -335.758977)
			(xy 83.774523 -335.804827) (xy 83.797165 -335.854404) (xy 83.81252 -335.906699) (xy 83.820276 -335.960647)
			(xy 83.820762 -335.987898) (xy 83.820255 -336.015808) (xy 83.812122 -336.071033) (xy 83.796029 -336.124483)
			(xy 83.77232 -336.175018) (xy 83.7415 -336.221559) (xy 83.723226 -336.24266) (xy 83.716876 -336.249772)
			(xy 83.710272 -336.267044) (xy 83.710272 -336.354166) (xy 83.716876 -336.371438) (xy 83.723226 -336.37855)
			(xy 83.741506 -336.399648) (xy 83.772332 -336.446187) (xy 83.796047 -336.496722) (xy 83.812143 -336.550174)
			(xy 83.820277 -336.605401) (xy 83.820762 -336.633312) (xy 83.820276 -336.660563) (xy 83.81252 -336.714511)
			(xy 83.797165 -336.766806) (xy 83.774523 -336.816383) (xy 83.745057 -336.862233) (xy 83.709366 -336.903424)
			(xy 83.668175 -336.939115) (xy 83.625096 -336.9668) (xy 87.439947 -336.9668) (xy 87.444116 -336.911181)
			(xy 87.456528 -336.856805) (xy 87.476905 -336.804886) (xy 87.504794 -336.756585) (xy 87.539571 -336.71298)
			(xy 87.580458 -336.675045) (xy 87.626543 -336.643629) (xy 87.676796 -336.619433) (xy 87.730094 -336.602997)
			(xy 87.785247 -336.594688) (xy 87.813134 -336.594196) (xy 87.839556 -336.594635) (xy 87.891873 -336.60209)
			(xy 87.942611 -336.616859) (xy 87.990755 -336.638647) (xy 88.035339 -336.667017) (xy 88.055704 -336.683858)
			(xy 88.062562 -336.689954) (xy 88.07958 -336.69605) (xy 88.163908 -336.69605) (xy 88.180926 -336.689954)
			(xy 88.187784 -336.683858) (xy 88.20815 -336.667019) (xy 88.252736 -336.638654) (xy 88.30088 -336.616867)
			(xy 88.351617 -336.602096) (xy 88.403932 -336.594636) (xy 88.456776 -336.594636) (xy 88.509091 -336.602096)
			(xy 88.559828 -336.616867) (xy 88.607972 -336.638654) (xy 88.652558 -336.667019) (xy 88.672924 -336.683858)
			(xy 88.679782 -336.689954) (xy 88.6968 -336.69605) (xy 88.781128 -336.69605) (xy 88.798146 -336.689954)
			(xy 88.805004 -336.683858) (xy 88.825835 -336.666667) (xy 88.871508 -336.637844) (xy 88.920863 -336.615915)
			(xy 88.946736 -336.608166) (xy 88.95842 -336.604864) (xy 88.9762 -336.588608) (xy 89.013792 -336.489802)
			(xy 89.011506 -336.465926) (xy 89.004902 -336.455766) (xy 88.99112 -336.43326) (xy 88.969376 -336.385174)
			(xy 88.954635 -336.334501) (xy 88.947192 -336.282255) (xy 88.946736 -336.255868) (xy 88.947278 -336.228246)
			(xy 88.955431 -336.173607) (xy 88.971569 -336.120772) (xy 88.995336 -336.070902) (xy 89.026211 -336.025091)
			(xy 89.063516 -335.984345) (xy 89.084658 -335.966562) (xy 89.093223 -335.958995) (xy 89.103002 -335.938359)
			(xy 89.103454 -335.926938) (xy 89.103454 -335.848198) (xy 89.102884 -335.836809) (xy 89.093104 -335.816238)
			(xy 89.084658 -335.808574) (xy 89.063503 -335.790803) (xy 89.026192 -335.750057) (xy 88.995311 -335.704245)
			(xy 88.971538 -335.654372) (xy 88.955395 -335.601535) (xy 88.947236 -335.546892) (xy 88.946736 -335.519268)
			(xy 88.947257 -335.491383) (xy 88.955569 -335.436236) (xy 88.972007 -335.382944) (xy 88.996205 -335.332698)
			(xy 89.027621 -335.286619) (xy 89.065554 -335.245737) (xy 89.109156 -335.210965) (xy 89.157454 -335.18308)
			(xy 89.209369 -335.162705) (xy 89.26374 -335.150295) (xy 89.319354 -335.146128) (xy 89.374968 -335.150295)
			(xy 89.429339 -335.162705) (xy 89.481254 -335.18308) (xy 89.529552 -335.210965) (xy 89.573154 -335.245737)
			(xy 89.611087 -335.286619) (xy 89.642503 -335.332698) (xy 89.666701 -335.382944) (xy 89.683139 -335.436236)
			(xy 89.691451 -335.491383) (xy 89.691972 -335.519268) (xy 89.691452 -335.546891) (xy 89.683294 -335.601531)
			(xy 89.667152 -335.654366) (xy 89.643381 -335.704236) (xy 89.612502 -335.750046) (xy 89.575193 -335.790791)
			(xy 89.55405 -335.808574) (xy 89.545515 -335.81617) (xy 89.535719 -335.836784) (xy 89.535254 -335.848198)
			(xy 89.535254 -335.926938) (xy 89.535857 -335.938323) (xy 89.545613 -335.958894) (xy 89.55405 -335.966562)
			(xy 89.575176 -335.984366) (xy 89.612489 -336.025105) (xy 89.643373 -336.070911) (xy 89.667151 -336.120777)
			(xy 89.6833 -336.173608) (xy 89.691467 -336.228246) (xy 89.691972 -336.255868) (xy 89.69155 -336.282722)
			(xy 89.683817 -336.335871) (xy 89.668536 -336.38736) (xy 89.646023 -336.436122) (xy 89.616744 -336.481149)
			(xy 89.581306 -336.521506) (xy 89.540442 -336.55636) (xy 89.494998 -336.584987) (xy 89.445917 -336.606796)
			(xy 89.420192 -336.614516) (xy 89.408508 -336.617818) (xy 89.390728 -336.634074) (xy 89.353136 -336.73288)
			(xy 89.355422 -336.756756) (xy 89.362026 -336.766916) (xy 89.375793 -336.789431) (xy 89.397542 -336.837513)
			(xy 89.412288 -336.888183) (xy 89.419734 -336.940428) (xy 89.420192 -336.966814) (xy 89.419779 -336.993433)
			(xy 89.4122 -337.04613) (xy 89.397199 -337.097211) (xy 89.37508 -337.145638) (xy 89.346295 -337.190424)
			(xy 89.311429 -337.230657) (xy 89.271192 -337.265519) (xy 89.226403 -337.294299) (xy 89.177974 -337.316413)
			(xy 89.126891 -337.331408) (xy 89.074193 -337.338982) (xy 89.047574 -337.339432) (xy 89.021152 -337.338982)
			(xy 88.968837 -337.331529) (xy 88.918098 -337.316762) (xy 88.869954 -337.294976) (xy 88.825369 -337.26661)
			(xy 88.805004 -337.24977) (xy 88.798146 -337.243674) (xy 88.781128 -337.237578) (xy 88.6968 -337.237578)
			(xy 88.679782 -337.243674) (xy 88.672924 -337.24977) (xy 88.652558 -337.266609) (xy 88.607972 -337.294974)
			(xy 88.559828 -337.316761) (xy 88.509091 -337.331532) (xy 88.456776 -337.338992) (xy 88.403932 -337.338992)
			(xy 88.351617 -337.331532) (xy 88.30088 -337.316761) (xy 88.252736 -337.294974) (xy 88.20815 -337.266609)
			(xy 88.187784 -337.24977) (xy 88.180926 -337.243674) (xy 88.163908 -337.237578) (xy 88.07958 -337.237578)
			(xy 88.062562 -337.243674) (xy 88.055704 -337.24977) (xy 88.035333 -337.266602) (xy 87.990745 -337.294959)
			(xy 87.942602 -337.31674) (xy 87.891866 -337.331509) (xy 87.839555 -337.33897) (xy 87.813134 -337.339432)
			(xy 87.785247 -337.338912) (xy 87.730094 -337.330603) (xy 87.676796 -337.314167) (xy 87.626543 -337.289971)
			(xy 87.580458 -337.258555) (xy 87.539571 -337.22062) (xy 87.504794 -337.177015) (xy 87.476905 -337.128714)
			(xy 87.456528 -337.076795) (xy 87.444116 -337.022419) (xy 87.439947 -336.9668) (xy 83.625096 -336.9668)
			(xy 83.622325 -336.968581) (xy 83.572748 -336.991223) (xy 83.520453 -337.006578) (xy 83.466505 -337.014334)
			(xy 83.412003 -337.014334) (xy 83.358055 -337.006578) (xy 83.30576 -336.991223) (xy 83.256183 -336.968581)
			(xy 83.210333 -336.939115) (xy 83.169142 -336.903424) (xy 83.133451 -336.862233) (xy 83.103985 -336.816383)
			(xy 83.081343 -336.766806) (xy 83.065988 -336.714511) (xy 83.058232 -336.660563) (xy 83.057746 -336.633312)
			(xy 81.023391 -336.633312) (xy 80.984852 -336.73161) (xy 80.9879 -336.75701) (xy 80.995012 -336.767424)
			(xy 81.010922 -336.791067) (xy 81.036174 -336.842149) (xy 81.053345 -336.896483) (xy 81.062032 -336.9528)
			(xy 81.062576 -336.981292) (xy 81.062158 -337.007912) (xy 81.054582 -337.060609) (xy 81.039583 -337.111691)
			(xy 81.017466 -337.160119) (xy 80.988681 -337.204906) (xy 80.953816 -337.24514) (xy 80.913578 -337.280002)
			(xy 80.868789 -337.308782) (xy 80.820359 -337.330895) (xy 80.769275 -337.345889) (xy 80.716578 -337.353461)
			(xy 80.689958 -337.35391) (xy 80.663535 -337.353474) (xy 80.611219 -337.346019) (xy 80.56048 -337.331248)
			(xy 80.512336 -337.30946) (xy 80.467753 -337.28109) (xy 80.447388 -337.264248) (xy 80.44053 -337.258152)
			(xy 80.423512 -337.252056) (xy 80.339184 -337.252056) (xy 80.322166 -337.258152) (xy 80.315308 -337.264248)
			(xy 80.294942 -337.281087) (xy 80.250356 -337.309452) (xy 80.202212 -337.331239) (xy 80.151475 -337.34601)
			(xy 80.09916 -337.35347) (xy 80.046316 -337.35347) (xy 79.994001 -337.34601) (xy 79.943264 -337.331239)
			(xy 79.89512 -337.309452) (xy 79.850534 -337.281087) (xy 79.830168 -337.264248) (xy 79.82331 -337.258152)
			(xy 79.806292 -337.252056) (xy 79.721964 -337.252056) (xy 79.704946 -337.258152) (xy 79.698088 -337.264248)
			(xy 79.67772 -337.281084) (xy 79.633132 -337.309441) (xy 79.584988 -337.331221) (xy 79.534252 -337.34599)
			(xy 79.481939 -337.35345) (xy 79.455518 -337.35391) (xy 79.42763 -337.353432) (xy 79.372476 -337.345122)
			(xy 79.319177 -337.328683) (xy 79.268923 -337.304485) (xy 79.222838 -337.273066) (xy 79.18195 -337.235129)
			(xy 79.147173 -337.191522) (xy 79.119284 -337.143219) (xy 79.098906 -337.091298) (xy 79.086494 -337.03692)
			(xy 79.082325 -336.9813) (xy 75.267446 -336.9813) (xy 75.264709 -336.983059) (xy 75.215132 -337.005701)
			(xy 75.162837 -337.021056) (xy 75.108889 -337.028812) (xy 75.054387 -337.028812) (xy 75.000439 -337.021056)
			(xy 74.948144 -337.005701) (xy 74.898567 -336.983059) (xy 74.852717 -336.953593) (xy 74.811526 -336.917902)
			(xy 74.775835 -336.876711) (xy 74.746369 -336.830861) (xy 74.723727 -336.781284) (xy 74.708372 -336.728989)
			(xy 74.700616 -336.675041) (xy 74.70013 -336.64779) (xy 72.665678 -336.64779) (xy 72.63003 -336.740246)
			(xy 72.633078 -336.765392) (xy 72.640444 -336.775806) (xy 72.65615 -336.799345) (xy 72.681017 -336.850173)
			(xy 72.697919 -336.904175) (xy 72.706468 -336.960111) (xy 72.706992 -336.988404) (xy 72.706569 -337.015023)
			(xy 72.698992 -337.067719) (xy 72.683992 -337.118801) (xy 72.661875 -337.167227) (xy 72.633091 -337.212013)
			(xy 72.598225 -337.252247) (xy 72.557989 -337.287109) (xy 72.513201 -337.315889) (xy 72.464773 -337.338002)
			(xy 72.41369 -337.352998) (xy 72.360993 -337.360572) (xy 72.334374 -337.361022) (xy 72.307952 -337.360574)
			(xy 72.255636 -337.353121) (xy 72.204898 -337.338353) (xy 72.156754 -337.316568) (xy 72.112169 -337.2882)
			(xy 72.091804 -337.27136) (xy 72.084946 -337.265264) (xy 72.067928 -337.259168) (xy 71.9836 -337.259168)
			(xy 71.966582 -337.265264) (xy 71.959724 -337.27136) (xy 71.939358 -337.288199) (xy 71.894772 -337.316564)
			(xy 71.846628 -337.338351) (xy 71.795891 -337.353122) (xy 71.743576 -337.360582) (xy 71.690732 -337.360582)
			(xy 71.638417 -337.353122) (xy 71.58768 -337.338351) (xy 71.539536 -337.316564) (xy 71.49495 -337.288199)
			(xy 71.474584 -337.27136) (xy 71.467726 -337.265264) (xy 71.450708 -337.259168) (xy 71.36638 -337.259168)
			(xy 71.349362 -337.265264) (xy 71.342504 -337.27136) (xy 71.322132 -337.28819) (xy 71.277545 -337.316548)
			(xy 71.229401 -337.338329) (xy 71.178666 -337.353099) (xy 71.126355 -337.36056) (xy 71.099934 -337.361022)
			(xy 71.072046 -337.360521) (xy 71.016892 -337.352213) (xy 70.963593 -337.335777) (xy 70.913338 -337.31158)
			(xy 70.867252 -337.280162) (xy 70.826364 -337.242227) (xy 70.791586 -337.198621) (xy 70.763696 -337.150318)
			(xy 70.743318 -337.098398) (xy 70.730906 -337.04402) (xy 70.726737 -336.9884) (xy 66.911881 -336.9884)
			(xy 66.909125 -336.990171) (xy 66.859548 -337.012813) (xy 66.807253 -337.028168) (xy 66.753305 -337.035924)
			(xy 66.698803 -337.035924) (xy 66.644855 -337.028168) (xy 66.59256 -337.012813) (xy 66.542983 -336.990171)
			(xy 66.497133 -336.960705) (xy 66.455942 -336.925014) (xy 66.420251 -336.883823) (xy 66.390785 -336.837973)
			(xy 66.368143 -336.788396) (xy 66.352788 -336.736101) (xy 66.345032 -336.682153) (xy 66.344546 -336.654902)
			(xy 21.260816 -336.654902) (xy 21.260816 -337.886548) (xy 67.302378 -337.886548) (xy 67.306449 -337.830926)
			(xy 67.318575 -337.776489) (xy 67.338498 -337.724398) (xy 67.365794 -337.675763) (xy 67.39988 -337.63162)
			(xy 67.440029 -337.592911) (xy 67.485387 -337.56046) (xy 67.534987 -337.534959) (xy 67.587771 -337.516952)
			(xy 67.642614 -337.506822) (xy 67.698348 -337.504785) (xy 67.753785 -337.510885) (xy 67.807742 -337.524991)
			(xy 67.859071 -337.546803) (xy 67.906677 -337.575857) (xy 67.949545 -337.611532) (xy 67.986762 -337.653069)
			(xy 68.017535 -337.699582) (xy 68.041207 -337.750079) (xy 68.057275 -337.803486) (xy 68.065395 -337.858662)
			(xy 68.065904 -337.886548) (xy 68.065395 -337.914434) (xy 68.057275 -337.96961) (xy 68.041207 -338.023017)
			(xy 68.017535 -338.073514) (xy 67.986762 -338.120027) (xy 67.949545 -338.161564) (xy 67.906677 -338.197239)
			(xy 67.859071 -338.226293) (xy 67.807742 -338.248105) (xy 67.753785 -338.262211) (xy 67.698348 -338.268311)
			(xy 67.642614 -338.266274) (xy 67.587771 -338.256144) (xy 67.534987 -338.238137) (xy 67.485387 -338.212636)
			(xy 67.440029 -338.180185) (xy 67.39988 -338.141476) (xy 67.365794 -338.097333) (xy 67.338498 -338.048698)
			(xy 67.318575 -337.996607) (xy 67.306449 -337.94217) (xy 67.302378 -337.886548) (xy 21.260816 -337.886548)
			(xy 21.260816 -338.781898) (xy 66.723258 -338.781898) (xy 66.727329 -338.726276) (xy 66.739455 -338.671839)
			(xy 66.759378 -338.619748) (xy 66.786674 -338.571113) (xy 66.82076 -338.52697) (xy 66.860909 -338.488261)
			(xy 66.906267 -338.45581) (xy 66.955867 -338.430309) (xy 67.008651 -338.412302) (xy 67.063494 -338.402172)
			(xy 67.119228 -338.400135) (xy 67.174665 -338.406235) (xy 67.228622 -338.420341) (xy 67.279951 -338.442153)
			(xy 67.327557 -338.471207) (xy 67.370425 -338.506882) (xy 67.407642 -338.548419) (xy 67.438415 -338.594932)
			(xy 67.462087 -338.645429) (xy 67.478155 -338.698836) (xy 67.486275 -338.754012) (xy 67.486784 -338.781898)
			(xy 67.486275 -338.809784) (xy 67.478155 -338.86496) (xy 67.462087 -338.918367) (xy 67.438415 -338.968864)
			(xy 67.407642 -339.015377) (xy 67.370425 -339.056914) (xy 67.327557 -339.092589) (xy 67.279951 -339.121643)
			(xy 67.228622 -339.143455) (xy 67.174665 -339.157561) (xy 67.119228 -339.163661) (xy 67.063494 -339.161624)
			(xy 67.008651 -339.151494) (xy 66.955867 -339.133487) (xy 66.906267 -339.107986) (xy 66.860909 -339.075535)
			(xy 66.82076 -339.036826) (xy 66.786674 -338.992683) (xy 66.759378 -338.944048) (xy 66.739455 -338.891957)
			(xy 66.727329 -338.83752) (xy 66.723258 -338.781898) (xy 21.260816 -338.781898) (xy 21.260816 -339.457538)
			(xy 68.062094 -339.457538) (xy 68.062604 -339.430064) (xy 68.070491 -339.375686) (xy 68.086105 -339.323004)
			(xy 68.109124 -339.273111) (xy 68.139071 -339.227041) (xy 68.156836 -339.206078) (xy 68.162932 -339.198966)
			(xy 68.169282 -339.181948) (xy 68.169282 -339.096096) (xy 68.162932 -339.079078) (xy 68.156836 -339.071966)
			(xy 68.139065 -339.05101) (xy 68.109143 -339.004925) (xy 68.086133 -338.955029) (xy 68.070509 -338.902352)
			(xy 68.062593 -338.847979) (xy 68.062094 -338.820506) (xy 68.06258 -338.793255) (xy 68.070336 -338.739307)
			(xy 68.085691 -338.687012) (xy 68.108333 -338.637435) (xy 68.137799 -338.591585) (xy 68.17349 -338.550394)
			(xy 68.214681 -338.514703) (xy 68.260531 -338.485237) (xy 68.310108 -338.462595) (xy 68.362403 -338.44724)
			(xy 68.416351 -338.439484) (xy 68.470853 -338.439484) (xy 68.524801 -338.44724) (xy 68.577096 -338.462595)
			(xy 68.626673 -338.485237) (xy 68.672523 -338.514703) (xy 68.713714 -338.550394) (xy 68.749405 -338.591585)
			(xy 68.778871 -338.637435) (xy 68.801513 -338.687012) (xy 68.816868 -338.739307) (xy 68.824624 -338.793255)
			(xy 68.82511 -338.820506) (xy 68.824625 -338.847981) (xy 68.816732 -338.90236) (xy 68.801112 -338.955042)
			(xy 68.798477 -338.960751) (xy 69.066891 -338.960751) (xy 69.066891 -338.906249) (xy 69.074648 -338.852301)
			(xy 69.090004 -338.800007) (xy 69.112645 -338.75043) (xy 69.142112 -338.704581) (xy 69.177804 -338.663392)
			(xy 69.218995 -338.627701) (xy 69.264846 -338.598237) (xy 69.314424 -338.575597) (xy 69.366719 -338.560244)
			(xy 69.420667 -338.55249) (xy 69.447918 -338.552028) (xy 69.473153 -338.552427) (xy 69.523187 -338.559046)
			(xy 69.571907 -338.572219) (xy 69.618459 -338.591714) (xy 69.64045 -338.604098) (xy 69.650102 -338.60994)
			(xy 69.6722 -338.611972) (xy 69.766688 -338.578444) (xy 69.78269 -338.56295) (xy 69.786754 -338.552536)
			(xy 69.797438 -338.525755) (xy 69.82573 -338.475516) (xy 69.861264 -338.430108) (xy 69.903228 -338.390568)
			(xy 69.950666 -338.357795) (xy 70.002498 -338.332538) (xy 70.057541 -338.315371) (xy 70.114541 -338.306687)
			(xy 70.14337 -338.306156) (xy 70.170619 -338.306706) (xy 70.224562 -338.314458) (xy 70.276854 -338.329807)
			(xy 70.326428 -338.352442) (xy 70.372277 -338.381902) (xy 70.413467 -338.417587) (xy 70.449159 -338.45877)
			(xy 70.478626 -338.504614) (xy 70.50127 -338.554184) (xy 70.513991 -338.597494) (xy 72.654922 -338.597494)
			(xy 72.655376 -338.569919) (xy 72.66333 -338.515345) (xy 72.679057 -338.462485) (xy 72.702229 -338.412439)
			(xy 72.732364 -338.366249) (xy 72.768834 -338.324879) (xy 72.789542 -338.306664) (xy 72.797679 -338.299078)
			(xy 72.807021 -338.278914) (xy 72.807576 -338.267802) (xy 72.807576 -338.190586) (xy 72.807039 -338.179472)
			(xy 72.797679 -338.159313) (xy 72.789542 -338.151724) (xy 72.768848 -338.133494) (xy 72.732374 -338.092131)
			(xy 72.702239 -338.045945) (xy 72.67907 -337.9959) (xy 72.66335 -337.943041) (xy 72.655408 -337.888468)
			(xy 72.654922 -337.860894) (xy 72.65535 -337.83364) (xy 72.663108 -337.779686) (xy 72.678467 -337.727386)
			(xy 72.701112 -337.677803) (xy 72.730584 -337.631949) (xy 72.766281 -337.590755) (xy 72.807478 -337.555062)
			(xy 72.853335 -337.525595) (xy 72.902919 -337.502954) (xy 72.955221 -337.487601) (xy 73.009176 -337.479847)
			(xy 73.03643 -337.479386) (xy 73.07072 -337.48091) (xy 73.08088 -337.481926) (xy 73.100184 -337.47583)
			(xy 73.170796 -337.416648) (xy 73.180194 -337.398614) (xy 73.18121 -337.388454) (xy 73.184139 -337.360278)
			(xy 73.197314 -337.305184) (xy 73.218494 -337.252645) (xy 73.247214 -337.203817) (xy 73.28284 -337.159775)
			(xy 73.324591 -337.121489) (xy 73.371545 -337.089799) (xy 73.422671 -337.065405) (xy 73.476844 -337.048843)
			(xy 73.53287 -337.040476) (xy 73.561194 -337.039966) (xy 73.579213 -337.040192) (xy 73.615088 -337.043623)
			(xy 73.632822 -337.046824) (xy 73.64222 -337.048602) (xy 73.66127 -337.044792) (xy 73.736454 -336.99704)
			(xy 73.747884 -336.981292) (xy 73.75017 -336.971894) (xy 73.757635 -336.94487) (xy 73.779256 -336.893146)
			(xy 73.808211 -336.845141) (xy 73.843878 -336.801889) (xy 73.885489 -336.76432) (xy 73.932148 -336.733243)
			(xy 73.982851 -336.709327) (xy 74.036508 -336.693085) (xy 74.091964 -336.684868) (xy 74.119994 -336.684366)
			(xy 74.147244 -336.684883) (xy 74.201189 -336.692638) (xy 74.253482 -336.707991) (xy 74.303057 -336.73063)
			(xy 74.348906 -336.760093) (xy 74.390096 -336.795781) (xy 74.425788 -336.836968) (xy 74.455255 -336.882815)
			(xy 74.477897 -336.932388) (xy 74.493255 -336.98468) (xy 74.501014 -337.038624) (xy 74.501502 -337.065874)
			(xy 74.501018 -337.093448) (xy 74.493069 -337.14802) (xy 74.477347 -337.200879) (xy 74.454181 -337.250925)
			(xy 74.424052 -337.297115) (xy 74.387588 -337.338488) (xy 74.366882 -337.356704) (xy 74.358764 -337.364306)
			(xy 74.34941 -337.384458) (xy 74.348848 -337.395566) (xy 74.348848 -337.472782) (xy 74.349395 -337.483895)
			(xy 74.358747 -337.504054) (xy 74.366882 -337.511644) (xy 74.387562 -337.529888) (xy 74.424027 -337.571255)
			(xy 74.454156 -337.617441) (xy 74.47732 -337.667484) (xy 74.493038 -337.720341) (xy 74.50098 -337.774911)
			(xy 74.500983 -337.830055) (xy 74.4938 -337.879436) (xy 75.657962 -337.879436) (xy 75.662033 -337.823814)
			(xy 75.674159 -337.769377) (xy 75.694082 -337.717286) (xy 75.721378 -337.668651) (xy 75.755464 -337.624508)
			(xy 75.795613 -337.585799) (xy 75.840971 -337.553348) (xy 75.890571 -337.527847) (xy 75.943355 -337.50984)
			(xy 75.998198 -337.49971) (xy 76.053932 -337.497673) (xy 76.109369 -337.503773) (xy 76.163326 -337.517879)
			(xy 76.214655 -337.539691) (xy 76.262261 -337.568745) (xy 76.305129 -337.60442) (xy 76.342346 -337.645957)
			(xy 76.373119 -337.69247) (xy 76.396791 -337.742967) (xy 76.412859 -337.796374) (xy 76.420979 -337.85155)
			(xy 76.421488 -337.879436) (xy 76.420979 -337.907322) (xy 76.412859 -337.962498) (xy 76.396791 -338.015905)
			(xy 76.373119 -338.066402) (xy 76.342346 -338.112915) (xy 76.305129 -338.154452) (xy 76.262261 -338.190127)
			(xy 76.214655 -338.219181) (xy 76.163326 -338.240993) (xy 76.109369 -338.255099) (xy 76.053932 -338.261199)
			(xy 75.998198 -338.259162) (xy 75.943355 -338.249032) (xy 75.890571 -338.231025) (xy 75.840971 -338.205524)
			(xy 75.795613 -338.173073) (xy 75.755464 -338.134364) (xy 75.721378 -338.090221) (xy 75.694082 -338.041586)
			(xy 75.674159 -337.989495) (xy 75.662033 -337.935058) (xy 75.657962 -337.879436) (xy 74.4938 -337.879436)
			(xy 74.493045 -337.884626) (xy 74.477332 -337.937484) (xy 74.454172 -337.98753) (xy 74.424048 -338.033719)
			(xy 74.387586 -338.075089) (xy 74.366882 -338.093304) (xy 74.358764 -338.100906) (xy 74.34941 -338.121058)
			(xy 74.348848 -338.132166) (xy 74.348848 -338.209382) (xy 74.349395 -338.220495) (xy 74.358747 -338.240654)
			(xy 74.366882 -338.248244) (xy 74.387566 -338.266485) (xy 74.424039 -338.307847) (xy 74.454175 -338.354031)
			(xy 74.477346 -338.404073) (xy 74.493068 -338.45693) (xy 74.501013 -338.511501) (xy 74.501502 -338.539074)
			(xy 74.50102 -338.566326) (xy 74.493267 -338.620277) (xy 74.477914 -338.672575) (xy 74.455274 -338.722155)
			(xy 74.425808 -338.768009) (xy 74.419936 -338.774786) (xy 75.078842 -338.774786) (xy 75.082913 -338.719164)
			(xy 75.095039 -338.664727) (xy 75.114962 -338.612636) (xy 75.142258 -338.564001) (xy 75.176344 -338.519858)
			(xy 75.216493 -338.481149) (xy 75.261851 -338.448698) (xy 75.311451 -338.423197) (xy 75.364235 -338.40519)
			(xy 75.419078 -338.39506) (xy 75.474812 -338.393023) (xy 75.530249 -338.399123) (xy 75.584206 -338.413229)
			(xy 75.635535 -338.435041) (xy 75.683141 -338.464095) (xy 75.726009 -338.49977) (xy 75.763226 -338.541307)
			(xy 75.793999 -338.58782) (xy 75.817671 -338.638317) (xy 75.833739 -338.691724) (xy 75.841859 -338.7469)
			(xy 75.842368 -338.774786) (xy 75.841859 -338.802672) (xy 75.833739 -338.857848) (xy 75.817671 -338.911255)
			(xy 75.793999 -338.961752) (xy 75.763226 -339.008265) (xy 75.726009 -339.049802) (xy 75.683141 -339.085477)
			(xy 75.635535 -339.114531) (xy 75.584206 -339.136343) (xy 75.530249 -339.150449) (xy 75.474812 -339.156549)
			(xy 75.419078 -339.154512) (xy 75.364235 -339.144382) (xy 75.311451 -339.126375) (xy 75.261851 -339.100874)
			(xy 75.216493 -339.068423) (xy 75.176344 -339.029714) (xy 75.142258 -338.985571) (xy 75.114962 -338.936936)
			(xy 75.095039 -338.884845) (xy 75.082913 -338.830408) (xy 75.078842 -338.774786) (xy 74.419936 -338.774786)
			(xy 74.390116 -338.809202) (xy 74.348925 -338.844896) (xy 74.303073 -338.874364) (xy 74.253494 -338.897007)
			(xy 74.201197 -338.912363) (xy 74.147246 -338.920119) (xy 74.119994 -338.920582) (xy 74.092138 -338.920078)
			(xy 74.037021 -338.911953) (xy 73.983669 -338.895906) (xy 73.933216 -338.872277) (xy 73.886731 -338.841568)
			(xy 73.845201 -338.80443) (xy 73.809509 -338.761652) (xy 73.780411 -338.714142) (xy 73.758525 -338.662908)
			(xy 73.750932 -338.636102) (xy 73.748646 -338.627212) (xy 73.737978 -338.611972) (xy 73.666096 -338.56422)
			(xy 73.648062 -338.560156) (xy 73.638918 -338.561426) (xy 73.625901 -338.563091) (xy 73.599717 -338.564874)
			(xy 73.586594 -338.564982) (xy 73.572445 -338.564889) (xy 73.544222 -338.562854) (xy 73.530206 -338.560918)
			(xy 73.520046 -338.559394) (xy 73.500488 -338.56422) (xy 73.426066 -338.6201) (xy 73.415906 -338.637626)
			(xy 73.414636 -338.647786) (xy 73.410562 -338.674941) (xy 73.395584 -338.727771) (xy 73.373189 -338.777907)
			(xy 73.343839 -338.824317) (xy 73.30814 -338.86604) (xy 73.266829 -338.902215) (xy 73.22076 -338.932096)
			(xy 73.170883 -338.955065) (xy 73.118229 -338.970648) (xy 73.063886 -338.978523) (xy 73.03643 -338.979002)
			(xy 73.009178 -338.978517) (xy 72.955227 -338.970764) (xy 72.902929 -338.955411) (xy 72.853349 -338.932772)
			(xy 72.807495 -338.903306) (xy 72.766302 -338.867615) (xy 72.730608 -338.826424) (xy 72.70114 -338.780572)
			(xy 72.678497 -338.730993) (xy 72.663141 -338.678696) (xy 72.655385 -338.624746) (xy 72.654922 -338.597494)
			(xy 70.513991 -338.597494) (xy 70.516628 -338.606473) (xy 70.524389 -338.660415) (xy 70.524878 -338.687664)
			(xy 70.524231 -338.719227) (xy 70.513839 -338.781493) (xy 70.493348 -338.841202) (xy 70.478904 -338.869274)
			(xy 70.474078 -338.878164) (xy 70.472046 -338.897722) (xy 70.4977 -338.98586) (xy 70.510146 -339.001354)
			(xy 70.519036 -339.006434) (xy 70.544122 -339.021008) (xy 70.590007 -339.056505) (xy 70.629985 -339.098543)
			(xy 70.663133 -339.146153) (xy 70.688687 -339.198234) (xy 70.706055 -339.253586) (xy 70.714838 -339.31093)
			(xy 70.715378 -339.339936) (xy 70.714892 -339.367187) (xy 70.707136 -339.421135) (xy 70.698535 -339.450426)
			(xy 76.417678 -339.450426) (xy 76.418185 -339.422952) (xy 76.426073 -339.368574) (xy 76.441688 -339.315892)
			(xy 76.464708 -339.265999) (xy 76.494655 -339.219929) (xy 76.51242 -339.198966) (xy 76.518516 -339.191854)
			(xy 76.524866 -339.174836) (xy 76.524866 -339.088984) (xy 76.518516 -339.071966) (xy 76.51242 -339.064854)
			(xy 76.494641 -339.043904) (xy 76.464721 -338.997818) (xy 76.441712 -338.94792) (xy 76.42609 -338.895241)
			(xy 76.418176 -338.840867) (xy 76.417678 -338.813394) (xy 76.418164 -338.786143) (xy 76.42592 -338.732195)
			(xy 76.441275 -338.6799) (xy 76.463917 -338.630323) (xy 76.493383 -338.584473) (xy 76.529074 -338.543282)
			(xy 76.570265 -338.507591) (xy 76.616115 -338.478125) (xy 76.665692 -338.455483) (xy 76.717987 -338.440128)
			(xy 76.771935 -338.432372) (xy 76.826437 -338.432372) (xy 76.880385 -338.440128) (xy 76.93268 -338.455483)
			(xy 76.982257 -338.478125) (xy 77.028107 -338.507591) (xy 77.069298 -338.543282) (xy 77.104989 -338.584473)
			(xy 77.134455 -338.630323) (xy 77.157097 -338.6799) (xy 77.172452 -338.732195) (xy 77.180208 -338.786143)
			(xy 77.180694 -338.813394) (xy 77.180206 -338.840869) (xy 77.172314 -338.895248) (xy 77.156695 -338.947931)
			(xy 77.154055 -338.953651) (xy 77.422479 -338.953651) (xy 77.422479 -338.899149) (xy 77.430236 -338.845201)
			(xy 77.445591 -338.792906) (xy 77.468232 -338.743329) (xy 77.497699 -338.697479) (xy 77.53339 -338.656289)
			(xy 77.57458 -338.620597) (xy 77.620431 -338.591131) (xy 77.670008 -338.56849) (xy 77.722303 -338.553135)
			(xy 77.776251 -338.545379) (xy 77.803502 -338.544916) (xy 77.828737 -338.54531) (xy 77.878772 -338.551929)
			(xy 77.927492 -338.565102) (xy 77.974044 -338.5846) (xy 77.996034 -338.596986) (xy 78.005686 -338.602828)
			(xy 78.027784 -338.60486) (xy 78.122272 -338.571332) (xy 78.138274 -338.555838) (xy 78.142338 -338.545424)
			(xy 78.153082 -338.518668) (xy 78.181362 -338.468427) (xy 78.216884 -338.423016) (xy 78.258839 -338.383472)
			(xy 78.30627 -338.350695) (xy 78.358094 -338.325434) (xy 78.413132 -338.308264) (xy 78.470127 -338.299576)
			(xy 78.498954 -338.299044) (xy 78.526202 -338.299621) (xy 78.580144 -338.30737) (xy 78.632434 -338.322717)
			(xy 78.682008 -338.345349) (xy 78.727856 -338.374806) (xy 78.769045 -338.410488) (xy 78.804738 -338.451669)
			(xy 78.834206 -338.49751) (xy 78.85685 -338.547078) (xy 78.869571 -338.590382) (xy 81.010506 -338.590382)
			(xy 81.011026 -338.562809) (xy 81.018967 -338.508239) (xy 81.034681 -338.45538) (xy 81.057841 -338.405334)
			(xy 81.087964 -338.359143) (xy 81.124423 -338.317769) (xy 81.145126 -338.299552) (xy 81.153266 -338.291969)
			(xy 81.162607 -338.271803) (xy 81.16316 -338.26069) (xy 81.16316 -338.183474) (xy 81.162635 -338.172359)
			(xy 81.153267 -338.1522) (xy 81.145126 -338.144612) (xy 81.124423 -338.126392) (xy 81.087951 -338.085026)
			(xy 81.057817 -338.038838) (xy 81.03465 -337.988792) (xy 81.018932 -337.93593) (xy 81.010991 -337.881356)
			(xy 81.010506 -337.853782) (xy 81.010961 -337.82653) (xy 81.01872 -337.77258) (xy 81.034079 -337.720284)
			(xy 81.056723 -337.670706) (xy 81.086192 -337.624855) (xy 81.121887 -337.583664) (xy 81.16308 -337.547973)
			(xy 81.208934 -337.518507) (xy 81.258514 -337.495867) (xy 81.310811 -337.480514) (xy 81.364762 -337.472759)
			(xy 81.392014 -337.472274) (xy 81.426304 -337.473798) (xy 81.436464 -337.474814) (xy 81.455768 -337.468718)
			(xy 81.52638 -337.409536) (xy 81.535778 -337.391502) (xy 81.536794 -337.381342) (xy 81.539728 -337.353167)
			(xy 81.552904 -337.298074) (xy 81.574085 -337.245536) (xy 81.602804 -337.196709) (xy 81.638431 -337.152668)
			(xy 81.68018 -337.114382) (xy 81.727134 -337.082692) (xy 81.778258 -337.058297) (xy 81.832429 -337.041734)
			(xy 81.888455 -337.033366) (xy 81.916778 -337.032854) (xy 81.934798 -337.033069) (xy 81.970672 -337.036507)
			(xy 81.988406 -337.039712) (xy 81.997804 -337.04149) (xy 82.016854 -337.03768) (xy 82.092038 -336.989928)
			(xy 82.103468 -336.97418) (xy 82.105754 -336.964782) (xy 82.113135 -336.937733) (xy 82.134764 -336.886004)
			(xy 82.163729 -336.837996) (xy 82.199406 -336.794743) (xy 82.241027 -336.757175) (xy 82.287697 -336.726101)
			(xy 82.338412 -336.70219) (xy 82.392079 -336.685957) (xy 82.447544 -336.67775) (xy 82.475578 -336.677254)
			(xy 82.502827 -336.677799) (xy 82.556771 -336.685551) (xy 82.609062 -336.700902) (xy 82.658636 -336.723537)
			(xy 82.704485 -336.752998) (xy 82.745674 -336.788683) (xy 82.781366 -336.829867) (xy 82.810834 -336.875711)
			(xy 82.833477 -336.925282) (xy 82.848836 -336.977571) (xy 82.856597 -337.031513) (xy 82.857086 -337.058762)
			(xy 82.856599 -337.086336) (xy 82.848652 -337.140908) (xy 82.832931 -337.193768) (xy 82.809765 -337.243814)
			(xy 82.779636 -337.290004) (xy 82.743172 -337.331376) (xy 82.722466 -337.349592) (xy 82.71435 -337.357197)
			(xy 82.704996 -337.377347) (xy 82.704432 -337.388454) (xy 82.704432 -337.46567) (xy 82.704991 -337.476781)
			(xy 82.714335 -337.49694) (xy 82.722466 -337.504532) (xy 82.743135 -337.522788) (xy 82.779602 -337.564153)
			(xy 82.809732 -337.610337) (xy 82.832897 -337.660379) (xy 82.848616 -337.713235) (xy 82.85656 -337.767804)
			(xy 82.856564 -337.822947) (xy 82.850454 -337.864958) (xy 84.015578 -337.864958) (xy 84.019649 -337.809336)
			(xy 84.031775 -337.754899) (xy 84.051698 -337.702808) (xy 84.078994 -337.654173) (xy 84.11308 -337.61003)
			(xy 84.153229 -337.571321) (xy 84.198587 -337.53887) (xy 84.248187 -337.513369) (xy 84.300971 -337.495362)
			(xy 84.355814 -337.485232) (xy 84.411548 -337.483195) (xy 84.466985 -337.489295) (xy 84.520942 -337.503401)
			(xy 84.572271 -337.525213) (xy 84.619877 -337.554267) (xy 84.662745 -337.589942) (xy 84.699962 -337.631479)
			(xy 84.730735 -337.677992) (xy 84.754407 -337.728489) (xy 84.770475 -337.781896) (xy 84.778595 -337.837072)
			(xy 84.779104 -337.864958) (xy 84.778595 -337.892844) (xy 84.770475 -337.94802) (xy 84.754407 -338.001427)
			(xy 84.730735 -338.051924) (xy 84.699962 -338.098437) (xy 84.662745 -338.139974) (xy 84.619877 -338.175649)
			(xy 84.572271 -338.204703) (xy 84.520942 -338.226515) (xy 84.466985 -338.240621) (xy 84.411548 -338.246721)
			(xy 84.355814 -338.244684) (xy 84.300971 -338.234554) (xy 84.248187 -338.216547) (xy 84.198587 -338.191046)
			(xy 84.153229 -338.158595) (xy 84.11308 -338.119886) (xy 84.078994 -338.075743) (xy 84.051698 -338.027108)
			(xy 84.031775 -337.975017) (xy 84.019649 -337.92058) (xy 84.015578 -337.864958) (xy 82.850454 -337.864958)
			(xy 82.848627 -337.877517) (xy 82.832915 -337.930375) (xy 82.809756 -337.98042) (xy 82.779631 -338.026608)
			(xy 82.74317 -338.067977) (xy 82.722466 -338.086192) (xy 82.71435 -338.093797) (xy 82.704996 -338.113947)
			(xy 82.704432 -338.125054) (xy 82.704432 -338.20227) (xy 82.704991 -338.213381) (xy 82.714335 -338.23354)
			(xy 82.722466 -338.241132) (xy 82.743189 -338.25933) (xy 82.77966 -338.300701) (xy 82.809791 -338.346893)
			(xy 82.832955 -338.396944) (xy 82.848669 -338.449809) (xy 82.856604 -338.504386) (xy 82.857086 -338.531962)
			(xy 82.856609 -338.559215) (xy 82.848857 -338.613167) (xy 82.833505 -338.665465) (xy 82.810865 -338.715047)
			(xy 82.78178 -338.760308) (xy 83.436458 -338.760308) (xy 83.440529 -338.704686) (xy 83.452655 -338.650249)
			(xy 83.472578 -338.598158) (xy 83.499874 -338.549523) (xy 83.53396 -338.50538) (xy 83.574109 -338.466671)
			(xy 83.619467 -338.43422) (xy 83.669067 -338.408719) (xy 83.721851 -338.390712) (xy 83.776694 -338.380582)
			(xy 83.832428 -338.378545) (xy 83.887865 -338.384645) (xy 83.941822 -338.398751) (xy 83.993151 -338.420563)
			(xy 84.040757 -338.449617) (xy 84.083625 -338.485292) (xy 84.120842 -338.526829) (xy 84.151615 -338.573342)
			(xy 84.175287 -338.623839) (xy 84.191355 -338.677246) (xy 84.199475 -338.732422) (xy 84.199984 -338.760308)
			(xy 84.199475 -338.788194) (xy 84.191355 -338.84337) (xy 84.175287 -338.896777) (xy 84.151615 -338.947274)
			(xy 84.120842 -338.993787) (xy 84.083625 -339.035324) (xy 84.040757 -339.070999) (xy 83.993151 -339.100053)
			(xy 83.941822 -339.121865) (xy 83.887865 -339.135971) (xy 83.832428 -339.142071) (xy 83.776694 -339.140034)
			(xy 83.721851 -339.129904) (xy 83.669067 -339.111897) (xy 83.619467 -339.086396) (xy 83.574109 -339.053945)
			(xy 83.53396 -339.015236) (xy 83.499874 -338.971093) (xy 83.472578 -338.922458) (xy 83.452655 -338.870367)
			(xy 83.440529 -338.81593) (xy 83.436458 -338.760308) (xy 82.78178 -338.760308) (xy 82.781399 -338.760901)
			(xy 82.745706 -338.802095) (xy 82.704514 -338.837789) (xy 82.658661 -338.867257) (xy 82.60908 -338.889899)
			(xy 82.556782 -338.905254) (xy 82.502831 -338.913008) (xy 82.475578 -338.91347) (xy 82.447721 -338.912989)
			(xy 82.392603 -338.904862) (xy 82.33925 -338.888812) (xy 82.288796 -338.86518) (xy 82.242311 -338.834468)
			(xy 82.200782 -338.797327) (xy 82.16509 -338.754547) (xy 82.135993 -338.707034) (xy 82.114108 -338.655797)
			(xy 82.106516 -338.62899) (xy 82.10423 -338.6201) (xy 82.093562 -338.60486) (xy 82.02168 -338.557108)
			(xy 82.003646 -338.553044) (xy 81.994502 -338.554314) (xy 81.981485 -338.555981) (xy 81.955301 -338.557762)
			(xy 81.942178 -338.55787) (xy 81.928029 -338.557779) (xy 81.899806 -338.555743) (xy 81.88579 -338.553806)
			(xy 81.87563 -338.552282) (xy 81.856072 -338.557108) (xy 81.78165 -338.612988) (xy 81.77149 -338.630514)
			(xy 81.77022 -338.640674) (xy 81.766152 -338.667831) (xy 81.751175 -338.720661) (xy 81.72878 -338.770799)
			(xy 81.69943 -338.817209) (xy 81.66373 -338.858933) (xy 81.622418 -338.895108) (xy 81.576348 -338.924989)
			(xy 81.52647 -338.947957) (xy 81.473815 -338.963539) (xy 81.41947 -338.971412) (xy 81.392014 -338.97189)
			(xy 81.364761 -338.971432) (xy 81.310809 -338.963676) (xy 81.25851 -338.948321) (xy 81.208928 -338.925679)
			(xy 81.163074 -338.896211) (xy 81.121881 -338.860516) (xy 81.086187 -338.819323) (xy 81.056719 -338.773468)
			(xy 81.034078 -338.723887) (xy 81.018723 -338.671587) (xy 81.010968 -338.617635) (xy 81.010506 -338.590382)
			(xy 78.869571 -338.590382) (xy 78.87221 -338.599364) (xy 78.879972 -338.653304) (xy 78.880462 -338.680552)
			(xy 78.879812 -338.712115) (xy 78.869421 -338.774381) (xy 78.848932 -338.83409) (xy 78.834488 -338.862162)
			(xy 78.829662 -338.871052) (xy 78.82763 -338.89061) (xy 78.853284 -338.978748) (xy 78.86573 -338.994242)
			(xy 78.87462 -338.999322) (xy 78.89972 -339.013872) (xy 78.945601 -339.049377) (xy 78.985575 -339.091421)
			(xy 79.01872 -339.139034) (xy 79.044271 -339.191118) (xy 79.061638 -339.246472) (xy 79.070422 -339.303817)
			(xy 79.070962 -339.332824) (xy 79.070476 -339.360075) (xy 79.06272 -339.414023) (xy 79.056282 -339.435948)
			(xy 84.775294 -339.435948) (xy 84.775751 -339.408472) (xy 84.78365 -339.354092) (xy 84.799277 -339.301409)
			(xy 84.822308 -339.251517) (xy 84.852266 -339.205449) (xy 84.870036 -339.184488) (xy 84.876132 -339.177376)
			(xy 84.882482 -339.160358) (xy 84.882482 -339.074506) (xy 84.876132 -339.057488) (xy 84.870036 -339.050376)
			(xy 84.85227 -339.029416) (xy 84.822347 -338.983333) (xy 84.799336 -338.933438) (xy 84.783711 -338.880761)
			(xy 84.775794 -338.826388) (xy 84.775294 -338.798916) (xy 84.77578 -338.771665) (xy 84.783536 -338.717717)
			(xy 84.798891 -338.665422) (xy 84.821533 -338.615845) (xy 84.850999 -338.569995) (xy 84.88669 -338.528804)
			(xy 84.927881 -338.493113) (xy 84.973731 -338.463647) (xy 85.023308 -338.441005) (xy 85.075603 -338.42565)
			(xy 85.129551 -338.417894) (xy 85.184053 -338.417894) (xy 85.238001 -338.42565) (xy 85.290296 -338.441005)
			(xy 85.339873 -338.463647) (xy 85.385723 -338.493113) (xy 85.426914 -338.528804) (xy 85.462605 -338.569995)
			(xy 85.492071 -338.615845) (xy 85.514713 -338.665422) (xy 85.530068 -338.717717) (xy 85.537824 -338.771665)
			(xy 85.53831 -338.798916) (xy 85.537831 -338.826391) (xy 85.529937 -338.880771) (xy 85.514315 -338.933453)
			(xy 85.511686 -338.93915) (xy 85.780101 -338.93915) (xy 85.780101 -338.88465) (xy 85.787858 -338.830704)
			(xy 85.803213 -338.778411) (xy 85.825854 -338.728835) (xy 85.85532 -338.682987) (xy 85.891011 -338.641799)
			(xy 85.932201 -338.606109) (xy 85.978051 -338.576645) (xy 86.027628 -338.554007) (xy 86.079921 -338.538654)
			(xy 86.133868 -338.5309) (xy 86.161118 -338.530438) (xy 86.186353 -338.530835) (xy 86.236387 -338.537455)
			(xy 86.285107 -338.550628) (xy 86.331659 -338.570124) (xy 86.35365 -338.582508) (xy 86.363302 -338.58835)
			(xy 86.3854 -338.590382) (xy 86.479888 -338.556854) (xy 86.49589 -338.54136) (xy 86.499954 -338.530946)
			(xy 86.510643 -338.504167) (xy 86.538934 -338.453928) (xy 86.574467 -338.40852) (xy 86.61643 -338.368979)
			(xy 86.663868 -338.336206) (xy 86.715699 -338.310948) (xy 86.770741 -338.293782) (xy 86.827741 -338.285097)
			(xy 86.85657 -338.284566) (xy 86.883821 -338.285083) (xy 86.937769 -338.292835) (xy 86.990064 -338.308186)
			(xy 87.039642 -338.330823) (xy 87.085494 -338.360286) (xy 87.126686 -338.395974) (xy 87.162381 -338.437161)
			(xy 87.19185 -338.483009) (xy 87.214494 -338.532584) (xy 87.227218 -338.575904) (xy 89.368122 -338.575904)
			(xy 89.368583 -338.548329) (xy 89.376535 -338.493756) (xy 89.392261 -338.440895) (xy 89.415432 -338.390849)
			(xy 89.445565 -338.34466) (xy 89.482034 -338.303289) (xy 89.502742 -338.285074) (xy 89.510874 -338.277484)
			(xy 89.520219 -338.257323) (xy 89.520776 -338.246212) (xy 89.520776 -338.168996) (xy 89.520234 -338.157883)
			(xy 89.510878 -338.137724) (xy 89.502742 -338.130134) (xy 89.482052 -338.111899) (xy 89.445579 -338.070536)
			(xy 89.415443 -338.024352) (xy 89.392273 -337.974308) (xy 89.376552 -337.921449) (xy 89.368609 -337.866878)
			(xy 89.368122 -337.839304) (xy 89.368559 -337.81205) (xy 89.376316 -337.758096) (xy 89.391673 -337.705796)
			(xy 89.414318 -337.656214) (xy 89.443788 -337.61036) (xy 89.479485 -337.569166) (xy 89.52068 -337.533472)
			(xy 89.566537 -337.504005) (xy 89.616121 -337.481364) (xy 89.668422 -337.466011) (xy 89.722376 -337.458257)
			(xy 89.74963 -337.457796) (xy 89.78392 -337.45932) (xy 89.79408 -337.460336) (xy 89.813384 -337.45424)
			(xy 89.883996 -337.395058) (xy 89.893394 -337.377024) (xy 89.89441 -337.366864) (xy 89.897347 -337.338689)
			(xy 89.910521 -337.283595) (xy 89.9317 -337.231056) (xy 89.960418 -337.182228) (xy 89.996044 -337.138186)
			(xy 90.037793 -337.099899) (xy 90.084747 -337.06821) (xy 90.135873 -337.043815) (xy 90.190044 -337.027253)
			(xy 90.24607 -337.018886) (xy 90.274394 -337.018376) (xy 90.292413 -337.018602) (xy 90.328288 -337.022033)
			(xy 90.346022 -337.025234) (xy 90.35542 -337.027012) (xy 90.37447 -337.023202) (xy 90.449654 -336.97545)
			(xy 90.461084 -336.959702) (xy 90.46337 -336.950304) (xy 90.470776 -336.923263) (xy 90.492409 -336.87154)
			(xy 90.521374 -336.823538) (xy 90.55705 -336.780288) (xy 90.598668 -336.742722) (xy 90.645333 -336.711648)
			(xy 90.696041 -336.687734) (xy 90.749702 -336.671494) (xy 90.805162 -336.663278) (xy 90.833194 -336.662776)
			(xy 90.860444 -336.663283) (xy 90.914391 -336.671039) (xy 90.958918 -336.684112) (xy 91.388946 -336.684112)
			(xy 91.389457 -336.656202) (xy 91.397589 -336.600977) (xy 91.41368 -336.547527) (xy 91.437389 -336.496992)
			(xy 91.468208 -336.450451) (xy 91.486482 -336.42935) (xy 91.492832 -336.422238) (xy 91.499436 -336.404966)
			(xy 91.499436 -336.317844) (xy 91.492832 -336.300572) (xy 91.486482 -336.29346) (xy 91.468208 -336.272357)
			(xy 91.437381 -336.225819) (xy 91.413665 -336.175286) (xy 91.397567 -336.121835) (xy 91.389432 -336.066609)
			(xy 91.388946 -336.038698) (xy 91.389432 -336.011447) (xy 91.397188 -335.957499) (xy 91.412543 -335.905204)
			(xy 91.435185 -335.855627) (xy 91.464651 -335.809777) (xy 91.500342 -335.768586) (xy 91.541533 -335.732895)
			(xy 91.587383 -335.703429) (xy 91.63696 -335.680787) (xy 91.689255 -335.665432) (xy 91.743203 -335.657676)
			(xy 91.797705 -335.657676) (xy 91.851653 -335.665432) (xy 91.903948 -335.680787) (xy 91.953525 -335.703429)
			(xy 91.999375 -335.732895) (xy 92.040566 -335.768586) (xy 92.076257 -335.809777) (xy 92.105723 -335.855627)
			(xy 92.128365 -335.905204) (xy 92.14372 -335.957499) (xy 92.151476 -336.011447) (xy 92.151962 -336.038698)
			(xy 92.151455 -336.066608) (xy 92.143322 -336.121833) (xy 92.127229 -336.175283) (xy 92.10352 -336.225818)
			(xy 92.0727 -336.272359) (xy 92.054426 -336.29346) (xy 92.048076 -336.300572) (xy 92.041472 -336.317844)
			(xy 92.041472 -336.404966) (xy 92.048076 -336.422238) (xy 92.054426 -336.42935) (xy 92.072706 -336.450448)
			(xy 92.103532 -336.496987) (xy 92.127247 -336.547522) (xy 92.143343 -336.600974) (xy 92.151477 -336.656201)
			(xy 92.151962 -336.684112) (xy 92.151476 -336.711363) (xy 92.14372 -336.765311) (xy 92.128365 -336.817606)
			(xy 92.105723 -336.867183) (xy 92.076257 -336.913033) (xy 92.040566 -336.954224) (xy 91.999375 -336.989915)
			(xy 91.956296 -337.0176) (xy 95.771147 -337.0176) (xy 95.775316 -336.961981) (xy 95.787728 -336.907605)
			(xy 95.808105 -336.855686) (xy 95.835994 -336.807385) (xy 95.870771 -336.76378) (xy 95.911658 -336.725845)
			(xy 95.957743 -336.694429) (xy 96.007996 -336.670233) (xy 96.061294 -336.653797) (xy 96.116447 -336.645488)
			(xy 96.144334 -336.644996) (xy 96.170756 -336.645435) (xy 96.223073 -336.65289) (xy 96.273811 -336.667659)
			(xy 96.321955 -336.689447) (xy 96.366539 -336.717817) (xy 96.386904 -336.734658) (xy 96.393762 -336.740754)
			(xy 96.41078 -336.74685) (xy 96.495108 -336.74685) (xy 96.512126 -336.740754) (xy 96.518984 -336.734658)
			(xy 96.53935 -336.717819) (xy 96.583936 -336.689454) (xy 96.63208 -336.667667) (xy 96.682817 -336.652896)
			(xy 96.735132 -336.645436) (xy 96.787976 -336.645436) (xy 96.840291 -336.652896) (xy 96.891028 -336.667667)
			(xy 96.939172 -336.689454) (xy 96.983758 -336.717819) (xy 97.004124 -336.734658) (xy 97.010982 -336.740754)
			(xy 97.028 -336.74685) (xy 97.112328 -336.74685) (xy 97.129346 -336.740754) (xy 97.136204 -336.734658)
			(xy 97.157001 -336.717486) (xy 97.202585 -336.688665) (xy 97.251853 -336.666726) (xy 97.277682 -336.658966)
			(xy 97.289366 -336.655664) (xy 97.306638 -336.64017) (xy 97.3455 -336.542888) (xy 97.343722 -336.519774)
			(xy 97.337626 -336.50936) (xy 97.325246 -336.487715) (xy 97.305774 -336.441811) (xy 97.292598 -336.393719)
			(xy 97.285952 -336.3443) (xy 97.285556 -336.319368) (xy 97.286091 -336.291746) (xy 97.294244 -336.237106)
			(xy 97.310383 -336.184271) (xy 97.334151 -336.1344) (xy 97.365028 -336.08859) (xy 97.402335 -336.047845)
			(xy 97.423478 -336.030062) (xy 97.432047 -336.022498) (xy 97.441823 -336.00186) (xy 97.442274 -335.990438)
			(xy 97.442274 -335.911698) (xy 97.441697 -335.90031) (xy 97.431921 -335.87974) (xy 97.423478 -335.872074)
			(xy 97.402307 -335.854323) (xy 97.365 -335.81357) (xy 97.334123 -335.767753) (xy 97.310354 -335.717877)
			(xy 97.294213 -335.665037) (xy 97.286056 -335.610393) (xy 97.285556 -335.582768) (xy 97.286077 -335.554883)
			(xy 97.294389 -335.499736) (xy 97.310827 -335.446444) (xy 97.335025 -335.396198) (xy 97.366441 -335.350119)
			(xy 97.404374 -335.309237) (xy 97.447976 -335.274465) (xy 97.496274 -335.24658) (xy 97.548189 -335.226205)
			(xy 97.60256 -335.213795) (xy 97.658174 -335.209628) (xy 97.713788 -335.213795) (xy 97.768159 -335.226205)
			(xy 97.820074 -335.24658) (xy 97.868372 -335.274465) (xy 97.911974 -335.309237) (xy 97.949907 -335.350119)
			(xy 97.981323 -335.396198) (xy 98.005521 -335.446444) (xy 98.021959 -335.499736) (xy 98.030271 -335.554883)
			(xy 98.030792 -335.582768) (xy 98.030302 -335.610392) (xy 98.022141 -335.665035) (xy 98.005996 -335.717872)
			(xy 97.982219 -335.767742) (xy 97.951333 -335.813552) (xy 97.914017 -335.854293) (xy 97.89287 -335.872074)
			(xy 97.884322 -335.879657) (xy 97.874537 -335.900281) (xy 97.874074 -335.911698) (xy 97.874074 -335.990438)
			(xy 97.874671 -336.001824) (xy 97.884431 -336.022396) (xy 97.89287 -336.030062) (xy 97.914 -336.047861)
			(xy 97.951312 -336.088602) (xy 97.982195 -336.134409) (xy 98.005972 -336.184275) (xy 98.022121 -336.237107)
			(xy 98.030287 -336.291746) (xy 98.030792 -336.319368) (xy 98.030319 -336.346211) (xy 98.022619 -336.399341)
			(xy 98.007372 -336.450816) (xy 97.984896 -336.499569) (xy 97.955655 -336.544593) (xy 97.920256 -336.584953)
			(xy 97.879429 -336.619815) (xy 97.834023 -336.648456) (xy 97.784975 -336.670284) (xy 97.759266 -336.678016)
			(xy 97.747582 -336.681318) (xy 97.73031 -336.696812) (xy 97.691448 -336.794094) (xy 97.693226 -336.817208)
			(xy 97.699322 -336.827622) (xy 97.711699 -336.849268) (xy 97.731171 -336.895173) (xy 97.744348 -336.943264)
			(xy 97.750995 -336.992682) (xy 97.751392 -337.017614) (xy 97.750979 -337.044233) (xy 97.7434 -337.09693)
			(xy 97.728399 -337.148011) (xy 97.70628 -337.196438) (xy 97.677495 -337.241224) (xy 97.642629 -337.281457)
			(xy 97.602392 -337.316319) (xy 97.557603 -337.345099) (xy 97.509174 -337.367213) (xy 97.458091 -337.382208)
			(xy 97.405393 -337.389782) (xy 97.378774 -337.390232) (xy 97.352352 -337.389782) (xy 97.300037 -337.382329)
			(xy 97.249298 -337.367562) (xy 97.201154 -337.345776) (xy 97.156569 -337.31741) (xy 97.136204 -337.30057)
			(xy 97.129346 -337.294474) (xy 97.112328 -337.288378) (xy 97.028 -337.288378) (xy 97.010982 -337.294474)
			(xy 97.004124 -337.30057) (xy 96.983758 -337.317409) (xy 96.939172 -337.345774) (xy 96.891028 -337.367561)
			(xy 96.840291 -337.382332) (xy 96.787976 -337.389792) (xy 96.735132 -337.389792) (xy 96.682817 -337.382332)
			(xy 96.63208 -337.367561) (xy 96.583936 -337.345774) (xy 96.53935 -337.317409) (xy 96.518984 -337.30057)
			(xy 96.512126 -337.294474) (xy 96.495108 -337.288378) (xy 96.41078 -337.288378) (xy 96.393762 -337.294474)
			(xy 96.386904 -337.30057) (xy 96.366533 -337.317402) (xy 96.321945 -337.345759) (xy 96.273802 -337.36754)
			(xy 96.223066 -337.382309) (xy 96.170755 -337.38977) (xy 96.144334 -337.390232) (xy 96.116447 -337.389712)
			(xy 96.061294 -337.381403) (xy 96.007996 -337.364967) (xy 95.957743 -337.340771) (xy 95.911658 -337.309355)
			(xy 95.870771 -337.27142) (xy 95.835994 -337.227815) (xy 95.808105 -337.179514) (xy 95.787728 -337.127595)
			(xy 95.775316 -337.073219) (xy 95.771147 -337.0176) (xy 91.956296 -337.0176) (xy 91.953525 -337.019381)
			(xy 91.903948 -337.042023) (xy 91.851653 -337.057378) (xy 91.797705 -337.065134) (xy 91.743203 -337.065134)
			(xy 91.689255 -337.057378) (xy 91.63696 -337.042023) (xy 91.587383 -337.019381) (xy 91.541533 -336.989915)
			(xy 91.500342 -336.954224) (xy 91.464651 -336.913033) (xy 91.435185 -336.867183) (xy 91.412543 -336.817606)
			(xy 91.397188 -336.765311) (xy 91.389432 -336.711363) (xy 91.388946 -336.684112) (xy 90.958918 -336.684112)
			(xy 90.966684 -336.686392) (xy 91.01626 -336.709031) (xy 91.06211 -336.738496) (xy 91.1033 -336.774185)
			(xy 91.138991 -336.815373) (xy 91.168458 -336.861221) (xy 91.1911 -336.910795) (xy 91.206457 -336.963088)
			(xy 91.214215 -337.017034) (xy 91.214702 -337.044284) (xy 91.214225 -337.071858) (xy 91.206274 -337.12643)
			(xy 91.190552 -337.17929) (xy 91.167384 -337.229336) (xy 91.137253 -337.275526) (xy 91.100788 -337.316898)
			(xy 91.080082 -337.335114) (xy 91.071959 -337.342712) (xy 91.062608 -337.362867) (xy 91.062048 -337.373976)
			(xy 91.062048 -337.451192) (xy 91.062589 -337.462306) (xy 91.071945 -337.482465) (xy 91.080082 -337.490054)
			(xy 91.100772 -337.508287) (xy 91.137237 -337.549655) (xy 91.167366 -337.595843) (xy 91.19053 -337.645888)
			(xy 91.206246 -337.698746) (xy 91.214188 -337.753317) (xy 91.21419 -337.808462) (xy 91.206251 -337.863034)
			(xy 91.190577 -337.915758) (xy 92.346778 -337.915758) (xy 92.350849 -337.860136) (xy 92.362975 -337.805699)
			(xy 92.382898 -337.753608) (xy 92.410194 -337.704973) (xy 92.44428 -337.66083) (xy 92.484429 -337.622121)
			(xy 92.529787 -337.58967) (xy 92.579387 -337.564169) (xy 92.632171 -337.546162) (xy 92.687014 -337.536032)
			(xy 92.742748 -337.533995) (xy 92.798185 -337.540095) (xy 92.852142 -337.554201) (xy 92.903471 -337.576013)
			(xy 92.951077 -337.605067) (xy 92.993945 -337.640742) (xy 93.031162 -337.682279) (xy 93.061935 -337.728792)
			(xy 93.085607 -337.779289) (xy 93.101675 -337.832696) (xy 93.109795 -337.887872) (xy 93.110304 -337.915758)
			(xy 93.109795 -337.943644) (xy 93.101675 -337.99882) (xy 93.085607 -338.052227) (xy 93.061935 -338.102724)
			(xy 93.031162 -338.149237) (xy 92.993945 -338.190774) (xy 92.951077 -338.226449) (xy 92.903471 -338.255503)
			(xy 92.852142 -338.277315) (xy 92.798185 -338.291421) (xy 92.742748 -338.297521) (xy 92.687014 -338.295484)
			(xy 92.632171 -338.285354) (xy 92.579387 -338.267347) (xy 92.529787 -338.241846) (xy 92.484429 -338.209395)
			(xy 92.44428 -338.170686) (xy 92.410194 -338.126543) (xy 92.382898 -338.077908) (xy 92.362975 -338.025817)
			(xy 92.350849 -337.97138) (xy 92.346778 -337.915758) (xy 91.190577 -337.915758) (xy 91.190537 -337.915893)
			(xy 91.167376 -337.965939) (xy 91.13725 -338.012128) (xy 91.100787 -338.053499) (xy 91.080082 -338.071714)
			(xy 91.071959 -338.079312) (xy 91.062608 -338.099467) (xy 91.062048 -338.110576) (xy 91.062048 -338.187792)
			(xy 91.062589 -338.198906) (xy 91.071945 -338.219065) (xy 91.080082 -338.226654) (xy 91.100771 -338.24489)
			(xy 91.137243 -338.286253) (xy 91.167379 -338.332437) (xy 91.190549 -338.382481) (xy 91.20627 -338.435339)
			(xy 91.214214 -338.489911) (xy 91.214702 -338.517484) (xy 91.21423 -338.544737) (xy 91.206475 -338.598688)
			(xy 91.191121 -338.650986) (xy 91.168479 -338.700566) (xy 91.139013 -338.74642) (xy 91.10332 -338.787613)
			(xy 91.076206 -338.811108) (xy 91.767658 -338.811108) (xy 91.771729 -338.755486) (xy 91.783855 -338.701049)
			(xy 91.803778 -338.648958) (xy 91.831074 -338.600323) (xy 91.86516 -338.55618) (xy 91.905309 -338.517471)
			(xy 91.950667 -338.48502) (xy 92.000267 -338.459519) (xy 92.053051 -338.441512) (xy 92.107894 -338.431382)
			(xy 92.163628 -338.429345) (xy 92.219065 -338.435445) (xy 92.273022 -338.449551) (xy 92.324351 -338.471363)
			(xy 92.371957 -338.500417) (xy 92.414825 -338.536092) (xy 92.452042 -338.577629) (xy 92.482815 -338.624142)
			(xy 92.506487 -338.674639) (xy 92.522555 -338.728046) (xy 92.530675 -338.783222) (xy 92.531184 -338.811108)
			(xy 92.530675 -338.838994) (xy 92.522555 -338.89417) (xy 92.506487 -338.947577) (xy 92.482815 -338.998074)
			(xy 92.452042 -339.044587) (xy 92.414825 -339.086124) (xy 92.371957 -339.121799) (xy 92.324351 -339.150853)
			(xy 92.273022 -339.172665) (xy 92.219065 -339.186771) (xy 92.163628 -339.192871) (xy 92.107894 -339.190834)
			(xy 92.053051 -339.180704) (xy 92.000267 -339.162697) (xy 91.950667 -339.137196) (xy 91.905309 -339.104745)
			(xy 91.86516 -339.066036) (xy 91.831074 -339.021893) (xy 91.803778 -338.973258) (xy 91.783855 -338.921167)
			(xy 91.771729 -338.86673) (xy 91.767658 -338.811108) (xy 91.076206 -338.811108) (xy 91.062128 -338.823307)
			(xy 91.016275 -338.852775) (xy 90.966695 -338.875417) (xy 90.914397 -338.890773) (xy 90.860447 -338.898529)
			(xy 90.833194 -338.898992) (xy 90.805338 -338.89848) (xy 90.750222 -338.890356) (xy 90.696871 -338.874309)
			(xy 90.646418 -338.850681) (xy 90.599933 -338.819973) (xy 90.558404 -338.782836) (xy 90.522711 -338.740059)
			(xy 90.493612 -338.69255) (xy 90.471725 -338.641318) (xy 90.464132 -338.614512) (xy 90.461846 -338.605622)
			(xy 90.451178 -338.590382) (xy 90.379296 -338.54263) (xy 90.361262 -338.538566) (xy 90.352118 -338.539836)
			(xy 90.339101 -338.541502) (xy 90.312917 -338.543284) (xy 90.299794 -338.543392) (xy 90.285645 -338.543299)
			(xy 90.257422 -338.541264) (xy 90.243406 -338.539328) (xy 90.233246 -338.537804) (xy 90.213688 -338.54263)
			(xy 90.139266 -338.59851) (xy 90.129106 -338.616036) (xy 90.127836 -338.626196) (xy 90.12377 -338.653353)
			(xy 90.108791 -338.706182) (xy 90.086395 -338.756319) (xy 90.057043 -338.802728) (xy 90.021343 -338.844451)
			(xy 89.980032 -338.880626) (xy 89.933961 -338.910507) (xy 89.884084 -338.933475) (xy 89.83143 -338.949058)
			(xy 89.777086 -338.956933) (xy 89.74963 -338.957412) (xy 89.722378 -338.956917) (xy 89.668428 -338.949164)
			(xy 89.616131 -338.933812) (xy 89.566552 -338.911173) (xy 89.520699 -338.881709) (xy 89.479506 -338.846018)
			(xy 89.443812 -338.804829) (xy 89.414343 -338.758978) (xy 89.3917 -338.7094) (xy 89.376343 -338.657105)
			(xy 89.368586 -338.603156) (xy 89.368122 -338.575904) (xy 87.227218 -338.575904) (xy 87.229853 -338.584877)
			(xy 87.237613 -338.638823) (xy 87.238078 -338.666074) (xy 87.237435 -338.697638) (xy 87.227041 -338.759903)
			(xy 87.206549 -338.819612) (xy 87.192104 -338.847684) (xy 87.187278 -338.856574) (xy 87.185246 -338.876132)
			(xy 87.2109 -338.96427) (xy 87.223346 -338.979764) (xy 87.232236 -338.984844) (xy 87.257326 -338.999411)
			(xy 87.303211 -339.034909) (xy 87.343189 -339.076948) (xy 87.376337 -339.124559) (xy 87.40189 -339.176642)
			(xy 87.419257 -339.231994) (xy 87.428039 -339.289339) (xy 87.428578 -339.318346) (xy 87.428092 -339.345597)
			(xy 87.420336 -339.399545) (xy 87.404981 -339.45184) (xy 87.382339 -339.501417) (xy 87.352873 -339.547267)
			(xy 87.317182 -339.588458) (xy 87.275991 -339.624149) (xy 87.230141 -339.653615) (xy 87.180564 -339.676257)
			(xy 87.128269 -339.691612) (xy 87.074321 -339.699368) (xy 87.019819 -339.699368) (xy 86.965871 -339.691612)
			(xy 86.913576 -339.676257) (xy 86.863999 -339.653615) (xy 86.818149 -339.624149) (xy 86.776958 -339.588458)
			(xy 86.741267 -339.547267) (xy 86.711801 -339.501417) (xy 86.689159 -339.45184) (xy 86.673804 -339.399545)
			(xy 86.666048 -339.345597) (xy 86.665562 -339.318346) (xy 86.66622 -339.286783) (xy 86.676609 -339.224518)
			(xy 86.697095 -339.164809) (xy 86.711536 -339.136736) (xy 86.716362 -339.127846) (xy 86.718394 -339.108288)
			(xy 86.69274 -339.02015) (xy 86.680294 -339.004656) (xy 86.671404 -338.999576) (xy 86.664038 -338.995512)
			(xy 86.654386 -338.98967) (xy 86.632288 -338.987638) (xy 86.5378 -339.021166) (xy 86.521798 -339.03666)
			(xy 86.517734 -339.047074) (xy 86.507012 -339.07384) (xy 86.47873 -339.124082) (xy 86.443204 -339.169493)
			(xy 86.401247 -339.209037) (xy 86.353813 -339.241813) (xy 86.301985 -339.267072) (xy 86.246944 -339.28424)
			(xy 86.189946 -339.292924) (xy 86.161118 -339.293454) (xy 86.133868 -339.2929) (xy 86.079921 -339.285146)
			(xy 86.027628 -339.269793) (xy 85.978051 -339.247155) (xy 85.932201 -339.217691) (xy 85.891011 -339.182001)
			(xy 85.85532 -339.140813) (xy 85.825854 -339.094965) (xy 85.803213 -339.045389) (xy 85.787858 -338.993096)
			(xy 85.780101 -338.93915) (xy 85.511686 -338.93915) (xy 85.491289 -338.983346) (xy 85.461336 -339.029414)
			(xy 85.443568 -339.050376) (xy 85.437472 -339.057488) (xy 85.431122 -339.074506) (xy 85.431122 -339.160358)
			(xy 85.437472 -339.177376) (xy 85.443568 -339.184488) (xy 85.461318 -339.205461) (xy 85.491243 -339.251541)
			(xy 85.514257 -339.301433) (xy 85.529886 -339.354107) (xy 85.537808 -339.408477) (xy 85.53831 -339.435948)
			(xy 85.537824 -339.463199) (xy 85.530068 -339.517147) (xy 85.514713 -339.569442) (xy 85.492071 -339.619019)
			(xy 85.462605 -339.664869) (xy 85.426914 -339.70606) (xy 85.385723 -339.741751) (xy 85.339873 -339.771217)
			(xy 85.290296 -339.793859) (xy 85.238001 -339.809214) (xy 85.184053 -339.81697) (xy 85.129551 -339.81697)
			(xy 85.075603 -339.809214) (xy 85.023308 -339.793859) (xy 84.973731 -339.771217) (xy 84.927881 -339.741751)
			(xy 84.88669 -339.70606) (xy 84.850999 -339.664869) (xy 84.821533 -339.619019) (xy 84.798891 -339.569442)
			(xy 84.783536 -339.517147) (xy 84.77578 -339.463199) (xy 84.775294 -339.435948) (xy 79.056282 -339.435948)
			(xy 79.047365 -339.466318) (xy 79.024723 -339.515895) (xy 78.995257 -339.561745) (xy 78.959566 -339.602936)
			(xy 78.918375 -339.638627) (xy 78.872525 -339.668093) (xy 78.822948 -339.690735) (xy 78.770653 -339.70609)
			(xy 78.716705 -339.713846) (xy 78.662203 -339.713846) (xy 78.608255 -339.70609) (xy 78.55596 -339.690735)
			(xy 78.506383 -339.668093) (xy 78.460533 -339.638627) (xy 78.419342 -339.602936) (xy 78.383651 -339.561745)
			(xy 78.354185 -339.515895) (xy 78.331543 -339.466318) (xy 78.316188 -339.414023) (xy 78.308432 -339.360075)
			(xy 78.307946 -339.332824) (xy 78.308586 -339.30126) (xy 78.31898 -339.238994) (xy 78.339474 -339.179286)
			(xy 78.35392 -339.151214) (xy 78.358746 -339.142324) (xy 78.360778 -339.122766) (xy 78.335124 -339.034628)
			(xy 78.322678 -339.019134) (xy 78.313788 -339.014054) (xy 78.306422 -339.00999) (xy 78.29677 -339.004148)
			(xy 78.274672 -339.002116) (xy 78.180184 -339.035644) (xy 78.164182 -339.051138) (xy 78.160118 -339.061552)
			(xy 78.149451 -339.088341) (xy 78.121157 -339.138581) (xy 78.085622 -339.183989) (xy 78.043656 -339.22353)
			(xy 77.996215 -339.256302) (xy 77.94438 -339.281558) (xy 77.889334 -339.298722) (xy 77.832332 -339.307403)
			(xy 77.803502 -339.307932) (xy 77.776251 -339.307421) (xy 77.722303 -339.299665) (xy 77.670008 -339.28431)
			(xy 77.620431 -339.261669) (xy 77.57458 -339.232203) (xy 77.53339 -339.196511) (xy 77.497699 -339.155321)
			(xy 77.468232 -339.109471) (xy 77.445591 -339.059894) (xy 77.430236 -339.007599) (xy 77.422479 -338.953651)
			(xy 77.154055 -338.953651) (xy 77.133671 -338.997823) (xy 77.103719 -339.043892) (xy 77.085952 -339.064854)
			(xy 77.079856 -339.071966) (xy 77.073506 -339.088984) (xy 77.073506 -339.174836) (xy 77.079856 -339.191854)
			(xy 77.085952 -339.198966) (xy 77.103689 -339.21995) (xy 77.133616 -339.266026) (xy 77.156633 -339.315915)
			(xy 77.172266 -339.368587) (xy 77.18019 -339.422955) (xy 77.180694 -339.450426) (xy 77.180208 -339.477677)
			(xy 77.172452 -339.531625) (xy 77.157097 -339.58392) (xy 77.134455 -339.633497) (xy 77.104989 -339.679347)
			(xy 77.069298 -339.720538) (xy 77.028107 -339.756229) (xy 76.982257 -339.785695) (xy 76.93268 -339.808337)
			(xy 76.880385 -339.823692) (xy 76.826437 -339.831448) (xy 76.771935 -339.831448) (xy 76.717987 -339.823692)
			(xy 76.665692 -339.808337) (xy 76.616115 -339.785695) (xy 76.570265 -339.756229) (xy 76.529074 -339.720538)
			(xy 76.493383 -339.679347) (xy 76.463917 -339.633497) (xy 76.441275 -339.58392) (xy 76.42592 -339.531625)
			(xy 76.418164 -339.477677) (xy 76.417678 -339.450426) (xy 70.698535 -339.450426) (xy 70.691781 -339.47343)
			(xy 70.669139 -339.523007) (xy 70.639673 -339.568857) (xy 70.603982 -339.610048) (xy 70.562791 -339.645739)
			(xy 70.516941 -339.675205) (xy 70.467364 -339.697847) (xy 70.415069 -339.713202) (xy 70.361121 -339.720958)
			(xy 70.306619 -339.720958) (xy 70.252671 -339.713202) (xy 70.200376 -339.697847) (xy 70.150799 -339.675205)
			(xy 70.104949 -339.645739) (xy 70.063758 -339.610048) (xy 70.028067 -339.568857) (xy 69.998601 -339.523007)
			(xy 69.975959 -339.47343) (xy 69.960604 -339.421135) (xy 69.952848 -339.367187) (xy 69.952362 -339.339936)
			(xy 69.953016 -339.308373) (xy 69.963407 -339.246108) (xy 69.983894 -339.186399) (xy 69.998336 -339.158326)
			(xy 70.003162 -339.149436) (xy 70.005194 -339.129878) (xy 69.97954 -339.04174) (xy 69.967094 -339.026246)
			(xy 69.958204 -339.021166) (xy 69.950838 -339.017102) (xy 69.941186 -339.01126) (xy 69.919088 -339.009228)
			(xy 69.8246 -339.042756) (xy 69.808598 -339.05825) (xy 69.804534 -339.068664) (xy 69.79386 -339.095449)
			(xy 69.765567 -339.145689) (xy 69.730032 -339.191097) (xy 69.688066 -339.230637) (xy 69.640626 -339.263409)
			(xy 69.588793 -339.288665) (xy 69.533749 -339.305831) (xy 69.476747 -339.314514) (xy 69.447918 -339.315044)
			(xy 69.420667 -339.31451) (xy 69.366719 -339.306756) (xy 69.314424 -339.291403) (xy 69.264846 -339.268763)
			(xy 69.218995 -339.239299) (xy 69.177804 -339.203608) (xy 69.142112 -339.162419) (xy 69.112645 -339.11657)
			(xy 69.090004 -339.066993) (xy 69.074648 -339.014699) (xy 69.066891 -338.960751) (xy 68.798477 -338.960751)
			(xy 68.778087 -339.004935) (xy 68.748135 -339.051004) (xy 68.730368 -339.071966) (xy 68.724272 -339.079078)
			(xy 68.717922 -339.096096) (xy 68.717922 -339.181948) (xy 68.724272 -339.198966) (xy 68.730368 -339.206078)
			(xy 68.748113 -339.227055) (xy 68.778039 -339.273134) (xy 68.801054 -339.323024) (xy 68.816684 -339.375698)
			(xy 68.824607 -339.430067) (xy 68.82511 -339.457538) (xy 68.824624 -339.484789) (xy 68.816868 -339.538737)
			(xy 68.801513 -339.591032) (xy 68.778871 -339.640609) (xy 68.749405 -339.686459) (xy 68.713714 -339.72765)
			(xy 68.672523 -339.763341) (xy 68.626673 -339.792807) (xy 68.577096 -339.815449) (xy 68.524801 -339.830804)
			(xy 68.470853 -339.83856) (xy 68.416351 -339.83856) (xy 68.362403 -339.830804) (xy 68.310108 -339.815449)
			(xy 68.260531 -339.792807) (xy 68.214681 -339.763341) (xy 68.17349 -339.72765) (xy 68.137799 -339.686459)
			(xy 68.108333 -339.640609) (xy 68.085691 -339.591032) (xy 68.070336 -339.538737) (xy 68.06258 -339.484789)
			(xy 68.062094 -339.457538) (xy 21.260816 -339.457538) (xy 21.260816 -343.394792) (xy 21.261238 -343.404863)
			(xy 21.268952 -343.423468) (xy 21.275802 -343.43086) (xy 24.110442 -346.2655) (xy 24.117295 -346.272896)
			(xy 24.125038 -346.291494) (xy 24.125428 -346.301568) (xy 24.125428 -348.375986) (xy 24.536146 -348.375986)
			(xy 24.536641 -348.348075) (xy 24.544777 -348.29285) (xy 24.560872 -348.2394) (xy 24.584584 -348.188865)
			(xy 24.615406 -348.142325) (xy 24.633682 -348.121224) (xy 24.640032 -348.114112) (xy 24.646636 -348.09684)
			(xy 24.646636 -348.009718) (xy 24.640032 -347.992446) (xy 24.633682 -347.985334) (xy 24.615396 -347.964241)
			(xy 24.58457 -347.917701) (xy 24.560857 -347.867164) (xy 24.544762 -347.813712) (xy 24.53663 -347.758484)
			(xy 24.536146 -347.730572) (xy 24.536632 -347.703321) (xy 24.544388 -347.649373) (xy 24.559743 -347.597078)
			(xy 24.582385 -347.547501) (xy 24.611851 -347.501651) (xy 24.647542 -347.46046) (xy 24.688733 -347.424769)
			(xy 24.734583 -347.395303) (xy 24.78416 -347.372661) (xy 24.836455 -347.357306) (xy 24.890403 -347.34955)
			(xy 24.944905 -347.34955) (xy 24.998853 -347.357306) (xy 25.051148 -347.372661) (xy 25.100725 -347.395303)
			(xy 25.146575 -347.424769) (xy 25.187766 -347.46046) (xy 25.223457 -347.501651) (xy 25.252923 -347.547501)
			(xy 25.275565 -347.597078) (xy 25.29092 -347.649373) (xy 25.298676 -347.703321) (xy 25.299162 -347.730572)
			(xy 25.298699 -347.758484) (xy 25.290555 -347.81371) (xy 25.274452 -347.867161) (xy 25.250733 -347.917695)
			(xy 25.219905 -347.964234) (xy 25.201626 -347.985334) (xy 25.195276 -347.992446) (xy 25.188672 -348.009718)
			(xy 25.188672 -348.09684) (xy 25.195276 -348.114112) (xy 25.201626 -348.121224) (xy 25.219894 -348.142332)
			(xy 25.250722 -348.188868) (xy 25.274439 -348.239401) (xy 25.290538 -348.29285) (xy 25.298675 -348.348075)
			(xy 25.299162 -348.375986) (xy 25.298676 -348.403237) (xy 25.29092 -348.457185) (xy 25.275565 -348.50948)
			(xy 25.252923 -348.559057) (xy 25.223457 -348.604907) (xy 25.187766 -348.646098) (xy 25.146575 -348.681789)
			(xy 25.103456 -348.7095) (xy 28.918321 -348.7095) (xy 28.92249 -348.653877) (xy 28.934903 -348.599498)
			(xy 28.955282 -348.547575) (xy 28.983173 -348.49927) (xy 29.017952 -348.455662) (xy 29.058842 -348.417725)
			(xy 29.10493 -348.386307) (xy 29.155187 -348.362108) (xy 29.208488 -348.345671) (xy 29.263645 -348.337363)
			(xy 29.291534 -348.33687) (xy 29.317956 -348.337315) (xy 29.370272 -348.344769) (xy 29.42101 -348.359538)
			(xy 29.469154 -348.381324) (xy 29.513739 -348.409692) (xy 29.534104 -348.426532) (xy 29.540962 -348.432628)
			(xy 29.55798 -348.438724) (xy 29.642308 -348.438724) (xy 29.659326 -348.432628) (xy 29.666184 -348.426532)
			(xy 29.68655 -348.409693) (xy 29.731136 -348.381328) (xy 29.77928 -348.359541) (xy 29.830017 -348.34477)
			(xy 29.882332 -348.33731) (xy 29.935176 -348.33731) (xy 29.987491 -348.34477) (xy 30.038228 -348.359541)
			(xy 30.086372 -348.381328) (xy 30.130958 -348.409693) (xy 30.151324 -348.426532) (xy 30.158182 -348.432628)
			(xy 30.1752 -348.438724) (xy 30.259528 -348.438724) (xy 30.276546 -348.432628) (xy 30.283404 -348.426532)
			(xy 30.304989 -348.408734) (xy 30.35245 -348.379119) (xy 30.403805 -348.356931) (xy 30.430724 -348.349316)
			(xy 30.44317 -348.346014) (xy 30.461204 -348.32925) (xy 30.498034 -348.226126) (xy 30.494478 -348.201488)
			(xy 30.486858 -348.191328) (xy 30.469594 -348.16671) (xy 30.442238 -348.113167) (xy 30.423634 -348.055991)
			(xy 30.414244 -347.996602) (xy 30.413706 -347.966538) (xy 30.414196 -347.938964) (xy 30.422143 -347.884392)
			(xy 30.437863 -347.831533) (xy 30.461029 -347.781487) (xy 30.491157 -347.735297) (xy 30.527621 -347.693924)
			(xy 30.548326 -347.675708) (xy 30.556441 -347.668102) (xy 30.565796 -347.647953) (xy 30.56636 -347.636846)
			(xy 30.56636 -347.55963) (xy 30.565804 -347.548518) (xy 30.556458 -347.528359) (xy 30.548326 -347.520768)
			(xy 30.527601 -347.502571) (xy 30.491131 -347.4612) (xy 30.461 -347.415008) (xy 30.437836 -347.364957)
			(xy 30.422123 -347.312091) (xy 30.414188 -347.257514) (xy 30.413706 -347.229938) (xy 30.414192 -347.202687)
			(xy 30.421948 -347.148739) (xy 30.437303 -347.096444) (xy 30.459945 -347.046867) (xy 30.489411 -347.001017)
			(xy 30.525102 -346.959826) (xy 30.566293 -346.924135) (xy 30.612143 -346.894669) (xy 30.66172 -346.872027)
			(xy 30.714015 -346.856672) (xy 30.767963 -346.848916) (xy 30.822465 -346.848916) (xy 30.876413 -346.856672)
			(xy 30.928708 -346.872027) (xy 30.978285 -346.894669) (xy 31.024135 -346.924135) (xy 31.065326 -346.959826)
			(xy 31.101017 -347.001017) (xy 31.130483 -347.046867) (xy 31.153125 -347.096444) (xy 31.16848 -347.148739)
			(xy 31.176236 -347.202687) (xy 31.176722 -347.229938) (xy 31.176206 -347.257511) (xy 31.168263 -347.312081)
			(xy 31.152547 -347.36494) (xy 31.129386 -347.414986) (xy 31.099263 -347.461176) (xy 31.062805 -347.50255)
			(xy 31.042102 -347.520768) (xy 31.034003 -347.528388) (xy 31.024638 -347.548526) (xy 31.024068 -347.55963)
			(xy 31.024068 -347.636846) (xy 31.024629 -347.647957) (xy 31.03397 -347.668117) (xy 31.042102 -347.675708)
			(xy 31.062821 -347.693911) (xy 31.09929 -347.735282) (xy 31.129421 -347.781473) (xy 31.152586 -347.831523)
			(xy 31.168301 -347.884387) (xy 31.176238 -347.938963) (xy 31.176722 -347.966538) (xy 31.176251 -347.994643)
			(xy 31.167999 -348.050245) (xy 31.151678 -348.104034) (xy 31.127642 -348.154846) (xy 31.096411 -348.201583)
			(xy 31.058662 -348.243231) (xy 31.01521 -348.27889) (xy 30.966997 -348.307789) (xy 30.915065 -348.329301)
			(xy 30.887924 -348.336616) (xy 30.875478 -348.339664) (xy 30.85719 -348.356174) (xy 30.849901 -348.375986)
			(xy 32.816546 -348.375986) (xy 32.817041 -348.348075) (xy 32.825177 -348.29285) (xy 32.841272 -348.2394)
			(xy 32.864984 -348.188865) (xy 32.895806 -348.142325) (xy 32.914082 -348.121224) (xy 32.920432 -348.114112)
			(xy 32.927036 -348.09684) (xy 32.927036 -348.009718) (xy 32.920432 -347.992446) (xy 32.914082 -347.985334)
			(xy 32.895796 -347.964241) (xy 32.86497 -347.917701) (xy 32.841257 -347.867164) (xy 32.825162 -347.813712)
			(xy 32.81703 -347.758484) (xy 32.816546 -347.730572) (xy 32.817032 -347.703321) (xy 32.824788 -347.649373)
			(xy 32.840143 -347.597078) (xy 32.862785 -347.547501) (xy 32.892251 -347.501651) (xy 32.927942 -347.46046)
			(xy 32.969133 -347.424769) (xy 33.014983 -347.395303) (xy 33.06456 -347.372661) (xy 33.116855 -347.357306)
			(xy 33.170803 -347.34955) (xy 33.225305 -347.34955) (xy 33.279253 -347.357306) (xy 33.331548 -347.372661)
			(xy 33.381125 -347.395303) (xy 33.426975 -347.424769) (xy 33.468166 -347.46046) (xy 33.503857 -347.501651)
			(xy 33.533323 -347.547501) (xy 33.555965 -347.597078) (xy 33.57132 -347.649373) (xy 33.579076 -347.703321)
			(xy 33.579562 -347.730572) (xy 33.579099 -347.758484) (xy 33.570955 -347.81371) (xy 33.554852 -347.867161)
			(xy 33.531133 -347.917695) (xy 33.500305 -347.964234) (xy 33.482026 -347.985334) (xy 33.475676 -347.992446)
			(xy 33.469072 -348.009718) (xy 33.469072 -348.09684) (xy 33.475676 -348.114112) (xy 33.482026 -348.121224)
			(xy 33.500294 -348.142332) (xy 33.531122 -348.188868) (xy 33.554839 -348.239401) (xy 33.570938 -348.29285)
			(xy 33.579075 -348.348075) (xy 33.579562 -348.375986) (xy 33.579076 -348.403237) (xy 33.57132 -348.457185)
			(xy 33.555965 -348.50948) (xy 33.533323 -348.559057) (xy 33.503857 -348.604907) (xy 33.468166 -348.646098)
			(xy 33.426975 -348.681789) (xy 33.383856 -348.7095) (xy 37.198721 -348.7095) (xy 37.20289 -348.653877)
			(xy 37.215303 -348.599498) (xy 37.235682 -348.547575) (xy 37.263573 -348.49927) (xy 37.298352 -348.455662)
			(xy 37.339242 -348.417725) (xy 37.38533 -348.386307) (xy 37.435587 -348.362108) (xy 37.488888 -348.345671)
			(xy 37.544045 -348.337363) (xy 37.571934 -348.33687) (xy 37.598356 -348.337315) (xy 37.650672 -348.344769)
			(xy 37.70141 -348.359538) (xy 37.749554 -348.381324) (xy 37.794139 -348.409692) (xy 37.814504 -348.426532)
			(xy 37.821362 -348.432628) (xy 37.83838 -348.438724) (xy 37.922708 -348.438724) (xy 37.939726 -348.432628)
			(xy 37.946584 -348.426532) (xy 37.96695 -348.409693) (xy 38.011536 -348.381328) (xy 38.05968 -348.359541)
			(xy 38.110417 -348.34477) (xy 38.162732 -348.33731) (xy 38.215576 -348.33731) (xy 38.267891 -348.34477)
			(xy 38.318628 -348.359541) (xy 38.366772 -348.381328) (xy 38.411358 -348.409693) (xy 38.431724 -348.426532)
			(xy 38.438582 -348.432628) (xy 38.4556 -348.438724) (xy 38.539928 -348.438724) (xy 38.556946 -348.432628)
			(xy 38.563804 -348.426532) (xy 38.582653 -348.410899) (xy 38.623697 -348.384187) (xy 38.667889 -348.363089)
			(xy 38.691058 -348.355158) (xy 38.702996 -348.351348) (xy 38.71976 -348.33433) (xy 38.75278 -348.232476)
			(xy 38.749224 -348.208854) (xy 38.741858 -348.198694) (xy 38.724615 -348.1741) (xy 38.697284 -348.120617)
			(xy 38.678681 -348.063509) (xy 38.669266 -348.004189) (xy 38.668706 -347.974158) (xy 38.66921 -347.946585)
			(xy 38.677154 -347.892014) (xy 38.692871 -347.839154) (xy 38.716034 -347.789108) (xy 38.74616 -347.742918)
			(xy 38.782622 -347.701545) (xy 38.803326 -347.683328) (xy 38.811432 -347.675714) (xy 38.820792 -347.655571)
			(xy 38.82136 -347.644466) (xy 38.82136 -347.56725) (xy 38.820793 -347.55614) (xy 38.811455 -347.53598)
			(xy 38.803326 -347.528388) (xy 38.782611 -347.510181) (xy 38.74614 -347.468812) (xy 38.716008 -347.422621)
			(xy 38.692842 -347.372573) (xy 38.677127 -347.319709) (xy 38.66919 -347.265133) (xy 38.668706 -347.237558)
			(xy 38.669192 -347.210307) (xy 38.676948 -347.156359) (xy 38.692303 -347.104064) (xy 38.714945 -347.054487)
			(xy 38.744411 -347.008637) (xy 38.780102 -346.967446) (xy 38.821293 -346.931755) (xy 38.867143 -346.902289)
			(xy 38.91672 -346.879647) (xy 38.969015 -346.864292) (xy 39.022963 -346.856536) (xy 39.077465 -346.856536)
			(xy 39.131413 -346.864292) (xy 39.183708 -346.879647) (xy 39.233285 -346.902289) (xy 39.279135 -346.931755)
			(xy 39.320326 -346.967446) (xy 39.356017 -347.008637) (xy 39.385483 -347.054487) (xy 39.408125 -347.104064)
			(xy 39.42348 -347.156359) (xy 39.431236 -347.210307) (xy 39.431722 -347.237558) (xy 39.43122 -347.265131)
			(xy 39.423274 -347.319702) (xy 39.407555 -347.372561) (xy 39.384392 -347.422607) (xy 39.354266 -347.468797)
			(xy 39.317806 -347.510171) (xy 39.297102 -347.528388) (xy 39.288994 -347.536) (xy 39.279634 -347.556144)
			(xy 39.279068 -347.56725) (xy 39.279068 -347.644466) (xy 39.279617 -347.655579) (xy 39.288967 -347.675739)
			(xy 39.297102 -347.683328) (xy 39.31783 -347.70152) (xy 39.354299 -347.742893) (xy 39.384429 -347.789087)
			(xy 39.407592 -347.839139) (xy 39.423305 -347.892005) (xy 39.431239 -347.946582) (xy 39.431722 -347.974158)
			(xy 39.431285 -348.001084) (xy 39.423713 -348.0544) (xy 39.408714 -348.10612) (xy 39.386586 -348.155215)
			(xy 39.357769 -348.200708) (xy 39.322837 -348.241693) (xy 39.282486 -348.277354) (xy 39.237518 -348.306983)
			(xy 39.188828 -348.329988) (xy 39.163244 -348.338394) (xy 39.15156 -348.342204) (xy 39.134288 -348.358968)
			(xy 39.12853 -348.375986) (xy 41.122346 -348.375986) (xy 41.122841 -348.348075) (xy 41.130977 -348.29285)
			(xy 41.147072 -348.2394) (xy 41.170784 -348.188865) (xy 41.201606 -348.142325) (xy 41.219882 -348.121224)
			(xy 41.226232 -348.114112) (xy 41.232836 -348.09684) (xy 41.232836 -348.009718) (xy 41.226232 -347.992446)
			(xy 41.219882 -347.985334) (xy 41.201596 -347.964241) (xy 41.17077 -347.917701) (xy 41.147057 -347.867164)
			(xy 41.130962 -347.813712) (xy 41.12283 -347.758484) (xy 41.122346 -347.730572) (xy 41.122832 -347.703321)
			(xy 41.130588 -347.649373) (xy 41.145943 -347.597078) (xy 41.168585 -347.547501) (xy 41.198051 -347.501651)
			(xy 41.233742 -347.46046) (xy 41.274933 -347.424769) (xy 41.320783 -347.395303) (xy 41.37036 -347.372661)
			(xy 41.422655 -347.357306) (xy 41.476603 -347.34955) (xy 41.531105 -347.34955) (xy 41.585053 -347.357306)
			(xy 41.637348 -347.372661) (xy 41.686925 -347.395303) (xy 41.732775 -347.424769) (xy 41.773966 -347.46046)
			(xy 41.809657 -347.501651) (xy 41.839123 -347.547501) (xy 41.861765 -347.597078) (xy 41.87712 -347.649373)
			(xy 41.884876 -347.703321) (xy 41.885362 -347.730572) (xy 41.884899 -347.758484) (xy 41.876755 -347.81371)
			(xy 41.860652 -347.867161) (xy 41.836933 -347.917695) (xy 41.806105 -347.964234) (xy 41.787826 -347.985334)
			(xy 41.781476 -347.992446) (xy 41.774872 -348.009718) (xy 41.774872 -348.09684) (xy 41.781476 -348.114112)
			(xy 41.787826 -348.121224) (xy 41.806094 -348.142332) (xy 41.836922 -348.188868) (xy 41.860639 -348.239401)
			(xy 41.876738 -348.29285) (xy 41.884875 -348.348075) (xy 41.885362 -348.375986) (xy 41.884876 -348.403237)
			(xy 41.87712 -348.457185) (xy 41.861765 -348.50948) (xy 41.839123 -348.559057) (xy 41.809657 -348.604907)
			(xy 41.773966 -348.646098) (xy 41.732775 -348.681789) (xy 41.689656 -348.7095) (xy 45.504521 -348.7095)
			(xy 45.50869 -348.653877) (xy 45.521103 -348.599498) (xy 45.541482 -348.547575) (xy 45.569373 -348.49927)
			(xy 45.604152 -348.455662) (xy 45.645042 -348.417725) (xy 45.69113 -348.386307) (xy 45.741387 -348.362108)
			(xy 45.794688 -348.345671) (xy 45.849845 -348.337363) (xy 45.877734 -348.33687) (xy 45.904156 -348.337315)
			(xy 45.956472 -348.344769) (xy 46.00721 -348.359538) (xy 46.055354 -348.381324) (xy 46.099939 -348.409692)
			(xy 46.120304 -348.426532) (xy 46.127162 -348.432628) (xy 46.14418 -348.438724) (xy 46.228508 -348.438724)
			(xy 46.245526 -348.432628) (xy 46.252384 -348.426532) (xy 46.27275 -348.409693) (xy 46.317336 -348.381328)
			(xy 46.36548 -348.359541) (xy 46.416217 -348.34477) (xy 46.468532 -348.33731) (xy 46.521376 -348.33731)
			(xy 46.573691 -348.34477) (xy 46.624428 -348.359541) (xy 46.672572 -348.381328) (xy 46.717158 -348.409693)
			(xy 46.737524 -348.426532) (xy 46.744382 -348.432628) (xy 46.7614 -348.438724) (xy 46.845728 -348.438724)
			(xy 46.862746 -348.432628) (xy 46.869604 -348.426532) (xy 46.895641 -348.405213) (xy 46.953781 -348.371343)
			(xy 46.985174 -348.359222) (xy 46.995842 -348.355158) (xy 47.011844 -348.33941) (xy 47.04588 -348.24416)
			(xy 47.043848 -348.221808) (xy 47.038006 -348.211902) (xy 47.02535 -348.189724) (xy 47.005398 -348.14272)
			(xy 46.991893 -348.093476) (xy 46.985077 -348.042869) (xy 46.984666 -348.017338) (xy 46.985135 -347.989763)
			(xy 46.993083 -347.93519) (xy 47.008806 -347.882329) (xy 47.031976 -347.832282) (xy 47.062109 -347.786093)
			(xy 47.098578 -347.744723) (xy 47.119286 -347.726508) (xy 47.127394 -347.718896) (xy 47.136755 -347.698752)
			(xy 47.13732 -347.687646) (xy 47.13732 -347.61043) (xy 47.136777 -347.599316) (xy 47.127424 -347.579156)
			(xy 47.119286 -347.571568) (xy 47.098553 -347.55338) (xy 47.062085 -347.512006) (xy 47.031956 -347.465811)
			(xy 47.008794 -347.415759) (xy 46.993082 -347.362892) (xy 46.985148 -347.308314) (xy 46.984666 -347.280738)
			(xy 46.985152 -347.253487) (xy 46.992908 -347.199539) (xy 47.008263 -347.147244) (xy 47.030905 -347.097667)
			(xy 47.060371 -347.051817) (xy 47.096062 -347.010626) (xy 47.137253 -346.974935) (xy 47.183103 -346.945469)
			(xy 47.23268 -346.922827) (xy 47.284975 -346.907472) (xy 47.338923 -346.899716) (xy 47.393425 -346.899716)
			(xy 47.447373 -346.907472) (xy 47.499668 -346.922827) (xy 47.549245 -346.945469) (xy 47.595095 -346.974935)
			(xy 47.636286 -347.010626) (xy 47.671977 -347.051817) (xy 47.701443 -347.097667) (xy 47.724085 -347.147244)
			(xy 47.73944 -347.199539) (xy 47.747196 -347.253487) (xy 47.747682 -347.280738) (xy 47.74718 -347.308311)
			(xy 47.739236 -347.362883) (xy 47.723518 -347.415742) (xy 47.700355 -347.465789) (xy 47.670229 -347.511979)
			(xy 47.633767 -347.553351) (xy 47.613062 -347.571568) (xy 47.604956 -347.579182) (xy 47.595596 -347.599325)
			(xy 47.595028 -347.61043) (xy 47.595028 -347.687646) (xy 47.595601 -347.698755) (xy 47.604935 -347.718915)
			(xy 47.613062 -347.726508) (xy 47.633773 -347.74472) (xy 47.670245 -347.786088) (xy 47.700378 -347.832277)
			(xy 47.723544 -347.882325) (xy 47.73926 -347.935188) (xy 47.747198 -347.989763) (xy 47.747682 -348.017338)
			(xy 47.747249 -348.043602) (xy 47.740051 -348.095633) (xy 47.725782 -348.146185) (xy 47.704713 -348.194302)
			(xy 47.677241 -348.239072) (xy 47.643886 -348.27965) (xy 47.60528 -348.315268) (xy 47.562152 -348.345253)
			(xy 47.515318 -348.369037) (xy 47.496219 -348.375986) (xy 49.478946 -348.375986) (xy 49.479441 -348.348075)
			(xy 49.487577 -348.29285) (xy 49.503672 -348.2394) (xy 49.527384 -348.188865) (xy 49.558206 -348.142325)
			(xy 49.576482 -348.121224) (xy 49.582832 -348.114112) (xy 49.589436 -348.09684) (xy 49.589436 -348.009718)
			(xy 49.582832 -347.992446) (xy 49.576482 -347.985334) (xy 49.558196 -347.964241) (xy 49.52737 -347.917701)
			(xy 49.503657 -347.867164) (xy 49.487562 -347.813712) (xy 49.47943 -347.758484) (xy 49.478946 -347.730572)
			(xy 49.479432 -347.703321) (xy 49.487188 -347.649373) (xy 49.502543 -347.597078) (xy 49.525185 -347.547501)
			(xy 49.554651 -347.501651) (xy 49.590342 -347.46046) (xy 49.631533 -347.424769) (xy 49.677383 -347.395303)
			(xy 49.72696 -347.372661) (xy 49.779255 -347.357306) (xy 49.833203 -347.34955) (xy 49.887705 -347.34955)
			(xy 49.941653 -347.357306) (xy 49.993948 -347.372661) (xy 50.043525 -347.395303) (xy 50.089375 -347.424769)
			(xy 50.130566 -347.46046) (xy 50.166257 -347.501651) (xy 50.195723 -347.547501) (xy 50.218365 -347.597078)
			(xy 50.23372 -347.649373) (xy 50.241476 -347.703321) (xy 50.241962 -347.730572) (xy 50.241499 -347.758484)
			(xy 50.233355 -347.81371) (xy 50.217252 -347.867161) (xy 50.193533 -347.917695) (xy 50.162705 -347.964234)
			(xy 50.144426 -347.985334) (xy 50.138076 -347.992446) (xy 50.131472 -348.009718) (xy 50.131472 -348.09684)
			(xy 50.138076 -348.114112) (xy 50.144426 -348.121224) (xy 50.162694 -348.142332) (xy 50.193522 -348.188868)
			(xy 50.217239 -348.239401) (xy 50.233338 -348.29285) (xy 50.241475 -348.348075) (xy 50.241962 -348.375986)
			(xy 50.241476 -348.403237) (xy 50.23372 -348.457185) (xy 50.218365 -348.50948) (xy 50.195723 -348.559057)
			(xy 50.166257 -348.604907) (xy 50.130566 -348.646098) (xy 50.089375 -348.681789) (xy 50.046256 -348.7095)
			(xy 53.861121 -348.7095) (xy 53.86529 -348.653877) (xy 53.877703 -348.599498) (xy 53.898082 -348.547575)
			(xy 53.925973 -348.49927) (xy 53.960752 -348.455662) (xy 54.001642 -348.417725) (xy 54.04773 -348.386307)
			(xy 54.097987 -348.362108) (xy 54.151288 -348.345671) (xy 54.206445 -348.337363) (xy 54.234334 -348.33687)
			(xy 54.260756 -348.337315) (xy 54.313072 -348.344769) (xy 54.36381 -348.359538) (xy 54.411954 -348.381324)
			(xy 54.456539 -348.409692) (xy 54.476904 -348.426532) (xy 54.483762 -348.432628) (xy 54.50078 -348.438724)
			(xy 54.585108 -348.438724) (xy 54.602126 -348.432628) (xy 54.608984 -348.426532) (xy 54.62935 -348.409693)
			(xy 54.673936 -348.381328) (xy 54.72208 -348.359541) (xy 54.772817 -348.34477) (xy 54.825132 -348.33731)
			(xy 54.877976 -348.33731) (xy 54.930291 -348.34477) (xy 54.981028 -348.359541) (xy 55.029172 -348.381328)
			(xy 55.073758 -348.409693) (xy 55.094124 -348.426532) (xy 55.100982 -348.432628) (xy 55.118 -348.438724)
			(xy 55.202328 -348.438724) (xy 55.219346 -348.432628) (xy 55.226204 -348.426532) (xy 55.245009 -348.410904)
			(xy 55.285974 -348.384209) (xy 55.33008 -348.363102) (xy 55.353204 -348.355158) (xy 55.364634 -348.351602)
			(xy 55.381398 -348.335346) (xy 55.41645 -348.236794) (xy 55.413656 -348.21368) (xy 55.407052 -348.20352)
			(xy 55.392675 -348.180322) (xy 55.369981 -348.130687) (xy 55.354589 -348.078326) (xy 55.346812 -348.024306)
			(xy 55.346346 -347.997018) (xy 55.346808 -347.969443) (xy 55.354759 -347.914869) (xy 55.370484 -347.862009)
			(xy 55.393654 -347.811962) (xy 55.423788 -347.765773) (xy 55.460258 -347.724403) (xy 55.480966 -347.706188)
			(xy 55.489096 -347.698596) (xy 55.498441 -347.678436) (xy 55.499 -347.667326) (xy 55.499 -347.59011)
			(xy 55.498442 -347.578999) (xy 55.489096 -347.55884) (xy 55.480966 -347.551248) (xy 55.460268 -347.533023)
			(xy 55.423798 -347.491656) (xy 55.393665 -347.445469) (xy 55.370498 -347.395424) (xy 55.354778 -347.342564)
			(xy 55.346834 -347.287992) (xy 55.346346 -347.260418) (xy 55.346832 -347.233167) (xy 55.354588 -347.179219)
			(xy 55.369943 -347.126924) (xy 55.392585 -347.077347) (xy 55.422051 -347.031497) (xy 55.457742 -346.990306)
			(xy 55.498933 -346.954615) (xy 55.544783 -346.925149) (xy 55.59436 -346.902507) (xy 55.646655 -346.887152)
			(xy 55.700603 -346.879396) (xy 55.755105 -346.879396) (xy 55.809053 -346.887152) (xy 55.861348 -346.902507)
			(xy 55.910925 -346.925149) (xy 55.956775 -346.954615) (xy 55.997966 -346.990306) (xy 56.033657 -347.031497)
			(xy 56.063123 -347.077347) (xy 56.085765 -347.126924) (xy 56.10112 -347.179219) (xy 56.108876 -347.233167)
			(xy 56.109362 -347.260418) (xy 56.108853 -347.287991) (xy 56.100911 -347.342563) (xy 56.085196 -347.395422)
			(xy 56.062034 -347.445469) (xy 56.031908 -347.491659) (xy 55.995447 -347.533032) (xy 55.974742 -347.551248)
			(xy 55.966597 -347.558826) (xy 55.95726 -347.578997) (xy 55.956708 -347.59011) (xy 55.956708 -347.667326)
			(xy 55.957243 -347.67844) (xy 55.966605 -347.698598) (xy 55.974742 -347.706188) (xy 55.995459 -347.724393)
			(xy 56.031927 -347.765764) (xy 56.062057 -347.811955) (xy 56.085222 -347.862005) (xy 56.100937 -347.914868)
			(xy 56.108877 -347.969443) (xy 56.109362 -347.997018) (xy 56.108932 -348.023945) (xy 56.101364 -348.077263)
			(xy 56.086367 -348.128986) (xy 56.06424 -348.178083) (xy 56.035422 -348.223577) (xy 56.000489 -348.264562)
			(xy 55.960135 -348.300223) (xy 55.915163 -348.329849) (xy 55.86647 -348.352851) (xy 55.840884 -348.361254)
			(xy 55.829454 -348.365064) (xy 55.817827 -348.375986) (xy 57.810146 -348.375986) (xy 57.810641 -348.348075)
			(xy 57.818777 -348.29285) (xy 57.834872 -348.2394) (xy 57.858584 -348.188865) (xy 57.889406 -348.142325)
			(xy 57.907682 -348.121224) (xy 57.914032 -348.114112) (xy 57.920636 -348.09684) (xy 57.920636 -348.009718)
			(xy 57.914032 -347.992446) (xy 57.907682 -347.985334) (xy 57.889396 -347.964241) (xy 57.85857 -347.917701)
			(xy 57.834857 -347.867164) (xy 57.818762 -347.813712) (xy 57.81063 -347.758484) (xy 57.810146 -347.730572)
			(xy 57.810632 -347.703321) (xy 57.818388 -347.649373) (xy 57.833743 -347.597078) (xy 57.856385 -347.547501)
			(xy 57.885851 -347.501651) (xy 57.921542 -347.46046) (xy 57.962733 -347.424769) (xy 58.008583 -347.395303)
			(xy 58.05816 -347.372661) (xy 58.110455 -347.357306) (xy 58.164403 -347.34955) (xy 58.218905 -347.34955)
			(xy 58.272853 -347.357306) (xy 58.325148 -347.372661) (xy 58.374725 -347.395303) (xy 58.420575 -347.424769)
			(xy 58.461766 -347.46046) (xy 58.497457 -347.501651) (xy 58.526923 -347.547501) (xy 58.549565 -347.597078)
			(xy 58.56492 -347.649373) (xy 58.572676 -347.703321) (xy 58.573162 -347.730572) (xy 58.572699 -347.758484)
			(xy 58.564555 -347.81371) (xy 58.548452 -347.867161) (xy 58.524733 -347.917695) (xy 58.493905 -347.964234)
			(xy 58.475626 -347.985334) (xy 58.469276 -347.992446) (xy 58.462672 -348.009718) (xy 58.462672 -348.09684)
			(xy 58.469276 -348.114112) (xy 58.475626 -348.121224) (xy 58.493894 -348.142332) (xy 58.524722 -348.188868)
			(xy 58.548439 -348.239401) (xy 58.564538 -348.29285) (xy 58.572675 -348.348075) (xy 58.573162 -348.375986)
			(xy 58.572676 -348.403237) (xy 58.56492 -348.457185) (xy 58.549565 -348.50948) (xy 58.526923 -348.559057)
			(xy 58.497457 -348.604907) (xy 58.461766 -348.646098) (xy 58.420575 -348.681789) (xy 58.377456 -348.7095)
			(xy 62.192321 -348.7095) (xy 62.19649 -348.653877) (xy 62.208903 -348.599498) (xy 62.229282 -348.547575)
			(xy 62.257173 -348.49927) (xy 62.291952 -348.455662) (xy 62.332842 -348.417725) (xy 62.37893 -348.386307)
			(xy 62.429187 -348.362108) (xy 62.482488 -348.345671) (xy 62.537645 -348.337363) (xy 62.565534 -348.33687)
			(xy 62.591956 -348.337315) (xy 62.644272 -348.344769) (xy 62.69501 -348.359538) (xy 62.743154 -348.381324)
			(xy 62.787739 -348.409692) (xy 62.808104 -348.426532) (xy 62.814962 -348.432628) (xy 62.83198 -348.438724)
			(xy 62.916308 -348.438724) (xy 62.933326 -348.432628) (xy 62.940184 -348.426532) (xy 62.96055 -348.409693)
			(xy 63.005136 -348.381328) (xy 63.05328 -348.359541) (xy 63.104017 -348.34477) (xy 63.156332 -348.33731)
			(xy 63.209176 -348.33731) (xy 63.261491 -348.34477) (xy 63.312228 -348.359541) (xy 63.360372 -348.381328)
			(xy 63.404958 -348.409693) (xy 63.425324 -348.426532) (xy 63.432182 -348.432628) (xy 63.4492 -348.438724)
			(xy 63.533528 -348.438724) (xy 63.550546 -348.432628) (xy 63.557404 -348.426532) (xy 63.575177 -348.411793)
			(xy 63.613713 -348.386357) (xy 63.655099 -348.365882) (xy 63.676784 -348.357952) (xy 63.687198 -348.354142)
			(xy 63.7032 -348.338648) (xy 63.739268 -348.246192) (xy 63.737998 -348.224094) (xy 63.732664 -348.214188)
			(xy 63.71891 -348.187042) (xy 63.699416 -348.1294) (xy 63.68956 -348.069353) (xy 63.688976 -348.038928)
			(xy 63.689475 -348.011304) (xy 63.697635 -347.956662) (xy 63.71378 -347.903826) (xy 63.737555 -347.853956)
			(xy 63.768438 -347.808146) (xy 63.805752 -347.767404) (xy 63.826898 -347.749622) (xy 63.835442 -347.742036)
			(xy 63.845231 -347.721414) (xy 63.845694 -347.709998) (xy 63.845694 -347.631258) (xy 63.845077 -347.619876)
			(xy 63.835329 -347.599305) (xy 63.826898 -347.591634) (xy 63.805759 -347.573845) (xy 63.76845 -347.533101)
			(xy 63.737569 -347.487292) (xy 63.713793 -347.437423) (xy 63.697646 -347.38459) (xy 63.68948 -347.329951)
			(xy 63.688976 -347.302328) (xy 63.689497 -347.274443) (xy 63.697809 -347.219296) (xy 63.714247 -347.166004)
			(xy 63.738445 -347.115758) (xy 63.769861 -347.069679) (xy 63.807794 -347.028797) (xy 63.851396 -346.994025)
			(xy 63.899694 -346.96614) (xy 63.951609 -346.945765) (xy 64.00598 -346.933355) (xy 64.061594 -346.929188)
			(xy 64.117208 -346.933355) (xy 64.171579 -346.945765) (xy 64.223494 -346.96614) (xy 64.271792 -346.994025)
			(xy 64.315394 -347.028797) (xy 64.353327 -347.069679) (xy 64.384743 -347.115758) (xy 64.408941 -347.166004)
			(xy 64.425379 -347.219296) (xy 64.433691 -347.274443) (xy 64.434212 -347.302328) (xy 64.433686 -347.329951)
			(xy 64.425532 -347.384592) (xy 64.409393 -347.437427) (xy 64.385623 -347.487298) (xy 64.354744 -347.533108)
			(xy 64.317434 -347.573852) (xy 64.29629 -347.591634) (xy 64.287718 -347.599194) (xy 64.277945 -347.619836)
			(xy 64.277494 -347.631258) (xy 64.277494 -347.709998) (xy 64.278084 -347.721384) (xy 64.287851 -347.741954)
			(xy 64.29629 -347.749622) (xy 64.317453 -347.767383) (xy 64.354761 -347.808133) (xy 64.38564 -347.853948)
			(xy 64.409411 -347.903822) (xy 64.425553 -347.95666) (xy 64.433712 -348.011303) (xy 64.434212 -348.038928)
			(xy 64.433698 -348.067675) (xy 64.424872 -348.124486) (xy 64.407417 -348.179265) (xy 64.381749 -348.23071)
			(xy 64.348478 -348.277598) (xy 64.308395 -348.318815) (xy 64.262453 -348.35338) (xy 64.211743 -348.380472)
			(xy 64.184784 -348.390464) (xy 64.17437 -348.394274) (xy 64.158368 -348.409768) (xy 64.1223 -348.502224)
			(xy 64.12357 -348.524322) (xy 64.128904 -348.534228) (xy 64.142661 -348.561372) (xy 64.162155 -348.619016)
			(xy 64.172009 -348.679062) (xy 64.172592 -348.709488) (xy 64.172155 -348.736107) (xy 64.164579 -348.788802)
			(xy 64.149581 -348.839884) (xy 64.127466 -348.88831) (xy 64.098683 -348.933096) (xy 64.06382 -348.97333)
			(xy 64.023585 -349.008192) (xy 63.978798 -349.036973) (xy 63.93037 -349.059086) (xy 63.879289 -349.074082)
			(xy 63.826593 -349.081656) (xy 63.799974 -349.082106) (xy 63.773552 -349.081662) (xy 63.721236 -349.074208)
			(xy 63.670497 -349.05944) (xy 63.622353 -349.037653) (xy 63.577769 -349.009285) (xy 63.557404 -348.992444)
			(xy 63.550546 -348.986348) (xy 63.533528 -348.980252) (xy 63.4492 -348.980252) (xy 63.432182 -348.986348)
			(xy 63.425324 -348.992444) (xy 63.404958 -349.009283) (xy 63.360372 -349.037648) (xy 63.312228 -349.059435)
			(xy 63.261491 -349.074206) (xy 63.209176 -349.081666) (xy 63.156332 -349.081666) (xy 63.104017 -349.074206)
			(xy 63.05328 -349.059435) (xy 63.005136 -349.037648) (xy 62.96055 -349.009283) (xy 62.940184 -348.992444)
			(xy 62.933326 -348.986348) (xy 62.916308 -348.980252) (xy 62.83198 -348.980252) (xy 62.814962 -348.986348)
			(xy 62.808104 -348.992444) (xy 62.78773 -349.009272) (xy 62.743143 -349.03763) (xy 62.695001 -349.059412)
			(xy 62.644266 -349.074182) (xy 62.591954 -349.081644) (xy 62.565534 -349.082106) (xy 62.537645 -349.081637)
			(xy 62.482488 -349.073329) (xy 62.429187 -349.056892) (xy 62.37893 -349.032693) (xy 62.332842 -349.001275)
			(xy 62.291952 -348.963338) (xy 62.257173 -348.91973) (xy 62.229282 -348.871425) (xy 62.208903 -348.819502)
			(xy 62.19649 -348.765123) (xy 62.192321 -348.7095) (xy 58.377456 -348.7095) (xy 58.374725 -348.711255)
			(xy 58.325148 -348.733897) (xy 58.272853 -348.749252) (xy 58.218905 -348.757008) (xy 58.164403 -348.757008)
			(xy 58.110455 -348.749252) (xy 58.05816 -348.733897) (xy 58.008583 -348.711255) (xy 57.962733 -348.681789)
			(xy 57.921542 -348.646098) (xy 57.885851 -348.604907) (xy 57.856385 -348.559057) (xy 57.833743 -348.50948)
			(xy 57.818388 -348.457185) (xy 57.810632 -348.403237) (xy 57.810146 -348.375986) (xy 55.817827 -348.375986)
			(xy 55.81269 -348.380812) (xy 55.776114 -348.478856) (xy 55.7784 -348.50197) (xy 55.78475 -348.51213)
			(xy 55.798167 -348.534423) (xy 55.81936 -348.581941) (xy 55.833718 -348.63195) (xy 55.840962 -348.683473)
			(xy 55.841392 -348.709488) (xy 55.840955 -348.736107) (xy 55.833379 -348.788802) (xy 55.818381 -348.839884)
			(xy 55.796266 -348.88831) (xy 55.767483 -348.933096) (xy 55.73262 -348.97333) (xy 55.692385 -349.008192)
			(xy 55.647598 -349.036973) (xy 55.59917 -349.059086) (xy 55.548089 -349.074082) (xy 55.495393 -349.081656)
			(xy 55.468774 -349.082106) (xy 55.442352 -349.081662) (xy 55.390036 -349.074208) (xy 55.339297 -349.05944)
			(xy 55.291153 -349.037653) (xy 55.246569 -349.009285) (xy 55.226204 -348.992444) (xy 55.219346 -348.986348)
			(xy 55.202328 -348.980252) (xy 55.118 -348.980252) (xy 55.100982 -348.986348) (xy 55.094124 -348.992444)
			(xy 55.073758 -349.009283) (xy 55.029172 -349.037648) (xy 54.981028 -349.059435) (xy 54.930291 -349.074206)
			(xy 54.877976 -349.081666) (xy 54.825132 -349.081666) (xy 54.772817 -349.074206) (xy 54.72208 -349.059435)
			(xy 54.673936 -349.037648) (xy 54.62935 -349.009283) (xy 54.608984 -348.992444) (xy 54.602126 -348.986348)
			(xy 54.585108 -348.980252) (xy 54.50078 -348.980252) (xy 54.483762 -348.986348) (xy 54.476904 -348.992444)
			(xy 54.45653 -349.009272) (xy 54.411943 -349.03763) (xy 54.363801 -349.059412) (xy 54.313066 -349.074182)
			(xy 54.260754 -349.081644) (xy 54.234334 -349.082106) (xy 54.206445 -349.081637) (xy 54.151288 -349.073329)
			(xy 54.097987 -349.056892) (xy 54.04773 -349.032693) (xy 54.001642 -349.001275) (xy 53.960752 -348.963338)
			(xy 53.925973 -348.91973) (xy 53.898082 -348.871425) (xy 53.877703 -348.819502) (xy 53.86529 -348.765123)
			(xy 53.861121 -348.7095) (xy 50.046256 -348.7095) (xy 50.043525 -348.711255) (xy 49.993948 -348.733897)
			(xy 49.941653 -348.749252) (xy 49.887705 -348.757008) (xy 49.833203 -348.757008) (xy 49.779255 -348.749252)
			(xy 49.72696 -348.733897) (xy 49.677383 -348.711255) (xy 49.631533 -348.681789) (xy 49.590342 -348.646098)
			(xy 49.554651 -348.604907) (xy 49.525185 -348.559057) (xy 49.502543 -348.50948) (xy 49.487188 -348.457185)
			(xy 49.479432 -348.403237) (xy 49.478946 -348.375986) (xy 47.496219 -348.375986) (xy 47.490634 -348.378018)
			(xy 47.479712 -348.381828) (xy 47.46371 -348.397322) (xy 47.42815 -348.492064) (xy 47.429928 -348.514416)
			(xy 47.435516 -348.524576) (xy 47.447221 -348.545761) (xy 47.465635 -348.590525) (xy 47.478095 -348.637296)
			(xy 47.484392 -348.685287) (xy 47.484792 -348.709488) (xy 47.484355 -348.736107) (xy 47.476779 -348.788802)
			(xy 47.461781 -348.839884) (xy 47.439666 -348.88831) (xy 47.410883 -348.933096) (xy 47.37602 -348.97333)
			(xy 47.335785 -349.008192) (xy 47.290998 -349.036973) (xy 47.24257 -349.059086) (xy 47.191489 -349.074082)
			(xy 47.138793 -349.081656) (xy 47.112174 -349.082106) (xy 47.085752 -349.081662) (xy 47.033436 -349.074208)
			(xy 46.982697 -349.05944) (xy 46.934553 -349.037653) (xy 46.889969 -349.009285) (xy 46.869604 -348.992444)
			(xy 46.862746 -348.986348) (xy 46.845728 -348.980252) (xy 46.7614 -348.980252) (xy 46.744382 -348.986348)
			(xy 46.737524 -348.992444) (xy 46.717158 -349.009283) (xy 46.672572 -349.037648) (xy 46.624428 -349.059435)
			(xy 46.573691 -349.074206) (xy 46.521376 -349.081666) (xy 46.468532 -349.081666) (xy 46.416217 -349.074206)
			(xy 46.36548 -349.059435) (xy 46.317336 -349.037648) (xy 46.27275 -349.009283) (xy 46.252384 -348.992444)
			(xy 46.245526 -348.986348) (xy 46.228508 -348.980252) (xy 46.14418 -348.980252) (xy 46.127162 -348.986348)
			(xy 46.120304 -348.992444) (xy 46.09993 -349.009272) (xy 46.055343 -349.03763) (xy 46.007201 -349.059412)
			(xy 45.956466 -349.074182) (xy 45.904154 -349.081644) (xy 45.877734 -349.082106) (xy 45.849845 -349.081637)
			(xy 45.794688 -349.073329) (xy 45.741387 -349.056892) (xy 45.69113 -349.032693) (xy 45.645042 -349.001275)
			(xy 45.604152 -348.963338) (xy 45.569373 -348.91973) (xy 45.541482 -348.871425) (xy 45.521103 -348.819502)
			(xy 45.50869 -348.765123) (xy 45.504521 -348.7095) (xy 41.689656 -348.7095) (xy 41.686925 -348.711255)
			(xy 41.637348 -348.733897) (xy 41.585053 -348.749252) (xy 41.531105 -348.757008) (xy 41.476603 -348.757008)
			(xy 41.422655 -348.749252) (xy 41.37036 -348.733897) (xy 41.320783 -348.711255) (xy 41.274933 -348.681789)
			(xy 41.233742 -348.646098) (xy 41.198051 -348.604907) (xy 41.168585 -348.559057) (xy 41.145943 -348.50948)
			(xy 41.130588 -348.457185) (xy 41.122832 -348.403237) (xy 41.122346 -348.375986) (xy 39.12853 -348.375986)
			(xy 39.099998 -348.460314) (xy 39.1033 -348.48419) (xy 39.110412 -348.49435) (xy 39.126583 -348.518058)
			(xy 39.152188 -348.569416) (xy 39.169613 -348.624092) (xy 39.178447 -348.680795) (xy 39.178992 -348.709488)
			(xy 39.178555 -348.736107) (xy 39.170979 -348.788802) (xy 39.155981 -348.839884) (xy 39.133866 -348.88831)
			(xy 39.105083 -348.933096) (xy 39.07022 -348.97333) (xy 39.029985 -349.008192) (xy 38.985198 -349.036973)
			(xy 38.93677 -349.059086) (xy 38.885689 -349.074082) (xy 38.832993 -349.081656) (xy 38.806374 -349.082106)
			(xy 38.779952 -349.081662) (xy 38.727636 -349.074208) (xy 38.676897 -349.05944) (xy 38.628753 -349.037653)
			(xy 38.584169 -349.009285) (xy 38.563804 -348.992444) (xy 38.556946 -348.986348) (xy 38.539928 -348.980252)
			(xy 38.4556 -348.980252) (xy 38.438582 -348.986348) (xy 38.431724 -348.992444) (xy 38.411358 -349.009283)
			(xy 38.366772 -349.037648) (xy 38.318628 -349.059435) (xy 38.267891 -349.074206) (xy 38.215576 -349.081666)
			(xy 38.162732 -349.081666) (xy 38.110417 -349.074206) (xy 38.05968 -349.059435) (xy 38.011536 -349.037648)
			(xy 37.96695 -349.009283) (xy 37.946584 -348.992444) (xy 37.939726 -348.986348) (xy 37.922708 -348.980252)
			(xy 37.83838 -348.980252) (xy 37.821362 -348.986348) (xy 37.814504 -348.992444) (xy 37.79413 -349.009272)
			(xy 37.749543 -349.03763) (xy 37.701401 -349.059412) (xy 37.650666 -349.074182) (xy 37.598354 -349.081644)
			(xy 37.571934 -349.082106) (xy 37.544045 -349.081637) (xy 37.488888 -349.073329) (xy 37.435587 -349.056892)
			(xy 37.38533 -349.032693) (xy 37.339242 -349.001275) (xy 37.298352 -348.963338) (xy 37.263573 -348.91973)
			(xy 37.235682 -348.871425) (xy 37.215303 -348.819502) (xy 37.20289 -348.765123) (xy 37.198721 -348.7095)
			(xy 33.383856 -348.7095) (xy 33.381125 -348.711255) (xy 33.331548 -348.733897) (xy 33.279253 -348.749252)
			(xy 33.225305 -348.757008) (xy 33.170803 -348.757008) (xy 33.116855 -348.749252) (xy 33.06456 -348.733897)
			(xy 33.014983 -348.711255) (xy 32.969133 -348.681789) (xy 32.927942 -348.646098) (xy 32.892251 -348.604907)
			(xy 32.862785 -348.559057) (xy 32.840143 -348.50948) (xy 32.824788 -348.457185) (xy 32.817032 -348.403237)
			(xy 32.816546 -348.375986) (xy 30.849901 -348.375986) (xy 30.819344 -348.459044) (xy 30.822392 -348.483428)
			(xy 30.830012 -348.493842) (xy 30.846212 -348.517607) (xy 30.871857 -348.569086) (xy 30.889284 -348.623895)
			(xy 30.89808 -348.680731) (xy 30.898592 -348.709488) (xy 30.898155 -348.736107) (xy 30.890579 -348.788802)
			(xy 30.875581 -348.839884) (xy 30.853466 -348.88831) (xy 30.824683 -348.933096) (xy 30.78982 -348.97333)
			(xy 30.749585 -349.008192) (xy 30.704798 -349.036973) (xy 30.65637 -349.059086) (xy 30.605289 -349.074082)
			(xy 30.552593 -349.081656) (xy 30.525974 -349.082106) (xy 30.499552 -349.081662) (xy 30.447236 -349.074208)
			(xy 30.396497 -349.05944) (xy 30.348353 -349.037653) (xy 30.303769 -349.009285) (xy 30.283404 -348.992444)
			(xy 30.276546 -348.986348) (xy 30.259528 -348.980252) (xy 30.1752 -348.980252) (xy 30.158182 -348.986348)
			(xy 30.151324 -348.992444) (xy 30.130958 -349.009283) (xy 30.086372 -349.037648) (xy 30.038228 -349.059435)
			(xy 29.987491 -349.074206) (xy 29.935176 -349.081666) (xy 29.882332 -349.081666) (xy 29.830017 -349.074206)
			(xy 29.77928 -349.059435) (xy 29.731136 -349.037648) (xy 29.68655 -349.009283) (xy 29.666184 -348.992444)
			(xy 29.659326 -348.986348) (xy 29.642308 -348.980252) (xy 29.55798 -348.980252) (xy 29.540962 -348.986348)
			(xy 29.534104 -348.992444) (xy 29.51373 -349.009272) (xy 29.469143 -349.03763) (xy 29.421001 -349.059412)
			(xy 29.370266 -349.074182) (xy 29.317954 -349.081644) (xy 29.291534 -349.082106) (xy 29.263645 -349.081637)
			(xy 29.208488 -349.073329) (xy 29.155187 -349.056892) (xy 29.10493 -349.032693) (xy 29.058842 -349.001275)
			(xy 29.017952 -348.963338) (xy 28.983173 -348.91973) (xy 28.955282 -348.871425) (xy 28.934903 -348.819502)
			(xy 28.92249 -348.765123) (xy 28.918321 -348.7095) (xy 25.103456 -348.7095) (xy 25.100725 -348.711255)
			(xy 25.051148 -348.733897) (xy 24.998853 -348.749252) (xy 24.944905 -348.757008) (xy 24.890403 -348.757008)
			(xy 24.836455 -348.749252) (xy 24.78416 -348.733897) (xy 24.734583 -348.711255) (xy 24.688733 -348.681789)
			(xy 24.647542 -348.646098) (xy 24.611851 -348.604907) (xy 24.582385 -348.559057) (xy 24.559743 -348.50948)
			(xy 24.544388 -348.457185) (xy 24.536632 -348.403237) (xy 24.536146 -348.375986) (xy 24.125428 -348.375986)
			(xy 24.125428 -349.607632) (xy 25.493978 -349.607632) (xy 25.498049 -349.55201) (xy 25.510175 -349.497573)
			(xy 25.530098 -349.445482) (xy 25.557394 -349.396847) (xy 25.59148 -349.352704) (xy 25.631629 -349.313995)
			(xy 25.676987 -349.281544) (xy 25.726587 -349.256043) (xy 25.779371 -349.238036) (xy 25.834214 -349.227906)
			(xy 25.889948 -349.225869) (xy 25.945385 -349.231969) (xy 25.999342 -349.246075) (xy 26.050671 -349.267887)
			(xy 26.098277 -349.296941) (xy 26.141145 -349.332616) (xy 26.178362 -349.374153) (xy 26.209135 -349.420666)
			(xy 26.232807 -349.471163) (xy 26.248875 -349.52457) (xy 26.256995 -349.579746) (xy 26.257504 -349.607632)
			(xy 26.256995 -349.635518) (xy 26.248875 -349.690694) (xy 26.232807 -349.744101) (xy 26.209135 -349.794598)
			(xy 26.178362 -349.841111) (xy 26.141145 -349.882648) (xy 26.098277 -349.918323) (xy 26.050671 -349.947377)
			(xy 25.999342 -349.969189) (xy 25.945385 -349.983295) (xy 25.889948 -349.989395) (xy 25.834214 -349.987358)
			(xy 25.779371 -349.977228) (xy 25.726587 -349.959221) (xy 25.676987 -349.93372) (xy 25.631629 -349.901269)
			(xy 25.59148 -349.86256) (xy 25.557394 -349.818417) (xy 25.530098 -349.769782) (xy 25.510175 -349.717691)
			(xy 25.498049 -349.663254) (xy 25.493978 -349.607632) (xy 24.125428 -349.607632) (xy 24.125428 -350.502982)
			(xy 24.914858 -350.502982) (xy 24.918929 -350.44736) (xy 24.931055 -350.392923) (xy 24.950978 -350.340832)
			(xy 24.978274 -350.292197) (xy 25.01236 -350.248054) (xy 25.052509 -350.209345) (xy 25.097867 -350.176894)
			(xy 25.147467 -350.151393) (xy 25.200251 -350.133386) (xy 25.255094 -350.123256) (xy 25.310828 -350.121219)
			(xy 25.366265 -350.127319) (xy 25.420222 -350.141425) (xy 25.471551 -350.163237) (xy 25.519157 -350.192291)
			(xy 25.562025 -350.227966) (xy 25.599242 -350.269503) (xy 25.630015 -350.316016) (xy 25.653687 -350.366513)
			(xy 25.669755 -350.41992) (xy 25.677875 -350.475096) (xy 25.678384 -350.502982) (xy 25.677875 -350.530868)
			(xy 25.669755 -350.586044) (xy 25.653687 -350.639451) (xy 25.630015 -350.689948) (xy 25.599242 -350.736461)
			(xy 25.562025 -350.777998) (xy 25.519157 -350.813673) (xy 25.471551 -350.842727) (xy 25.420222 -350.864539)
			(xy 25.366265 -350.878645) (xy 25.310828 -350.884745) (xy 25.255094 -350.882708) (xy 25.200251 -350.872578)
			(xy 25.147467 -350.854571) (xy 25.097867 -350.82907) (xy 25.052509 -350.796619) (xy 25.01236 -350.75791)
			(xy 24.978274 -350.713767) (xy 24.950978 -350.665132) (xy 24.931055 -350.613041) (xy 24.918929 -350.558604)
			(xy 24.914858 -350.502982) (xy 24.125428 -350.502982) (xy 24.125428 -351.178622) (xy 26.253694 -351.178622)
			(xy 26.254195 -351.151148) (xy 26.262083 -351.096769) (xy 26.2777 -351.044087) (xy 26.300722 -350.994194)
			(xy 26.33067 -350.948124) (xy 26.348436 -350.927162) (xy 26.354532 -350.92005) (xy 26.360882 -350.903032)
			(xy 26.360882 -350.81718) (xy 26.354532 -350.800162) (xy 26.348436 -350.79305) (xy 26.330658 -350.7721)
			(xy 26.300737 -350.726014) (xy 26.277728 -350.676116) (xy 26.262106 -350.623437) (xy 26.254192 -350.569063)
			(xy 26.253694 -350.54159) (xy 26.25418 -350.514339) (xy 26.261936 -350.460391) (xy 26.277291 -350.408096)
			(xy 26.299933 -350.358519) (xy 26.329399 -350.312669) (xy 26.36509 -350.271478) (xy 26.406281 -350.235787)
			(xy 26.452131 -350.206321) (xy 26.501708 -350.183679) (xy 26.554003 -350.168324) (xy 26.607951 -350.160568)
			(xy 26.662453 -350.160568) (xy 26.716401 -350.168324) (xy 26.768696 -350.183679) (xy 26.818273 -350.206321)
			(xy 26.864123 -350.235787) (xy 26.905314 -350.271478) (xy 26.941005 -350.312669) (xy 26.970471 -350.358519)
			(xy 26.993113 -350.408096) (xy 27.008468 -350.460391) (xy 27.016224 -350.514339) (xy 27.01671 -350.54159)
			(xy 27.016215 -350.569064) (xy 27.008325 -350.623443) (xy 26.992707 -350.676126) (xy 26.990065 -350.681852)
			(xy 27.258475 -350.681852) (xy 27.258475 -350.627348) (xy 27.266232 -350.573398) (xy 27.281589 -350.521102)
			(xy 27.304231 -350.471523) (xy 27.333699 -350.425671) (xy 27.369393 -350.38448) (xy 27.410586 -350.348788)
			(xy 27.456439 -350.319322) (xy 27.506018 -350.296682) (xy 27.558316 -350.281329) (xy 27.612266 -350.273574)
			(xy 27.639518 -350.273112) (xy 27.664754 -350.273499) (xy 27.714788 -350.28012) (xy 27.763508 -350.293296)
			(xy 27.81006 -350.312796) (xy 27.83205 -350.325182) (xy 27.841702 -350.331024) (xy 27.8638 -350.333056)
			(xy 27.958288 -350.299528) (xy 27.97429 -350.284034) (xy 27.978354 -350.27362) (xy 27.989083 -350.246857)
			(xy 28.017365 -350.196615) (xy 28.052889 -350.151205) (xy 28.094846 -350.111661) (xy 28.142279 -350.078885)
			(xy 28.194106 -350.053625) (xy 28.249145 -350.036457) (xy 28.306142 -350.027771) (xy 28.33497 -350.02724)
			(xy 28.362224 -350.027683) (xy 28.416178 -350.035437) (xy 28.46848 -350.050792) (xy 28.518063 -350.073435)
			(xy 28.563918 -350.102904) (xy 28.605113 -350.1386) (xy 28.640807 -350.179796) (xy 28.670274 -350.225653)
			(xy 28.692914 -350.275237) (xy 28.705636 -350.318578) (xy 30.846522 -350.318578) (xy 30.847034 -350.291005)
			(xy 30.854976 -350.236434) (xy 30.870691 -350.183575) (xy 30.893852 -350.133528) (xy 30.923977 -350.087337)
			(xy 30.960438 -350.045965) (xy 30.981142 -350.027748) (xy 30.989241 -350.020128) (xy 30.998604 -349.99999)
			(xy 30.999176 -349.988886) (xy 30.999176 -349.91167) (xy 30.998648 -349.900555) (xy 30.989282 -349.880396)
			(xy 30.981142 -349.872808) (xy 30.96044 -349.854587) (xy 30.923967 -349.813221) (xy 30.893833 -349.767034)
			(xy 30.870665 -349.716988) (xy 30.854947 -349.664126) (xy 30.847007 -349.609552) (xy 30.846522 -349.581978)
			(xy 30.846934 -349.554723) (xy 30.854695 -349.500769) (xy 30.870056 -349.448468) (xy 30.892703 -349.398886)
			(xy 30.922176 -349.353031) (xy 30.957875 -349.311838) (xy 30.999073 -349.276145) (xy 31.044932 -349.246678)
			(xy 31.094517 -349.224037) (xy 31.14682 -349.208684) (xy 31.200775 -349.200931) (xy 31.22803 -349.20047)
			(xy 31.26232 -349.201994) (xy 31.27248 -349.20301) (xy 31.291784 -349.196914) (xy 31.362396 -349.137732)
			(xy 31.371794 -349.119698) (xy 31.37281 -349.109538) (xy 31.375725 -349.08136) (xy 31.388903 -349.026266)
			(xy 31.410085 -348.973727) (xy 31.438806 -348.924899) (xy 31.474435 -348.880858) (xy 31.516186 -348.842572)
			(xy 31.563142 -348.810883) (xy 31.614269 -348.786489) (xy 31.668443 -348.769927) (xy 31.72447 -348.76156)
			(xy 31.752794 -348.76105) (xy 31.770813 -348.761277) (xy 31.806688 -348.764707) (xy 31.824422 -348.767908)
			(xy 31.83382 -348.769686) (xy 31.85287 -348.765876) (xy 31.928054 -348.718124) (xy 31.939484 -348.702376)
			(xy 31.94177 -348.692978) (xy 31.949225 -348.665951) (xy 31.970848 -348.614227) (xy 31.999805 -348.566223)
			(xy 32.035473 -348.522971) (xy 32.077085 -348.485403) (xy 32.123745 -348.454326) (xy 32.174449 -348.43041)
			(xy 32.228107 -348.414169) (xy 32.283563 -348.405952) (xy 32.311594 -348.40545) (xy 32.338843 -348.405983)
			(xy 32.392787 -348.413738) (xy 32.445078 -348.42909) (xy 32.494653 -348.451727) (xy 32.540501 -348.481189)
			(xy 32.58169 -348.516876) (xy 32.617382 -348.55806) (xy 32.64685 -348.603905) (xy 32.669493 -348.653477)
			(xy 32.684852 -348.705766) (xy 32.692613 -348.759709) (xy 32.693102 -348.786958) (xy 32.692607 -348.814531)
			(xy 32.68466 -348.869103) (xy 32.668941 -348.921962) (xy 32.645776 -348.972008) (xy 32.615649 -349.018199)
			(xy 32.579187 -349.059571) (xy 32.558482 -349.077788) (xy 32.550371 -349.085397) (xy 32.541013 -349.105544)
			(xy 32.540448 -349.11665) (xy 32.540448 -349.193866) (xy 32.541004 -349.204978) (xy 32.550349 -349.225137)
			(xy 32.558482 -349.232728) (xy 32.579146 -349.250989) (xy 32.615611 -349.292354) (xy 32.64574 -349.338538)
			(xy 32.668905 -349.388579) (xy 32.684623 -349.441434) (xy 32.692567 -349.496001) (xy 32.692571 -349.551144)
			(xy 32.684635 -349.605713) (xy 32.684065 -349.607632) (xy 33.774378 -349.607632) (xy 33.778449 -349.55201)
			(xy 33.790575 -349.497573) (xy 33.810498 -349.445482) (xy 33.837794 -349.396847) (xy 33.87188 -349.352704)
			(xy 33.912029 -349.313995) (xy 33.957387 -349.281544) (xy 34.006987 -349.256043) (xy 34.059771 -349.238036)
			(xy 34.114614 -349.227906) (xy 34.170348 -349.225869) (xy 34.225785 -349.231969) (xy 34.279742 -349.246075)
			(xy 34.331071 -349.267887) (xy 34.378677 -349.296941) (xy 34.421545 -349.332616) (xy 34.458762 -349.374153)
			(xy 34.489535 -349.420666) (xy 34.513207 -349.471163) (xy 34.529275 -349.52457) (xy 34.537395 -349.579746)
			(xy 34.537904 -349.607632) (xy 34.537395 -349.635518) (xy 34.529275 -349.690694) (xy 34.513207 -349.744101)
			(xy 34.489535 -349.794598) (xy 34.458762 -349.841111) (xy 34.421545 -349.882648) (xy 34.378677 -349.918323)
			(xy 34.331071 -349.947377) (xy 34.279742 -349.969189) (xy 34.225785 -349.983295) (xy 34.170348 -349.989395)
			(xy 34.114614 -349.987358) (xy 34.059771 -349.977228) (xy 34.006987 -349.959221) (xy 33.957387 -349.93372)
			(xy 33.912029 -349.901269) (xy 33.87188 -349.86256) (xy 33.837794 -349.818417) (xy 33.810498 -349.769782)
			(xy 33.790575 -349.717691) (xy 33.778449 -349.663254) (xy 33.774378 -349.607632) (xy 32.684065 -349.607632)
			(xy 32.668924 -349.65857) (xy 32.645767 -349.708615) (xy 32.615644 -349.754803) (xy 32.579185 -349.796173)
			(xy 32.558482 -349.814388) (xy 32.550371 -349.821997) (xy 32.541013 -349.842144) (xy 32.540448 -349.85325)
			(xy 32.540448 -349.930466) (xy 32.541004 -349.941578) (xy 32.550349 -349.961737) (xy 32.558482 -349.969328)
			(xy 32.579206 -349.987525) (xy 32.615676 -350.028896) (xy 32.645807 -350.075089) (xy 32.668971 -350.12514)
			(xy 32.684684 -350.178005) (xy 32.692619 -350.232582) (xy 32.693102 -350.260158) (xy 32.692606 -350.28741)
			(xy 32.684854 -350.34136) (xy 32.669503 -350.393658) (xy 32.646865 -350.443238) (xy 32.617401 -350.489092)
			(xy 32.605367 -350.502982) (xy 33.195258 -350.502982) (xy 33.199329 -350.44736) (xy 33.211455 -350.392923)
			(xy 33.231378 -350.340832) (xy 33.258674 -350.292197) (xy 33.29276 -350.248054) (xy 33.332909 -350.209345)
			(xy 33.378267 -350.176894) (xy 33.427867 -350.151393) (xy 33.480651 -350.133386) (xy 33.535494 -350.123256)
			(xy 33.591228 -350.121219) (xy 33.646665 -350.127319) (xy 33.700622 -350.141425) (xy 33.751951 -350.163237)
			(xy 33.799557 -350.192291) (xy 33.842425 -350.227966) (xy 33.879642 -350.269503) (xy 33.910415 -350.316016)
			(xy 33.934087 -350.366513) (xy 33.950155 -350.41992) (xy 33.958275 -350.475096) (xy 33.958784 -350.502982)
			(xy 33.958275 -350.530868) (xy 33.950155 -350.586044) (xy 33.934087 -350.639451) (xy 33.910415 -350.689948)
			(xy 33.879642 -350.736461) (xy 33.842425 -350.777998) (xy 33.799557 -350.813673) (xy 33.751951 -350.842727)
			(xy 33.700622 -350.864539) (xy 33.646665 -350.878645) (xy 33.591228 -350.884745) (xy 33.535494 -350.882708)
			(xy 33.480651 -350.872578) (xy 33.427867 -350.854571) (xy 33.378267 -350.82907) (xy 33.332909 -350.796619)
			(xy 33.29276 -350.75791) (xy 33.258674 -350.713767) (xy 33.231378 -350.665132) (xy 33.211455 -350.613041)
			(xy 33.199329 -350.558604) (xy 33.195258 -350.502982) (xy 32.605367 -350.502982) (xy 32.581711 -350.530285)
			(xy 32.540521 -350.565979) (xy 32.49467 -350.595448) (xy 32.445092 -350.618091) (xy 32.392795 -350.633447)
			(xy 32.338846 -350.641203) (xy 32.311594 -350.641666) (xy 32.283737 -350.641174) (xy 32.228619 -350.633048)
			(xy 32.175267 -350.617) (xy 32.124813 -350.59337) (xy 32.078327 -350.56266) (xy 32.036798 -350.52552)
			(xy 32.001106 -350.482741) (xy 31.972009 -350.435229) (xy 31.950124 -350.383993) (xy 31.942532 -350.357186)
			(xy 31.940246 -350.348296) (xy 31.929578 -350.333056) (xy 31.857696 -350.285304) (xy 31.839662 -350.28124)
			(xy 31.830518 -350.28251) (xy 31.817501 -350.284175) (xy 31.791317 -350.285958) (xy 31.778194 -350.286066)
			(xy 31.764045 -350.285973) (xy 31.735822 -350.283938) (xy 31.721806 -350.282002) (xy 31.711646 -350.280478)
			(xy 31.692088 -350.285304) (xy 31.617666 -350.341184) (xy 31.607506 -350.35871) (xy 31.606236 -350.36887)
			(xy 31.60215 -350.396023) (xy 31.587174 -350.448852) (xy 31.564781 -350.498989) (xy 31.535432 -350.545399)
			(xy 31.499735 -350.587122) (xy 31.458425 -350.623298) (xy 31.412357 -350.653179) (xy 31.362481 -350.676149)
			(xy 31.309828 -350.691732) (xy 31.255485 -350.699607) (xy 31.22803 -350.700086) (xy 31.200777 -350.699617)
			(xy 31.146825 -350.691863) (xy 31.094526 -350.67651) (xy 31.044944 -350.653869) (xy 30.99909 -350.624402)
			(xy 30.957897 -350.588709) (xy 30.922202 -350.547516) (xy 30.892735 -350.501663) (xy 30.870093 -350.452082)
			(xy 30.854738 -350.399783) (xy 30.846984 -350.345831) (xy 30.846522 -350.318578) (xy 28.705636 -350.318578)
			(xy 28.708266 -350.327539) (xy 28.716018 -350.381494) (xy 28.716478 -350.408748) (xy 28.715825 -350.440311)
			(xy 28.705435 -350.502577) (xy 28.684947 -350.562286) (xy 28.670504 -350.590358) (xy 28.665678 -350.599248)
			(xy 28.663646 -350.618806) (xy 28.6893 -350.706944) (xy 28.701746 -350.722438) (xy 28.710636 -350.727518)
			(xy 28.735715 -350.742104) (xy 28.7816 -350.777599) (xy 28.821578 -350.819635) (xy 28.854727 -350.867242)
			(xy 28.880282 -350.919322) (xy 28.897652 -350.974672) (xy 28.906437 -351.032014) (xy 28.906978 -351.06102)
			(xy 28.906492 -351.088271) (xy 28.898736 -351.142219) (xy 28.888047 -351.178622) (xy 34.534094 -351.178622)
			(xy 34.534595 -351.151148) (xy 34.542483 -351.096769) (xy 34.5581 -351.044087) (xy 34.581122 -350.994194)
			(xy 34.61107 -350.948124) (xy 34.628836 -350.927162) (xy 34.634932 -350.92005) (xy 34.641282 -350.903032)
			(xy 34.641282 -350.81718) (xy 34.634932 -350.800162) (xy 34.628836 -350.79305) (xy 34.611058 -350.7721)
			(xy 34.581137 -350.726014) (xy 34.558128 -350.676116) (xy 34.542506 -350.623437) (xy 34.534592 -350.569063)
			(xy 34.534094 -350.54159) (xy 34.53458 -350.514339) (xy 34.542336 -350.460391) (xy 34.557691 -350.408096)
			(xy 34.580333 -350.358519) (xy 34.609799 -350.312669) (xy 34.64549 -350.271478) (xy 34.686681 -350.235787)
			(xy 34.732531 -350.206321) (xy 34.782108 -350.183679) (xy 34.834403 -350.168324) (xy 34.888351 -350.160568)
			(xy 34.942853 -350.160568) (xy 34.996801 -350.168324) (xy 35.049096 -350.183679) (xy 35.098673 -350.206321)
			(xy 35.144523 -350.235787) (xy 35.185714 -350.271478) (xy 35.221405 -350.312669) (xy 35.250871 -350.358519)
			(xy 35.273513 -350.408096) (xy 35.288868 -350.460391) (xy 35.296624 -350.514339) (xy 35.29711 -350.54159)
			(xy 35.296615 -350.569064) (xy 35.288725 -350.623443) (xy 35.273107 -350.676126) (xy 35.270465 -350.681852)
			(xy 35.538875 -350.681852) (xy 35.538875 -350.627348) (xy 35.546632 -350.573398) (xy 35.561989 -350.521102)
			(xy 35.584631 -350.471523) (xy 35.614099 -350.425671) (xy 35.649793 -350.38448) (xy 35.690986 -350.348788)
			(xy 35.736839 -350.319322) (xy 35.786418 -350.296682) (xy 35.838716 -350.281329) (xy 35.892666 -350.273574)
			(xy 35.919918 -350.273112) (xy 35.945154 -350.273499) (xy 35.995188 -350.28012) (xy 36.043908 -350.293296)
			(xy 36.09046 -350.312796) (xy 36.11245 -350.325182) (xy 36.122102 -350.331024) (xy 36.1442 -350.333056)
			(xy 36.238688 -350.299528) (xy 36.25469 -350.284034) (xy 36.258754 -350.27362) (xy 36.269483 -350.246857)
			(xy 36.297765 -350.196615) (xy 36.333289 -350.151205) (xy 36.375246 -350.111661) (xy 36.422679 -350.078885)
			(xy 36.474506 -350.053625) (xy 36.529545 -350.036457) (xy 36.586542 -350.027771) (xy 36.61537 -350.02724)
			(xy 36.642624 -350.027683) (xy 36.696578 -350.035437) (xy 36.74888 -350.050792) (xy 36.798463 -350.073435)
			(xy 36.844318 -350.102904) (xy 36.885513 -350.1386) (xy 36.921207 -350.179796) (xy 36.950674 -350.225653)
			(xy 36.973314 -350.275237) (xy 36.986036 -350.318578) (xy 39.126922 -350.318578) (xy 39.127434 -350.291005)
			(xy 39.135376 -350.236434) (xy 39.151091 -350.183575) (xy 39.174252 -350.133528) (xy 39.204377 -350.087337)
			(xy 39.240838 -350.045965) (xy 39.261542 -350.027748) (xy 39.269641 -350.020128) (xy 39.279004 -349.99999)
			(xy 39.279576 -349.988886) (xy 39.279576 -349.91167) (xy 39.279048 -349.900555) (xy 39.269682 -349.880396)
			(xy 39.261542 -349.872808) (xy 39.24084 -349.854587) (xy 39.204367 -349.813221) (xy 39.174233 -349.767034)
			(xy 39.151065 -349.716988) (xy 39.135347 -349.664126) (xy 39.127407 -349.609552) (xy 39.126922 -349.581978)
			(xy 39.127334 -349.554723) (xy 39.135095 -349.500769) (xy 39.150456 -349.448468) (xy 39.173103 -349.398886)
			(xy 39.202576 -349.353031) (xy 39.238275 -349.311838) (xy 39.279473 -349.276145) (xy 39.325332 -349.246678)
			(xy 39.374917 -349.224037) (xy 39.42722 -349.208684) (xy 39.481175 -349.200931) (xy 39.50843 -349.20047)
			(xy 39.54272 -349.201994) (xy 39.55288 -349.20301) (xy 39.572184 -349.196914) (xy 39.642796 -349.137732)
			(xy 39.652194 -349.119698) (xy 39.65321 -349.109538) (xy 39.656125 -349.08136) (xy 39.669303 -349.026266)
			(xy 39.690485 -348.973727) (xy 39.719206 -348.924899) (xy 39.754835 -348.880858) (xy 39.796586 -348.842572)
			(xy 39.843542 -348.810883) (xy 39.894669 -348.786489) (xy 39.948843 -348.769927) (xy 40.00487 -348.76156)
			(xy 40.033194 -348.76105) (xy 40.051213 -348.761277) (xy 40.087088 -348.764707) (xy 40.104822 -348.767908)
			(xy 40.11422 -348.769686) (xy 40.13327 -348.765876) (xy 40.208454 -348.718124) (xy 40.219884 -348.702376)
			(xy 40.22217 -348.692978) (xy 40.229625 -348.665951) (xy 40.251248 -348.614227) (xy 40.280205 -348.566223)
			(xy 40.315873 -348.522971) (xy 40.357485 -348.485403) (xy 40.404145 -348.454326) (xy 40.454849 -348.43041)
			(xy 40.508507 -348.414169) (xy 40.563963 -348.405952) (xy 40.591994 -348.40545) (xy 40.619243 -348.405983)
			(xy 40.673187 -348.413738) (xy 40.725478 -348.42909) (xy 40.775053 -348.451727) (xy 40.820901 -348.481189)
			(xy 40.86209 -348.516876) (xy 40.897782 -348.55806) (xy 40.92725 -348.603905) (xy 40.949893 -348.653477)
			(xy 40.965252 -348.705766) (xy 40.973013 -348.759709) (xy 40.973502 -348.786958) (xy 40.973007 -348.814531)
			(xy 40.96506 -348.869103) (xy 40.949341 -348.921962) (xy 40.926176 -348.972008) (xy 40.896049 -349.018199)
			(xy 40.859587 -349.059571) (xy 40.838882 -349.077788) (xy 40.830771 -349.085397) (xy 40.821413 -349.105544)
			(xy 40.820848 -349.11665) (xy 40.820848 -349.193866) (xy 40.821404 -349.204978) (xy 40.830749 -349.225137)
			(xy 40.838882 -349.232728) (xy 40.859546 -349.250989) (xy 40.896011 -349.292354) (xy 40.92614 -349.338538)
			(xy 40.949305 -349.388579) (xy 40.965023 -349.441434) (xy 40.972967 -349.496001) (xy 40.972971 -349.551144)
			(xy 40.965035 -349.605713) (xy 40.964465 -349.607632) (xy 42.080178 -349.607632) (xy 42.084249 -349.55201)
			(xy 42.096375 -349.497573) (xy 42.116298 -349.445482) (xy 42.143594 -349.396847) (xy 42.17768 -349.352704)
			(xy 42.217829 -349.313995) (xy 42.263187 -349.281544) (xy 42.312787 -349.256043) (xy 42.365571 -349.238036)
			(xy 42.420414 -349.227906) (xy 42.476148 -349.225869) (xy 42.531585 -349.231969) (xy 42.585542 -349.246075)
			(xy 42.636871 -349.267887) (xy 42.684477 -349.296941) (xy 42.727345 -349.332616) (xy 42.764562 -349.374153)
			(xy 42.795335 -349.420666) (xy 42.819007 -349.471163) (xy 42.835075 -349.52457) (xy 42.843195 -349.579746)
			(xy 42.843704 -349.607632) (xy 42.843195 -349.635518) (xy 42.835075 -349.690694) (xy 42.819007 -349.744101)
			(xy 42.795335 -349.794598) (xy 42.764562 -349.841111) (xy 42.727345 -349.882648) (xy 42.684477 -349.918323)
			(xy 42.636871 -349.947377) (xy 42.585542 -349.969189) (xy 42.531585 -349.983295) (xy 42.476148 -349.989395)
			(xy 42.420414 -349.987358) (xy 42.365571 -349.977228) (xy 42.312787 -349.959221) (xy 42.263187 -349.93372)
			(xy 42.217829 -349.901269) (xy 42.17768 -349.86256) (xy 42.143594 -349.818417) (xy 42.116298 -349.769782)
			(xy 42.096375 -349.717691) (xy 42.084249 -349.663254) (xy 42.080178 -349.607632) (xy 40.964465 -349.607632)
			(xy 40.949324 -349.65857) (xy 40.926167 -349.708615) (xy 40.896044 -349.754803) (xy 40.859585 -349.796173)
			(xy 40.838882 -349.814388) (xy 40.830771 -349.821997) (xy 40.821413 -349.842144) (xy 40.820848 -349.85325)
			(xy 40.820848 -349.930466) (xy 40.821404 -349.941578) (xy 40.830749 -349.961737) (xy 40.838882 -349.969328)
			(xy 40.859606 -349.987525) (xy 40.896076 -350.028896) (xy 40.926207 -350.075089) (xy 40.949371 -350.12514)
			(xy 40.965084 -350.178005) (xy 40.973019 -350.232582) (xy 40.973502 -350.260158) (xy 40.973006 -350.28741)
			(xy 40.965254 -350.34136) (xy 40.949903 -350.393658) (xy 40.927265 -350.443238) (xy 40.897801 -350.489092)
			(xy 40.885767 -350.502982) (xy 41.501058 -350.502982) (xy 41.505129 -350.44736) (xy 41.517255 -350.392923)
			(xy 41.537178 -350.340832) (xy 41.564474 -350.292197) (xy 41.59856 -350.248054) (xy 41.638709 -350.209345)
			(xy 41.684067 -350.176894) (xy 41.733667 -350.151393) (xy 41.786451 -350.133386) (xy 41.841294 -350.123256)
			(xy 41.897028 -350.121219) (xy 41.952465 -350.127319) (xy 42.006422 -350.141425) (xy 42.057751 -350.163237)
			(xy 42.105357 -350.192291) (xy 42.148225 -350.227966) (xy 42.185442 -350.269503) (xy 42.216215 -350.316016)
			(xy 42.239887 -350.366513) (xy 42.255955 -350.41992) (xy 42.264075 -350.475096) (xy 42.264584 -350.502982)
			(xy 42.264075 -350.530868) (xy 42.255955 -350.586044) (xy 42.239887 -350.639451) (xy 42.216215 -350.689948)
			(xy 42.185442 -350.736461) (xy 42.148225 -350.777998) (xy 42.105357 -350.813673) (xy 42.057751 -350.842727)
			(xy 42.006422 -350.864539) (xy 41.952465 -350.878645) (xy 41.897028 -350.884745) (xy 41.841294 -350.882708)
			(xy 41.786451 -350.872578) (xy 41.733667 -350.854571) (xy 41.684067 -350.82907) (xy 41.638709 -350.796619)
			(xy 41.59856 -350.75791) (xy 41.564474 -350.713767) (xy 41.537178 -350.665132) (xy 41.517255 -350.613041)
			(xy 41.505129 -350.558604) (xy 41.501058 -350.502982) (xy 40.885767 -350.502982) (xy 40.862111 -350.530285)
			(xy 40.820921 -350.565979) (xy 40.77507 -350.595448) (xy 40.725492 -350.618091) (xy 40.673195 -350.633447)
			(xy 40.619246 -350.641203) (xy 40.591994 -350.641666) (xy 40.564137 -350.641174) (xy 40.509019 -350.633048)
			(xy 40.455667 -350.617) (xy 40.405213 -350.59337) (xy 40.358727 -350.56266) (xy 40.317198 -350.52552)
			(xy 40.281506 -350.482741) (xy 40.252409 -350.435229) (xy 40.230524 -350.383993) (xy 40.222932 -350.357186)
			(xy 40.220646 -350.348296) (xy 40.209978 -350.333056) (xy 40.138096 -350.285304) (xy 40.120062 -350.28124)
			(xy 40.110918 -350.28251) (xy 40.097901 -350.284175) (xy 40.071717 -350.285958) (xy 40.058594 -350.286066)
			(xy 40.044445 -350.285973) (xy 40.016222 -350.283938) (xy 40.002206 -350.282002) (xy 39.992046 -350.280478)
			(xy 39.972488 -350.285304) (xy 39.898066 -350.341184) (xy 39.887906 -350.35871) (xy 39.886636 -350.36887)
			(xy 39.88255 -350.396023) (xy 39.867574 -350.448852) (xy 39.845181 -350.498989) (xy 39.815832 -350.545399)
			(xy 39.780135 -350.587122) (xy 39.738825 -350.623298) (xy 39.692757 -350.653179) (xy 39.642881 -350.676149)
			(xy 39.590228 -350.691732) (xy 39.535885 -350.699607) (xy 39.50843 -350.700086) (xy 39.481177 -350.699617)
			(xy 39.427225 -350.691863) (xy 39.374926 -350.67651) (xy 39.325344 -350.653869) (xy 39.27949 -350.624402)
			(xy 39.238297 -350.588709) (xy 39.202602 -350.547516) (xy 39.173135 -350.501663) (xy 39.150493 -350.452082)
			(xy 39.135138 -350.399783) (xy 39.127384 -350.345831) (xy 39.126922 -350.318578) (xy 36.986036 -350.318578)
			(xy 36.988666 -350.327539) (xy 36.996418 -350.381494) (xy 36.996878 -350.408748) (xy 36.996225 -350.440311)
			(xy 36.985835 -350.502577) (xy 36.965347 -350.562286) (xy 36.950904 -350.590358) (xy 36.946078 -350.599248)
			(xy 36.944046 -350.618806) (xy 36.9697 -350.706944) (xy 36.982146 -350.722438) (xy 36.991036 -350.727518)
			(xy 37.016115 -350.742104) (xy 37.062 -350.777599) (xy 37.101978 -350.819635) (xy 37.135127 -350.867242)
			(xy 37.160682 -350.919322) (xy 37.178052 -350.974672) (xy 37.186837 -351.032014) (xy 37.187378 -351.06102)
			(xy 37.186892 -351.088271) (xy 37.179136 -351.142219) (xy 37.168447 -351.178622) (xy 42.839894 -351.178622)
			(xy 42.840395 -351.151148) (xy 42.848283 -351.096769) (xy 42.8639 -351.044087) (xy 42.886922 -350.994194)
			(xy 42.91687 -350.948124) (xy 42.934636 -350.927162) (xy 42.940732 -350.92005) (xy 42.947082 -350.903032)
			(xy 42.947082 -350.81718) (xy 42.940732 -350.800162) (xy 42.934636 -350.79305) (xy 42.916858 -350.7721)
			(xy 42.886937 -350.726014) (xy 42.863928 -350.676116) (xy 42.848306 -350.623437) (xy 42.840392 -350.569063)
			(xy 42.839894 -350.54159) (xy 42.84038 -350.514339) (xy 42.848136 -350.460391) (xy 42.863491 -350.408096)
			(xy 42.886133 -350.358519) (xy 42.915599 -350.312669) (xy 42.95129 -350.271478) (xy 42.992481 -350.235787)
			(xy 43.038331 -350.206321) (xy 43.087908 -350.183679) (xy 43.140203 -350.168324) (xy 43.194151 -350.160568)
			(xy 43.248653 -350.160568) (xy 43.302601 -350.168324) (xy 43.354896 -350.183679) (xy 43.404473 -350.206321)
			(xy 43.450323 -350.235787) (xy 43.491514 -350.271478) (xy 43.527205 -350.312669) (xy 43.556671 -350.358519)
			(xy 43.579313 -350.408096) (xy 43.594668 -350.460391) (xy 43.602424 -350.514339) (xy 43.60291 -350.54159)
			(xy 43.602415 -350.569064) (xy 43.594525 -350.623443) (xy 43.578907 -350.676126) (xy 43.576265 -350.681852)
			(xy 43.844675 -350.681852) (xy 43.844675 -350.627348) (xy 43.852432 -350.573398) (xy 43.867789 -350.521102)
			(xy 43.890431 -350.471523) (xy 43.919899 -350.425671) (xy 43.955593 -350.38448) (xy 43.996786 -350.348788)
			(xy 44.042639 -350.319322) (xy 44.092218 -350.296682) (xy 44.144516 -350.281329) (xy 44.198466 -350.273574)
			(xy 44.225718 -350.273112) (xy 44.250954 -350.273499) (xy 44.300988 -350.28012) (xy 44.349708 -350.293296)
			(xy 44.39626 -350.312796) (xy 44.41825 -350.325182) (xy 44.427902 -350.331024) (xy 44.45 -350.333056)
			(xy 44.544488 -350.299528) (xy 44.56049 -350.284034) (xy 44.564554 -350.27362) (xy 44.575283 -350.246857)
			(xy 44.603565 -350.196615) (xy 44.639089 -350.151205) (xy 44.681046 -350.111661) (xy 44.728479 -350.078885)
			(xy 44.780306 -350.053625) (xy 44.835345 -350.036457) (xy 44.892342 -350.027771) (xy 44.92117 -350.02724)
			(xy 44.948424 -350.027683) (xy 45.002378 -350.035437) (xy 45.05468 -350.050792) (xy 45.104263 -350.073435)
			(xy 45.150118 -350.102904) (xy 45.191313 -350.1386) (xy 45.227007 -350.179796) (xy 45.256474 -350.225653)
			(xy 45.279114 -350.275237) (xy 45.291836 -350.318578) (xy 47.432722 -350.318578) (xy 47.433234 -350.291005)
			(xy 47.441176 -350.236434) (xy 47.456891 -350.183575) (xy 47.480052 -350.133528) (xy 47.510177 -350.087337)
			(xy 47.546638 -350.045965) (xy 47.567342 -350.027748) (xy 47.575441 -350.020128) (xy 47.584804 -349.99999)
			(xy 47.585376 -349.988886) (xy 47.585376 -349.91167) (xy 47.584848 -349.900555) (xy 47.575482 -349.880396)
			(xy 47.567342 -349.872808) (xy 47.54664 -349.854587) (xy 47.510167 -349.813221) (xy 47.480033 -349.767034)
			(xy 47.456865 -349.716988) (xy 47.441147 -349.664126) (xy 47.433207 -349.609552) (xy 47.432722 -349.581978)
			(xy 47.433134 -349.554723) (xy 47.440895 -349.500769) (xy 47.456256 -349.448468) (xy 47.478903 -349.398886)
			(xy 47.508376 -349.353031) (xy 47.544075 -349.311838) (xy 47.585273 -349.276145) (xy 47.631132 -349.246678)
			(xy 47.680717 -349.224037) (xy 47.73302 -349.208684) (xy 47.786975 -349.200931) (xy 47.81423 -349.20047)
			(xy 47.84852 -349.201994) (xy 47.85868 -349.20301) (xy 47.877984 -349.196914) (xy 47.948596 -349.137732)
			(xy 47.957994 -349.119698) (xy 47.95901 -349.109538) (xy 47.961925 -349.08136) (xy 47.975103 -349.026266)
			(xy 47.996285 -348.973727) (xy 48.025006 -348.924899) (xy 48.060635 -348.880858) (xy 48.102386 -348.842572)
			(xy 48.149342 -348.810883) (xy 48.200469 -348.786489) (xy 48.254643 -348.769927) (xy 48.31067 -348.76156)
			(xy 48.338994 -348.76105) (xy 48.357013 -348.761277) (xy 48.392888 -348.764707) (xy 48.410622 -348.767908)
			(xy 48.42002 -348.769686) (xy 48.43907 -348.765876) (xy 48.514254 -348.718124) (xy 48.525684 -348.702376)
			(xy 48.52797 -348.692978) (xy 48.535425 -348.665951) (xy 48.557048 -348.614227) (xy 48.586005 -348.566223)
			(xy 48.621673 -348.522971) (xy 48.663285 -348.485403) (xy 48.709945 -348.454326) (xy 48.760649 -348.43041)
			(xy 48.814307 -348.414169) (xy 48.869763 -348.405952) (xy 48.897794 -348.40545) (xy 48.925043 -348.405983)
			(xy 48.978987 -348.413738) (xy 49.031278 -348.42909) (xy 49.080853 -348.451727) (xy 49.126701 -348.481189)
			(xy 49.16789 -348.516876) (xy 49.203582 -348.55806) (xy 49.23305 -348.603905) (xy 49.255693 -348.653477)
			(xy 49.271052 -348.705766) (xy 49.278813 -348.759709) (xy 49.279302 -348.786958) (xy 49.278807 -348.814531)
			(xy 49.27086 -348.869103) (xy 49.255141 -348.921962) (xy 49.231976 -348.972008) (xy 49.201849 -349.018199)
			(xy 49.165387 -349.059571) (xy 49.144682 -349.077788) (xy 49.136571 -349.085397) (xy 49.127213 -349.105544)
			(xy 49.126648 -349.11665) (xy 49.126648 -349.193866) (xy 49.127204 -349.204978) (xy 49.136549 -349.225137)
			(xy 49.144682 -349.232728) (xy 49.165346 -349.250989) (xy 49.201811 -349.292354) (xy 49.23194 -349.338538)
			(xy 49.255105 -349.388579) (xy 49.270823 -349.441434) (xy 49.278767 -349.496001) (xy 49.278771 -349.551144)
			(xy 49.270835 -349.605713) (xy 49.270265 -349.607632) (xy 50.436778 -349.607632) (xy 50.440849 -349.55201)
			(xy 50.452975 -349.497573) (xy 50.472898 -349.445482) (xy 50.500194 -349.396847) (xy 50.53428 -349.352704)
			(xy 50.574429 -349.313995) (xy 50.619787 -349.281544) (xy 50.669387 -349.256043) (xy 50.722171 -349.238036)
			(xy 50.777014 -349.227906) (xy 50.832748 -349.225869) (xy 50.888185 -349.231969) (xy 50.942142 -349.246075)
			(xy 50.993471 -349.267887) (xy 51.041077 -349.296941) (xy 51.083945 -349.332616) (xy 51.121162 -349.374153)
			(xy 51.151935 -349.420666) (xy 51.175607 -349.471163) (xy 51.191675 -349.52457) (xy 51.199795 -349.579746)
			(xy 51.200304 -349.607632) (xy 51.199795 -349.635518) (xy 51.191675 -349.690694) (xy 51.175607 -349.744101)
			(xy 51.151935 -349.794598) (xy 51.121162 -349.841111) (xy 51.083945 -349.882648) (xy 51.041077 -349.918323)
			(xy 50.993471 -349.947377) (xy 50.942142 -349.969189) (xy 50.888185 -349.983295) (xy 50.832748 -349.989395)
			(xy 50.777014 -349.987358) (xy 50.722171 -349.977228) (xy 50.669387 -349.959221) (xy 50.619787 -349.93372)
			(xy 50.574429 -349.901269) (xy 50.53428 -349.86256) (xy 50.500194 -349.818417) (xy 50.472898 -349.769782)
			(xy 50.452975 -349.717691) (xy 50.440849 -349.663254) (xy 50.436778 -349.607632) (xy 49.270265 -349.607632)
			(xy 49.255124 -349.65857) (xy 49.231967 -349.708615) (xy 49.201844 -349.754803) (xy 49.165385 -349.796173)
			(xy 49.144682 -349.814388) (xy 49.136571 -349.821997) (xy 49.127213 -349.842144) (xy 49.126648 -349.85325)
			(xy 49.126648 -349.930466) (xy 49.127204 -349.941578) (xy 49.136549 -349.961737) (xy 49.144682 -349.969328)
			(xy 49.165406 -349.987525) (xy 49.201876 -350.028896) (xy 49.232007 -350.075089) (xy 49.255171 -350.12514)
			(xy 49.270884 -350.178005) (xy 49.278819 -350.232582) (xy 49.279302 -350.260158) (xy 49.278806 -350.28741)
			(xy 49.271054 -350.34136) (xy 49.255703 -350.393658) (xy 49.233065 -350.443238) (xy 49.203601 -350.489092)
			(xy 49.191567 -350.502982) (xy 49.857658 -350.502982) (xy 49.861729 -350.44736) (xy 49.873855 -350.392923)
			(xy 49.893778 -350.340832) (xy 49.921074 -350.292197) (xy 49.95516 -350.248054) (xy 49.995309 -350.209345)
			(xy 50.040667 -350.176894) (xy 50.090267 -350.151393) (xy 50.143051 -350.133386) (xy 50.197894 -350.123256)
			(xy 50.253628 -350.121219) (xy 50.309065 -350.127319) (xy 50.363022 -350.141425) (xy 50.414351 -350.163237)
			(xy 50.461957 -350.192291) (xy 50.504825 -350.227966) (xy 50.542042 -350.269503) (xy 50.572815 -350.316016)
			(xy 50.596487 -350.366513) (xy 50.612555 -350.41992) (xy 50.620675 -350.475096) (xy 50.621184 -350.502982)
			(xy 50.620675 -350.530868) (xy 50.612555 -350.586044) (xy 50.596487 -350.639451) (xy 50.572815 -350.689948)
			(xy 50.542042 -350.736461) (xy 50.504825 -350.777998) (xy 50.461957 -350.813673) (xy 50.414351 -350.842727)
			(xy 50.363022 -350.864539) (xy 50.309065 -350.878645) (xy 50.253628 -350.884745) (xy 50.197894 -350.882708)
			(xy 50.143051 -350.872578) (xy 50.090267 -350.854571) (xy 50.040667 -350.82907) (xy 49.995309 -350.796619)
			(xy 49.95516 -350.75791) (xy 49.921074 -350.713767) (xy 49.893778 -350.665132) (xy 49.873855 -350.613041)
			(xy 49.861729 -350.558604) (xy 49.857658 -350.502982) (xy 49.191567 -350.502982) (xy 49.167911 -350.530285)
			(xy 49.126721 -350.565979) (xy 49.08087 -350.595448) (xy 49.031292 -350.618091) (xy 48.978995 -350.633447)
			(xy 48.925046 -350.641203) (xy 48.897794 -350.641666) (xy 48.869937 -350.641174) (xy 48.814819 -350.633048)
			(xy 48.761467 -350.617) (xy 48.711013 -350.59337) (xy 48.664527 -350.56266) (xy 48.622998 -350.52552)
			(xy 48.587306 -350.482741) (xy 48.558209 -350.435229) (xy 48.536324 -350.383993) (xy 48.528732 -350.357186)
			(xy 48.526446 -350.348296) (xy 48.515778 -350.333056) (xy 48.443896 -350.285304) (xy 48.425862 -350.28124)
			(xy 48.416718 -350.28251) (xy 48.403701 -350.284175) (xy 48.377517 -350.285958) (xy 48.364394 -350.286066)
			(xy 48.350245 -350.285973) (xy 48.322022 -350.283938) (xy 48.308006 -350.282002) (xy 48.297846 -350.280478)
			(xy 48.278288 -350.285304) (xy 48.203866 -350.341184) (xy 48.193706 -350.35871) (xy 48.192436 -350.36887)
			(xy 48.18835 -350.396023) (xy 48.173374 -350.448852) (xy 48.150981 -350.498989) (xy 48.121632 -350.545399)
			(xy 48.085935 -350.587122) (xy 48.044625 -350.623298) (xy 47.998557 -350.653179) (xy 47.948681 -350.676149)
			(xy 47.896028 -350.691732) (xy 47.841685 -350.699607) (xy 47.81423 -350.700086) (xy 47.786977 -350.699617)
			(xy 47.733025 -350.691863) (xy 47.680726 -350.67651) (xy 47.631144 -350.653869) (xy 47.58529 -350.624402)
			(xy 47.544097 -350.588709) (xy 47.508402 -350.547516) (xy 47.478935 -350.501663) (xy 47.456293 -350.452082)
			(xy 47.440938 -350.399783) (xy 47.433184 -350.345831) (xy 47.432722 -350.318578) (xy 45.291836 -350.318578)
			(xy 45.294466 -350.327539) (xy 45.302218 -350.381494) (xy 45.302678 -350.408748) (xy 45.302025 -350.440311)
			(xy 45.291635 -350.502577) (xy 45.271147 -350.562286) (xy 45.256704 -350.590358) (xy 45.251878 -350.599248)
			(xy 45.249846 -350.618806) (xy 45.2755 -350.706944) (xy 45.287946 -350.722438) (xy 45.296836 -350.727518)
			(xy 45.321915 -350.742104) (xy 45.3678 -350.777599) (xy 45.407778 -350.819635) (xy 45.440927 -350.867242)
			(xy 45.466482 -350.919322) (xy 45.483852 -350.974672) (xy 45.492637 -351.032014) (xy 45.493178 -351.06102)
			(xy 45.492692 -351.088271) (xy 45.484936 -351.142219) (xy 45.469581 -351.194514) (xy 45.446939 -351.244091)
			(xy 45.417473 -351.289941) (xy 45.381782 -351.331132) (xy 45.340591 -351.366823) (xy 45.294741 -351.396289)
			(xy 45.245164 -351.418931) (xy 45.192869 -351.434286) (xy 45.138921 -351.442042) (xy 45.084419 -351.442042)
			(xy 45.030471 -351.434286) (xy 44.978176 -351.418931) (xy 44.928599 -351.396289) (xy 44.882749 -351.366823)
			(xy 44.841558 -351.331132) (xy 44.805867 -351.289941) (xy 44.776401 -351.244091) (xy 44.753759 -351.194514)
			(xy 44.738404 -351.142219) (xy 44.730648 -351.088271) (xy 44.730162 -351.06102) (xy 44.73081 -351.029457)
			(xy 44.741203 -350.967191) (xy 44.761693 -350.907483) (xy 44.776136 -350.87941) (xy 44.780962 -350.87052)
			(xy 44.782994 -350.850962) (xy 44.75734 -350.762824) (xy 44.744894 -350.74733) (xy 44.736004 -350.74225)
			(xy 44.728638 -350.738186) (xy 44.718986 -350.732344) (xy 44.696888 -350.730312) (xy 44.6024 -350.76384)
			(xy 44.586398 -350.779334) (xy 44.582334 -350.789748) (xy 44.571652 -350.81653) (xy 44.54336 -350.86677)
			(xy 44.507827 -350.912178) (xy 44.465863 -350.951719) (xy 44.418424 -350.984492) (xy 44.366592 -351.009749)
			(xy 44.311548 -351.026915) (xy 44.254547 -351.035598) (xy 44.225718 -351.036128) (xy 44.198466 -351.035626)
			(xy 44.144516 -351.027871) (xy 44.092218 -351.012518) (xy 44.042639 -350.989878) (xy 43.996786 -350.960412)
			(xy 43.955593 -350.92472) (xy 43.919899 -350.883529) (xy 43.890431 -350.837677) (xy 43.867789 -350.788098)
			(xy 43.852432 -350.735802) (xy 43.844675 -350.681852) (xy 43.576265 -350.681852) (xy 43.555884 -350.726018)
			(xy 43.525934 -350.772088) (xy 43.508168 -350.79305) (xy 43.502072 -350.800162) (xy 43.495722 -350.81718)
			(xy 43.495722 -350.903032) (xy 43.502072 -350.92005) (xy 43.508168 -350.927162) (xy 43.525906 -350.948145)
			(xy 43.555832 -350.994222) (xy 43.578849 -351.044111) (xy 43.594481 -351.096783) (xy 43.602406 -351.151151)
			(xy 43.60291 -351.178622) (xy 43.602424 -351.205873) (xy 43.594668 -351.259821) (xy 43.579313 -351.312116)
			(xy 43.556671 -351.361693) (xy 43.527205 -351.407543) (xy 43.491514 -351.448734) (xy 43.450323 -351.484425)
			(xy 43.404473 -351.513891) (xy 43.354896 -351.536533) (xy 43.302601 -351.551888) (xy 43.248653 -351.559644)
			(xy 43.194151 -351.559644) (xy 43.140203 -351.551888) (xy 43.087908 -351.536533) (xy 43.038331 -351.513891)
			(xy 42.992481 -351.484425) (xy 42.95129 -351.448734) (xy 42.915599 -351.407543) (xy 42.886133 -351.361693)
			(xy 42.863491 -351.312116) (xy 42.848136 -351.259821) (xy 42.84038 -351.205873) (xy 42.839894 -351.178622)
			(xy 37.168447 -351.178622) (xy 37.163781 -351.194514) (xy 37.141139 -351.244091) (xy 37.111673 -351.289941)
			(xy 37.075982 -351.331132) (xy 37.034791 -351.366823) (xy 36.988941 -351.396289) (xy 36.939364 -351.418931)
			(xy 36.887069 -351.434286) (xy 36.833121 -351.442042) (xy 36.778619 -351.442042) (xy 36.724671 -351.434286)
			(xy 36.672376 -351.418931) (xy 36.622799 -351.396289) (xy 36.576949 -351.366823) (xy 36.535758 -351.331132)
			(xy 36.500067 -351.289941) (xy 36.470601 -351.244091) (xy 36.447959 -351.194514) (xy 36.432604 -351.142219)
			(xy 36.424848 -351.088271) (xy 36.424362 -351.06102) (xy 36.42501 -351.029457) (xy 36.435403 -350.967191)
			(xy 36.455893 -350.907483) (xy 36.470336 -350.87941) (xy 36.475162 -350.87052) (xy 36.477194 -350.850962)
			(xy 36.45154 -350.762824) (xy 36.439094 -350.74733) (xy 36.430204 -350.74225) (xy 36.422838 -350.738186)
			(xy 36.413186 -350.732344) (xy 36.391088 -350.730312) (xy 36.2966 -350.76384) (xy 36.280598 -350.779334)
			(xy 36.276534 -350.789748) (xy 36.265852 -350.81653) (xy 36.23756 -350.86677) (xy 36.202027 -350.912178)
			(xy 36.160063 -350.951719) (xy 36.112624 -350.984492) (xy 36.060792 -351.009749) (xy 36.005748 -351.026915)
			(xy 35.948747 -351.035598) (xy 35.919918 -351.036128) (xy 35.892666 -351.035626) (xy 35.838716 -351.027871)
			(xy 35.786418 -351.012518) (xy 35.736839 -350.989878) (xy 35.690986 -350.960412) (xy 35.649793 -350.92472)
			(xy 35.614099 -350.883529) (xy 35.584631 -350.837677) (xy 35.561989 -350.788098) (xy 35.546632 -350.735802)
			(xy 35.538875 -350.681852) (xy 35.270465 -350.681852) (xy 35.250084 -350.726018) (xy 35.220134 -350.772088)
			(xy 35.202368 -350.79305) (xy 35.196272 -350.800162) (xy 35.189922 -350.81718) (xy 35.189922 -350.903032)
			(xy 35.196272 -350.92005) (xy 35.202368 -350.927162) (xy 35.220106 -350.948145) (xy 35.250032 -350.994222)
			(xy 35.273049 -351.044111) (xy 35.288681 -351.096783) (xy 35.296606 -351.151151) (xy 35.29711 -351.178622)
			(xy 35.296624 -351.205873) (xy 35.288868 -351.259821) (xy 35.273513 -351.312116) (xy 35.250871 -351.361693)
			(xy 35.221405 -351.407543) (xy 35.185714 -351.448734) (xy 35.144523 -351.484425) (xy 35.098673 -351.513891)
			(xy 35.049096 -351.536533) (xy 34.996801 -351.551888) (xy 34.942853 -351.559644) (xy 34.888351 -351.559644)
			(xy 34.834403 -351.551888) (xy 34.782108 -351.536533) (xy 34.732531 -351.513891) (xy 34.686681 -351.484425)
			(xy 34.64549 -351.448734) (xy 34.609799 -351.407543) (xy 34.580333 -351.361693) (xy 34.557691 -351.312116)
			(xy 34.542336 -351.259821) (xy 34.53458 -351.205873) (xy 34.534094 -351.178622) (xy 28.888047 -351.178622)
			(xy 28.883381 -351.194514) (xy 28.860739 -351.244091) (xy 28.831273 -351.289941) (xy 28.795582 -351.331132)
			(xy 28.754391 -351.366823) (xy 28.708541 -351.396289) (xy 28.658964 -351.418931) (xy 28.606669 -351.434286)
			(xy 28.552721 -351.442042) (xy 28.498219 -351.442042) (xy 28.444271 -351.434286) (xy 28.391976 -351.418931)
			(xy 28.342399 -351.396289) (xy 28.296549 -351.366823) (xy 28.255358 -351.331132) (xy 28.219667 -351.289941)
			(xy 28.190201 -351.244091) (xy 28.167559 -351.194514) (xy 28.152204 -351.142219) (xy 28.144448 -351.088271)
			(xy 28.143962 -351.06102) (xy 28.14461 -351.029457) (xy 28.155003 -350.967191) (xy 28.175493 -350.907483)
			(xy 28.189936 -350.87941) (xy 28.194762 -350.87052) (xy 28.196794 -350.850962) (xy 28.17114 -350.762824)
			(xy 28.158694 -350.74733) (xy 28.149804 -350.74225) (xy 28.142438 -350.738186) (xy 28.132786 -350.732344)
			(xy 28.110688 -350.730312) (xy 28.0162 -350.76384) (xy 28.000198 -350.779334) (xy 27.996134 -350.789748)
			(xy 27.985452 -350.81653) (xy 27.95716 -350.86677) (xy 27.921627 -350.912178) (xy 27.879663 -350.951719)
			(xy 27.832224 -350.984492) (xy 27.780392 -351.009749) (xy 27.725348 -351.026915) (xy 27.668347 -351.035598)
			(xy 27.639518 -351.036128) (xy 27.612266 -351.035626) (xy 27.558316 -351.027871) (xy 27.506018 -351.012518)
			(xy 27.456439 -350.989878) (xy 27.410586 -350.960412) (xy 27.369393 -350.92472) (xy 27.333699 -350.883529)
			(xy 27.304231 -350.837677) (xy 27.281589 -350.788098) (xy 27.266232 -350.735802) (xy 27.258475 -350.681852)
			(xy 26.990065 -350.681852) (xy 26.969684 -350.726018) (xy 26.939734 -350.772088) (xy 26.921968 -350.79305)
			(xy 26.915872 -350.800162) (xy 26.909522 -350.81718) (xy 26.909522 -350.903032) (xy 26.915872 -350.92005)
			(xy 26.921968 -350.927162) (xy 26.939706 -350.948145) (xy 26.969632 -350.994222) (xy 26.992649 -351.044111)
			(xy 27.008281 -351.096783) (xy 27.016206 -351.151151) (xy 27.01671 -351.178622) (xy 27.016224 -351.205873)
			(xy 27.008468 -351.259821) (xy 26.993113 -351.312116) (xy 26.970471 -351.361693) (xy 26.941005 -351.407543)
			(xy 26.905314 -351.448734) (xy 26.864123 -351.484425) (xy 26.818273 -351.513891) (xy 26.768696 -351.536533)
			(xy 26.716401 -351.551888) (xy 26.662453 -351.559644) (xy 26.607951 -351.559644) (xy 26.554003 -351.551888)
			(xy 26.501708 -351.536533) (xy 26.452131 -351.513891) (xy 26.406281 -351.484425) (xy 26.36509 -351.448734)
			(xy 26.329399 -351.407543) (xy 26.299933 -351.361693) (xy 26.277291 -351.312116) (xy 26.261936 -351.259821)
			(xy 26.25418 -351.205873) (xy 26.253694 -351.178622) (xy 24.125428 -351.178622) (xy 24.125428 -351.270824)
			(xy 24.125001 -351.280893) (xy 24.117284 -351.299494) (xy 24.110442 -351.306892) (xy 23.395686 -352.021648)
			(xy 24.394666 -352.021648) (xy 24.398737 -351.966026) (xy 24.410863 -351.911589) (xy 24.430786 -351.859498)
			(xy 24.458082 -351.810863) (xy 24.492168 -351.76672) (xy 24.532317 -351.728011) (xy 24.577675 -351.69556)
			(xy 24.627275 -351.670059) (xy 24.680059 -351.652052) (xy 24.734902 -351.641922) (xy 24.790636 -351.639885)
			(xy 24.846073 -351.645985) (xy 24.90003 -351.660091) (xy 24.951359 -351.681903) (xy 24.998965 -351.710957)
			(xy 25.041833 -351.746632) (xy 25.07905 -351.788169) (xy 25.109823 -351.834682) (xy 25.133495 -351.885179)
			(xy 25.149563 -351.938586) (xy 25.157683 -351.993762) (xy 25.158192 -352.021648) (xy 25.157683 -352.049534)
			(xy 25.149563 -352.10471) (xy 25.133495 -352.158117) (xy 25.109823 -352.208614) (xy 25.07905 -352.255127)
			(xy 25.041833 -352.296664) (xy 24.998965 -352.332339) (xy 24.951359 -352.361393) (xy 24.90003 -352.383205)
			(xy 24.846073 -352.397311) (xy 24.790636 -352.403411) (xy 24.734902 -352.401374) (xy 24.680059 -352.391244)
			(xy 24.627275 -352.373237) (xy 24.577675 -352.347736) (xy 24.532317 -352.315285) (xy 24.492168 -352.276576)
			(xy 24.458082 -352.232433) (xy 24.430786 -352.183798) (xy 24.410863 -352.131707) (xy 24.398737 -352.07727)
			(xy 24.394666 -352.021648) (xy 23.395686 -352.021648) (xy 22.133306 -353.284028) (xy 22.126956 -353.313238)
			(xy 22.132544 -353.327716) (xy 22.14074 -353.349776) (xy 22.152257 -353.395407) (xy 22.158075 -353.442107)
			(xy 22.158452 -353.465638) (xy 22.157964 -353.492889) (xy 22.150203 -353.546835) (xy 22.134845 -353.599127)
			(xy 22.112202 -353.648703) (xy 22.082736 -353.694551) (xy 22.047045 -353.735741) (xy 22.005856 -353.771432)
			(xy 21.960008 -353.800899) (xy 21.910433 -353.823543) (xy 21.85814 -353.838902) (xy 21.804195 -353.846663)
			(xy 21.776944 -353.847146) (xy 21.753413 -353.846781) (xy 21.706712 -353.840959) (xy 21.661083 -353.829433)
			(xy 21.639022 -353.821238) (xy 21.624544 -353.81565) (xy 21.595334 -353.822) (xy 19.031204 -356.38613)
			(xy 19.024524 -356.393541) (xy 19.016952 -356.411977) (xy 19.016472 -356.421944) (xy 19.016472 -356.63632)
			(xy 21.67204 -356.63632) (xy 21.676111 -356.580698) (xy 21.688237 -356.526261) (xy 21.70816 -356.47417)
			(xy 21.735456 -356.425535) (xy 21.769542 -356.381392) (xy 21.809691 -356.342683) (xy 21.855049 -356.310232)
			(xy 21.904649 -356.284731) (xy 21.957433 -356.266724) (xy 22.012276 -356.256594) (xy 22.06801 -356.254557)
			(xy 22.123447 -356.260657) (xy 22.177404 -356.274763) (xy 22.228733 -356.296575) (xy 22.276339 -356.325629)
			(xy 22.319207 -356.361304) (xy 22.356424 -356.402841) (xy 22.387197 -356.449354) (xy 22.410869 -356.499851)
			(xy 22.426937 -356.553258) (xy 22.435057 -356.608434) (xy 22.435566 -356.63632) (xy 22.435057 -356.664206)
			(xy 22.426937 -356.719382) (xy 22.410869 -356.772789) (xy 22.387197 -356.823286) (xy 22.356424 -356.869799)
			(xy 22.319207 -356.911336) (xy 22.276339 -356.947011) (xy 22.228733 -356.976065) (xy 22.177404 -356.997877)
			(xy 22.123447 -357.011983) (xy 22.06801 -357.018083) (xy 22.012276 -357.016046) (xy 21.957433 -357.005916)
			(xy 21.904649 -356.987909) (xy 21.855049 -356.962408) (xy 21.809691 -356.929957) (xy 21.769542 -356.891248)
			(xy 21.735456 -356.847105) (xy 21.70816 -356.79847) (xy 21.688237 -356.746379) (xy 21.676111 -356.691942)
			(xy 21.67204 -356.63632) (xy 19.016472 -356.63632) (xy 19.016472 -357.295704) (xy 20.033994 -357.295704)
			(xy 20.038065 -357.240082) (xy 20.050191 -357.185645) (xy 20.070114 -357.133554) (xy 20.09741 -357.084919)
			(xy 20.131496 -357.040776) (xy 20.171645 -357.002067) (xy 20.217003 -356.969616) (xy 20.266603 -356.944115)
			(xy 20.319387 -356.926108) (xy 20.37423 -356.915978) (xy 20.429964 -356.913941) (xy 20.485401 -356.920041)
			(xy 20.539358 -356.934147) (xy 20.590687 -356.955959) (xy 20.638293 -356.985013) (xy 20.681161 -357.020688)
			(xy 20.718378 -357.062225) (xy 20.749151 -357.108738) (xy 20.772823 -357.159235) (xy 20.788891 -357.212642)
			(xy 20.797011 -357.267818) (xy 20.79752 -357.295704) (xy 20.797011 -357.32359) (xy 20.788891 -357.378766)
			(xy 20.772823 -357.432173) (xy 20.749151 -357.48267) (xy 20.718378 -357.529183) (xy 20.681161 -357.57072)
			(xy 20.638293 -357.606395) (xy 20.596338 -357.632) (xy 23.239982 -357.632) (xy 23.244053 -357.576378)
			(xy 23.256179 -357.521941) (xy 23.276102 -357.46985) (xy 23.303398 -357.421215) (xy 23.337484 -357.377072)
			(xy 23.377633 -357.338363) (xy 23.422991 -357.305912) (xy 23.472591 -357.280411) (xy 23.525375 -357.262404)
			(xy 23.580218 -357.252274) (xy 23.635952 -357.250237) (xy 23.691389 -357.256337) (xy 23.745346 -357.270443)
			(xy 23.796675 -357.292255) (xy 23.844281 -357.321309) (xy 23.887149 -357.356984) (xy 23.924366 -357.398521)
			(xy 23.955139 -357.445034) (xy 23.97432 -357.48595) (xy 27.558492 -357.48595) (xy 27.559002 -357.458698)
			(xy 27.566752 -357.404749) (xy 27.582102 -357.352452) (xy 27.604738 -357.302872) (xy 27.634201 -357.257019)
			(xy 27.66989 -357.215826) (xy 27.711079 -357.180131) (xy 27.756928 -357.150662) (xy 27.806505 -357.128019)
			(xy 27.8588 -357.112663) (xy 27.912748 -357.104905) (xy 27.94 -357.104442) (xy 27.970147 -357.105003)
			(xy 28.02969 -357.114482) (xy 28.086998 -357.13322) (xy 28.140641 -357.160748) (xy 28.165298 -357.178102)
			(xy 28.176982 -357.186738) (xy 28.20543 -357.189024) (xy 28.299156 -357.141526) (xy 28.307342 -357.136913)
			(xy 28.319918 -357.12297) (xy 28.326665 -357.105448) (xy 28.327096 -357.09606) (xy 28.327096 -356.795324)
			(xy 28.302966 -356.766876) (xy 28.284424 -356.763828) (xy 28.25799 -356.759024) (xy 28.206727 -356.742945)
			(xy 28.158226 -356.719832) (xy 28.113448 -356.690144) (xy 28.073278 -356.654467) (xy 28.03851 -356.613507)
			(xy 28.009833 -356.568075) (xy 27.987814 -356.519069) (xy 27.972888 -356.467458) (xy 27.96535 -356.414263)
			(xy 27.964892 -356.3874) (xy 27.965378 -356.360149) (xy 27.973134 -356.306201) (xy 27.988489 -356.253906)
			(xy 28.011131 -356.204329) (xy 28.040597 -356.158479) (xy 28.076288 -356.117288) (xy 28.117479 -356.081597)
			(xy 28.163329 -356.052131) (xy 28.212906 -356.029489) (xy 28.265201 -356.014134) (xy 28.319149 -356.006378)
			(xy 28.3464 -356.005892) (xy 28.375923 -356.006464) (xy 28.434259 -356.015594) (xy 28.490491 -356.033606)
			(xy 28.543275 -356.060068) (xy 28.567634 -356.076758) (xy 28.583128 -356.08768) (xy 28.619704 -356.084378)
			(xy 28.904946 -355.79939) (xy 28.911767 -355.791961) (xy 28.919495 -355.773354) (xy 28.919406 -355.753206)
			(xy 28.915868 -355.743764) (xy 28.87345 -355.642672) (xy 28.847796 -355.625654) (xy 28.832302 -355.625908)
			(xy 28.829 -355.625908) (xy 28.801749 -355.625422) (xy 28.747801 -355.617666) (xy 28.695506 -355.602311)
			(xy 28.645929 -355.579669) (xy 28.600079 -355.550203) (xy 28.558888 -355.514512) (xy 28.523197 -355.473321)
			(xy 28.493731 -355.427471) (xy 28.471089 -355.377894) (xy 28.455734 -355.325599) (xy 28.447978 -355.271651)
			(xy 28.447978 -355.217149) (xy 28.455734 -355.163201) (xy 28.471089 -355.110906) (xy 28.493731 -355.061329)
			(xy 28.523197 -355.015479) (xy 28.558888 -354.974288) (xy 28.600079 -354.938597) (xy 28.645929 -354.909131)
			(xy 28.695506 -354.886489) (xy 28.747801 -354.871134) (xy 28.801749 -354.863378) (xy 28.856251 -354.863378)
			(xy 28.910199 -354.871134) (xy 28.962494 -354.886489) (xy 29.012071 -354.909131) (xy 29.057921 -354.938597)
			(xy 29.099112 -354.974288) (xy 29.134803 -355.015479) (xy 29.164269 -355.061329) (xy 29.186911 -355.110906)
			(xy 29.202266 -355.163201) (xy 29.210022 -355.217149) (xy 29.210508 -355.2444) (xy 29.210508 -355.247702)
			(xy 29.210254 -355.263196) (xy 29.227272 -355.28885) (xy 29.328364 -355.331268) (xy 29.337813 -355.334762)
			(xy 29.357944 -355.33481) (xy 29.37656 -355.327149) (xy 29.38399 -355.320346) (xy 29.840428 -354.863654)
			(xy 29.857703 -354.846982) (xy 29.896515 -354.818726) (xy 29.93927 -354.796891) (xy 29.984914 -354.782013)
			(xy 30.032324 -354.77446) (xy 30.056328 -354.773992) (xy 30.565852 -354.773992) (xy 30.572456 -354.772214)
			(xy 30.592076 -354.767174) (xy 30.632213 -354.761693) (xy 30.652466 -354.761292) (xy 35.09518 -354.761292)
			(xy 35.100071 -354.761422) (xy 35.109663 -354.763345) (xy 35.11423 -354.765102) (xy 35.209988 -354.803964)
			(xy 35.214816 -354.806049) (xy 35.223524 -354.811946) (xy 35.22726 -354.815648) (xy 35.262566 -354.852224)
			(xy 35.263328 -354.852732) (xy 35.343846 -354.93325) (xy 35.359911 -354.949892) (xy 35.387332 -354.987143)
			(xy 35.408814 -355.028107) (xy 35.416744 -355.049836) (xy 35.421062 -355.062282) (xy 35.44062 -355.079808)
			(xy 35.53714 -355.10216) (xy 35.545606 -355.10378) (xy 35.562731 -355.101924) (xy 35.578284 -355.094522)
			(xy 35.584638 -355.088698) (xy 38.102286 -352.57105) (xy 38.120389 -352.55382) (xy 38.161951 -352.52608)
			(xy 38.208123 -352.506975) (xy 38.257134 -352.497237) (xy 38.282118 -352.496628) (xy 50.325782 -352.496628)
			(xy 50.335853 -352.496212) (xy 50.354452 -352.488487) (xy 50.36185 -352.481642) (xy 50.752502 -352.09099)
			(xy 50.759339 -352.083588) (xy 50.767061 -352.06499) (xy 50.767488 -352.054922) (xy 50.767488 -350.821498)
			(xy 50.768106 -350.796515) (xy 50.777846 -350.747506) (xy 50.796951 -350.701337) (xy 50.824689 -350.659776)
			(xy 50.84191 -350.641666) (xy 51.121818 -350.361758) (xy 51.137467 -350.346706) (xy 51.172933 -350.321661)
			(xy 51.212136 -350.303003) (xy 51.253939 -350.291275) (xy 51.275488 -350.288606) (xy 51.284202 -350.287308)
			(xy 51.300053 -350.279649) (xy 51.306476 -350.27362) (xy 51.328124 -350.252509) (xy 51.376848 -350.216706)
			(xy 51.43061 -350.189038) (xy 51.488064 -350.170198) (xy 51.54777 -350.160659) (xy 51.578002 -350.160082)
			(xy 51.605253 -350.160576) (xy 51.6592 -350.168332) (xy 51.711494 -350.183687) (xy 51.76107 -350.206328)
			(xy 51.80692 -350.235794) (xy 51.84811 -350.271484) (xy 51.883802 -350.312673) (xy 51.913268 -350.358523)
			(xy 51.93591 -350.408099) (xy 51.951266 -350.460392) (xy 51.959024 -350.514339) (xy 51.95951 -350.54159)
			(xy 51.959015 -350.569064) (xy 51.951125 -350.623443) (xy 51.935507 -350.676126) (xy 51.932865 -350.681852)
			(xy 52.201275 -350.681852) (xy 52.201275 -350.627348) (xy 52.209032 -350.573398) (xy 52.224389 -350.521102)
			(xy 52.247031 -350.471523) (xy 52.276499 -350.425671) (xy 52.312193 -350.38448) (xy 52.353386 -350.348788)
			(xy 52.399239 -350.319322) (xy 52.448818 -350.296682) (xy 52.501116 -350.281329) (xy 52.555066 -350.273574)
			(xy 52.582318 -350.273112) (xy 52.607554 -350.273499) (xy 52.657588 -350.28012) (xy 52.706308 -350.293296)
			(xy 52.75286 -350.312796) (xy 52.77485 -350.325182) (xy 52.784502 -350.331024) (xy 52.8066 -350.333056)
			(xy 52.901088 -350.299528) (xy 52.91709 -350.284034) (xy 52.921154 -350.27362) (xy 52.931883 -350.246857)
			(xy 52.960165 -350.196615) (xy 52.995689 -350.151205) (xy 53.037646 -350.111661) (xy 53.085079 -350.078885)
			(xy 53.136906 -350.053625) (xy 53.191945 -350.036457) (xy 53.248942 -350.027771) (xy 53.27777 -350.02724)
			(xy 53.305024 -350.027683) (xy 53.358978 -350.035437) (xy 53.41128 -350.050792) (xy 53.460863 -350.073435)
			(xy 53.506718 -350.102904) (xy 53.547913 -350.1386) (xy 53.583607 -350.179796) (xy 53.613074 -350.225653)
			(xy 53.635714 -350.275237) (xy 53.648436 -350.318578) (xy 55.789322 -350.318578) (xy 55.789834 -350.291005)
			(xy 55.797776 -350.236434) (xy 55.813491 -350.183575) (xy 55.836652 -350.133528) (xy 55.866777 -350.087337)
			(xy 55.903238 -350.045965) (xy 55.923942 -350.027748) (xy 55.932041 -350.020128) (xy 55.941404 -349.99999)
			(xy 55.941976 -349.988886) (xy 55.941976 -349.91167) (xy 55.941448 -349.900555) (xy 55.932082 -349.880396)
			(xy 55.923942 -349.872808) (xy 55.90324 -349.854587) (xy 55.866767 -349.813221) (xy 55.836633 -349.767034)
			(xy 55.813465 -349.716988) (xy 55.797747 -349.664126) (xy 55.789807 -349.609552) (xy 55.789322 -349.581978)
			(xy 55.789734 -349.554723) (xy 55.797495 -349.500769) (xy 55.812856 -349.448468) (xy 55.835503 -349.398886)
			(xy 55.864976 -349.353031) (xy 55.900675 -349.311838) (xy 55.941873 -349.276145) (xy 55.987732 -349.246678)
			(xy 56.037317 -349.224037) (xy 56.08962 -349.208684) (xy 56.143575 -349.200931) (xy 56.17083 -349.20047)
			(xy 56.20512 -349.201994) (xy 56.21528 -349.20301) (xy 56.234584 -349.196914) (xy 56.305196 -349.137732)
			(xy 56.314594 -349.119698) (xy 56.31561 -349.109538) (xy 56.318525 -349.08136) (xy 56.331703 -349.026266)
			(xy 56.352885 -348.973727) (xy 56.381606 -348.924899) (xy 56.417235 -348.880858) (xy 56.458986 -348.842572)
			(xy 56.505942 -348.810883) (xy 56.557069 -348.786489) (xy 56.611243 -348.769927) (xy 56.66727 -348.76156)
			(xy 56.695594 -348.76105) (xy 56.713613 -348.761277) (xy 56.749488 -348.764707) (xy 56.767222 -348.767908)
			(xy 56.77662 -348.769686) (xy 56.79567 -348.765876) (xy 56.870854 -348.718124) (xy 56.882284 -348.702376)
			(xy 56.88457 -348.692978) (xy 56.892025 -348.665951) (xy 56.913648 -348.614227) (xy 56.942605 -348.566223)
			(xy 56.978273 -348.522971) (xy 57.019885 -348.485403) (xy 57.066545 -348.454326) (xy 57.117249 -348.43041)
			(xy 57.170907 -348.414169) (xy 57.226363 -348.405952) (xy 57.254394 -348.40545) (xy 57.281643 -348.405983)
			(xy 57.335587 -348.413738) (xy 57.387878 -348.42909) (xy 57.437453 -348.451727) (xy 57.483301 -348.481189)
			(xy 57.52449 -348.516876) (xy 57.560182 -348.55806) (xy 57.58965 -348.603905) (xy 57.612293 -348.653477)
			(xy 57.627652 -348.705766) (xy 57.635413 -348.759709) (xy 57.635902 -348.786958) (xy 57.635407 -348.814531)
			(xy 57.62746 -348.869103) (xy 57.611741 -348.921962) (xy 57.588576 -348.972008) (xy 57.558449 -349.018199)
			(xy 57.521987 -349.059571) (xy 57.501282 -349.077788) (xy 57.493171 -349.085397) (xy 57.483813 -349.105544)
			(xy 57.483248 -349.11665) (xy 57.483248 -349.193866) (xy 57.483804 -349.204978) (xy 57.493149 -349.225137)
			(xy 57.501282 -349.232728) (xy 57.521946 -349.250989) (xy 57.558411 -349.292354) (xy 57.58854 -349.338538)
			(xy 57.611705 -349.388579) (xy 57.627423 -349.441434) (xy 57.635367 -349.496001) (xy 57.635371 -349.551144)
			(xy 57.627435 -349.605713) (xy 57.626865 -349.607632) (xy 58.767978 -349.607632) (xy 58.772049 -349.55201)
			(xy 58.784175 -349.497573) (xy 58.804098 -349.445482) (xy 58.831394 -349.396847) (xy 58.86548 -349.352704)
			(xy 58.905629 -349.313995) (xy 58.950987 -349.281544) (xy 59.000587 -349.256043) (xy 59.053371 -349.238036)
			(xy 59.108214 -349.227906) (xy 59.163948 -349.225869) (xy 59.219385 -349.231969) (xy 59.273342 -349.246075)
			(xy 59.324671 -349.267887) (xy 59.372277 -349.296941) (xy 59.415145 -349.332616) (xy 59.452362 -349.374153)
			(xy 59.483135 -349.420666) (xy 59.506807 -349.471163) (xy 59.522875 -349.52457) (xy 59.530995 -349.579746)
			(xy 59.531504 -349.607632) (xy 59.530995 -349.635518) (xy 59.522875 -349.690694) (xy 59.506807 -349.744101)
			(xy 59.483135 -349.794598) (xy 59.452362 -349.841111) (xy 59.415145 -349.882648) (xy 59.372277 -349.918323)
			(xy 59.324671 -349.947377) (xy 59.273342 -349.969189) (xy 59.219385 -349.983295) (xy 59.163948 -349.989395)
			(xy 59.108214 -349.987358) (xy 59.053371 -349.977228) (xy 59.000587 -349.959221) (xy 58.950987 -349.93372)
			(xy 58.905629 -349.901269) (xy 58.86548 -349.86256) (xy 58.831394 -349.818417) (xy 58.804098 -349.769782)
			(xy 58.784175 -349.717691) (xy 58.772049 -349.663254) (xy 58.767978 -349.607632) (xy 57.626865 -349.607632)
			(xy 57.611724 -349.65857) (xy 57.588567 -349.708615) (xy 57.558444 -349.754803) (xy 57.521985 -349.796173)
			(xy 57.501282 -349.814388) (xy 57.493171 -349.821997) (xy 57.483813 -349.842144) (xy 57.483248 -349.85325)
			(xy 57.483248 -349.930466) (xy 57.483804 -349.941578) (xy 57.493149 -349.961737) (xy 57.501282 -349.969328)
			(xy 57.522006 -349.987525) (xy 57.558476 -350.028896) (xy 57.588607 -350.075089) (xy 57.611771 -350.12514)
			(xy 57.627484 -350.178005) (xy 57.635419 -350.232582) (xy 57.635902 -350.260158) (xy 57.635406 -350.28741)
			(xy 57.627654 -350.34136) (xy 57.612303 -350.393658) (xy 57.589665 -350.443238) (xy 57.560201 -350.489092)
			(xy 57.548167 -350.502982) (xy 58.188858 -350.502982) (xy 58.192929 -350.44736) (xy 58.205055 -350.392923)
			(xy 58.224978 -350.340832) (xy 58.252274 -350.292197) (xy 58.28636 -350.248054) (xy 58.326509 -350.209345)
			(xy 58.371867 -350.176894) (xy 58.421467 -350.151393) (xy 58.474251 -350.133386) (xy 58.529094 -350.123256)
			(xy 58.584828 -350.121219) (xy 58.640265 -350.127319) (xy 58.694222 -350.141425) (xy 58.745551 -350.163237)
			(xy 58.793157 -350.192291) (xy 58.836025 -350.227966) (xy 58.873242 -350.269503) (xy 58.904015 -350.316016)
			(xy 58.927687 -350.366513) (xy 58.943755 -350.41992) (xy 58.951875 -350.475096) (xy 58.952384 -350.502982)
			(xy 58.951875 -350.530868) (xy 58.943755 -350.586044) (xy 58.927687 -350.639451) (xy 58.904015 -350.689948)
			(xy 58.873242 -350.736461) (xy 58.836025 -350.777998) (xy 58.793157 -350.813673) (xy 58.745551 -350.842727)
			(xy 58.694222 -350.864539) (xy 58.640265 -350.878645) (xy 58.584828 -350.884745) (xy 58.529094 -350.882708)
			(xy 58.474251 -350.872578) (xy 58.421467 -350.854571) (xy 58.371867 -350.82907) (xy 58.326509 -350.796619)
			(xy 58.28636 -350.75791) (xy 58.252274 -350.713767) (xy 58.224978 -350.665132) (xy 58.205055 -350.613041)
			(xy 58.192929 -350.558604) (xy 58.188858 -350.502982) (xy 57.548167 -350.502982) (xy 57.524511 -350.530285)
			(xy 57.483321 -350.565979) (xy 57.43747 -350.595448) (xy 57.387892 -350.618091) (xy 57.335595 -350.633447)
			(xy 57.281646 -350.641203) (xy 57.254394 -350.641666) (xy 57.226537 -350.641174) (xy 57.171419 -350.633048)
			(xy 57.118067 -350.617) (xy 57.067613 -350.59337) (xy 57.021127 -350.56266) (xy 56.979598 -350.52552)
			(xy 56.943906 -350.482741) (xy 56.914809 -350.435229) (xy 56.892924 -350.383993) (xy 56.885332 -350.357186)
			(xy 56.883046 -350.348296) (xy 56.872378 -350.333056) (xy 56.800496 -350.285304) (xy 56.782462 -350.28124)
			(xy 56.773318 -350.28251) (xy 56.760301 -350.284175) (xy 56.734117 -350.285958) (xy 56.720994 -350.286066)
			(xy 56.706845 -350.285973) (xy 56.678622 -350.283938) (xy 56.664606 -350.282002) (xy 56.654446 -350.280478)
			(xy 56.634888 -350.285304) (xy 56.560466 -350.341184) (xy 56.550306 -350.35871) (xy 56.549036 -350.36887)
			(xy 56.54495 -350.396023) (xy 56.529974 -350.448852) (xy 56.507581 -350.498989) (xy 56.478232 -350.545399)
			(xy 56.442535 -350.587122) (xy 56.401225 -350.623298) (xy 56.355157 -350.653179) (xy 56.305281 -350.676149)
			(xy 56.252628 -350.691732) (xy 56.198285 -350.699607) (xy 56.17083 -350.700086) (xy 56.143577 -350.699617)
			(xy 56.089625 -350.691863) (xy 56.037326 -350.67651) (xy 55.987744 -350.653869) (xy 55.94189 -350.624402)
			(xy 55.900697 -350.588709) (xy 55.865002 -350.547516) (xy 55.835535 -350.501663) (xy 55.812893 -350.452082)
			(xy 55.797538 -350.399783) (xy 55.789784 -350.345831) (xy 55.789322 -350.318578) (xy 53.648436 -350.318578)
			(xy 53.651066 -350.327539) (xy 53.658818 -350.381494) (xy 53.659278 -350.408748) (xy 53.658625 -350.440311)
			(xy 53.648235 -350.502577) (xy 53.627747 -350.562286) (xy 53.613304 -350.590358) (xy 53.608478 -350.599248)
			(xy 53.606446 -350.618806) (xy 53.6321 -350.706944) (xy 53.644546 -350.722438) (xy 53.653436 -350.727518)
			(xy 53.678515 -350.742104) (xy 53.7244 -350.777599) (xy 53.764378 -350.819635) (xy 53.797527 -350.867242)
			(xy 53.823082 -350.919322) (xy 53.840452 -350.974672) (xy 53.849237 -351.032014) (xy 53.849778 -351.06102)
			(xy 53.849292 -351.088271) (xy 53.841536 -351.142219) (xy 53.830847 -351.178622) (xy 59.527694 -351.178622)
			(xy 59.528195 -351.151148) (xy 59.536083 -351.096769) (xy 59.5517 -351.044087) (xy 59.574722 -350.994194)
			(xy 59.60467 -350.948124) (xy 59.622436 -350.927162) (xy 59.628532 -350.92005) (xy 59.634882 -350.903032)
			(xy 59.634882 -350.81718) (xy 59.628532 -350.800162) (xy 59.622436 -350.79305) (xy 59.604658 -350.7721)
			(xy 59.574737 -350.726014) (xy 59.551728 -350.676116) (xy 59.536106 -350.623437) (xy 59.528192 -350.569063)
			(xy 59.527694 -350.54159) (xy 59.52818 -350.514339) (xy 59.535936 -350.460391) (xy 59.551291 -350.408096)
			(xy 59.573933 -350.358519) (xy 59.603399 -350.312669) (xy 59.63909 -350.271478) (xy 59.680281 -350.235787)
			(xy 59.726131 -350.206321) (xy 59.775708 -350.183679) (xy 59.828003 -350.168324) (xy 59.881951 -350.160568)
			(xy 59.936453 -350.160568) (xy 59.990401 -350.168324) (xy 60.042696 -350.183679) (xy 60.092273 -350.206321)
			(xy 60.138123 -350.235787) (xy 60.179314 -350.271478) (xy 60.215005 -350.312669) (xy 60.244471 -350.358519)
			(xy 60.267113 -350.408096) (xy 60.282468 -350.460391) (xy 60.290224 -350.514339) (xy 60.29071 -350.54159)
			(xy 60.290215 -350.569064) (xy 60.282325 -350.623443) (xy 60.266707 -350.676126) (xy 60.264065 -350.681852)
			(xy 60.532475 -350.681852) (xy 60.532475 -350.627348) (xy 60.540232 -350.573398) (xy 60.555589 -350.521102)
			(xy 60.578231 -350.471523) (xy 60.607699 -350.425671) (xy 60.643393 -350.38448) (xy 60.684586 -350.348788)
			(xy 60.730439 -350.319322) (xy 60.780018 -350.296682) (xy 60.832316 -350.281329) (xy 60.886266 -350.273574)
			(xy 60.913518 -350.273112) (xy 60.938754 -350.273499) (xy 60.988788 -350.28012) (xy 61.037508 -350.293296)
			(xy 61.08406 -350.312796) (xy 61.10605 -350.325182) (xy 61.115702 -350.331024) (xy 61.1378 -350.333056)
			(xy 61.232288 -350.299528) (xy 61.24829 -350.284034) (xy 61.252354 -350.27362) (xy 61.263083 -350.246857)
			(xy 61.291365 -350.196615) (xy 61.326889 -350.151205) (xy 61.368846 -350.111661) (xy 61.416279 -350.078885)
			(xy 61.468106 -350.053625) (xy 61.523145 -350.036457) (xy 61.580142 -350.027771) (xy 61.60897 -350.02724)
			(xy 61.636224 -350.027683) (xy 61.690178 -350.035437) (xy 61.74248 -350.050792) (xy 61.792063 -350.073435)
			(xy 61.837918 -350.102904) (xy 61.879113 -350.1386) (xy 61.914807 -350.179796) (xy 61.944274 -350.225653)
			(xy 61.966914 -350.275237) (xy 61.979636 -350.318578) (xy 64.120522 -350.318578) (xy 64.121034 -350.291005)
			(xy 64.128976 -350.236434) (xy 64.144691 -350.183575) (xy 64.167852 -350.133528) (xy 64.197977 -350.087337)
			(xy 64.234438 -350.045965) (xy 64.255142 -350.027748) (xy 64.263241 -350.020128) (xy 64.272604 -349.99999)
			(xy 64.273176 -349.988886) (xy 64.273176 -349.91167) (xy 64.272648 -349.900555) (xy 64.263282 -349.880396)
			(xy 64.255142 -349.872808) (xy 64.23444 -349.854587) (xy 64.197967 -349.813221) (xy 64.167833 -349.767034)
			(xy 64.144665 -349.716988) (xy 64.128947 -349.664126) (xy 64.121007 -349.609552) (xy 64.120522 -349.581978)
			(xy 64.120934 -349.554723) (xy 64.128695 -349.500769) (xy 64.144056 -349.448468) (xy 64.166703 -349.398886)
			(xy 64.196176 -349.353031) (xy 64.231875 -349.311838) (xy 64.273073 -349.276145) (xy 64.318932 -349.246678)
			(xy 64.368517 -349.224037) (xy 64.42082 -349.208684) (xy 64.474775 -349.200931) (xy 64.50203 -349.20047)
			(xy 64.53632 -349.201994) (xy 64.54648 -349.20301) (xy 64.565784 -349.196914) (xy 64.636396 -349.137732)
			(xy 64.645794 -349.119698) (xy 64.64681 -349.109538) (xy 64.649725 -349.08136) (xy 64.662903 -349.026266)
			(xy 64.684085 -348.973727) (xy 64.712806 -348.924899) (xy 64.748435 -348.880858) (xy 64.790186 -348.842572)
			(xy 64.837142 -348.810883) (xy 64.888269 -348.786489) (xy 64.942443 -348.769927) (xy 64.99847 -348.76156)
			(xy 65.026794 -348.76105) (xy 65.044813 -348.761277) (xy 65.080688 -348.764707) (xy 65.098422 -348.767908)
			(xy 65.10782 -348.769686) (xy 65.12687 -348.765876) (xy 65.202054 -348.718124) (xy 65.213484 -348.702376)
			(xy 65.21577 -348.692978) (xy 65.223225 -348.665951) (xy 65.244848 -348.614227) (xy 65.273805 -348.566223)
			(xy 65.309473 -348.522971) (xy 65.351085 -348.485403) (xy 65.397745 -348.454326) (xy 65.448449 -348.43041)
			(xy 65.502107 -348.414169) (xy 65.557563 -348.405952) (xy 65.585594 -348.40545) (xy 65.612843 -348.405983)
			(xy 65.666787 -348.413738) (xy 65.719078 -348.42909) (xy 65.768653 -348.451727) (xy 65.814501 -348.481189)
			(xy 65.85569 -348.516876) (xy 65.891382 -348.55806) (xy 65.92085 -348.603905) (xy 65.943493 -348.653477)
			(xy 65.958852 -348.705766) (xy 65.966613 -348.759709) (xy 65.967102 -348.786958) (xy 65.966607 -348.814531)
			(xy 65.95866 -348.869103) (xy 65.942941 -348.921962) (xy 65.919776 -348.972008) (xy 65.889649 -349.018199)
			(xy 65.853187 -349.059571) (xy 65.832482 -349.077788) (xy 65.824371 -349.085397) (xy 65.815013 -349.105544)
			(xy 65.814448 -349.11665) (xy 65.814448 -349.193866) (xy 65.815004 -349.204978) (xy 65.824349 -349.225137)
			(xy 65.832482 -349.232728) (xy 65.853146 -349.250989) (xy 65.889611 -349.292354) (xy 65.91974 -349.338538)
			(xy 65.942905 -349.388579) (xy 65.958623 -349.441434) (xy 65.966567 -349.496001) (xy 65.966571 -349.551144)
			(xy 65.958635 -349.605713) (xy 65.942924 -349.65857) (xy 65.919767 -349.708615) (xy 65.889644 -349.754803)
			(xy 65.853185 -349.796173) (xy 65.832482 -349.814388) (xy 65.824371 -349.821997) (xy 65.815013 -349.842144)
			(xy 65.814448 -349.85325) (xy 65.814448 -349.930466) (xy 65.815004 -349.941578) (xy 65.824349 -349.961737)
			(xy 65.832482 -349.969328) (xy 65.853206 -349.987525) (xy 65.889676 -350.028896) (xy 65.919807 -350.075089)
			(xy 65.942971 -350.12514) (xy 65.958684 -350.178005) (xy 65.966619 -350.232582) (xy 65.967102 -350.260158)
			(xy 65.966606 -350.28741) (xy 65.958854 -350.34136) (xy 65.943503 -350.393658) (xy 65.920865 -350.443238)
			(xy 65.891401 -350.489092) (xy 65.855711 -350.530285) (xy 65.814521 -350.565979) (xy 65.76867 -350.595448)
			(xy 65.719092 -350.618091) (xy 65.666795 -350.633447) (xy 65.612846 -350.641203) (xy 65.585594 -350.641666)
			(xy 65.557737 -350.641174) (xy 65.502619 -350.633048) (xy 65.449267 -350.617) (xy 65.398813 -350.59337)
			(xy 65.352327 -350.56266) (xy 65.310798 -350.52552) (xy 65.275106 -350.482741) (xy 65.246009 -350.435229)
			(xy 65.224124 -350.383993) (xy 65.216532 -350.357186) (xy 65.214246 -350.348296) (xy 65.203578 -350.333056)
			(xy 65.131696 -350.285304) (xy 65.113662 -350.28124) (xy 65.104518 -350.28251) (xy 65.091501 -350.284175)
			(xy 65.065317 -350.285958) (xy 65.052194 -350.286066) (xy 65.038045 -350.285973) (xy 65.009822 -350.283938)
			(xy 64.995806 -350.282002) (xy 64.985646 -350.280478) (xy 64.966088 -350.285304) (xy 64.891666 -350.341184)
			(xy 64.881506 -350.35871) (xy 64.880236 -350.36887) (xy 64.87615 -350.396023) (xy 64.861174 -350.448852)
			(xy 64.838781 -350.498989) (xy 64.809432 -350.545399) (xy 64.773735 -350.587122) (xy 64.732425 -350.623298)
			(xy 64.686357 -350.653179) (xy 64.636481 -350.676149) (xy 64.583828 -350.691732) (xy 64.529485 -350.699607)
			(xy 64.50203 -350.700086) (xy 64.474777 -350.699617) (xy 64.420825 -350.691863) (xy 64.368526 -350.67651)
			(xy 64.318944 -350.653869) (xy 64.27309 -350.624402) (xy 64.231897 -350.588709) (xy 64.196202 -350.547516)
			(xy 64.166735 -350.501663) (xy 64.144093 -350.452082) (xy 64.128738 -350.399783) (xy 64.120984 -350.345831)
			(xy 64.120522 -350.318578) (xy 61.979636 -350.318578) (xy 61.982266 -350.327539) (xy 61.990018 -350.381494)
			(xy 61.990478 -350.408748) (xy 61.989825 -350.440311) (xy 61.979435 -350.502577) (xy 61.958947 -350.562286)
			(xy 61.944504 -350.590358) (xy 61.939678 -350.599248) (xy 61.937646 -350.618806) (xy 61.9633 -350.706944)
			(xy 61.975746 -350.722438) (xy 61.984636 -350.727518) (xy 62.009715 -350.742104) (xy 62.0556 -350.777599)
			(xy 62.095578 -350.819635) (xy 62.128727 -350.867242) (xy 62.154282 -350.919322) (xy 62.171652 -350.974672)
			(xy 62.180437 -351.032014) (xy 62.180978 -351.06102) (xy 62.180492 -351.088271) (xy 62.172736 -351.142219)
			(xy 62.157381 -351.194514) (xy 62.134739 -351.244091) (xy 62.105273 -351.289941) (xy 62.069582 -351.331132)
			(xy 62.028391 -351.366823) (xy 61.982541 -351.396289) (xy 61.932964 -351.418931) (xy 61.880669 -351.434286)
			(xy 61.826721 -351.442042) (xy 61.772219 -351.442042) (xy 61.718271 -351.434286) (xy 61.665976 -351.418931)
			(xy 61.616399 -351.396289) (xy 61.570549 -351.366823) (xy 61.529358 -351.331132) (xy 61.493667 -351.289941)
			(xy 61.464201 -351.244091) (xy 61.441559 -351.194514) (xy 61.426204 -351.142219) (xy 61.418448 -351.088271)
			(xy 61.417962 -351.06102) (xy 61.41861 -351.029457) (xy 61.429003 -350.967191) (xy 61.449493 -350.907483)
			(xy 61.463936 -350.87941) (xy 61.468762 -350.87052) (xy 61.470794 -350.850962) (xy 61.44514 -350.762824)
			(xy 61.432694 -350.74733) (xy 61.423804 -350.74225) (xy 61.416438 -350.738186) (xy 61.406786 -350.732344)
			(xy 61.384688 -350.730312) (xy 61.2902 -350.76384) (xy 61.274198 -350.779334) (xy 61.270134 -350.789748)
			(xy 61.259452 -350.81653) (xy 61.23116 -350.86677) (xy 61.195627 -350.912178) (xy 61.153663 -350.951719)
			(xy 61.106224 -350.984492) (xy 61.054392 -351.009749) (xy 60.999348 -351.026915) (xy 60.942347 -351.035598)
			(xy 60.913518 -351.036128) (xy 60.886266 -351.035626) (xy 60.832316 -351.027871) (xy 60.780018 -351.012518)
			(xy 60.730439 -350.989878) (xy 60.684586 -350.960412) (xy 60.643393 -350.92472) (xy 60.607699 -350.883529)
			(xy 60.578231 -350.837677) (xy 60.555589 -350.788098) (xy 60.540232 -350.735802) (xy 60.532475 -350.681852)
			(xy 60.264065 -350.681852) (xy 60.243684 -350.726018) (xy 60.213734 -350.772088) (xy 60.195968 -350.79305)
			(xy 60.189872 -350.800162) (xy 60.183522 -350.81718) (xy 60.183522 -350.903032) (xy 60.189872 -350.92005)
			(xy 60.195968 -350.927162) (xy 60.213706 -350.948145) (xy 60.243632 -350.994222) (xy 60.266649 -351.044111)
			(xy 60.282281 -351.096783) (xy 60.290206 -351.151151) (xy 60.29071 -351.178622) (xy 60.290224 -351.205873)
			(xy 60.282468 -351.259821) (xy 60.267113 -351.312116) (xy 60.244471 -351.361693) (xy 60.215005 -351.407543)
			(xy 60.179314 -351.448734) (xy 60.138123 -351.484425) (xy 60.092273 -351.513891) (xy 60.042696 -351.536533)
			(xy 59.990401 -351.551888) (xy 59.936453 -351.559644) (xy 59.881951 -351.559644) (xy 59.828003 -351.551888)
			(xy 59.775708 -351.536533) (xy 59.726131 -351.513891) (xy 59.680281 -351.484425) (xy 59.63909 -351.448734)
			(xy 59.603399 -351.407543) (xy 59.573933 -351.361693) (xy 59.551291 -351.312116) (xy 59.535936 -351.259821)
			(xy 59.52818 -351.205873) (xy 59.527694 -351.178622) (xy 53.830847 -351.178622) (xy 53.826181 -351.194514)
			(xy 53.803539 -351.244091) (xy 53.774073 -351.289941) (xy 53.738382 -351.331132) (xy 53.697191 -351.366823)
			(xy 53.651341 -351.396289) (xy 53.601764 -351.418931) (xy 53.549469 -351.434286) (xy 53.495521 -351.442042)
			(xy 53.441019 -351.442042) (xy 53.387071 -351.434286) (xy 53.334776 -351.418931) (xy 53.285199 -351.396289)
			(xy 53.239349 -351.366823) (xy 53.198158 -351.331132) (xy 53.162467 -351.289941) (xy 53.133001 -351.244091)
			(xy 53.110359 -351.194514) (xy 53.095004 -351.142219) (xy 53.087248 -351.088271) (xy 53.086762 -351.06102)
			(xy 53.08741 -351.029457) (xy 53.097803 -350.967191) (xy 53.118293 -350.907483) (xy 53.132736 -350.87941)
			(xy 53.137562 -350.87052) (xy 53.139594 -350.850962) (xy 53.11394 -350.762824) (xy 53.101494 -350.74733)
			(xy 53.092604 -350.74225) (xy 53.085238 -350.738186) (xy 53.075586 -350.732344) (xy 53.053488 -350.730312)
			(xy 52.959 -350.76384) (xy 52.942998 -350.779334) (xy 52.938934 -350.789748) (xy 52.928252 -350.81653)
			(xy 52.89996 -350.86677) (xy 52.864427 -350.912178) (xy 52.822463 -350.951719) (xy 52.775024 -350.984492)
			(xy 52.723192 -351.009749) (xy 52.668148 -351.026915) (xy 52.611147 -351.035598) (xy 52.582318 -351.036128)
			(xy 52.555066 -351.035626) (xy 52.501116 -351.027871) (xy 52.448818 -351.012518) (xy 52.399239 -350.989878)
			(xy 52.353386 -350.960412) (xy 52.312193 -350.92472) (xy 52.276499 -350.883529) (xy 52.247031 -350.837677)
			(xy 52.224389 -350.788098) (xy 52.209032 -350.735802) (xy 52.201275 -350.681852) (xy 51.932865 -350.681852)
			(xy 51.912484 -350.726018) (xy 51.882534 -350.772088) (xy 51.864768 -350.79305) (xy 51.858672 -350.800162)
			(xy 51.852322 -350.81718) (xy 51.852322 -350.903032) (xy 51.858672 -350.92005) (xy 51.864768 -350.927162)
			(xy 51.882506 -350.948145) (xy 51.912432 -350.994222) (xy 51.935449 -351.044111) (xy 51.951081 -351.096783)
			(xy 51.959006 -351.151151) (xy 51.95951 -351.178622) (xy 51.959038 -351.205468) (xy 51.951533 -351.258632)
			(xy 51.936645 -351.310219) (xy 51.914669 -351.359207) (xy 51.886039 -351.404629) (xy 51.851322 -351.445586)
			(xy 51.811204 -351.481269) (xy 51.766477 -351.510973) (xy 51.718027 -351.534111) (xy 51.692556 -351.542604)
			(xy 51.676808 -351.54743) (xy 51.656996 -351.574354) (xy 51.656996 -352.339402) (xy 51.656354 -352.364384)
			(xy 51.646618 -352.41339) (xy 51.627519 -352.459559) (xy 51.599791 -352.501122) (xy 51.582574 -352.519234)
			(xy 50.790094 -353.311714) (xy 50.771994 -353.328947) (xy 50.730432 -353.356688) (xy 50.684259 -353.375793)
			(xy 50.635247 -353.385529) (xy 50.610262 -353.386136) (xy 38.566598 -353.386136) (xy 38.556527 -353.386551)
			(xy 38.537929 -353.394278) (xy 38.53053 -353.401122) (xy 35.544252 -356.387654) (xy 35.538156 -356.417372)
			(xy 35.544252 -356.43185) (xy 35.548466 -356.44091) (xy 35.562561 -356.455048) (xy 35.581006 -356.462685)
			(xy 35.590988 -356.463092) (xy 36.170108 -356.463092) (xy 36.180151 -356.462703) (xy 36.198747 -356.455128)
			(xy 36.206176 -356.44836) (xy 38.962076 -353.69246) (xy 38.980197 -353.675232) (xy 39.021732 -353.647414)
			(xy 39.067896 -353.628233) (xy 39.116914 -353.618425) (xy 39.141908 -353.617784) (xy 65.467738 -353.617784)
			(xy 65.477783 -353.617413) (xy 65.496379 -353.609825) (xy 65.503806 -353.603052) (xy 78.190852 -340.916006)
			(xy 78.208978 -340.898802) (xy 78.250531 -340.871055) (xy 78.296696 -340.851942) (xy 78.345701 -340.842197)
			(xy 78.370684 -340.841584) (xy 92.212668 -340.841584) (xy 92.222736 -340.841146) (xy 92.241334 -340.833435)
			(xy 92.248736 -340.826598) (xy 92.634562 -340.440772) (xy 92.641401 -340.433371) (xy 92.649123 -340.414773)
			(xy 92.649548 -340.404704) (xy 92.649548 -339.134196) (xy 92.650176 -339.109213) (xy 92.659914 -339.060206)
			(xy 92.679017 -339.014036) (xy 92.706751 -338.972475) (xy 92.72397 -338.954364) (xy 93.00845 -338.669884)
			(xy 93.026528 -338.652609) (xy 93.068079 -338.624803) (xy 93.114256 -338.605635) (xy 93.163284 -338.595842)
			(xy 93.188282 -338.595208) (xy 93.203776 -338.595208) (xy 93.221936 -338.575583) (xy 93.262822 -338.541126)
			(xy 93.308118 -338.512714) (xy 93.356936 -338.490903) (xy 93.408322 -338.476121) (xy 93.461267 -338.468657)
			(xy 93.488002 -338.468208) (xy 93.515256 -338.468654) (xy 93.569208 -338.476411) (xy 93.621507 -338.491768)
			(xy 93.671088 -338.514412) (xy 93.716942 -338.543882) (xy 93.758135 -338.579577) (xy 93.793829 -338.620772)
			(xy 93.823296 -338.666627) (xy 93.845938 -338.71621) (xy 93.861293 -338.76851) (xy 93.869048 -338.822462)
			(xy 93.86951 -338.849716) (xy 93.869031 -338.877191) (xy 93.861137 -338.931571) (xy 93.845515 -338.984253)
			(xy 93.842886 -338.98995) (xy 94.111301 -338.98995) (xy 94.111301 -338.93545) (xy 94.119058 -338.881504)
			(xy 94.134413 -338.829211) (xy 94.157054 -338.779635) (xy 94.18652 -338.733787) (xy 94.222211 -338.692599)
			(xy 94.263401 -338.656909) (xy 94.309251 -338.627445) (xy 94.358828 -338.604807) (xy 94.411121 -338.589454)
			(xy 94.465068 -338.5817) (xy 94.492318 -338.581238) (xy 94.517553 -338.581635) (xy 94.567587 -338.588255)
			(xy 94.616307 -338.601428) (xy 94.662859 -338.620924) (xy 94.68485 -338.633308) (xy 94.694502 -338.63915)
			(xy 94.7166 -338.641182) (xy 94.811088 -338.607654) (xy 94.82709 -338.59216) (xy 94.831154 -338.581746)
			(xy 94.841843 -338.554967) (xy 94.870134 -338.504728) (xy 94.905667 -338.45932) (xy 94.94763 -338.419779)
			(xy 94.995068 -338.387006) (xy 95.046899 -338.361748) (xy 95.101941 -338.344582) (xy 95.158941 -338.335897)
			(xy 95.18777 -338.335366) (xy 95.215021 -338.335883) (xy 95.268969 -338.343635) (xy 95.321264 -338.358986)
			(xy 95.370842 -338.381623) (xy 95.416694 -338.411086) (xy 95.457886 -338.446774) (xy 95.493581 -338.487961)
			(xy 95.52305 -338.533809) (xy 95.545694 -338.583384) (xy 95.558418 -338.626704) (xy 97.699322 -338.626704)
			(xy 97.699783 -338.599129) (xy 97.707735 -338.544556) (xy 97.723461 -338.491695) (xy 97.746632 -338.441649)
			(xy 97.776765 -338.39546) (xy 97.813234 -338.354089) (xy 97.833942 -338.335874) (xy 97.842074 -338.328284)
			(xy 97.851419 -338.308123) (xy 97.851976 -338.297012) (xy 97.851976 -338.219796) (xy 97.851434 -338.208683)
			(xy 97.842078 -338.188524) (xy 97.833942 -338.180934) (xy 97.813252 -338.162699) (xy 97.776779 -338.121336)
			(xy 97.746643 -338.075152) (xy 97.723473 -338.025108) (xy 97.707752 -337.972249) (xy 97.699809 -337.917678)
			(xy 97.699322 -337.890104) (xy 97.699759 -337.86285) (xy 97.707516 -337.808896) (xy 97.722873 -337.756596)
			(xy 97.745518 -337.707014) (xy 97.774988 -337.66116) (xy 97.810685 -337.619966) (xy 97.85188 -337.584272)
			(xy 97.897737 -337.554805) (xy 97.947321 -337.532164) (xy 97.999622 -337.516811) (xy 98.053576 -337.509057)
			(xy 98.08083 -337.508596) (xy 98.11512 -337.51012) (xy 98.12528 -337.511136) (xy 98.144584 -337.50504)
			(xy 98.215196 -337.445858) (xy 98.224594 -337.427824) (xy 98.22561 -337.417664) (xy 98.228547 -337.389489)
			(xy 98.241721 -337.334395) (xy 98.2629 -337.281856) (xy 98.291618 -337.233028) (xy 98.327244 -337.188986)
			(xy 98.368993 -337.150699) (xy 98.415947 -337.11901) (xy 98.467073 -337.094615) (xy 98.521244 -337.078053)
			(xy 98.57727 -337.069686) (xy 98.605594 -337.069176) (xy 98.632844 -337.069683) (xy 98.686791 -337.077439)
			(xy 98.739084 -337.092792) (xy 98.78866 -337.115431) (xy 98.83451 -337.144896) (xy 98.8757 -337.180585)
			(xy 98.911391 -337.221773) (xy 98.940858 -337.267621) (xy 98.9635 -337.317195) (xy 98.978857 -337.369488)
			(xy 98.986615 -337.423434) (xy 98.987102 -337.450684) (xy 98.986613 -337.478546) (xy 98.978512 -337.533679)
			(xy 98.962482 -337.587049) (xy 98.938862 -337.63752) (xy 98.908154 -337.68402) (xy 98.871012 -337.725562)
			(xy 98.849942 -337.7438) (xy 98.840798 -337.75142) (xy 98.831146 -337.772502) (xy 98.834702 -337.876388)
			(xy 98.845624 -337.896962) (xy 98.855276 -337.904074) (xy 98.875807 -337.919521) (xy 98.91294 -337.95503)
			(xy 98.944972 -337.995202) (xy 98.971323 -338.039309) (xy 98.991515 -338.086554) (xy 99.005184 -338.136081)
			(xy 99.012082 -338.186995) (xy 99.012502 -338.212684) (xy 99.011987 -338.242127) (xy 99.002939 -338.300314)
			(xy 98.985057 -338.356419) (xy 98.958764 -338.409109) (xy 98.924687 -338.457133) (xy 98.904552 -338.478622)
			(xy 98.895916 -338.487258) (xy 98.888804 -338.509864) (xy 98.904806 -338.614004) (xy 98.918522 -338.633308)
			(xy 98.928936 -338.638896) (xy 98.954506 -338.6533) (xy 99.001281 -338.688741) (xy 99.042078 -338.730927)
			(xy 99.075934 -338.778862) (xy 99.102052 -338.831415) (xy 99.119814 -338.887348) (xy 99.128803 -338.945341)
			(xy 99.129342 -338.974684) (xy 99.128834 -339.003602) (xy 99.120106 -339.060774) (xy 99.102848 -339.115974)
			(xy 99.077454 -339.167936) (xy 99.044508 -339.21547) (xy 99.004763 -339.257485) (xy 98.982276 -339.275674)
			(xy 98.973526 -339.283247) (xy 98.963337 -339.303998) (xy 98.962718 -339.315552) (xy 98.962718 -339.395816)
			(xy 98.963273 -339.407386) (xy 98.973478 -339.428157) (xy 98.982276 -339.435694) (xy 99.004752 -339.453894)
			(xy 99.044488 -339.495912) (xy 99.077429 -339.543444) (xy 99.102819 -339.595404) (xy 99.120077 -339.6506)
			(xy 99.128807 -339.707768) (xy 99.129342 -339.736684) (xy 99.128807 -339.763933) (xy 99.121054 -339.817877)
			(xy 99.105702 -339.870169) (xy 99.083065 -339.919744) (xy 99.053604 -339.965593) (xy 99.017918 -340.006782)
			(xy 98.976733 -340.042474) (xy 98.930888 -340.071941) (xy 98.881316 -340.094585) (xy 98.829026 -340.109943)
			(xy 98.775083 -340.117703) (xy 98.747834 -340.118192) (xy 98.718894 -340.117667) (xy 98.661681 -340.108901)
			(xy 98.606448 -340.091596) (xy 98.554462 -340.066148) (xy 98.506915 -340.033142) (xy 98.464898 -339.993334)
			(xy 98.429374 -339.947637) (xy 98.401158 -339.897099) (xy 98.380898 -339.842881) (xy 98.374454 -339.814662)
			(xy 98.372422 -339.80501) (xy 98.361754 -339.788754) (xy 98.287586 -339.7377) (xy 98.26879 -339.733382)
			(xy 98.258884 -339.734906) (xy 98.244063 -339.737147) (xy 98.214183 -339.73956) (xy 98.199194 -339.739732)
			(xy 98.171944 -339.739228) (xy 98.117998 -339.731471) (xy 98.065705 -339.716116) (xy 98.016129 -339.693476)
			(xy 97.97028 -339.664012) (xy 97.929091 -339.628322) (xy 97.893399 -339.587134) (xy 97.863932 -339.541287)
			(xy 97.84129 -339.491712) (xy 97.825933 -339.43942) (xy 97.818173 -339.385474) (xy 97.817686 -339.358224)
			(xy 97.818159 -339.330984) (xy 97.825925 -339.277061) (xy 97.841289 -339.224793) (xy 97.863937 -339.175245)
			(xy 97.893407 -339.129424) (xy 97.910904 -339.108542) (xy 97.91827 -339.099906) (xy 97.924366 -339.078316)
			(xy 97.908364 -338.979002) (xy 97.895664 -338.96046) (xy 97.886012 -338.954618) (xy 97.862006 -338.939797)
			(xy 97.818266 -338.904163) (xy 97.780254 -338.862474) (xy 97.748798 -338.81564) (xy 97.724585 -338.764683)
			(xy 97.708143 -338.710714) (xy 97.699831 -338.654913) (xy 97.699322 -338.626704) (xy 95.558418 -338.626704)
			(xy 95.561053 -338.635677) (xy 95.568813 -338.689623) (xy 95.569278 -338.716874) (xy 95.568635 -338.748438)
			(xy 95.558241 -338.810703) (xy 95.537749 -338.870412) (xy 95.523304 -338.898484) (xy 95.518478 -338.907374)
			(xy 95.516446 -338.926932) (xy 95.5421 -339.01507) (xy 95.554546 -339.030564) (xy 95.563436 -339.035644)
			(xy 95.588526 -339.050211) (xy 95.634411 -339.085709) (xy 95.674389 -339.127748) (xy 95.707537 -339.175359)
			(xy 95.73309 -339.227442) (xy 95.750457 -339.282794) (xy 95.759239 -339.340139) (xy 95.759778 -339.369146)
			(xy 95.759292 -339.396397) (xy 95.751536 -339.450345) (xy 95.736181 -339.50264) (xy 95.713539 -339.552217)
			(xy 95.684073 -339.598067) (xy 95.648382 -339.639258) (xy 95.607191 -339.674949) (xy 95.561341 -339.704415)
			(xy 95.511764 -339.727057) (xy 95.459469 -339.742412) (xy 95.405521 -339.750168) (xy 95.351019 -339.750168)
			(xy 95.297071 -339.742412) (xy 95.244776 -339.727057) (xy 95.195199 -339.704415) (xy 95.149349 -339.674949)
			(xy 95.108158 -339.639258) (xy 95.072467 -339.598067) (xy 95.043001 -339.552217) (xy 95.020359 -339.50264)
			(xy 95.005004 -339.450345) (xy 94.997248 -339.396397) (xy 94.996762 -339.369146) (xy 94.99742 -339.337583)
			(xy 95.007809 -339.275318) (xy 95.028295 -339.215609) (xy 95.042736 -339.187536) (xy 95.047562 -339.178646)
			(xy 95.049594 -339.159088) (xy 95.02394 -339.07095) (xy 95.011494 -339.055456) (xy 95.002604 -339.050376)
			(xy 94.995238 -339.046312) (xy 94.985586 -339.04047) (xy 94.963488 -339.038438) (xy 94.869 -339.071966)
			(xy 94.852998 -339.08746) (xy 94.848934 -339.097874) (xy 94.838212 -339.12464) (xy 94.80993 -339.174882)
			(xy 94.774404 -339.220293) (xy 94.732447 -339.259837) (xy 94.685013 -339.292613) (xy 94.633185 -339.317872)
			(xy 94.578144 -339.33504) (xy 94.521146 -339.343724) (xy 94.492318 -339.344254) (xy 94.465068 -339.3437)
			(xy 94.411121 -339.335946) (xy 94.358828 -339.320593) (xy 94.309251 -339.297955) (xy 94.263401 -339.268491)
			(xy 94.222211 -339.232801) (xy 94.18652 -339.191613) (xy 94.157054 -339.145765) (xy 94.134413 -339.096189)
			(xy 94.119058 -339.043896) (xy 94.111301 -338.98995) (xy 93.842886 -338.98995) (xy 93.822489 -339.034146)
			(xy 93.792536 -339.080214) (xy 93.774768 -339.101176) (xy 93.768672 -339.108288) (xy 93.762322 -339.125306)
			(xy 93.762322 -339.211158) (xy 93.768672 -339.228176) (xy 93.774768 -339.235288) (xy 93.792518 -339.256261)
			(xy 93.822443 -339.302341) (xy 93.845457 -339.352233) (xy 93.861086 -339.404907) (xy 93.869008 -339.459277)
			(xy 93.86951 -339.486748) (xy 93.869013 -339.515018) (xy 93.860689 -339.570941) (xy 93.8442 -339.625023)
			(xy 93.819909 -339.676078) (xy 93.788346 -339.722988) (xy 93.750205 -339.764724) (xy 93.70632 -339.800373)
			(xy 93.657654 -339.829153) (xy 93.605272 -339.850433) (xy 93.577918 -339.857588) (xy 93.5609 -339.861652)
			(xy 93.539056 -339.889338) (xy 93.539056 -340.709758) (xy 93.53846 -340.734742) (xy 93.528711 -340.783751)
			(xy 93.509599 -340.82992) (xy 93.481857 -340.87148) (xy 93.464634 -340.88959) (xy 92.760038 -341.594186)
			(xy 99.664774 -341.594186) (xy 99.665262 -341.566275) (xy 99.673398 -341.511049) (xy 99.689495 -341.457599)
			(xy 99.713209 -341.407064) (xy 99.744033 -341.360524) (xy 99.76231 -341.339424) (xy 99.76866 -341.332312)
			(xy 99.775264 -341.31504) (xy 99.775264 -341.227918) (xy 99.76866 -341.210646) (xy 99.76231 -341.203534)
			(xy 99.744028 -341.182437) (xy 99.713201 -341.135898) (xy 99.689486 -341.085363) (xy 99.673391 -341.031911)
			(xy 99.665258 -340.976684) (xy 99.664774 -340.948772) (xy 99.66526 -340.921521) (xy 99.673016 -340.867573)
			(xy 99.688371 -340.815278) (xy 99.711013 -340.765701) (xy 99.740479 -340.719851) (xy 99.77617 -340.67866)
			(xy 99.817361 -340.642969) (xy 99.863211 -340.613503) (xy 99.912788 -340.590861) (xy 99.965083 -340.575506)
			(xy 100.019031 -340.56775) (xy 100.073533 -340.56775) (xy 100.127481 -340.575506) (xy 100.179776 -340.590861)
			(xy 100.229353 -340.613503) (xy 100.275203 -340.642969) (xy 100.316394 -340.67866) (xy 100.352085 -340.719851)
			(xy 100.381551 -340.765701) (xy 100.404193 -340.815278) (xy 100.419548 -340.867573) (xy 100.427304 -340.921521)
			(xy 100.42779 -340.948772) (xy 100.42732 -340.976683) (xy 100.419177 -341.031909) (xy 100.403075 -341.08536)
			(xy 100.379358 -341.135894) (xy 100.348531 -341.182434) (xy 100.330254 -341.203534) (xy 100.323904 -341.210646)
			(xy 100.3173 -341.227918) (xy 100.3173 -341.31504) (xy 100.323904 -341.332312) (xy 100.330254 -341.339424)
			(xy 100.348526 -341.360528) (xy 100.379353 -341.407066) (xy 100.403068 -341.4576) (xy 100.419166 -341.51105)
			(xy 100.427303 -341.566275) (xy 100.42779 -341.594186) (xy 100.427304 -341.621437) (xy 100.419548 -341.675385)
			(xy 100.404193 -341.72768) (xy 100.381551 -341.777257) (xy 100.352085 -341.823107) (xy 100.316394 -341.864298)
			(xy 100.275203 -341.899989) (xy 100.232084 -341.9277) (xy 104.047047 -341.9277) (xy 104.051215 -341.872088)
			(xy 104.063623 -341.817718) (xy 104.083996 -341.765805) (xy 104.111879 -341.717508) (xy 104.146648 -341.673905)
			(xy 104.187526 -341.635971) (xy 104.233602 -341.604553) (xy 104.283845 -341.580353) (xy 104.337134 -341.56391)
			(xy 104.392278 -341.555594) (xy 104.420162 -341.55507) (xy 104.446585 -341.555499) (xy 104.498901 -341.562957)
			(xy 104.54964 -341.577729) (xy 104.597784 -341.599519) (xy 104.642367 -341.62789) (xy 104.662732 -341.644732)
			(xy 104.66959 -341.650828) (xy 104.686608 -341.656924) (xy 104.770936 -341.656924) (xy 104.787954 -341.650828)
			(xy 104.794812 -341.644732) (xy 104.815178 -341.627893) (xy 104.859764 -341.599528) (xy 104.907908 -341.577741)
			(xy 104.958645 -341.56297) (xy 105.01096 -341.55551) (xy 105.063804 -341.55551) (xy 105.116119 -341.56297)
			(xy 105.166856 -341.577741) (xy 105.215 -341.599528) (xy 105.259586 -341.627893) (xy 105.279952 -341.644732)
			(xy 105.28681 -341.650828) (xy 105.303828 -341.656924) (xy 105.388156 -341.656924) (xy 105.405174 -341.650828)
			(xy 105.412032 -341.644732) (xy 105.432821 -341.627549) (xy 105.478409 -341.598732) (xy 105.527679 -341.576798)
			(xy 105.55351 -341.56904) (xy 105.565194 -341.565738) (xy 105.582466 -341.550244) (xy 105.621328 -341.452962)
			(xy 105.61955 -341.429848) (xy 105.613454 -341.419434) (xy 105.601097 -341.397777) (xy 105.581621 -341.351876)
			(xy 105.568438 -341.303789) (xy 105.561785 -341.254373) (xy 105.561384 -341.229442) (xy 105.56189 -341.201818)
			(xy 105.570048 -341.147177) (xy 105.586191 -341.094341) (xy 105.609965 -341.04447) (xy 105.640848 -340.998661)
			(xy 105.67816 -340.957918) (xy 105.699306 -340.940136) (xy 105.707845 -340.932545) (xy 105.717636 -340.911927)
			(xy 105.718102 -340.900512) (xy 105.718102 -340.821772) (xy 105.717474 -340.810391) (xy 105.707733 -340.78982)
			(xy 105.699306 -340.782148) (xy 105.678176 -340.764349) (xy 105.640865 -340.723607) (xy 105.609983 -340.6778)
			(xy 105.586206 -340.627934) (xy 105.570057 -340.575102) (xy 105.561889 -340.520464) (xy 105.561384 -340.492842)
			(xy 105.561905 -340.464957) (xy 105.570217 -340.40981) (xy 105.586655 -340.356518) (xy 105.610853 -340.306272)
			(xy 105.642269 -340.260193) (xy 105.680202 -340.219311) (xy 105.723804 -340.184539) (xy 105.772102 -340.156654)
			(xy 105.824017 -340.136279) (xy 105.878388 -340.123869) (xy 105.934002 -340.119702) (xy 105.989616 -340.123869)
			(xy 106.043987 -340.136279) (xy 106.095902 -340.156654) (xy 106.1442 -340.184539) (xy 106.187802 -340.219311)
			(xy 106.225735 -340.260193) (xy 106.257151 -340.306272) (xy 106.281349 -340.356518) (xy 106.297787 -340.40981)
			(xy 106.306099 -340.464957) (xy 106.30662 -340.492842) (xy 106.306101 -340.520465) (xy 106.297945 -340.575106)
			(xy 106.281805 -340.627942) (xy 106.258033 -340.677812) (xy 106.227153 -340.723622) (xy 106.189842 -340.764366)
			(xy 106.168698 -340.782148) (xy 106.160121 -340.789704) (xy 106.150351 -340.810348) (xy 106.149902 -340.821772)
			(xy 106.149902 -340.900512) (xy 106.150537 -340.911892) (xy 106.160273 -340.932463) (xy 106.168698 -340.940136)
			(xy 106.189821 -340.957942) (xy 106.227132 -340.998683) (xy 106.258015 -341.044488) (xy 106.281793 -341.094353)
			(xy 106.297944 -341.147183) (xy 106.306113 -341.20182) (xy 106.30662 -341.229442) (xy 106.306104 -341.256283)
			(xy 106.298407 -341.30941) (xy 106.283166 -341.360883) (xy 106.260695 -341.409636) (xy 106.23146 -341.454658)
			(xy 106.196065 -341.495019) (xy 106.155245 -341.529882) (xy 106.109843 -341.558525) (xy 106.060801 -341.580356)
			(xy 106.035094 -341.58809) (xy 106.02341 -341.591392) (xy 106.006138 -341.606886) (xy 105.967276 -341.704168)
			(xy 105.969054 -341.727282) (xy 105.97515 -341.737696) (xy 105.98752 -341.759346) (xy 106.006992 -341.805249)
			(xy 106.020171 -341.853339) (xy 106.026821 -341.902757) (xy 106.02722 -341.927688) (xy 106.026755 -341.954305)
			(xy 106.01918 -342.006999) (xy 106.004184 -342.058078) (xy 105.98207 -342.106502) (xy 105.95329 -342.151287)
			(xy 105.91843 -342.19152) (xy 105.878198 -342.226382) (xy 105.833415 -342.255163) (xy 105.784991 -342.277279)
			(xy 105.733912 -342.292277) (xy 105.681219 -342.299854) (xy 105.654602 -342.300306) (xy 105.62818 -342.299846)
			(xy 105.575865 -342.292396) (xy 105.525127 -342.277632) (xy 105.476982 -342.255848) (xy 105.432397 -342.227483)
			(xy 105.412032 -342.210644) (xy 105.405174 -342.204548) (xy 105.388156 -342.198452) (xy 105.303828 -342.198452)
			(xy 105.28681 -342.204548) (xy 105.279952 -342.210644) (xy 105.259586 -342.227483) (xy 105.215 -342.255848)
			(xy 105.166856 -342.277635) (xy 105.116119 -342.292406) (xy 105.063804 -342.299866) (xy 105.01096 -342.299866)
			(xy 104.958645 -342.292406) (xy 104.907908 -342.277635) (xy 104.859764 -342.255848) (xy 104.815178 -342.227483)
			(xy 104.794812 -342.210644) (xy 104.787954 -342.204548) (xy 104.770936 -342.198452) (xy 104.686608 -342.198452)
			(xy 104.66959 -342.204548) (xy 104.662732 -342.210644) (xy 104.642348 -342.227458) (xy 104.597764 -342.255819)
			(xy 104.549624 -342.277604) (xy 104.498891 -342.292377) (xy 104.446582 -342.299842) (xy 104.420162 -342.300306)
			(xy 104.392278 -342.299806) (xy 104.337134 -342.29149) (xy 104.283845 -342.275047) (xy 104.233602 -342.250847)
			(xy 104.187526 -342.219429) (xy 104.146648 -342.181495) (xy 104.111879 -342.137892) (xy 104.083996 -342.089595)
			(xy 104.063623 -342.037682) (xy 104.051215 -341.983312) (xy 104.047047 -341.9277) (xy 100.232084 -341.9277)
			(xy 100.229353 -341.929455) (xy 100.179776 -341.952097) (xy 100.127481 -341.967452) (xy 100.073533 -341.975208)
			(xy 100.019031 -341.975208) (xy 99.965083 -341.967452) (xy 99.912788 -341.952097) (xy 99.863211 -341.929455)
			(xy 99.817361 -341.899989) (xy 99.77617 -341.864298) (xy 99.740479 -341.823107) (xy 99.711013 -341.777257)
			(xy 99.688371 -341.72768) (xy 99.673016 -341.675385) (xy 99.66526 -341.621437) (xy 99.664774 -341.594186)
			(xy 92.760038 -341.594186) (xy 92.697554 -341.65667) (xy 92.679437 -341.673884) (xy 92.63788 -341.701626)
			(xy 92.591712 -341.720735) (xy 92.542705 -341.730479) (xy 92.517722 -341.731092) (xy 78.655164 -341.731092)
			(xy 78.645089 -341.731474) (xy 78.626491 -341.739223) (xy 78.619096 -341.746078) (xy 65.93205 -354.433124)
			(xy 65.913973 -354.450401) (xy 65.872421 -354.478206) (xy 65.826244 -354.497373) (xy 65.777216 -354.507166)
			(xy 65.752218 -354.5078) (xy 39.426388 -354.5078) (xy 39.416341 -354.508163) (xy 39.397744 -354.515754)
			(xy 39.39032 -354.522532) (xy 36.92144 -356.991412) (xy 36.914751 -356.998896) (xy 36.907158 -357.017453)
			(xy 36.906708 -357.02748) (xy 36.906708 -357.611172) (xy 36.906297 -357.633295) (xy 36.899899 -357.677076)
			(xy 36.887234 -357.719471) (xy 36.87826 -357.739696) (xy 36.871402 -357.754428) (xy 36.876736 -357.785416)
			(xy 36.888166 -357.796846) (xy 36.8956 -357.803562) (xy 36.9141 -357.811198) (xy 36.934114 -357.811198)
			(xy 36.952614 -357.803562) (xy 36.960048 -357.796846) (xy 39.784782 -354.972366) (xy 39.802889 -354.955141)
			(xy 39.844449 -354.927399) (xy 39.89062 -354.908293) (xy 39.93963 -354.898554) (xy 39.964614 -354.897944)
			(xy 66.12001 -354.897944) (xy 66.130082 -354.897539) (xy 66.14868 -354.889806) (xy 66.156078 -354.882958)
			(xy 78.55839 -342.480646) (xy 78.576491 -342.463414) (xy 78.618053 -342.435675) (xy 78.664226 -342.41657)
			(xy 78.713237 -342.406833) (xy 78.738222 -342.406224) (xy 96.518222 -342.406224) (xy 96.543205 -342.406848)
			(xy 96.592212 -342.416589) (xy 96.638381 -342.435692) (xy 96.679943 -342.463427) (xy 96.698054 -342.480646)
			(xy 97.04324 -342.825832) (xy 100.622606 -342.825832) (xy 100.626677 -342.77021) (xy 100.638803 -342.715773)
			(xy 100.658726 -342.663682) (xy 100.686022 -342.615047) (xy 100.720108 -342.570904) (xy 100.760257 -342.532195)
			(xy 100.805615 -342.499744) (xy 100.855215 -342.474243) (xy 100.907999 -342.456236) (xy 100.962842 -342.446106)
			(xy 101.018576 -342.444069) (xy 101.074013 -342.450169) (xy 101.12797 -342.464275) (xy 101.179299 -342.486087)
			(xy 101.226905 -342.515141) (xy 101.269773 -342.550816) (xy 101.30699 -342.592353) (xy 101.337763 -342.638866)
			(xy 101.361435 -342.689363) (xy 101.377503 -342.74277) (xy 101.385623 -342.797946) (xy 101.386132 -342.825832)
			(xy 101.385623 -342.853718) (xy 101.377503 -342.908894) (xy 101.361435 -342.962301) (xy 101.337763 -343.012798)
			(xy 101.30699 -343.059311) (xy 101.269773 -343.100848) (xy 101.226905 -343.136523) (xy 101.179299 -343.165577)
			(xy 101.12797 -343.187389) (xy 101.074013 -343.201495) (xy 101.018576 -343.207595) (xy 100.962842 -343.205558)
			(xy 100.907999 -343.195428) (xy 100.855215 -343.177421) (xy 100.805615 -343.15192) (xy 100.760257 -343.119469)
			(xy 100.720108 -343.08076) (xy 100.686022 -343.036617) (xy 100.658726 -342.987982) (xy 100.638803 -342.935891)
			(xy 100.626677 -342.881454) (xy 100.622606 -342.825832) (xy 97.04324 -342.825832) (xy 97.93859 -343.721182)
			(xy 100.043486 -343.721182) (xy 100.047557 -343.66556) (xy 100.059683 -343.611123) (xy 100.079606 -343.559032)
			(xy 100.106902 -343.510397) (xy 100.140988 -343.466254) (xy 100.181137 -343.427545) (xy 100.226495 -343.395094)
			(xy 100.276095 -343.369593) (xy 100.328879 -343.351586) (xy 100.383722 -343.341456) (xy 100.439456 -343.339419)
			(xy 100.494893 -343.345519) (xy 100.54885 -343.359625) (xy 100.600179 -343.381437) (xy 100.647785 -343.410491)
			(xy 100.690653 -343.446166) (xy 100.72787 -343.487703) (xy 100.758643 -343.534216) (xy 100.782315 -343.584713)
			(xy 100.798383 -343.63812) (xy 100.806503 -343.693296) (xy 100.807012 -343.721182) (xy 100.806503 -343.749068)
			(xy 100.798383 -343.804244) (xy 100.782315 -343.857651) (xy 100.758643 -343.908148) (xy 100.72787 -343.954661)
			(xy 100.690653 -343.996198) (xy 100.647785 -344.031873) (xy 100.600179 -344.060927) (xy 100.54885 -344.082739)
			(xy 100.494893 -344.096845) (xy 100.439456 -344.102945) (xy 100.383722 -344.100908) (xy 100.328879 -344.090778)
			(xy 100.276095 -344.072771) (xy 100.226495 -344.04727) (xy 100.181137 -344.014819) (xy 100.140988 -343.97611)
			(xy 100.106902 -343.931967) (xy 100.079606 -343.883332) (xy 100.059683 -343.831241) (xy 100.047557 -343.776804)
			(xy 100.043486 -343.721182) (xy 97.93859 -343.721182) (xy 99.834446 -345.617038) (xy 99.841905 -345.623794)
			(xy 99.860464 -345.631517) (xy 99.870514 -345.632024) (xy 100.55225 -345.632024) (xy 100.562319 -345.631592)
			(xy 100.580918 -345.623878) (xy 100.588318 -345.617038) (xy 100.977954 -345.227402) (xy 100.984779 -345.21999)
			(xy 100.992509 -345.2014) (xy 100.99294 -345.191334) (xy 100.99294 -344.171778) (xy 100.993559 -344.146795)
			(xy 101.003301 -344.097787) (xy 101.022406 -344.051618) (xy 101.050142 -344.010057) (xy 101.067362 -343.991946)
			(xy 101.389434 -343.66962) (xy 101.395784 -343.659206) (xy 101.397562 -343.652856) (xy 101.405698 -343.626808)
			(xy 101.428308 -343.577143) (xy 101.457762 -343.531205) (xy 101.493458 -343.489931) (xy 101.53467 -343.454162)
			(xy 101.580556 -343.424628) (xy 101.630182 -343.401931) (xy 101.682534 -343.386535) (xy 101.736545 -343.378752)
			(xy 101.76383 -343.378282) (xy 101.791082 -343.37875) (xy 101.845029 -343.38651) (xy 101.897324 -343.401869)
			(xy 101.946901 -343.424513) (xy 101.99275 -343.453981) (xy 102.03394 -343.489674) (xy 102.069631 -343.530866)
			(xy 102.099097 -343.576717) (xy 102.121738 -343.626295) (xy 102.137094 -343.67859) (xy 102.144852 -343.732538)
			(xy 102.145338 -343.75979) (xy 102.144836 -343.787264) (xy 102.136947 -343.841643) (xy 102.12133 -343.894324)
			(xy 102.118686 -343.900054) (xy 102.387075 -343.900054) (xy 102.387075 -343.845546) (xy 102.394833 -343.791594)
			(xy 102.410191 -343.739296) (xy 102.432835 -343.689715) (xy 102.462306 -343.643862) (xy 102.498003 -343.60267)
			(xy 102.539199 -343.566979) (xy 102.585055 -343.537513) (xy 102.634639 -343.514875) (xy 102.686939 -343.499523)
			(xy 102.740892 -343.491772) (xy 102.768146 -343.491312) (xy 102.793382 -343.491687) (xy 102.843417 -343.498312)
			(xy 102.892137 -343.511491) (xy 102.938688 -343.530994) (xy 102.960678 -343.543382) (xy 102.97033 -343.549224)
			(xy 102.992428 -343.551256) (xy 103.086916 -343.517728) (xy 103.102918 -343.502234) (xy 103.106982 -343.49182)
			(xy 103.117687 -343.465047) (xy 103.145972 -343.414804) (xy 103.1815 -343.369393) (xy 103.22346 -343.32985)
			(xy 103.270896 -343.297075) (xy 103.322727 -343.271817) (xy 103.377769 -343.254651) (xy 103.434769 -343.245969)
			(xy 103.463598 -343.24544) (xy 103.490853 -343.245857) (xy 103.544808 -343.253615) (xy 103.59711 -343.268973)
			(xy 103.646693 -343.291619) (xy 103.692548 -343.321092) (xy 103.733742 -343.35679) (xy 103.769436 -343.397988)
			(xy 103.798903 -343.443847) (xy 103.801787 -343.450164) (xy 105.961942 -343.450164) (xy 105.962437 -343.42259)
			(xy 105.970382 -343.368018) (xy 105.9861 -343.315158) (xy 106.009264 -343.265112) (xy 106.039392 -343.218922)
			(xy 106.075856 -343.17755) (xy 106.096562 -343.159334) (xy 106.10467 -343.151723) (xy 106.114028 -343.131577)
			(xy 106.114596 -343.120472) (xy 106.114596 -343.043256) (xy 106.114014 -343.032148) (xy 106.104685 -343.011989)
			(xy 106.096562 -343.004394) (xy 106.075837 -342.986198) (xy 106.03937 -342.944825) (xy 106.00924 -342.898632)
			(xy 105.986077 -342.848581) (xy 105.970363 -342.795716) (xy 105.962426 -342.741139) (xy 105.961942 -342.713564)
			(xy 105.962322 -342.686308) (xy 105.970085 -342.632351) (xy 105.985448 -342.580049) (xy 106.008098 -342.530465)
			(xy 106.037575 -342.48461) (xy 106.073277 -342.443416) (xy 106.114479 -342.407723) (xy 106.160341 -342.378257)
			(xy 106.20993 -342.355618) (xy 106.262236 -342.340266) (xy 106.316194 -342.332515) (xy 106.34345 -342.332056)
			(xy 106.375072 -342.33266) (xy 106.437445 -342.343115) (xy 106.497234 -342.363729) (xy 106.525314 -342.378284)
			(xy 106.53395 -342.382856) (xy 106.553254 -342.385142) (xy 106.639868 -342.362028) (xy 106.655362 -342.350344)
			(xy 106.660442 -342.341962) (xy 106.676797 -342.316317) (xy 106.716359 -342.270121) (xy 106.739182 -342.250014)
			(xy 106.747303 -342.242414) (xy 106.756652 -342.22226) (xy 106.757216 -342.211152) (xy 106.757216 -342.133936)
			(xy 106.756671 -342.122823) (xy 106.747319 -342.102662) (xy 106.739182 -342.095074) (xy 106.718451 -342.076884)
			(xy 106.681983 -342.03551) (xy 106.651854 -341.989316) (xy 106.628692 -341.939264) (xy 106.61298 -341.886398)
			(xy 106.605045 -341.83182) (xy 106.604562 -341.804244) (xy 106.605048 -341.776993) (xy 106.612804 -341.723045)
			(xy 106.628159 -341.67075) (xy 106.650801 -341.621173) (xy 106.680267 -341.575323) (xy 106.715958 -341.534132)
			(xy 106.757149 -341.498441) (xy 106.802999 -341.468975) (xy 106.852576 -341.446333) (xy 106.904871 -341.430978)
			(xy 106.958819 -341.423222) (xy 107.013321 -341.423222) (xy 107.067269 -341.430978) (xy 107.119564 -341.446333)
			(xy 107.169141 -341.468975) (xy 107.214991 -341.498441) (xy 107.256182 -341.534132) (xy 107.291873 -341.575323)
			(xy 107.321339 -341.621173) (xy 107.343981 -341.67075) (xy 107.359336 -341.723045) (xy 107.367092 -341.776993)
			(xy 107.367578 -341.804244) (xy 107.367081 -341.831818) (xy 107.359136 -341.886389) (xy 107.343418 -341.939249)
			(xy 107.320254 -341.989295) (xy 107.290126 -342.035486) (xy 107.253663 -342.076858) (xy 107.232958 -342.095074)
			(xy 107.224849 -342.102685) (xy 107.215491 -342.12283) (xy 107.214924 -342.133936) (xy 107.214924 -342.211152)
			(xy 107.215495 -342.222262) (xy 107.224831 -342.242421) (xy 107.232958 -342.250014) (xy 107.253671 -342.268224)
			(xy 107.290143 -342.309592) (xy 107.320276 -342.355781) (xy 107.343442 -342.40583) (xy 107.359157 -342.458693)
			(xy 107.367094 -342.513269) (xy 107.367578 -342.540844) (xy 107.367008 -342.570786) (xy 107.357634 -342.629932)
			(xy 107.339138 -342.686889) (xy 107.311974 -342.740259) (xy 107.27681 -342.788732) (xy 107.256072 -342.810338)
			(xy 107.248452 -342.817958) (xy 107.240832 -342.837516) (xy 107.244642 -342.933528) (xy 107.253786 -342.952578)
			(xy 107.261914 -342.959436) (xy 107.282469 -342.977667) (xy 107.318675 -343.018991) (xy 107.34858 -343.065079)
			(xy 107.371568 -343.114979) (xy 107.387162 -343.167661) (xy 107.39504 -343.222034) (xy 107.395518 -343.249504)
			(xy 107.395049 -343.277078) (xy 107.387096 -343.331651) (xy 107.371371 -343.38451) (xy 107.348202 -343.434556)
			(xy 107.31807 -343.480746) (xy 107.281604 -343.522118) (xy 107.260898 -343.540334) (xy 107.252768 -343.547926)
			(xy 107.24342 -343.568086) (xy 107.242864 -343.579196) (xy 107.242864 -343.656412) (xy 107.243389 -343.667528)
			(xy 107.252756 -343.687687) (xy 107.260898 -343.695274) (xy 107.281599 -343.713496) (xy 107.318071 -343.754862)
			(xy 107.348204 -343.80105) (xy 107.371371 -343.851096) (xy 107.38709 -343.903957) (xy 107.395032 -343.95853)
			(xy 107.395518 -343.986104) (xy 107.395032 -344.013355) (xy 107.387276 -344.067303) (xy 107.371921 -344.119598)
			(xy 107.349279 -344.169175) (xy 107.319813 -344.215025) (xy 107.284122 -344.256216) (xy 107.242931 -344.291907)
			(xy 107.197081 -344.321373) (xy 107.147504 -344.344015) (xy 107.095209 -344.35937) (xy 107.041261 -344.367126)
			(xy 106.986759 -344.367126) (xy 106.932811 -344.35937) (xy 106.880516 -344.344015) (xy 106.830939 -344.321373)
			(xy 106.785089 -344.291907) (xy 106.743898 -344.256216) (xy 106.708207 -344.215025) (xy 106.678741 -344.169175)
			(xy 106.656099 -344.119598) (xy 106.640744 -344.067303) (xy 106.632988 -344.013355) (xy 106.632502 -343.986104)
			(xy 106.632717 -343.967246) (xy 106.636402 -343.929712) (xy 106.639868 -343.911174) (xy 106.642662 -343.897204)
			(xy 106.63301 -343.870534) (xy 106.540046 -343.796366) (xy 106.512106 -343.79281) (xy 106.498898 -343.798652)
			(xy 106.47434 -343.809127) (xy 106.423019 -343.823842) (xy 106.370145 -343.831248) (xy 106.34345 -343.831672)
			(xy 106.316197 -343.831198) (xy 106.262244 -343.823447) (xy 106.209944 -343.808095) (xy 106.160362 -343.785456)
			(xy 106.114507 -343.75599) (xy 106.073313 -343.720297) (xy 106.037618 -343.679104) (xy 106.008151 -343.63325)
			(xy 105.985509 -343.583669) (xy 105.970156 -343.531369) (xy 105.962403 -343.477417) (xy 105.961942 -343.450164)
			(xy 103.801787 -343.450164) (xy 103.821543 -343.493433) (xy 103.836895 -343.545737) (xy 103.844646 -343.599693)
			(xy 103.845106 -343.626948) (xy 103.844449 -343.658511) (xy 103.834061 -343.720776) (xy 103.813574 -343.780485)
			(xy 103.799132 -343.808558) (xy 103.794306 -343.817448) (xy 103.792274 -343.837006) (xy 103.817928 -343.925144)
			(xy 103.830374 -343.940638) (xy 103.839264 -343.945718) (xy 103.864349 -343.960293) (xy 103.910233 -343.995791)
			(xy 103.95021 -344.037829) (xy 103.983358 -344.085439) (xy 104.008911 -344.13752) (xy 104.026281 -344.192871)
			(xy 104.035065 -344.250214) (xy 104.035606 -344.27922) (xy 104.03512 -344.306471) (xy 104.027364 -344.360419)
			(xy 104.012009 -344.412714) (xy 103.989367 -344.462291) (xy 103.959901 -344.508141) (xy 103.92421 -344.549332)
			(xy 103.883019 -344.585023) (xy 103.837169 -344.614489) (xy 103.787592 -344.637131) (xy 103.735297 -344.652486)
			(xy 103.681349 -344.660242) (xy 103.626847 -344.660242) (xy 103.572899 -344.652486) (xy 103.520604 -344.637131)
			(xy 103.471027 -344.614489) (xy 103.425177 -344.585023) (xy 103.383986 -344.549332) (xy 103.348295 -344.508141)
			(xy 103.318829 -344.462291) (xy 103.296187 -344.412714) (xy 103.280832 -344.360419) (xy 103.273076 -344.306471)
			(xy 103.27259 -344.27922) (xy 103.273235 -344.247657) (xy 103.283628 -344.185391) (xy 103.30412 -344.125682)
			(xy 103.318564 -344.09761) (xy 103.32339 -344.08872) (xy 103.325422 -344.069162) (xy 103.299768 -343.981024)
			(xy 103.287322 -343.96553) (xy 103.278432 -343.96045) (xy 103.271066 -343.956386) (xy 103.261414 -343.950544)
			(xy 103.239316 -343.948512) (xy 103.144828 -343.98204) (xy 103.128826 -343.997534) (xy 103.124762 -344.007948)
			(xy 103.114056 -344.03472) (xy 103.085767 -344.084959) (xy 103.050238 -344.130367) (xy 103.008277 -344.169908)
			(xy 102.960841 -344.202682) (xy 102.909013 -344.227941) (xy 102.853972 -344.245109) (xy 102.796974 -344.253796)
			(xy 102.768146 -344.254328) (xy 102.740892 -344.253828) (xy 102.686939 -344.246077) (xy 102.634639 -344.230725)
			(xy 102.585055 -344.208087) (xy 102.539199 -344.178621) (xy 102.498003 -344.14293) (xy 102.462306 -344.101738)
			(xy 102.432835 -344.055885) (xy 102.410191 -344.006304) (xy 102.394833 -343.954006) (xy 102.387075 -343.900054)
			(xy 102.118686 -343.900054) (xy 102.098309 -343.944217) (xy 102.068361 -343.990287) (xy 102.050596 -344.01125)
			(xy 102.0445 -344.018362) (xy 102.03815 -344.03538) (xy 102.03815 -344.121232) (xy 102.0445 -344.13825)
			(xy 102.050596 -344.145362) (xy 102.068322 -344.166354) (xy 102.098253 -344.212428) (xy 102.121273 -344.262314)
			(xy 102.136908 -344.314985) (xy 102.144834 -344.369352) (xy 102.145338 -344.396822) (xy 102.144788 -344.426874)
			(xy 102.135349 -344.486233) (xy 102.116722 -344.543379) (xy 102.089368 -344.596899) (xy 102.053963 -344.645469)
			(xy 102.03307 -344.667078) (xy 102.026336 -344.674473) (xy 102.018623 -344.692905) (xy 102.018084 -344.702892)
			(xy 102.018084 -345.340178) (xy 102.017492 -345.365162) (xy 102.007741 -345.414171) (xy 101.988628 -345.46034)
			(xy 101.960885 -345.5019) (xy 101.943662 -345.52001) (xy 101.016562 -346.44711) (xy 100.998432 -346.46431)
			(xy 100.956881 -346.492057) (xy 100.910717 -346.511171) (xy 100.861712 -346.520918) (xy 100.83673 -346.521532)
			(xy 99.586034 -346.521532) (xy 99.561049 -346.520948) (xy 99.512039 -346.511197) (xy 99.46587 -346.492081)
			(xy 99.424311 -346.464335) (xy 99.406202 -346.44711) (xy 96.26981 -343.310718) (xy 96.262399 -343.303892)
			(xy 96.243808 -343.296163) (xy 96.233742 -343.295732) (xy 79.022702 -343.295732) (xy 79.012632 -343.29615)
			(xy 78.994033 -343.303875) (xy 78.986634 -343.310718) (xy 77.05979 -345.237562) (xy 88.93302 -345.237562)
			(xy 88.933443 -345.210309) (xy 88.941205 -345.156357) (xy 88.956566 -345.104059) (xy 88.979214 -345.05448)
			(xy 89.008687 -345.008629) (xy 89.044385 -344.967438) (xy 89.085582 -344.931747) (xy 89.131438 -344.902282)
			(xy 89.181021 -344.879643) (xy 89.233322 -344.864291) (xy 89.287274 -344.856538) (xy 89.314528 -344.856054)
			(xy 89.339987 -344.856488) (xy 89.390452 -344.863253) (xy 89.439569 -344.876671) (xy 89.486464 -344.896505)
			(xy 89.530304 -344.922402) (xy 89.570308 -344.953902) (xy 89.58834 -344.971878) (xy 89.595198 -344.97899)
			(xy 89.612978 -344.986864) (xy 89.703148 -344.989912) (xy 89.721436 -344.983308) (xy 89.728802 -344.976704)
			(xy 89.749893 -344.958526) (xy 89.796364 -344.927857) (xy 89.8468 -344.904269) (xy 89.900128 -344.888262)
			(xy 89.955217 -344.880177) (xy 89.983056 -344.879676) (xy 90.010426 -344.880149) (xy 90.064606 -344.887963)
			(xy 90.117109 -344.903449) (xy 90.166857 -344.92629) (xy 90.212823 -344.956014) (xy 90.233754 -344.973656)
			(xy 90.240866 -344.979752) (xy 90.257884 -344.986102) (xy 90.343228 -344.986102) (xy 90.360246 -344.979752)
			(xy 90.367358 -344.973656) (xy 90.388289 -344.956016) (xy 90.434263 -344.926306) (xy 90.484011 -344.90347)
			(xy 90.536511 -344.887979) (xy 90.590687 -344.88015) (xy 90.618056 -344.879676) (xy 90.646973 -344.880197)
			(xy 90.704145 -344.888922) (xy 90.759345 -344.906177) (xy 90.811308 -344.931568) (xy 90.858841 -344.964513)
			(xy 90.900857 -345.004256) (xy 90.919046 -345.026742) (xy 90.926585 -345.035527) (xy 90.947361 -345.045696)
			(xy 90.958924 -345.0463) (xy 91.039188 -345.0463) (xy 91.050755 -345.045722) (xy 91.071526 -345.035533)
			(xy 91.079066 -345.026742) (xy 91.097287 -345.004284) (xy 91.139299 -344.964545) (xy 91.186827 -344.931602)
			(xy 91.238783 -344.906209) (xy 91.293976 -344.888947) (xy 91.351142 -344.880213) (xy 91.380056 -344.879676)
			(xy 91.407426 -344.880149) (xy 91.461606 -344.887963) (xy 91.514109 -344.903449) (xy 91.563857 -344.92629)
			(xy 91.609823 -344.956014) (xy 91.630754 -344.973656) (xy 91.637866 -344.979752) (xy 91.654884 -344.986102)
			(xy 91.740228 -344.986102) (xy 91.757246 -344.979752) (xy 91.764358 -344.973656) (xy 91.785291 -344.956015)
			(xy 91.831259 -344.926291) (xy 91.881005 -344.903445) (xy 91.933507 -344.887949) (xy 91.987685 -344.88012)
			(xy 92.042427 -344.88012) (xy 92.096605 -344.887949) (xy 92.149107 -344.903445) (xy 92.198853 -344.926291)
			(xy 92.244821 -344.956015) (xy 92.265754 -344.973656) (xy 92.272866 -344.979752) (xy 92.289884 -344.986102)
			(xy 92.375228 -344.986102) (xy 92.392246 -344.979752) (xy 92.399358 -344.973656) (xy 92.420289 -344.956016)
			(xy 92.466263 -344.926306) (xy 92.516011 -344.90347) (xy 92.568511 -344.887979) (xy 92.622687 -344.88015)
			(xy 92.650056 -344.879676) (xy 92.677307 -344.880196) (xy 92.731255 -344.887947) (xy 92.783551 -344.903296)
			(xy 92.83313 -344.925933) (xy 92.878982 -344.955395) (xy 92.920175 -344.991082) (xy 92.955869 -345.03227)
			(xy 92.985339 -345.078117) (xy 93.007983 -345.127693) (xy 93.02334 -345.179986) (xy 93.0311 -345.233933)
			(xy 93.031564 -345.261184) (xy 93.031019 -345.289629) (xy 93.022568 -345.345888) (xy 93.00585 -345.400266)
			(xy 92.981238 -345.451556) (xy 92.949277 -345.49862) (xy 92.910677 -345.540411) (xy 92.888816 -345.558618)
			(xy 92.880434 -345.565476) (xy 92.870782 -345.584018) (xy 92.864178 -345.68003) (xy 92.87129 -345.699842)
			(xy 92.878656 -345.707716) (xy 92.898109 -345.72907) (xy 92.930987 -345.776563) (xy 92.956328 -345.828471)
			(xy 92.973551 -345.883606) (xy 92.982263 -345.940709) (xy 92.982796 -345.96959) (xy 92.98234 -345.996725)
			(xy 92.974645 -346.050445) (xy 92.959409 -346.102532) (xy 92.936941 -346.151931) (xy 92.907694 -346.197645)
			(xy 92.89034 -346.21851) (xy 92.883736 -346.22613) (xy 92.87764 -346.244418) (xy 92.88272 -346.33535)
			(xy 92.890848 -346.352622) (xy 92.898468 -346.35948) (xy 92.917459 -346.377615) (xy 92.950775 -346.418205)
			(xy 92.978215 -346.462976) (xy 92.999261 -346.511085) (xy 93.013517 -346.561624) (xy 93.020713 -346.61364)
			(xy 93.02115 -346.639896) (xy 93.020619 -346.667145) (xy 93.012864 -346.721089) (xy 92.997511 -346.77338)
			(xy 92.974874 -346.822955) (xy 92.945412 -346.868803) (xy 92.909725 -346.909992) (xy 92.86854 -346.945684)
			(xy 92.822695 -346.975152) (xy 92.773124 -346.997795) (xy 92.720834 -347.013154) (xy 92.666891 -347.020915)
			(xy 92.639642 -347.021404) (xy 92.612273 -347.020912) (xy 92.558095 -347.013101) (xy 92.505592 -346.997617)
			(xy 92.455845 -346.974781) (xy 92.409877 -346.945063) (xy 92.388944 -346.927424) (xy 92.381832 -346.921328)
			(xy 92.364814 -346.914978) (xy 92.27947 -346.914978) (xy 92.262452 -346.921328) (xy 92.25534 -346.927424)
			(xy 92.234407 -346.945062) (xy 92.188434 -346.974773) (xy 92.138687 -346.997609) (xy 92.086186 -347.0131)
			(xy 92.032011 -347.020929) (xy 92.004642 -347.021404) (xy 91.978325 -347.020968) (xy 91.926191 -347.013744)
			(xy 91.875542 -346.999428) (xy 91.82734 -346.97829) (xy 91.782499 -346.950732) (xy 91.741868 -346.917275)
			(xy 91.723718 -346.898214) (xy 91.71619 -346.89082) (xy 91.696915 -346.882291) (xy 91.68638 -346.881704)
			(xy 91.611704 -346.881704) (xy 91.601153 -346.882221) (xy 91.581858 -346.890765) (xy 91.574366 -346.898214)
			(xy 91.556251 -346.917313) (xy 91.515626 -346.950788) (xy 91.470781 -346.978356) (xy 91.42257 -346.999491)
			(xy 91.371909 -347.013792) (xy 91.319763 -347.020986) (xy 91.293442 -347.021404) (xy 91.266073 -347.020912)
			(xy 91.211895 -347.013101) (xy 91.159392 -346.997617) (xy 91.109645 -346.974781) (xy 91.063677 -346.945063)
			(xy 91.042744 -346.927424) (xy 91.035632 -346.921328) (xy 91.018614 -346.914978) (xy 90.93327 -346.914978)
			(xy 90.916252 -346.921328) (xy 90.90914 -346.927424) (xy 90.888207 -346.945065) (xy 90.842239 -346.974789)
			(xy 90.792493 -346.997635) (xy 90.739991 -347.013131) (xy 90.685813 -347.02096) (xy 90.631071 -347.02096)
			(xy 90.576893 -347.013131) (xy 90.524391 -346.997635) (xy 90.474645 -346.974789) (xy 90.428677 -346.945065)
			(xy 90.407744 -346.927424) (xy 90.400632 -346.921328) (xy 90.383614 -346.914978) (xy 90.29827 -346.914978)
			(xy 90.281252 -346.921328) (xy 90.27414 -346.927424) (xy 90.253207 -346.945065) (xy 90.207239 -346.974789)
			(xy 90.157493 -346.997635) (xy 90.104991 -347.013131) (xy 90.050813 -347.02096) (xy 89.996071 -347.02096)
			(xy 89.941893 -347.013131) (xy 89.889391 -346.997635) (xy 89.839645 -346.974789) (xy 89.793677 -346.945065)
			(xy 89.772744 -346.927424) (xy 89.765632 -346.921328) (xy 89.748614 -346.914978) (xy 89.66327 -346.914978)
			(xy 89.646252 -346.921328) (xy 89.63914 -346.927424) (xy 89.618207 -346.945062) (xy 89.572234 -346.974773)
			(xy 89.522487 -346.997609) (xy 89.469986 -347.0131) (xy 89.415811 -347.020929) (xy 89.388442 -347.021404)
			(xy 89.36119 -347.020906) (xy 89.30724 -347.013154) (xy 89.254943 -346.997803) (xy 89.205362 -346.975165)
			(xy 89.159509 -346.945701) (xy 89.118316 -346.910011) (xy 89.082621 -346.868822) (xy 89.053153 -346.822971)
			(xy 89.03051 -346.773393) (xy 89.015154 -346.721097) (xy 89.007397 -346.667148) (xy 89.006934 -346.639896)
			(xy 89.007433 -346.612763) (xy 89.015116 -346.559044) (xy 89.030342 -346.506957) (xy 89.0528 -346.457557)
			(xy 89.082039 -346.411842) (xy 89.09939 -346.390976) (xy 89.105994 -346.383356) (xy 89.11209 -346.365068)
			(xy 89.10701 -346.274136) (xy 89.098882 -346.256864) (xy 89.091262 -346.250006) (xy 89.07227 -346.231872)
			(xy 89.038953 -346.191283) (xy 89.011512 -346.146511) (xy 88.990466 -346.098402) (xy 88.976211 -346.047862)
			(xy 88.969016 -345.995846) (xy 88.96858 -345.96959) (xy 88.968982 -345.943757) (xy 88.975961 -345.892564)
			(xy 88.989789 -345.842783) (xy 89.010214 -345.795326) (xy 89.036861 -345.751062) (xy 89.069241 -345.710801)
			(xy 89.087706 -345.69273) (xy 89.095834 -345.684856) (xy 89.103962 -345.664282) (xy 89.099136 -345.565222)
			(xy 89.088976 -345.54541) (xy 89.08034 -345.538552) (xy 89.057862 -345.520341) (xy 89.018088 -345.478337)
			(xy 88.985105 -345.430814) (xy 88.959669 -345.37886) (xy 88.942362 -345.323662) (xy 88.933581 -345.266485)
			(xy 88.93302 -345.237562) (xy 77.05979 -345.237562) (xy 73.397872 -348.89948) (xy 81.802478 -348.89948)
			(xy 81.802982 -348.871033) (xy 81.81144 -348.814772) (xy 81.828164 -348.760392) (xy 81.852784 -348.709102)
			(xy 81.884753 -348.66204) (xy 81.923361 -348.620251) (xy 81.945226 -348.602046) (xy 81.953608 -348.595188)
			(xy 81.96326 -348.576646) (xy 81.969864 -348.480634) (xy 81.962752 -348.460822) (xy 81.955386 -348.452948)
			(xy 81.93597 -348.431562) (xy 81.903085 -348.384078) (xy 81.877737 -348.332179) (xy 81.860505 -348.27705)
			(xy 81.851784 -348.219953) (xy 81.851246 -348.191074) (xy 81.851732 -348.163823) (xy 81.859488 -348.109875)
			(xy 81.874843 -348.05758) (xy 81.897485 -348.008003) (xy 81.926951 -347.962153) (xy 81.962642 -347.920962)
			(xy 82.003833 -347.885271) (xy 82.049683 -347.855805) (xy 82.09926 -347.833163) (xy 82.151555 -347.817808)
			(xy 82.205503 -347.810052) (xy 82.260005 -347.810052) (xy 82.313953 -347.817808) (xy 82.366248 -347.833163)
			(xy 82.415825 -347.855805) (xy 82.461675 -347.885271) (xy 82.502866 -347.920962) (xy 82.538557 -347.962153)
			(xy 82.568023 -348.008003) (xy 82.590665 -348.05758) (xy 82.60602 -348.109875) (xy 82.613776 -348.163823)
			(xy 82.614262 -348.191074) (xy 82.613711 -348.219519) (xy 82.605261 -348.275777) (xy 82.588544 -348.330155)
			(xy 82.563933 -348.381446) (xy 82.531973 -348.428509) (xy 82.493375 -348.470301) (xy 82.471514 -348.488508)
			(xy 82.463132 -348.495366) (xy 82.45348 -348.513908) (xy 82.446876 -348.60992) (xy 82.453988 -348.629732)
			(xy 82.461354 -348.637606) (xy 82.480802 -348.658964) (xy 82.513681 -348.706456) (xy 82.539022 -348.758363)
			(xy 82.556247 -348.813497) (xy 82.563515 -348.861126) (xy 84.464144 -348.861126) (xy 84.464693 -348.832681)
			(xy 84.473143 -348.776422) (xy 84.48986 -348.722044) (xy 84.514471 -348.670754) (xy 84.546432 -348.62369)
			(xy 84.585031 -348.581899) (xy 84.606892 -348.563692) (xy 84.615274 -348.556834) (xy 84.624926 -348.538292)
			(xy 84.63153 -348.44228) (xy 84.624418 -348.422468) (xy 84.617052 -348.414594) (xy 84.597605 -348.393235)
			(xy 84.564726 -348.345743) (xy 84.539384 -348.293837) (xy 84.522159 -348.238702) (xy 84.513446 -348.181601)
			(xy 84.512912 -348.15272) (xy 84.513398 -348.125469) (xy 84.521154 -348.071521) (xy 84.536509 -348.019226)
			(xy 84.559151 -347.969649) (xy 84.588617 -347.923799) (xy 84.624308 -347.882608) (xy 84.665499 -347.846917)
			(xy 84.711349 -347.817451) (xy 84.760926 -347.794809) (xy 84.813221 -347.779454) (xy 84.867169 -347.771698)
			(xy 84.921671 -347.771698) (xy 84.975619 -347.779454) (xy 85.027914 -347.794809) (xy 85.077491 -347.817451)
			(xy 85.123341 -347.846917) (xy 85.164532 -347.882608) (xy 85.200223 -347.923799) (xy 85.229689 -347.969649)
			(xy 85.252331 -348.019226) (xy 85.267686 -348.071521) (xy 85.275442 -348.125469) (xy 85.275928 -348.15272)
			(xy 85.275422 -348.181167) (xy 85.266964 -348.237428) (xy 85.25024 -348.291807) (xy 85.22562 -348.343098)
			(xy 85.193652 -348.39016) (xy 85.155045 -348.431949) (xy 85.13318 -348.450154) (xy 85.124798 -348.457012)
			(xy 85.115146 -348.475554) (xy 85.108542 -348.571566) (xy 85.115654 -348.591378) (xy 85.12302 -348.599252)
			(xy 85.142437 -348.620638) (xy 85.175321 -348.668121) (xy 85.200669 -348.720021) (xy 85.217901 -348.77515)
			(xy 85.226622 -348.832247) (xy 85.22716 -348.861126) (xy 85.226675 -348.88826) (xy 85.218989 -348.94198)
			(xy 85.20376 -348.994066) (xy 85.181298 -349.043466) (xy 85.152056 -349.089181) (xy 85.134704 -349.110046)
			(xy 85.1281 -349.117666) (xy 85.122004 -349.135954) (xy 85.127084 -349.226886) (xy 85.135212 -349.244158)
			(xy 85.142832 -349.251016) (xy 85.161804 -349.26917) (xy 85.19512 -349.309756) (xy 85.222561 -349.354524)
			(xy 85.24361 -349.40263) (xy 85.257871 -349.453165) (xy 85.265073 -349.505178) (xy 85.265514 -349.531432)
			(xy 85.265113 -349.55761) (xy 85.257943 -349.609471) (xy 85.243741 -349.659864) (xy 85.222777 -349.707838)
			(xy 85.195443 -349.752492) (xy 85.162255 -349.792984) (xy 85.14334 -349.811086) (xy 85.135996 -349.818627)
			(xy 85.127606 -349.83791) (xy 85.127084 -349.848424) (xy 85.127084 -349.922846) (xy 85.127591 -349.933366)
			(xy 85.135975 -349.952657) (xy 85.14334 -349.960184) (xy 85.162222 -349.978313) (xy 85.195378 -350.018819)
			(xy 85.222691 -350.063473) (xy 85.243649 -350.111439) (xy 85.257861 -350.161818) (xy 85.265059 -350.213666)
			(xy 85.265514 -350.239838) (xy 85.265028 -350.267089) (xy 85.257272 -350.321037) (xy 85.241917 -350.373332)
			(xy 85.219275 -350.422909) (xy 85.189809 -350.468759) (xy 85.154118 -350.50995) (xy 85.112927 -350.545641)
			(xy 85.067077 -350.575107) (xy 85.0175 -350.597749) (xy 84.965205 -350.613104) (xy 84.911257 -350.62086)
			(xy 84.856755 -350.62086) (xy 84.802807 -350.613104) (xy 84.750512 -350.597749) (xy 84.700935 -350.575107)
			(xy 84.655085 -350.545641) (xy 84.613894 -350.50995) (xy 84.578203 -350.468759) (xy 84.548737 -350.422909)
			(xy 84.526095 -350.373332) (xy 84.51074 -350.321037) (xy 84.502984 -350.267089) (xy 84.502498 -350.239838)
			(xy 84.502974 -350.213663) (xy 84.510133 -350.161806) (xy 84.524321 -350.111416) (xy 84.545272 -350.063442)
			(xy 84.572591 -350.018786) (xy 84.605765 -349.97829) (xy 84.624672 -349.960184) (xy 84.632031 -349.952655)
			(xy 84.640412 -349.933363) (xy 84.640928 -349.922846) (xy 84.640928 -349.848424) (xy 84.640462 -349.837899)
			(xy 84.632052 -349.818606) (xy 84.624672 -349.811086) (xy 84.605778 -349.792969) (xy 84.572623 -349.752461)
			(xy 84.545311 -349.707804) (xy 84.524354 -349.659836) (xy 84.510146 -349.609455) (xy 84.502951 -349.557605)
			(xy 84.502498 -349.531432) (xy 84.502968 -349.504298) (xy 84.51066 -349.450578) (xy 84.525892 -349.398491)
			(xy 84.548357 -349.349092) (xy 84.577601 -349.303377) (xy 84.594954 -349.282512) (xy 84.601558 -349.274892)
			(xy 84.607654 -349.256604) (xy 84.602574 -349.165672) (xy 84.594446 -349.1484) (xy 84.586826 -349.141542)
			(xy 84.567845 -349.123397) (xy 84.534528 -349.08281) (xy 84.507087 -349.03804) (xy 84.486039 -348.989933)
			(xy 84.471781 -348.939396) (xy 84.464582 -348.887381) (xy 84.464144 -348.861126) (xy 82.563515 -348.861126)
			(xy 82.56496 -348.870599) (xy 82.565494 -348.89948) (xy 82.565032 -348.926614) (xy 82.557339 -348.980335)
			(xy 82.542105 -349.032421) (xy 82.519638 -349.081821) (xy 82.490392 -349.127535) (xy 82.473038 -349.1484)
			(xy 82.466434 -349.15602) (xy 82.460338 -349.174308) (xy 82.465418 -349.26524) (xy 82.473546 -349.282512)
			(xy 82.481166 -349.28937) (xy 82.500152 -349.307511) (xy 82.533468 -349.348099) (xy 82.560909 -349.392869)
			(xy 82.581956 -349.440977) (xy 82.596213 -349.491515) (xy 82.60341 -349.543531) (xy 82.603848 -349.569786)
			(xy 82.603378 -349.597599) (xy 82.595301 -349.652636) (xy 82.579317 -349.705916) (xy 82.555764 -349.756309)
			(xy 82.525142 -349.802748) (xy 82.4881 -349.844246) (xy 82.445423 -349.879925) (xy 82.421984 -349.894906)
			(xy 82.410554 -349.902018) (xy 82.397854 -349.924624) (xy 82.3976 -350.038162) (xy 82.410554 -350.061022)
			(xy 82.421984 -350.068134) (xy 82.445372 -350.083138) (xy 82.487977 -350.118807) (xy 82.524956 -350.16028)
			(xy 82.555528 -350.206678) (xy 82.579045 -350.257021) (xy 82.59501 -350.310243) (xy 82.603085 -350.365218)
			(xy 82.603594 -350.393) (xy 82.603108 -350.420251) (xy 82.595352 -350.474199) (xy 82.579997 -350.526494)
			(xy 82.557355 -350.576071) (xy 82.527889 -350.621921) (xy 82.492198 -350.663112) (xy 82.451007 -350.698803)
			(xy 82.405157 -350.728269) (xy 82.35558 -350.750911) (xy 82.303285 -350.766266) (xy 82.249337 -350.774022)
			(xy 82.194835 -350.774022) (xy 82.140887 -350.766266) (xy 82.088592 -350.750911) (xy 82.039015 -350.728269)
			(xy 81.993165 -350.698803) (xy 81.951974 -350.663112) (xy 81.916283 -350.621921) (xy 81.886817 -350.576071)
			(xy 81.864175 -350.526494) (xy 81.84882 -350.474199) (xy 81.841064 -350.420251) (xy 81.840578 -350.393)
			(xy 81.841025 -350.365186) (xy 81.849104 -350.310148) (xy 81.865092 -350.256867) (xy 81.888648 -350.206473)
			(xy 81.919274 -350.160034) (xy 81.95632 -350.118537) (xy 81.999001 -350.082859) (xy 82.022442 -350.06788)
			(xy 82.033872 -350.060768) (xy 82.046572 -350.038162) (xy 82.046826 -349.924624) (xy 82.033872 -349.901764)
			(xy 82.022442 -349.894652) (xy 81.999053 -349.879648) (xy 81.956447 -349.84398) (xy 81.919467 -349.802508)
			(xy 81.888895 -349.756109) (xy 81.865378 -349.705766) (xy 81.849414 -349.652544) (xy 81.84134 -349.597568)
			(xy 81.840832 -349.569786) (xy 81.841326 -349.542653) (xy 81.84901 -349.488933) (xy 81.864237 -349.436847)
			(xy 81.886697 -349.387447) (xy 81.915937 -349.341731) (xy 81.933288 -349.320866) (xy 81.939892 -349.313246)
			(xy 81.945988 -349.294958) (xy 81.940908 -349.204026) (xy 81.93278 -349.186754) (xy 81.92516 -349.179896)
			(xy 81.906163 -349.161767) (xy 81.872846 -349.121177) (xy 81.845406 -349.076404) (xy 81.824361 -349.028294)
			(xy 81.810107 -348.977753) (xy 81.802913 -348.925736) (xy 81.802478 -348.89948) (xy 73.397872 -348.89948)
			(xy 70.659498 -351.637854) (xy 74.429874 -351.637854) (xy 74.430361 -351.609407) (xy 74.438823 -351.553145)
			(xy 74.455551 -351.498765) (xy 74.480174 -351.447474) (xy 74.512146 -351.400413) (xy 74.550756 -351.358624)
			(xy 74.572622 -351.34042) (xy 74.581004 -351.333562) (xy 74.590656 -351.31502) (xy 74.59726 -351.219008)
			(xy 74.590148 -351.199196) (xy 74.582782 -351.191322) (xy 74.563353 -351.169947) (xy 74.53047 -351.12246)
			(xy 74.505125 -351.070558) (xy 74.487896 -351.015427) (xy 74.479178 -350.958328) (xy 74.478642 -350.929448)
			(xy 74.479128 -350.902197) (xy 74.486884 -350.848249) (xy 74.502239 -350.795954) (xy 74.524881 -350.746377)
			(xy 74.554347 -350.700527) (xy 74.590038 -350.659336) (xy 74.631229 -350.623645) (xy 74.677079 -350.594179)
			(xy 74.726656 -350.571537) (xy 74.778951 -350.556182) (xy 74.832899 -350.548426) (xy 74.887401 -350.548426)
			(xy 74.941349 -350.556182) (xy 74.993644 -350.571537) (xy 75.043221 -350.594179) (xy 75.089071 -350.623645)
			(xy 75.130262 -350.659336) (xy 75.165953 -350.700527) (xy 75.195419 -350.746377) (xy 75.218061 -350.795954)
			(xy 75.233416 -350.848249) (xy 75.241172 -350.902197) (xy 75.241658 -350.929448) (xy 75.24116 -350.957895)
			(xy 75.232699 -351.014156) (xy 75.215973 -351.068535) (xy 75.191351 -351.119825) (xy 75.159382 -351.166887)
			(xy 75.120775 -351.208677) (xy 75.09891 -351.226882) (xy 75.090528 -351.23374) (xy 75.080876 -351.252282)
			(xy 75.074272 -351.348294) (xy 75.081384 -351.368106) (xy 75.08875 -351.37598) (xy 75.108185 -351.39735)
			(xy 75.141066 -351.444838) (xy 75.16641 -351.496742) (xy 75.183637 -351.551874) (xy 75.190908 -351.5995)
			(xy 77.09154 -351.5995) (xy 77.092072 -351.571055) (xy 77.100526 -351.514795) (xy 77.117246 -351.460417)
			(xy 77.141861 -351.409126) (xy 77.173824 -351.362063) (xy 77.212426 -351.320272) (xy 77.234288 -351.302066)
			(xy 77.24267 -351.295208) (xy 77.252322 -351.276666) (xy 77.258926 -351.180654) (xy 77.251814 -351.160842)
			(xy 77.244448 -351.152968) (xy 77.224988 -351.13162) (xy 77.192111 -351.084126) (xy 77.166771 -351.032216)
			(xy 77.14955 -350.977079) (xy 77.14084 -350.919976) (xy 77.140308 -350.891094) (xy 77.140794 -350.863843)
			(xy 77.14855 -350.809895) (xy 77.163905 -350.7576) (xy 77.186547 -350.708023) (xy 77.216013 -350.662173)
			(xy 77.251704 -350.620982) (xy 77.292895 -350.585291) (xy 77.338745 -350.555825) (xy 77.388322 -350.533183)
			(xy 77.440617 -350.517828) (xy 77.494565 -350.510072) (xy 77.549067 -350.510072) (xy 77.603015 -350.517828)
			(xy 77.65531 -350.533183) (xy 77.704887 -350.555825) (xy 77.750737 -350.585291) (xy 77.791928 -350.620982)
			(xy 77.827619 -350.662173) (xy 77.857085 -350.708023) (xy 77.879727 -350.7576) (xy 77.895082 -350.809895)
			(xy 77.902838 -350.863843) (xy 77.903324 -350.891094) (xy 77.902801 -350.91954) (xy 77.894347 -350.9758)
			(xy 77.877626 -351.03018) (xy 77.85301 -351.08147) (xy 77.821044 -351.128533) (xy 77.78244 -351.170323)
			(xy 77.760576 -351.188528) (xy 77.752194 -351.195386) (xy 77.742542 -351.213928) (xy 77.735938 -351.30994)
			(xy 77.74305 -351.329752) (xy 77.750416 -351.337626) (xy 77.769867 -351.358982) (xy 77.802747 -351.406473)
			(xy 77.828089 -351.458381) (xy 77.845312 -351.513516) (xy 77.854023 -351.570619) (xy 77.854556 -351.5995)
			(xy 77.854057 -351.626633) (xy 77.846374 -351.680352) (xy 77.831149 -351.732439) (xy 77.80869 -351.781839)
			(xy 77.779451 -351.827555) (xy 77.7621 -351.84842) (xy 77.755496 -351.85604) (xy 77.7494 -351.874328)
			(xy 77.75448 -351.96526) (xy 77.762608 -351.982532) (xy 77.770228 -351.98939) (xy 77.789235 -352.007508)
			(xy 77.822548 -352.048103) (xy 77.849984 -352.092878) (xy 77.871028 -352.14099) (xy 77.88528 -352.191532)
			(xy 77.892474 -352.24355) (xy 77.89291 -352.269806) (xy 77.892493 -352.295983) (xy 77.885326 -352.347844)
			(xy 77.871128 -352.398236) (xy 77.850166 -352.446211) (xy 77.822835 -352.490865) (xy 77.78965 -352.531357)
			(xy 77.770736 -352.54946) (xy 77.763403 -352.55701) (xy 77.755007 -352.576286) (xy 77.75448 -352.586798)
			(xy 77.75448 -352.66122) (xy 77.754974 -352.671742) (xy 77.763364 -352.691035) (xy 77.770736 -352.698558)
			(xy 77.789605 -352.716701) (xy 77.822762 -352.757203) (xy 77.850077 -352.801855) (xy 77.871038 -352.849818)
			(xy 77.885252 -352.900195) (xy 77.892453 -352.952041) (xy 77.89291 -352.978212) (xy 77.892424 -353.005463)
			(xy 77.884668 -353.059411) (xy 77.869313 -353.111706) (xy 77.846671 -353.161283) (xy 77.817205 -353.207133)
			(xy 77.781514 -353.248324) (xy 77.740323 -353.284015) (xy 77.694473 -353.313481) (xy 77.644896 -353.336123)
			(xy 77.592601 -353.351478) (xy 77.538653 -353.359234) (xy 77.484151 -353.359234) (xy 77.430203 -353.351478)
			(xy 77.377908 -353.336123) (xy 77.328331 -353.313481) (xy 77.282481 -353.284015) (xy 77.24129 -353.248324)
			(xy 77.205599 -353.207133) (xy 77.176133 -353.161283) (xy 77.153491 -353.111706) (xy 77.138136 -353.059411)
			(xy 77.13038 -353.005463) (xy 77.129894 -352.978212) (xy 77.130354 -352.952037) (xy 77.137516 -352.900179)
			(xy 77.151708 -352.849788) (xy 77.172662 -352.801814) (xy 77.199984 -352.757159) (xy 77.23316 -352.716663)
			(xy 77.252068 -352.698558) (xy 77.259393 -352.691002) (xy 77.267794 -352.67173) (xy 77.268324 -352.66122)
			(xy 77.268324 -352.586798) (xy 77.267873 -352.576271) (xy 77.259452 -352.556979) (xy 77.252068 -352.54946)
			(xy 77.23316 -352.531356) (xy 77.200007 -352.490845) (xy 77.172697 -352.446186) (xy 77.151743 -352.398215)
			(xy 77.137537 -352.347831) (xy 77.130345 -352.29598) (xy 77.129894 -352.269806) (xy 77.130385 -352.242672)
			(xy 77.138068 -352.188952) (xy 77.153294 -352.136865) (xy 77.175756 -352.087465) (xy 77.204998 -352.041751)
			(xy 77.22235 -352.020886) (xy 77.228954 -352.013266) (xy 77.23505 -351.994978) (xy 77.22997 -351.904046)
			(xy 77.221842 -351.886774) (xy 77.214222 -351.879916) (xy 77.195227 -351.861784) (xy 77.161912 -351.821194)
			(xy 77.134473 -351.776422) (xy 77.113427 -351.728312) (xy 77.099172 -351.677772) (xy 77.091977 -351.625756)
			(xy 77.09154 -351.5995) (xy 75.190908 -351.5995) (xy 75.192354 -351.608974) (xy 75.19289 -351.637854)
			(xy 75.192414 -351.664988) (xy 75.184724 -351.718708) (xy 75.169494 -351.770794) (xy 75.14703 -351.820194)
			(xy 75.117787 -351.865909) (xy 75.100434 -351.886774) (xy 75.09383 -351.894394) (xy 75.087734 -351.912682)
			(xy 75.092814 -352.003614) (xy 75.100942 -352.020886) (xy 75.108562 -352.027744) (xy 75.127534 -352.045898)
			(xy 75.160852 -352.086483) (xy 75.188295 -352.131251) (xy 75.209345 -352.179356) (xy 75.223604 -352.229892)
			(xy 75.230805 -352.281905) (xy 75.231244 -352.30816) (xy 75.230756 -352.335972) (xy 75.222682 -352.391008)
			(xy 75.206701 -352.444288) (xy 75.183151 -352.494681) (xy 75.152532 -352.54112) (xy 75.115492 -352.582619)
			(xy 75.072818 -352.618299) (xy 75.04938 -352.63328) (xy 75.03795 -352.640392) (xy 75.02525 -352.662998)
			(xy 75.024996 -352.776536) (xy 75.03795 -352.799396) (xy 75.04938 -352.806508) (xy 75.072801 -352.821464)
			(xy 75.115406 -352.857141) (xy 75.152383 -352.898621) (xy 75.182951 -352.945028) (xy 75.206463 -352.995379)
			(xy 75.22242 -353.048608) (xy 75.230486 -353.103589) (xy 75.23099 -353.131374) (xy 75.230504 -353.158625)
			(xy 75.222748 -353.212573) (xy 75.207393 -353.264868) (xy 75.184751 -353.314445) (xy 75.155285 -353.360295)
			(xy 75.119594 -353.401486) (xy 75.078403 -353.437177) (xy 75.032553 -353.466643) (xy 74.982976 -353.489285)
			(xy 74.930681 -353.50464) (xy 74.876733 -353.512396) (xy 74.822231 -353.512396) (xy 74.768283 -353.50464)
			(xy 74.715988 -353.489285) (xy 74.666411 -353.466643) (xy 74.620561 -353.437177) (xy 74.57937 -353.401486)
			(xy 74.543679 -353.360295) (xy 74.514213 -353.314445) (xy 74.491571 -353.264868) (xy 74.476216 -353.212573)
			(xy 74.46846 -353.158625) (xy 74.467974 -353.131374) (xy 74.46848 -353.103562) (xy 74.476549 -353.048527)
			(xy 74.492526 -352.995247) (xy 74.516073 -352.944853) (xy 74.54669 -352.898414) (xy 74.583728 -352.856915)
			(xy 74.6264 -352.821235) (xy 74.649838 -352.806254) (xy 74.661268 -352.799142) (xy 74.673968 -352.776536)
			(xy 74.674222 -352.662998) (xy 74.661268 -352.640138) (xy 74.649838 -352.633026) (xy 74.626436 -352.618041)
			(xy 74.583831 -352.58237) (xy 74.546852 -352.540894) (xy 74.516281 -352.494492) (xy 74.492766 -352.444146)
			(xy 74.476805 -352.390921) (xy 74.468734 -352.335943) (xy 74.468228 -352.30816) (xy 74.468708 -352.281026)
			(xy 74.476396 -352.227306) (xy 74.491626 -352.17522) (xy 74.514089 -352.12582) (xy 74.543331 -352.080105)
			(xy 74.560684 -352.05924) (xy 74.567288 -352.05162) (xy 74.573384 -352.033332) (xy 74.568304 -351.9424)
			(xy 74.560176 -351.925128) (xy 74.552556 -351.91827) (xy 74.533594 -351.900106) (xy 74.500274 -351.859523)
			(xy 74.47283 -351.814758) (xy 74.451778 -351.766655) (xy 74.437517 -351.71612) (xy 74.430314 -351.664108)
			(xy 74.429874 -351.637854) (xy 70.659498 -351.637854) (xy 67.925188 -354.372164) (xy 86.93785 -354.372164)
			(xy 86.938309 -354.346244) (xy 86.945343 -354.294883) (xy 86.959263 -354.244946) (xy 86.979813 -354.197352)
			(xy 87.006615 -354.152978) (xy 87.039176 -354.112639) (xy 87.057738 -354.094542) (xy 87.064596 -354.087938)
			(xy 87.072724 -354.07092) (xy 87.079074 -353.98329) (xy 87.073486 -353.965256) (xy 87.067644 -353.957636)
			(xy 87.052104 -353.937355) (xy 87.026046 -353.893404) (xy 87.006084 -353.84637) (xy 86.992574 -353.797094)
			(xy 86.985757 -353.746455) (xy 86.985348 -353.720908) (xy 86.985807 -353.693537) (xy 86.993625 -353.639358)
			(xy 87.009115 -353.586854) (xy 87.031958 -353.537107) (xy 87.061685 -353.491141) (xy 87.079328 -353.47021)
			(xy 87.085424 -353.463098) (xy 87.091774 -353.44608) (xy 87.091774 -353.360736) (xy 87.085424 -353.343718)
			(xy 87.079328 -353.336606) (xy 87.061695 -353.315667) (xy 87.03197 -353.2697) (xy 87.009124 -353.219955)
			(xy 86.993627 -353.167454) (xy 86.985798 -353.113276) (xy 86.985797 -353.058536) (xy 86.993625 -353.004358)
			(xy 87.00912 -352.951856) (xy 87.031964 -352.90211) (xy 87.061688 -352.856143) (xy 87.079328 -352.83521)
			(xy 87.085424 -352.828098) (xy 87.091774 -352.81108) (xy 87.091774 -352.725736) (xy 87.085424 -352.708718)
			(xy 87.079328 -352.701606) (xy 87.061695 -352.680667) (xy 87.03197 -352.6347) (xy 87.009124 -352.584955)
			(xy 86.993627 -352.532454) (xy 86.985798 -352.478276) (xy 86.985797 -352.423536) (xy 86.993625 -352.369358)
			(xy 87.00912 -352.316856) (xy 87.031964 -352.26711) (xy 87.061688 -352.221143) (xy 87.079328 -352.20021)
			(xy 87.085424 -352.193098) (xy 87.091774 -352.17608) (xy 87.091774 -352.090736) (xy 87.085424 -352.073718)
			(xy 87.079328 -352.066606) (xy 87.061695 -352.045667) (xy 87.03197 -351.9997) (xy 87.009124 -351.949955)
			(xy 86.993627 -351.897454) (xy 86.985798 -351.843276) (xy 86.985797 -351.788536) (xy 86.993625 -351.734358)
			(xy 87.00912 -351.681856) (xy 87.031964 -351.63211) (xy 87.061688 -351.586143) (xy 87.079328 -351.56521)
			(xy 87.085424 -351.558098) (xy 87.091774 -351.54108) (xy 87.091774 -351.455736) (xy 87.085424 -351.438718)
			(xy 87.079328 -351.431606) (xy 87.061695 -351.410667) (xy 87.03197 -351.3647) (xy 87.009124 -351.314955)
			(xy 86.993627 -351.262454) (xy 86.985798 -351.208276) (xy 86.985797 -351.153536) (xy 86.993625 -351.099358)
			(xy 87.00912 -351.046856) (xy 87.031964 -350.99711) (xy 87.061688 -350.951143) (xy 87.079328 -350.93021)
			(xy 87.085424 -350.923098) (xy 87.091774 -350.90608) (xy 87.091774 -350.820736) (xy 87.085424 -350.803718)
			(xy 87.079328 -350.796606) (xy 87.061683 -350.775679) (xy 87.031971 -350.729705) (xy 87.009136 -350.679956)
			(xy 86.993646 -350.627455) (xy 86.98582 -350.573278) (xy 86.985348 -350.545908) (xy 86.985885 -350.518659)
			(xy 86.993639 -350.464715) (xy 87.008991 -350.412424) (xy 87.031628 -350.36285) (xy 87.06109 -350.317002)
			(xy 87.096776 -350.275812) (xy 87.13796 -350.240121) (xy 87.183804 -350.210653) (xy 87.233375 -350.188009)
			(xy 87.285664 -350.17265) (xy 87.339607 -350.164889) (xy 87.366856 -350.1644) (xy 87.394225 -350.164892)
			(xy 87.448403 -350.172703) (xy 87.500906 -350.188187) (xy 87.550653 -350.211022) (xy 87.596621 -350.240741)
			(xy 87.617554 -350.25838) (xy 87.624666 -350.264476) (xy 87.641684 -350.270826) (xy 87.727028 -350.270826)
			(xy 87.744046 -350.264476) (xy 87.751158 -350.25838) (xy 87.772091 -350.240739) (xy 87.818059 -350.211015)
			(xy 87.867805 -350.188169) (xy 87.920307 -350.172673) (xy 87.974485 -350.164844) (xy 88.029227 -350.164844)
			(xy 88.083405 -350.172673) (xy 88.135907 -350.188169) (xy 88.185653 -350.211015) (xy 88.231621 -350.240739)
			(xy 88.252554 -350.25838) (xy 88.259666 -350.264476) (xy 88.276684 -350.270826) (xy 88.362028 -350.270826)
			(xy 88.379046 -350.264476) (xy 88.386158 -350.25838) (xy 88.407091 -350.240739) (xy 88.453059 -350.211015)
			(xy 88.502805 -350.188169) (xy 88.555307 -350.172673) (xy 88.609485 -350.164844) (xy 88.664227 -350.164844)
			(xy 88.718405 -350.172673) (xy 88.770907 -350.188169) (xy 88.820653 -350.211015) (xy 88.866621 -350.240739)
			(xy 88.887554 -350.25838) (xy 88.894666 -350.264476) (xy 88.911684 -350.270826) (xy 88.997028 -350.270826)
			(xy 89.014046 -350.264476) (xy 89.021158 -350.25838) (xy 89.042091 -350.240739) (xy 89.088059 -350.211015)
			(xy 89.137805 -350.188169) (xy 89.190307 -350.172673) (xy 89.244485 -350.164844) (xy 89.299227 -350.164844)
			(xy 89.353405 -350.172673) (xy 89.405907 -350.188169) (xy 89.455653 -350.211015) (xy 89.501621 -350.240739)
			(xy 89.522554 -350.25838) (xy 89.529666 -350.264476) (xy 89.546684 -350.270826) (xy 89.632028 -350.270826)
			(xy 89.649046 -350.264476) (xy 89.656158 -350.25838) (xy 89.677091 -350.240739) (xy 89.723059 -350.211015)
			(xy 89.772805 -350.188169) (xy 89.825307 -350.172673) (xy 89.879485 -350.164844) (xy 89.934227 -350.164844)
			(xy 89.988405 -350.172673) (xy 90.040907 -350.188169) (xy 90.090653 -350.211015) (xy 90.136621 -350.240739)
			(xy 90.157554 -350.25838) (xy 90.164666 -350.264476) (xy 90.181684 -350.270826) (xy 90.267028 -350.270826)
			(xy 90.284046 -350.264476) (xy 90.291158 -350.25838) (xy 90.312091 -350.240739) (xy 90.358059 -350.211015)
			(xy 90.407805 -350.188169) (xy 90.460307 -350.172673) (xy 90.514485 -350.164844) (xy 90.569227 -350.164844)
			(xy 90.623405 -350.172673) (xy 90.675907 -350.188169) (xy 90.725653 -350.211015) (xy 90.771621 -350.240739)
			(xy 90.792554 -350.25838) (xy 90.799666 -350.264476) (xy 90.816684 -350.270826) (xy 90.902028 -350.270826)
			(xy 90.919046 -350.264476) (xy 90.926158 -350.25838) (xy 90.947091 -350.240739) (xy 90.993059 -350.211015)
			(xy 91.042805 -350.188169) (xy 91.095307 -350.172673) (xy 91.149485 -350.164844) (xy 91.204227 -350.164844)
			(xy 91.258405 -350.172673) (xy 91.310907 -350.188169) (xy 91.360653 -350.211015) (xy 91.406621 -350.240739)
			(xy 91.427554 -350.25838) (xy 91.434666 -350.264476) (xy 91.451684 -350.270826) (xy 91.537028 -350.270826)
			(xy 91.554046 -350.264476) (xy 91.561158 -350.25838) (xy 91.582091 -350.240739) (xy 91.628059 -350.211015)
			(xy 91.677805 -350.188169) (xy 91.730307 -350.172673) (xy 91.784485 -350.164844) (xy 91.839227 -350.164844)
			(xy 91.893405 -350.172673) (xy 91.945907 -350.188169) (xy 91.995653 -350.211015) (xy 92.041621 -350.240739)
			(xy 92.062554 -350.25838) (xy 92.069666 -350.264476) (xy 92.086684 -350.270826) (xy 92.172028 -350.270826)
			(xy 92.189046 -350.264476) (xy 92.196158 -350.25838) (xy 92.217091 -350.240739) (xy 92.263059 -350.211015)
			(xy 92.312805 -350.188169) (xy 92.365307 -350.172673) (xy 92.419485 -350.164844) (xy 92.474227 -350.164844)
			(xy 92.528405 -350.172673) (xy 92.580907 -350.188169) (xy 92.630653 -350.211015) (xy 92.676621 -350.240739)
			(xy 92.697554 -350.25838) (xy 92.704666 -350.264476) (xy 92.721684 -350.270826) (xy 92.807028 -350.270826)
			(xy 92.824046 -350.264476) (xy 92.831158 -350.25838) (xy 92.852091 -350.240739) (xy 92.898059 -350.211015)
			(xy 92.947805 -350.188169) (xy 93.000307 -350.172673) (xy 93.054485 -350.164844) (xy 93.109227 -350.164844)
			(xy 93.163405 -350.172673) (xy 93.215907 -350.188169) (xy 93.265653 -350.211015) (xy 93.311621 -350.240739)
			(xy 93.332554 -350.25838) (xy 93.339666 -350.264476) (xy 93.356684 -350.270826) (xy 93.442028 -350.270826)
			(xy 93.459046 -350.264476) (xy 93.466158 -350.25838) (xy 93.487093 -350.240744) (xy 93.533065 -350.211032)
			(xy 93.582812 -350.188196) (xy 93.635312 -350.172704) (xy 93.689487 -350.164875) (xy 93.716856 -350.1644)
			(xy 93.744108 -350.164896) (xy 93.798058 -350.172647) (xy 93.850356 -350.187998) (xy 93.899937 -350.210636)
			(xy 93.94579 -350.2401) (xy 93.986984 -350.275791) (xy 94.022678 -350.316981) (xy 94.052146 -350.362832)
			(xy 94.074789 -350.41241) (xy 94.090145 -350.464706) (xy 94.097901 -350.518656) (xy 94.098364 -350.545908)
			(xy 94.097911 -350.573279) (xy 94.090092 -350.627459) (xy 94.0746 -350.679962) (xy 94.051755 -350.729709)
			(xy 94.022027 -350.775675) (xy 94.004384 -350.796606) (xy 93.998288 -350.803718) (xy 93.991938 -350.820736)
			(xy 93.991938 -350.90608) (xy 93.998288 -350.923098) (xy 94.004384 -350.93021) (xy 94.022032 -350.951137)
			(xy 94.051756 -350.997106) (xy 94.0746 -351.046853) (xy 94.090095 -351.099356) (xy 94.097923 -351.153535)
			(xy 94.097922 -351.208277) (xy 94.090093 -351.262456) (xy 94.074596 -351.314958) (xy 94.05175 -351.364705)
			(xy 94.022025 -351.410673) (xy 94.004384 -351.431606) (xy 93.998288 -351.438718) (xy 93.991938 -351.455736)
			(xy 93.991938 -351.54108) (xy 93.998288 -351.558098) (xy 94.004384 -351.56521) (xy 94.022039 -351.58613)
			(xy 94.051749 -351.632106) (xy 94.074582 -351.681856) (xy 94.090069 -351.73436) (xy 94.097893 -351.788538)
			(xy 94.098364 -351.815908) (xy 94.097824 -351.844763) (xy 94.089138 -351.901815) (xy 94.07195 -351.956905)
			(xy 94.046654 -352.008775) (xy 94.013827 -352.056238) (xy 93.97422 -352.098211) (xy 93.951806 -352.11639)
			(xy 93.944186 -352.122486) (xy 93.934534 -352.138742) (xy 93.920056 -352.225356) (xy 93.92412 -352.243898)
			(xy 93.9292 -352.252026) (xy 93.943856 -352.275367) (xy 93.966997 -352.325387) (xy 93.982711 -352.378213)
			(xy 93.990672 -352.432749) (xy 93.991176 -352.460306) (xy 93.990727 -352.486168) (xy 93.983745 -352.537418)
			(xy 93.969896 -352.587253) (xy 93.949435 -352.634758) (xy 93.922738 -352.679059) (xy 93.890296 -352.719343)
			(xy 93.871796 -352.73742) (xy 93.863922 -352.744786) (xy 93.855794 -352.763836) (xy 93.855794 -352.859086)
			(xy 93.863922 -352.877882) (xy 93.871796 -352.885248) (xy 93.890305 -352.903358) (xy 93.922813 -352.943663)
			(xy 93.949569 -352.987995) (xy 93.970082 -353.03554) (xy 93.983975 -353.085422) (xy 93.990991 -353.136726)
			(xy 93.99143 -353.162616) (xy 93.99099 -353.189987) (xy 93.983169 -353.244168) (xy 93.967674 -353.296672)
			(xy 93.944826 -353.346419) (xy 93.915095 -353.392384) (xy 93.89745 -353.413314) (xy 93.891354 -353.420426)
			(xy 93.885004 -353.437444) (xy 93.885004 -353.522788) (xy 93.891354 -353.539806) (xy 93.89745 -353.546918)
			(xy 93.915056 -353.567877) (xy 93.944775 -353.613841) (xy 93.967618 -353.663582) (xy 93.983116 -353.716077)
			(xy 93.990952 -353.770249) (xy 93.99143 -353.797616) (xy 93.990974 -353.823944) (xy 93.983748 -353.876102)
			(xy 93.969409 -353.926768) (xy 93.948229 -353.974977) (xy 93.920612 -354.01981) (xy 93.887085 -354.060413)
			(xy 93.867986 -354.07854) (xy 93.860874 -354.085144) (xy 93.852492 -354.102416) (xy 93.846142 -354.191316)
			(xy 93.851984 -354.209858) (xy 93.85808 -354.217478) (xy 93.874192 -354.237978) (xy 93.901292 -354.282522)
			(xy 93.922072 -354.330342) (xy 93.936146 -354.380546) (xy 93.943251 -354.4322) (xy 93.943678 -354.45827)
			(xy 93.943217 -354.485523) (xy 93.935463 -354.539476) (xy 93.920109 -354.591776) (xy 93.897468 -354.641358)
			(xy 93.868 -354.687213) (xy 93.832306 -354.728406) (xy 93.791113 -354.7641) (xy 93.745258 -354.793568)
			(xy 93.695676 -354.816209) (xy 93.643376 -354.831563) (xy 93.589423 -354.839317) (xy 93.56217 -354.839778)
			(xy 93.533989 -354.839267) (xy 93.478242 -354.830966) (xy 93.42432 -354.814563) (xy 93.373394 -354.790415)
			(xy 93.326569 -354.759046) (xy 93.305376 -354.740464) (xy 93.298264 -354.73386) (xy 93.280738 -354.727256)
			(xy 93.193108 -354.727256) (xy 93.175582 -354.734114) (xy 93.16847 -354.740464) (xy 93.147286 -354.759166)
			(xy 93.100394 -354.790697) (xy 93.049364 -354.814968) (xy 92.995313 -354.831449) (xy 92.939422 -354.839777)
			(xy 92.911168 -354.840286) (xy 92.883666 -354.839821) (xy 92.829232 -354.831924) (xy 92.776495 -354.816297)
			(xy 92.726546 -354.793264) (xy 92.68042 -354.763302) (xy 92.63907 -354.727031) (xy 92.620846 -354.706428)
			(xy 92.613988 -354.698046) (xy 92.594938 -354.688902) (xy 92.498926 -354.685092) (xy 92.479622 -354.692712)
			(xy 92.472002 -354.700332) (xy 92.450374 -354.720979) (xy 92.401929 -354.756021) (xy 92.348609 -354.783073)
			(xy 92.29172 -354.801472) (xy 92.232657 -354.810766) (xy 92.202762 -354.81133) (xy 92.1747 -354.810835)
			(xy 92.119184 -354.802595) (xy 92.065474 -354.786314) (xy 92.014727 -354.762341) (xy 91.968039 -354.731195)
			(xy 91.926415 -354.693547) (xy 91.890754 -354.650209) (xy 91.875864 -354.626418) (xy 91.86926 -354.61575)
			(xy 91.84767 -354.602796) (xy 91.73845 -354.5967) (xy 91.71559 -354.607368) (xy 91.70797 -354.617528)
			(xy 91.689791 -354.640507) (xy 91.647619 -354.681181) (xy 91.599726 -354.71493) (xy 91.547235 -354.740961)
			(xy 91.491383 -354.758662) (xy 91.433481 -354.767617) (xy 91.404186 -354.76815) (xy 91.374745 -354.767578)
			(xy 91.316562 -354.758542) (xy 91.260458 -354.740672) (xy 91.207767 -354.714393) (xy 91.15974 -354.680328)
			(xy 91.138248 -354.6602) (xy 91.131136 -354.653342) (xy 91.112848 -354.645976) (xy 91.02217 -354.645976)
			(xy 91.003882 -354.653342) (xy 90.99677 -354.6602) (xy 90.975265 -354.680314) (xy 90.927241 -354.714383)
			(xy 90.874554 -354.74067) (xy 90.818454 -354.758551) (xy 90.760272 -354.767602) (xy 90.730832 -354.76815)
			(xy 90.702652 -354.767668) (xy 90.64691 -354.759354) (xy 90.592996 -354.742931) (xy 90.542085 -354.718756)
			(xy 90.495283 -354.687356) (xy 90.453608 -354.649413) (xy 90.417969 -354.605753) (xy 90.389138 -354.557326)
			(xy 90.367745 -354.505184) (xy 90.354253 -354.450464) (xy 90.351102 -354.422456) (xy 90.34907 -354.402644)
			(xy 90.320368 -354.376228) (xy 89.897966 -354.376228) (xy 89.869264 -354.402644) (xy 89.867232 -354.422456)
			(xy 89.864083 -354.450461) (xy 89.850594 -354.505176) (xy 89.829201 -354.557311) (xy 89.800369 -354.605731)
			(xy 89.764727 -354.649382) (xy 89.72305 -354.687313) (xy 89.676246 -354.718699) (xy 89.625333 -354.742856)
			(xy 89.571419 -354.75926) (xy 89.515679 -354.767551) (xy 89.459325 -354.767551) (xy 89.403585 -354.75926)
			(xy 89.349671 -354.742856) (xy 89.298758 -354.718699) (xy 89.251954 -354.687313) (xy 89.210277 -354.649382)
			(xy 89.174635 -354.605731) (xy 89.145803 -354.557311) (xy 89.12441 -354.505176) (xy 89.110921 -354.450461)
			(xy 89.107772 -354.422456) (xy 89.10574 -354.402644) (xy 89.077038 -354.376228) (xy 89.03462 -354.376228)
			(xy 89.024597 -354.376637) (xy 89.006075 -354.384305) (xy 88.991901 -354.398482) (xy 88.984235 -354.417005)
			(xy 88.98382 -354.427028) (xy 88.98382 -354.429568) (xy 88.983315 -354.45682) (xy 88.975563 -354.510768)
			(xy 88.960211 -354.563065) (xy 88.937573 -354.612644) (xy 88.90811 -354.658497) (xy 88.87242 -354.699689)
			(xy 88.831232 -354.735383) (xy 88.785383 -354.764852) (xy 88.735806 -354.787496) (xy 88.683511 -354.802853)
			(xy 88.629563 -354.810612) (xy 88.602312 -354.811076) (xy 88.572261 -354.810494) (xy 88.512904 -354.80106)
			(xy 88.455759 -354.78244) (xy 88.402239 -354.755094) (xy 88.353666 -354.719697) (xy 88.332056 -354.698808)
			(xy 88.325452 -354.692204) (xy 88.308434 -354.684584) (xy 88.222328 -354.679504) (xy 88.204548 -354.685092)
			(xy 88.197182 -354.690934) (xy 88.176892 -354.706404) (xy 88.13298 -354.732385) (xy 88.086 -354.752287)
			(xy 88.036787 -354.765755) (xy 87.986219 -354.772551) (xy 87.960708 -354.772976) (xy 87.931827 -354.772419)
			(xy 87.874725 -354.763719) (xy 87.819589 -354.746503) (xy 87.767682 -354.721164) (xy 87.720192 -354.688283)
			(xy 87.698834 -354.668836) (xy 87.691976 -354.662486) (xy 87.674958 -354.655374) (xy 87.588852 -354.652834)
			(xy 87.571326 -354.65893) (xy 87.56396 -354.664772) (xy 87.543298 -354.681482) (xy 87.498197 -354.709584)
			(xy 87.449634 -354.731159) (xy 87.398549 -354.74579) (xy 87.345927 -354.753195) (xy 87.319358 -354.753672)
			(xy 87.292104 -354.753261) (xy 87.238152 -354.745498) (xy 87.185853 -354.730136) (xy 87.136274 -354.707487)
			(xy 87.090422 -354.678013) (xy 87.049231 -354.642314) (xy 87.01354 -354.601116) (xy 86.984076 -354.555258)
			(xy 86.961437 -354.505673) (xy 86.946085 -354.453372) (xy 86.938333 -354.399418) (xy 86.93785 -354.372164)
			(xy 67.925188 -354.372164) (xy 66.584322 -355.71303) (xy 66.566212 -355.730252) (xy 66.524653 -355.757995)
			(xy 66.478483 -355.777102) (xy 66.429474 -355.786842) (xy 66.40449 -355.787452) (xy 40.249094 -355.787452)
			(xy 40.239023 -355.78786) (xy 40.220424 -355.795591) (xy 40.213026 -355.802438) (xy 37.46627 -358.549194)
			(xy 40.988234 -358.549194) (xy 40.988686 -358.523273) (xy 40.995718 -358.471911) (xy 41.009638 -358.421973)
			(xy 41.030189 -358.374379) (xy 41.056993 -358.330005) (xy 41.089557 -358.289667) (xy 41.108122 -358.271572)
			(xy 41.11498 -358.264968) (xy 41.123108 -358.24795) (xy 41.129712 -358.16032) (xy 41.124124 -358.142286)
			(xy 41.118028 -358.134666) (xy 41.102545 -358.114386) (xy 41.076567 -358.070471) (xy 41.056669 -358.023487)
			(xy 41.043203 -357.974273) (xy 41.03641 -357.923704) (xy 41.035986 -357.898192) (xy 41.036451 -357.870822)
			(xy 41.044269 -357.816643) (xy 41.059759 -357.76414) (xy 41.082601 -357.714393) (xy 41.112325 -357.668426)
			(xy 41.129966 -357.647494) (xy 41.136062 -357.640382) (xy 41.142412 -357.623364) (xy 41.142412 -357.53802)
			(xy 41.136062 -357.521002) (xy 41.129966 -357.51389) (xy 41.112303 -357.492977) (xy 41.082596 -357.446998)
			(xy 41.059765 -357.397246) (xy 41.04428 -357.344741) (xy 41.036457 -357.290562) (xy 41.035986 -357.263192)
			(xy 41.036472 -357.235941) (xy 41.044228 -357.181993) (xy 41.059583 -357.129698) (xy 41.082225 -357.080121)
			(xy 41.111691 -357.034271) (xy 41.147382 -356.99308) (xy 41.188573 -356.957389) (xy 41.234423 -356.927923)
			(xy 41.284 -356.905281) (xy 41.336295 -356.889926) (xy 41.390243 -356.88217) (xy 41.444745 -356.88217)
			(xy 41.498693 -356.889926) (xy 41.550988 -356.905281) (xy 41.600565 -356.927923) (xy 41.646415 -356.957389)
			(xy 41.687606 -356.99308) (xy 41.723297 -357.034271) (xy 41.752763 -357.080121) (xy 41.775405 -357.129698)
			(xy 41.79076 -357.181993) (xy 41.798516 -357.235941) (xy 41.799002 -357.263192) (xy 41.798531 -357.290562)
			(xy 41.790714 -357.344741) (xy 41.775226 -357.397244) (xy 41.752386 -357.446991) (xy 41.722663 -357.492958)
			(xy 41.705022 -357.51389) (xy 41.698926 -357.521002) (xy 41.692576 -357.53802) (xy 41.692576 -357.623364)
			(xy 41.698926 -357.640382) (xy 41.705022 -357.647494) (xy 41.722675 -357.668415) (xy 41.752384 -357.714391)
			(xy 41.775217 -357.764141) (xy 41.790705 -357.816644) (xy 41.79853 -357.870822) (xy 41.799002 -357.898192)
			(xy 41.798529 -357.924112) (xy 41.7915 -357.975473) (xy 41.777584 -358.02541) (xy 41.757036 -358.073004)
			(xy 41.730236 -358.117379) (xy 41.697676 -358.157718) (xy 41.679114 -358.175814) (xy 41.672256 -358.182418)
			(xy 41.664128 -358.199436) (xy 41.657524 -358.287066) (xy 41.663112 -358.3051) (xy 41.669208 -358.31272)
			(xy 41.684676 -358.333012) (xy 41.710657 -358.376923) (xy 41.73056 -358.423903) (xy 41.744029 -358.473115)
			(xy 41.749099 -358.51084) (xy 43.554396 -358.51084) (xy 43.554825 -358.484919) (xy 43.561863 -358.433556)
			(xy 43.575788 -358.383618) (xy 43.596343 -358.336024) (xy 43.623151 -358.29165) (xy 43.655718 -358.251313)
			(xy 43.674284 -358.233218) (xy 43.681142 -358.226614) (xy 43.68927 -358.209596) (xy 43.695874 -358.121966)
			(xy 43.690286 -358.103932) (xy 43.68419 -358.096312) (xy 43.668737 -358.07601) (xy 43.642753 -358.032102)
			(xy 43.622847 -357.985124) (xy 43.609375 -357.935914) (xy 43.602575 -357.885348) (xy 43.602148 -357.859838)
			(xy 43.602625 -357.832468) (xy 43.610438 -357.778289) (xy 43.625924 -357.725785) (xy 43.648764 -357.676038)
			(xy 43.678487 -357.630072) (xy 43.696128 -357.60914) (xy 43.702224 -357.602028) (xy 43.708574 -357.58501)
			(xy 43.708574 -357.499666) (xy 43.702224 -357.482648) (xy 43.696128 -357.475536) (xy 43.678497 -357.454598)
			(xy 43.648783 -357.408627) (xy 43.625945 -357.358881) (xy 43.610452 -357.306382) (xy 43.602623 -357.252207)
			(xy 43.602148 -357.224838) (xy 43.602634 -357.197587) (xy 43.61039 -357.143639) (xy 43.625745 -357.091344)
			(xy 43.648387 -357.041767) (xy 43.677853 -356.995917) (xy 43.713544 -356.954726) (xy 43.754735 -356.919035)
			(xy 43.800585 -356.889569) (xy 43.850162 -356.866927) (xy 43.902457 -356.851572) (xy 43.956405 -356.843816)
			(xy 44.010907 -356.843816) (xy 44.064855 -356.851572) (xy 44.11715 -356.866927) (xy 44.166727 -356.889569)
			(xy 44.212577 -356.919035) (xy 44.253768 -356.954726) (xy 44.289459 -356.995917) (xy 44.318925 -357.041767)
			(xy 44.341567 -357.091344) (xy 44.356922 -357.143639) (xy 44.364678 -357.197587) (xy 44.365164 -357.224838)
			(xy 44.36467 -357.252207) (xy 44.356861 -357.306386) (xy 44.341378 -357.358889) (xy 44.318543 -357.408636)
			(xy 44.288823 -357.454604) (xy 44.271184 -357.475536) (xy 44.265088 -357.482648) (xy 44.258738 -357.499666)
			(xy 44.258738 -357.58501) (xy 44.265088 -357.602028) (xy 44.271184 -357.60914) (xy 44.288806 -357.630086)
			(xy 44.318521 -357.676055) (xy 44.34136 -357.725799) (xy 44.356855 -357.778296) (xy 44.364688 -357.83247)
			(xy 44.365164 -357.859838) (xy 44.364733 -357.885759) (xy 44.357697 -357.937123) (xy 44.343774 -357.987061)
			(xy 44.323218 -358.034655) (xy 44.29641 -358.079029) (xy 44.272612 -358.108504) (xy 47.49927 -358.108504)
			(xy 47.499749 -358.082584) (xy 47.506778 -358.031224) (xy 47.520694 -357.981287) (xy 47.54124 -357.933694)
			(xy 47.568039 -357.889318) (xy 47.600597 -357.848979) (xy 47.619158 -357.830882) (xy 47.626016 -357.824278)
			(xy 47.634144 -357.80726) (xy 47.640748 -357.71963) (xy 47.63516 -357.701596) (xy 47.629064 -357.693976)
			(xy 47.613591 -357.673689) (xy 47.587611 -357.629776) (xy 47.567709 -357.582795) (xy 47.554241 -357.533581)
			(xy 47.547447 -357.483013) (xy 47.547022 -357.457502) (xy 47.547484 -357.430132) (xy 47.555302 -357.375952)
			(xy 47.570792 -357.323449) (xy 47.593634 -357.273702) (xy 47.62336 -357.227735) (xy 47.641002 -357.206804)
			(xy 47.647098 -357.199692) (xy 47.653448 -357.182674) (xy 47.653448 -357.09733) (xy 47.647098 -357.080312)
			(xy 47.641002 -357.0732) (xy 47.62335 -357.052279) (xy 47.59364 -357.006303) (xy 47.570806 -356.956553)
			(xy 47.555318 -356.90405) (xy 47.547494 -356.849872) (xy 47.547022 -356.822502) (xy 47.547457 -356.795248)
			(xy 47.555215 -356.741294) (xy 47.570572 -356.688994) (xy 47.593217 -356.639412) (xy 47.622687 -356.593557)
			(xy 47.658384 -356.552364) (xy 47.69958 -356.51667) (xy 47.745437 -356.487203) (xy 47.79502 -356.464562)
			(xy 47.847322 -356.449209) (xy 47.901276 -356.441455) (xy 47.92853 -356.440994) (xy 47.957165 -356.441498)
			(xy 48.01379 -356.450062) (xy 48.0685 -356.466994) (xy 48.120064 -356.491913) (xy 48.167324 -356.52426)
			(xy 48.209219 -356.563306) (xy 48.244806 -356.608177) (xy 48.259492 -356.632764) (xy 48.264243 -356.640338)
			(xy 48.277941 -356.651811) (xy 48.294752 -356.657867) (xy 48.303688 -356.658164) (xy 48.391572 -356.658164)
			(xy 48.4005 -356.657828) (xy 48.417292 -356.651761) (xy 48.430994 -356.640315) (xy 48.435768 -356.632764)
			(xy 48.450459 -356.608179) (xy 48.486042 -356.563306) (xy 48.527934 -356.524256) (xy 48.575194 -356.491909)
			(xy 48.626758 -356.466992) (xy 48.681469 -356.450064) (xy 48.738095 -356.441506) (xy 48.76673 -356.440994)
			(xy 48.794101 -356.441444) (xy 48.848281 -356.449266) (xy 48.900784 -356.464759) (xy 48.95053 -356.487604)
			(xy 48.996497 -356.517332) (xy 49.017428 -356.534974) (xy 49.02454 -356.54107) (xy 49.041558 -356.54742)
			(xy 49.126902 -356.54742) (xy 49.14392 -356.54107) (xy 49.151032 -356.534974) (xy 49.171965 -356.517333)
			(xy 49.217933 -356.487609) (xy 49.267679 -356.464763) (xy 49.320181 -356.449267) (xy 49.374359 -356.441438)
			(xy 49.429101 -356.441438) (xy 49.483279 -356.449267) (xy 49.535781 -356.464763) (xy 49.585527 -356.487609)
			(xy 49.631495 -356.517333) (xy 49.652428 -356.534974) (xy 49.65954 -356.54107) (xy 49.676558 -356.54742)
			(xy 49.761902 -356.54742) (xy 49.77892 -356.54107) (xy 49.786032 -356.534974) (xy 49.806965 -356.517333)
			(xy 49.852933 -356.487609) (xy 49.902679 -356.464763) (xy 49.955181 -356.449267) (xy 50.009359 -356.441438)
			(xy 50.064101 -356.441438) (xy 50.118279 -356.449267) (xy 50.170781 -356.464763) (xy 50.220527 -356.487609)
			(xy 50.266495 -356.517333) (xy 50.287428 -356.534974) (xy 50.29454 -356.54107) (xy 50.311558 -356.54742)
			(xy 50.396902 -356.54742) (xy 50.41392 -356.54107) (xy 50.421032 -356.534974) (xy 50.441976 -356.517349)
			(xy 50.487946 -356.487636) (xy 50.53769 -356.464798) (xy 50.590188 -356.449303) (xy 50.644362 -356.441471)
			(xy 50.67173 -356.440994) (xy 50.698982 -356.44145) (xy 50.752931 -356.449211) (xy 50.805226 -356.46457)
			(xy 50.854804 -356.487214) (xy 50.900654 -356.516684) (xy 50.941844 -356.552379) (xy 50.977535 -356.593571)
			(xy 51.007001 -356.639424) (xy 51.029642 -356.689004) (xy 51.044996 -356.7413) (xy 51.052752 -356.79525)
			(xy 51.053238 -356.822502) (xy 51.052788 -356.849873) (xy 51.044969 -356.904053) (xy 51.029477 -356.956557)
			(xy 51.006631 -357.006304) (xy 50.976902 -357.052269) (xy 50.959258 -357.0732) (xy 50.953162 -357.080312)
			(xy 50.946812 -357.09733) (xy 50.946812 -357.182674) (xy 50.953162 -357.199692) (xy 50.959258 -357.206804)
			(xy 50.976906 -357.227729) (xy 51.006618 -357.273703) (xy 51.029453 -357.323452) (xy 51.044942 -357.375955)
			(xy 51.052766 -357.430132) (xy 51.053238 -357.457502) (xy 51.052761 -357.483422) (xy 51.045731 -357.534782)
			(xy 51.031815 -357.584719) (xy 51.011268 -357.632312) (xy 50.984469 -357.676687) (xy 50.951911 -357.717027)
			(xy 50.93335 -357.735124) (xy 50.926492 -357.741728) (xy 50.918364 -357.758746) (xy 50.91176 -357.846376)
			(xy 50.917348 -357.86441) (xy 50.923444 -357.87203) (xy 50.938921 -357.892314) (xy 50.964901 -357.936228)
			(xy 50.984801 -357.98321) (xy 50.998268 -358.032424) (xy 51.005062 -358.082993) (xy 51.005486 -358.108504)
			(xy 51.005048 -358.135758) (xy 50.99729 -358.189711) (xy 50.981933 -358.242011) (xy 50.959288 -358.291592)
			(xy 50.929818 -358.337446) (xy 50.894121 -358.37864) (xy 50.852926 -358.414333) (xy 50.807069 -358.4438)
			(xy 50.757486 -358.466442) (xy 50.705185 -358.481796) (xy 50.651232 -358.48955) (xy 50.623978 -358.490012)
			(xy 50.596607 -358.489556) (xy 50.542428 -358.481735) (xy 50.489925 -358.466244) (xy 50.440178 -358.4434)
			(xy 50.394212 -358.413674) (xy 50.37328 -358.396032) (xy 50.366168 -358.389936) (xy 50.34915 -358.383586)
			(xy 50.263806 -358.383586) (xy 50.246788 -358.389936) (xy 50.239676 -358.396032) (xy 50.218743 -358.413673)
			(xy 50.172775 -358.443397) (xy 50.123029 -358.466243) (xy 50.070527 -358.481739) (xy 50.016349 -358.489568)
			(xy 49.961607 -358.489568) (xy 49.907429 -358.481739) (xy 49.854927 -358.466243) (xy 49.805181 -358.443397)
			(xy 49.759213 -358.413673) (xy 49.73828 -358.396032) (xy 49.731168 -358.389936) (xy 49.71415 -358.383586)
			(xy 49.628806 -358.383586) (xy 49.611788 -358.389936) (xy 49.604676 -358.396032) (xy 49.583743 -358.413673)
			(xy 49.537775 -358.443397) (xy 49.488029 -358.466243) (xy 49.435527 -358.481739) (xy 49.381349 -358.489568)
			(xy 49.326607 -358.489568) (xy 49.272429 -358.481739) (xy 49.219927 -358.466243) (xy 49.170181 -358.443397)
			(xy 49.124213 -358.413673) (xy 49.10328 -358.396032) (xy 49.096168 -358.389936) (xy 49.07915 -358.383586)
			(xy 48.993806 -358.383586) (xy 48.976788 -358.389936) (xy 48.969676 -358.396032) (xy 48.94873 -358.413654)
			(xy 48.902761 -358.443367) (xy 48.853017 -358.466206) (xy 48.800519 -358.481701) (xy 48.746346 -358.489535)
			(xy 48.718978 -358.490012) (xy 48.690344 -358.489499) (xy 48.633719 -358.480936) (xy 48.57901 -358.464005)
			(xy 48.527446 -358.439088) (xy 48.480185 -358.406743) (xy 48.43829 -358.367697) (xy 48.402702 -358.322829)
			(xy 48.388016 -358.298242) (xy 48.383258 -358.290673) (xy 48.369563 -358.279199) (xy 48.352755 -358.273141)
			(xy 48.34382 -358.272842) (xy 48.255936 -358.272842) (xy 48.247008 -358.273181) (xy 48.230216 -358.279246)
			(xy 48.216514 -358.290691) (xy 48.21174 -358.298242) (xy 48.197046 -358.322824) (xy 48.161463 -358.367698)
			(xy 48.119571 -358.406747) (xy 48.072312 -358.439094) (xy 48.020748 -358.464012) (xy 47.966039 -358.480941)
			(xy 47.909413 -358.4895) (xy 47.880778 -358.490012) (xy 47.853526 -358.489543) (xy 47.799578 -358.481783)
			(xy 47.747283 -358.466426) (xy 47.697706 -358.443782) (xy 47.651856 -358.414314) (xy 47.610666 -358.378621)
			(xy 47.574975 -358.337429) (xy 47.545509 -358.291578) (xy 47.522868 -358.242) (xy 47.507513 -358.189704)
			(xy 47.499756 -358.135756) (xy 47.49927 -358.108504) (xy 44.272612 -358.108504) (xy 44.263842 -358.119366)
			(xy 44.245276 -358.13746) (xy 44.238418 -358.144064) (xy 44.23029 -358.161082) (xy 44.223686 -358.248712)
			(xy 44.229274 -358.266746) (xy 44.23537 -358.274366) (xy 44.250822 -358.294669) (xy 44.276804 -358.338578)
			(xy 44.296709 -358.385555) (xy 44.310182 -358.434765) (xy 44.316984 -358.48533) (xy 44.317412 -358.51084)
			(xy 44.316847 -358.539303) (xy 44.308379 -358.595597) (xy 44.291638 -358.650006) (xy 44.266995 -358.701322)
			(xy 44.234998 -358.748406) (xy 44.216066 -358.769666) (xy 44.2087 -358.77754) (xy 44.202096 -358.797352)
			(xy 44.209716 -358.893618) (xy 44.219622 -358.911906) (xy 44.228258 -358.918764) (xy 44.250665 -358.936951)
			(xy 44.290263 -358.978928) (xy 44.323086 -359.026392) (xy 44.348384 -359.078259) (xy 44.36558 -359.133345)
			(xy 44.374282 -359.190392) (xy 44.374816 -359.219246) (xy 44.37433 -359.246497) (xy 44.366574 -359.300445)
			(xy 44.351219 -359.35274) (xy 44.328577 -359.402317) (xy 44.299111 -359.448167) (xy 44.26342 -359.489358)
			(xy 44.222229 -359.525049) (xy 44.176379 -359.554515) (xy 44.126802 -359.577157) (xy 44.074507 -359.592512)
			(xy 44.020559 -359.600268) (xy 43.966057 -359.600268) (xy 43.912109 -359.592512) (xy 43.859814 -359.577157)
			(xy 43.810237 -359.554515) (xy 43.764387 -359.525049) (xy 43.723196 -359.489358) (xy 43.687505 -359.448167)
			(xy 43.658039 -359.402317) (xy 43.635397 -359.35274) (xy 43.620042 -359.300445) (xy 43.612286 -359.246497)
			(xy 43.6118 -359.219246) (xy 43.612354 -359.190782) (xy 43.620824 -359.134488) (xy 43.637567 -359.080079)
			(xy 43.662213 -359.028763) (xy 43.694212 -358.98168) (xy 43.713146 -358.96042) (xy 43.720512 -358.952546)
			(xy 43.727116 -358.932734) (xy 43.719496 -358.836468) (xy 43.70959 -358.81818) (xy 43.700954 -358.811322)
			(xy 43.678543 -358.79314) (xy 43.638944 -358.751162) (xy 43.606122 -358.703697) (xy 43.580824 -358.65183)
			(xy 43.563629 -358.596743) (xy 43.554929 -358.539694) (xy 43.554396 -358.51084) (xy 41.749099 -358.51084)
			(xy 41.750825 -358.523683) (xy 41.75125 -358.549194) (xy 41.750733 -358.577659) (xy 41.742256 -358.633955)
			(xy 41.725505 -358.688366) (xy 41.700851 -358.739682) (xy 41.668842 -358.786762) (xy 41.649904 -358.80802)
			(xy 41.642538 -358.815894) (xy 41.635934 -358.835706) (xy 41.643554 -358.931972) (xy 41.65346 -358.95026)
			(xy 41.662096 -358.957118) (xy 41.684516 -358.97529) (xy 41.724116 -359.017269) (xy 41.756939 -359.064735)
			(xy 41.782236 -359.116605) (xy 41.799428 -359.171694) (xy 41.808123 -359.228745) (xy 41.808654 -359.2576)
			(xy 41.808168 -359.284851) (xy 41.800412 -359.338799) (xy 41.785057 -359.391094) (xy 41.762415 -359.440671)
			(xy 41.732949 -359.486521) (xy 41.697258 -359.527712) (xy 41.656067 -359.563403) (xy 41.610217 -359.592869)
			(xy 41.56064 -359.615511) (xy 41.508345 -359.630866) (xy 41.454397 -359.638622) (xy 41.399895 -359.638622)
			(xy 41.345947 -359.630866) (xy 41.293652 -359.615511) (xy 41.244075 -359.592869) (xy 41.198225 -359.563403)
			(xy 41.157034 -359.527712) (xy 41.121343 -359.486521) (xy 41.091877 -359.440671) (xy 41.069235 -359.391094)
			(xy 41.05388 -359.338799) (xy 41.046124 -359.284851) (xy 41.045638 -359.2576) (xy 41.046154 -359.229135)
			(xy 41.054632 -359.172839) (xy 41.071384 -359.118428) (xy 41.096038 -359.067113) (xy 41.128046 -359.020032)
			(xy 41.146984 -358.998774) (xy 41.15435 -358.9909) (xy 41.160954 -358.971088) (xy 41.153334 -358.874822)
			(xy 41.143428 -358.856534) (xy 41.134792 -358.849676) (xy 41.112367 -358.831511) (xy 41.072767 -358.78953)
			(xy 41.039945 -358.742062) (xy 41.01465 -358.690191) (xy 40.997459 -358.635101) (xy 40.988764 -358.578049)
			(xy 40.988234 -358.549194) (xy 37.46627 -358.549194) (xy 37.289232 -358.726232) (xy 37.271174 -358.743533)
			(xy 37.22962 -358.771348) (xy 37.183437 -358.790521) (xy 37.134402 -358.800316) (xy 37.1094 -358.800908)
			(xy 36.959794 -358.800908) (xy 36.949771 -358.801315) (xy 36.931253 -358.808988) (xy 36.91708 -358.823165)
			(xy 36.909412 -358.841685) (xy 36.908994 -358.851708) (xy 36.908994 -358.868218) (xy 36.928552 -358.895142)
			(xy 36.944554 -358.899968) (xy 36.970024 -358.908457) (xy 37.018461 -358.931614) (xy 37.063176 -358.96133)
			(xy 37.103285 -358.997018) (xy 37.137998 -359.037974) (xy 37.166629 -359.083391) (xy 37.188614 -359.132371)
			(xy 37.203518 -359.183949) (xy 37.211048 -359.237106) (xy 37.211508 -359.26395) (xy 37.211061 -359.290906)
			(xy 37.203452 -359.344279) (xy 37.188408 -359.39605) (xy 37.166228 -359.445189) (xy 37.137352 -359.490717)
			(xy 37.102357 -359.531728) (xy 37.061938 -359.567406) (xy 37.016901 -359.59704) (xy 36.968141 -359.620041)
			(xy 36.942522 -359.62844) (xy 36.926266 -359.63352) (xy 36.906708 -359.66019) (xy 36.906708 -365.28883)
			(xy 36.9063 -365.314506) (xy 36.898906 -365.365325) (xy 36.88429 -365.414554) (xy 36.862755 -365.461174)
			(xy 36.834749 -365.504218) (xy 36.80085 -365.542793) (xy 36.761763 -365.5761) (xy 36.718297 -365.603447)
			(xy 36.671355 -365.624269) (xy 36.621908 -365.638133) (xy 36.570983 -365.644752) (xy 36.519636 -365.643988)
			(xy 36.494212 -365.640366) (xy 36.493704 -365.640366) (xy 36.471606 -365.635794) (xy 36.469828 -365.635286)
			(xy 36.463424 -365.634021) (xy 36.450446 -365.632619) (xy 36.44392 -365.632492) (xy 36.443412 -365.632492)
			(xy 36.426691 -365.632999) (xy 36.394388 -365.641652) (xy 36.365426 -365.658371) (xy 36.341778 -365.682016)
			(xy 36.325056 -365.710977) (xy 36.316401 -365.743279) (xy 36.315904 -365.76) (xy 36.316238 -365.773521)
			(xy 36.321925 -365.799958) (xy 36.333043 -365.824609) (xy 36.340796 -365.835692) (xy 36.34105 -365.835946)
			(xy 36.39693 -365.911892) (xy 36.40201 -365.919411) (xy 36.406949 -365.93686) (xy 36.406582 -365.945928)
			(xy 36.392612 -366.13338) (xy 36.391519 -366.142435) (xy 36.383844 -366.158966) (xy 36.377626 -366.165638)
			(xy 36.18484 -366.358424) (xy 36.182061 -366.361132) (xy 36.175806 -366.36572) (xy 36.172394 -366.367568)
			(xy 36.101274 -366.404398) (xy 36.0976 -366.406211) (xy 36.089814 -366.40876) (xy 36.08578 -366.409478)
			(xy 36.046664 -366.415574) (xy 36.045648 -366.415828) (xy 36.030447 -366.418949) (xy 36.002121 -366.431608)
			(xy 35.977683 -366.450724) (xy 35.958578 -366.47517) (xy 35.945932 -366.503502) (xy 35.942778 -366.518698)
			(xy 35.942524 -366.519714) (xy 35.936428 -366.55883) (xy 35.935715 -366.562865) (xy 35.933166 -366.570652)
			(xy 35.931348 -366.574324) (xy 35.894518 -366.645444) (xy 35.892656 -366.648846) (xy 35.888063 -366.655095)
			(xy 35.885374 -366.65789) (xy 35.835336 -366.708182) (xy 35.816643 -366.726066) (xy 35.774392 -366.755912)
			(xy 35.727715 -366.778211) (xy 35.677947 -366.792323) (xy 35.626513 -366.797845) (xy 35.574884 -366.794619)
			(xy 35.549586 -366.789208) (xy 35.521049 -366.782864) (xy 35.462992 -366.775989) (xy 35.433762 -366.775492)
			(xy 35.433 -366.775492) (xy 35.402269 -366.775956) (xy 35.341255 -366.783365) (xy 35.281579 -366.798073)
			(xy 35.224111 -366.819868) (xy 35.169689 -366.848431) (xy 35.119107 -366.883345) (xy 35.073102 -366.924102)
			(xy 35.032345 -366.970107) (xy 34.997431 -367.020689) (xy 34.968868 -367.075111) (xy 34.947073 -367.132579)
			(xy 34.932365 -367.192255) (xy 34.924956 -367.253269) (xy 34.924492 -367.284) (xy 35.050982 -367.284)
			(xy 35.055053 -367.228378) (xy 35.067179 -367.173941) (xy 35.087102 -367.12185) (xy 35.114398 -367.073215)
			(xy 35.148484 -367.029072) (xy 35.188633 -366.990363) (xy 35.233991 -366.957912) (xy 35.283591 -366.932411)
			(xy 35.336375 -366.914404) (xy 35.391218 -366.904274) (xy 35.446952 -366.902237) (xy 35.502389 -366.908337)
			(xy 35.556346 -366.922443) (xy 35.607675 -366.944255) (xy 35.655281 -366.973309) (xy 35.698149 -367.008984)
			(xy 35.735366 -367.050521) (xy 35.766139 -367.097034) (xy 35.789811 -367.147531) (xy 35.805879 -367.200938)
			(xy 35.813999 -367.256114) (xy 35.814508 -367.284) (xy 35.813999 -367.311886) (xy 35.805879 -367.367062)
			(xy 35.789811 -367.420469) (xy 35.766139 -367.470966) (xy 35.735366 -367.517479) (xy 35.698149 -367.559016)
			(xy 35.655281 -367.594691) (xy 35.607675 -367.623745) (xy 35.556346 -367.645557) (xy 35.502389 -367.659663)
			(xy 35.446952 -367.665763) (xy 35.391218 -367.663726) (xy 35.336375 -367.653596) (xy 35.283591 -367.635589)
			(xy 35.233991 -367.610088) (xy 35.188633 -367.577637) (xy 35.148484 -367.538928) (xy 35.114398 -367.494785)
			(xy 35.087102 -367.44615) (xy 35.067179 -367.394059) (xy 35.055053 -367.339622) (xy 35.050982 -367.284)
			(xy 34.924492 -367.284) (xy 34.924492 -367.284762) (xy 34.92498 -367.313992) (xy 34.931859 -367.372049)
			(xy 34.938208 -367.400586) (xy 34.943594 -367.425889) (xy 34.946818 -367.477514) (xy 34.941297 -367.528945)
			(xy 34.92719 -367.578711) (xy 34.904899 -367.625387) (xy 34.875062 -367.667641) (xy 34.857182 -367.686336)
			(xy 34.802572 -367.740692) (xy 34.796984 -367.74882) (xy 34.77133 -367.774728) (xy 34.754016 -367.79134)
			(xy 34.715191 -367.819531) (xy 34.672438 -367.841309) (xy 34.626807 -367.856139) (xy 34.57942 -367.863657)
			(xy 34.55543 -367.864136) (xy 33.308036 -367.864136) (xy 33.284365 -367.863692) (xy 33.237589 -367.856401)
			(xy 33.192501 -367.841974) (xy 33.150181 -367.820756) (xy 33.111647 -367.793256) (xy 33.094422 -367.777014)
			(xy 33.092136 -367.774474) (xy 33.091882 -367.774474) (xy 32.879538 -367.561876) (xy 32.863087 -367.544625)
			(xy 32.835169 -367.505991) (xy 32.813593 -367.463489) (xy 32.798882 -367.418151) (xy 32.791392 -367.371078)
			(xy 32.790892 -367.347246) (xy 32.790892 -361.85221) (xy 32.78759 -361.848908) (xy 29.726128 -361.848908)
			(xy 29.702446 -361.848482) (xy 29.655654 -361.841137) (xy 29.610559 -361.82665) (xy 29.568244 -361.805369)
			(xy 29.529726 -361.777805) (xy 29.512514 -361.761532) (xy 29.510228 -361.758992) (xy 29.509974 -361.758992)
			(xy 28.415488 -360.664252) (xy 28.399076 -360.646981) (xy 28.371224 -360.608329) (xy 28.349705 -360.565825)
			(xy 28.33504 -360.520496) (xy 28.327584 -360.473442) (xy 28.327096 -360.449622) (xy 28.327096 -358.670098)
			(xy 28.326745 -358.660925) (xy 28.32025 -358.643768) (xy 28.308102 -358.630021) (xy 28.300172 -358.625394)
			(xy 28.208986 -358.576372) (xy 28.181046 -358.577642) (xy 28.169362 -358.585262) (xy 28.145832 -358.600185)
			(xy 28.095383 -358.62383) (xy 28.042029 -358.639881) (xy 27.986908 -358.647997) (xy 27.95905 -358.648508)
			(xy 27.931798 -358.647998) (xy 27.877849 -358.640248) (xy 27.825552 -358.624898) (xy 27.775972 -358.602262)
			(xy 27.730119 -358.572799) (xy 27.688926 -358.53711) (xy 27.653231 -358.495921) (xy 27.623762 -358.450072)
			(xy 27.601119 -358.400495) (xy 27.585763 -358.3482) (xy 27.578005 -358.294252) (xy 27.577542 -358.267)
			(xy 27.578092 -358.237813) (xy 27.586992 -358.18012) (xy 27.604568 -358.124454) (xy 27.630413 -358.072111)
			(xy 27.663922 -358.024312) (xy 27.704316 -357.982169) (xy 27.727148 -357.963978) (xy 27.737054 -357.956612)
			(xy 27.747468 -357.934768) (xy 27.744674 -357.828088) (xy 27.733244 -357.806752) (xy 27.723084 -357.799894)
			(xy 27.701646 -357.784578) (xy 27.662848 -357.748932) (xy 27.629322 -357.708287) (xy 27.601704 -357.663419)
			(xy 27.580519 -357.615178) (xy 27.566171 -357.564481) (xy 27.558932 -357.512294) (xy 27.558492 -357.48595)
			(xy 23.97432 -357.48595) (xy 23.978811 -357.495531) (xy 23.994879 -357.548938) (xy 24.002999 -357.604114)
			(xy 24.003508 -357.632) (xy 24.002999 -357.659886) (xy 23.994879 -357.715062) (xy 23.978811 -357.768469)
			(xy 23.955139 -357.818966) (xy 23.924366 -357.865479) (xy 23.887149 -357.907016) (xy 23.844281 -357.942691)
			(xy 23.796675 -357.971745) (xy 23.745346 -357.993557) (xy 23.691389 -358.007663) (xy 23.635952 -358.013763)
			(xy 23.580218 -358.011726) (xy 23.525375 -358.001596) (xy 23.472591 -357.983589) (xy 23.422991 -357.958088)
			(xy 23.377633 -357.925637) (xy 23.337484 -357.886928) (xy 23.303398 -357.842785) (xy 23.276102 -357.79415)
			(xy 23.256179 -357.742059) (xy 23.244053 -357.687622) (xy 23.239982 -357.632) (xy 20.596338 -357.632)
			(xy 20.590687 -357.635449) (xy 20.539358 -357.657261) (xy 20.485401 -357.671367) (xy 20.429964 -357.677467)
			(xy 20.37423 -357.67543) (xy 20.319387 -357.6653) (xy 20.266603 -357.647293) (xy 20.217003 -357.621792)
			(xy 20.171645 -357.589341) (xy 20.131496 -357.550632) (xy 20.09741 -357.506489) (xy 20.070114 -357.457854)
			(xy 20.050191 -357.405763) (xy 20.038065 -357.351326) (xy 20.033994 -357.295704) (xy 19.016472 -357.295704)
			(xy 19.016472 -358.775) (xy 23.257508 -358.775) (xy 23.261579 -358.719378) (xy 23.273705 -358.664941)
			(xy 23.293628 -358.61285) (xy 23.320924 -358.564215) (xy 23.35501 -358.520072) (xy 23.395159 -358.481363)
			(xy 23.440517 -358.448912) (xy 23.490117 -358.423411) (xy 23.542901 -358.405404) (xy 23.597744 -358.395274)
			(xy 23.653478 -358.393237) (xy 23.708915 -358.399337) (xy 23.762872 -358.413443) (xy 23.814201 -358.435255)
			(xy 23.861807 -358.464309) (xy 23.904675 -358.499984) (xy 23.941892 -358.541521) (xy 23.972665 -358.588034)
			(xy 23.996337 -358.638531) (xy 24.012405 -358.691938) (xy 24.020525 -358.747114) (xy 24.021034 -358.775)
			(xy 24.020525 -358.802886) (xy 24.012405 -358.858062) (xy 23.996337 -358.911469) (xy 23.972665 -358.961966)
			(xy 23.941892 -359.008479) (xy 23.904675 -359.050016) (xy 23.861807 -359.085691) (xy 23.814201 -359.114745)
			(xy 23.762872 -359.136557) (xy 23.708915 -359.150663) (xy 23.653478 -359.156763) (xy 23.597744 -359.154726)
			(xy 23.542901 -359.144596) (xy 23.490117 -359.126589) (xy 23.440517 -359.101088) (xy 23.395159 -359.068637)
			(xy 23.35501 -359.029928) (xy 23.320924 -358.985785) (xy 23.293628 -358.93715) (xy 23.273705 -358.885059)
			(xy 23.261579 -358.830622) (xy 23.257508 -358.775) (xy 19.016472 -358.775) (xy 19.016472 -359.918)
			(xy 23.239982 -359.918) (xy 23.244053 -359.862378) (xy 23.256179 -359.807941) (xy 23.276102 -359.75585)
			(xy 23.303398 -359.707215) (xy 23.337484 -359.663072) (xy 23.377633 -359.624363) (xy 23.422991 -359.591912)
			(xy 23.472591 -359.566411) (xy 23.525375 -359.548404) (xy 23.580218 -359.538274) (xy 23.635952 -359.536237)
			(xy 23.691389 -359.542337) (xy 23.745346 -359.556443) (xy 23.796675 -359.578255) (xy 23.844281 -359.607309)
			(xy 23.887149 -359.642984) (xy 23.924366 -359.684521) (xy 23.955139 -359.731034) (xy 23.978811 -359.781531)
			(xy 23.994879 -359.834938) (xy 24.002999 -359.890114) (xy 24.003508 -359.918) (xy 24.002999 -359.945886)
			(xy 23.994879 -360.001062) (xy 23.978811 -360.054469) (xy 23.955139 -360.104966) (xy 23.924366 -360.151479)
			(xy 23.887149 -360.193016) (xy 23.844281 -360.228691) (xy 23.796675 -360.257745) (xy 23.745346 -360.279557)
			(xy 23.691389 -360.293663) (xy 23.635952 -360.299763) (xy 23.580218 -360.297726) (xy 23.525375 -360.287596)
			(xy 23.472591 -360.269589) (xy 23.422991 -360.244088) (xy 23.377633 -360.211637) (xy 23.337484 -360.172928)
			(xy 23.303398 -360.128785) (xy 23.276102 -360.08015) (xy 23.256179 -360.028059) (xy 23.244053 -359.973622)
			(xy 23.239982 -359.918) (xy 19.016472 -359.918) (xy 19.016472 -361.061) (xy 23.239982 -361.061) (xy 23.244053 -361.005378)
			(xy 23.256179 -360.950941) (xy 23.276102 -360.89885) (xy 23.303398 -360.850215) (xy 23.337484 -360.806072)
			(xy 23.377633 -360.767363) (xy 23.422991 -360.734912) (xy 23.472591 -360.709411) (xy 23.525375 -360.691404)
			(xy 23.580218 -360.681274) (xy 23.635952 -360.679237) (xy 23.691389 -360.685337) (xy 23.745346 -360.699443)
			(xy 23.796675 -360.721255) (xy 23.844281 -360.750309) (xy 23.887149 -360.785984) (xy 23.924366 -360.827521)
			(xy 23.955139 -360.874034) (xy 23.978811 -360.924531) (xy 23.994879 -360.977938) (xy 24.002999 -361.033114)
			(xy 24.003508 -361.061) (xy 24.002999 -361.088886) (xy 23.994879 -361.144062) (xy 23.978811 -361.197469)
			(xy 23.955139 -361.247966) (xy 23.924366 -361.294479) (xy 23.887149 -361.336016) (xy 23.844281 -361.371691)
			(xy 23.796675 -361.400745) (xy 23.745346 -361.422557) (xy 23.691389 -361.436663) (xy 23.635952 -361.442763)
			(xy 23.580218 -361.440726) (xy 23.525375 -361.430596) (xy 23.472591 -361.412589) (xy 23.422991 -361.387088)
			(xy 23.377633 -361.354637) (xy 23.337484 -361.315928) (xy 23.303398 -361.271785) (xy 23.276102 -361.22315)
			(xy 23.256179 -361.171059) (xy 23.244053 -361.116622) (xy 23.239982 -361.061) (xy 19.016472 -361.061)
			(xy 19.016472 -362.56214) (xy 20.2057 -362.56214) (xy 20.206189 -362.533998) (xy 20.214472 -362.478327)
			(xy 20.230847 -362.424478) (xy 20.25496 -362.373621) (xy 20.286288 -362.326862) (xy 20.324148 -362.285215)
			(xy 20.367719 -362.249585) (xy 20.391628 -362.234734) (xy 20.40394 -362.226789) (xy 20.423742 -362.205208)
			(xy 20.436612 -362.178897) (xy 20.441493 -362.150016) (xy 20.437983 -362.120937) (xy 20.426371 -362.094048)
			(xy 20.40761 -362.071555) (xy 20.395692 -362.06303) (xy 20.373663 -362.047776) (xy 20.333696 -362.012087)
			(xy 20.299118 -361.971155) (xy 20.27061 -361.925787) (xy 20.248733 -361.876874) (xy 20.233917 -361.825381)
			(xy 20.226455 -361.772321) (xy 20.22602 -361.74553) (xy 20.226506 -361.718279) (xy 20.234262 -361.664331)
			(xy 20.249617 -361.612036) (xy 20.272259 -361.562459) (xy 20.301725 -361.516609) (xy 20.337416 -361.475418)
			(xy 20.378607 -361.439727) (xy 20.424457 -361.410261) (xy 20.474034 -361.387619) (xy 20.526329 -361.372264)
			(xy 20.580277 -361.364508) (xy 20.634779 -361.364508) (xy 20.688727 -361.372264) (xy 20.741022 -361.387619)
			(xy 20.790599 -361.410261) (xy 20.836449 -361.439727) (xy 20.87764 -361.475418) (xy 20.913331 -361.516609)
			(xy 20.942797 -361.562459) (xy 20.965439 -361.612036) (xy 20.980794 -361.664331) (xy 20.98855 -361.718279)
			(xy 20.989036 -361.74553) (xy 20.988554 -361.773673) (xy 20.980275 -361.829345) (xy 20.9639 -361.883196)
			(xy 20.939786 -361.934054) (xy 20.908457 -361.980814) (xy 20.870594 -362.02246) (xy 20.827019 -362.058086)
			(xy 20.803108 -362.072936) (xy 20.790822 -362.080919) (xy 20.771014 -362.10249) (xy 20.758138 -362.128793)
			(xy 20.753253 -362.157668) (xy 20.756759 -362.186743) (xy 20.76421 -362.204) (xy 23.239982 -362.204)
			(xy 23.244053 -362.148378) (xy 23.256179 -362.093941) (xy 23.276102 -362.04185) (xy 23.303398 -361.993215)
			(xy 23.337484 -361.949072) (xy 23.377633 -361.910363) (xy 23.422991 -361.877912) (xy 23.472591 -361.852411)
			(xy 23.525375 -361.834404) (xy 23.580218 -361.824274) (xy 23.635952 -361.822237) (xy 23.691389 -361.828337)
			(xy 23.745346 -361.842443) (xy 23.796675 -361.864255) (xy 23.844281 -361.893309) (xy 23.887149 -361.928984)
			(xy 23.924366 -361.970521) (xy 23.955139 -362.017034) (xy 23.978811 -362.067531) (xy 23.994879 -362.120938)
			(xy 24.002999 -362.176114) (xy 24.003508 -362.204) (xy 24.002999 -362.231886) (xy 23.994879 -362.287062)
			(xy 23.978811 -362.340469) (xy 23.955139 -362.390966) (xy 23.924366 -362.437479) (xy 23.887149 -362.479016)
			(xy 23.844281 -362.514691) (xy 23.796675 -362.543745) (xy 23.745346 -362.565557) (xy 23.691389 -362.579663)
			(xy 23.635952 -362.585763) (xy 23.580218 -362.583726) (xy 23.525375 -362.573596) (xy 23.472591 -362.555589)
			(xy 23.422991 -362.530088) (xy 23.377633 -362.497637) (xy 23.337484 -362.458928) (xy 23.303398 -362.414785)
			(xy 23.276102 -362.36615) (xy 23.256179 -362.314059) (xy 23.244053 -362.259622) (xy 23.239982 -362.204)
			(xy 20.76421 -362.204) (xy 20.768368 -362.213629) (xy 20.787127 -362.236118) (xy 20.799044 -362.24464)
			(xy 20.821091 -362.25987) (xy 20.861061 -362.29556) (xy 20.895639 -362.336495) (xy 20.924146 -362.381868)
			(xy 20.946021 -362.430785) (xy 20.960831 -362.482283) (xy 20.968286 -362.535347) (xy 20.968716 -362.56214)
			(xy 20.96823 -362.589391) (xy 20.960474 -362.643339) (xy 20.952768 -362.669582) (xy 25.545286 -362.669582)
			(xy 25.549357 -362.61396) (xy 25.561483 -362.559523) (xy 25.581406 -362.507432) (xy 25.608702 -362.458797)
			(xy 25.642788 -362.414654) (xy 25.682937 -362.375945) (xy 25.728295 -362.343494) (xy 25.777895 -362.317993)
			(xy 25.830679 -362.299986) (xy 25.885522 -362.289856) (xy 25.941256 -362.287819) (xy 25.996693 -362.293919)
			(xy 26.05065 -362.308025) (xy 26.101979 -362.329837) (xy 26.149585 -362.358891) (xy 26.192453 -362.394566)
			(xy 26.22967 -362.436103) (xy 26.260443 -362.482616) (xy 26.284115 -362.533113) (xy 26.300183 -362.58652)
			(xy 26.308303 -362.641696) (xy 26.308812 -362.669582) (xy 26.308303 -362.697468) (xy 26.300183 -362.752644)
			(xy 26.284115 -362.806051) (xy 26.260443 -362.856548) (xy 26.22967 -362.903061) (xy 26.192453 -362.944598)
			(xy 26.149585 -362.980273) (xy 26.101979 -363.009327) (xy 26.05065 -363.031139) (xy 25.996693 -363.045245)
			(xy 25.941256 -363.051345) (xy 25.885522 -363.049308) (xy 25.830679 -363.039178) (xy 25.777895 -363.021171)
			(xy 25.728295 -362.99567) (xy 25.682937 -362.963219) (xy 25.642788 -362.92451) (xy 25.608702 -362.880367)
			(xy 25.581406 -362.831732) (xy 25.561483 -362.779641) (xy 25.549357 -362.725204) (xy 25.545286 -362.669582)
			(xy 20.952768 -362.669582) (xy 20.945119 -362.695634) (xy 20.922477 -362.745211) (xy 20.893011 -362.791061)
			(xy 20.85732 -362.832252) (xy 20.816129 -362.867943) (xy 20.770279 -362.897409) (xy 20.720702 -362.920051)
			(xy 20.668407 -362.935406) (xy 20.614459 -362.943162) (xy 20.559957 -362.943162) (xy 20.506009 -362.935406)
			(xy 20.453714 -362.920051) (xy 20.404137 -362.897409) (xy 20.358287 -362.867943) (xy 20.317096 -362.832252)
			(xy 20.281405 -362.791061) (xy 20.251939 -362.745211) (xy 20.229297 -362.695634) (xy 20.213942 -362.643339)
			(xy 20.206186 -362.589391) (xy 20.2057 -362.56214) (xy 19.016472 -362.56214) (xy 19.016472 -363.347)
			(xy 20.812506 -363.347) (xy 20.812992 -363.319749) (xy 20.820748 -363.265801) (xy 20.836103 -363.213506)
			(xy 20.858745 -363.163929) (xy 20.888211 -363.118079) (xy 20.923902 -363.076888) (xy 20.965093 -363.041197)
			(xy 21.010943 -363.011731) (xy 21.06052 -362.989089) (xy 21.112815 -362.973734) (xy 21.166763 -362.965978)
			(xy 21.221265 -362.965978) (xy 21.275213 -362.973734) (xy 21.327508 -362.989089) (xy 21.377085 -363.011731)
			(xy 21.422935 -363.041197) (xy 21.464126 -363.076888) (xy 21.499817 -363.118079) (xy 21.529283 -363.163929)
			(xy 21.551925 -363.213506) (xy 21.56728 -363.265801) (xy 21.575036 -363.319749) (xy 21.575522 -363.347)
			(xy 21.574843 -363.380468) (xy 21.563225 -363.446386) (xy 21.552408 -363.478064) (xy 21.548257 -363.490879)
			(xy 21.545994 -363.517709) (xy 21.550823 -363.544198) (xy 21.562406 -363.568504) (xy 21.579939 -363.588938)
			(xy 21.602204 -363.604079) (xy 21.627651 -363.612876) (xy 21.641054 -363.614208) (xy 21.669689 -363.616645)
			(xy 21.725819 -363.628959) (xy 21.779469 -363.649551) (xy 21.829424 -363.677955) (xy 21.874554 -363.713529)
			(xy 21.91384 -363.755469) (xy 21.946393 -363.802825) (xy 21.971476 -363.854527) (xy 21.988522 -363.909407)
			(xy 21.997146 -363.966221) (xy 21.99767 -363.994954) (xy 21.997184 -364.022205) (xy 21.989428 -364.076153)
			(xy 21.974073 -364.128448) (xy 21.951431 -364.178025) (xy 21.921965 -364.223875) (xy 21.886274 -364.265066)
			(xy 21.845083 -364.300757) (xy 21.799233 -364.330223) (xy 21.749656 -364.352865) (xy 21.697361 -364.36822)
			(xy 21.643413 -364.375976) (xy 21.588911 -364.375976) (xy 21.534963 -364.36822) (xy 21.482668 -364.352865)
			(xy 21.433091 -364.330223) (xy 21.387241 -364.300757) (xy 21.34605 -364.265066) (xy 21.310359 -364.223875)
			(xy 21.280893 -364.178025) (xy 21.258251 -364.128448) (xy 21.242896 -364.076153) (xy 21.23514 -364.022205)
			(xy 21.234654 -363.994954) (xy 21.235322 -363.961486) (xy 21.246947 -363.895568) (xy 21.257768 -363.86389)
			(xy 21.261994 -363.851096) (xy 21.264248 -363.824255) (xy 21.259409 -363.797758) (xy 21.247814 -363.773446)
			(xy 21.230268 -363.753009) (xy 21.20799 -363.737868) (xy 21.18253 -363.729075) (xy 21.169122 -363.727746)
			(xy 21.14048 -363.725375) (xy 21.084345 -363.713056) (xy 21.030692 -363.692457) (xy 20.980735 -363.664046)
			(xy 20.935603 -363.628464) (xy 20.896318 -363.586517) (xy 20.863767 -363.539153) (xy 20.838687 -363.487443)
			(xy 20.821645 -363.432557) (xy 20.813026 -363.375736) (xy 20.812506 -363.347) (xy 19.016472 -363.347)
			(xy 19.016472 -364.263229) (xy 19.699007 -364.263229) (xy 19.69901 -364.208731) (xy 19.706768 -364.154789)
			(xy 19.722124 -364.1025) (xy 19.744765 -364.052929) (xy 19.774231 -364.007084) (xy 19.809921 -363.965899)
			(xy 19.851108 -363.930213) (xy 19.896955 -363.900751) (xy 19.946528 -363.878114) (xy 19.998819 -363.862762)
			(xy 20.052761 -363.855007) (xy 20.107259 -363.855009) (xy 20.161201 -363.862766) (xy 20.21349 -363.878121)
			(xy 20.263062 -363.900761) (xy 20.308908 -363.930225) (xy 20.350094 -363.965913) (xy 20.385781 -364.0071)
			(xy 20.415244 -364.052946) (xy 20.437883 -364.102519) (xy 20.453236 -364.154809) (xy 20.460992 -364.208751)
			(xy 20.461478 -364.236) (xy 20.461375 -364.24906) (xy 20.459596 -364.275118) (xy 20.457922 -364.28807)
			(xy 20.45645 -364.302203) (xy 20.460431 -364.330326) (xy 20.472008 -364.356261) (xy 20.490286 -364.378002)
			(xy 20.513847 -364.393863) (xy 20.540867 -364.402615) (xy 20.569253 -364.403582) (xy 20.583144 -364.400592)
			(xy 20.605947 -364.395241) (xy 20.652434 -364.389515) (xy 20.675854 -364.389162) (xy 20.703111 -364.389606)
			(xy 20.757072 -364.397358) (xy 20.80938 -364.412711) (xy 20.858971 -364.435352) (xy 20.904834 -364.46482)
			(xy 20.946037 -364.500516) (xy 20.98174 -364.541712) (xy 21.011216 -364.587571) (xy 21.033866 -364.637157)
			(xy 21.049228 -364.689463) (xy 21.056989 -364.743422) (xy 21.056992 -364.797937) (xy 21.049237 -364.851897)
			(xy 21.03388 -364.904204) (xy 21.011236 -364.953793) (xy 20.981765 -364.999654) (xy 20.946066 -365.040855)
			(xy 20.904867 -365.076555) (xy 20.859007 -365.106028) (xy 20.809419 -365.128675) (xy 20.757112 -365.144033)
			(xy 20.703153 -365.151791) (xy 20.648638 -365.151791) (xy 20.594678 -365.144031) (xy 20.542372 -365.128672)
			(xy 20.492785 -365.106024) (xy 20.446925 -365.076549) (xy 20.405727 -365.040848) (xy 20.37003 -364.999647)
			(xy 20.340559 -364.953785) (xy 20.317916 -364.904195) (xy 20.302561 -364.851888) (xy 20.294807 -364.797927)
			(xy 20.294346 -364.77067) (xy 20.294446 -364.75761) (xy 20.296227 -364.731552) (xy 20.297902 -364.7186)
			(xy 20.299374 -364.704468) (xy 20.295386 -364.676349) (xy 20.283806 -364.650418) (xy 20.265529 -364.62868)
			(xy 20.24197 -364.61282) (xy 20.214954 -364.604065) (xy 20.18657 -364.603092) (xy 20.17268 -364.606078)
			(xy 20.149877 -364.611426) (xy 20.103389 -364.617154) (xy 20.07997 -364.617508) (xy 20.052721 -364.61699)
			(xy 19.998779 -364.60923) (xy 19.946491 -364.593872) (xy 19.89692 -364.57123) (xy 19.851076 -364.541763)
			(xy 19.809892 -364.506072) (xy 19.774207 -364.464884) (xy 19.744746 -364.419036) (xy 19.72211 -364.369462)
			(xy 19.70676 -364.317172) (xy 19.699007 -364.263229) (xy 19.016472 -364.263229) (xy 19.016472 -364.366048)
			(xy 19.016954 -364.376012) (xy 19.024534 -364.394444) (xy 19.031204 -364.401862) (xy 20.7518 -366.122712)
			(xy 20.769811 -366.141434) (xy 20.800363 -366.18345) (xy 20.823976 -366.229723) (xy 20.840069 -366.279117)
			(xy 20.848248 -366.330418) (xy 20.848828 -366.356392) (xy 20.848828 -366.903) (xy 21.080982 -366.903)
			(xy 21.085053 -366.847378) (xy 21.097179 -366.792941) (xy 21.117102 -366.74085) (xy 21.144398 -366.692215)
			(xy 21.178484 -366.648072) (xy 21.218633 -366.609363) (xy 21.263991 -366.576912) (xy 21.313591 -366.551411)
			(xy 21.366375 -366.533404) (xy 21.421218 -366.523274) (xy 21.476952 -366.521237) (xy 21.532389 -366.527337)
			(xy 21.586346 -366.541443) (xy 21.637675 -366.563255) (xy 21.685281 -366.592309) (xy 21.728149 -366.627984)
			(xy 21.765366 -366.669521) (xy 21.796139 -366.716034) (xy 21.819811 -366.766531) (xy 21.835879 -366.819938)
			(xy 21.843999 -366.875114) (xy 21.844508 -366.903) (xy 23.239982 -366.903) (xy 23.244053 -366.847378)
			(xy 23.256179 -366.792941) (xy 23.276102 -366.74085) (xy 23.303398 -366.692215) (xy 23.337484 -366.648072)
			(xy 23.377633 -366.609363) (xy 23.422991 -366.576912) (xy 23.472591 -366.551411) (xy 23.525375 -366.533404)
			(xy 23.580218 -366.523274) (xy 23.635952 -366.521237) (xy 23.691389 -366.527337) (xy 23.745346 -366.541443)
			(xy 23.796675 -366.563255) (xy 23.815228 -366.574578) (xy 24.459692 -366.574578) (xy 24.459692 -363.982)
			(xy 24.460178 -363.954749) (xy 24.467934 -363.900801) (xy 24.483289 -363.848506) (xy 24.505931 -363.798929)
			(xy 24.535397 -363.753079) (xy 24.571088 -363.711888) (xy 24.612279 -363.676197) (xy 24.658129 -363.646731)
			(xy 24.707706 -363.624089) (xy 24.760001 -363.608734) (xy 24.813949 -363.600978) (xy 24.868451 -363.600978)
			(xy 24.922399 -363.608734) (xy 24.974694 -363.624089) (xy 25.024271 -363.646731) (xy 25.070121 -363.676197)
			(xy 25.111312 -363.711888) (xy 25.147003 -363.753079) (xy 25.176469 -363.798929) (xy 25.199111 -363.848506)
			(xy 25.214466 -363.900801) (xy 25.222222 -363.954749) (xy 25.222708 -363.982) (xy 25.222708 -364.744)
			(xy 25.399492 -364.744) (xy 25.399972 -364.71724) (xy 25.407447 -364.664245) (xy 25.42225 -364.612813)
			(xy 25.444091 -364.563953) (xy 25.472542 -364.518622) (xy 25.507045 -364.477709) (xy 25.546924 -364.442015)
			(xy 25.56891 -364.426754) (xy 25.580028 -364.418875) (xy 25.597849 -364.398266) (xy 25.609593 -364.373682)
			(xy 25.614427 -364.34687) (xy 25.612007 -364.319732) (xy 25.602505 -364.294198) (xy 25.586597 -364.27208)
			(xy 25.576276 -364.263178) (xy 25.554506 -364.244975) (xy 25.516101 -364.2032) (xy 25.484308 -364.156197)
			(xy 25.45983 -364.105002) (xy 25.443208 -364.050746) (xy 25.434807 -363.994625) (xy 25.43429 -363.966252)
			(xy 25.434776 -363.939001) (xy 25.442532 -363.885053) (xy 25.457887 -363.832758) (xy 25.480529 -363.783181)
			(xy 25.509995 -363.737331) (xy 25.545686 -363.69614) (xy 25.586877 -363.660449) (xy 25.632727 -363.630983)
			(xy 25.682304 -363.608341) (xy 25.734599 -363.592986) (xy 25.788547 -363.58523) (xy 25.843049 -363.58523)
			(xy 25.896997 -363.592986) (xy 25.949292 -363.608341) (xy 25.998869 -363.630983) (xy 26.044719 -363.660449)
			(xy 26.08591 -363.69614) (xy 26.121601 -363.737331) (xy 26.151067 -363.783181) (xy 26.173709 -363.832758)
			(xy 26.189064 -363.885053) (xy 26.19682 -363.939001) (xy 26.197306 -363.966252) (xy 26.196866 -363.993013)
			(xy 26.189384 -364.04601) (xy 26.174574 -364.097443) (xy 26.152727 -364.146303) (xy 26.12427 -364.191634)
			(xy 26.089761 -364.232546) (xy 26.049877 -364.268238) (xy 26.027888 -364.283498) (xy 26.016815 -364.291436)
			(xy 25.998996 -364.312032) (xy 25.98725 -364.336603) (xy 25.982411 -364.363403) (xy 25.984822 -364.390531)
			(xy 25.994313 -364.416058) (xy 26.010208 -364.438172) (xy 26.020522 -364.447074) (xy 26.042268 -364.465304)
			(xy 26.080676 -364.507073) (xy 26.112471 -364.55407) (xy 26.136953 -364.60526) (xy 26.153581 -364.659512)
			(xy 26.161987 -364.715629) (xy 26.162508 -364.744) (xy 26.162022 -364.771251) (xy 26.154266 -364.825199)
			(xy 26.138911 -364.877494) (xy 26.116269 -364.927071) (xy 26.086803 -364.972921) (xy 26.051112 -365.014112)
			(xy 26.009921 -365.049803) (xy 25.964071 -365.079269) (xy 25.914494 -365.101911) (xy 25.862199 -365.117266)
			(xy 25.808251 -365.125022) (xy 25.753749 -365.125022) (xy 25.699801 -365.117266) (xy 25.647506 -365.101911)
			(xy 25.597929 -365.079269) (xy 25.552079 -365.049803) (xy 25.510888 -365.014112) (xy 25.475197 -364.972921)
			(xy 25.445731 -364.927071) (xy 25.423089 -364.877494) (xy 25.407734 -364.825199) (xy 25.399978 -364.771251)
			(xy 25.399492 -364.744) (xy 25.222708 -364.744) (xy 25.222708 -365.76) (xy 25.627074 -365.76) (xy 25.631145 -365.704378)
			(xy 25.643271 -365.649941) (xy 25.663194 -365.59785) (xy 25.69049 -365.549215) (xy 25.724576 -365.505072)
			(xy 25.764725 -365.466363) (xy 25.810083 -365.433912) (xy 25.859683 -365.408411) (xy 25.912467 -365.390404)
			(xy 25.96731 -365.380274) (xy 26.023044 -365.378237) (xy 26.078481 -365.384337) (xy 26.132438 -365.398443)
			(xy 26.183767 -365.420255) (xy 26.231373 -365.449309) (xy 26.274241 -365.484984) (xy 26.311458 -365.526521)
			(xy 26.342231 -365.573034) (xy 26.365903 -365.623531) (xy 26.381971 -365.676938) (xy 26.390091 -365.732114)
			(xy 26.3906 -365.76) (xy 26.390091 -365.787886) (xy 26.381971 -365.843062) (xy 26.365903 -365.896469)
			(xy 26.342231 -365.946966) (xy 26.311458 -365.993479) (xy 26.274241 -366.035016) (xy 26.231373 -366.070691)
			(xy 26.183767 -366.099745) (xy 26.132438 -366.121557) (xy 26.078481 -366.135663) (xy 26.023044 -366.141763)
			(xy 25.96731 -366.139726) (xy 25.912467 -366.129596) (xy 25.859683 -366.111589) (xy 25.810083 -366.086088)
			(xy 25.764725 -366.053637) (xy 25.724576 -366.014928) (xy 25.69049 -365.970785) (xy 25.663194 -365.92215)
			(xy 25.643271 -365.870059) (xy 25.631145 -365.815622) (xy 25.627074 -365.76) (xy 25.222708 -365.76)
			(xy 25.222708 -366.395508) (xy 25.223097 -366.405551) (xy 25.230672 -366.424147) (xy 25.23744 -366.431576)
			(xy 25.65781 -366.851946) (xy 25.665207 -366.858789) (xy 25.683809 -366.866506) (xy 25.693878 -366.866932)
			(xy 31.134812 -366.866932) (xy 31.164786 -366.867424) (xy 31.224003 -366.876752) (xy 31.281028 -366.895237)
			(xy 31.334456 -366.922425) (xy 31.382966 -366.957643) (xy 31.40456 -366.978438) (xy 32.657034 -368.231166)
			(xy 32.664432 -368.238009) (xy 32.683033 -368.245728) (xy 32.693102 -368.246152) (xy 36.281614 -368.246152)
			(xy 36.291686 -368.245747) (xy 36.310284 -368.238013) (xy 36.317682 -368.231166) (xy 37.662358 -366.88649)
			(xy 37.669189 -366.879083) (xy 37.676915 -366.860489) (xy 37.677344 -366.850422) (xy 37.677344 -365.731044)
			(xy 37.676911 -365.720975) (xy 37.669197 -365.702377) (xy 37.662358 -365.694976) (xy 37.15893 -365.191802)
			(xy 37.138196 -365.170159) (xy 37.103006 -365.121646) (xy 37.075833 -365.068228) (xy 37.057346 -365.011219)
			(xy 37.047999 -364.95202) (xy 37.047424 -364.922054) (xy 37.047424 -362.41736) (xy 37.047964 -362.387388)
			(xy 37.05728 -362.328173) (xy 37.075754 -362.271148) (xy 37.102931 -362.21772) (xy 37.13814 -362.169208)
			(xy 37.15893 -362.147612) (xy 37.49929 -361.807252) (xy 37.520882 -361.786444) (xy 37.569384 -361.751189)
			(xy 37.622807 -361.723959) (xy 37.679833 -361.705427) (xy 37.739057 -361.696048) (xy 37.769038 -361.695492)
			(xy 38.3286 -361.695492) (xy 38.355851 -361.695978) (xy 38.409799 -361.703734) (xy 38.462094 -361.719089)
			(xy 38.511671 -361.741731) (xy 38.557521 -361.771197) (xy 38.598712 -361.806888) (xy 38.634403 -361.848079)
			(xy 38.663869 -361.893929) (xy 38.686511 -361.943506) (xy 38.701866 -361.995801) (xy 38.709622 -362.049749)
			(xy 38.709622 -362.104251) (xy 38.701866 -362.158199) (xy 38.686511 -362.210494) (xy 38.663869 -362.260071)
			(xy 38.634403 -362.305921) (xy 38.598712 -362.347112) (xy 38.557521 -362.382803) (xy 38.511671 -362.412269)
			(xy 38.462094 -362.434911) (xy 38.409799 -362.450266) (xy 38.355851 -362.458022) (xy 38.3286 -362.458508)
			(xy 37.948108 -362.458508) (xy 37.93806 -362.458853) (xy 37.919464 -362.466459) (xy 37.91204 -362.47324)
			(xy 37.824918 -362.560362) (xy 37.818104 -362.567783) (xy 37.810369 -362.586366) (xy 37.809932 -362.59643)
			(xy 37.809932 -362.85424) (xy 46.115224 -362.85424) (xy 46.115708 -362.82687) (xy 46.12352 -362.772692)
			(xy 46.139005 -362.720189) (xy 46.161843 -362.670441) (xy 46.191564 -362.624474) (xy 46.209204 -362.603542)
			(xy 46.2153 -362.59643) (xy 46.22165 -362.579412) (xy 46.22165 -362.494068) (xy 46.2153 -362.47705)
			(xy 46.209204 -362.469938) (xy 46.191603 -362.448973) (xy 46.161879 -362.40301) (xy 46.139032 -362.353269)
			(xy 46.123534 -362.300772) (xy 46.115702 -362.246599) (xy 46.115698 -362.191862) (xy 46.123521 -362.137687)
			(xy 46.139011 -362.085187) (xy 46.16185 -362.035443) (xy 46.191567 -361.989475) (xy 46.209204 -361.968542)
			(xy 46.2153 -361.96143) (xy 46.22165 -361.944412) (xy 46.22165 -361.859068) (xy 46.2153 -361.84205)
			(xy 46.209204 -361.834938) (xy 46.191603 -361.813973) (xy 46.161879 -361.76801) (xy 46.139032 -361.718269)
			(xy 46.123534 -361.665772) (xy 46.115702 -361.611599) (xy 46.115698 -361.556862) (xy 46.123521 -361.502687)
			(xy 46.139011 -361.450187) (xy 46.16185 -361.400443) (xy 46.191567 -361.354475) (xy 46.209204 -361.333542)
			(xy 46.2153 -361.32643) (xy 46.22165 -361.309412) (xy 46.22165 -361.224068) (xy 46.2153 -361.20705)
			(xy 46.209204 -361.199938) (xy 46.191603 -361.178973) (xy 46.161879 -361.13301) (xy 46.139032 -361.083269)
			(xy 46.123534 -361.030772) (xy 46.115702 -360.976599) (xy 46.115698 -360.921862) (xy 46.123521 -360.867687)
			(xy 46.139011 -360.815187) (xy 46.16185 -360.765443) (xy 46.191567 -360.719475) (xy 46.209204 -360.698542)
			(xy 46.2153 -360.69143) (xy 46.22165 -360.674412) (xy 46.22165 -360.589068) (xy 46.2153 -360.57205)
			(xy 46.209204 -360.564938) (xy 46.191603 -360.543973) (xy 46.161879 -360.49801) (xy 46.139032 -360.448269)
			(xy 46.123534 -360.395772) (xy 46.115702 -360.341599) (xy 46.115698 -360.286862) (xy 46.123521 -360.232687)
			(xy 46.139011 -360.180187) (xy 46.16185 -360.130443) (xy 46.191567 -360.084475) (xy 46.209204 -360.063542)
			(xy 46.2153 -360.05643) (xy 46.22165 -360.039412) (xy 46.22165 -359.954068) (xy 46.2153 -359.93705)
			(xy 46.209204 -359.929938) (xy 46.19157 -359.909002) (xy 46.161857 -359.86303) (xy 46.13902 -359.813284)
			(xy 46.123528 -359.760784) (xy 46.115699 -359.706609) (xy 46.115224 -359.67924) (xy 46.115693 -359.651987)
			(xy 46.123445 -359.598034) (xy 46.138798 -359.545735) (xy 46.161438 -359.496152) (xy 46.190905 -359.450298)
			(xy 46.226598 -359.409104) (xy 46.267791 -359.373409) (xy 46.313645 -359.343942) (xy 46.363227 -359.3213)
			(xy 46.415526 -359.305947) (xy 46.469479 -359.298193) (xy 46.496732 -359.297732) (xy 46.524103 -359.298172)
			(xy 46.578284 -359.305995) (xy 46.630788 -359.321489) (xy 46.680534 -359.344337) (xy 46.726499 -359.374068)
			(xy 46.74743 -359.391712) (xy 46.754542 -359.397808) (xy 46.77156 -359.404158) (xy 46.856904 -359.404158)
			(xy 46.873922 -359.397808) (xy 46.881034 -359.391712) (xy 46.901967 -359.374071) (xy 46.947935 -359.344347)
			(xy 46.997681 -359.321501) (xy 47.050183 -359.306005) (xy 47.104361 -359.298176) (xy 47.159103 -359.298176)
			(xy 47.213281 -359.306005) (xy 47.265783 -359.321501) (xy 47.315529 -359.344347) (xy 47.361497 -359.374071)
			(xy 47.38243 -359.391712) (xy 47.389542 -359.397808) (xy 47.40656 -359.404158) (xy 47.491904 -359.404158)
			(xy 47.508922 -359.397808) (xy 47.516034 -359.391712) (xy 47.536982 -359.374092) (xy 47.58295 -359.344377)
			(xy 47.632694 -359.321537) (xy 47.685191 -359.306042) (xy 47.739364 -359.298209) (xy 47.766732 -359.297732)
			(xy 47.793558 -359.298162) (xy 47.846678 -359.305703) (xy 47.898219 -359.320605) (xy 47.947167 -359.342574)
			(xy 47.992559 -359.371178) (xy 48.033501 -359.405853) (xy 48.069187 -359.445917) (xy 48.098914 -359.490581)
			(xy 48.122097 -359.538966) (xy 48.13828 -359.590119) (xy 48.14316 -359.616502) (xy 48.144938 -359.627424)
			(xy 48.156876 -359.645458) (xy 48.240442 -359.697274) (xy 48.262032 -359.700068) (xy 48.272446 -359.69702)
			(xy 48.299366 -359.689407) (xy 48.354711 -359.681252) (xy 48.382682 -359.680764) (xy 48.410053 -359.681225)
			(xy 48.464233 -359.689042) (xy 48.516736 -359.704531) (xy 48.566483 -359.727374) (xy 48.612449 -359.757101)
			(xy 48.63338 -359.774744) (xy 48.640492 -359.78084) (xy 48.65751 -359.78719) (xy 48.742854 -359.78719)
			(xy 48.759872 -359.78084) (xy 48.766984 -359.774744) (xy 48.787917 -359.757103) (xy 48.833885 -359.727379)
			(xy 48.883631 -359.704533) (xy 48.936133 -359.689037) (xy 48.990311 -359.681208) (xy 49.045053 -359.681208)
			(xy 49.099231 -359.689037) (xy 49.151733 -359.704533) (xy 49.201479 -359.727379) (xy 49.247447 -359.757103)
			(xy 49.26838 -359.774744) (xy 49.275492 -359.78084) (xy 49.29251 -359.78719) (xy 49.377854 -359.78719)
			(xy 49.394872 -359.78084) (xy 49.401984 -359.774744) (xy 49.422917 -359.757103) (xy 49.468885 -359.727379)
			(xy 49.518631 -359.704533) (xy 49.571133 -359.689037) (xy 49.625311 -359.681208) (xy 49.680053 -359.681208)
			(xy 49.734231 -359.689037) (xy 49.786733 -359.704533) (xy 49.836479 -359.727379) (xy 49.882447 -359.757103)
			(xy 49.90338 -359.774744) (xy 49.910492 -359.78084) (xy 49.92751 -359.78719) (xy 50.012854 -359.78719)
			(xy 50.029872 -359.78084) (xy 50.036984 -359.774744) (xy 50.057917 -359.757106) (xy 50.103889 -359.727392)
			(xy 50.153636 -359.704555) (xy 50.206137 -359.689064) (xy 50.260313 -359.681237) (xy 50.287682 -359.680764)
			(xy 50.31765 -359.68129) (xy 50.376858 -359.690599) (xy 50.405538 -359.699306) (xy 50.415698 -359.702608)
			(xy 50.436018 -359.70083) (xy 50.519584 -359.655364) (xy 50.532284 -359.639362) (xy 50.535078 -359.628948)
			(xy 50.542719 -359.602235) (xy 50.564657 -359.551191) (xy 50.59377 -359.50387) (xy 50.629442 -359.461274)
			(xy 50.670916 -359.424306) (xy 50.717316 -359.393746) (xy 50.76766 -359.370244) (xy 50.82088 -359.354295)
			(xy 50.875852 -359.346237) (xy 50.903632 -359.345738) (xy 50.932527 -359.346241) (xy 50.989656 -359.354951)
			(xy 51.044816 -359.372184) (xy 51.096745 -359.397542) (xy 51.120802 -359.413556) (xy 51.128422 -359.41889)
			(xy 51.146964 -359.423462) (xy 51.233578 -359.411778) (xy 51.250088 -359.402634) (xy 51.256184 -359.395522)
			(xy 51.274429 -359.374664) (xy 51.315856 -359.33786) (xy 51.362173 -359.30744) (xy 51.412405 -359.284044)
			(xy 51.465495 -359.268163) (xy 51.520323 -359.260134) (xy 51.54803 -359.259632) (xy 51.573982 -359.26006)
			(xy 51.625404 -359.267112) (xy 51.675397 -359.281066) (xy 51.723038 -359.301667) (xy 51.767447 -359.328534)
			(xy 51.807806 -359.36117) (xy 51.825906 -359.379774) (xy 51.832764 -359.386886) (xy 51.85029 -359.395268)
			(xy 51.939698 -359.400348) (xy 51.957986 -359.394252) (xy 51.965606 -359.387902) (xy 51.986326 -359.370947)
			(xy 52.031651 -359.34245) (xy 52.080513 -359.320564) (xy 52.131953 -359.305717) (xy 52.184963 -359.298202)
			(xy 52.211732 -359.297732) (xy 52.239103 -359.298172) (xy 52.293284 -359.305995) (xy 52.345788 -359.321489)
			(xy 52.395534 -359.344337) (xy 52.441499 -359.374068) (xy 52.46243 -359.391712) (xy 52.469542 -359.397808)
			(xy 52.48656 -359.404158) (xy 52.571904 -359.404158) (xy 52.588922 -359.397808) (xy 52.596034 -359.391712)
			(xy 52.616982 -359.374092) (xy 52.66295 -359.344377) (xy 52.712694 -359.321537) (xy 52.765191 -359.306042)
			(xy 52.819364 -359.298209) (xy 52.846732 -359.297732) (xy 52.873988 -359.298125) (xy 52.927943 -359.305888)
			(xy 52.980245 -359.32125) (xy 53.029828 -359.343899) (xy 53.075683 -359.373374) (xy 53.116876 -359.409075)
			(xy 53.152569 -359.450275) (xy 53.182036 -359.496136) (xy 53.204675 -359.545723) (xy 53.220028 -359.598027)
			(xy 53.22778 -359.651984) (xy 53.22824 -359.67924) (xy 53.227753 -359.707176) (xy 53.219642 -359.762456)
			(xy 53.203555 -359.815961) (xy 53.179837 -359.866548) (xy 53.148995 -359.913135) (xy 53.130704 -359.934256)
			(xy 53.1241 -359.941368) (xy 53.117496 -359.95864) (xy 53.11775 -360.045762) (xy 53.124354 -360.063034)
			(xy 53.130704 -360.070146) (xy 53.149106 -360.091278) (xy 53.180168 -360.137913) (xy 53.204071 -360.188592)
			(xy 53.2203 -360.242224) (xy 53.228505 -360.297653) (xy 53.229002 -360.32567) (xy 53.228517 -360.352922)
			(xy 53.220764 -360.406873) (xy 53.205411 -360.459171) (xy 53.182772 -360.508751) (xy 53.153306 -360.554605)
			(xy 53.117615 -360.595798) (xy 53.076424 -360.631492) (xy 53.030572 -360.66096) (xy 52.980993 -360.683603)
			(xy 52.928696 -360.698959) (xy 52.874746 -360.706715) (xy 52.847494 -360.707178) (xy 52.819383 -360.706684)
			(xy 52.763768 -360.698437) (xy 52.709964 -360.682124) (xy 52.659135 -360.658096) (xy 52.612379 -360.626873)
			(xy 52.591208 -360.608372) (xy 52.58435 -360.602022) (xy 52.567586 -360.595418) (xy 52.481734 -360.593894)
			(xy 52.464716 -360.59999) (xy 52.457604 -360.605832) (xy 52.4369 -360.622757) (xy 52.391624 -360.651213)
			(xy 52.342812 -360.673053) (xy 52.291423 -360.687848) (xy 52.23847 -360.695308) (xy 52.211732 -360.695748)
			(xy 52.185781 -360.695285) (xy 52.13436 -360.688242) (xy 52.084367 -360.674294) (xy 52.036727 -360.6537)
			(xy 51.992316 -360.626839) (xy 51.951956 -360.594207) (xy 51.933856 -360.575606) (xy 51.926998 -360.568494)
			(xy 51.909472 -360.560112) (xy 51.820064 -360.555032) (xy 51.801776 -360.561128) (xy 51.794156 -360.567478)
			(xy 51.773411 -360.584402) (xy 51.728093 -360.612904) (xy 51.679237 -360.634796) (xy 51.627803 -360.64965)
			(xy 51.574798 -360.657174) (xy 51.54803 -360.657648) (xy 51.519137 -360.6571) (xy 51.46201 -360.6484)
			(xy 51.40685 -360.631181) (xy 51.35492 -360.605836) (xy 51.33086 -360.58983) (xy 51.32324 -360.584496)
			(xy 51.304698 -360.579924) (xy 51.218084 -360.591608) (xy 51.201574 -360.600752) (xy 51.195478 -360.607864)
			(xy 51.17592 -360.629454) (xy 51.1683 -360.637328) (xy 51.160934 -360.656886) (xy 51.166014 -360.75366)
			(xy 51.175412 -360.772202) (xy 51.183794 -360.77906) (xy 51.205176 -360.797302) (xy 51.242916 -360.838946)
			(xy 51.274139 -360.885676) (xy 51.298169 -360.936481) (xy 51.314486 -360.990261) (xy 51.322737 -361.045853)
			(xy 51.32324 -361.073954) (xy 51.322702 -361.101204) (xy 51.314952 -361.155151) (xy 51.299604 -361.207445)
			(xy 51.276969 -361.257023) (xy 51.247509 -361.302875) (xy 51.211823 -361.344067) (xy 51.170638 -361.379762)
			(xy 51.124792 -361.409231) (xy 51.075219 -361.431876) (xy 51.022927 -361.447236) (xy 50.968982 -361.454996)
			(xy 50.941732 -361.455462) (xy 50.913823 -361.455008) (xy 50.858598 -361.446901) (xy 50.80515 -361.430813)
			(xy 50.77968 -361.419394) (xy 50.770028 -361.414822) (xy 50.7492 -361.41406) (xy 50.660808 -361.449112)
			(xy 50.645822 -361.463844) (xy 50.642012 -361.473496) (xy 50.630964 -361.499689) (xy 50.602339 -361.548798)
			(xy 50.56674 -361.593113) (xy 50.524956 -361.631652) (xy 50.477913 -361.663561) (xy 50.426655 -361.688132)
			(xy 50.372317 -361.70482) (xy 50.316104 -361.713257) (xy 50.287682 -361.71378) (xy 50.260311 -361.713329)
			(xy 50.206131 -361.705509) (xy 50.153628 -361.690016) (xy 50.103881 -361.667171) (xy 50.057915 -361.637443)
			(xy 50.036984 -361.6198) (xy 50.029872 -361.613704) (xy 50.012854 -361.607354) (xy 49.92751 -361.607354)
			(xy 49.910492 -361.613704) (xy 49.90338 -361.6198) (xy 49.882447 -361.637441) (xy 49.836479 -361.667165)
			(xy 49.786733 -361.690011) (xy 49.734231 -361.705507) (xy 49.680053 -361.713336) (xy 49.625311 -361.713336)
			(xy 49.571133 -361.705507) (xy 49.518631 -361.690011) (xy 49.468885 -361.667165) (xy 49.422917 -361.637441)
			(xy 49.401984 -361.6198) (xy 49.394872 -361.613704) (xy 49.377854 -361.607354) (xy 49.29251 -361.607354)
			(xy 49.275492 -361.613704) (xy 49.26838 -361.6198) (xy 49.247447 -361.637441) (xy 49.201479 -361.667165)
			(xy 49.151733 -361.690011) (xy 49.099231 -361.705507) (xy 49.045053 -361.713336) (xy 48.990311 -361.713336)
			(xy 48.936133 -361.705507) (xy 48.883631 -361.690011) (xy 48.833885 -361.667165) (xy 48.787917 -361.637441)
			(xy 48.766984 -361.6198) (xy 48.759872 -361.613704) (xy 48.742854 -361.607354) (xy 48.65751 -361.607354)
			(xy 48.640492 -361.613704) (xy 48.63338 -361.6198) (xy 48.612429 -361.637415) (xy 48.566461 -361.667131)
			(xy 48.516718 -361.689971) (xy 48.464222 -361.705468) (xy 48.41005 -361.713302) (xy 48.382682 -361.71378)
			(xy 48.359066 -361.713447) (xy 48.312192 -361.707641) (xy 48.266392 -361.696097) (xy 48.244252 -361.687872)
			(xy 48.235108 -361.684062) (xy 48.21555 -361.684316) (xy 48.132746 -361.718352) (xy 48.118776 -361.731814)
			(xy 48.114712 -361.740704) (xy 48.102724 -361.766129) (xy 48.072367 -361.813437) (xy 48.05426 -361.834938)
			(xy 48.048164 -361.84205) (xy 48.041814 -361.859068) (xy 48.041814 -361.944412) (xy 48.048164 -361.96143)
			(xy 48.05426 -361.968542) (xy 48.071879 -361.98949) (xy 48.101595 -362.035458) (xy 48.124436 -362.085201)
			(xy 48.139931 -362.137699) (xy 48.147764 -362.191872) (xy 48.14824 -362.21924) (xy 48.147759 -362.246491)
			(xy 48.139998 -362.300437) (xy 48.12464 -362.35273) (xy 48.101996 -362.402305) (xy 48.072529 -362.448154)
			(xy 48.036837 -362.489343) (xy 47.995647 -362.525034) (xy 47.949798 -362.5545) (xy 47.900222 -362.577143)
			(xy 47.847929 -362.5925) (xy 47.793983 -362.60026) (xy 47.766732 -362.600748) (xy 47.737254 -362.600203)
			(xy 47.679001 -362.591137) (xy 47.622836 -362.573217) (xy 47.570096 -362.546868) (xy 47.522039 -362.512719)
			(xy 47.50054 -362.492544) (xy 47.493193 -362.486026) (xy 47.475042 -362.478573) (xy 47.465234 -362.478066)
			(xy 47.411894 -362.478066) (xy 47.405036 -362.485432) (xy 47.398486 -362.492754) (xy 47.391052 -362.510924)
			(xy 47.390558 -362.520738) (xy 47.390558 -362.552742) (xy 47.391043 -362.562556) (xy 47.39849 -362.58072)
			(xy 47.405036 -362.588048) (xy 47.42523 -362.609529) (xy 47.459372 -362.657593) (xy 47.485715 -362.710337)
			(xy 47.503632 -362.766506) (xy 47.512694 -362.824762) (xy 47.51324 -362.85424) (xy 47.512759 -362.881491)
			(xy 47.504998 -362.935437) (xy 47.48964 -362.98773) (xy 47.466996 -363.037305) (xy 47.437529 -363.083154)
			(xy 47.401837 -363.124343) (xy 47.360647 -363.160034) (xy 47.314798 -363.1895) (xy 47.265222 -363.212143)
			(xy 47.212929 -363.2275) (xy 47.158983 -363.23526) (xy 47.131732 -363.235748) (xy 47.104362 -363.235276)
			(xy 47.050183 -363.227461) (xy 46.997679 -363.211974) (xy 46.947932 -363.189134) (xy 46.901965 -363.159409)
			(xy 46.881034 -363.141768) (xy 46.873922 -363.135672) (xy 46.856904 -363.129322) (xy 46.77156 -363.129322)
			(xy 46.754542 -363.135672) (xy 46.74743 -363.141768) (xy 46.726493 -363.159402) (xy 46.680522 -363.189115)
			(xy 46.630776 -363.211953) (xy 46.578276 -363.227445) (xy 46.524101 -363.235274) (xy 46.496732 -363.235748)
			(xy 46.469483 -363.235192) (xy 46.41554 -363.227441) (xy 46.363249 -363.212092) (xy 46.313675 -363.189457)
			(xy 46.267826 -363.159998) (xy 46.226637 -363.124314) (xy 46.190945 -363.083131) (xy 46.161477 -363.037288)
			(xy 46.138833 -362.987718) (xy 46.123474 -362.93543) (xy 46.115713 -362.881489) (xy 46.115224 -362.85424)
			(xy 37.809932 -362.85424) (xy 37.809932 -364.590584) (xy 39.286178 -364.590584) (xy 39.290249 -364.534962)
			(xy 39.302375 -364.480525) (xy 39.322298 -364.428434) (xy 39.349594 -364.379799) (xy 39.38368 -364.335656)
			(xy 39.423829 -364.296947) (xy 39.469187 -364.264496) (xy 39.518787 -364.238995) (xy 39.571571 -364.220988)
			(xy 39.626414 -364.210858) (xy 39.682148 -364.208821) (xy 39.737585 -364.214921) (xy 39.791542 -364.229027)
			(xy 39.842871 -364.250839) (xy 39.890477 -364.279893) (xy 39.933345 -364.315568) (xy 39.970562 -364.357105)
			(xy 40.001335 -364.403618) (xy 40.025007 -364.454115) (xy 40.041075 -364.507522) (xy 40.049195 -364.562698)
			(xy 40.049704 -364.590584) (xy 40.049195 -364.61847) (xy 40.041075 -364.673646) (xy 40.025007 -364.727053)
			(xy 40.001335 -364.77755) (xy 39.970562 -364.824063) (xy 39.933345 -364.8656) (xy 39.890477 -364.901275)
			(xy 39.842871 -364.930329) (xy 39.791542 -364.952141) (xy 39.737585 -364.966247) (xy 39.682148 -364.972347)
			(xy 39.626414 -364.97031) (xy 39.571571 -364.96018) (xy 39.518787 -364.942173) (xy 39.469187 -364.916672)
			(xy 39.423829 -364.884221) (xy 39.38368 -364.845512) (xy 39.349594 -364.801369) (xy 39.322298 -364.752734)
			(xy 39.302375 -364.700643) (xy 39.290249 -364.646206) (xy 39.286178 -364.590584) (xy 37.809932 -364.590584)
			(xy 37.809932 -364.742984) (xy 37.810357 -364.753053) (xy 37.818077 -364.771652) (xy 37.824918 -364.779052)
			(xy 38.328346 -365.282226) (xy 38.34909 -365.303861) (xy 38.384279 -365.352375) (xy 38.41145 -365.405796)
			(xy 38.429935 -365.462807) (xy 38.439279 -365.522007) (xy 38.439852 -365.551974) (xy 38.439852 -365.637654)
			(xy 39.929749 -365.637654) (xy 39.929749 -365.583146) (xy 39.937507 -365.529193) (xy 39.952864 -365.476893)
			(xy 39.975508 -365.427311) (xy 40.004978 -365.381456) (xy 40.040674 -365.340263) (xy 40.081869 -365.304568)
			(xy 40.127725 -365.2751) (xy 40.177308 -365.252458) (xy 40.229608 -365.237104) (xy 40.283562 -365.229348)
			(xy 40.310816 -365.228886) (xy 40.338124 -365.229343) (xy 40.392178 -365.237159) (xy 40.444565 -365.252601)
			(xy 40.494216 -365.275353) (xy 40.540117 -365.304951) (xy 40.58133 -365.34079) (xy 40.617013 -365.382137)
			(xy 40.646437 -365.428149) (xy 40.669002 -365.477886) (xy 40.684246 -365.530332) (xy 40.688514 -365.557308)
			(xy 40.690038 -365.566706) (xy 40.699182 -365.58347) (xy 40.766746 -365.639096) (xy 40.78478 -365.645192)
			(xy 40.794432 -365.644684) (xy 40.813736 -365.644176) (xy 40.840309 -365.644685) (xy 40.89294 -365.652065)
			(xy 40.944038 -365.666678) (xy 40.992614 -365.68824) (xy 41.037727 -365.716335) (xy 41.078505 -365.750418)
			(xy 41.114158 -365.78983) (xy 41.129458 -365.811562) (xy 41.135046 -365.819944) (xy 41.151048 -365.830612)
			(xy 41.239948 -365.849154) (xy 41.258998 -365.845852) (xy 41.267634 -365.840518) (xy 41.290547 -365.826607)
			(xy 41.339456 -365.80467) (xy 41.390957 -365.789802) (xy 41.444032 -365.782297) (xy 41.470834 -365.781844)
			(xy 41.49808 -365.782428) (xy 41.552017 -365.790188) (xy 41.604301 -365.805544) (xy 41.653868 -365.828184)
			(xy 41.699708 -365.857648) (xy 41.740889 -365.893335) (xy 41.776573 -365.934519) (xy 41.806032 -365.980362)
			(xy 41.828668 -366.02993) (xy 41.844019 -366.082216) (xy 41.851774 -366.136154) (xy 41.851774 -366.190646)
			(xy 41.844019 -366.244584) (xy 41.828668 -366.29687) (xy 41.806032 -366.346438) (xy 41.776573 -366.392281)
			(xy 41.740889 -366.433465) (xy 41.699708 -366.469152) (xy 41.653868 -366.498616) (xy 41.604301 -366.521256)
			(xy 41.552017 -366.536612) (xy 41.49808 -366.544372) (xy 41.470834 -366.54486) (xy 41.43883 -366.54359)
			(xy 41.427654 -366.542574) (xy 41.407588 -366.549686) (xy 41.336468 -366.616996) (xy 41.32834 -366.636808)
			(xy 41.328594 -366.647984) (xy 41.328848 -366.659668) (xy 41.328362 -366.686919) (xy 41.320606 -366.740867)
			(xy 41.305251 -366.793162) (xy 41.282609 -366.842739) (xy 41.253143 -366.888589) (xy 41.217452 -366.92978)
			(xy 41.176261 -366.965471) (xy 41.130411 -366.994937) (xy 41.080834 -367.017579) (xy 41.028539 -367.032934)
			(xy 40.974591 -367.04069) (xy 40.920089 -367.04069) (xy 40.866141 -367.032934) (xy 40.813846 -367.017579)
			(xy 40.764269 -366.994937) (xy 40.718419 -366.965471) (xy 40.677228 -366.92978) (xy 40.641537 -366.888589)
			(xy 40.612071 -366.842739) (xy 40.589429 -366.793162) (xy 40.574074 -366.740867) (xy 40.566318 -366.686919)
			(xy 40.565832 -366.659668) (xy 40.56624 -366.634507) (xy 40.572854 -366.584621) (xy 40.585963 -366.536036)
			(xy 40.60534 -366.489593) (xy 40.617648 -366.467644) (xy 40.622474 -366.459262) (xy 40.625522 -366.441228)
			(xy 40.607488 -366.35563) (xy 40.597328 -366.340136) (xy 40.589454 -366.334294) (xy 40.569062 -366.318937)
			(xy 40.532164 -366.283659) (xy 40.500294 -366.243781) (xy 40.474019 -366.200014) (xy 40.453807 -366.153137)
			(xy 40.440019 -366.103986) (xy 40.436038 -366.07877) (xy 40.434514 -366.069372) (xy 40.42537 -366.052608)
			(xy 40.357806 -365.996982) (xy 40.339772 -365.990886) (xy 40.33012 -365.991394) (xy 40.310816 -365.991902)
			(xy 40.283562 -365.991452) (xy 40.229608 -365.983696) (xy 40.177308 -365.968342) (xy 40.127725 -365.9457)
			(xy 40.081869 -365.916232) (xy 40.040674 -365.880537) (xy 40.004978 -365.839344) (xy 39.975508 -365.793489)
			(xy 39.952864 -365.743907) (xy 39.937507 -365.691607) (xy 39.929749 -365.637654) (xy 38.439852 -365.637654)
			(xy 38.439852 -366.06353) (xy 38.846504 -366.06353) (xy 38.850575 -366.007908) (xy 38.862701 -365.953471)
			(xy 38.882624 -365.90138) (xy 38.90992 -365.852745) (xy 38.944006 -365.808602) (xy 38.984155 -365.769893)
			(xy 39.029513 -365.737442) (xy 39.079113 -365.711941) (xy 39.131897 -365.693934) (xy 39.18674 -365.683804)
			(xy 39.242474 -365.681767) (xy 39.297911 -365.687867) (xy 39.351868 -365.701973) (xy 39.403197 -365.723785)
			(xy 39.450803 -365.752839) (xy 39.493671 -365.788514) (xy 39.530888 -365.830051) (xy 39.561661 -365.876564)
			(xy 39.585333 -365.927061) (xy 39.601401 -365.980468) (xy 39.609521 -366.035644) (xy 39.61003 -366.06353)
			(xy 39.609521 -366.091416) (xy 39.601401 -366.146592) (xy 39.585333 -366.199999) (xy 39.561661 -366.250496)
			(xy 39.530888 -366.297009) (xy 39.493671 -366.338546) (xy 39.450803 -366.374221) (xy 39.403197 -366.403275)
			(xy 39.351868 -366.425087) (xy 39.297911 -366.439193) (xy 39.242474 -366.445293) (xy 39.18674 -366.443256)
			(xy 39.131897 -366.433126) (xy 39.079113 -366.415119) (xy 39.029513 -366.389618) (xy 38.984155 -366.357167)
			(xy 38.944006 -366.318458) (xy 38.90992 -366.274315) (xy 38.882624 -366.22568) (xy 38.862701 -366.173589)
			(xy 38.850575 -366.119152) (xy 38.846504 -366.06353) (xy 38.439852 -366.06353) (xy 38.439852 -367.029492)
			(xy 38.439352 -367.059466) (xy 38.430027 -367.118682) (xy 38.411544 -367.175708) (xy 38.384358 -367.229135)
			(xy 38.34914 -367.277646) (xy 38.328346 -367.29924) (xy 36.730432 -368.897154) (xy 36.708817 -368.917919)
			(xy 36.660297 -368.953105) (xy 36.606872 -368.980273) (xy 36.549856 -368.998752) (xy 36.490652 -369.00809)
			(xy 36.460684 -369.00866) (xy 32.514032 -369.00866) (xy 32.484059 -369.008142) (xy 32.424843 -368.998822)
			(xy 32.367818 -368.980342) (xy 32.31439 -368.95316) (xy 32.265879 -368.917947) (xy 32.244284 -368.897154)
			(xy 30.99181 -367.644426) (xy 30.984397 -367.637602) (xy 30.965808 -367.629872) (xy 30.955742 -367.62944)
			(xy 30.059122 -367.62944) (xy 30.049406 -367.629856) (xy 30.031368 -367.637078) (xy 30.017313 -367.650495)
			(xy 30.012894 -367.659158) (xy 29.967936 -367.756694) (xy 29.972254 -367.785904) (xy 29.981906 -367.797334)
			(xy 29.999194 -367.818206) (xy 30.028361 -367.863884) (xy 30.050766 -367.913231) (xy 30.065959 -367.965253)
			(xy 30.073632 -368.018902) (xy 30.074108 -368.046) (xy 30.073622 -368.073251) (xy 30.065866 -368.127199)
			(xy 30.050511 -368.179494) (xy 30.027869 -368.229071) (xy 29.998403 -368.274921) (xy 29.962712 -368.316112)
			(xy 29.921521 -368.351803) (xy 29.875671 -368.381269) (xy 29.826094 -368.403911) (xy 29.773799 -368.419266)
			(xy 29.719851 -368.427022) (xy 29.6926 -368.427508) (xy 29.664775 -368.427029) (xy 29.609717 -368.418938)
			(xy 29.556421 -368.402929) (xy 29.506018 -368.379341) (xy 29.45958 -368.348675) (xy 29.418094 -368.311584)
			(xy 29.382442 -368.268855) (xy 29.36748 -368.24539) (xy 29.360114 -368.233706) (xy 29.336238 -368.220752)
			(xy 29.220668 -368.224308) (xy 29.197554 -368.238786) (xy 29.191204 -368.250724) (xy 29.176815 -368.27647)
			(xy 29.141405 -368.323633) (xy 29.099163 -368.364788) (xy 29.051094 -368.398956) (xy 28.998341 -368.425324)
			(xy 28.94216 -368.443265) (xy 28.883888 -368.452351) (xy 28.8544 -368.452908) (xy 28.827149 -368.452422)
			(xy 28.773201 -368.444666) (xy 28.720906 -368.429311) (xy 28.671329 -368.406669) (xy 28.625479 -368.377203)
			(xy 28.584288 -368.341512) (xy 28.548597 -368.300321) (xy 28.519131 -368.254471) (xy 28.496489 -368.204894)
			(xy 28.481134 -368.152599) (xy 28.473378 -368.098651) (xy 28.472892 -368.0714) (xy 28.473459 -368.041565)
			(xy 28.482761 -367.982625) (xy 28.501123 -367.925851) (xy 28.528098 -367.872627) (xy 28.563028 -367.82425)
			(xy 28.583636 -367.802668) (xy 28.594558 -367.791746) (xy 28.6004 -367.761774) (xy 28.558236 -367.660936)
			(xy 28.553941 -367.651906) (xy 28.539888 -367.637722) (xy 28.521481 -367.629984) (xy 28.5115 -367.62944)
			(xy 26.322274 -367.62944) (xy 26.313486 -367.629826) (xy 26.296946 -367.635775) (xy 26.28339 -367.646964)
			(xy 26.278586 -367.654332) (xy 26.227024 -367.740692) (xy 26.226262 -367.767362) (xy 26.232612 -367.7793)
			(xy 26.246879 -367.807202) (xy 26.267135 -367.866499) (xy 26.277423 -367.92831) (xy 26.278078 -367.95964)
			(xy 26.277592 -367.986891) (xy 26.269836 -368.040839) (xy 26.254481 -368.093134) (xy 26.231839 -368.142711)
			(xy 26.202373 -368.188561) (xy 26.166682 -368.229752) (xy 26.125491 -368.265443) (xy 26.079641 -368.294909)
			(xy 26.030064 -368.317551) (xy 25.977769 -368.332906) (xy 25.923821 -368.340662) (xy 25.869319 -368.340662)
			(xy 25.815371 -368.332906) (xy 25.763076 -368.317551) (xy 25.713499 -368.294909) (xy 25.667649 -368.265443)
			(xy 25.626458 -368.229752) (xy 25.590767 -368.188561) (xy 25.561301 -368.142711) (xy 25.538659 -368.093134)
			(xy 25.523304 -368.040839) (xy 25.515548 -367.986891) (xy 25.515062 -367.95964) (xy 25.515655 -367.92977)
			(xy 25.524967 -367.870761) (xy 25.54337 -367.813927) (xy 25.570412 -367.760659) (xy 25.587452 -367.73612)
			(xy 25.592364 -367.728589) (xy 25.597168 -367.711277) (xy 25.595721 -367.69337) (xy 25.592278 -367.685066)
			(xy 25.58034 -367.658904) (xy 25.575855 -367.650317) (xy 25.561772 -367.637038) (xy 25.543789 -367.629875)
			(xy 25.534112 -367.62944) (xy 25.514808 -367.62944) (xy 25.484834 -367.628943) (xy 25.425617 -367.619618)
			(xy 25.368591 -367.601134) (xy 25.315164 -367.573948) (xy 25.266654 -367.538729) (xy 25.24506 -367.517934)
			(xy 24.571452 -366.844326) (xy 24.550652 -366.822727) (xy 24.515396 -366.774226) (xy 24.488164 -366.720806)
			(xy 24.46963 -366.663781) (xy 24.460249 -366.604559) (xy 24.459692 -366.574578) (xy 23.815228 -366.574578)
			(xy 23.844281 -366.592309) (xy 23.887149 -366.627984) (xy 23.924366 -366.669521) (xy 23.955139 -366.716034)
			(xy 23.978811 -366.766531) (xy 23.994879 -366.819938) (xy 24.002999 -366.875114) (xy 24.003508 -366.903)
			(xy 24.002999 -366.930886) (xy 23.994879 -366.986062) (xy 23.978811 -367.039469) (xy 23.955139 -367.089966)
			(xy 23.924366 -367.136479) (xy 23.887149 -367.178016) (xy 23.844281 -367.213691) (xy 23.796675 -367.242745)
			(xy 23.745346 -367.264557) (xy 23.691389 -367.278663) (xy 23.635952 -367.284763) (xy 23.580218 -367.282726)
			(xy 23.525375 -367.272596) (xy 23.472591 -367.254589) (xy 23.422991 -367.229088) (xy 23.377633 -367.196637)
			(xy 23.337484 -367.157928) (xy 23.303398 -367.113785) (xy 23.276102 -367.06515) (xy 23.256179 -367.013059)
			(xy 23.244053 -366.958622) (xy 23.239982 -366.903) (xy 21.844508 -366.903) (xy 21.843999 -366.930886)
			(xy 21.835879 -366.986062) (xy 21.819811 -367.039469) (xy 21.796139 -367.089966) (xy 21.765366 -367.136479)
			(xy 21.728149 -367.178016) (xy 21.685281 -367.213691) (xy 21.637675 -367.242745) (xy 21.586346 -367.264557)
			(xy 21.532389 -367.278663) (xy 21.476952 -367.284763) (xy 21.421218 -367.282726) (xy 21.366375 -367.272596)
			(xy 21.313591 -367.254589) (xy 21.263991 -367.229088) (xy 21.218633 -367.196637) (xy 21.178484 -367.157928)
			(xy 21.144398 -367.113785) (xy 21.117102 -367.06515) (xy 21.097179 -367.013059) (xy 21.085053 -366.958622)
			(xy 21.080982 -366.903) (xy 20.848828 -366.903) (xy 20.848828 -367.13668) (xy 20.849317 -367.14664)
			(xy 20.856912 -367.165059) (xy 20.86356 -367.172494) (xy 21.26234 -367.571274) (xy 21.293328 -367.576862)
			(xy 21.307806 -367.570512) (xy 21.332331 -367.56007) (xy 21.383566 -367.545368) (xy 21.436349 -367.537944)
			(xy 21.463 -367.537492) (xy 21.490251 -367.537978) (xy 21.544199 -367.545734) (xy 21.596494 -367.561089)
			(xy 21.646071 -367.583731) (xy 21.691921 -367.613197) (xy 21.733112 -367.648888) (xy 21.768803 -367.690079)
			(xy 21.798269 -367.735929) (xy 21.820911 -367.785506) (xy 21.836266 -367.837801) (xy 21.844022 -367.891749)
			(xy 21.844508 -367.919) (xy 23.239982 -367.919) (xy 23.244053 -367.863378) (xy 23.256179 -367.808941)
			(xy 23.276102 -367.75685) (xy 23.303398 -367.708215) (xy 23.337484 -367.664072) (xy 23.377633 -367.625363)
			(xy 23.422991 -367.592912) (xy 23.472591 -367.567411) (xy 23.525375 -367.549404) (xy 23.580218 -367.539274)
			(xy 23.635952 -367.537237) (xy 23.691389 -367.543337) (xy 23.745346 -367.557443) (xy 23.796675 -367.579255)
			(xy 23.844281 -367.608309) (xy 23.887149 -367.643984) (xy 23.924366 -367.685521) (xy 23.955139 -367.732034)
			(xy 23.978811 -367.782531) (xy 23.994879 -367.835938) (xy 24.002999 -367.891114) (xy 24.003508 -367.919)
			(xy 24.002999 -367.946886) (xy 23.994879 -368.002062) (xy 23.978811 -368.055469) (xy 23.955139 -368.105966)
			(xy 23.924366 -368.152479) (xy 23.887149 -368.194016) (xy 23.844281 -368.229691) (xy 23.796675 -368.258745)
			(xy 23.745346 -368.280557) (xy 23.691389 -368.294663) (xy 23.635952 -368.300763) (xy 23.580218 -368.298726)
			(xy 23.525375 -368.288596) (xy 23.472591 -368.270589) (xy 23.422991 -368.245088) (xy 23.377633 -368.212637)
			(xy 23.337484 -368.173928) (xy 23.303398 -368.129785) (xy 23.276102 -368.08115) (xy 23.256179 -368.029059)
			(xy 23.244053 -367.974622) (xy 23.239982 -367.919) (xy 21.844508 -367.919) (xy 21.844063 -367.945652)
			(xy 21.836638 -367.998435) (xy 21.821931 -368.04967) (xy 21.811488 -368.074194) (xy 21.805138 -368.088672)
			(xy 21.810726 -368.11966) (xy 22.081236 -368.39017) (xy 22.088582 -368.396978) (xy 22.107045 -368.404702)
			(xy 22.11705 -368.405156) (xy 24.708612 -368.405156) (xy 24.73458 -368.405666) (xy 24.785875 -368.41379)
			(xy 24.835269 -368.429837) (xy 24.881546 -368.453411) (xy 24.923566 -368.483932) (xy 24.942292 -368.50193)
			(xy 25.356154 -368.915696) (xy 28.188666 -368.915696) (xy 28.189152 -368.888445) (xy 28.196908 -368.834497)
			(xy 28.212263 -368.782202) (xy 28.234905 -368.732625) (xy 28.264371 -368.686775) (xy 28.300062 -368.645584)
			(xy 28.341253 -368.609893) (xy 28.387103 -368.580427) (xy 28.43668 -368.557785) (xy 28.488975 -368.54243)
			(xy 28.542923 -368.534674) (xy 28.597425 -368.534674) (xy 28.651373 -368.54243) (xy 28.703668 -368.557785)
			(xy 28.753245 -368.580427) (xy 28.799095 -368.609893) (xy 28.840286 -368.645584) (xy 28.875977 -368.686775)
			(xy 28.905443 -368.732625) (xy 28.928085 -368.782202) (xy 28.94344 -368.834497) (xy 28.951196 -368.888445)
			(xy 28.951682 -368.915696) (xy 28.951134 -368.944648) (xy 28.942379 -369.001886) (xy 28.92507 -369.057143)
			(xy 28.899604 -369.109146) (xy 28.866567 -369.156701) (xy 28.847034 -369.178078) (xy 28.838027 -369.188285)
			(xy 28.825148 -369.212251) (xy 28.819066 -369.23877) (xy 28.820213 -369.265953) (xy 28.828508 -369.291865)
			(xy 28.843361 -369.31466) (xy 28.863712 -369.332717) (xy 28.888115 -369.344748) (xy 28.90139 -369.34775)
			(xy 28.927158 -369.3532) (xy 28.976996 -369.370229) (xy 29.02402 -369.393949) (xy 29.067337 -369.423908)
			(xy 29.106123 -369.459538) (xy 29.128944 -369.487196) (xy 37.296342 -369.487196) (xy 37.300413 -369.431574)
			(xy 37.312539 -369.377137) (xy 37.332462 -369.325046) (xy 37.359758 -369.276411) (xy 37.393844 -369.232268)
			(xy 37.433993 -369.193559) (xy 37.479351 -369.161108) (xy 37.528951 -369.135607) (xy 37.581735 -369.1176)
			(xy 37.636578 -369.10747) (xy 37.692312 -369.105433) (xy 37.747749 -369.111533) (xy 37.801706 -369.125639)
			(xy 37.853035 -369.147451) (xy 37.900641 -369.176505) (xy 37.943509 -369.21218) (xy 37.980726 -369.253717)
			(xy 38.011499 -369.30023) (xy 38.035171 -369.350727) (xy 38.051239 -369.404134) (xy 38.059359 -369.45931)
			(xy 38.059868 -369.487196) (xy 38.059359 -369.515082) (xy 38.051239 -369.570258) (xy 38.035171 -369.623665)
			(xy 38.011499 -369.674162) (xy 37.980726 -369.720675) (xy 37.943509 -369.762212) (xy 37.900641 -369.797887)
			(xy 37.854941 -369.825778) (xy 38.755574 -369.825778) (xy 38.755949 -369.799903) (xy 38.762937 -369.748626)
			(xy 38.776794 -369.698766) (xy 38.797266 -369.651237) (xy 38.823977 -369.606913) (xy 38.856436 -369.566608)
			(xy 38.894047 -369.531062) (xy 38.914832 -369.515644) (xy 38.92423 -369.50904) (xy 38.935152 -369.489736)
			(xy 38.942772 -369.389152) (xy 38.934898 -369.368578) (xy 38.92677 -369.36045) (xy 38.908912 -369.342468)
			(xy 38.877688 -369.302549) (xy 38.852024 -369.258848) (xy 38.832372 -369.212134) (xy 38.819077 -369.163229)
			(xy 38.812373 -369.112994) (xy 38.811962 -369.087654) (xy 38.812532 -369.058423) (xy 38.82147 -369.000647)
			(xy 38.839116 -368.944911) (xy 38.865056 -368.892518) (xy 38.898684 -368.844694) (xy 38.939212 -368.802558)
			(xy 38.985692 -368.767097) (xy 39.011098 -368.752628) (xy 39.022274 -368.746532) (xy 39.035736 -368.726466)
			(xy 39.048436 -368.619024) (xy 39.040054 -368.596418) (xy 39.030656 -368.588036) (xy 39.01124 -368.569849)
			(xy 38.977118 -368.529034) (xy 38.948992 -368.483879) (xy 38.927405 -368.435257) (xy 38.912776 -368.384109)
			(xy 38.905388 -368.331425) (xy 38.904926 -368.304826) (xy 38.90536 -368.278098) (xy 38.912844 -368.225169)
			(xy 38.927642 -368.173802) (xy 38.949465 -368.125003) (xy 38.977884 -368.079727) (xy 39.012344 -368.038861)
			(xy 39.05217 -368.003204) (xy 39.096582 -367.973454) (xy 39.144712 -367.950193) (xy 39.195618 -367.933877)
			(xy 39.248302 -367.924825) (xy 39.275004 -367.923572) (xy 39.286434 -367.923064) (xy 39.306246 -367.913158)
			(xy 39.36873 -367.834164) (xy 39.37381 -367.812574) (xy 39.371524 -367.801398) (xy 39.367842 -367.782307)
			(xy 39.3639 -367.743624) (xy 39.36365 -367.724182) (xy 39.364136 -367.696931) (xy 39.371892 -367.642983)
			(xy 39.387247 -367.590688) (xy 39.409889 -367.541111) (xy 39.439355 -367.495261) (xy 39.475046 -367.45407)
			(xy 39.516237 -367.418379) (xy 39.562087 -367.388913) (xy 39.611664 -367.366271) (xy 39.663959 -367.350916)
			(xy 39.717907 -367.34316) (xy 39.772409 -367.34316) (xy 39.826357 -367.350916) (xy 39.878652 -367.366271)
			(xy 39.928229 -367.388913) (xy 39.974079 -367.418379) (xy 40.01527 -367.45407) (xy 40.050961 -367.495261)
			(xy 40.080427 -367.541111) (xy 40.103069 -367.590688) (xy 40.118424 -367.642983) (xy 40.12618 -367.696931)
			(xy 40.126666 -367.724182) (xy 40.126248 -367.75091) (xy 40.118762 -367.803841) (xy 40.103962 -367.855208)
			(xy 40.082138 -367.904008) (xy 40.053718 -367.949284) (xy 40.019256 -367.990151) (xy 39.979429 -368.025808)
			(xy 39.935014 -368.055557) (xy 39.886883 -368.078817) (xy 39.835976 -368.095132) (xy 39.783291 -368.104183)
			(xy 39.756588 -368.105436) (xy 39.745158 -368.105944) (xy 39.725346 -368.11585) (xy 39.662862 -368.194844)
			(xy 39.657782 -368.216434) (xy 39.660068 -368.22761) (xy 39.663751 -368.246701) (xy 39.667692 -368.285384)
			(xy 39.667942 -368.304826) (xy 39.667354 -368.334057) (xy 39.658419 -368.391831) (xy 39.640776 -368.447567)
			(xy 39.614839 -368.49996) (xy 39.581214 -368.547784) (xy 39.540688 -368.58992) (xy 39.494211 -368.625383)
			(xy 39.468806 -368.639852) (xy 39.45763 -368.645948) (xy 39.444168 -368.666014) (xy 39.431468 -368.773456)
			(xy 39.43985 -368.796062) (xy 39.449248 -368.804444) (xy 39.468655 -368.82264) (xy 39.502778 -368.863453)
			(xy 39.530906 -368.908606) (xy 39.552494 -368.957227) (xy 39.567125 -369.008373) (xy 39.574515 -369.061055)
			(xy 39.574978 -369.087654) (xy 39.57453 -369.113527) (xy 39.567553 -369.164799) (xy 39.553707 -369.214657)
			(xy 39.533246 -369.262185) (xy 39.506547 -369.30651) (xy 39.474099 -369.346817) (xy 39.436499 -369.382367)
			(xy 39.41572 -369.397788) (xy 39.406322 -369.404392) (xy 39.3954 -369.423696) (xy 39.38778 -369.52428)
			(xy 39.395654 -369.544854) (xy 39.403782 -369.552982) (xy 39.421598 -369.571003) (xy 39.452828 -369.610913)
			(xy 39.478499 -369.654606) (xy 39.498159 -369.701312) (xy 39.511462 -369.750211) (xy 39.518174 -369.80044)
			(xy 39.51859 -369.825778) (xy 39.518104 -369.853029) (xy 39.510348 -369.906977) (xy 39.494993 -369.959272)
			(xy 39.472351 -370.008849) (xy 39.442885 -370.054699) (xy 39.407194 -370.09589) (xy 39.366003 -370.131581)
			(xy 39.320153 -370.161047) (xy 39.270576 -370.183689) (xy 39.218281 -370.199044) (xy 39.164333 -370.2068)
			(xy 39.109831 -370.2068) (xy 39.055883 -370.199044) (xy 39.003588 -370.183689) (xy 38.954011 -370.161047)
			(xy 38.908161 -370.131581) (xy 38.86697 -370.09589) (xy 38.831279 -370.054699) (xy 38.801813 -370.008849)
			(xy 38.779171 -369.959272) (xy 38.763816 -369.906977) (xy 38.75606 -369.853029) (xy 38.755574 -369.825778)
			(xy 37.854941 -369.825778) (xy 37.853035 -369.826941) (xy 37.801706 -369.848753) (xy 37.747749 -369.862859)
			(xy 37.692312 -369.868959) (xy 37.636578 -369.866922) (xy 37.581735 -369.856792) (xy 37.528951 -369.838785)
			(xy 37.479351 -369.813284) (xy 37.433993 -369.780833) (xy 37.393844 -369.742124) (xy 37.359758 -369.697981)
			(xy 37.332462 -369.649346) (xy 37.312539 -369.597255) (xy 37.300413 -369.542818) (xy 37.296342 -369.487196)
			(xy 29.128944 -369.487196) (xy 29.139643 -369.500163) (xy 29.167259 -369.54501) (xy 29.188447 -369.593228)
			(xy 29.202804 -369.643901) (xy 29.210059 -369.696066) (xy 29.210508 -369.7224) (xy 29.210022 -369.749651)
			(xy 29.202266 -369.803599) (xy 29.186911 -369.855894) (xy 29.164269 -369.905471) (xy 29.134803 -369.951321)
			(xy 29.099112 -369.992512) (xy 29.057921 -370.028203) (xy 29.012071 -370.057669) (xy 28.962494 -370.080311)
			(xy 28.910199 -370.095666) (xy 28.856251 -370.103422) (xy 28.801749 -370.103422) (xy 28.747801 -370.095666)
			(xy 28.695506 -370.080311) (xy 28.645929 -370.057669) (xy 28.600079 -370.028203) (xy 28.558888 -369.992512)
			(xy 28.523197 -369.951321) (xy 28.493731 -369.905471) (xy 28.471089 -369.855894) (xy 28.455734 -369.803599)
			(xy 28.447978 -369.749651) (xy 28.447492 -369.7224) (xy 28.448017 -369.693447) (xy 28.456775 -369.636207)
			(xy 28.474088 -369.580949) (xy 28.49956 -369.528946) (xy 28.532603 -369.481393) (xy 28.55214 -369.460018)
			(xy 28.561165 -369.449824) (xy 28.574048 -369.425855) (xy 28.580133 -369.399332) (xy 28.578985 -369.372144)
			(xy 28.570687 -369.346228) (xy 28.55583 -369.32343) (xy 28.535472 -369.305374) (xy 28.511062 -369.293345)
			(xy 28.497784 -369.290346) (xy 28.472027 -369.284846) (xy 28.422188 -369.267826) (xy 28.375163 -369.244115)
			(xy 28.331845 -369.214162) (xy 28.293056 -369.178538) (xy 28.259535 -369.137919) (xy 28.231917 -369.093076)
			(xy 28.210728 -369.044861) (xy 28.19637 -368.994191) (xy 28.189115 -368.942028) (xy 28.188666 -368.915696)
			(xy 25.356154 -368.915696) (xy 26.040334 -369.599718) (xy 26.047677 -369.606532) (xy 26.066141 -369.614265)
			(xy 26.076148 -369.614704) (xy 26.578306 -369.614704) (xy 26.588376 -369.615128) (xy 26.606978 -369.622845)
			(xy 26.614374 -369.62969) (xy 27.316684 -370.332) (xy 29.11297 -370.332) (xy 29.117041 -370.276378)
			(xy 29.129167 -370.221941) (xy 29.14909 -370.16985) (xy 29.176386 -370.121215) (xy 29.210472 -370.077072)
			(xy 29.250621 -370.038363) (xy 29.295979 -370.005912) (xy 29.345579 -369.980411) (xy 29.398363 -369.962404)
			(xy 29.453206 -369.952274) (xy 29.50894 -369.950237) (xy 29.564377 -369.956337) (xy 29.618334 -369.970443)
			(xy 29.669663 -369.992255) (xy 29.717269 -370.021309) (xy 29.760137 -370.056984) (xy 29.797354 -370.098521)
			(xy 29.828127 -370.145034) (xy 29.851799 -370.195531) (xy 29.867867 -370.248938) (xy 29.875987 -370.304114)
			(xy 29.876496 -370.332) (xy 29.875987 -370.359886) (xy 29.867867 -370.415062) (xy 29.851799 -370.468469)
			(xy 29.828127 -370.518966) (xy 29.797354 -370.565479) (xy 29.760137 -370.607016) (xy 29.717269 -370.642691)
			(xy 29.669663 -370.671745) (xy 29.618334 -370.693557) (xy 29.564377 -370.707663) (xy 29.50894 -370.713763)
			(xy 29.453206 -370.711726) (xy 29.398363 -370.701596) (xy 29.345579 -370.683589) (xy 29.295979 -370.658088)
			(xy 29.250621 -370.625637) (xy 29.210472 -370.586928) (xy 29.176386 -370.542785) (xy 29.14909 -370.49415)
			(xy 29.129167 -370.442059) (xy 29.117041 -370.387622) (xy 29.11297 -370.332) (xy 27.316684 -370.332)
			(xy 27.900884 -370.9162) (xy 29.869382 -370.9162) (xy 29.873453 -370.860578) (xy 29.885579 -370.806141)
			(xy 29.905502 -370.75405) (xy 29.932798 -370.705415) (xy 29.966884 -370.661272) (xy 30.007033 -370.622563)
			(xy 30.052391 -370.590112) (xy 30.101991 -370.564611) (xy 30.154775 -370.546604) (xy 30.209618 -370.536474)
			(xy 30.265352 -370.534437) (xy 30.320789 -370.540537) (xy 30.374746 -370.554643) (xy 30.426075 -370.576455)
			(xy 30.473681 -370.605509) (xy 30.516549 -370.641184) (xy 30.553766 -370.682721) (xy 30.584539 -370.729234)
			(xy 30.608211 -370.779731) (xy 30.624279 -370.833138) (xy 30.632399 -370.888314) (xy 30.632908 -370.9162)
			(xy 30.632399 -370.944086) (xy 30.624279 -370.999262) (xy 30.608211 -371.052669) (xy 30.584539 -371.103166)
			(xy 30.553766 -371.149679) (xy 30.516549 -371.191216) (xy 30.473681 -371.226891) (xy 30.426075 -371.255945)
			(xy 30.374746 -371.277757) (xy 30.320789 -371.291863) (xy 30.265352 -371.297963) (xy 30.209618 -371.295926)
			(xy 30.154775 -371.285796) (xy 30.101991 -371.267789) (xy 30.052391 -371.242288) (xy 30.007033 -371.209837)
			(xy 29.966884 -371.171128) (xy 29.932798 -371.126985) (xy 29.905502 -371.07835) (xy 29.885579 -371.026259)
			(xy 29.873453 -370.971822) (xy 29.869382 -370.9162) (xy 27.900884 -370.9162) (xy 28.085796 -371.101112)
			(xy 28.093206 -371.107795) (xy 28.111642 -371.115377) (xy 28.12161 -371.115844) (xy 28.941268 -371.115844)
			(xy 28.967249 -371.116341) (xy 29.018568 -371.124502) (xy 29.067975 -371.140597) (xy 29.114254 -371.164228)
			(xy 29.156263 -371.194813) (xy 29.174948 -371.212872) (xy 29.66847 -371.70614) (xy 29.675816 -371.712946)
			(xy 29.694279 -371.720663) (xy 29.704284 -371.721126) (xy 32.304228 -371.721126)
		)
		(stroke
			(width 0)
			(type solid)
		)
		(fill yes)
		(layer "In13.Cu")
		(net "GND")
	)
	(gr_poly
		(pts
			(xy 121.552716 -262.94842) (xy 121.561728 -262.947647) (xy 121.57838 -262.940614) (xy 121.585228 -262.934704)
			(xy 121.590816 -262.928608) (xy 121.639838 -262.865362) (xy 121.646478 -262.855747) (xy 121.651095 -262.832864)
			(xy 121.648728 -262.82142) (xy 121.644423 -262.803371) (xy 121.639708 -262.766565) (xy 121.63933 -262.748014)
			(xy 121.63933 -262.743442) (xy 121.640069 -262.718338) (xy 121.64874 -262.668873) (xy 121.665389 -262.621494)
			(xy 121.689567 -262.577478) (xy 121.720622 -262.538012) (xy 121.757716 -262.50416) (xy 121.79985 -262.476835)
			(xy 121.845888 -262.456773) (xy 121.894588 -262.444515) (xy 121.944638 -262.440392) (xy 121.994688 -262.444515)
			(xy 122.043388 -262.456773) (xy 122.089426 -262.476835) (xy 122.13156 -262.50416) (xy 122.168654 -262.538012)
			(xy 122.199709 -262.577478) (xy 122.223887 -262.621494) (xy 122.240536 -262.668873) (xy 122.249207 -262.718338)
			(xy 122.249946 -262.743442) (xy 122.249946 -262.74649) (xy 122.249643 -262.765424) (xy 122.244928 -262.802997)
			(xy 122.240548 -262.82142) (xy 122.238123 -262.832864) (xy 122.242743 -262.85577) (xy 122.249438 -262.865362)
			(xy 122.29846 -262.928608) (xy 122.304048 -262.934704) (xy 122.310891 -262.940617) (xy 122.327549 -262.947628)
			(xy 122.33656 -262.94842) (xy 122.490484 -262.94842) (xy 122.49277 -262.94842) (xy 122.501786 -262.947655)
			(xy 122.518447 -262.940632) (xy 122.525282 -262.934704) (xy 122.53087 -262.928608) (xy 122.579892 -262.865362)
			(xy 122.586537 -262.855748) (xy 122.591158 -262.832864) (xy 122.588782 -262.82142) (xy 122.584477 -262.803371)
			(xy 122.579761 -262.766565) (xy 122.579384 -262.748014) (xy 122.579384 -262.743442) (xy 122.580123 -262.718338)
			(xy 122.588794 -262.668873) (xy 122.605443 -262.621494) (xy 122.629621 -262.577478) (xy 122.660676 -262.538012)
			(xy 122.69777 -262.50416) (xy 122.739904 -262.476835) (xy 122.785942 -262.456773) (xy 122.834642 -262.444515)
			(xy 122.884692 -262.440392) (xy 122.934742 -262.444515) (xy 122.983442 -262.456773) (xy 123.02948 -262.476835)
			(xy 123.071614 -262.50416) (xy 123.108708 -262.538012) (xy 123.139763 -262.577478) (xy 123.163941 -262.621494)
			(xy 123.18059 -262.668873) (xy 123.189261 -262.718338) (xy 123.19 -262.743442) (xy 123.19 -262.74649)
			(xy 123.189697 -262.765424) (xy 123.184981 -262.802997) (xy 123.180602 -262.82142) (xy 123.178176 -262.832864)
			(xy 123.182801 -262.855768) (xy 123.189492 -262.865362) (xy 123.238514 -262.928608) (xy 123.244102 -262.934704)
			(xy 123.250943 -262.940623) (xy 123.2676 -262.947649) (xy 123.276614 -262.94842) (xy 123.430538 -262.94842)
			(xy 123.432824 -262.94842) (xy 123.441836 -262.947646) (xy 123.458485 -262.940611) (xy 123.465336 -262.934704)
			(xy 123.470924 -262.928608) (xy 123.519946 -262.865362) (xy 123.526596 -262.855749) (xy 123.531221 -262.832863)
			(xy 123.528836 -262.82142) (xy 123.524531 -262.803371) (xy 123.519816 -262.766565) (xy 123.519438 -262.748014)
			(xy 123.519438 -262.743442) (xy 123.520177 -262.718338) (xy 123.528848 -262.668873) (xy 123.545497 -262.621494)
			(xy 123.569675 -262.577478) (xy 123.60073 -262.538012) (xy 123.637824 -262.50416) (xy 123.679958 -262.476835)
			(xy 123.725996 -262.456773) (xy 123.774696 -262.444515) (xy 123.824746 -262.440392) (xy 123.874796 -262.444515)
			(xy 123.923496 -262.456773) (xy 123.969534 -262.476835) (xy 124.011668 -262.50416) (xy 124.048762 -262.538012)
			(xy 124.079817 -262.577478) (xy 124.103995 -262.621494) (xy 124.120644 -262.668873) (xy 124.129315 -262.718338)
			(xy 124.130054 -262.743442) (xy 124.130054 -262.74649) (xy 124.129751 -262.765424) (xy 124.125036 -262.802997)
			(xy 124.120656 -262.82142) (xy 124.118231 -262.832864) (xy 124.122852 -262.85577) (xy 124.129546 -262.865362)
			(xy 124.178568 -262.928608) (xy 124.184156 -262.934704) (xy 124.191 -262.940616) (xy 124.207658 -262.947624)
			(xy 124.216668 -262.94842) (xy 125.310646 -262.94842) (xy 125.312932 -262.94842) (xy 125.321943 -262.947645)
			(xy 125.338591 -262.940607) (xy 125.345444 -262.934704) (xy 125.351032 -262.928608) (xy 125.400054 -262.865362)
			(xy 125.406703 -262.855749) (xy 125.411328 -262.832863) (xy 125.408944 -262.82142) (xy 125.404639 -262.803371)
			(xy 125.399924 -262.766565) (xy 125.399546 -262.748014) (xy 125.399546 -262.743442) (xy 125.400285 -262.718338)
			(xy 125.408956 -262.668873) (xy 125.425605 -262.621494) (xy 125.449783 -262.577478) (xy 125.480838 -262.538012)
			(xy 125.517932 -262.50416) (xy 125.560066 -262.476835) (xy 125.606104 -262.456773) (xy 125.654804 -262.444515)
			(xy 125.704854 -262.440392) (xy 125.754904 -262.444515) (xy 125.803604 -262.456773) (xy 125.849642 -262.476835)
			(xy 125.891776 -262.50416) (xy 125.92887 -262.538012) (xy 125.959925 -262.577478) (xy 125.984103 -262.621494)
			(xy 126.000752 -262.668873) (xy 126.009423 -262.718338) (xy 126.010162 -262.743442) (xy 126.010162 -262.74649)
			(xy 126.009859 -262.765424) (xy 126.005144 -262.802997) (xy 126.000764 -262.82142) (xy 125.998339 -262.832864)
			(xy 126.002961 -262.85577) (xy 126.009654 -262.865362) (xy 126.058676 -262.928608) (xy 126.064264 -262.934704)
			(xy 126.071108 -262.940615) (xy 126.087767 -262.94762) (xy 126.096776 -262.94842) (xy 127.1905 -262.94842)
			(xy 127.192786 -262.94842) (xy 127.2018 -262.947652) (xy 127.218459 -262.940626) (xy 127.225298 -262.934704)
			(xy 127.230886 -262.928608) (xy 127.279908 -262.865362) (xy 127.286551 -262.855747) (xy 127.291171 -262.832864)
			(xy 127.288798 -262.82142) (xy 127.284494 -262.803371) (xy 127.279779 -262.766565) (xy 127.2794 -262.748014)
			(xy 127.2794 -262.743442) (xy 127.280139 -262.718338) (xy 127.28881 -262.668873) (xy 127.305459 -262.621494)
			(xy 127.329637 -262.577478) (xy 127.360692 -262.538012) (xy 127.397786 -262.50416) (xy 127.43992 -262.476835)
			(xy 127.485958 -262.456773) (xy 127.534658 -262.444515) (xy 127.584708 -262.440392) (xy 127.634758 -262.444515)
			(xy 127.683458 -262.456773) (xy 127.729496 -262.476835) (xy 127.77163 -262.50416) (xy 127.808724 -262.538012)
			(xy 127.839779 -262.577478) (xy 127.863957 -262.621494) (xy 127.880606 -262.668873) (xy 127.889277 -262.718338)
			(xy 127.890016 -262.743442) (xy 127.890016 -262.74649) (xy 127.889713 -262.765424) (xy 127.884998 -262.802997)
			(xy 127.880618 -262.82142) (xy 127.878194 -262.832865) (xy 127.882812 -262.855771) (xy 127.889508 -262.865362)
			(xy 127.93853 -262.928608) (xy 127.944118 -262.934704) (xy 127.95096 -262.940621) (xy 127.967617 -262.947642)
			(xy 127.97663 -262.94842) (xy 128.12649 -262.94842) (xy 128.128776 -262.94842) (xy 128.138508 -262.947542)
			(xy 128.156271 -262.939439) (xy 128.16332 -262.932672) (xy 128.166622 -262.928862) (xy 128.218184 -262.862314)
			(xy 128.22301 -262.8392) (xy 128.219962 -262.827516) (xy 128.214917 -262.807573) (xy 128.209438 -262.766803)
			(xy 128.20904 -262.746236) (xy 128.209527 -262.721426) (xy 128.217289 -262.672418) (xy 128.232622 -262.625228)
			(xy 128.255149 -262.581017) (xy 128.284314 -262.540874) (xy 128.3194 -262.505788) (xy 128.359543 -262.476623)
			(xy 128.403754 -262.454096) (xy 128.450944 -262.438763) (xy 128.499952 -262.431001) (xy 128.549572 -262.431001)
			(xy 128.59858 -262.438763) (xy 128.64577 -262.454096) (xy 128.689981 -262.476623) (xy 128.730124 -262.505788)
			(xy 128.76521 -262.540874) (xy 128.794375 -262.581017) (xy 128.816902 -262.625228) (xy 128.832235 -262.672418)
			(xy 128.839997 -262.721426) (xy 128.840484 -262.746236) (xy 128.840084 -262.766803) (xy 128.834602 -262.807572)
			(xy 128.829562 -262.827516) (xy 128.826514 -262.8392) (xy 128.83134 -262.862314) (xy 128.882902 -262.928862)
			(xy 128.886204 -262.932672) (xy 128.893249 -262.939448) (xy 128.911013 -262.947563) (xy 128.920748 -262.94842)
			(xy 129.066544 -262.94842) (xy 129.06883 -262.94842) (xy 129.078566 -262.94755) (xy 129.09634 -262.939458)
			(xy 129.103374 -262.932672) (xy 129.106676 -262.928862) (xy 129.158238 -262.862314) (xy 129.163064 -262.8392)
			(xy 129.160016 -262.827516) (xy 129.155037 -262.807565) (xy 129.149681 -262.766796) (xy 129.149348 -262.746236)
			(xy 129.149834 -262.721446) (xy 129.15759 -262.672478) (xy 129.172911 -262.625325) (xy 129.19542 -262.58115)
			(xy 129.224562 -262.541039) (xy 129.259619 -262.505982) (xy 129.29973 -262.47684) (xy 129.343905 -262.454331)
			(xy 129.391058 -262.43901) (xy 129.440026 -262.431254) (xy 129.489606 -262.431254) (xy 129.538574 -262.43901)
			(xy 129.585727 -262.454331) (xy 129.629902 -262.47684) (xy 129.670013 -262.505982) (xy 129.70507 -262.541039)
			(xy 129.734212 -262.58115) (xy 129.756721 -262.625325) (xy 129.772042 -262.672478) (xy 129.779798 -262.721446)
			(xy 129.780284 -262.746236) (xy 129.779954 -262.766796) (xy 129.774602 -262.807567) (xy 129.769616 -262.827516)
			(xy 129.766568 -262.8392) (xy 129.771394 -262.862314) (xy 129.822956 -262.928862) (xy 129.826258 -262.932672)
			(xy 129.833305 -262.93944) (xy 129.851071 -262.947536) (xy 129.860802 -262.94842) (xy 130.010662 -262.94842)
			(xy 130.012948 -262.94842) (xy 130.021965 -262.947658) (xy 130.038632 -262.940641) (xy 130.04546 -262.934704)
			(xy 130.051048 -262.928608) (xy 130.10007 -262.865362) (xy 130.106717 -262.855749) (xy 130.11134 -262.832863)
			(xy 130.10896 -262.82142) (xy 130.104655 -262.803371) (xy 130.099939 -262.766565) (xy 130.099562 -262.748014)
			(xy 130.099562 -262.743442) (xy 130.100301 -262.718338) (xy 130.108972 -262.668873) (xy 130.125621 -262.621494)
			(xy 130.149799 -262.577478) (xy 130.180854 -262.538012) (xy 130.217948 -262.50416) (xy 130.260082 -262.476835)
			(xy 130.30612 -262.456773) (xy 130.35482 -262.444515) (xy 130.40487 -262.440392) (xy 130.45492 -262.444515)
			(xy 130.50362 -262.456773) (xy 130.549658 -262.476835) (xy 130.591792 -262.50416) (xy 130.628886 -262.538012)
			(xy 130.659941 -262.577478) (xy 130.684119 -262.621494) (xy 130.700768 -262.668873) (xy 130.709439 -262.718338)
			(xy 130.710178 -262.743442) (xy 130.710178 -262.74649) (xy 130.709875 -262.765424) (xy 130.705161 -262.802997)
			(xy 130.70078 -262.82142) (xy 130.698355 -262.832864) (xy 130.702977 -262.855769) (xy 130.70967 -262.865362)
			(xy 130.758692 -262.928608) (xy 130.76428 -262.934704) (xy 130.77112 -262.940626) (xy 130.787777 -262.947659)
			(xy 130.796792 -262.94842) (xy 130.946398 -262.94842) (xy 130.948684 -262.94842) (xy 130.958415 -262.947541)
			(xy 130.976176 -262.939436) (xy 130.983228 -262.932672) (xy 130.98653 -262.928862) (xy 131.038092 -262.862314)
			(xy 131.042918 -262.8392) (xy 131.03987 -262.827516) (xy 131.034825 -262.807573) (xy 131.029345 -262.766803)
			(xy 131.028948 -262.746236) (xy 131.029435 -262.721426) (xy 131.037197 -262.672418) (xy 131.05253 -262.625228)
			(xy 131.075057 -262.581017) (xy 131.104222 -262.540874) (xy 131.139308 -262.505788) (xy 131.179451 -262.476623)
			(xy 131.223662 -262.454096) (xy 131.270852 -262.438763) (xy 131.31986 -262.431001) (xy 131.36948 -262.431001)
			(xy 131.418488 -262.438763) (xy 131.465678 -262.454096) (xy 131.509889 -262.476623) (xy 131.550032 -262.505788)
			(xy 131.585118 -262.540874) (xy 131.614283 -262.581017) (xy 131.63681 -262.625228) (xy 131.652143 -262.672418)
			(xy 131.659905 -262.721426) (xy 131.660392 -262.746236) (xy 131.659992 -262.766803) (xy 131.65451 -262.807572)
			(xy 131.64947 -262.827516) (xy 131.646422 -262.8392) (xy 131.651248 -262.862314) (xy 131.70281 -262.928862)
			(xy 131.706112 -262.932672) (xy 131.713157 -262.939447) (xy 131.730921 -262.947559) (xy 131.740656 -262.94842)
			(xy 131.890516 -262.94842) (xy 131.892802 -262.94842) (xy 131.901815 -262.947649) (xy 131.91847 -262.940619)
			(xy 131.925314 -262.934704) (xy 131.930902 -262.928608) (xy 131.979924 -262.865362) (xy 131.986565 -262.855747)
			(xy 131.991184 -262.832864) (xy 131.988814 -262.82142) (xy 131.984509 -262.803371) (xy 131.979795 -262.766565)
			(xy 131.979416 -262.748014) (xy 131.979416 -262.743442) (xy 131.980155 -262.718338) (xy 131.988826 -262.668873)
			(xy 132.005475 -262.621494) (xy 132.029653 -262.577478) (xy 132.060708 -262.538012) (xy 132.097802 -262.50416)
			(xy 132.139936 -262.476835) (xy 132.185974 -262.456773) (xy 132.234674 -262.444515) (xy 132.284724 -262.440392)
			(xy 132.334774 -262.444515) (xy 132.383474 -262.456773) (xy 132.429512 -262.476835) (xy 132.471646 -262.50416)
			(xy 132.50874 -262.538012) (xy 132.539795 -262.577478) (xy 132.563973 -262.621494) (xy 132.580622 -262.668873)
			(xy 132.589293 -262.718338) (xy 132.590032 -262.743442) (xy 132.590032 -262.74649) (xy 132.589729 -262.765424)
			(xy 132.585014 -262.802997) (xy 132.580634 -262.82142) (xy 132.57821 -262.832864) (xy 132.582829 -262.855771)
			(xy 132.589524 -262.865362) (xy 132.638546 -262.928608) (xy 132.644134 -262.934704) (xy 132.650976 -262.940619)
			(xy 132.667634 -262.947635) (xy 132.676646 -262.94842) (xy 132.678932 -262.94842) (xy 132.826506 -262.94842)
			(xy 132.828792 -262.94842) (xy 132.838523 -262.94754) (xy 132.856281 -262.939433) (xy 132.863336 -262.932672)
			(xy 132.866638 -262.928862) (xy 132.9182 -262.862314) (xy 132.923026 -262.8392) (xy 132.919978 -262.827516)
			(xy 132.914933 -262.807573) (xy 132.909453 -262.766803) (xy 132.909056 -262.746236) (xy 132.909515 -262.721431)
			(xy 132.917276 -262.67243) (xy 132.93261 -262.625249) (xy 132.955141 -262.58105) (xy 132.984313 -262.540922)
			(xy 133.019406 -262.505856) (xy 133.059557 -262.476714) (xy 133.103773 -262.454217) (xy 133.150966 -262.438919)
			(xy 133.199972 -262.431196) (xy 133.224778 -262.430768) (xy 133.247099 -262.431139) (xy 133.291301 -262.4374)
			(xy 133.334178 -262.449829) (xy 133.374875 -262.468177) (xy 133.393942 -262.47979) (xy 133.403949 -262.485549)
			(xy 133.426854 -262.488262) (xy 133.448643 -262.480697) (xy 133.457188 -262.472932) (xy 133.56717 -262.36295)
			(xy 133.575113 -262.354191) (xy 133.582641 -262.331809) (xy 133.581648 -262.320024) (xy 133.568948 -262.227822)
			(xy 133.55574 -262.208264) (xy 133.545072 -262.202422) (xy 133.525138 -262.190733) (xy 133.488724 -262.162285)
			(xy 133.457015 -262.128672) (xy 133.430734 -262.090665) (xy 133.410482 -262.04913) (xy 133.396721 -262.005017)
			(xy 133.389767 -261.959335) (xy 133.38937 -261.93623) (xy 133.389855 -261.911728) (xy 133.397682 -261.863352)
			(xy 133.413141 -261.816849) (xy 133.435833 -261.773415) (xy 133.465175 -261.734166) (xy 133.500414 -261.700111)
			(xy 133.540642 -261.672126) (xy 133.584825 -261.65093) (xy 133.631829 -261.637068) (xy 133.65607 -261.633462)
			(xy 133.675374 -261.630922) (xy 133.70052 -261.60222) (xy 133.70052 -256.930144) (xy 133.700368 -256.924276)
			(xy 133.69767 -256.912856) (xy 133.695186 -256.907538) (xy 133.682994 -256.8829) (xy 133.67639 -256.874772)
			(xy 133.672072 -256.871216) (xy 133.653265 -256.855288) (xy 133.62055 -256.818429) (xy 133.59418 -256.776793)
			(xy 133.57484 -256.731463) (xy 133.563032 -256.683616) (xy 133.559062 -256.634492) (xy 133.563034 -256.585369)
			(xy 133.574845 -256.537522) (xy 133.594187 -256.492193) (xy 133.620559 -256.450559) (xy 133.653276 -256.413702)
			(xy 133.672072 -256.39776) (xy 133.67639 -256.394204) (xy 133.682994 -256.386076) (xy 133.695186 -256.361438)
			(xy 133.697645 -256.356112) (xy 133.700334 -256.344696) (xy 133.70052 -256.338832) (xy 133.70052 -256.176272)
			(xy 133.700372 -256.170199) (xy 133.697543 -256.158389) (xy 133.694932 -256.152904) (xy 133.691332 -256.146608)
			(xy 133.681278 -256.136162) (xy 133.67512 -256.13233) (xy 133.59892 -256.088388) (xy 133.590994 -256.084214)
			(xy 133.573355 -256.08116) (xy 133.555746 -256.084384) (xy 133.547866 -256.088642) (xy 133.524433 -256.10157)
			(xy 133.47416 -256.11991) (xy 133.421461 -256.129214) (xy 133.394704 -256.12979) (xy 133.369448 -256.129298)
			(xy 133.319623 -256.120984) (xy 133.271847 -256.104583) (xy 133.227422 -256.080542) (xy 133.18756 -256.049517)
			(xy 133.153349 -256.012353) (xy 133.125721 -255.970066) (xy 133.10543 -255.923808) (xy 133.093029 -255.87484)
			(xy 133.088858 -255.8245) (xy 133.093029 -255.77416) (xy 133.10543 -255.725192) (xy 133.125721 -255.678934)
			(xy 133.153349 -255.636647) (xy 133.18756 -255.599483) (xy 133.227422 -255.568458) (xy 133.271847 -255.544417)
			(xy 133.319623 -255.528016) (xy 133.369448 -255.519702) (xy 133.394704 -255.519174) (xy 133.421462 -255.519727)
			(xy 133.474162 -255.529041) (xy 133.524437 -255.547384) (xy 133.547866 -255.560322) (xy 133.55578 -255.564475)
			(xy 133.573355 -255.567646) (xy 133.59096 -255.564642) (xy 133.59892 -255.560576) (xy 133.67512 -255.516634)
			(xy 133.681308 -255.512841) (xy 133.691357 -255.502378) (xy 133.694932 -255.49606) (xy 133.70052 -255.484884)
			(xy 133.70052 -255.310132) (xy 133.700367 -255.304265) (xy 133.697666 -255.292846) (xy 133.695186 -255.287526)
			(xy 133.682994 -255.262888) (xy 133.67639 -255.25476) (xy 133.672072 -255.251204) (xy 133.653266 -255.235276)
			(xy 133.620553 -255.198417) (xy 133.594185 -255.156782) (xy 133.574846 -255.111453) (xy 133.56304 -255.063607)
			(xy 133.559072 -255.014485) (xy 133.563045 -254.965363) (xy 133.574856 -254.917518) (xy 133.594199 -254.872191)
			(xy 133.620571 -254.830559) (xy 133.653287 -254.793703) (xy 133.672072 -254.777748) (xy 133.67639 -254.774192)
			(xy 133.682994 -254.766064) (xy 133.695186 -254.741426) (xy 133.697644 -254.7361) (xy 133.70033 -254.724684)
			(xy 133.70052 -254.71882) (xy 133.70052 -254.55626) (xy 133.700371 -254.550188) (xy 133.697539 -254.538379)
			(xy 133.694932 -254.532892) (xy 133.691331 -254.526597) (xy 133.681276 -254.516153) (xy 133.67512 -254.512318)
			(xy 133.59892 -254.468376) (xy 133.590994 -254.464203) (xy 133.573355 -254.461149) (xy 133.555746 -254.464372)
			(xy 133.547866 -254.46863) (xy 133.524433 -254.481559) (xy 133.47416 -254.4999) (xy 133.421461 -254.509204)
			(xy 133.394704 -254.509778) (xy 133.369449 -254.509286) (xy 133.319626 -254.500973) (xy 133.271852 -254.484572)
			(xy 133.227429 -254.460532) (xy 133.187569 -254.429508) (xy 133.153358 -254.392346) (xy 133.125731 -254.35006)
			(xy 133.105441 -254.303804) (xy 133.093041 -254.254838) (xy 133.08887 -254.2045) (xy 133.093041 -254.154162)
			(xy 133.105441 -254.105196) (xy 133.125731 -254.05894) (xy 133.153358 -254.016654) (xy 133.187569 -253.979492)
			(xy 133.227429 -253.948468) (xy 133.271852 -253.924428) (xy 133.319626 -253.908027) (xy 133.369449 -253.899714)
			(xy 133.394704 -253.899162) (xy 133.421462 -253.899716) (xy 133.474161 -253.909032) (xy 133.524433 -253.92738)
			(xy 133.547866 -253.94031) (xy 133.55578 -253.944463) (xy 133.573355 -253.947635) (xy 133.59096 -253.94463)
			(xy 133.59892 -253.940564) (xy 133.67512 -253.896622) (xy 133.681314 -253.892834) (xy 133.691379 -253.882379)
			(xy 133.694932 -253.876048) (xy 133.70052 -253.864872) (xy 133.70052 -253.69012) (xy 133.700365 -253.684253)
			(xy 133.697662 -253.672835) (xy 133.695186 -253.667514) (xy 133.682994 -253.642876) (xy 133.67639 -253.634748)
			(xy 133.672072 -253.631192) (xy 133.653266 -253.615264) (xy 133.620556 -253.578405) (xy 133.594189 -253.536771)
			(xy 133.574853 -253.491443) (xy 133.563048 -253.443598) (xy 133.559081 -253.394477) (xy 133.563055 -253.345357)
			(xy 133.574867 -253.297514) (xy 133.594211 -253.252188) (xy 133.620583 -253.210558) (xy 133.653299 -253.173705)
			(xy 133.672072 -253.157736) (xy 133.67639 -253.15418) (xy 133.682994 -253.146052) (xy 133.695186 -253.121414)
			(xy 133.697643 -253.116087) (xy 133.700326 -253.104671) (xy 133.70052 -253.098808) (xy 133.70052 -252.936248)
			(xy 133.700381 -252.930173) (xy 133.697567 -252.918355) (xy 133.694932 -252.91288) (xy 133.69133 -252.906586)
			(xy 133.681274 -252.896144) (xy 133.67512 -252.892306) (xy 133.59892 -252.848364) (xy 133.590994 -252.844192)
			(xy 133.573355 -252.841139) (xy 133.555747 -252.844361) (xy 133.547866 -252.848618) (xy 133.524433 -252.861547)
			(xy 133.47416 -252.879889) (xy 133.421461 -252.889193) (xy 133.394704 -252.889766) (xy 133.36945 -252.889274)
			(xy 133.319629 -252.880961) (xy 133.271857 -252.864561) (xy 133.227436 -252.840522) (xy 133.187577 -252.809499)
			(xy 133.153368 -252.772339) (xy 133.125742 -252.730054) (xy 133.105452 -252.6838) (xy 133.093053 -252.634836)
			(xy 133.088882 -252.5845) (xy 133.093053 -252.534164) (xy 133.105452 -252.4852) (xy 133.125742 -252.438946)
			(xy 133.153368 -252.396661) (xy 133.187577 -252.359501) (xy 133.227436 -252.328478) (xy 133.271857 -252.304439)
			(xy 133.319629 -252.288039) (xy 133.36945 -252.279726) (xy 133.394704 -252.27915) (xy 133.421462 -252.279704)
			(xy 133.474161 -252.28902) (xy 133.524433 -252.307367) (xy 133.547866 -252.320298) (xy 133.55578 -252.324452)
			(xy 133.573355 -252.327625) (xy 133.59096 -252.324619) (xy 133.59892 -252.320552) (xy 133.67512 -252.27661)
			(xy 133.681313 -252.272822) (xy 133.691376 -252.262366) (xy 133.694932 -252.256036) (xy 133.70052 -252.24486)
			(xy 133.70052 -252.070108) (xy 133.700364 -252.064242) (xy 133.697659 -252.052825) (xy 133.695186 -252.047502)
			(xy 133.682994 -252.022864) (xy 133.67639 -252.014736) (xy 133.672072 -252.01118) (xy 133.653267 -251.995252)
			(xy 133.620558 -251.958394) (xy 133.594194 -251.91676) (xy 133.574859 -251.871433) (xy 133.563056 -251.823589)
			(xy 133.55909 -251.77447) (xy 133.563065 -251.725351) (xy 133.574878 -251.677509) (xy 133.594222 -251.632186)
			(xy 133.620595 -251.590558) (xy 133.653311 -251.553706) (xy 133.672072 -251.537724) (xy 133.67639 -251.534168)
			(xy 133.682994 -251.52604) (xy 133.695186 -251.501402) (xy 133.697652 -251.496077) (xy 133.700355 -251.484661)
			(xy 133.70052 -251.478796) (xy 133.70052 -251.316236) (xy 133.70038 -251.310161) (xy 133.697564 -251.298345)
			(xy 133.694932 -251.292868) (xy 133.691329 -251.286575) (xy 133.681271 -251.276135) (xy 133.67512 -251.272294)
			(xy 133.59892 -251.228352) (xy 133.590993 -251.224181) (xy 133.573355 -251.221129) (xy 133.555747 -251.22435)
			(xy 133.547866 -251.228606) (xy 133.524434 -251.241536) (xy 133.474161 -251.259878) (xy 133.421461 -251.269183)
			(xy 133.394704 -251.269754) (xy 133.369442 -251.269261) (xy 133.319608 -251.260946) (xy 133.271822 -251.244542)
			(xy 133.227387 -251.220496) (xy 133.187517 -251.189464) (xy 133.153298 -251.152293) (xy 133.125664 -251.109996)
			(xy 133.105369 -251.063728) (xy 133.092966 -251.014751) (xy 133.088794 -250.9644) (xy 133.092966 -250.914049)
			(xy 133.105369 -250.865072) (xy 133.125664 -250.818804) (xy 133.153298 -250.776507) (xy 133.187517 -250.739336)
			(xy 133.227387 -250.708304) (xy 133.271822 -250.684258) (xy 133.319608 -250.667854) (xy 133.369442 -250.659539)
			(xy 133.394704 -250.659138) (xy 133.421462 -250.659692) (xy 133.474161 -250.669008) (xy 133.524434 -250.687354)
			(xy 133.547866 -250.700286) (xy 133.55578 -250.704441) (xy 133.573355 -250.707614) (xy 133.59096 -250.704608)
			(xy 133.59892 -250.70054) (xy 133.67512 -250.656598) (xy 133.681312 -250.652809) (xy 133.691373 -250.642352)
			(xy 133.694932 -250.636024) (xy 133.70052 -250.624848) (xy 133.70052 -250.450096) (xy 133.700374 -250.444227)
			(xy 133.697687 -250.432801) (xy 133.695186 -250.42749) (xy 133.682994 -250.402852) (xy 133.67639 -250.394724)
			(xy 133.672072 -250.391168) (xy 133.65326 -250.37524) (xy 133.620537 -250.338379) (xy 133.594159 -250.296742)
			(xy 133.574812 -250.251408) (xy 133.562997 -250.203555) (xy 133.559021 -250.154425) (xy 133.562989 -250.105295)
			(xy 133.574796 -250.05744) (xy 133.594136 -250.012103) (xy 133.620507 -249.970461) (xy 133.653224 -249.933595)
			(xy 133.672072 -249.917712) (xy 133.67639 -249.914156) (xy 133.682994 -249.906028) (xy 133.695186 -249.88139)
			(xy 133.697651 -249.876065) (xy 133.700351 -249.864649) (xy 133.70052 -249.858784) (xy 133.70052 -249.696224)
			(xy 133.700378 -249.69015) (xy 133.69756 -249.678334) (xy 133.694932 -249.672856) (xy 133.691336 -249.666555)
			(xy 133.681287 -249.6561) (xy 133.67512 -249.652282) (xy 133.59892 -249.60834) (xy 133.590993 -249.60417)
			(xy 133.573355 -249.601118) (xy 133.555747 -249.604339) (xy 133.547866 -249.608594) (xy 133.524433 -249.621524)
			(xy 133.474161 -249.639867) (xy 133.421461 -249.649172) (xy 133.394704 -249.649742) (xy 133.369443 -249.64925)
			(xy 133.319611 -249.640935) (xy 133.271826 -249.624531) (xy 133.227394 -249.600486) (xy 133.187525 -249.569455)
			(xy 133.153308 -249.532285) (xy 133.125675 -249.489991) (xy 133.10538 -249.443724) (xy 133.092978 -249.394749)
			(xy 133.088806 -249.3444) (xy 133.092978 -249.294051) (xy 133.10538 -249.245076) (xy 133.125675 -249.198809)
			(xy 133.153308 -249.156515) (xy 133.187525 -249.119345) (xy 133.227394 -249.088314) (xy 133.271826 -249.064269)
			(xy 133.319611 -249.047865) (xy 133.369443 -249.03955) (xy 133.394704 -249.039126) (xy 133.421462 -249.039679)
			(xy 133.474161 -249.048995) (xy 133.524435 -249.067341) (xy 133.547866 -249.080274) (xy 133.555779 -249.08443)
			(xy 133.573355 -249.087604) (xy 133.590961 -249.084597) (xy 133.59892 -249.080528) (xy 133.67512 -249.036586)
			(xy 133.681311 -249.032796) (xy 133.69137 -249.022338) (xy 133.694932 -249.016012) (xy 133.70052 -249.004836)
			(xy 133.70052 -248.830084) (xy 133.700373 -248.824215) (xy 133.697683 -248.812791) (xy 133.695186 -248.807478)
			(xy 133.682994 -248.78284) (xy 133.67639 -248.774712) (xy 133.672072 -248.771156) (xy 133.653261 -248.755228)
			(xy 133.62054 -248.718367) (xy 133.594164 -248.67673) (xy 133.574819 -248.631397) (xy 133.563005 -248.583546)
			(xy 133.559031 -248.534418) (xy 133.563 -248.485289) (xy 133.574807 -248.437436) (xy 133.594148 -248.392101)
			(xy 133.620519 -248.350461) (xy 133.653236 -248.313597) (xy 133.672072 -248.2977) (xy 133.67639 -248.294144)
			(xy 133.682994 -248.286016) (xy 133.695186 -248.261378) (xy 133.697649 -248.256053) (xy 133.700347 -248.244637)
			(xy 133.70052 -248.238772) (xy 133.70052 -248.076212) (xy 133.700377 -248.070138) (xy 133.697556 -248.058324)
			(xy 133.694932 -248.052844) (xy 133.691335 -248.046544) (xy 133.681285 -248.036092) (xy 133.67512 -248.03227)
			(xy 133.59892 -247.988328) (xy 133.590993 -247.984159) (xy 133.573355 -247.981108) (xy 133.555747 -247.984328)
			(xy 133.547866 -247.988582) (xy 133.524434 -248.001512) (xy 133.474161 -248.019856) (xy 133.421462 -248.029162)
			(xy 133.394704 -248.02973) (xy 133.369444 -248.029238) (xy 133.319614 -248.020923) (xy 133.271831 -248.00452)
			(xy 133.227401 -247.980476) (xy 133.187533 -247.949446) (xy 133.153317 -247.912278) (xy 133.125685 -247.869985)
			(xy 133.105392 -247.823721) (xy 133.09299 -247.774747) (xy 133.088818 -247.7244) (xy 133.09299 -247.674053)
			(xy 133.105392 -247.625079) (xy 133.125685 -247.578815) (xy 133.153317 -247.536522) (xy 133.187533 -247.499354)
			(xy 133.227401 -247.468324) (xy 133.271831 -247.44428) (xy 133.319614 -247.427877) (xy 133.369444 -247.419562)
			(xy 133.394704 -247.419114) (xy 133.421462 -247.419667) (xy 133.474162 -247.428982) (xy 133.524435 -247.447328)
			(xy 133.547866 -247.460262) (xy 133.555779 -247.464419) (xy 133.573355 -247.467594) (xy 133.590961 -247.464586)
			(xy 133.59892 -247.460516) (xy 133.67512 -247.416574) (xy 133.681311 -247.412784) (xy 133.691367 -247.402324)
			(xy 133.694932 -247.396) (xy 133.70052 -247.384824) (xy 133.70052 -247.210072) (xy 133.700371 -247.204204)
			(xy 133.697679 -247.19278) (xy 133.695186 -247.187466) (xy 133.682994 -247.162828) (xy 133.67639 -247.1547)
			(xy 133.672072 -247.151144) (xy 133.653262 -247.135216) (xy 133.620543 -247.098356) (xy 133.594169 -247.056719)
			(xy 133.574825 -247.011387) (xy 133.563013 -246.963537) (xy 133.559041 -246.91441) (xy 133.56301 -246.865283)
			(xy 133.574819 -246.817432) (xy 133.59416 -246.772099) (xy 133.620531 -246.73046) (xy 133.653248 -246.693598)
			(xy 133.672072 -246.677688) (xy 133.67639 -246.674132) (xy 133.682994 -246.666004) (xy 133.695186 -246.641366)
			(xy 133.697648 -246.63604) (xy 133.700343 -246.624624) (xy 133.70052 -246.61876) (xy 133.70052 -246.4562)
			(xy 133.700375 -246.450126) (xy 133.697552 -246.438314) (xy 133.694932 -246.432832) (xy 133.691334 -246.426533)
			(xy 133.681283 -246.416082) (xy 133.67512 -246.412258) (xy 133.59892 -246.368316) (xy 133.590993 -246.364147)
			(xy 133.573355 -246.361097) (xy 133.555747 -246.364316) (xy 133.547866 -246.36857) (xy 133.524434 -246.381501)
			(xy 133.474161 -246.399845) (xy 133.421462 -246.409151) (xy 133.394704 -246.409718) (xy 133.369445 -246.409226)
			(xy 133.319617 -246.400911) (xy 133.271836 -246.384509) (xy 133.227407 -246.360465) (xy 133.187541 -246.329437)
			(xy 133.153327 -246.292271) (xy 133.125696 -246.249979) (xy 133.105403 -246.203717) (xy 133.093002 -246.154745)
			(xy 133.08883 -246.1044) (xy 133.093002 -246.054055) (xy 133.105403 -246.005083) (xy 133.125696 -245.958821)
			(xy 133.153327 -245.916529) (xy 133.187541 -245.879363) (xy 133.227407 -245.848335) (xy 133.271836 -245.824291)
			(xy 133.319617 -245.807889) (xy 133.369445 -245.799574) (xy 133.394704 -245.799102) (xy 133.421462 -245.799655)
			(xy 133.474162 -245.80897) (xy 133.524436 -245.827315) (xy 133.547866 -245.84025) (xy 133.555779 -245.844408)
			(xy 133.573355 -245.847583) (xy 133.590961 -245.844575) (xy 133.59892 -245.840504) (xy 133.67512 -245.796562)
			(xy 133.68131 -245.792771) (xy 133.691364 -245.78231) (xy 133.694932 -245.775988) (xy 133.70052 -245.764812)
			(xy 133.70052 -245.59006) (xy 133.70037 -245.584192) (xy 133.697675 -245.57277) (xy 133.695186 -245.567454)
			(xy 133.682994 -245.542816) (xy 133.67639 -245.534688) (xy 133.672072 -245.531132) (xy 133.653263 -245.515204)
			(xy 133.620546 -245.478344) (xy 133.594174 -245.436708) (xy 133.574831 -245.391377) (xy 133.563021 -245.343528)
			(xy 133.55905 -245.294403) (xy 133.56302 -245.245277) (xy 133.57483 -245.197428) (xy 133.594171 -245.152096)
			(xy 133.620543 -245.11046) (xy 133.65326 -245.0736) (xy 133.672072 -245.057676) (xy 133.67639 -245.05412)
			(xy 133.682994 -245.045992) (xy 133.695186 -245.021354) (xy 133.697647 -245.016028) (xy 133.700339 -245.004612)
			(xy 133.70052 -244.998748) (xy 133.70052 -244.836188) (xy 133.700374 -244.830115) (xy 133.697548 -244.818303)
			(xy 133.694932 -244.81282) (xy 133.691333 -244.806522) (xy 133.681281 -244.796073) (xy 133.67512 -244.792246)
			(xy 133.59892 -244.748304) (xy 133.590993 -244.744136) (xy 133.573355 -244.741087) (xy 133.555748 -244.744305)
			(xy 133.547866 -244.748558) (xy 133.524434 -244.761489) (xy 133.474161 -244.779834) (xy 133.421462 -244.789141)
			(xy 133.394704 -244.789706) (xy 133.369446 -244.789214) (xy 133.31962 -244.7809) (xy 133.271841 -244.764498)
			(xy 133.227414 -244.740455) (xy 133.18755 -244.709428) (xy 133.153336 -244.672263) (xy 133.125707 -244.629973)
			(xy 133.105415 -244.583713) (xy 133.093014 -244.534743) (xy 133.088842 -244.4844) (xy 133.093014 -244.434057)
			(xy 133.105415 -244.385087) (xy 133.125707 -244.338827) (xy 133.153336 -244.296537) (xy 133.18755 -244.259372)
			(xy 133.227414 -244.228345) (xy 133.271841 -244.204302) (xy 133.31962 -244.1879) (xy 133.369446 -244.179586)
			(xy 133.394704 -244.17909) (xy 133.421462 -244.179643) (xy 133.474162 -244.188958) (xy 133.524436 -244.207302)
			(xy 133.547866 -244.220238) (xy 133.555781 -244.22439) (xy 133.573355 -244.22756) (xy 133.59096 -244.224556)
			(xy 133.59892 -244.220492) (xy 133.67512 -244.17655) (xy 133.681309 -244.172758) (xy 133.691361 -244.162296)
			(xy 133.694932 -244.155976) (xy 133.70052 -244.1448) (xy 133.70052 -243.970048) (xy 133.700369 -243.96418)
			(xy 133.697671 -243.95276) (xy 133.695186 -243.947442) (xy 133.682994 -243.922804) (xy 133.67639 -243.914676)
			(xy 133.672072 -243.91112) (xy 133.653264 -243.895192) (xy 133.620549 -243.858332) (xy 133.594178 -243.816697)
			(xy 133.574838 -243.771367) (xy 133.563029 -243.723519) (xy 133.559059 -243.674395) (xy 133.563031 -243.625271)
			(xy 133.574841 -243.577424) (xy 133.594183 -243.532094) (xy 133.620555 -243.490459) (xy 133.653272 -243.453601)
			(xy 133.672072 -243.437664) (xy 133.67639 -243.434108) (xy 133.682994 -243.42598) (xy 133.695186 -243.401342)
			(xy 133.697646 -243.396016) (xy 133.700336 -243.3846) (xy 133.70052 -243.378736) (xy 133.70052 -243.216176)
			(xy 133.700373 -243.210103) (xy 133.697544 -243.198293) (xy 133.694932 -243.192808) (xy 133.691332 -243.186511)
			(xy 133.681279 -243.176065) (xy 133.67512 -243.172234) (xy 133.59892 -243.128292) (xy 133.590994 -243.124119)
			(xy 133.573355 -243.121064) (xy 133.555746 -243.124288) (xy 133.547866 -243.128546) (xy 133.524433 -243.141474)
			(xy 133.47416 -243.159814) (xy 133.421461 -243.169118) (xy 133.394704 -243.169694) (xy 133.369447 -243.169202)
			(xy 133.319623 -243.160888) (xy 133.271846 -243.144487) (xy 133.22742 -243.120445) (xy 133.187558 -243.08942)
			(xy 133.153346 -243.052256) (xy 133.125717 -243.009968) (xy 133.105426 -242.963709) (xy 133.093025 -242.914741)
			(xy 133.088854 -242.8644) (xy 133.093025 -242.814059) (xy 133.105426 -242.765091) (xy 133.125717 -242.718832)
			(xy 133.153346 -242.676544) (xy 133.187558 -242.63938) (xy 133.22742 -242.608355) (xy 133.271846 -242.584313)
			(xy 133.319623 -242.567912) (xy 133.369447 -242.559598) (xy 133.394704 -242.559078) (xy 133.421462 -242.559631)
			(xy 133.474162 -242.568945) (xy 133.524437 -242.587289) (xy 133.547866 -242.600226) (xy 133.55578 -242.604379)
			(xy 133.573355 -242.60755) (xy 133.59096 -242.604545) (xy 133.59892 -242.60048) (xy 133.67512 -242.556538)
			(xy 133.681308 -242.552746) (xy 133.691358 -242.542283) (xy 133.694932 -242.535964) (xy 133.70052 -242.524788)
			(xy 133.70052 -242.350036) (xy 133.700367 -242.344169) (xy 133.697668 -242.332749) (xy 133.695186 -242.32743)
			(xy 133.682994 -242.302792) (xy 133.67639 -242.294664) (xy 133.672072 -242.291108) (xy 133.653265 -242.27518)
			(xy 133.620552 -242.238321) (xy 133.594183 -242.196686) (xy 133.574844 -242.151357) (xy 133.563037 -242.10351)
			(xy 133.559068 -242.054387) (xy 133.563041 -242.005265) (xy 133.574852 -241.957419) (xy 133.594195 -241.912092)
			(xy 133.620567 -241.870459) (xy 133.653283 -241.833603) (xy 133.672072 -241.817652) (xy 133.67639 -241.814096)
			(xy 133.682994 -241.805968) (xy 133.695186 -241.78133) (xy 133.697644 -241.776004) (xy 133.700332 -241.764588)
			(xy 133.70052 -241.758724) (xy 133.70052 -241.596164) (xy 133.700371 -241.590091) (xy 133.69754 -241.578283)
			(xy 133.694932 -241.572796) (xy 133.691331 -241.5665) (xy 133.681277 -241.556056) (xy 133.67512 -241.552222)
			(xy 133.59892 -241.50828) (xy 133.590994 -241.504107) (xy 133.573355 -241.501053) (xy 133.555746 -241.504276)
			(xy 133.547866 -241.508534) (xy 133.524433 -241.521463) (xy 133.47416 -241.539803) (xy 133.421461 -241.549107)
			(xy 133.394704 -241.549682) (xy 133.369448 -241.54919) (xy 133.319625 -241.540876) (xy 133.271851 -241.524476)
			(xy 133.227427 -241.500435) (xy 133.187566 -241.469411) (xy 133.153355 -241.432248) (xy 133.125728 -241.389962)
			(xy 133.105437 -241.343705) (xy 133.093037 -241.294739) (xy 133.088866 -241.2444) (xy 133.093037 -241.194061)
			(xy 133.105437 -241.145095) (xy 133.125728 -241.098838) (xy 133.153355 -241.056552) (xy 133.187566 -241.019389)
			(xy 133.227427 -240.988365) (xy 133.271851 -240.964324) (xy 133.319625 -240.947924) (xy 133.369448 -240.93961)
			(xy 133.394704 -240.939066) (xy 133.421462 -240.939619) (xy 133.474162 -240.948933) (xy 133.524437 -240.967276)
			(xy 133.547866 -240.980214) (xy 133.55578 -240.984368) (xy 133.573355 -240.987539) (xy 133.59096 -240.984534)
			(xy 133.59892 -240.980468) (xy 133.67512 -240.936526) (xy 133.681314 -240.932738) (xy 133.69138 -240.922284)
			(xy 133.694932 -240.915952) (xy 133.70052 -240.904776) (xy 133.70052 -240.730024) (xy 133.700366 -240.724157)
			(xy 133.697664 -240.712739) (xy 133.695186 -240.707418) (xy 133.682994 -240.68278) (xy 133.67639 -240.674652)
			(xy 133.672072 -240.671096) (xy 133.653266 -240.655168) (xy 133.620555 -240.618309) (xy 133.594188 -240.576675)
			(xy 133.574851 -240.531347) (xy 133.563045 -240.483501) (xy 133.559078 -240.43438) (xy 133.563052 -240.385259)
			(xy 133.574863 -240.337415) (xy 133.594207 -240.292089) (xy 133.620579 -240.250459) (xy 133.653295 -240.213604)
			(xy 133.672072 -240.19764) (xy 133.67639 -240.194084) (xy 133.682994 -240.185956) (xy 133.695186 -240.161318)
			(xy 133.697643 -240.155991) (xy 133.700328 -240.144575) (xy 133.70052 -240.138712) (xy 133.70052 -239.976152)
			(xy 133.700382 -239.970077) (xy 133.697569 -239.958258) (xy 133.694932 -239.952784) (xy 133.69133 -239.946489)
			(xy 133.681274 -239.936047) (xy 133.67512 -239.93221) (xy 133.59892 -239.888268) (xy 133.590994 -239.884096)
			(xy 133.573355 -239.881042) (xy 133.555747 -239.884265) (xy 133.547866 -239.888522) (xy 133.524433 -239.901451)
			(xy 133.47416 -239.919792) (xy 133.421461 -239.929097) (xy 133.394704 -239.92967) (xy 133.369449 -239.929178)
			(xy 133.319628 -239.920865) (xy 133.271855 -239.904465) (xy 133.227433 -239.880425) (xy 133.187574 -239.849402)
			(xy 133.153365 -239.812241) (xy 133.125738 -239.769956) (xy 133.105449 -239.723701) (xy 133.093049 -239.674737)
			(xy 133.088878 -239.6244) (xy 133.093049 -239.574063) (xy 133.105449 -239.525099) (xy 133.125738 -239.478844)
			(xy 133.153365 -239.436559) (xy 133.187574 -239.399398) (xy 133.227433 -239.368375) (xy 133.271855 -239.344335)
			(xy 133.319628 -239.327935) (xy 133.369449 -239.319622) (xy 133.394704 -239.319054) (xy 133.421462 -239.319608)
			(xy 133.474161 -239.328924) (xy 133.524433 -239.347271) (xy 133.547866 -239.360202) (xy 133.55578 -239.364356)
			(xy 133.573355 -239.367528) (xy 133.59096 -239.364523) (xy 133.59892 -239.360456) (xy 133.67512 -239.316514)
			(xy 133.681313 -239.312726) (xy 133.691377 -239.30227) (xy 133.694932 -239.29594) (xy 133.70052 -239.284764)
			(xy 133.70052 -239.110012) (xy 133.700365 -239.104145) (xy 133.69766 -239.092728) (xy 133.695186 -239.087406)
			(xy 133.682994 -239.062768) (xy 133.67639 -239.05464) (xy 133.672072 -239.051084) (xy 133.653267 -239.035156)
			(xy 133.620557 -238.998297) (xy 133.594193 -238.956664) (xy 133.574857 -238.911336) (xy 133.563053 -238.863492)
			(xy 133.559087 -238.814372) (xy 133.563062 -238.765253) (xy 133.574875 -238.717411) (xy 133.594218 -238.672087)
			(xy 133.620591 -238.630458) (xy 133.653307 -238.593606) (xy 133.672072 -238.577628) (xy 133.67639 -238.574072)
			(xy 133.682994 -238.565944) (xy 133.695186 -238.541306) (xy 133.697652 -238.535981) (xy 133.700356 -238.524565)
			(xy 133.70052 -238.5187) (xy 133.70052 -238.35614) (xy 133.70038 -238.350065) (xy 133.697565 -238.338248)
			(xy 133.694932 -238.332772) (xy 133.691329 -238.326478) (xy 133.681272 -238.316038) (xy 133.67512 -238.312198)
			(xy 133.59892 -238.268256) (xy 133.590993 -238.264085) (xy 133.573355 -238.261032) (xy 133.555747 -238.264254)
			(xy 133.547866 -238.26851) (xy 133.524433 -238.281439) (xy 133.474161 -238.299782) (xy 133.421461 -238.309086)
			(xy 133.394704 -238.309658) (xy 133.369442 -238.309165) (xy 133.319607 -238.30085) (xy 133.27182 -238.284445)
			(xy 133.227385 -238.260399) (xy 133.187514 -238.229367) (xy 133.153295 -238.192195) (xy 133.125661 -238.149898)
			(xy 133.105365 -238.10363) (xy 133.092962 -238.054652) (xy 133.08879 -238.0043) (xy 133.092962 -237.953948)
			(xy 133.105365 -237.90497) (xy 133.125661 -237.858702) (xy 133.153295 -237.816405) (xy 133.187514 -237.779233)
			(xy 133.227385 -237.748201) (xy 133.27182 -237.724155) (xy 133.319607 -237.70775) (xy 133.369442 -237.699435)
			(xy 133.394704 -237.699042) (xy 133.421462 -237.699596) (xy 133.474161 -237.708912) (xy 133.524434 -237.727258)
			(xy 133.547866 -237.74019) (xy 133.55578 -237.744345) (xy 133.573355 -237.747518) (xy 133.59096 -237.744512)
			(xy 133.59892 -237.740444) (xy 133.67512 -237.696502) (xy 133.681312 -237.692713) (xy 133.691374 -237.682256)
			(xy 133.694932 -237.675928) (xy 133.70052 -237.664752) (xy 133.70052 -237.49) (xy 133.700375 -237.484131)
			(xy 133.697688 -237.472705) (xy 133.695186 -237.467394) (xy 133.682994 -237.442756) (xy 133.67639 -237.434628)
			(xy 133.672072 -237.431072) (xy 133.65326 -237.415144) (xy 133.620536 -237.378283) (xy 133.594158 -237.336645)
			(xy 133.57481 -237.291311) (xy 133.562994 -237.243458) (xy 133.559018 -237.194328) (xy 133.562985 -237.145197)
			(xy 133.574792 -237.097342) (xy 133.594132 -237.052004) (xy 133.620503 -237.010361) (xy 133.65322 -236.973495)
			(xy 133.672072 -236.957616) (xy 133.67639 -236.95406) (xy 133.682994 -236.945932) (xy 133.695186 -236.921294)
			(xy 133.697651 -236.915969) (xy 133.700353 -236.904553) (xy 133.70052 -236.898688) (xy 133.70052 -236.736128)
			(xy 133.700379 -236.730053) (xy 133.697561 -236.718238) (xy 133.694932 -236.71276) (xy 133.691328 -236.706467)
			(xy 133.68127 -236.696029) (xy 133.67512 -236.692186) (xy 133.59892 -236.648244) (xy 133.590993 -236.644074)
			(xy 133.573355 -236.641022) (xy 133.555747 -236.644243) (xy 133.547866 -236.648498) (xy 133.524434 -236.661428)
			(xy 133.474161 -236.679771) (xy 133.421461 -236.689076) (xy 133.394704 -236.689646) (xy 133.369443 -236.689154)
			(xy 133.31961 -236.680838) (xy 133.271825 -236.664434) (xy 133.227392 -236.640389) (xy 133.187522 -236.609358)
			(xy 133.153305 -236.572188) (xy 133.125671 -236.529892) (xy 133.105377 -236.483626) (xy 133.092974 -236.43465)
			(xy 133.088802 -236.3843) (xy 133.092974 -236.33395) (xy 133.105377 -236.284974) (xy 133.125671 -236.238708)
			(xy 133.153305 -236.196412) (xy 133.187522 -236.159242) (xy 133.227392 -236.128211) (xy 133.271825 -236.104166)
			(xy 133.31961 -236.087762) (xy 133.369443 -236.079446) (xy 133.394704 -236.07903) (xy 133.421462 -236.079583)
			(xy 133.474161 -236.088899) (xy 133.524435 -236.107245) (xy 133.547866 -236.120178) (xy 133.55578 -236.124334)
			(xy 133.573355 -236.127508) (xy 133.590961 -236.1245) (xy 133.59892 -236.120432) (xy 133.67512 -236.07649)
			(xy 133.681312 -236.0727) (xy 133.691371 -236.062243) (xy 133.694932 -236.055916) (xy 133.70052 -236.04474)
			(xy 133.70052 -235.869988) (xy 133.700373 -235.864119) (xy 133.697684 -235.852694) (xy 133.695186 -235.847382)
			(xy 133.682994 -235.822744) (xy 133.67639 -235.814616) (xy 133.672072 -235.81106) (xy 133.653261 -235.795132)
			(xy 133.620539 -235.758271) (xy 133.594163 -235.716634) (xy 133.574816 -235.671301) (xy 133.563003 -235.623449)
			(xy 133.559028 -235.57432) (xy 133.562996 -235.525191) (xy 133.574804 -235.477338) (xy 133.594144 -235.432002)
			(xy 133.620515 -235.390361) (xy 133.653232 -235.353497) (xy 133.672072 -235.337604) (xy 133.67639 -235.334048)
			(xy 133.682994 -235.32592) (xy 133.695186 -235.301282) (xy 133.69765 -235.295957) (xy 133.700349 -235.284541)
			(xy 133.70052 -235.278676) (xy 133.70052 -235.116116) (xy 133.700377 -235.110042) (xy 133.697557 -235.098227)
			(xy 133.694932 -235.092748) (xy 133.691335 -235.086448) (xy 133.681286 -235.075994) (xy 133.67512 -235.072174)
			(xy 133.59892 -235.028232) (xy 133.590993 -235.024062) (xy 133.573355 -235.021011) (xy 133.555747 -235.024231)
			(xy 133.547866 -235.028486) (xy 133.524434 -235.041416) (xy 133.474161 -235.059759) (xy 133.421462 -235.069065)
			(xy 133.394704 -235.069634) (xy 133.369444 -235.069142) (xy 133.319613 -235.060827) (xy 133.27183 -235.044423)
			(xy 133.227398 -235.020379) (xy 133.187531 -234.989349) (xy 133.153314 -234.95218) (xy 133.125682 -234.909887)
			(xy 133.105388 -234.863622) (xy 133.092986 -234.814648) (xy 133.088814 -234.7643) (xy 133.092986 -234.713952)
			(xy 133.105388 -234.664978) (xy 133.125682 -234.618713) (xy 133.153314 -234.57642) (xy 133.187531 -234.539251)
			(xy 133.227398 -234.508221) (xy 133.27183 -234.484177) (xy 133.319613 -234.467773) (xy 133.369444 -234.459458)
			(xy 133.394704 -234.459018) (xy 133.421462 -234.459571) (xy 133.474161 -234.468887) (xy 133.524435 -234.487232)
			(xy 133.547866 -234.500166) (xy 133.555779 -234.504323) (xy 133.573355 -234.507497) (xy 133.590961 -234.504489)
			(xy 133.59892 -234.50042) (xy 133.67512 -234.456478) (xy 133.681311 -234.452688) (xy 133.691368 -234.442229)
			(xy 133.694932 -234.435904) (xy 133.70052 -234.424728) (xy 133.70052 -234.249976) (xy 133.700372 -234.244108)
			(xy 133.69768 -234.232684) (xy 133.695186 -234.22737) (xy 133.682994 -234.202732) (xy 133.67639 -234.194604)
			(xy 133.672072 -234.191048) (xy 133.653262 -234.17512) (xy 133.620542 -234.13826) (xy 133.594167 -234.096623)
			(xy 133.574823 -234.051291) (xy 133.563011 -234.00344) (xy 133.559037 -233.954313) (xy 133.563007 -233.905185)
			(xy 133.574815 -233.857333) (xy 133.594156 -233.811999) (xy 133.620527 -233.770361) (xy 133.653244 -233.733498)
			(xy 133.672072 -233.717592) (xy 133.67639 -233.714036) (xy 133.682994 -233.705908) (xy 133.695186 -233.68127)
			(xy 133.697649 -233.675945) (xy 133.700345 -233.664529) (xy 133.70052 -233.658664) (xy 133.70052 -233.496104)
			(xy 133.700376 -233.49003) (xy 133.697553 -233.478217) (xy 133.694932 -233.472736) (xy 133.691334 -233.466437)
			(xy 133.681284 -233.455986) (xy 133.67512 -233.452162) (xy 133.59892 -233.40822) (xy 133.590993 -233.404051)
			(xy 133.573355 -233.401) (xy 133.555747 -233.40422) (xy 133.547866 -233.408474) (xy 133.524434 -233.421404)
			(xy 133.474161 -233.439749) (xy 133.421462 -233.449055) (xy 133.394704 -233.449622) (xy 133.369445 -233.44913)
			(xy 133.319616 -233.440815) (xy 133.271835 -233.424412) (xy 133.227405 -233.400369) (xy 133.187539 -233.36934)
			(xy 133.153323 -233.332173) (xy 133.125692 -233.289881) (xy 133.105399 -233.243618) (xy 133.092998 -233.194646)
			(xy 133.088826 -233.1443) (xy 133.092998 -233.093954) (xy 133.105399 -233.044982) (xy 133.125692 -232.998719)
			(xy 133.153323 -232.956427) (xy 133.187539 -232.91926) (xy 133.227405 -232.888231) (xy 133.271835 -232.864188)
			(xy 133.319616 -232.847785) (xy 133.369445 -232.83947) (xy 133.394704 -232.839006) (xy 133.421462 -232.839559)
			(xy 133.474162 -232.848874) (xy 133.524436 -232.867219) (xy 133.547866 -232.880154) (xy 133.555779 -232.884311)
			(xy 133.573355 -232.887487) (xy 133.590961 -232.884478) (xy 133.59892 -232.880408) (xy 133.67512 -232.836466)
			(xy 133.68131 -232.832675) (xy 133.691365 -232.822215) (xy 133.694932 -232.815892) (xy 133.70052 -232.804716)
			(xy 133.70052 -232.629964) (xy 133.70037 -232.624096) (xy 133.697676 -232.612673) (xy 133.695186 -232.607358)
			(xy 133.682994 -232.58272) (xy 133.67639 -232.574592) (xy 133.672072 -232.571036) (xy 133.653263 -232.555108)
			(xy 133.620545 -232.518248) (xy 133.594172 -232.476612) (xy 133.574829 -232.43128) (xy 133.563019 -232.383431)
			(xy 133.559047 -232.334305) (xy 133.563017 -232.285179) (xy 133.574826 -232.237329) (xy 133.594167 -232.191997)
			(xy 133.620539 -232.15036) (xy 133.653256 -232.113499) (xy 133.672072 -232.09758) (xy 133.67639 -232.094024)
			(xy 133.682994 -232.085896) (xy 133.695186 -232.061258) (xy 133.697647 -232.055932) (xy 133.700341 -232.044516)
			(xy 133.70052 -232.038652) (xy 133.70052 -231.876092) (xy 133.700375 -231.870019) (xy 133.697549 -231.858207)
			(xy 133.694932 -231.852724) (xy 133.691333 -231.846426) (xy 133.681282 -231.835976) (xy 133.67512 -231.83215)
			(xy 133.59892 -231.788208) (xy 133.590993 -231.78404) (xy 133.573355 -231.78099) (xy 133.555748 -231.784209)
			(xy 133.547866 -231.788462) (xy 133.524434 -231.801393) (xy 133.474161 -231.819738) (xy 133.421462 -231.829044)
			(xy 133.394704 -231.82961) (xy 133.369446 -231.829118) (xy 133.319619 -231.820804) (xy 133.271839 -231.804401)
			(xy 133.227411 -231.780359) (xy 133.187547 -231.749331) (xy 133.153333 -231.712166) (xy 133.125703 -231.669875)
			(xy 133.105411 -231.623614) (xy 133.09301 -231.574644) (xy 133.088838 -231.5243) (xy 133.09301 -231.473956)
			(xy 133.105411 -231.424986) (xy 133.125703 -231.378725) (xy 133.153333 -231.336434) (xy 133.187547 -231.299269)
			(xy 133.227411 -231.268241) (xy 133.271839 -231.244199) (xy 133.319619 -231.227796) (xy 133.369446 -231.219482)
			(xy 133.394704 -231.218994) (xy 133.421462 -231.219547) (xy 133.474162 -231.228862) (xy 133.524436 -231.247206)
			(xy 133.547866 -231.260142) (xy 133.555779 -231.2643) (xy 133.573355 -231.267476) (xy 133.590961 -231.264467)
			(xy 133.59892 -231.260396) (xy 133.67512 -231.216454) (xy 133.681309 -231.212663) (xy 133.691362 -231.202201)
			(xy 133.694932 -231.19588) (xy 133.70052 -231.184704) (xy 133.70052 -231.010206) (xy 133.700364 -231.00434)
			(xy 133.697658 -230.992923) (xy 133.695186 -230.9876) (xy 133.682994 -230.962962) (xy 133.67639 -230.954834)
			(xy 133.672072 -230.951278) (xy 133.651421 -230.933704) (xy 133.616082 -230.892582) (xy 133.588556 -230.845868)
			(xy 133.569707 -230.795028) (xy 133.560128 -230.74166) (xy 133.55955 -230.71455) (xy 133.55955 -230.714296)
			(xy 133.560139 -230.687148) (xy 133.569734 -230.633707) (xy 133.58862 -230.582802) (xy 133.616205 -230.536036)
			(xy 133.651619 -230.494879) (xy 133.672326 -230.477314) (xy 133.676644 -230.473758) (xy 133.683248 -230.46563)
			(xy 133.695186 -230.4415) (xy 133.697652 -230.436175) (xy 133.700355 -230.424759) (xy 133.70052 -230.418894)
			(xy 133.70052 -230.25608) (xy 133.700373 -230.250007) (xy 133.697545 -230.238196) (xy 133.694932 -230.232712)
			(xy 133.691332 -230.226415) (xy 133.68128 -230.215968) (xy 133.67512 -230.212138) (xy 133.59892 -230.168196)
			(xy 133.590994 -230.164022) (xy 133.573355 -230.160967) (xy 133.555746 -230.164192) (xy 133.547866 -230.16845)
			(xy 133.524434 -230.181381) (xy 133.474162 -230.199727) (xy 133.421462 -230.209034) (xy 133.394704 -230.209598)
			(xy 133.369447 -230.209106) (xy 133.319622 -230.200792) (xy 133.271844 -230.18439) (xy 133.227418 -230.160349)
			(xy 133.187555 -230.129323) (xy 133.153342 -230.092158) (xy 133.125714 -230.04987) (xy 133.105422 -230.00361)
			(xy 133.093021 -229.954642) (xy 133.08885 -229.9043) (xy 133.093021 -229.853958) (xy 133.105422 -229.80499)
			(xy 133.125714 -229.75873) (xy 133.153342 -229.716442) (xy 133.187555 -229.679277) (xy 133.227418 -229.648251)
			(xy 133.271844 -229.62421) (xy 133.319622 -229.607808) (xy 133.369447 -229.599494) (xy 133.394704 -229.598982)
			(xy 133.421462 -229.599535) (xy 133.474162 -229.608849) (xy 133.524437 -229.627193) (xy 133.547866 -229.64013)
			(xy 133.55578 -229.644282) (xy 133.573355 -229.647453) (xy 133.59096 -229.644449) (xy 133.59892 -229.640384)
			(xy 133.67512 -229.596442) (xy 133.681309 -229.59265) (xy 133.691359 -229.582187) (xy 133.694932 -229.575868)
			(xy 133.70052 -229.564692) (xy 133.70052 -229.390194) (xy 133.700374 -229.384325) (xy 133.697686 -229.3729)
			(xy 133.695186 -229.367588) (xy 133.682994 -229.34295) (xy 133.67639 -229.334822) (xy 133.672072 -229.331266)
			(xy 133.65326 -229.315338) (xy 133.620537 -229.278477) (xy 133.59416 -229.23684) (xy 133.574813 -229.191506)
			(xy 133.562998 -229.143653) (xy 133.559023 -229.094524) (xy 133.56299 -229.045394) (xy 133.574798 -228.99754)
			(xy 133.594138 -228.952203) (xy 133.620509 -228.910561) (xy 133.653225 -228.873695) (xy 133.672072 -228.85781)
			(xy 133.67639 -228.854254) (xy 133.682994 -228.846126) (xy 133.695186 -228.821488) (xy 133.697651 -228.816163)
			(xy 133.700351 -228.804747) (xy 133.70052 -228.798882) (xy 133.70052 -228.636322) (xy 133.700378 -228.630248)
			(xy 133.697559 -228.618432) (xy 133.694932 -228.612954) (xy 133.691336 -228.606654) (xy 133.681287 -228.596199)
			(xy 133.67512 -228.59238) (xy 133.59892 -228.548438) (xy 133.590993 -228.544268) (xy 133.573355 -228.541216)
			(xy 133.555747 -228.544437) (xy 133.547866 -228.548692) (xy 133.524433 -228.561622) (xy 133.474161 -228.579965)
			(xy 133.421461 -228.58927) (xy 133.394704 -228.58984) (xy 133.369443 -228.589348) (xy 133.319611 -228.581033)
			(xy 133.271827 -228.564629) (xy 133.227395 -228.540584) (xy 133.187527 -228.509553) (xy 133.153309 -228.472384)
			(xy 133.125677 -228.43009) (xy 133.105382 -228.383824) (xy 133.09298 -228.334849) (xy 133.088808 -228.2845)
			(xy 133.09298 -228.234151) (xy 133.105382 -228.185176) (xy 133.125677 -228.13891) (xy 133.153309 -228.096616)
			(xy 133.187527 -228.059447) (xy 133.227395 -228.028416) (xy 133.271827 -228.004371) (xy 133.319611 -227.987967)
			(xy 133.369443 -227.979652) (xy 133.394704 -227.979224) (xy 133.421462 -227.979777) (xy 133.474161 -227.989093)
			(xy 133.524435 -228.007438) (xy 133.547866 -228.020372) (xy 133.555779 -228.024528) (xy 133.573355 -228.027702)
			(xy 133.590961 -228.024695) (xy 133.59892 -228.020626) (xy 133.67512 -227.976684) (xy 133.681311 -227.972894)
			(xy 133.69137 -227.962436) (xy 133.694932 -227.95611) (xy 133.70052 -227.944934) (xy 133.70052 -227.770182)
			(xy 133.700372 -227.764313) (xy 133.697682 -227.752889) (xy 133.695186 -227.747576) (xy 133.682994 -227.722938)
			(xy 133.67639 -227.71481) (xy 133.672072 -227.711254) (xy 133.653262 -227.695326) (xy 133.620541 -227.658465)
			(xy 133.594165 -227.616828) (xy 133.57482 -227.571496) (xy 133.563007 -227.523644) (xy 133.559033 -227.474516)
			(xy 133.563001 -227.425388) (xy 133.574809 -227.377536) (xy 133.59415 -227.332201) (xy 133.620521 -227.290561)
			(xy 133.653238 -227.253697) (xy 133.672072 -227.237798) (xy 133.67639 -227.234242) (xy 133.682994 -227.226114)
			(xy 133.695186 -227.201476) (xy 133.697649 -227.196151) (xy 133.700347 -227.184735) (xy 133.70052 -227.17887)
			(xy 133.70052 -227.01631) (xy 133.700377 -227.010236) (xy 133.697555 -226.998422) (xy 133.694932 -226.992942)
			(xy 133.691335 -226.986643) (xy 133.681285 -226.97619) (xy 133.67512 -226.972368) (xy 133.59892 -226.928426)
			(xy 133.590993 -226.924257) (xy 133.573355 -226.921206) (xy 133.555747 -226.924426) (xy 133.547866 -226.92868)
			(xy 133.524434 -226.94161) (xy 133.474161 -226.959954) (xy 133.421462 -226.96926) (xy 133.394704 -226.969828)
			(xy 133.370712 -226.969358) (xy 133.323319 -226.961852) (xy 133.277683 -226.947025) (xy 133.234928 -226.925242)
			(xy 133.196107 -226.897039) (xy 133.162176 -226.863111) (xy 133.13397 -226.824292) (xy 133.112184 -226.781539)
			(xy 133.097353 -226.735905) (xy 133.089844 -226.688512) (xy 133.089396 -226.66452) (xy 133.089536 -226.651757)
			(xy 133.091702 -226.626324) (xy 133.093714 -226.61372) (xy 133.098118 -226.590363) (xy 133.113198 -226.54529)
			(xy 133.135078 -226.503097) (xy 133.163229 -226.464802) (xy 133.196971 -226.43133) (xy 133.235491 -226.403488)
			(xy 133.277859 -226.381948) (xy 133.323051 -226.367231) (xy 133.346444 -226.363022) (xy 133.360668 -226.360736)
			(xy 133.382258 -226.342194) (xy 133.414516 -226.242372) (xy 133.416949 -226.233368) (xy 133.415907 -226.21476)
			(xy 133.408317 -226.197739) (xy 133.40207 -226.19081) (xy 133.372606 -226.161346) (xy 133.365494 -226.15398)
			(xy 133.346698 -226.14636) (xy 133.0452 -226.14636) (xy 133.036564 -226.149662) (xy 133.009617 -226.159223)
			(xy 132.953389 -226.169568) (xy 132.924804 -226.170236) (xy 132.896217 -226.169594) (xy 132.839988 -226.159237)
			(xy 132.813044 -226.149662) (xy 132.804408 -226.14636) (xy 132.074666 -226.14636) (xy 132.067808 -226.148392)
			(xy 132.046046 -226.154089) (xy 132.001422 -226.159776) (xy 131.956447 -226.158868) (xy 131.934204 -226.155504)
			(xy 131.934204 -226.155758) (xy 131.901946 -226.148392) (xy 131.894834 -226.14636) (xy 131.165092 -226.14636)
			(xy 131.156456 -226.149662) (xy 131.129509 -226.159222) (xy 131.073281 -226.169566) (xy 131.044696 -226.170236)
			(xy 131.016109 -226.169593) (xy 130.95988 -226.159235) (xy 130.932936 -226.149662) (xy 130.9243 -226.14636)
			(xy 130.194558 -226.14636) (xy 130.1877 -226.148392) (xy 130.165937 -226.154088) (xy 130.121314 -226.159774)
			(xy 130.076339 -226.158866) (xy 130.054096 -226.155504) (xy 130.054096 -226.155758) (xy 130.021838 -226.148392)
			(xy 130.014726 -226.14636) (xy 129.285238 -226.14636) (xy 129.276602 -226.149662) (xy 129.249656 -226.159226)
			(xy 129.193428 -226.169578) (xy 129.164842 -226.170236) (xy 129.136254 -226.169597) (xy 129.080023 -226.159247)
			(xy 129.053082 -226.149662) (xy 129.044446 -226.14636) (xy 128.705102 -226.14636) (xy 128.695033 -226.146784)
			(xy 128.676434 -226.154505) (xy 128.669034 -226.161346) (xy 128.644142 -226.186238) (xy 128.641348 -226.189032)
			(xy 128.641348 -226.189286) (xy 128.635701 -226.196481) (xy 128.62943 -226.213651) (xy 128.629535 -226.231929)
			(xy 128.632458 -226.240594) (xy 128.67132 -226.341432) (xy 128.69545 -226.358958) (xy 128.71069 -226.35972)
			(xy 128.736389 -226.361611) (xy 128.786659 -226.372922) (xy 128.834318 -226.392509) (xy 128.878014 -226.419815)
			(xy 128.916507 -226.454067) (xy 128.948707 -226.494293) (xy 128.9737 -226.539352) (xy 128.990778 -226.587966)
			(xy 128.999454 -226.638757) (xy 128.999996 -226.66452) (xy 129.318507 -226.66452) (xy 129.322602 -226.613792)
			(xy 129.334781 -226.564378) (xy 129.354729 -226.517558) (xy 129.38193 -226.474544) (xy 129.415678 -226.43645)
			(xy 129.4551 -226.404263) (xy 129.499174 -226.378817) (xy 129.54676 -226.36077) (xy 129.596624 -226.35059)
			(xy 129.647476 -226.348541) (xy 129.697997 -226.354675) (xy 129.746881 -226.368835) (xy 129.79286 -226.390652)
			(xy 129.834744 -226.419562) (xy 129.871448 -226.454817) (xy 129.902021 -226.495503) (xy 129.925672 -226.540566)
			(xy 129.941788 -226.58884) (xy 129.949952 -226.639074) (xy 129.950464 -226.66452) (xy 130.268992 -226.66452)
			(xy 130.272952 -226.615466) (xy 130.284729 -226.567682) (xy 130.30402 -226.522406) (xy 130.330323 -226.48081)
			(xy 130.362958 -226.443973) (xy 130.401079 -226.412848) (xy 130.4437 -226.388241) (xy 130.489716 -226.370789)
			(xy 130.537935 -226.360945) (xy 130.58711 -226.358964) (xy 130.635965 -226.364896) (xy 130.683236 -226.378588)
			(xy 130.727698 -226.399686) (xy 130.768201 -226.427642) (xy 130.803694 -226.461734) (xy 130.833259 -226.501078)
			(xy 130.85613 -226.544655) (xy 130.871714 -226.591336) (xy 130.879609 -226.639913) (xy 130.880104 -226.66452)
			(xy 131.198615 -226.66452) (xy 131.20271 -226.613792) (xy 131.214889 -226.564378) (xy 131.234837 -226.517558)
			(xy 131.262038 -226.474544) (xy 131.295786 -226.43645) (xy 131.335208 -226.404263) (xy 131.379282 -226.378817)
			(xy 131.426868 -226.36077) (xy 131.476732 -226.35059) (xy 131.527584 -226.348541) (xy 131.578105 -226.354675)
			(xy 131.626989 -226.368835) (xy 131.672968 -226.390652) (xy 131.714852 -226.419562) (xy 131.751556 -226.454817)
			(xy 131.782129 -226.495503) (xy 131.80578 -226.540566) (xy 131.821896 -226.58884) (xy 131.83006 -226.639074)
			(xy 131.830572 -226.66452) (xy 132.138415 -226.66452) (xy 132.14251 -226.613792) (xy 132.154689 -226.564378)
			(xy 132.174637 -226.517558) (xy 132.201838 -226.474544) (xy 132.235586 -226.43645) (xy 132.275008 -226.404263)
			(xy 132.319082 -226.378817) (xy 132.366668 -226.36077) (xy 132.416532 -226.35059) (xy 132.467384 -226.348541)
			(xy 132.517905 -226.354675) (xy 132.566789 -226.368835) (xy 132.612768 -226.390652) (xy 132.654652 -226.419562)
			(xy 132.691356 -226.454817) (xy 132.721929 -226.495503) (xy 132.74558 -226.540566) (xy 132.761696 -226.58884)
			(xy 132.76986 -226.639074) (xy 132.770372 -226.66452) (xy 132.76986 -226.689966) (xy 132.761696 -226.7402)
			(xy 132.74558 -226.788474) (xy 132.721929 -226.833537) (xy 132.691356 -226.874223) (xy 132.654652 -226.909478)
			(xy 132.612768 -226.938388) (xy 132.566789 -226.960205) (xy 132.517905 -226.974365) (xy 132.467384 -226.980499)
			(xy 132.416532 -226.97845) (xy 132.366668 -226.96827) (xy 132.319082 -226.950223) (xy 132.275008 -226.924777)
			(xy 132.235586 -226.89259) (xy 132.201838 -226.854496) (xy 132.174637 -226.811482) (xy 132.154689 -226.764662)
			(xy 132.14251 -226.715248) (xy 132.138415 -226.66452) (xy 131.830572 -226.66452) (xy 131.83006 -226.689966)
			(xy 131.821896 -226.7402) (xy 131.80578 -226.788474) (xy 131.782129 -226.833537) (xy 131.751556 -226.874223)
			(xy 131.714852 -226.909478) (xy 131.672968 -226.938388) (xy 131.626989 -226.960205) (xy 131.578105 -226.974365)
			(xy 131.527584 -226.980499) (xy 131.476732 -226.97845) (xy 131.426868 -226.96827) (xy 131.379282 -226.950223)
			(xy 131.335208 -226.924777) (xy 131.295786 -226.89259) (xy 131.262038 -226.854496) (xy 131.234837 -226.811482)
			(xy 131.214889 -226.764662) (xy 131.20271 -226.715248) (xy 131.198615 -226.66452) (xy 130.880104 -226.66452)
			(xy 130.879609 -226.689127) (xy 130.871714 -226.737704) (xy 130.85613 -226.784385) (xy 130.833259 -226.827962)
			(xy 130.803694 -226.867306) (xy 130.768201 -226.901398) (xy 130.727698 -226.929354) (xy 130.683236 -226.950452)
			(xy 130.635965 -226.964144) (xy 130.58711 -226.970076) (xy 130.537935 -226.968095) (xy 130.489716 -226.958251)
			(xy 130.4437 -226.940799) (xy 130.401079 -226.916192) (xy 130.362958 -226.885067) (xy 130.330323 -226.84823)
			(xy 130.30402 -226.806634) (xy 130.284729 -226.761358) (xy 130.272952 -226.713574) (xy 130.268992 -226.66452)
			(xy 129.950464 -226.66452) (xy 129.949952 -226.689966) (xy 129.941788 -226.7402) (xy 129.925672 -226.788474)
			(xy 129.902021 -226.833537) (xy 129.871448 -226.874223) (xy 129.834744 -226.909478) (xy 129.79286 -226.938388)
			(xy 129.746881 -226.960205) (xy 129.697997 -226.974365) (xy 129.647476 -226.980499) (xy 129.596624 -226.97845)
			(xy 129.54676 -226.96827) (xy 129.499174 -226.950223) (xy 129.4551 -226.924777) (xy 129.415678 -226.89259)
			(xy 129.38193 -226.854496) (xy 129.354729 -226.811482) (xy 129.334781 -226.764662) (xy 129.322602 -226.715248)
			(xy 129.318507 -226.66452) (xy 128.999996 -226.66452) (xy 128.999524 -226.68851) (xy 128.992015 -226.735898)
			(xy 128.977186 -226.781529) (xy 128.955401 -226.824278) (xy 128.927197 -226.863093) (xy 128.893269 -226.897018)
			(xy 128.854451 -226.925218) (xy 128.811699 -226.946998) (xy 128.766067 -226.961823) (xy 128.718678 -226.969326)
			(xy 128.694688 -226.969828) (xy 128.668919 -226.969299) (xy 128.618111 -226.960655) (xy 128.569478 -226.943599)
			(xy 128.524401 -226.918614) (xy 128.484163 -226.886412) (xy 128.449906 -226.847907) (xy 128.422605 -226.804194)
			(xy 128.403036 -226.756517) (xy 128.391755 -226.706229) (xy 128.389888 -226.680522) (xy 128.389126 -226.665282)
			(xy 128.3716 -226.641152) (xy 128.270762 -226.60229) (xy 128.261416 -226.599173) (xy 128.241736 -226.599535)
			(xy 128.223647 -226.607293) (xy 128.216406 -226.613974) (xy 128.047242 -226.783138) (xy 128.043432 -226.791774)
			(xy 128.033613 -226.813005) (xy 128.00864 -226.852557) (xy 127.978104 -226.887991) (xy 127.942672 -226.918529)
			(xy 127.903122 -226.943504) (xy 127.881888 -226.953318) (xy 127.873252 -226.957128) (xy 127.835406 -226.994974)
			(xy 127.82804 -227.002086) (xy 127.82042 -227.020882) (xy 127.82042 -227.196904) (xy 127.820875 -227.207076)
			(xy 127.828792 -227.225817) (xy 127.843377 -227.24) (xy 127.852678 -227.244148) (xy 127.94107 -227.278438)
			(xy 127.948273 -227.281034) (xy 127.96353 -227.282202) (xy 127.971042 -227.280724) (xy 127.976884 -227.279454)
			(xy 127.991914 -227.261007) (xy 128.026581 -227.228415) (xy 128.065751 -227.201399) (xy 128.108534 -227.180574)
			(xy 128.15396 -227.166412) (xy 128.200997 -227.159233) (xy 128.224788 -227.158804) (xy 128.249598 -227.159264)
			(xy 128.298608 -227.167025) (xy 128.3458 -227.182357) (xy 128.390012 -227.204883) (xy 128.430157 -227.234048)
			(xy 128.465244 -227.269134) (xy 128.494411 -227.309277) (xy 128.516938 -227.353489) (xy 128.532272 -227.400681)
			(xy 128.540035 -227.44969) (xy 128.540035 -227.474526) (xy 128.848607 -227.474526) (xy 128.852702 -227.423798)
			(xy 128.864881 -227.374384) (xy 128.884829 -227.327564) (xy 128.91203 -227.28455) (xy 128.945778 -227.246456)
			(xy 128.9852 -227.214269) (xy 129.029274 -227.188823) (xy 129.07686 -227.170776) (xy 129.126724 -227.160596)
			(xy 129.177576 -227.158547) (xy 129.228097 -227.164681) (xy 129.276981 -227.178841) (xy 129.32296 -227.200658)
			(xy 129.364844 -227.229568) (xy 129.401548 -227.264823) (xy 129.432121 -227.305509) (xy 129.455772 -227.350572)
			(xy 129.471888 -227.398846) (xy 129.480052 -227.44908) (xy 129.480564 -227.474526) (xy 130.728461 -227.474526)
			(xy 130.732556 -227.423798) (xy 130.744735 -227.374384) (xy 130.764683 -227.327564) (xy 130.791884 -227.28455)
			(xy 130.825632 -227.246456) (xy 130.865054 -227.214269) (xy 130.909128 -227.188823) (xy 130.956714 -227.170776)
			(xy 131.006578 -227.160596) (xy 131.05743 -227.158547) (xy 131.107951 -227.164681) (xy 131.156835 -227.178841)
			(xy 131.202814 -227.200658) (xy 131.244698 -227.229568) (xy 131.281402 -227.264823) (xy 131.311975 -227.305509)
			(xy 131.335626 -227.350572) (xy 131.351742 -227.398846) (xy 131.359906 -227.44908) (xy 131.360418 -227.474526)
			(xy 131.678946 -227.474526) (xy 131.682906 -227.425472) (xy 131.694683 -227.377688) (xy 131.713974 -227.332412)
			(xy 131.740277 -227.290816) (xy 131.772912 -227.253979) (xy 131.811033 -227.222854) (xy 131.853654 -227.198247)
			(xy 131.89967 -227.180795) (xy 131.947889 -227.170951) (xy 131.997064 -227.16897) (xy 132.045919 -227.174902)
			(xy 132.09319 -227.188594) (xy 132.137652 -227.209692) (xy 132.178155 -227.237648) (xy 132.213648 -227.27174)
			(xy 132.243213 -227.311084) (xy 132.266084 -227.354661) (xy 132.281668 -227.401342) (xy 132.289563 -227.449919)
			(xy 132.290058 -227.474526) (xy 132.608569 -227.474526) (xy 132.612664 -227.423798) (xy 132.624843 -227.374384)
			(xy 132.644791 -227.327564) (xy 132.671992 -227.28455) (xy 132.70574 -227.246456) (xy 132.745162 -227.214269)
			(xy 132.789236 -227.188823) (xy 132.836822 -227.170776) (xy 132.886686 -227.160596) (xy 132.937538 -227.158547)
			(xy 132.988059 -227.164681) (xy 133.036943 -227.178841) (xy 133.082922 -227.200658) (xy 133.124806 -227.229568)
			(xy 133.16151 -227.264823) (xy 133.192083 -227.305509) (xy 133.215734 -227.350572) (xy 133.23185 -227.398846)
			(xy 133.240014 -227.44908) (xy 133.240526 -227.474526) (xy 133.240014 -227.499972) (xy 133.23185 -227.550206)
			(xy 133.215734 -227.59848) (xy 133.192083 -227.643543) (xy 133.16151 -227.684229) (xy 133.124806 -227.719484)
			(xy 133.082922 -227.748394) (xy 133.036943 -227.770211) (xy 132.988059 -227.784371) (xy 132.937538 -227.790505)
			(xy 132.886686 -227.788456) (xy 132.836822 -227.778276) (xy 132.789236 -227.760229) (xy 132.745162 -227.734783)
			(xy 132.70574 -227.702596) (xy 132.671992 -227.664502) (xy 132.644791 -227.621488) (xy 132.624843 -227.574668)
			(xy 132.612664 -227.525254) (xy 132.608569 -227.474526) (xy 132.290058 -227.474526) (xy 132.289563 -227.499133)
			(xy 132.281668 -227.54771) (xy 132.266084 -227.594391) (xy 132.243213 -227.637968) (xy 132.213648 -227.677312)
			(xy 132.178155 -227.711404) (xy 132.137652 -227.73936) (xy 132.09319 -227.760458) (xy 132.045919 -227.77415)
			(xy 131.997064 -227.780082) (xy 131.947889 -227.778101) (xy 131.89967 -227.768257) (xy 131.853654 -227.750805)
			(xy 131.811033 -227.726198) (xy 131.772912 -227.695073) (xy 131.740277 -227.658236) (xy 131.713974 -227.61664)
			(xy 131.694683 -227.571364) (xy 131.682906 -227.52358) (xy 131.678946 -227.474526) (xy 131.360418 -227.474526)
			(xy 131.359906 -227.499972) (xy 131.351742 -227.550206) (xy 131.335626 -227.59848) (xy 131.311975 -227.643543)
			(xy 131.281402 -227.684229) (xy 131.244698 -227.719484) (xy 131.202814 -227.748394) (xy 131.156835 -227.770211)
			(xy 131.107951 -227.784371) (xy 131.05743 -227.790505) (xy 131.006578 -227.788456) (xy 130.956714 -227.778276)
			(xy 130.909128 -227.760229) (xy 130.865054 -227.734783) (xy 130.825632 -227.702596) (xy 130.791884 -227.664502)
			(xy 130.764683 -227.621488) (xy 130.744735 -227.574668) (xy 130.732556 -227.525254) (xy 130.728461 -227.474526)
			(xy 129.480564 -227.474526) (xy 129.480052 -227.499972) (xy 129.471888 -227.550206) (xy 129.455772 -227.59848)
			(xy 129.432121 -227.643543) (xy 129.401548 -227.684229) (xy 129.364844 -227.719484) (xy 129.32296 -227.748394)
			(xy 129.276981 -227.770211) (xy 129.228097 -227.784371) (xy 129.177576 -227.790505) (xy 129.126724 -227.788456)
			(xy 129.07686 -227.778276) (xy 129.029274 -227.760229) (xy 128.9852 -227.734783) (xy 128.945778 -227.702596)
			(xy 128.91203 -227.664502) (xy 128.884829 -227.621488) (xy 128.864881 -227.574668) (xy 128.852702 -227.525254)
			(xy 128.848607 -227.474526) (xy 128.540035 -227.474526) (xy 128.540035 -227.49931) (xy 128.532272 -227.548319)
			(xy 128.516938 -227.595511) (xy 128.494411 -227.639723) (xy 128.465244 -227.679866) (xy 128.430157 -227.714952)
			(xy 128.390012 -227.744117) (xy 128.3458 -227.766643) (xy 128.298608 -227.781975) (xy 128.249598 -227.789736)
			(xy 128.224788 -227.790248) (xy 128.197805 -227.789673) (xy 128.14463 -227.780456) (xy 128.093793 -227.762343)
			(xy 128.046769 -227.735861) (xy 128.004926 -227.701778) (xy 127.98679 -227.68179) (xy 127.981332 -227.676047)
			(xy 127.967757 -227.667894) (xy 127.96012 -227.665788) (xy 127.955802 -227.664772) (xy 127.852678 -227.704904)
			(xy 127.843371 -227.70904) (xy 127.828793 -227.723238) (xy 127.820854 -227.741975) (xy 127.82042 -227.752148)
			(xy 127.82042 -227.95357) (xy 127.83947 -227.979986) (xy 127.854964 -227.98532) (xy 127.878163 -227.993578)
			(xy 127.921869 -228.016264) (xy 127.961518 -228.045464) (xy 127.99615 -228.080471) (xy 128.024921 -228.120433)
			(xy 128.047134 -228.16438) (xy 128.062248 -228.211245) (xy 128.069898 -228.259889) (xy 128.069897 -228.284532)
			(xy 128.388884 -228.284532) (xy 128.392844 -228.235478) (xy 128.404621 -228.187694) (xy 128.423912 -228.142418)
			(xy 128.450215 -228.100822) (xy 128.48285 -228.063985) (xy 128.520971 -228.03286) (xy 128.563592 -228.008253)
			(xy 128.609608 -227.990801) (xy 128.657827 -227.980957) (xy 128.707002 -227.978976) (xy 128.755857 -227.984908)
			(xy 128.803128 -227.9986) (xy 128.84759 -228.019698) (xy 128.888093 -228.047654) (xy 128.923586 -228.081746)
			(xy 128.953151 -228.12109) (xy 128.976022 -228.164667) (xy 128.991606 -228.211348) (xy 128.999501 -228.259925)
			(xy 128.999996 -228.284532) (xy 129.318507 -228.284532) (xy 129.322602 -228.233804) (xy 129.334781 -228.18439)
			(xy 129.354729 -228.13757) (xy 129.38193 -228.094556) (xy 129.415678 -228.056462) (xy 129.4551 -228.024275)
			(xy 129.499174 -227.998829) (xy 129.54676 -227.980782) (xy 129.596624 -227.970602) (xy 129.647476 -227.968553)
			(xy 129.697997 -227.974687) (xy 129.746881 -227.988847) (xy 129.79286 -228.010664) (xy 129.834744 -228.039574)
			(xy 129.871448 -228.074829) (xy 129.902021 -228.115515) (xy 129.925672 -228.160578) (xy 129.941788 -228.208852)
			(xy 129.949952 -228.259086) (xy 129.950464 -228.284532) (xy 130.268992 -228.284532) (xy 130.272952 -228.235478)
			(xy 130.284729 -228.187694) (xy 130.30402 -228.142418) (xy 130.330323 -228.100822) (xy 130.362958 -228.063985)
			(xy 130.401079 -228.03286) (xy 130.4437 -228.008253) (xy 130.489716 -227.990801) (xy 130.537935 -227.980957)
			(xy 130.58711 -227.978976) (xy 130.635965 -227.984908) (xy 130.683236 -227.9986) (xy 130.727698 -228.019698)
			(xy 130.768201 -228.047654) (xy 130.803694 -228.081746) (xy 130.833259 -228.12109) (xy 130.85613 -228.164667)
			(xy 130.871714 -228.211348) (xy 130.879609 -228.259925) (xy 130.880104 -228.284532) (xy 131.198615 -228.284532)
			(xy 131.20271 -228.233804) (xy 131.214889 -228.18439) (xy 131.234837 -228.13757) (xy 131.262038 -228.094556)
			(xy 131.295786 -228.056462) (xy 131.335208 -228.024275) (xy 131.379282 -227.998829) (xy 131.426868 -227.980782)
			(xy 131.476732 -227.970602) (xy 131.527584 -227.968553) (xy 131.578105 -227.974687) (xy 131.626989 -227.988847)
			(xy 131.672968 -228.010664) (xy 131.714852 -228.039574) (xy 131.751556 -228.074829) (xy 131.782129 -228.115515)
			(xy 131.80578 -228.160578) (xy 131.821896 -228.208852) (xy 131.83006 -228.259086) (xy 131.830572 -228.284532)
			(xy 132.138415 -228.284532) (xy 132.14251 -228.233804) (xy 132.154689 -228.18439) (xy 132.174637 -228.13757)
			(xy 132.201838 -228.094556) (xy 132.235586 -228.056462) (xy 132.275008 -228.024275) (xy 132.319082 -227.998829)
			(xy 132.366668 -227.980782) (xy 132.416532 -227.970602) (xy 132.467384 -227.968553) (xy 132.517905 -227.974687)
			(xy 132.566789 -227.988847) (xy 132.612768 -228.010664) (xy 132.654652 -228.039574) (xy 132.691356 -228.074829)
			(xy 132.721929 -228.115515) (xy 132.74558 -228.160578) (xy 132.761696 -228.208852) (xy 132.76986 -228.259086)
			(xy 132.770372 -228.284532) (xy 132.76986 -228.309978) (xy 132.761696 -228.360212) (xy 132.74558 -228.408486)
			(xy 132.721929 -228.453549) (xy 132.691356 -228.494235) (xy 132.654652 -228.52949) (xy 132.612768 -228.5584)
			(xy 132.566789 -228.580217) (xy 132.517905 -228.594377) (xy 132.467384 -228.600511) (xy 132.416532 -228.598462)
			(xy 132.366668 -228.588282) (xy 132.319082 -228.570235) (xy 132.275008 -228.544789) (xy 132.235586 -228.512602)
			(xy 132.201838 -228.474508) (xy 132.174637 -228.431494) (xy 132.154689 -228.384674) (xy 132.14251 -228.33526)
			(xy 132.138415 -228.284532) (xy 131.830572 -228.284532) (xy 131.83006 -228.309978) (xy 131.821896 -228.360212)
			(xy 131.80578 -228.408486) (xy 131.782129 -228.453549) (xy 131.751556 -228.494235) (xy 131.714852 -228.52949)
			(xy 131.672968 -228.5584) (xy 131.626989 -228.580217) (xy 131.578105 -228.594377) (xy 131.527584 -228.600511)
			(xy 131.476732 -228.598462) (xy 131.426868 -228.588282) (xy 131.379282 -228.570235) (xy 131.335208 -228.544789)
			(xy 131.295786 -228.512602) (xy 131.262038 -228.474508) (xy 131.234837 -228.431494) (xy 131.214889 -228.384674)
			(xy 131.20271 -228.33526) (xy 131.198615 -228.284532) (xy 130.880104 -228.284532) (xy 130.879609 -228.309139)
			(xy 130.871714 -228.357716) (xy 130.85613 -228.404397) (xy 130.833259 -228.447974) (xy 130.803694 -228.487318)
			(xy 130.768201 -228.52141) (xy 130.727698 -228.549366) (xy 130.683236 -228.570464) (xy 130.635965 -228.584156)
			(xy 130.58711 -228.590088) (xy 130.537935 -228.588107) (xy 130.489716 -228.578263) (xy 130.4437 -228.560811)
			(xy 130.401079 -228.536204) (xy 130.362958 -228.505079) (xy 130.330323 -228.468242) (xy 130.30402 -228.426646)
			(xy 130.284729 -228.38137) (xy 130.272952 -228.333586) (xy 130.268992 -228.284532) (xy 129.950464 -228.284532)
			(xy 129.949952 -228.309978) (xy 129.941788 -228.360212) (xy 129.925672 -228.408486) (xy 129.902021 -228.453549)
			(xy 129.871448 -228.494235) (xy 129.834744 -228.52949) (xy 129.79286 -228.5584) (xy 129.746881 -228.580217)
			(xy 129.697997 -228.594377) (xy 129.647476 -228.600511) (xy 129.596624 -228.598462) (xy 129.54676 -228.588282)
			(xy 129.499174 -228.570235) (xy 129.4551 -228.544789) (xy 129.415678 -228.512602) (xy 129.38193 -228.474508)
			(xy 129.354729 -228.431494) (xy 129.334781 -228.384674) (xy 129.322602 -228.33526) (xy 129.318507 -228.284532)
			(xy 128.999996 -228.284532) (xy 128.999501 -228.309139) (xy 128.991606 -228.357716) (xy 128.976022 -228.404397)
			(xy 128.953151 -228.447974) (xy 128.923586 -228.487318) (xy 128.888093 -228.52141) (xy 128.84759 -228.549366)
			(xy 128.803128 -228.570464) (xy 128.755857 -228.584156) (xy 128.707002 -228.590088) (xy 128.657827 -228.588107)
			(xy 128.609608 -228.578263) (xy 128.563592 -228.560811) (xy 128.520971 -228.536204) (xy 128.48285 -228.505079)
			(xy 128.450215 -228.468242) (xy 128.423912 -228.426646) (xy 128.404621 -228.38137) (xy 128.392844 -228.333586)
			(xy 128.388884 -228.284532) (xy 128.069897 -228.284532) (xy 128.069896 -228.309131) (xy 128.062244 -228.357775)
			(xy 128.047126 -228.404639) (xy 128.02491 -228.448585) (xy 127.996136 -228.488545) (xy 127.961503 -228.523549)
			(xy 127.921851 -228.552747) (xy 127.878145 -228.57543) (xy 127.854964 -228.583744) (xy 127.83947 -228.589078)
			(xy 127.82042 -228.615494) (xy 127.82042 -228.816916) (xy 127.820859 -228.827098) (xy 127.828758 -228.845867)
			(xy 127.843342 -228.860077) (xy 127.852678 -228.86416) (xy 127.94107 -228.89845) (xy 127.948273 -228.901045)
			(xy 127.96353 -228.902213) (xy 127.971042 -228.900736) (xy 127.976884 -228.899466) (xy 127.991914 -228.881018)
			(xy 128.02658 -228.848425) (xy 128.06575 -228.821409) (xy 128.108533 -228.800583) (xy 128.153959 -228.786419)
			(xy 128.200997 -228.77924) (xy 128.224788 -228.778816) (xy 128.249597 -228.779276) (xy 128.298605 -228.787037)
			(xy 128.345795 -228.802368) (xy 128.390006 -228.824893) (xy 128.430149 -228.854057) (xy 128.465235 -228.889142)
			(xy 128.4944 -228.929284) (xy 128.516927 -228.973494) (xy 128.532261 -229.020683) (xy 128.540023 -229.069691)
			(xy 128.540023 -229.094538) (xy 128.848607 -229.094538) (xy 128.852702 -229.04381) (xy 128.864881 -228.994396)
			(xy 128.884829 -228.947576) (xy 128.91203 -228.904562) (xy 128.945778 -228.866468) (xy 128.9852 -228.834281)
			(xy 129.029274 -228.808835) (xy 129.07686 -228.790788) (xy 129.126724 -228.780608) (xy 129.177576 -228.778559)
			(xy 129.228097 -228.784693) (xy 129.276981 -228.798853) (xy 129.32296 -228.82067) (xy 129.364844 -228.84958)
			(xy 129.401548 -228.884835) (xy 129.432121 -228.925521) (xy 129.455772 -228.970584) (xy 129.471888 -229.018858)
			(xy 129.480052 -229.069092) (xy 129.480564 -229.094538) (xy 129.798838 -229.094538) (xy 129.802798 -229.045484)
			(xy 129.814575 -228.9977) (xy 129.833866 -228.952424) (xy 129.860169 -228.910828) (xy 129.892804 -228.873991)
			(xy 129.930925 -228.842866) (xy 129.973546 -228.818259) (xy 130.019562 -228.800807) (xy 130.067781 -228.790963)
			(xy 130.116956 -228.788982) (xy 130.165811 -228.794914) (xy 130.213082 -228.808606) (xy 130.257544 -228.829704)
			(xy 130.298047 -228.85766) (xy 130.33354 -228.891752) (xy 130.363105 -228.931096) (xy 130.385976 -228.974673)
			(xy 130.40156 -229.021354) (xy 130.409455 -229.069931) (xy 130.40995 -229.094538) (xy 130.728461 -229.094538)
			(xy 130.732556 -229.04381) (xy 130.744735 -228.994396) (xy 130.764683 -228.947576) (xy 130.791884 -228.904562)
			(xy 130.825632 -228.866468) (xy 130.865054 -228.834281) (xy 130.909128 -228.808835) (xy 130.956714 -228.790788)
			(xy 131.006578 -228.780608) (xy 131.05743 -228.778559) (xy 131.107951 -228.784693) (xy 131.156835 -228.798853)
			(xy 131.202814 -228.82067) (xy 131.244698 -228.84958) (xy 131.281402 -228.884835) (xy 131.311975 -228.925521)
			(xy 131.335626 -228.970584) (xy 131.351742 -229.018858) (xy 131.359906 -229.069092) (xy 131.360418 -229.094538)
			(xy 131.678946 -229.094538) (xy 131.682906 -229.045484) (xy 131.694683 -228.9977) (xy 131.713974 -228.952424)
			(xy 131.740277 -228.910828) (xy 131.772912 -228.873991) (xy 131.811033 -228.842866) (xy 131.853654 -228.818259)
			(xy 131.89967 -228.800807) (xy 131.947889 -228.790963) (xy 131.997064 -228.788982) (xy 132.045919 -228.794914)
			(xy 132.09319 -228.808606) (xy 132.137652 -228.829704) (xy 132.178155 -228.85766) (xy 132.213648 -228.891752)
			(xy 132.243213 -228.931096) (xy 132.266084 -228.974673) (xy 132.281668 -229.021354) (xy 132.289563 -229.069931)
			(xy 132.290058 -229.094538) (xy 132.608569 -229.094538) (xy 132.612664 -229.04381) (xy 132.624843 -228.994396)
			(xy 132.644791 -228.947576) (xy 132.671992 -228.904562) (xy 132.70574 -228.866468) (xy 132.745162 -228.834281)
			(xy 132.789236 -228.808835) (xy 132.836822 -228.790788) (xy 132.886686 -228.780608) (xy 132.937538 -228.778559)
			(xy 132.988059 -228.784693) (xy 133.036943 -228.798853) (xy 133.082922 -228.82067) (xy 133.124806 -228.84958)
			(xy 133.16151 -228.884835) (xy 133.192083 -228.925521) (xy 133.215734 -228.970584) (xy 133.23185 -229.018858)
			(xy 133.240014 -229.069092) (xy 133.240526 -229.094538) (xy 133.240014 -229.119984) (xy 133.23185 -229.170218)
			(xy 133.215734 -229.218492) (xy 133.192083 -229.263555) (xy 133.16151 -229.304241) (xy 133.124806 -229.339496)
			(xy 133.082922 -229.368406) (xy 133.036943 -229.390223) (xy 132.988059 -229.404383) (xy 132.937538 -229.410517)
			(xy 132.886686 -229.408468) (xy 132.836822 -229.398288) (xy 132.789236 -229.380241) (xy 132.745162 -229.354795)
			(xy 132.70574 -229.322608) (xy 132.671992 -229.284514) (xy 132.644791 -229.2415) (xy 132.624843 -229.19468)
			(xy 132.612664 -229.145266) (xy 132.608569 -229.094538) (xy 132.290058 -229.094538) (xy 132.289563 -229.119145)
			(xy 132.281668 -229.167722) (xy 132.266084 -229.214403) (xy 132.243213 -229.25798) (xy 132.213648 -229.297324)
			(xy 132.178155 -229.331416) (xy 132.137652 -229.359372) (xy 132.09319 -229.38047) (xy 132.045919 -229.394162)
			(xy 131.997064 -229.400094) (xy 131.947889 -229.398113) (xy 131.89967 -229.388269) (xy 131.853654 -229.370817)
			(xy 131.811033 -229.34621) (xy 131.772912 -229.315085) (xy 131.740277 -229.278248) (xy 131.713974 -229.236652)
			(xy 131.694683 -229.191376) (xy 131.682906 -229.143592) (xy 131.678946 -229.094538) (xy 131.360418 -229.094538)
			(xy 131.359906 -229.119984) (xy 131.351742 -229.170218) (xy 131.335626 -229.218492) (xy 131.311975 -229.263555)
			(xy 131.281402 -229.304241) (xy 131.244698 -229.339496) (xy 131.202814 -229.368406) (xy 131.156835 -229.390223)
			(xy 131.107951 -229.404383) (xy 131.05743 -229.410517) (xy 131.006578 -229.408468) (xy 130.956714 -229.398288)
			(xy 130.909128 -229.380241) (xy 130.865054 -229.354795) (xy 130.825632 -229.322608) (xy 130.791884 -229.284514)
			(xy 130.764683 -229.2415) (xy 130.744735 -229.19468) (xy 130.732556 -229.145266) (xy 130.728461 -229.094538)
			(xy 130.40995 -229.094538) (xy 130.409455 -229.119145) (xy 130.40156 -229.167722) (xy 130.385976 -229.214403)
			(xy 130.363105 -229.25798) (xy 130.33354 -229.297324) (xy 130.298047 -229.331416) (xy 130.257544 -229.359372)
			(xy 130.213082 -229.38047) (xy 130.165811 -229.394162) (xy 130.116956 -229.400094) (xy 130.067781 -229.398113)
			(xy 130.019562 -229.388269) (xy 129.973546 -229.370817) (xy 129.930925 -229.34621) (xy 129.892804 -229.315085)
			(xy 129.860169 -229.278248) (xy 129.833866 -229.236652) (xy 129.814575 -229.191376) (xy 129.802798 -229.143592)
			(xy 129.798838 -229.094538) (xy 129.480564 -229.094538) (xy 129.480052 -229.119984) (xy 129.471888 -229.170218)
			(xy 129.455772 -229.218492) (xy 129.432121 -229.263555) (xy 129.401548 -229.304241) (xy 129.364844 -229.339496)
			(xy 129.32296 -229.368406) (xy 129.276981 -229.390223) (xy 129.228097 -229.404383) (xy 129.177576 -229.410517)
			(xy 129.126724 -229.408468) (xy 129.07686 -229.398288) (xy 129.029274 -229.380241) (xy 128.9852 -229.354795)
			(xy 128.945778 -229.322608) (xy 128.91203 -229.284514) (xy 128.884829 -229.2415) (xy 128.864881 -229.19468)
			(xy 128.852702 -229.145266) (xy 128.848607 -229.094538) (xy 128.540023 -229.094538) (xy 128.540023 -229.119309)
			(xy 128.532261 -229.168317) (xy 128.516927 -229.215506) (xy 128.4944 -229.259716) (xy 128.465235 -229.299858)
			(xy 128.430149 -229.334943) (xy 128.390006 -229.364107) (xy 128.345795 -229.386632) (xy 128.298605 -229.401963)
			(xy 128.249597 -229.409724) (xy 128.224788 -229.41026) (xy 128.197805 -229.409685) (xy 128.144629 -229.400468)
			(xy 128.093792 -229.382356) (xy 128.046768 -229.355874) (xy 128.004923 -229.321792) (xy 127.98679 -229.301802)
			(xy 127.981333 -229.296058) (xy 127.967758 -229.287903) (xy 127.96012 -229.2858) (xy 127.955802 -229.284784)
			(xy 127.852678 -229.324916) (xy 127.843373 -229.329053) (xy 127.828798 -229.343251) (xy 127.820863 -229.361988)
			(xy 127.82042 -229.37216) (xy 127.82042 -229.573328) (xy 127.83947 -229.599744) (xy 127.854964 -229.605078)
			(xy 127.878167 -229.613336) (xy 127.921879 -229.636022) (xy 127.961535 -229.665225) (xy 127.996172 -229.700234)
			(xy 128.024948 -229.740201) (xy 128.047166 -229.784152) (xy 128.062284 -229.831023) (xy 128.069937 -229.879673)
			(xy 128.069937 -229.90429) (xy 128.388884 -229.90429) (xy 128.392844 -229.855236) (xy 128.404621 -229.807452)
			(xy 128.423912 -229.762176) (xy 128.450215 -229.72058) (xy 128.48285 -229.683743) (xy 128.520971 -229.652618)
			(xy 128.563592 -229.628011) (xy 128.609608 -229.610559) (xy 128.657827 -229.600715) (xy 128.707002 -229.598734)
			(xy 128.755857 -229.604666) (xy 128.803128 -229.618358) (xy 128.84759 -229.639456) (xy 128.888093 -229.667412)
			(xy 128.923586 -229.701504) (xy 128.953151 -229.740848) (xy 128.976022 -229.784425) (xy 128.991606 -229.831106)
			(xy 128.999501 -229.879683) (xy 128.999996 -229.90429) (xy 129.318507 -229.90429) (xy 129.322602 -229.853562)
			(xy 129.334781 -229.804148) (xy 129.354729 -229.757328) (xy 129.38193 -229.714314) (xy 129.415678 -229.67622)
			(xy 129.4551 -229.644033) (xy 129.499174 -229.618587) (xy 129.54676 -229.60054) (xy 129.596624 -229.59036)
			(xy 129.647476 -229.588311) (xy 129.697997 -229.594445) (xy 129.746881 -229.608605) (xy 129.79286 -229.630422)
			(xy 129.834744 -229.659332) (xy 129.871448 -229.694587) (xy 129.902021 -229.735273) (xy 129.925672 -229.780336)
			(xy 129.941788 -229.82861) (xy 129.949952 -229.878844) (xy 129.950464 -229.90429) (xy 131.198615 -229.90429)
			(xy 131.20271 -229.853562) (xy 131.214889 -229.804148) (xy 131.234837 -229.757328) (xy 131.262038 -229.714314)
			(xy 131.295786 -229.67622) (xy 131.335208 -229.644033) (xy 131.379282 -229.618587) (xy 131.426868 -229.60054)
			(xy 131.476732 -229.59036) (xy 131.527584 -229.588311) (xy 131.578105 -229.594445) (xy 131.626989 -229.608605)
			(xy 131.672968 -229.630422) (xy 131.714852 -229.659332) (xy 131.751556 -229.694587) (xy 131.782129 -229.735273)
			(xy 131.80578 -229.780336) (xy 131.821896 -229.82861) (xy 131.83006 -229.878844) (xy 131.830572 -229.90429)
			(xy 132.138415 -229.90429) (xy 132.14251 -229.853562) (xy 132.154689 -229.804148) (xy 132.174637 -229.757328)
			(xy 132.201838 -229.714314) (xy 132.235586 -229.67622) (xy 132.275008 -229.644033) (xy 132.319082 -229.618587)
			(xy 132.366668 -229.60054) (xy 132.416532 -229.59036) (xy 132.467384 -229.588311) (xy 132.517905 -229.594445)
			(xy 132.566789 -229.608605) (xy 132.612768 -229.630422) (xy 132.654652 -229.659332) (xy 132.691356 -229.694587)
			(xy 132.721929 -229.735273) (xy 132.74558 -229.780336) (xy 132.761696 -229.82861) (xy 132.76986 -229.878844)
			(xy 132.770372 -229.90429) (xy 132.76986 -229.929736) (xy 132.761696 -229.97997) (xy 132.74558 -230.028244)
			(xy 132.721929 -230.073307) (xy 132.691356 -230.113993) (xy 132.654652 -230.149248) (xy 132.612768 -230.178158)
			(xy 132.566789 -230.199975) (xy 132.517905 -230.214135) (xy 132.467384 -230.220269) (xy 132.416532 -230.21822)
			(xy 132.366668 -230.20804) (xy 132.319082 -230.189993) (xy 132.275008 -230.164547) (xy 132.235586 -230.13236)
			(xy 132.201838 -230.094266) (xy 132.174637 -230.051252) (xy 132.154689 -230.004432) (xy 132.14251 -229.955018)
			(xy 132.138415 -229.90429) (xy 131.830572 -229.90429) (xy 131.83006 -229.929736) (xy 131.821896 -229.97997)
			(xy 131.80578 -230.028244) (xy 131.782129 -230.073307) (xy 131.751556 -230.113993) (xy 131.714852 -230.149248)
			(xy 131.672968 -230.178158) (xy 131.626989 -230.199975) (xy 131.578105 -230.214135) (xy 131.527584 -230.220269)
			(xy 131.476732 -230.21822) (xy 131.426868 -230.20804) (xy 131.379282 -230.189993) (xy 131.335208 -230.164547)
			(xy 131.295786 -230.13236) (xy 131.262038 -230.094266) (xy 131.234837 -230.051252) (xy 131.214889 -230.004432)
			(xy 131.20271 -229.955018) (xy 131.198615 -229.90429) (xy 129.950464 -229.90429) (xy 129.949952 -229.929736)
			(xy 129.941788 -229.97997) (xy 129.925672 -230.028244) (xy 129.902021 -230.073307) (xy 129.871448 -230.113993)
			(xy 129.834744 -230.149248) (xy 129.79286 -230.178158) (xy 129.746881 -230.199975) (xy 129.697997 -230.214135)
			(xy 129.647476 -230.220269) (xy 129.596624 -230.21822) (xy 129.54676 -230.20804) (xy 129.499174 -230.189993)
			(xy 129.4551 -230.164547) (xy 129.415678 -230.13236) (xy 129.38193 -230.094266) (xy 129.354729 -230.051252)
			(xy 129.334781 -230.004432) (xy 129.322602 -229.955018) (xy 129.318507 -229.90429) (xy 128.999996 -229.90429)
			(xy 128.999501 -229.928897) (xy 128.991606 -229.977474) (xy 128.976022 -230.024155) (xy 128.953151 -230.067732)
			(xy 128.923586 -230.107076) (xy 128.888093 -230.141168) (xy 128.84759 -230.169124) (xy 128.803128 -230.190222)
			(xy 128.755857 -230.203914) (xy 128.707002 -230.209846) (xy 128.657827 -230.207865) (xy 128.609608 -230.198021)
			(xy 128.563592 -230.180569) (xy 128.520971 -230.155962) (xy 128.48285 -230.124837) (xy 128.450215 -230.088)
			(xy 128.423912 -230.046404) (xy 128.404621 -230.001128) (xy 128.392844 -229.953344) (xy 128.388884 -229.90429)
			(xy 128.069937 -229.90429) (xy 128.069937 -229.928921) (xy 128.062286 -229.977571) (xy 128.047168 -230.024442)
			(xy 128.024952 -230.068394) (xy 127.996176 -230.108361) (xy 127.961539 -230.143371) (xy 127.921884 -230.172574)
			(xy 127.878173 -230.195262) (xy 127.854964 -230.203502) (xy 127.83947 -230.208836) (xy 127.82042 -230.235252)
			(xy 127.82042 -230.436928) (xy 127.820861 -230.447109) (xy 127.828762 -230.465874) (xy 127.843347 -230.48008)
			(xy 127.852678 -230.484172) (xy 127.94107 -230.518462) (xy 127.948273 -230.521057) (xy 127.96353 -230.522224)
			(xy 127.971042 -230.520748) (xy 127.976884 -230.519478) (xy 127.991913 -230.501029) (xy 128.02658 -230.468435)
			(xy 128.065749 -230.441418) (xy 128.108532 -230.420591) (xy 128.153958 -230.406427) (xy 128.200997 -230.399248)
			(xy 128.224788 -230.398828) (xy 128.249596 -230.399288) (xy 128.298602 -230.407048) (xy 128.345791 -230.422379)
			(xy 128.39 -230.444903) (xy 128.430141 -230.474066) (xy 128.465226 -230.50915) (xy 128.49439 -230.54929)
			(xy 128.516916 -230.593498) (xy 128.532249 -230.640686) (xy 128.540011 -230.689692) (xy 128.540011 -230.71455)
			(xy 128.848607 -230.71455) (xy 128.852702 -230.663822) (xy 128.864881 -230.614408) (xy 128.884829 -230.567588)
			(xy 128.91203 -230.524574) (xy 128.945778 -230.48648) (xy 128.9852 -230.454293) (xy 129.029274 -230.428847)
			(xy 129.07686 -230.4108) (xy 129.126724 -230.40062) (xy 129.177576 -230.398571) (xy 129.228097 -230.404705)
			(xy 129.276981 -230.418865) (xy 129.32296 -230.440682) (xy 129.364844 -230.469592) (xy 129.401548 -230.504847)
			(xy 129.432121 -230.545533) (xy 129.455772 -230.590596) (xy 129.471888 -230.63887) (xy 129.480052 -230.689104)
			(xy 129.480564 -230.71455) (xy 129.798838 -230.71455) (xy 129.802798 -230.665496) (xy 129.814575 -230.617712)
			(xy 129.833866 -230.572436) (xy 129.860169 -230.53084) (xy 129.892804 -230.494003) (xy 129.930925 -230.462878)
			(xy 129.973546 -230.438271) (xy 130.019562 -230.420819) (xy 130.067781 -230.410975) (xy 130.116956 -230.408994)
			(xy 130.165811 -230.414926) (xy 130.213082 -230.428618) (xy 130.257544 -230.449716) (xy 130.298047 -230.477672)
			(xy 130.33354 -230.511764) (xy 130.363105 -230.551108) (xy 130.385976 -230.594685) (xy 130.40156 -230.641366)
			(xy 130.409455 -230.689943) (xy 130.40995 -230.71455) (xy 130.728461 -230.71455) (xy 130.732556 -230.663822)
			(xy 130.744735 -230.614408) (xy 130.764683 -230.567588) (xy 130.791884 -230.524574) (xy 130.825632 -230.48648)
			(xy 130.865054 -230.454293) (xy 130.909128 -230.428847) (xy 130.956714 -230.4108) (xy 131.006578 -230.40062)
			(xy 131.05743 -230.398571) (xy 131.107951 -230.404705) (xy 131.156835 -230.418865) (xy 131.202814 -230.440682)
			(xy 131.244698 -230.469592) (xy 131.281402 -230.504847) (xy 131.311975 -230.545533) (xy 131.335626 -230.590596)
			(xy 131.351742 -230.63887) (xy 131.359906 -230.689104) (xy 131.360418 -230.71455) (xy 131.678946 -230.71455)
			(xy 131.682906 -230.665496) (xy 131.694683 -230.617712) (xy 131.713974 -230.572436) (xy 131.740277 -230.53084)
			(xy 131.772912 -230.494003) (xy 131.811033 -230.462878) (xy 131.853654 -230.438271) (xy 131.89967 -230.420819)
			(xy 131.947889 -230.410975) (xy 131.997064 -230.408994) (xy 132.045919 -230.414926) (xy 132.09319 -230.428618)
			(xy 132.137652 -230.449716) (xy 132.178155 -230.477672) (xy 132.213648 -230.511764) (xy 132.243213 -230.551108)
			(xy 132.266084 -230.594685) (xy 132.281668 -230.641366) (xy 132.289563 -230.689943) (xy 132.290058 -230.71455)
			(xy 132.608569 -230.71455) (xy 132.612664 -230.663822) (xy 132.624843 -230.614408) (xy 132.644791 -230.567588)
			(xy 132.671992 -230.524574) (xy 132.70574 -230.48648) (xy 132.745162 -230.454293) (xy 132.789236 -230.428847)
			(xy 132.836822 -230.4108) (xy 132.886686 -230.40062) (xy 132.937538 -230.398571) (xy 132.988059 -230.404705)
			(xy 133.036943 -230.418865) (xy 133.082922 -230.440682) (xy 133.124806 -230.469592) (xy 133.16151 -230.504847)
			(xy 133.192083 -230.545533) (xy 133.215734 -230.590596) (xy 133.23185 -230.63887) (xy 133.240014 -230.689104)
			(xy 133.240526 -230.71455) (xy 133.240014 -230.739996) (xy 133.23185 -230.79023) (xy 133.215734 -230.838504)
			(xy 133.192083 -230.883567) (xy 133.16151 -230.924253) (xy 133.124806 -230.959508) (xy 133.082922 -230.988418)
			(xy 133.036943 -231.010235) (xy 132.988059 -231.024395) (xy 132.937538 -231.030529) (xy 132.886686 -231.02848)
			(xy 132.836822 -231.0183) (xy 132.789236 -231.000253) (xy 132.745162 -230.974807) (xy 132.70574 -230.94262)
			(xy 132.671992 -230.904526) (xy 132.644791 -230.861512) (xy 132.624843 -230.814692) (xy 132.612664 -230.765278)
			(xy 132.608569 -230.71455) (xy 132.290058 -230.71455) (xy 132.289563 -230.739157) (xy 132.281668 -230.787734)
			(xy 132.266084 -230.834415) (xy 132.243213 -230.877992) (xy 132.213648 -230.917336) (xy 132.178155 -230.951428)
			(xy 132.137652 -230.979384) (xy 132.09319 -231.000482) (xy 132.045919 -231.014174) (xy 131.997064 -231.020106)
			(xy 131.947889 -231.018125) (xy 131.89967 -231.008281) (xy 131.853654 -230.990829) (xy 131.811033 -230.966222)
			(xy 131.772912 -230.935097) (xy 131.740277 -230.89826) (xy 131.713974 -230.856664) (xy 131.694683 -230.811388)
			(xy 131.682906 -230.763604) (xy 131.678946 -230.71455) (xy 131.360418 -230.71455) (xy 131.359906 -230.739996)
			(xy 131.351742 -230.79023) (xy 131.335626 -230.838504) (xy 131.311975 -230.883567) (xy 131.281402 -230.924253)
			(xy 131.244698 -230.959508) (xy 131.202814 -230.988418) (xy 131.156835 -231.010235) (xy 131.107951 -231.024395)
			(xy 131.05743 -231.030529) (xy 131.006578 -231.02848) (xy 130.956714 -231.0183) (xy 130.909128 -231.000253)
			(xy 130.865054 -230.974807) (xy 130.825632 -230.94262) (xy 130.791884 -230.904526) (xy 130.764683 -230.861512)
			(xy 130.744735 -230.814692) (xy 130.732556 -230.765278) (xy 130.728461 -230.71455) (xy 130.40995 -230.71455)
			(xy 130.409455 -230.739157) (xy 130.40156 -230.787734) (xy 130.385976 -230.834415) (xy 130.363105 -230.877992)
			(xy 130.33354 -230.917336) (xy 130.298047 -230.951428) (xy 130.257544 -230.979384) (xy 130.213082 -231.000482)
			(xy 130.165811 -231.014174) (xy 130.116956 -231.020106) (xy 130.067781 -231.018125) (xy 130.019562 -231.008281)
			(xy 129.973546 -230.990829) (xy 129.930925 -230.966222) (xy 129.892804 -230.935097) (xy 129.860169 -230.89826)
			(xy 129.833866 -230.856664) (xy 129.814575 -230.811388) (xy 129.802798 -230.763604) (xy 129.798838 -230.71455)
			(xy 129.480564 -230.71455) (xy 129.480052 -230.739996) (xy 129.471888 -230.79023) (xy 129.455772 -230.838504)
			(xy 129.432121 -230.883567) (xy 129.401548 -230.924253) (xy 129.364844 -230.959508) (xy 129.32296 -230.988418)
			(xy 129.276981 -231.010235) (xy 129.228097 -231.024395) (xy 129.177576 -231.030529) (xy 129.126724 -231.02848)
			(xy 129.07686 -231.0183) (xy 129.029274 -231.000253) (xy 128.9852 -230.974807) (xy 128.945778 -230.94262)
			(xy 128.91203 -230.904526) (xy 128.884829 -230.861512) (xy 128.864881 -230.814692) (xy 128.852702 -230.765278)
			(xy 128.848607 -230.71455) (xy 128.540011 -230.71455) (xy 128.540011 -230.739308) (xy 128.532249 -230.788314)
			(xy 128.516916 -230.835502) (xy 128.49439 -230.87971) (xy 128.465226 -230.91985) (xy 128.430141 -230.954934)
			(xy 128.39 -230.984097) (xy 128.345791 -231.006621) (xy 128.298602 -231.021952) (xy 128.249596 -231.029712)
			(xy 128.224788 -231.030272) (xy 128.197804 -231.029697) (xy 128.144629 -231.020481) (xy 128.093791 -231.002369)
			(xy 128.046766 -230.975888) (xy 128.004921 -230.941806) (xy 127.98679 -230.921814) (xy 127.981333 -230.916069)
			(xy 127.967759 -230.907912) (xy 127.96012 -230.905812) (xy 127.955802 -230.904796) (xy 127.852678 -230.944928)
			(xy 127.843374 -230.949066) (xy 127.828803 -230.963264) (xy 127.820872 -230.982) (xy 127.82042 -230.992172)
			(xy 127.82042 -231.19334) (xy 127.83947 -231.219756) (xy 127.854964 -231.22509) (xy 127.878166 -231.233348)
			(xy 127.921876 -231.256034) (xy 127.96153 -231.285236) (xy 127.996165 -231.320245) (xy 128.024941 -231.36021)
			(xy 128.047157 -231.40416) (xy 128.062274 -231.451029) (xy 128.069926 -231.499677) (xy 128.069926 -231.524302)
			(xy 128.388884 -231.524302) (xy 128.392844 -231.475248) (xy 128.404621 -231.427464) (xy 128.423912 -231.382188)
			(xy 128.450215 -231.340592) (xy 128.48285 -231.303755) (xy 128.520971 -231.27263) (xy 128.563592 -231.248023)
			(xy 128.609608 -231.230571) (xy 128.657827 -231.220727) (xy 128.707002 -231.218746) (xy 128.755857 -231.224678)
			(xy 128.803128 -231.23837) (xy 128.84759 -231.259468) (xy 128.888093 -231.287424) (xy 128.923586 -231.321516)
			(xy 128.953151 -231.36086) (xy 128.976022 -231.404437) (xy 128.991606 -231.451118) (xy 128.999501 -231.499695)
			(xy 128.999996 -231.524302) (xy 129.318507 -231.524302) (xy 129.322602 -231.473574) (xy 129.334781 -231.42416)
			(xy 129.354729 -231.37734) (xy 129.38193 -231.334326) (xy 129.415678 -231.296232) (xy 129.4551 -231.264045)
			(xy 129.499174 -231.238599) (xy 129.54676 -231.220552) (xy 129.596624 -231.210372) (xy 129.647476 -231.208323)
			(xy 129.697997 -231.214457) (xy 129.746881 -231.228617) (xy 129.79286 -231.250434) (xy 129.834744 -231.279344)
			(xy 129.871448 -231.314599) (xy 129.902021 -231.355285) (xy 129.925672 -231.400348) (xy 129.941788 -231.448622)
			(xy 129.949952 -231.498856) (xy 129.950464 -231.524302) (xy 130.268992 -231.524302) (xy 130.272952 -231.475248)
			(xy 130.284729 -231.427464) (xy 130.30402 -231.382188) (xy 130.330323 -231.340592) (xy 130.362958 -231.303755)
			(xy 130.401079 -231.27263) (xy 130.4437 -231.248023) (xy 130.489716 -231.230571) (xy 130.537935 -231.220727)
			(xy 130.58711 -231.218746) (xy 130.635965 -231.224678) (xy 130.683236 -231.23837) (xy 130.727698 -231.259468)
			(xy 130.768201 -231.287424) (xy 130.803694 -231.321516) (xy 130.833259 -231.36086) (xy 130.85613 -231.404437)
			(xy 130.871714 -231.451118) (xy 130.879609 -231.499695) (xy 130.880104 -231.524302) (xy 131.198615 -231.524302)
			(xy 131.20271 -231.473574) (xy 131.214889 -231.42416) (xy 131.234837 -231.37734) (xy 131.262038 -231.334326)
			(xy 131.295786 -231.296232) (xy 131.335208 -231.264045) (xy 131.379282 -231.238599) (xy 131.426868 -231.220552)
			(xy 131.476732 -231.210372) (xy 131.527584 -231.208323) (xy 131.578105 -231.214457) (xy 131.626989 -231.228617)
			(xy 131.672968 -231.250434) (xy 131.714852 -231.279344) (xy 131.751556 -231.314599) (xy 131.782129 -231.355285)
			(xy 131.80578 -231.400348) (xy 131.821896 -231.448622) (xy 131.83006 -231.498856) (xy 131.830572 -231.524302)
			(xy 132.138415 -231.524302) (xy 132.14251 -231.473574) (xy 132.154689 -231.42416) (xy 132.174637 -231.37734)
			(xy 132.201838 -231.334326) (xy 132.235586 -231.296232) (xy 132.275008 -231.264045) (xy 132.319082 -231.238599)
			(xy 132.366668 -231.220552) (xy 132.416532 -231.210372) (xy 132.467384 -231.208323) (xy 132.517905 -231.214457)
			(xy 132.566789 -231.228617) (xy 132.612768 -231.250434) (xy 132.654652 -231.279344) (xy 132.691356 -231.314599)
			(xy 132.721929 -231.355285) (xy 132.74558 -231.400348) (xy 132.761696 -231.448622) (xy 132.76986 -231.498856)
			(xy 132.770372 -231.524302) (xy 132.76986 -231.549748) (xy 132.761696 -231.599982) (xy 132.74558 -231.648256)
			(xy 132.721929 -231.693319) (xy 132.691356 -231.734005) (xy 132.654652 -231.76926) (xy 132.612768 -231.79817)
			(xy 132.566789 -231.819987) (xy 132.517905 -231.834147) (xy 132.467384 -231.840281) (xy 132.416532 -231.838232)
			(xy 132.366668 -231.828052) (xy 132.319082 -231.810005) (xy 132.275008 -231.784559) (xy 132.235586 -231.752372)
			(xy 132.201838 -231.714278) (xy 132.174637 -231.671264) (xy 132.154689 -231.624444) (xy 132.14251 -231.57503)
			(xy 132.138415 -231.524302) (xy 131.830572 -231.524302) (xy 131.83006 -231.549748) (xy 131.821896 -231.599982)
			(xy 131.80578 -231.648256) (xy 131.782129 -231.693319) (xy 131.751556 -231.734005) (xy 131.714852 -231.76926)
			(xy 131.672968 -231.79817) (xy 131.626989 -231.819987) (xy 131.578105 -231.834147) (xy 131.527584 -231.840281)
			(xy 131.476732 -231.838232) (xy 131.426868 -231.828052) (xy 131.379282 -231.810005) (xy 131.335208 -231.784559)
			(xy 131.295786 -231.752372) (xy 131.262038 -231.714278) (xy 131.234837 -231.671264) (xy 131.214889 -231.624444)
			(xy 131.20271 -231.57503) (xy 131.198615 -231.524302) (xy 130.880104 -231.524302) (xy 130.879609 -231.548909)
			(xy 130.871714 -231.597486) (xy 130.85613 -231.644167) (xy 130.833259 -231.687744) (xy 130.803694 -231.727088)
			(xy 130.768201 -231.76118) (xy 130.727698 -231.789136) (xy 130.683236 -231.810234) (xy 130.635965 -231.823926)
			(xy 130.58711 -231.829858) (xy 130.537935 -231.827877) (xy 130.489716 -231.818033) (xy 130.4437 -231.800581)
			(xy 130.401079 -231.775974) (xy 130.362958 -231.744849) (xy 130.330323 -231.708012) (xy 130.30402 -231.666416)
			(xy 130.284729 -231.62114) (xy 130.272952 -231.573356) (xy 130.268992 -231.524302) (xy 129.950464 -231.524302)
			(xy 129.949952 -231.549748) (xy 129.941788 -231.599982) (xy 129.925672 -231.648256) (xy 129.902021 -231.693319)
			(xy 129.871448 -231.734005) (xy 129.834744 -231.76926) (xy 129.79286 -231.79817) (xy 129.746881 -231.819987)
			(xy 129.697997 -231.834147) (xy 129.647476 -231.840281) (xy 129.596624 -231.838232) (xy 129.54676 -231.828052)
			(xy 129.499174 -231.810005) (xy 129.4551 -231.784559) (xy 129.415678 -231.752372) (xy 129.38193 -231.714278)
			(xy 129.354729 -231.671264) (xy 129.334781 -231.624444) (xy 129.322602 -231.57503) (xy 129.318507 -231.524302)
			(xy 128.999996 -231.524302) (xy 128.999501 -231.548909) (xy 128.991606 -231.597486) (xy 128.976022 -231.644167)
			(xy 128.953151 -231.687744) (xy 128.923586 -231.727088) (xy 128.888093 -231.76118) (xy 128.84759 -231.789136)
			(xy 128.803128 -231.810234) (xy 128.755857 -231.823926) (xy 128.707002 -231.829858) (xy 128.657827 -231.827877)
			(xy 128.609608 -231.818033) (xy 128.563592 -231.800581) (xy 128.520971 -231.775974) (xy 128.48285 -231.744849)
			(xy 128.450215 -231.708012) (xy 128.423912 -231.666416) (xy 128.404621 -231.62114) (xy 128.392844 -231.573356)
			(xy 128.388884 -231.524302) (xy 128.069926 -231.524302) (xy 128.069926 -231.548924) (xy 128.062274 -231.597572)
			(xy 128.047156 -231.644441) (xy 128.02494 -231.688391) (xy 127.996165 -231.728356) (xy 127.961529 -231.763365)
			(xy 127.921875 -231.792567) (xy 127.878165 -231.815253) (xy 127.854964 -231.823514) (xy 127.83947 -231.828848)
			(xy 127.82042 -231.855264) (xy 127.82042 -232.056686) (xy 127.820871 -232.06686) (xy 127.828785 -232.085607)
			(xy 127.84337 -232.099795) (xy 127.852678 -232.10393) (xy 127.94107 -232.13822) (xy 127.948273 -232.140812)
			(xy 127.96353 -232.141979) (xy 127.971042 -232.140506) (xy 127.976884 -232.139236) (xy 127.991931 -232.12082)
			(xy 128.026621 -232.088291) (xy 128.0658 -232.061336) (xy 128.108581 -232.040567) (xy 128.153993 -232.026453)
			(xy 128.20101 -232.019315) (xy 128.224788 -232.01884) (xy 128.24958 -232.0193) (xy 128.298552 -232.027055)
			(xy 128.345709 -232.042376) (xy 128.389889 -232.064885) (xy 128.430003 -232.094028) (xy 128.465064 -232.129088)
			(xy 128.494209 -232.169201) (xy 128.51672 -232.21338) (xy 128.532042 -232.260536) (xy 128.539799 -232.309508)
			(xy 128.539799 -232.334308) (xy 128.848607 -232.334308) (xy 128.852702 -232.28358) (xy 128.864881 -232.234166)
			(xy 128.884829 -232.187346) (xy 128.91203 -232.144332) (xy 128.945778 -232.106238) (xy 128.9852 -232.074051)
			(xy 129.029274 -232.048605) (xy 129.07686 -232.030558) (xy 129.126724 -232.020378) (xy 129.177576 -232.018329)
			(xy 129.228097 -232.024463) (xy 129.276981 -232.038623) (xy 129.32296 -232.06044) (xy 129.364844 -232.08935)
			(xy 129.401548 -232.124605) (xy 129.432121 -232.165291) (xy 129.455772 -232.210354) (xy 129.471888 -232.258628)
			(xy 129.480052 -232.308862) (xy 129.480564 -232.334308) (xy 130.728461 -232.334308) (xy 130.732556 -232.28358)
			(xy 130.744735 -232.234166) (xy 130.764683 -232.187346) (xy 130.791884 -232.144332) (xy 130.825632 -232.106238)
			(xy 130.865054 -232.074051) (xy 130.909128 -232.048605) (xy 130.956714 -232.030558) (xy 131.006578 -232.020378)
			(xy 131.05743 -232.018329) (xy 131.107951 -232.024463) (xy 131.156835 -232.038623) (xy 131.202814 -232.06044)
			(xy 131.244698 -232.08935) (xy 131.281402 -232.124605) (xy 131.311975 -232.165291) (xy 131.335626 -232.210354)
			(xy 131.351742 -232.258628) (xy 131.359906 -232.308862) (xy 131.360418 -232.334308) (xy 131.678946 -232.334308)
			(xy 131.682906 -232.285254) (xy 131.694683 -232.23747) (xy 131.713974 -232.192194) (xy 131.740277 -232.150598)
			(xy 131.772912 -232.113761) (xy 131.811033 -232.082636) (xy 131.853654 -232.058029) (xy 131.89967 -232.040577)
			(xy 131.947889 -232.030733) (xy 131.997064 -232.028752) (xy 132.045919 -232.034684) (xy 132.09319 -232.048376)
			(xy 132.137652 -232.069474) (xy 132.178155 -232.09743) (xy 132.213648 -232.131522) (xy 132.243213 -232.170866)
			(xy 132.266084 -232.214443) (xy 132.281668 -232.261124) (xy 132.289563 -232.309701) (xy 132.290058 -232.334308)
			(xy 132.608569 -232.334308) (xy 132.612664 -232.28358) (xy 132.624843 -232.234166) (xy 132.644791 -232.187346)
			(xy 132.671992 -232.144332) (xy 132.70574 -232.106238) (xy 132.745162 -232.074051) (xy 132.789236 -232.048605)
			(xy 132.836822 -232.030558) (xy 132.886686 -232.020378) (xy 132.937538 -232.018329) (xy 132.988059 -232.024463)
			(xy 133.036943 -232.038623) (xy 133.082922 -232.06044) (xy 133.124806 -232.08935) (xy 133.16151 -232.124605)
			(xy 133.192083 -232.165291) (xy 133.215734 -232.210354) (xy 133.23185 -232.258628) (xy 133.240014 -232.308862)
			(xy 133.240526 -232.334308) (xy 133.240014 -232.359754) (xy 133.23185 -232.409988) (xy 133.215734 -232.458262)
			(xy 133.192083 -232.503325) (xy 133.16151 -232.544011) (xy 133.124806 -232.579266) (xy 133.082922 -232.608176)
			(xy 133.036943 -232.629993) (xy 132.988059 -232.644153) (xy 132.937538 -232.650287) (xy 132.886686 -232.648238)
			(xy 132.836822 -232.638058) (xy 132.789236 -232.620011) (xy 132.745162 -232.594565) (xy 132.70574 -232.562378)
			(xy 132.671992 -232.524284) (xy 132.644791 -232.48127) (xy 132.624843 -232.43445) (xy 132.612664 -232.385036)
			(xy 132.608569 -232.334308) (xy 132.290058 -232.334308) (xy 132.289563 -232.358915) (xy 132.281668 -232.407492)
			(xy 132.266084 -232.454173) (xy 132.243213 -232.49775) (xy 132.213648 -232.537094) (xy 132.178155 -232.571186)
			(xy 132.137652 -232.599142) (xy 132.09319 -232.62024) (xy 132.045919 -232.633932) (xy 131.997064 -232.639864)
			(xy 131.947889 -232.637883) (xy 131.89967 -232.628039) (xy 131.853654 -232.610587) (xy 131.811033 -232.58598)
			(xy 131.772912 -232.554855) (xy 131.740277 -232.518018) (xy 131.713974 -232.476422) (xy 131.694683 -232.431146)
			(xy 131.682906 -232.383362) (xy 131.678946 -232.334308) (xy 131.360418 -232.334308) (xy 131.359906 -232.359754)
			(xy 131.351742 -232.409988) (xy 131.335626 -232.458262) (xy 131.311975 -232.503325) (xy 131.281402 -232.544011)
			(xy 131.244698 -232.579266) (xy 131.202814 -232.608176) (xy 131.156835 -232.629993) (xy 131.107951 -232.644153)
			(xy 131.05743 -232.650287) (xy 131.006578 -232.648238) (xy 130.956714 -232.638058) (xy 130.909128 -232.620011)
			(xy 130.865054 -232.594565) (xy 130.825632 -232.562378) (xy 130.791884 -232.524284) (xy 130.764683 -232.48127)
			(xy 130.744735 -232.43445) (xy 130.732556 -232.385036) (xy 130.728461 -232.334308) (xy 129.480564 -232.334308)
			(xy 129.480052 -232.359754) (xy 129.471888 -232.409988) (xy 129.455772 -232.458262) (xy 129.432121 -232.503325)
			(xy 129.401548 -232.544011) (xy 129.364844 -232.579266) (xy 129.32296 -232.608176) (xy 129.276981 -232.629993)
			(xy 129.228097 -232.644153) (xy 129.177576 -232.650287) (xy 129.126724 -232.648238) (xy 129.07686 -232.638058)
			(xy 129.029274 -232.620011) (xy 128.9852 -232.594565) (xy 128.945778 -232.562378) (xy 128.91203 -232.524284)
			(xy 128.884829 -232.48127) (xy 128.864881 -232.43445) (xy 128.852702 -232.385036) (xy 128.848607 -232.334308)
			(xy 128.539799 -232.334308) (xy 128.539799 -232.359092) (xy 128.532042 -232.408064) (xy 128.51672 -232.45522)
			(xy 128.494209 -232.499399) (xy 128.465064 -232.539512) (xy 128.430003 -232.574572) (xy 128.389889 -232.603715)
			(xy 128.345709 -232.626224) (xy 128.298552 -232.641545) (xy 128.24958 -232.6493) (xy 128.224788 -232.649776)
			(xy 128.197812 -232.649248) (xy 128.144641 -232.64011) (xy 128.093802 -232.622051) (xy 128.046781 -232.5956)
			(xy 128.004951 -232.561528) (xy 127.98679 -232.541572) (xy 127.981331 -232.535831) (xy 127.967756 -232.52768)
			(xy 127.96012 -232.52557) (xy 127.955802 -232.524554) (xy 127.852678 -232.564686) (xy 127.84338 -232.568826)
			(xy 127.828825 -232.583028) (xy 127.820915 -232.601763) (xy 127.82042 -232.61193) (xy 127.82042 -232.813352)
			(xy 127.83947 -232.839768) (xy 127.854964 -232.845102) (xy 127.878165 -232.85336) (xy 127.921873 -232.876046)
			(xy 127.961526 -232.905247) (xy 127.996159 -232.940255) (xy 128.024933 -232.980219) (xy 128.047148 -233.024168)
			(xy 128.062264 -233.071035) (xy 128.069915 -233.119682) (xy 128.069914 -233.144314) (xy 128.388884 -233.144314)
			(xy 128.392844 -233.09526) (xy 128.404621 -233.047476) (xy 128.423912 -233.0022) (xy 128.450215 -232.960604)
			(xy 128.48285 -232.923767) (xy 128.520971 -232.892642) (xy 128.563592 -232.868035) (xy 128.609608 -232.850583)
			(xy 128.657827 -232.840739) (xy 128.707002 -232.838758) (xy 128.755857 -232.84469) (xy 128.803128 -232.858382)
			(xy 128.84759 -232.87948) (xy 128.888093 -232.907436) (xy 128.923586 -232.941528) (xy 128.953151 -232.980872)
			(xy 128.976022 -233.024449) (xy 128.991606 -233.07113) (xy 128.999501 -233.119707) (xy 128.999996 -233.144314)
			(xy 129.318507 -233.144314) (xy 129.322602 -233.093586) (xy 129.334781 -233.044172) (xy 129.354729 -232.997352)
			(xy 129.38193 -232.954338) (xy 129.415678 -232.916244) (xy 129.4551 -232.884057) (xy 129.499174 -232.858611)
			(xy 129.54676 -232.840564) (xy 129.596624 -232.830384) (xy 129.647476 -232.828335) (xy 129.697997 -232.834469)
			(xy 129.746881 -232.848629) (xy 129.79286 -232.870446) (xy 129.834744 -232.899356) (xy 129.871448 -232.934611)
			(xy 129.902021 -232.975297) (xy 129.925672 -233.02036) (xy 129.941788 -233.068634) (xy 129.949952 -233.118868)
			(xy 129.950464 -233.144314) (xy 130.268992 -233.144314) (xy 130.272952 -233.09526) (xy 130.284729 -233.047476)
			(xy 130.30402 -233.0022) (xy 130.330323 -232.960604) (xy 130.362958 -232.923767) (xy 130.401079 -232.892642)
			(xy 130.4437 -232.868035) (xy 130.489716 -232.850583) (xy 130.537935 -232.840739) (xy 130.58711 -232.838758)
			(xy 130.635965 -232.84469) (xy 130.683236 -232.858382) (xy 130.727698 -232.87948) (xy 130.768201 -232.907436)
			(xy 130.803694 -232.941528) (xy 130.833259 -232.980872) (xy 130.85613 -233.024449) (xy 130.871714 -233.07113)
			(xy 130.879609 -233.119707) (xy 130.880104 -233.144314) (xy 131.198615 -233.144314) (xy 131.20271 -233.093586)
			(xy 131.214889 -233.044172) (xy 131.234837 -232.997352) (xy 131.262038 -232.954338) (xy 131.295786 -232.916244)
			(xy 131.335208 -232.884057) (xy 131.379282 -232.858611) (xy 131.426868 -232.840564) (xy 131.476732 -232.830384)
			(xy 131.527584 -232.828335) (xy 131.578105 -232.834469) (xy 131.626989 -232.848629) (xy 131.672968 -232.870446)
			(xy 131.714852 -232.899356) (xy 131.751556 -232.934611) (xy 131.782129 -232.975297) (xy 131.80578 -233.02036)
			(xy 131.821896 -233.068634) (xy 131.83006 -233.118868) (xy 131.830572 -233.144314) (xy 132.138415 -233.144314)
			(xy 132.14251 -233.093586) (xy 132.154689 -233.044172) (xy 132.174637 -232.997352) (xy 132.201838 -232.954338)
			(xy 132.235586 -232.916244) (xy 132.275008 -232.884057) (xy 132.319082 -232.858611) (xy 132.366668 -232.840564)
			(xy 132.416532 -232.830384) (xy 132.467384 -232.828335) (xy 132.517905 -232.834469) (xy 132.566789 -232.848629)
			(xy 132.612768 -232.870446) (xy 132.654652 -232.899356) (xy 132.691356 -232.934611) (xy 132.721929 -232.975297)
			(xy 132.74558 -233.02036) (xy 132.761696 -233.068634) (xy 132.76986 -233.118868) (xy 132.770372 -233.144314)
			(xy 132.76986 -233.16976) (xy 132.761696 -233.219994) (xy 132.74558 -233.268268) (xy 132.721929 -233.313331)
			(xy 132.691356 -233.354017) (xy 132.654652 -233.389272) (xy 132.612768 -233.418182) (xy 132.566789 -233.439999)
			(xy 132.517905 -233.454159) (xy 132.467384 -233.460293) (xy 132.416532 -233.458244) (xy 132.366668 -233.448064)
			(xy 132.319082 -233.430017) (xy 132.275008 -233.404571) (xy 132.235586 -233.372384) (xy 132.201838 -233.33429)
			(xy 132.174637 -233.291276) (xy 132.154689 -233.244456) (xy 132.14251 -233.195042) (xy 132.138415 -233.144314)
			(xy 131.830572 -233.144314) (xy 131.83006 -233.16976) (xy 131.821896 -233.219994) (xy 131.80578 -233.268268)
			(xy 131.782129 -233.313331) (xy 131.751556 -233.354017) (xy 131.714852 -233.389272) (xy 131.672968 -233.418182)
			(xy 131.626989 -233.439999) (xy 131.578105 -233.454159) (xy 131.527584 -233.460293) (xy 131.476732 -233.458244)
			(xy 131.426868 -233.448064) (xy 131.379282 -233.430017) (xy 131.335208 -233.404571) (xy 131.295786 -233.372384)
			(xy 131.262038 -233.33429) (xy 131.234837 -233.291276) (xy 131.214889 -233.244456) (xy 131.20271 -233.195042)
			(xy 131.198615 -233.144314) (xy 130.880104 -233.144314) (xy 130.879609 -233.168921) (xy 130.871714 -233.217498)
			(xy 130.85613 -233.264179) (xy 130.833259 -233.307756) (xy 130.803694 -233.3471) (xy 130.768201 -233.381192)
			(xy 130.727698 -233.409148) (xy 130.683236 -233.430246) (xy 130.635965 -233.443938) (xy 130.58711 -233.44987)
			(xy 130.537935 -233.447889) (xy 130.489716 -233.438045) (xy 130.4437 -233.420593) (xy 130.401079 -233.395986)
			(xy 130.362958 -233.364861) (xy 130.330323 -233.328024) (xy 130.30402 -233.286428) (xy 130.284729 -233.241152)
			(xy 130.272952 -233.193368) (xy 130.268992 -233.144314) (xy 129.950464 -233.144314) (xy 129.949952 -233.16976)
			(xy 129.941788 -233.219994) (xy 129.925672 -233.268268) (xy 129.902021 -233.313331) (xy 129.871448 -233.354017)
			(xy 129.834744 -233.389272) (xy 129.79286 -233.418182) (xy 129.746881 -233.439999) (xy 129.697997 -233.454159)
			(xy 129.647476 -233.460293) (xy 129.596624 -233.458244) (xy 129.54676 -233.448064) (xy 129.499174 -233.430017)
			(xy 129.4551 -233.404571) (xy 129.415678 -233.372384) (xy 129.38193 -233.33429) (xy 129.354729 -233.291276)
			(xy 129.334781 -233.244456) (xy 129.322602 -233.195042) (xy 129.318507 -233.144314) (xy 128.999996 -233.144314)
			(xy 128.999501 -233.168921) (xy 128.991606 -233.217498) (xy 128.976022 -233.264179) (xy 128.953151 -233.307756)
			(xy 128.923586 -233.3471) (xy 128.888093 -233.381192) (xy 128.84759 -233.409148) (xy 128.803128 -233.430246)
			(xy 128.755857 -233.443938) (xy 128.707002 -233.44987) (xy 128.657827 -233.447889) (xy 128.609608 -233.438045)
			(xy 128.563592 -233.420593) (xy 128.520971 -233.395986) (xy 128.48285 -233.364861) (xy 128.450215 -233.328024)
			(xy 128.423912 -233.286428) (xy 128.404621 -233.241152) (xy 128.392844 -233.193368) (xy 128.388884 -233.144314)
			(xy 128.069914 -233.144314) (xy 128.069914 -233.168927) (xy 128.062262 -233.217573) (xy 128.047144 -233.26444)
			(xy 128.024928 -233.308389) (xy 127.996153 -233.348352) (xy 127.961519 -233.383359) (xy 127.921866 -233.412559)
			(xy 127.878157 -233.435244) (xy 127.854964 -233.443526) (xy 127.83947 -233.44886) (xy 127.82042 -233.475276)
			(xy 127.82042 -233.676698) (xy 127.820873 -233.686871) (xy 127.82879 -233.705613) (xy 127.843375 -233.719798)
			(xy 127.852678 -233.723942) (xy 127.94107 -233.758232) (xy 127.948273 -233.760828) (xy 127.96353 -233.761996)
			(xy 127.971042 -233.760518) (xy 127.976884 -233.759248) (xy 127.991931 -233.740831) (xy 128.02662 -233.708301)
			(xy 128.065799 -233.681346) (xy 128.10858 -233.660576) (xy 128.153993 -233.646462) (xy 128.20101 -233.639323)
			(xy 128.224788 -233.638852) (xy 128.249579 -233.639312) (xy 128.29855 -233.647067) (xy 128.345705 -233.662387)
			(xy 128.389883 -233.684895) (xy 128.429995 -233.714037) (xy 128.465055 -233.749096) (xy 128.494199 -233.789207)
			(xy 128.516709 -233.833384) (xy 128.532031 -233.880539) (xy 128.539787 -233.929509) (xy 128.539787 -233.95432)
			(xy 128.848607 -233.95432) (xy 128.852702 -233.903592) (xy 128.864881 -233.854178) (xy 128.884829 -233.807358)
			(xy 128.91203 -233.764344) (xy 128.945778 -233.72625) (xy 128.9852 -233.694063) (xy 129.029274 -233.668617)
			(xy 129.07686 -233.65057) (xy 129.126724 -233.64039) (xy 129.177576 -233.638341) (xy 129.228097 -233.644475)
			(xy 129.276981 -233.658635) (xy 129.32296 -233.680452) (xy 129.364844 -233.709362) (xy 129.401548 -233.744617)
			(xy 129.432121 -233.785303) (xy 129.455772 -233.830366) (xy 129.471888 -233.87864) (xy 129.480052 -233.928874)
			(xy 129.480564 -233.95432) (xy 129.798838 -233.95432) (xy 129.802798 -233.905266) (xy 129.814575 -233.857482)
			(xy 129.833866 -233.812206) (xy 129.860169 -233.77061) (xy 129.892804 -233.733773) (xy 129.930925 -233.702648)
			(xy 129.973546 -233.678041) (xy 130.019562 -233.660589) (xy 130.067781 -233.650745) (xy 130.116956 -233.648764)
			(xy 130.165811 -233.654696) (xy 130.213082 -233.668388) (xy 130.257544 -233.689486) (xy 130.298047 -233.717442)
			(xy 130.33354 -233.751534) (xy 130.363105 -233.790878) (xy 130.385976 -233.834455) (xy 130.40156 -233.881136)
			(xy 130.409455 -233.929713) (xy 130.40995 -233.95432) (xy 130.728461 -233.95432) (xy 130.732556 -233.903592)
			(xy 130.744735 -233.854178) (xy 130.764683 -233.807358) (xy 130.791884 -233.764344) (xy 130.825632 -233.72625)
			(xy 130.865054 -233.694063) (xy 130.909128 -233.668617) (xy 130.956714 -233.65057) (xy 131.006578 -233.64039)
			(xy 131.05743 -233.638341) (xy 131.107951 -233.644475) (xy 131.156835 -233.658635) (xy 131.202814 -233.680452)
			(xy 131.244698 -233.709362) (xy 131.281402 -233.744617) (xy 131.311975 -233.785303) (xy 131.335626 -233.830366)
			(xy 131.351742 -233.87864) (xy 131.359906 -233.928874) (xy 131.360418 -233.95432) (xy 131.678946 -233.95432)
			(xy 131.682906 -233.905266) (xy 131.694683 -233.857482) (xy 131.713974 -233.812206) (xy 131.740277 -233.77061)
			(xy 131.772912 -233.733773) (xy 131.811033 -233.702648) (xy 131.853654 -233.678041) (xy 131.89967 -233.660589)
			(xy 131.947889 -233.650745) (xy 131.997064 -233.648764) (xy 132.045919 -233.654696) (xy 132.09319 -233.668388)
			(xy 132.137652 -233.689486) (xy 132.178155 -233.717442) (xy 132.213648 -233.751534) (xy 132.243213 -233.790878)
			(xy 132.266084 -233.834455) (xy 132.281668 -233.881136) (xy 132.289563 -233.929713) (xy 132.290058 -233.95432)
			(xy 132.608569 -233.95432) (xy 132.612664 -233.903592) (xy 132.624843 -233.854178) (xy 132.644791 -233.807358)
			(xy 132.671992 -233.764344) (xy 132.70574 -233.72625) (xy 132.745162 -233.694063) (xy 132.789236 -233.668617)
			(xy 132.836822 -233.65057) (xy 132.886686 -233.64039) (xy 132.937538 -233.638341) (xy 132.988059 -233.644475)
			(xy 133.036943 -233.658635) (xy 133.082922 -233.680452) (xy 133.124806 -233.709362) (xy 133.16151 -233.744617)
			(xy 133.192083 -233.785303) (xy 133.215734 -233.830366) (xy 133.23185 -233.87864) (xy 133.240014 -233.928874)
			(xy 133.240526 -233.95432) (xy 133.240014 -233.979766) (xy 133.23185 -234.03) (xy 133.215734 -234.078274)
			(xy 133.192083 -234.123337) (xy 133.16151 -234.164023) (xy 133.124806 -234.199278) (xy 133.082922 -234.228188)
			(xy 133.036943 -234.250005) (xy 132.988059 -234.264165) (xy 132.937538 -234.270299) (xy 132.886686 -234.26825)
			(xy 132.836822 -234.25807) (xy 132.789236 -234.240023) (xy 132.745162 -234.214577) (xy 132.70574 -234.18239)
			(xy 132.671992 -234.144296) (xy 132.644791 -234.101282) (xy 132.624843 -234.054462) (xy 132.612664 -234.005048)
			(xy 132.608569 -233.95432) (xy 132.290058 -233.95432) (xy 132.289563 -233.978927) (xy 132.281668 -234.027504)
			(xy 132.266084 -234.074185) (xy 132.243213 -234.117762) (xy 132.213648 -234.157106) (xy 132.178155 -234.191198)
			(xy 132.137652 -234.219154) (xy 132.09319 -234.240252) (xy 132.045919 -234.253944) (xy 131.997064 -234.259876)
			(xy 131.947889 -234.257895) (xy 131.89967 -234.248051) (xy 131.853654 -234.230599) (xy 131.811033 -234.205992)
			(xy 131.772912 -234.174867) (xy 131.740277 -234.13803) (xy 131.713974 -234.096434) (xy 131.694683 -234.051158)
			(xy 131.682906 -234.003374) (xy 131.678946 -233.95432) (xy 131.360418 -233.95432) (xy 131.359906 -233.979766)
			(xy 131.351742 -234.03) (xy 131.335626 -234.078274) (xy 131.311975 -234.123337) (xy 131.281402 -234.164023)
			(xy 131.244698 -234.199278) (xy 131.202814 -234.228188) (xy 131.156835 -234.250005) (xy 131.107951 -234.264165)
			(xy 131.05743 -234.270299) (xy 131.006578 -234.26825) (xy 130.956714 -234.25807) (xy 130.909128 -234.240023)
			(xy 130.865054 -234.214577) (xy 130.825632 -234.18239) (xy 130.791884 -234.144296) (xy 130.764683 -234.101282)
			(xy 130.744735 -234.054462) (xy 130.732556 -234.005048) (xy 130.728461 -233.95432) (xy 130.40995 -233.95432)
			(xy 130.409455 -233.978927) (xy 130.40156 -234.027504) (xy 130.385976 -234.074185) (xy 130.363105 -234.117762)
			(xy 130.33354 -234.157106) (xy 130.298047 -234.191198) (xy 130.257544 -234.219154) (xy 130.213082 -234.240252)
			(xy 130.165811 -234.253944) (xy 130.116956 -234.259876) (xy 130.067781 -234.257895) (xy 130.019562 -234.248051)
			(xy 129.973546 -234.230599) (xy 129.930925 -234.205992) (xy 129.892804 -234.174867) (xy 129.860169 -234.13803)
			(xy 129.833866 -234.096434) (xy 129.814575 -234.051158) (xy 129.802798 -234.003374) (xy 129.798838 -233.95432)
			(xy 129.480564 -233.95432) (xy 129.480052 -233.979766) (xy 129.471888 -234.03) (xy 129.455772 -234.078274)
			(xy 129.432121 -234.123337) (xy 129.401548 -234.164023) (xy 129.364844 -234.199278) (xy 129.32296 -234.228188)
			(xy 129.276981 -234.250005) (xy 129.228097 -234.264165) (xy 129.177576 -234.270299) (xy 129.126724 -234.26825)
			(xy 129.07686 -234.25807) (xy 129.029274 -234.240023) (xy 128.9852 -234.214577) (xy 128.945778 -234.18239)
			(xy 128.91203 -234.144296) (xy 128.884829 -234.101282) (xy 128.864881 -234.054462) (xy 128.852702 -234.005048)
			(xy 128.848607 -233.95432) (xy 128.539787 -233.95432) (xy 128.539787 -233.979091) (xy 128.532031 -234.028061)
			(xy 128.516709 -234.075216) (xy 128.494199 -234.119393) (xy 128.465055 -234.159504) (xy 128.429995 -234.194563)
			(xy 128.389883 -234.223705) (xy 128.345705 -234.246213) (xy 128.29855 -234.261533) (xy 128.249579 -234.269288)
			(xy 128.224788 -234.269788) (xy 128.197812 -234.26926) (xy 128.14464 -234.260122) (xy 128.093801 -234.242064)
			(xy 128.046779 -234.215613) (xy 128.004948 -234.181542) (xy 127.98679 -234.161584) (xy 127.981332 -234.155842)
			(xy 127.967757 -234.147689) (xy 127.96012 -234.145582) (xy 127.955802 -234.144566) (xy 127.852678 -234.184698)
			(xy 127.843371 -234.188834) (xy 127.828791 -234.203031) (xy 127.820849 -234.221768) (xy 127.82042 -234.231942)
			(xy 127.82042 -234.433364) (xy 127.83947 -234.45978) (xy 127.854964 -234.465114) (xy 127.878164 -234.473372)
			(xy 127.92187 -234.496057) (xy 127.961521 -234.525258) (xy 127.996153 -234.560265) (xy 128.024925 -234.600228)
			(xy 128.047139 -234.644176) (xy 128.062254 -234.691042) (xy 128.069904 -234.739687) (xy 128.069903 -234.764326)
			(xy 128.388884 -234.764326) (xy 128.392844 -234.715272) (xy 128.404621 -234.667488) (xy 128.423912 -234.622212)
			(xy 128.450215 -234.580616) (xy 128.48285 -234.543779) (xy 128.520971 -234.512654) (xy 128.563592 -234.488047)
			(xy 128.609608 -234.470595) (xy 128.657827 -234.460751) (xy 128.707002 -234.45877) (xy 128.755857 -234.464702)
			(xy 128.803128 -234.478394) (xy 128.84759 -234.499492) (xy 128.888093 -234.527448) (xy 128.923586 -234.56154)
			(xy 128.953151 -234.600884) (xy 128.976022 -234.644461) (xy 128.991606 -234.691142) (xy 128.999501 -234.739719)
			(xy 128.999996 -234.764326) (xy 129.318507 -234.764326) (xy 129.322602 -234.713598) (xy 129.334781 -234.664184)
			(xy 129.354729 -234.617364) (xy 129.38193 -234.57435) (xy 129.415678 -234.536256) (xy 129.4551 -234.504069)
			(xy 129.499174 -234.478623) (xy 129.54676 -234.460576) (xy 129.596624 -234.450396) (xy 129.647476 -234.448347)
			(xy 129.697997 -234.454481) (xy 129.746881 -234.468641) (xy 129.79286 -234.490458) (xy 129.834744 -234.519368)
			(xy 129.871448 -234.554623) (xy 129.902021 -234.595309) (xy 129.925672 -234.640372) (xy 129.941788 -234.688646)
			(xy 129.949952 -234.73888) (xy 129.950464 -234.764326) (xy 131.198615 -234.764326) (xy 131.20271 -234.713598)
			(xy 131.214889 -234.664184) (xy 131.234837 -234.617364) (xy 131.262038 -234.57435) (xy 131.295786 -234.536256)
			(xy 131.335208 -234.504069) (xy 131.379282 -234.478623) (xy 131.426868 -234.460576) (xy 131.476732 -234.450396)
			(xy 131.527584 -234.448347) (xy 131.578105 -234.454481) (xy 131.626989 -234.468641) (xy 131.672968 -234.490458)
			(xy 131.714852 -234.519368) (xy 131.751556 -234.554623) (xy 131.782129 -234.595309) (xy 131.80578 -234.640372)
			(xy 131.821896 -234.688646) (xy 131.83006 -234.73888) (xy 131.830572 -234.764326) (xy 132.138415 -234.764326)
			(xy 132.14251 -234.713598) (xy 132.154689 -234.664184) (xy 132.174637 -234.617364) (xy 132.201838 -234.57435)
			(xy 132.235586 -234.536256) (xy 132.275008 -234.504069) (xy 132.319082 -234.478623) (xy 132.366668 -234.460576)
			(xy 132.416532 -234.450396) (xy 132.467384 -234.448347) (xy 132.517905 -234.454481) (xy 132.566789 -234.468641)
			(xy 132.612768 -234.490458) (xy 132.654652 -234.519368) (xy 132.691356 -234.554623) (xy 132.721929 -234.595309)
			(xy 132.74558 -234.640372) (xy 132.761696 -234.688646) (xy 132.76986 -234.73888) (xy 132.770372 -234.764326)
			(xy 132.76986 -234.789772) (xy 132.761696 -234.840006) (xy 132.74558 -234.88828) (xy 132.721929 -234.933343)
			(xy 132.691356 -234.974029) (xy 132.654652 -235.009284) (xy 132.612768 -235.038194) (xy 132.566789 -235.060011)
			(xy 132.517905 -235.074171) (xy 132.467384 -235.080305) (xy 132.416532 -235.078256) (xy 132.366668 -235.068076)
			(xy 132.319082 -235.050029) (xy 132.275008 -235.024583) (xy 132.235586 -234.992396) (xy 132.201838 -234.954302)
			(xy 132.174637 -234.911288) (xy 132.154689 -234.864468) (xy 132.14251 -234.815054) (xy 132.138415 -234.764326)
			(xy 131.830572 -234.764326) (xy 131.83006 -234.789772) (xy 131.821896 -234.840006) (xy 131.80578 -234.88828)
			(xy 131.782129 -234.933343) (xy 131.751556 -234.974029) (xy 131.714852 -235.009284) (xy 131.672968 -235.038194)
			(xy 131.626989 -235.060011) (xy 131.578105 -235.074171) (xy 131.527584 -235.080305) (xy 131.476732 -235.078256)
			(xy 131.426868 -235.068076) (xy 131.379282 -235.050029) (xy 131.335208 -235.024583) (xy 131.295786 -234.992396)
			(xy 131.262038 -234.954302) (xy 131.234837 -234.911288) (xy 131.214889 -234.864468) (xy 131.20271 -234.815054)
			(xy 131.198615 -234.764326) (xy 129.950464 -234.764326) (xy 129.949952 -234.789772) (xy 129.941788 -234.840006)
			(xy 129.925672 -234.88828) (xy 129.902021 -234.933343) (xy 129.871448 -234.974029) (xy 129.834744 -235.009284)
			(xy 129.79286 -235.038194) (xy 129.746881 -235.060011) (xy 129.697997 -235.074171) (xy 129.647476 -235.080305)
			(xy 129.596624 -235.078256) (xy 129.54676 -235.068076) (xy 129.499174 -235.050029) (xy 129.4551 -235.024583)
			(xy 129.415678 -234.992396) (xy 129.38193 -234.954302) (xy 129.354729 -234.911288) (xy 129.334781 -234.864468)
			(xy 129.322602 -234.815054) (xy 129.318507 -234.764326) (xy 128.999996 -234.764326) (xy 128.999501 -234.788933)
			(xy 128.991606 -234.83751) (xy 128.976022 -234.884191) (xy 128.953151 -234.927768) (xy 128.923586 -234.967112)
			(xy 128.888093 -235.001204) (xy 128.84759 -235.02916) (xy 128.803128 -235.050258) (xy 128.755857 -235.06395)
			(xy 128.707002 -235.069882) (xy 128.657827 -235.067901) (xy 128.609608 -235.058057) (xy 128.563592 -235.040605)
			(xy 128.520971 -235.015998) (xy 128.48285 -234.984873) (xy 128.450215 -234.948036) (xy 128.423912 -234.90644)
			(xy 128.404621 -234.861164) (xy 128.392844 -234.81338) (xy 128.388884 -234.764326) (xy 128.069903 -234.764326)
			(xy 128.069903 -234.78893) (xy 128.06225 -234.837574) (xy 128.047132 -234.884439) (xy 128.024917 -234.928386)
			(xy 127.996142 -234.968347) (xy 127.961509 -235.003353) (xy 127.921856 -235.032551) (xy 127.878149 -235.055235)
			(xy 127.854964 -235.063538) (xy 127.83947 -235.068872) (xy 127.82042 -235.095288) (xy 127.82042 -235.29671)
			(xy 127.820858 -235.306893) (xy 127.828755 -235.325663) (xy 127.84334 -235.339876) (xy 127.852678 -235.343954)
			(xy 127.94107 -235.378244) (xy 127.948273 -235.380839) (xy 127.96353 -235.382007) (xy 127.971042 -235.38053)
			(xy 127.976884 -235.37926) (xy 127.99193 -235.360843) (xy 128.02662 -235.328312) (xy 128.065798 -235.301355)
			(xy 128.108579 -235.280584) (xy 128.153992 -235.266469) (xy 128.20101 -235.25933) (xy 128.224788 -235.258864)
			(xy 128.249578 -235.259324) (xy 128.298547 -235.267078) (xy 128.3457 -235.282398) (xy 128.389876 -235.304905)
			(xy 128.429987 -235.334046) (xy 128.465046 -235.369103) (xy 128.494189 -235.409214) (xy 128.516698 -235.453389)
			(xy 128.532019 -235.500541) (xy 128.539775 -235.54951) (xy 128.539775 -235.574332) (xy 128.848607 -235.574332)
			(xy 128.852702 -235.523604) (xy 128.864881 -235.47419) (xy 128.884829 -235.42737) (xy 128.91203 -235.384356)
			(xy 128.945778 -235.346262) (xy 128.9852 -235.314075) (xy 129.029274 -235.288629) (xy 129.07686 -235.270582)
			(xy 129.126724 -235.260402) (xy 129.177576 -235.258353) (xy 129.228097 -235.264487) (xy 129.276981 -235.278647)
			(xy 129.32296 -235.300464) (xy 129.364844 -235.329374) (xy 129.401548 -235.364629) (xy 129.432121 -235.405315)
			(xy 129.455772 -235.450378) (xy 129.471888 -235.498652) (xy 129.480052 -235.548886) (xy 129.480564 -235.574332)
			(xy 129.798838 -235.574332) (xy 129.802798 -235.525278) (xy 129.814575 -235.477494) (xy 129.833866 -235.432218)
			(xy 129.860169 -235.390622) (xy 129.892804 -235.353785) (xy 129.930925 -235.32266) (xy 129.973546 -235.298053)
			(xy 130.019562 -235.280601) (xy 130.067781 -235.270757) (xy 130.116956 -235.268776) (xy 130.165811 -235.274708)
			(xy 130.213082 -235.2884) (xy 130.257544 -235.309498) (xy 130.298047 -235.337454) (xy 130.33354 -235.371546)
			(xy 130.363105 -235.41089) (xy 130.385976 -235.454467) (xy 130.40156 -235.501148) (xy 130.409455 -235.549725)
			(xy 130.40995 -235.574332) (xy 130.728461 -235.574332) (xy 130.732556 -235.523604) (xy 130.744735 -235.47419)
			(xy 130.764683 -235.42737) (xy 130.791884 -235.384356) (xy 130.825632 -235.346262) (xy 130.865054 -235.314075)
			(xy 130.909128 -235.288629) (xy 130.956714 -235.270582) (xy 131.006578 -235.260402) (xy 131.05743 -235.258353)
			(xy 131.107951 -235.264487) (xy 131.156835 -235.278647) (xy 131.202814 -235.300464) (xy 131.244698 -235.329374)
			(xy 131.281402 -235.364629) (xy 131.311975 -235.405315) (xy 131.335626 -235.450378) (xy 131.351742 -235.498652)
			(xy 131.359906 -235.548886) (xy 131.360418 -235.574332) (xy 131.678946 -235.574332) (xy 131.682906 -235.525278)
			(xy 131.694683 -235.477494) (xy 131.713974 -235.432218) (xy 131.740277 -235.390622) (xy 131.772912 -235.353785)
			(xy 131.811033 -235.32266) (xy 131.853654 -235.298053) (xy 131.89967 -235.280601) (xy 131.947889 -235.270757)
			(xy 131.997064 -235.268776) (xy 132.045919 -235.274708) (xy 132.09319 -235.2884) (xy 132.137652 -235.309498)
			(xy 132.178155 -235.337454) (xy 132.213648 -235.371546) (xy 132.243213 -235.41089) (xy 132.266084 -235.454467)
			(xy 132.281668 -235.501148) (xy 132.289563 -235.549725) (xy 132.290058 -235.574332) (xy 132.608569 -235.574332)
			(xy 132.612664 -235.523604) (xy 132.624843 -235.47419) (xy 132.644791 -235.42737) (xy 132.671992 -235.384356)
			(xy 132.70574 -235.346262) (xy 132.745162 -235.314075) (xy 132.789236 -235.288629) (xy 132.836822 -235.270582)
			(xy 132.886686 -235.260402) (xy 132.937538 -235.258353) (xy 132.988059 -235.264487) (xy 133.036943 -235.278647)
			(xy 133.082922 -235.300464) (xy 133.124806 -235.329374) (xy 133.16151 -235.364629) (xy 133.192083 -235.405315)
			(xy 133.215734 -235.450378) (xy 133.23185 -235.498652) (xy 133.240014 -235.548886) (xy 133.240526 -235.574332)
			(xy 133.240014 -235.599778) (xy 133.23185 -235.650012) (xy 133.215734 -235.698286) (xy 133.192083 -235.743349)
			(xy 133.16151 -235.784035) (xy 133.124806 -235.81929) (xy 133.082922 -235.8482) (xy 133.036943 -235.870017)
			(xy 132.988059 -235.884177) (xy 132.937538 -235.890311) (xy 132.886686 -235.888262) (xy 132.836822 -235.878082)
			(xy 132.789236 -235.860035) (xy 132.745162 -235.834589) (xy 132.70574 -235.802402) (xy 132.671992 -235.764308)
			(xy 132.644791 -235.721294) (xy 132.624843 -235.674474) (xy 132.612664 -235.62506) (xy 132.608569 -235.574332)
			(xy 132.290058 -235.574332) (xy 132.289563 -235.598939) (xy 132.281668 -235.647516) (xy 132.266084 -235.694197)
			(xy 132.243213 -235.737774) (xy 132.213648 -235.777118) (xy 132.178155 -235.81121) (xy 132.137652 -235.839166)
			(xy 132.09319 -235.860264) (xy 132.045919 -235.873956) (xy 131.997064 -235.879888) (xy 131.947889 -235.877907)
			(xy 131.89967 -235.868063) (xy 131.853654 -235.850611) (xy 131.811033 -235.826004) (xy 131.772912 -235.794879)
			(xy 131.740277 -235.758042) (xy 131.713974 -235.716446) (xy 131.694683 -235.67117) (xy 131.682906 -235.623386)
			(xy 131.678946 -235.574332) (xy 131.360418 -235.574332) (xy 131.359906 -235.599778) (xy 131.351742 -235.650012)
			(xy 131.335626 -235.698286) (xy 131.311975 -235.743349) (xy 131.281402 -235.784035) (xy 131.244698 -235.81929)
			(xy 131.202814 -235.8482) (xy 131.156835 -235.870017) (xy 131.107951 -235.884177) (xy 131.05743 -235.890311)
			(xy 131.006578 -235.888262) (xy 130.956714 -235.878082) (xy 130.909128 -235.860035) (xy 130.865054 -235.834589)
			(xy 130.825632 -235.802402) (xy 130.791884 -235.764308) (xy 130.764683 -235.721294) (xy 130.744735 -235.674474)
			(xy 130.732556 -235.62506) (xy 130.728461 -235.574332) (xy 130.40995 -235.574332) (xy 130.409455 -235.598939)
			(xy 130.40156 -235.647516) (xy 130.385976 -235.694197) (xy 130.363105 -235.737774) (xy 130.33354 -235.777118)
			(xy 130.298047 -235.81121) (xy 130.257544 -235.839166) (xy 130.213082 -235.860264) (xy 130.165811 -235.873956)
			(xy 130.116956 -235.879888) (xy 130.067781 -235.877907) (xy 130.019562 -235.868063) (xy 129.973546 -235.850611)
			(xy 129.930925 -235.826004) (xy 129.892804 -235.794879) (xy 129.860169 -235.758042) (xy 129.833866 -235.716446)
			(xy 129.814575 -235.67117) (xy 129.802798 -235.623386) (xy 129.798838 -235.574332) (xy 129.480564 -235.574332)
			(xy 129.480052 -235.599778) (xy 129.471888 -235.650012) (xy 129.455772 -235.698286) (xy 129.432121 -235.743349)
			(xy 129.401548 -235.784035) (xy 129.364844 -235.81929) (xy 129.32296 -235.8482) (xy 129.276981 -235.870017)
			(xy 129.228097 -235.884177) (xy 129.177576 -235.890311) (xy 129.126724 -235.888262) (xy 129.07686 -235.878082)
			(xy 129.029274 -235.860035) (xy 128.9852 -235.834589) (xy 128.945778 -235.802402) (xy 128.91203 -235.764308)
			(xy 128.884829 -235.721294) (xy 128.864881 -235.674474) (xy 128.852702 -235.62506) (xy 128.848607 -235.574332)
			(xy 128.539775 -235.574332) (xy 128.539775 -235.59909) (xy 128.532019 -235.648059) (xy 128.516698 -235.695211)
			(xy 128.494189 -235.739386) (xy 128.465046 -235.779497) (xy 128.429987 -235.814554) (xy 128.389876 -235.843695)
			(xy 128.3457 -235.866202) (xy 128.298547 -235.881522) (xy 128.249578 -235.889276) (xy 128.224788 -235.8898)
			(xy 128.197812 -235.889272) (xy 128.14464 -235.880134) (xy 128.0938 -235.862077) (xy 128.046778 -235.835627)
			(xy 128.004946 -235.801556) (xy 127.98679 -235.781596) (xy 127.981332 -235.775853) (xy 127.967758 -235.767698)
			(xy 127.96012 -235.765594) (xy 127.955802 -235.764578) (xy 127.852678 -235.80471) (xy 127.843372 -235.808846)
			(xy 127.828795 -235.823044) (xy 127.820858 -235.841781) (xy 127.82042 -235.851954) (xy 127.82042 -236.053376)
			(xy 127.83947 -236.079792) (xy 127.854964 -236.085126) (xy 127.878163 -236.093384) (xy 127.921867 -236.116069)
			(xy 127.961516 -236.14527) (xy 127.996146 -236.180276) (xy 128.024917 -236.220237) (xy 128.047129 -236.264184)
			(xy 128.062243 -236.311048) (xy 128.069892 -236.359692) (xy 128.069891 -236.384338) (xy 128.388884 -236.384338)
			(xy 128.392844 -236.335284) (xy 128.404621 -236.2875) (xy 128.423912 -236.242224) (xy 128.450215 -236.200628)
			(xy 128.48285 -236.163791) (xy 128.520971 -236.132666) (xy 128.563592 -236.108059) (xy 128.609608 -236.090607)
			(xy 128.657827 -236.080763) (xy 128.707002 -236.078782) (xy 128.755857 -236.084714) (xy 128.803128 -236.098406)
			(xy 128.84759 -236.119504) (xy 128.888093 -236.14746) (xy 128.923586 -236.181552) (xy 128.953151 -236.220896)
			(xy 128.976022 -236.264473) (xy 128.991606 -236.311154) (xy 128.999501 -236.359731) (xy 128.999996 -236.384338)
			(xy 129.318507 -236.384338) (xy 129.322602 -236.33361) (xy 129.334781 -236.284196) (xy 129.354729 -236.237376)
			(xy 129.38193 -236.194362) (xy 129.415678 -236.156268) (xy 129.4551 -236.124081) (xy 129.499174 -236.098635)
			(xy 129.54676 -236.080588) (xy 129.596624 -236.070408) (xy 129.647476 -236.068359) (xy 129.697997 -236.074493)
			(xy 129.746881 -236.088653) (xy 129.79286 -236.11047) (xy 129.834744 -236.13938) (xy 129.871448 -236.174635)
			(xy 129.902021 -236.215321) (xy 129.925672 -236.260384) (xy 129.941788 -236.308658) (xy 129.949952 -236.358892)
			(xy 129.950464 -236.384338) (xy 130.268992 -236.384338) (xy 130.272952 -236.335284) (xy 130.284729 -236.2875)
			(xy 130.30402 -236.242224) (xy 130.330323 -236.200628) (xy 130.362958 -236.163791) (xy 130.401079 -236.132666)
			(xy 130.4437 -236.108059) (xy 130.489716 -236.090607) (xy 130.537935 -236.080763) (xy 130.58711 -236.078782)
			(xy 130.635965 -236.084714) (xy 130.683236 -236.098406) (xy 130.727698 -236.119504) (xy 130.768201 -236.14746)
			(xy 130.803694 -236.181552) (xy 130.833259 -236.220896) (xy 130.85613 -236.264473) (xy 130.871714 -236.311154)
			(xy 130.879609 -236.359731) (xy 130.880104 -236.384338) (xy 131.198615 -236.384338) (xy 131.20271 -236.33361)
			(xy 131.214889 -236.284196) (xy 131.234837 -236.237376) (xy 131.262038 -236.194362) (xy 131.295786 -236.156268)
			(xy 131.335208 -236.124081) (xy 131.379282 -236.098635) (xy 131.426868 -236.080588) (xy 131.476732 -236.070408)
			(xy 131.527584 -236.068359) (xy 131.578105 -236.074493) (xy 131.626989 -236.088653) (xy 131.672968 -236.11047)
			(xy 131.714852 -236.13938) (xy 131.751556 -236.174635) (xy 131.782129 -236.215321) (xy 131.80578 -236.260384)
			(xy 131.821896 -236.308658) (xy 131.83006 -236.358892) (xy 131.830572 -236.384338) (xy 132.138415 -236.384338)
			(xy 132.14251 -236.33361) (xy 132.154689 -236.284196) (xy 132.174637 -236.237376) (xy 132.201838 -236.194362)
			(xy 132.235586 -236.156268) (xy 132.275008 -236.124081) (xy 132.319082 -236.098635) (xy 132.366668 -236.080588)
			(xy 132.416532 -236.070408) (xy 132.467384 -236.068359) (xy 132.517905 -236.074493) (xy 132.566789 -236.088653)
			(xy 132.612768 -236.11047) (xy 132.654652 -236.13938) (xy 132.691356 -236.174635) (xy 132.721929 -236.215321)
			(xy 132.74558 -236.260384) (xy 132.761696 -236.308658) (xy 132.76986 -236.358892) (xy 132.770372 -236.384338)
			(xy 132.76986 -236.409784) (xy 132.761696 -236.460018) (xy 132.74558 -236.508292) (xy 132.721929 -236.553355)
			(xy 132.691356 -236.594041) (xy 132.654652 -236.629296) (xy 132.612768 -236.658206) (xy 132.566789 -236.680023)
			(xy 132.517905 -236.694183) (xy 132.467384 -236.700317) (xy 132.416532 -236.698268) (xy 132.366668 -236.688088)
			(xy 132.319082 -236.670041) (xy 132.275008 -236.644595) (xy 132.235586 -236.612408) (xy 132.201838 -236.574314)
			(xy 132.174637 -236.5313) (xy 132.154689 -236.48448) (xy 132.14251 -236.435066) (xy 132.138415 -236.384338)
			(xy 131.830572 -236.384338) (xy 131.83006 -236.409784) (xy 131.821896 -236.460018) (xy 131.80578 -236.508292)
			(xy 131.782129 -236.553355) (xy 131.751556 -236.594041) (xy 131.714852 -236.629296) (xy 131.672968 -236.658206)
			(xy 131.626989 -236.680023) (xy 131.578105 -236.694183) (xy 131.527584 -236.700317) (xy 131.476732 -236.698268)
			(xy 131.426868 -236.688088) (xy 131.379282 -236.670041) (xy 131.335208 -236.644595) (xy 131.295786 -236.612408)
			(xy 131.262038 -236.574314) (xy 131.234837 -236.5313) (xy 131.214889 -236.48448) (xy 131.20271 -236.435066)
			(xy 131.198615 -236.384338) (xy 130.880104 -236.384338) (xy 130.879609 -236.408945) (xy 130.871714 -236.457522)
			(xy 130.85613 -236.504203) (xy 130.833259 -236.54778) (xy 130.803694 -236.587124) (xy 130.768201 -236.621216)
			(xy 130.727698 -236.649172) (xy 130.683236 -236.67027) (xy 130.635965 -236.683962) (xy 130.58711 -236.689894)
			(xy 130.537935 -236.687913) (xy 130.489716 -236.678069) (xy 130.4437 -236.660617) (xy 130.401079 -236.63601)
			(xy 130.362958 -236.604885) (xy 130.330323 -236.568048) (xy 130.30402 -236.526452) (xy 130.284729 -236.481176)
			(xy 130.272952 -236.433392) (xy 130.268992 -236.384338) (xy 129.950464 -236.384338) (xy 129.949952 -236.409784)
			(xy 129.941788 -236.460018) (xy 129.925672 -236.508292) (xy 129.902021 -236.553355) (xy 129.871448 -236.594041)
			(xy 129.834744 -236.629296) (xy 129.79286 -236.658206) (xy 129.746881 -236.680023) (xy 129.697997 -236.694183)
			(xy 129.647476 -236.700317) (xy 129.596624 -236.698268) (xy 129.54676 -236.688088) (xy 129.499174 -236.670041)
			(xy 129.4551 -236.644595) (xy 129.415678 -236.612408) (xy 129.38193 -236.574314) (xy 129.354729 -236.5313)
			(xy 129.334781 -236.48448) (xy 129.322602 -236.435066) (xy 129.318507 -236.384338) (xy 128.999996 -236.384338)
			(xy 128.999501 -236.408945) (xy 128.991606 -236.457522) (xy 128.976022 -236.504203) (xy 128.953151 -236.54778)
			(xy 128.923586 -236.587124) (xy 128.888093 -236.621216) (xy 128.84759 -236.649172) (xy 128.803128 -236.67027)
			(xy 128.755857 -236.683962) (xy 128.707002 -236.689894) (xy 128.657827 -236.687913) (xy 128.609608 -236.678069)
			(xy 128.563592 -236.660617) (xy 128.520971 -236.63601) (xy 128.48285 -236.604885) (xy 128.450215 -236.568048)
			(xy 128.423912 -236.526452) (xy 128.404621 -236.481176) (xy 128.392844 -236.433392) (xy 128.388884 -236.384338)
			(xy 128.069891 -236.384338) (xy 128.06989 -236.408933) (xy 128.062238 -236.457575) (xy 128.04712 -236.504438)
			(xy 128.024904 -236.548383) (xy 127.996131 -236.588343) (xy 127.961498 -236.623346) (xy 127.921847 -236.652543)
			(xy 127.878141 -236.675225) (xy 127.854964 -236.68355) (xy 127.83947 -236.688884) (xy 127.82042 -236.7153)
			(xy 127.82042 -236.916722) (xy 127.82086 -236.926904) (xy 127.82876 -236.94567) (xy 127.843345 -236.959879)
			(xy 127.852678 -236.963966) (xy 127.94107 -236.998256) (xy 127.948273 -237.000851) (xy 127.96353 -237.002018)
			(xy 127.971042 -237.000542) (xy 127.976884 -236.999272) (xy 127.99193 -236.980854) (xy 128.026619 -236.948322)
			(xy 128.065797 -236.921364) (xy 128.108578 -236.900593) (xy 128.153992 -236.886477) (xy 128.20101 -236.879338)
			(xy 128.224788 -236.878876) (xy 128.249577 -236.879336) (xy 128.298544 -236.88709) (xy 128.345696 -236.902409)
			(xy 128.38987 -236.924915) (xy 128.42998 -236.954055) (xy 128.465037 -236.989111) (xy 128.494178 -237.02922)
			(xy 128.516687 -237.073393) (xy 128.532007 -237.120544) (xy 128.539763 -237.169511) (xy 128.539763 -237.194344)
			(xy 128.848607 -237.194344) (xy 128.852702 -237.143616) (xy 128.864881 -237.094202) (xy 128.884829 -237.047382)
			(xy 128.91203 -237.004368) (xy 128.945778 -236.966274) (xy 128.9852 -236.934087) (xy 129.029274 -236.908641)
			(xy 129.07686 -236.890594) (xy 129.126724 -236.880414) (xy 129.177576 -236.878365) (xy 129.228097 -236.884499)
			(xy 129.276981 -236.898659) (xy 129.32296 -236.920476) (xy 129.364844 -236.949386) (xy 129.401548 -236.984641)
			(xy 129.432121 -237.025327) (xy 129.455772 -237.07039) (xy 129.471888 -237.118664) (xy 129.480052 -237.168898)
			(xy 129.480564 -237.194344) (xy 130.728461 -237.194344) (xy 130.732556 -237.143616) (xy 130.744735 -237.094202)
			(xy 130.764683 -237.047382) (xy 130.791884 -237.004368) (xy 130.825632 -236.966274) (xy 130.865054 -236.934087)
			(xy 130.909128 -236.908641) (xy 130.956714 -236.890594) (xy 131.006578 -236.880414) (xy 131.05743 -236.878365)
			(xy 131.107951 -236.884499) (xy 131.156835 -236.898659) (xy 131.202814 -236.920476) (xy 131.244698 -236.949386)
			(xy 131.281402 -236.984641) (xy 131.311975 -237.025327) (xy 131.335626 -237.07039) (xy 131.351742 -237.118664)
			(xy 131.359906 -237.168898) (xy 131.360418 -237.194344) (xy 131.678946 -237.194344) (xy 131.682906 -237.14529)
			(xy 131.694683 -237.097506) (xy 131.713974 -237.05223) (xy 131.740277 -237.010634) (xy 131.772912 -236.973797)
			(xy 131.811033 -236.942672) (xy 131.853654 -236.918065) (xy 131.89967 -236.900613) (xy 131.947889 -236.890769)
			(xy 131.997064 -236.888788) (xy 132.045919 -236.89472) (xy 132.09319 -236.908412) (xy 132.137652 -236.92951)
			(xy 132.178155 -236.957466) (xy 132.213648 -236.991558) (xy 132.243213 -237.030902) (xy 132.266084 -237.074479)
			(xy 132.281668 -237.12116) (xy 132.289563 -237.169737) (xy 132.290058 -237.194344) (xy 132.608569 -237.194344)
			(xy 132.612664 -237.143616) (xy 132.624843 -237.094202) (xy 132.644791 -237.047382) (xy 132.671992 -237.004368)
			(xy 132.70574 -236.966274) (xy 132.745162 -236.934087) (xy 132.789236 -236.908641) (xy 132.836822 -236.890594)
			(xy 132.886686 -236.880414) (xy 132.937538 -236.878365) (xy 132.988059 -236.884499) (xy 133.036943 -236.898659)
			(xy 133.082922 -236.920476) (xy 133.124806 -236.949386) (xy 133.16151 -236.984641) (xy 133.192083 -237.025327)
			(xy 133.215734 -237.07039) (xy 133.23185 -237.118664) (xy 133.240014 -237.168898) (xy 133.240526 -237.194344)
			(xy 133.240014 -237.21979) (xy 133.23185 -237.270024) (xy 133.215734 -237.318298) (xy 133.192083 -237.363361)
			(xy 133.16151 -237.404047) (xy 133.124806 -237.439302) (xy 133.082922 -237.468212) (xy 133.036943 -237.490029)
			(xy 132.988059 -237.504189) (xy 132.937538 -237.510323) (xy 132.886686 -237.508274) (xy 132.836822 -237.498094)
			(xy 132.789236 -237.480047) (xy 132.745162 -237.454601) (xy 132.70574 -237.422414) (xy 132.671992 -237.38432)
			(xy 132.644791 -237.341306) (xy 132.624843 -237.294486) (xy 132.612664 -237.245072) (xy 132.608569 -237.194344)
			(xy 132.290058 -237.194344) (xy 132.289563 -237.218951) (xy 132.281668 -237.267528) (xy 132.266084 -237.314209)
			(xy 132.243213 -237.357786) (xy 132.213648 -237.39713) (xy 132.178155 -237.431222) (xy 132.137652 -237.459178)
			(xy 132.09319 -237.480276) (xy 132.045919 -237.493968) (xy 131.997064 -237.4999) (xy 131.947889 -237.497919)
			(xy 131.89967 -237.488075) (xy 131.853654 -237.470623) (xy 131.811033 -237.446016) (xy 131.772912 -237.414891)
			(xy 131.740277 -237.378054) (xy 131.713974 -237.336458) (xy 131.694683 -237.291182) (xy 131.682906 -237.243398)
			(xy 131.678946 -237.194344) (xy 131.360418 -237.194344) (xy 131.359906 -237.21979) (xy 131.351742 -237.270024)
			(xy 131.335626 -237.318298) (xy 131.311975 -237.363361) (xy 131.281402 -237.404047) (xy 131.244698 -237.439302)
			(xy 131.202814 -237.468212) (xy 131.156835 -237.490029) (xy 131.107951 -237.504189) (xy 131.05743 -237.510323)
			(xy 131.006578 -237.508274) (xy 130.956714 -237.498094) (xy 130.909128 -237.480047) (xy 130.865054 -237.454601)
			(xy 130.825632 -237.422414) (xy 130.791884 -237.38432) (xy 130.764683 -237.341306) (xy 130.744735 -237.294486)
			(xy 130.732556 -237.245072) (xy 130.728461 -237.194344) (xy 129.480564 -237.194344) (xy 129.480052 -237.21979)
			(xy 129.471888 -237.270024) (xy 129.455772 -237.318298) (xy 129.432121 -237.363361) (xy 129.401548 -237.404047)
			(xy 129.364844 -237.439302) (xy 129.32296 -237.468212) (xy 129.276981 -237.490029) (xy 129.228097 -237.504189)
			(xy 129.177576 -237.510323) (xy 129.126724 -237.508274) (xy 129.07686 -237.498094) (xy 129.029274 -237.480047)
			(xy 128.9852 -237.454601) (xy 128.945778 -237.422414) (xy 128.91203 -237.38432) (xy 128.884829 -237.341306)
			(xy 128.864881 -237.294486) (xy 128.852702 -237.245072) (xy 128.848607 -237.194344) (xy 128.539763 -237.194344)
			(xy 128.539763 -237.219089) (xy 128.532007 -237.268056) (xy 128.516687 -237.315207) (xy 128.494178 -237.35938)
			(xy 128.465037 -237.399489) (xy 128.42998 -237.434545) (xy 128.38987 -237.463685) (xy 128.345696 -237.486191)
			(xy 128.298544 -237.50151) (xy 128.249577 -237.509264) (xy 128.224788 -237.509812) (xy 128.197812 -237.509284)
			(xy 128.14464 -237.500147) (xy 128.0938 -237.48209) (xy 128.046776 -237.45564) (xy 128.004943 -237.42157)
			(xy 127.98679 -237.401608) (xy 127.981333 -237.395863) (xy 127.967759 -237.387707) (xy 127.96012 -237.385606)
			(xy 127.955802 -237.38459) (xy 127.852678 -237.424722) (xy 127.843373 -237.428859) (xy 127.8288 -237.443058)
			(xy 127.820867 -237.461794) (xy 127.82042 -237.471966) (xy 127.82042 -237.673388) (xy 127.83947 -237.699804)
			(xy 127.854964 -237.705138) (xy 127.878162 -237.713396) (xy 127.921865 -237.736081) (xy 127.961512 -237.765281)
			(xy 127.99614 -237.800286) (xy 128.024909 -237.840247) (xy 128.04712 -237.884192) (xy 128.062233 -237.931055)
			(xy 128.069881 -237.979696) (xy 128.06988 -238.00435) (xy 128.388884 -238.00435) (xy 128.392844 -237.955296)
			(xy 128.404621 -237.907512) (xy 128.423912 -237.862236) (xy 128.450215 -237.82064) (xy 128.48285 -237.783803)
			(xy 128.520971 -237.752678) (xy 128.563592 -237.728071) (xy 128.609608 -237.710619) (xy 128.657827 -237.700775)
			(xy 128.707002 -237.698794) (xy 128.755857 -237.704726) (xy 128.803128 -237.718418) (xy 128.84759 -237.739516)
			(xy 128.888093 -237.767472) (xy 128.923586 -237.801564) (xy 128.953151 -237.840908) (xy 128.976022 -237.884485)
			(xy 128.991606 -237.931166) (xy 128.999501 -237.979743) (xy 128.999996 -238.00435) (xy 129.318507 -238.00435)
			(xy 129.322602 -237.953622) (xy 129.334781 -237.904208) (xy 129.354729 -237.857388) (xy 129.38193 -237.814374)
			(xy 129.415678 -237.77628) (xy 129.4551 -237.744093) (xy 129.499174 -237.718647) (xy 129.54676 -237.7006)
			(xy 129.596624 -237.69042) (xy 129.647476 -237.688371) (xy 129.697997 -237.694505) (xy 129.746881 -237.708665)
			(xy 129.79286 -237.730482) (xy 129.834744 -237.759392) (xy 129.871448 -237.794647) (xy 129.902021 -237.835333)
			(xy 129.925672 -237.880396) (xy 129.941788 -237.92867) (xy 129.949952 -237.978904) (xy 129.950464 -238.00435)
			(xy 130.268992 -238.00435) (xy 130.272952 -237.955296) (xy 130.284729 -237.907512) (xy 130.30402 -237.862236)
			(xy 130.330323 -237.82064) (xy 130.362958 -237.783803) (xy 130.401079 -237.752678) (xy 130.4437 -237.728071)
			(xy 130.489716 -237.710619) (xy 130.537935 -237.700775) (xy 130.58711 -237.698794) (xy 130.635965 -237.704726)
			(xy 130.683236 -237.718418) (xy 130.727698 -237.739516) (xy 130.768201 -237.767472) (xy 130.803694 -237.801564)
			(xy 130.833259 -237.840908) (xy 130.85613 -237.884485) (xy 130.871714 -237.931166) (xy 130.879609 -237.979743)
			(xy 130.880104 -238.00435) (xy 131.198615 -238.00435) (xy 131.20271 -237.953622) (xy 131.214889 -237.904208)
			(xy 131.234837 -237.857388) (xy 131.262038 -237.814374) (xy 131.295786 -237.77628) (xy 131.335208 -237.744093)
			(xy 131.379282 -237.718647) (xy 131.426868 -237.7006) (xy 131.476732 -237.69042) (xy 131.527584 -237.688371)
			(xy 131.578105 -237.694505) (xy 131.626989 -237.708665) (xy 131.672968 -237.730482) (xy 131.714852 -237.759392)
			(xy 131.751556 -237.794647) (xy 131.782129 -237.835333) (xy 131.80578 -237.880396) (xy 131.821896 -237.92867)
			(xy 131.83006 -237.978904) (xy 131.830572 -238.00435) (xy 132.138415 -238.00435) (xy 132.14251 -237.953622)
			(xy 132.154689 -237.904208) (xy 132.174637 -237.857388) (xy 132.201838 -237.814374) (xy 132.235586 -237.77628)
			(xy 132.275008 -237.744093) (xy 132.319082 -237.718647) (xy 132.366668 -237.7006) (xy 132.416532 -237.69042)
			(xy 132.467384 -237.688371) (xy 132.517905 -237.694505) (xy 132.566789 -237.708665) (xy 132.612768 -237.730482)
			(xy 132.654652 -237.759392) (xy 132.691356 -237.794647) (xy 132.721929 -237.835333) (xy 132.74558 -237.880396)
			(xy 132.761696 -237.92867) (xy 132.76986 -237.978904) (xy 132.770372 -238.00435) (xy 132.76986 -238.029796)
			(xy 132.761696 -238.08003) (xy 132.74558 -238.128304) (xy 132.721929 -238.173367) (xy 132.691356 -238.214053)
			(xy 132.654652 -238.249308) (xy 132.612768 -238.278218) (xy 132.566789 -238.300035) (xy 132.517905 -238.314195)
			(xy 132.467384 -238.320329) (xy 132.416532 -238.31828) (xy 132.366668 -238.3081) (xy 132.319082 -238.290053)
			(xy 132.275008 -238.264607) (xy 132.235586 -238.23242) (xy 132.201838 -238.194326) (xy 132.174637 -238.151312)
			(xy 132.154689 -238.104492) (xy 132.14251 -238.055078) (xy 132.138415 -238.00435) (xy 131.830572 -238.00435)
			(xy 131.83006 -238.029796) (xy 131.821896 -238.08003) (xy 131.80578 -238.128304) (xy 131.782129 -238.173367)
			(xy 131.751556 -238.214053) (xy 131.714852 -238.249308) (xy 131.672968 -238.278218) (xy 131.626989 -238.300035)
			(xy 131.578105 -238.314195) (xy 131.527584 -238.320329) (xy 131.476732 -238.31828) (xy 131.426868 -238.3081)
			(xy 131.379282 -238.290053) (xy 131.335208 -238.264607) (xy 131.295786 -238.23242) (xy 131.262038 -238.194326)
			(xy 131.234837 -238.151312) (xy 131.214889 -238.104492) (xy 131.20271 -238.055078) (xy 131.198615 -238.00435)
			(xy 130.880104 -238.00435) (xy 130.879609 -238.028957) (xy 130.871714 -238.077534) (xy 130.85613 -238.124215)
			(xy 130.833259 -238.167792) (xy 130.803694 -238.207136) (xy 130.768201 -238.241228) (xy 130.727698 -238.269184)
			(xy 130.683236 -238.290282) (xy 130.635965 -238.303974) (xy 130.58711 -238.309906) (xy 130.537935 -238.307925)
			(xy 130.489716 -238.298081) (xy 130.4437 -238.280629) (xy 130.401079 -238.256022) (xy 130.362958 -238.224897)
			(xy 130.330323 -238.18806) (xy 130.30402 -238.146464) (xy 130.284729 -238.101188) (xy 130.272952 -238.053404)
			(xy 130.268992 -238.00435) (xy 129.950464 -238.00435) (xy 129.949952 -238.029796) (xy 129.941788 -238.08003)
			(xy 129.925672 -238.128304) (xy 129.902021 -238.173367) (xy 129.871448 -238.214053) (xy 129.834744 -238.249308)
			(xy 129.79286 -238.278218) (xy 129.746881 -238.300035) (xy 129.697997 -238.314195) (xy 129.647476 -238.320329)
			(xy 129.596624 -238.31828) (xy 129.54676 -238.3081) (xy 129.499174 -238.290053) (xy 129.4551 -238.264607)
			(xy 129.415678 -238.23242) (xy 129.38193 -238.194326) (xy 129.354729 -238.151312) (xy 129.334781 -238.104492)
			(xy 129.322602 -238.055078) (xy 129.318507 -238.00435) (xy 128.999996 -238.00435) (xy 128.999501 -238.028957)
			(xy 128.991606 -238.077534) (xy 128.976022 -238.124215) (xy 128.953151 -238.167792) (xy 128.923586 -238.207136)
			(xy 128.888093 -238.241228) (xy 128.84759 -238.269184) (xy 128.803128 -238.290282) (xy 128.755857 -238.303974)
			(xy 128.707002 -238.309906) (xy 128.657827 -238.307925) (xy 128.609608 -238.298081) (xy 128.563592 -238.280629)
			(xy 128.520971 -238.256022) (xy 128.48285 -238.224897) (xy 128.450215 -238.18806) (xy 128.423912 -238.146464)
			(xy 128.404621 -238.101188) (xy 128.392844 -238.053404) (xy 128.388884 -238.00435) (xy 128.06988 -238.00435)
			(xy 128.069879 -238.028935) (xy 128.062226 -238.077576) (xy 128.047108 -238.124437) (xy 128.024893 -238.168381)
			(xy 127.99612 -238.208338) (xy 127.961488 -238.24334) (xy 127.921838 -238.272536) (xy 127.878133 -238.295216)
			(xy 127.854964 -238.303562) (xy 127.83947 -238.308896) (xy 127.82042 -238.335312) (xy 127.82042 -238.536734)
			(xy 127.820862 -238.546914) (xy 127.828765 -238.565677) (xy 127.843349 -238.579882) (xy 127.852678 -238.583978)
			(xy 127.94107 -238.618268) (xy 127.948273 -238.620862) (xy 127.96353 -238.62203) (xy 127.971042 -238.620554)
			(xy 127.976884 -238.619284) (xy 127.99193 -238.600866) (xy 128.026618 -238.568332) (xy 128.065796 -238.541374)
			(xy 128.108577 -238.520601) (xy 128.153991 -238.506485) (xy 128.201009 -238.499345) (xy 128.224788 -238.498888)
			(xy 128.249584 -238.499348) (xy 128.298565 -238.507104) (xy 128.345729 -238.522428) (xy 128.389916 -238.54494)
			(xy 128.430037 -238.574088) (xy 128.465104 -238.609154) (xy 128.494253 -238.649274) (xy 128.516768 -238.69346)
			(xy 128.532093 -238.740624) (xy 128.539851 -238.789604) (xy 128.539851 -238.814356) (xy 128.848607 -238.814356)
			(xy 128.852702 -238.763628) (xy 128.864881 -238.714214) (xy 128.884829 -238.667394) (xy 128.91203 -238.62438)
			(xy 128.945778 -238.586286) (xy 128.9852 -238.554099) (xy 129.029274 -238.528653) (xy 129.07686 -238.510606)
			(xy 129.126724 -238.500426) (xy 129.177576 -238.498377) (xy 129.228097 -238.504511) (xy 129.276981 -238.518671)
			(xy 129.32296 -238.540488) (xy 129.364844 -238.569398) (xy 129.401548 -238.604653) (xy 129.432121 -238.645339)
			(xy 129.455772 -238.690402) (xy 129.471888 -238.738676) (xy 129.480052 -238.78891) (xy 129.480564 -238.814356)
			(xy 129.798838 -238.814356) (xy 129.802798 -238.765302) (xy 129.814575 -238.717518) (xy 129.833866 -238.672242)
			(xy 129.860169 -238.630646) (xy 129.892804 -238.593809) (xy 129.930925 -238.562684) (xy 129.973546 -238.538077)
			(xy 130.019562 -238.520625) (xy 130.067781 -238.510781) (xy 130.116956 -238.5088) (xy 130.165811 -238.514732)
			(xy 130.213082 -238.528424) (xy 130.257544 -238.549522) (xy 130.298047 -238.577478) (xy 130.33354 -238.61157)
			(xy 130.363105 -238.650914) (xy 130.385976 -238.694491) (xy 130.40156 -238.741172) (xy 130.409455 -238.789749)
			(xy 130.40995 -238.814356) (xy 130.728461 -238.814356) (xy 130.732556 -238.763628) (xy 130.744735 -238.714214)
			(xy 130.764683 -238.667394) (xy 130.791884 -238.62438) (xy 130.825632 -238.586286) (xy 130.865054 -238.554099)
			(xy 130.909128 -238.528653) (xy 130.956714 -238.510606) (xy 131.006578 -238.500426) (xy 131.05743 -238.498377)
			(xy 131.107951 -238.504511) (xy 131.156835 -238.518671) (xy 131.202814 -238.540488) (xy 131.244698 -238.569398)
			(xy 131.281402 -238.604653) (xy 131.311975 -238.645339) (xy 131.335626 -238.690402) (xy 131.351742 -238.738676)
			(xy 131.359906 -238.78891) (xy 131.360418 -238.814356) (xy 131.678946 -238.814356) (xy 131.682906 -238.765302)
			(xy 131.694683 -238.717518) (xy 131.713974 -238.672242) (xy 131.740277 -238.630646) (xy 131.772912 -238.593809)
			(xy 131.811033 -238.562684) (xy 131.853654 -238.538077) (xy 131.89967 -238.520625) (xy 131.947889 -238.510781)
			(xy 131.997064 -238.5088) (xy 132.045919 -238.514732) (xy 132.09319 -238.528424) (xy 132.137652 -238.549522)
			(xy 132.178155 -238.577478) (xy 132.213648 -238.61157) (xy 132.243213 -238.650914) (xy 132.266084 -238.694491)
			(xy 132.281668 -238.741172) (xy 132.289563 -238.789749) (xy 132.290058 -238.814356) (xy 132.608569 -238.814356)
			(xy 132.612664 -238.763628) (xy 132.624843 -238.714214) (xy 132.644791 -238.667394) (xy 132.671992 -238.62438)
			(xy 132.70574 -238.586286) (xy 132.745162 -238.554099) (xy 132.789236 -238.528653) (xy 132.836822 -238.510606)
			(xy 132.886686 -238.500426) (xy 132.937538 -238.498377) (xy 132.988059 -238.504511) (xy 133.036943 -238.518671)
			(xy 133.082922 -238.540488) (xy 133.124806 -238.569398) (xy 133.16151 -238.604653) (xy 133.192083 -238.645339)
			(xy 133.215734 -238.690402) (xy 133.23185 -238.738676) (xy 133.240014 -238.78891) (xy 133.240526 -238.814356)
			(xy 133.240014 -238.839802) (xy 133.23185 -238.890036) (xy 133.215734 -238.93831) (xy 133.192083 -238.983373)
			(xy 133.16151 -239.024059) (xy 133.124806 -239.059314) (xy 133.082922 -239.088224) (xy 133.036943 -239.110041)
			(xy 132.988059 -239.124201) (xy 132.937538 -239.130335) (xy 132.886686 -239.128286) (xy 132.836822 -239.118106)
			(xy 132.789236 -239.100059) (xy 132.745162 -239.074613) (xy 132.70574 -239.042426) (xy 132.671992 -239.004332)
			(xy 132.644791 -238.961318) (xy 132.624843 -238.914498) (xy 132.612664 -238.865084) (xy 132.608569 -238.814356)
			(xy 132.290058 -238.814356) (xy 132.289563 -238.838963) (xy 132.281668 -238.88754) (xy 132.266084 -238.934221)
			(xy 132.243213 -238.977798) (xy 132.213648 -239.017142) (xy 132.178155 -239.051234) (xy 132.137652 -239.07919)
			(xy 132.09319 -239.100288) (xy 132.045919 -239.11398) (xy 131.997064 -239.119912) (xy 131.947889 -239.117931)
			(xy 131.89967 -239.108087) (xy 131.853654 -239.090635) (xy 131.811033 -239.066028) (xy 131.772912 -239.034903)
			(xy 131.740277 -238.998066) (xy 131.713974 -238.95647) (xy 131.694683 -238.911194) (xy 131.682906 -238.86341)
			(xy 131.678946 -238.814356) (xy 131.360418 -238.814356) (xy 131.359906 -238.839802) (xy 131.351742 -238.890036)
			(xy 131.335626 -238.93831) (xy 131.311975 -238.983373) (xy 131.281402 -239.024059) (xy 131.244698 -239.059314)
			(xy 131.202814 -239.088224) (xy 131.156835 -239.110041) (xy 131.107951 -239.124201) (xy 131.05743 -239.130335)
			(xy 131.006578 -239.128286) (xy 130.956714 -239.118106) (xy 130.909128 -239.100059) (xy 130.865054 -239.074613)
			(xy 130.825632 -239.042426) (xy 130.791884 -239.004332) (xy 130.764683 -238.961318) (xy 130.744735 -238.914498)
			(xy 130.732556 -238.865084) (xy 130.728461 -238.814356) (xy 130.40995 -238.814356) (xy 130.409455 -238.838963)
			(xy 130.40156 -238.88754) (xy 130.385976 -238.934221) (xy 130.363105 -238.977798) (xy 130.33354 -239.017142)
			(xy 130.298047 -239.051234) (xy 130.257544 -239.07919) (xy 130.213082 -239.100288) (xy 130.165811 -239.11398)
			(xy 130.116956 -239.119912) (xy 130.067781 -239.117931) (xy 130.019562 -239.108087) (xy 129.973546 -239.090635)
			(xy 129.930925 -239.066028) (xy 129.892804 -239.034903) (xy 129.860169 -238.998066) (xy 129.833866 -238.95647)
			(xy 129.814575 -238.911194) (xy 129.802798 -238.86341) (xy 129.798838 -238.814356) (xy 129.480564 -238.814356)
			(xy 129.480052 -238.839802) (xy 129.471888 -238.890036) (xy 129.455772 -238.93831) (xy 129.432121 -238.983373)
			(xy 129.401548 -239.024059) (xy 129.364844 -239.059314) (xy 129.32296 -239.088224) (xy 129.276981 -239.110041)
			(xy 129.228097 -239.124201) (xy 129.177576 -239.130335) (xy 129.126724 -239.128286) (xy 129.07686 -239.118106)
			(xy 129.029274 -239.100059) (xy 128.9852 -239.074613) (xy 128.945778 -239.042426) (xy 128.91203 -239.004332)
			(xy 128.884829 -238.961318) (xy 128.864881 -238.914498) (xy 128.852702 -238.865084) (xy 128.848607 -238.814356)
			(xy 128.539851 -238.814356) (xy 128.539851 -238.839196) (xy 128.532093 -238.888176) (xy 128.516768 -238.93534)
			(xy 128.494253 -238.979526) (xy 128.465104 -239.019646) (xy 128.430037 -239.054712) (xy 128.389916 -239.08386)
			(xy 128.345729 -239.106372) (xy 128.298565 -239.121696) (xy 128.249584 -239.129452) (xy 128.224788 -239.129824)
			(xy 128.197812 -239.129296) (xy 128.144639 -239.120159) (xy 128.093799 -239.102102) (xy 128.046775 -239.075654)
			(xy 128.004941 -239.041585) (xy 127.98679 -239.02162) (xy 127.981334 -239.015874) (xy 127.96776 -239.007716)
			(xy 127.96012 -239.005618) (xy 127.955802 -239.004602) (xy 127.852678 -239.044734) (xy 127.843375 -239.048872)
			(xy 127.828805 -239.063071) (xy 127.820876 -239.081807) (xy 127.82042 -239.091978) (xy 127.82042 -239.2934)
			(xy 127.83947 -239.319816) (xy 127.854964 -239.32515) (xy 127.878169 -239.333408) (xy 127.921885 -239.356095)
			(xy 127.961545 -239.385299) (xy 127.996186 -239.42031) (xy 128.024966 -239.460279) (xy 128.047187 -239.504234)
			(xy 128.062308 -239.551108) (xy 128.069963 -239.599762) (xy 128.069964 -239.624362) (xy 128.388884 -239.624362)
			(xy 128.392844 -239.575308) (xy 128.404621 -239.527524) (xy 128.423912 -239.482248) (xy 128.450215 -239.440652)
			(xy 128.48285 -239.403815) (xy 128.520971 -239.37269) (xy 128.563592 -239.348083) (xy 128.609608 -239.330631)
			(xy 128.657827 -239.320787) (xy 128.707002 -239.318806) (xy 128.755857 -239.324738) (xy 128.803128 -239.33843)
			(xy 128.84759 -239.359528) (xy 128.888093 -239.387484) (xy 128.923586 -239.421576) (xy 128.953151 -239.46092)
			(xy 128.976022 -239.504497) (xy 128.991606 -239.551178) (xy 128.999501 -239.599755) (xy 128.999996 -239.624362)
			(xy 129.318507 -239.624362) (xy 129.322602 -239.573634) (xy 129.334781 -239.52422) (xy 129.354729 -239.4774)
			(xy 129.38193 -239.434386) (xy 129.415678 -239.396292) (xy 129.4551 -239.364105) (xy 129.499174 -239.338659)
			(xy 129.54676 -239.320612) (xy 129.596624 -239.310432) (xy 129.647476 -239.308383) (xy 129.697997 -239.314517)
			(xy 129.746881 -239.328677) (xy 129.79286 -239.350494) (xy 129.834744 -239.379404) (xy 129.871448 -239.414659)
			(xy 129.902021 -239.455345) (xy 129.925672 -239.500408) (xy 129.941788 -239.548682) (xy 129.949952 -239.598916)
			(xy 129.950464 -239.624362) (xy 131.198615 -239.624362) (xy 131.20271 -239.573634) (xy 131.214889 -239.52422)
			(xy 131.234837 -239.4774) (xy 131.262038 -239.434386) (xy 131.295786 -239.396292) (xy 131.335208 -239.364105)
			(xy 131.379282 -239.338659) (xy 131.426868 -239.320612) (xy 131.476732 -239.310432) (xy 131.527584 -239.308383)
			(xy 131.578105 -239.314517) (xy 131.626989 -239.328677) (xy 131.672968 -239.350494) (xy 131.714852 -239.379404)
			(xy 131.751556 -239.414659) (xy 131.782129 -239.455345) (xy 131.80578 -239.500408) (xy 131.821896 -239.548682)
			(xy 131.83006 -239.598916) (xy 131.830572 -239.624362) (xy 132.138415 -239.624362) (xy 132.14251 -239.573634)
			(xy 132.154689 -239.52422) (xy 132.174637 -239.4774) (xy 132.201838 -239.434386) (xy 132.235586 -239.396292)
			(xy 132.275008 -239.364105) (xy 132.319082 -239.338659) (xy 132.366668 -239.320612) (xy 132.416532 -239.310432)
			(xy 132.467384 -239.308383) (xy 132.517905 -239.314517) (xy 132.566789 -239.328677) (xy 132.612768 -239.350494)
			(xy 132.654652 -239.379404) (xy 132.691356 -239.414659) (xy 132.721929 -239.455345) (xy 132.74558 -239.500408)
			(xy 132.761696 -239.548682) (xy 132.76986 -239.598916) (xy 132.770372 -239.624362) (xy 132.76986 -239.649808)
			(xy 132.761696 -239.700042) (xy 132.74558 -239.748316) (xy 132.721929 -239.793379) (xy 132.691356 -239.834065)
			(xy 132.654652 -239.86932) (xy 132.612768 -239.89823) (xy 132.566789 -239.920047) (xy 132.517905 -239.934207)
			(xy 132.467384 -239.940341) (xy 132.416532 -239.938292) (xy 132.366668 -239.928112) (xy 132.319082 -239.910065)
			(xy 132.275008 -239.884619) (xy 132.235586 -239.852432) (xy 132.201838 -239.814338) (xy 132.174637 -239.771324)
			(xy 132.154689 -239.724504) (xy 132.14251 -239.67509) (xy 132.138415 -239.624362) (xy 131.830572 -239.624362)
			(xy 131.83006 -239.649808) (xy 131.821896 -239.700042) (xy 131.80578 -239.748316) (xy 131.782129 -239.793379)
			(xy 131.751556 -239.834065) (xy 131.714852 -239.86932) (xy 131.672968 -239.89823) (xy 131.626989 -239.920047)
			(xy 131.578105 -239.934207) (xy 131.527584 -239.940341) (xy 131.476732 -239.938292) (xy 131.426868 -239.928112)
			(xy 131.379282 -239.910065) (xy 131.335208 -239.884619) (xy 131.295786 -239.852432) (xy 131.262038 -239.814338)
			(xy 131.234837 -239.771324) (xy 131.214889 -239.724504) (xy 131.20271 -239.67509) (xy 131.198615 -239.624362)
			(xy 129.950464 -239.624362) (xy 129.949952 -239.649808) (xy 129.941788 -239.700042) (xy 129.925672 -239.748316)
			(xy 129.902021 -239.793379) (xy 129.871448 -239.834065) (xy 129.834744 -239.86932) (xy 129.79286 -239.89823)
			(xy 129.746881 -239.920047) (xy 129.697997 -239.934207) (xy 129.647476 -239.940341) (xy 129.596624 -239.938292)
			(xy 129.54676 -239.928112) (xy 129.499174 -239.910065) (xy 129.4551 -239.884619) (xy 129.415678 -239.852432)
			(xy 129.38193 -239.814338) (xy 129.354729 -239.771324) (xy 129.334781 -239.724504) (xy 129.322602 -239.67509)
			(xy 129.318507 -239.624362) (xy 128.999996 -239.624362) (xy 128.999501 -239.648969) (xy 128.991606 -239.697546)
			(xy 128.976022 -239.744227) (xy 128.953151 -239.787804) (xy 128.923586 -239.827148) (xy 128.888093 -239.86124)
			(xy 128.84759 -239.889196) (xy 128.803128 -239.910294) (xy 128.755857 -239.923986) (xy 128.707002 -239.929918)
			(xy 128.657827 -239.927937) (xy 128.609608 -239.918093) (xy 128.563592 -239.900641) (xy 128.520971 -239.876034)
			(xy 128.48285 -239.844909) (xy 128.450215 -239.808072) (xy 128.423912 -239.766476) (xy 128.404621 -239.7212)
			(xy 128.392844 -239.673416) (xy 128.388884 -239.624362) (xy 128.069964 -239.624362) (xy 128.069965 -239.649014)
			(xy 128.062314 -239.697669) (xy 128.047196 -239.744544) (xy 128.024979 -239.7885) (xy 127.996202 -239.828471)
			(xy 127.961564 -239.863485) (xy 127.921906 -239.892692) (xy 127.878191 -239.915383) (xy 127.854964 -239.923574)
			(xy 127.83947 -239.928908) (xy 127.82042 -239.955324) (xy 127.82042 -240.156746) (xy 127.820864 -240.166925)
			(xy 127.828769 -240.185684) (xy 127.843354 -240.199885) (xy 127.852678 -240.20399) (xy 127.94107 -240.23828)
			(xy 127.948273 -240.240874) (xy 127.96353 -240.242041) (xy 127.971042 -240.240566) (xy 127.976884 -240.239296)
			(xy 127.991929 -240.220877) (xy 128.026617 -240.188342) (xy 128.065795 -240.161383) (xy 128.108576 -240.140609)
			(xy 128.15399 -240.126493) (xy 128.201009 -240.119353) (xy 128.224788 -240.1189) (xy 128.249583 -240.11936)
			(xy 128.298562 -240.127116) (xy 128.345725 -240.142439) (xy 128.38991 -240.164951) (xy 128.430029 -240.194098)
			(xy 128.465095 -240.229162) (xy 128.494243 -240.26928) (xy 128.516757 -240.313464) (xy 128.532081 -240.360626)
			(xy 128.539839 -240.409605) (xy 128.539839 -240.434368) (xy 128.848607 -240.434368) (xy 128.852702 -240.38364)
			(xy 128.864881 -240.334226) (xy 128.884829 -240.287406) (xy 128.91203 -240.244392) (xy 128.945778 -240.206298)
			(xy 128.9852 -240.174111) (xy 129.029274 -240.148665) (xy 129.07686 -240.130618) (xy 129.126724 -240.120438)
			(xy 129.177576 -240.118389) (xy 129.228097 -240.124523) (xy 129.276981 -240.138683) (xy 129.32296 -240.1605)
			(xy 129.364844 -240.18941) (xy 129.401548 -240.224665) (xy 129.432121 -240.265351) (xy 129.455772 -240.310414)
			(xy 129.471888 -240.358688) (xy 129.480052 -240.408922) (xy 129.480564 -240.434368) (xy 129.798838 -240.434368)
			(xy 129.802798 -240.385314) (xy 129.814575 -240.33753) (xy 129.833866 -240.292254) (xy 129.860169 -240.250658)
			(xy 129.892804 -240.213821) (xy 129.930925 -240.182696) (xy 129.973546 -240.158089) (xy 130.019562 -240.140637)
			(xy 130.067781 -240.130793) (xy 130.116956 -240.128812) (xy 130.165811 -240.134744) (xy 130.213082 -240.148436)
			(xy 130.257544 -240.169534) (xy 130.298047 -240.19749) (xy 130.33354 -240.231582) (xy 130.363105 -240.270926)
			(xy 130.385976 -240.314503) (xy 130.40156 -240.361184) (xy 130.409455 -240.409761) (xy 130.40995 -240.434368)
			(xy 130.728461 -240.434368) (xy 130.732556 -240.38364) (xy 130.744735 -240.334226) (xy 130.764683 -240.287406)
			(xy 130.791884 -240.244392) (xy 130.825632 -240.206298) (xy 130.865054 -240.174111) (xy 130.909128 -240.148665)
			(xy 130.956714 -240.130618) (xy 131.006578 -240.120438) (xy 131.05743 -240.118389) (xy 131.107951 -240.124523)
			(xy 131.156835 -240.138683) (xy 131.202814 -240.1605) (xy 131.244698 -240.18941) (xy 131.281402 -240.224665)
			(xy 131.311975 -240.265351) (xy 131.335626 -240.310414) (xy 131.351742 -240.358688) (xy 131.359906 -240.408922)
			(xy 131.360418 -240.434368) (xy 131.678946 -240.434368) (xy 131.682906 -240.385314) (xy 131.694683 -240.33753)
			(xy 131.713974 -240.292254) (xy 131.740277 -240.250658) (xy 131.772912 -240.213821) (xy 131.811033 -240.182696)
			(xy 131.853654 -240.158089) (xy 131.89967 -240.140637) (xy 131.947889 -240.130793) (xy 131.997064 -240.128812)
			(xy 132.045919 -240.134744) (xy 132.09319 -240.148436) (xy 132.137652 -240.169534) (xy 132.178155 -240.19749)
			(xy 132.213648 -240.231582) (xy 132.243213 -240.270926) (xy 132.266084 -240.314503) (xy 132.281668 -240.361184)
			(xy 132.289563 -240.409761) (xy 132.290058 -240.434368) (xy 132.608569 -240.434368) (xy 132.612664 -240.38364)
			(xy 132.624843 -240.334226) (xy 132.644791 -240.287406) (xy 132.671992 -240.244392) (xy 132.70574 -240.206298)
			(xy 132.745162 -240.174111) (xy 132.789236 -240.148665) (xy 132.836822 -240.130618) (xy 132.886686 -240.120438)
			(xy 132.937538 -240.118389) (xy 132.988059 -240.124523) (xy 133.036943 -240.138683) (xy 133.082922 -240.1605)
			(xy 133.124806 -240.18941) (xy 133.16151 -240.224665) (xy 133.192083 -240.265351) (xy 133.215734 -240.310414)
			(xy 133.23185 -240.358688) (xy 133.240014 -240.408922) (xy 133.240526 -240.434368) (xy 133.240014 -240.459814)
			(xy 133.23185 -240.510048) (xy 133.215734 -240.558322) (xy 133.192083 -240.603385) (xy 133.16151 -240.644071)
			(xy 133.124806 -240.679326) (xy 133.082922 -240.708236) (xy 133.036943 -240.730053) (xy 132.988059 -240.744213)
			(xy 132.937538 -240.750347) (xy 132.886686 -240.748298) (xy 132.836822 -240.738118) (xy 132.789236 -240.720071)
			(xy 132.745162 -240.694625) (xy 132.70574 -240.662438) (xy 132.671992 -240.624344) (xy 132.644791 -240.58133)
			(xy 132.624843 -240.53451) (xy 132.612664 -240.485096) (xy 132.608569 -240.434368) (xy 132.290058 -240.434368)
			(xy 132.289563 -240.458975) (xy 132.281668 -240.507552) (xy 132.266084 -240.554233) (xy 132.243213 -240.59781)
			(xy 132.213648 -240.637154) (xy 132.178155 -240.671246) (xy 132.137652 -240.699202) (xy 132.09319 -240.7203)
			(xy 132.045919 -240.733992) (xy 131.997064 -240.739924) (xy 131.947889 -240.737943) (xy 131.89967 -240.728099)
			(xy 131.853654 -240.710647) (xy 131.811033 -240.68604) (xy 131.772912 -240.654915) (xy 131.740277 -240.618078)
			(xy 131.713974 -240.576482) (xy 131.694683 -240.531206) (xy 131.682906 -240.483422) (xy 131.678946 -240.434368)
			(xy 131.360418 -240.434368) (xy 131.359906 -240.459814) (xy 131.351742 -240.510048) (xy 131.335626 -240.558322)
			(xy 131.311975 -240.603385) (xy 131.281402 -240.644071) (xy 131.244698 -240.679326) (xy 131.202814 -240.708236)
			(xy 131.156835 -240.730053) (xy 131.107951 -240.744213) (xy 131.05743 -240.750347) (xy 131.006578 -240.748298)
			(xy 130.956714 -240.738118) (xy 130.909128 -240.720071) (xy 130.865054 -240.694625) (xy 130.825632 -240.662438)
			(xy 130.791884 -240.624344) (xy 130.764683 -240.58133) (xy 130.744735 -240.53451) (xy 130.732556 -240.485096)
			(xy 130.728461 -240.434368) (xy 130.40995 -240.434368) (xy 130.409455 -240.458975) (xy 130.40156 -240.507552)
			(xy 130.385976 -240.554233) (xy 130.363105 -240.59781) (xy 130.33354 -240.637154) (xy 130.298047 -240.671246)
			(xy 130.257544 -240.699202) (xy 130.213082 -240.7203) (xy 130.165811 -240.733992) (xy 130.116956 -240.739924)
			(xy 130.067781 -240.737943) (xy 130.019562 -240.728099) (xy 129.973546 -240.710647) (xy 129.930925 -240.68604)
			(xy 129.892804 -240.654915) (xy 129.860169 -240.618078) (xy 129.833866 -240.576482) (xy 129.814575 -240.531206)
			(xy 129.802798 -240.483422) (xy 129.798838 -240.434368) (xy 129.480564 -240.434368) (xy 129.480052 -240.459814)
			(xy 129.471888 -240.510048) (xy 129.455772 -240.558322) (xy 129.432121 -240.603385) (xy 129.401548 -240.644071)
			(xy 129.364844 -240.679326) (xy 129.32296 -240.708236) (xy 129.276981 -240.730053) (xy 129.228097 -240.744213)
			(xy 129.177576 -240.750347) (xy 129.126724 -240.748298) (xy 129.07686 -240.738118) (xy 129.029274 -240.720071)
			(xy 128.9852 -240.694625) (xy 128.945778 -240.662438) (xy 128.91203 -240.624344) (xy 128.884829 -240.58133)
			(xy 128.864881 -240.53451) (xy 128.852702 -240.485096) (xy 128.848607 -240.434368) (xy 128.539839 -240.434368)
			(xy 128.539839 -240.459195) (xy 128.532081 -240.508174) (xy 128.516757 -240.555336) (xy 128.494243 -240.59952)
			(xy 128.465095 -240.639638) (xy 128.430029 -240.674702) (xy 128.38991 -240.703849) (xy 128.345725 -240.726361)
			(xy 128.298562 -240.741684) (xy 128.249583 -240.74944) (xy 128.224788 -240.749836) (xy 128.197812 -240.749308)
			(xy 128.144639 -240.740171) (xy 128.093798 -240.722115) (xy 128.046773 -240.695667) (xy 128.004938 -240.661599)
			(xy 127.98679 -240.641632) (xy 127.981334 -240.635886) (xy 127.967761 -240.627726) (xy 127.96012 -240.62563)
			(xy 127.955802 -240.624614) (xy 127.852678 -240.664746) (xy 127.843376 -240.668884) (xy 127.82881 -240.683084)
			(xy 127.820885 -240.70182) (xy 127.82042 -240.71199) (xy 127.82042 -240.913412) (xy 127.83947 -240.939828)
			(xy 127.854964 -240.945162) (xy 127.878168 -240.95342) (xy 127.921882 -240.976107) (xy 127.961541 -241.00531)
			(xy 127.99618 -241.040321) (xy 128.024959 -241.080288) (xy 128.047178 -241.124242) (xy 128.062298 -241.171114)
			(xy 128.069952 -241.219766) (xy 128.069952 -241.244374) (xy 128.388884 -241.244374) (xy 128.392844 -241.19532)
			(xy 128.404621 -241.147536) (xy 128.423912 -241.10226) (xy 128.450215 -241.060664) (xy 128.48285 -241.023827)
			(xy 128.520971 -240.992702) (xy 128.563592 -240.968095) (xy 128.609608 -240.950643) (xy 128.657827 -240.940799)
			(xy 128.707002 -240.938818) (xy 128.755857 -240.94475) (xy 128.803128 -240.958442) (xy 128.84759 -240.97954)
			(xy 128.888093 -241.007496) (xy 128.923586 -241.041588) (xy 128.953151 -241.080932) (xy 128.976022 -241.124509)
			(xy 128.991606 -241.17119) (xy 128.999501 -241.219767) (xy 128.999996 -241.244374) (xy 129.318507 -241.244374)
			(xy 129.322602 -241.193646) (xy 129.334781 -241.144232) (xy 129.354729 -241.097412) (xy 129.38193 -241.054398)
			(xy 129.415678 -241.016304) (xy 129.4551 -240.984117) (xy 129.499174 -240.958671) (xy 129.54676 -240.940624)
			(xy 129.596624 -240.930444) (xy 129.647476 -240.928395) (xy 129.697997 -240.934529) (xy 129.746881 -240.948689)
			(xy 129.79286 -240.970506) (xy 129.834744 -240.999416) (xy 129.871448 -241.034671) (xy 129.902021 -241.075357)
			(xy 129.925672 -241.12042) (xy 129.941788 -241.168694) (xy 129.949952 -241.218928) (xy 129.950464 -241.244374)
			(xy 130.268992 -241.244374) (xy 130.272952 -241.19532) (xy 130.284729 -241.147536) (xy 130.30402 -241.10226)
			(xy 130.330323 -241.060664) (xy 130.362958 -241.023827) (xy 130.401079 -240.992702) (xy 130.4437 -240.968095)
			(xy 130.489716 -240.950643) (xy 130.537935 -240.940799) (xy 130.58711 -240.938818) (xy 130.635965 -240.94475)
			(xy 130.683236 -240.958442) (xy 130.727698 -240.97954) (xy 130.768201 -241.007496) (xy 130.803694 -241.041588)
			(xy 130.833259 -241.080932) (xy 130.85613 -241.124509) (xy 130.871714 -241.17119) (xy 130.879609 -241.219767)
			(xy 130.880104 -241.244374) (xy 131.198615 -241.244374) (xy 131.20271 -241.193646) (xy 131.214889 -241.144232)
			(xy 131.234837 -241.097412) (xy 131.262038 -241.054398) (xy 131.295786 -241.016304) (xy 131.335208 -240.984117)
			(xy 131.379282 -240.958671) (xy 131.426868 -240.940624) (xy 131.476732 -240.930444) (xy 131.527584 -240.928395)
			(xy 131.578105 -240.934529) (xy 131.626989 -240.948689) (xy 131.672968 -240.970506) (xy 131.714852 -240.999416)
			(xy 131.751556 -241.034671) (xy 131.782129 -241.075357) (xy 131.80578 -241.12042) (xy 131.821896 -241.168694)
			(xy 131.83006 -241.218928) (xy 131.830572 -241.244374) (xy 132.138415 -241.244374) (xy 132.14251 -241.193646)
			(xy 132.154689 -241.144232) (xy 132.174637 -241.097412) (xy 132.201838 -241.054398) (xy 132.235586 -241.016304)
			(xy 132.275008 -240.984117) (xy 132.319082 -240.958671) (xy 132.366668 -240.940624) (xy 132.416532 -240.930444)
			(xy 132.467384 -240.928395) (xy 132.517905 -240.934529) (xy 132.566789 -240.948689) (xy 132.612768 -240.970506)
			(xy 132.654652 -240.999416) (xy 132.691356 -241.034671) (xy 132.721929 -241.075357) (xy 132.74558 -241.12042)
			(xy 132.761696 -241.168694) (xy 132.76986 -241.218928) (xy 132.770372 -241.244374) (xy 132.76986 -241.26982)
			(xy 132.761696 -241.320054) (xy 132.74558 -241.368328) (xy 132.721929 -241.413391) (xy 132.691356 -241.454077)
			(xy 132.654652 -241.489332) (xy 132.612768 -241.518242) (xy 132.566789 -241.540059) (xy 132.517905 -241.554219)
			(xy 132.467384 -241.560353) (xy 132.416532 -241.558304) (xy 132.366668 -241.548124) (xy 132.319082 -241.530077)
			(xy 132.275008 -241.504631) (xy 132.235586 -241.472444) (xy 132.201838 -241.43435) (xy 132.174637 -241.391336)
			(xy 132.154689 -241.344516) (xy 132.14251 -241.295102) (xy 132.138415 -241.244374) (xy 131.830572 -241.244374)
			(xy 131.83006 -241.26982) (xy 131.821896 -241.320054) (xy 131.80578 -241.368328) (xy 131.782129 -241.413391)
			(xy 131.751556 -241.454077) (xy 131.714852 -241.489332) (xy 131.672968 -241.518242) (xy 131.626989 -241.540059)
			(xy 131.578105 -241.554219) (xy 131.527584 -241.560353) (xy 131.476732 -241.558304) (xy 131.426868 -241.548124)
			(xy 131.379282 -241.530077) (xy 131.335208 -241.504631) (xy 131.295786 -241.472444) (xy 131.262038 -241.43435)
			(xy 131.234837 -241.391336) (xy 131.214889 -241.344516) (xy 131.20271 -241.295102) (xy 131.198615 -241.244374)
			(xy 130.880104 -241.244374) (xy 130.879609 -241.268981) (xy 130.871714 -241.317558) (xy 130.85613 -241.364239)
			(xy 130.833259 -241.407816) (xy 130.803694 -241.44716) (xy 130.768201 -241.481252) (xy 130.727698 -241.509208)
			(xy 130.683236 -241.530306) (xy 130.635965 -241.543998) (xy 130.58711 -241.54993) (xy 130.537935 -241.547949)
			(xy 130.489716 -241.538105) (xy 130.4437 -241.520653) (xy 130.401079 -241.496046) (xy 130.362958 -241.464921)
			(xy 130.330323 -241.428084) (xy 130.30402 -241.386488) (xy 130.284729 -241.341212) (xy 130.272952 -241.293428)
			(xy 130.268992 -241.244374) (xy 129.950464 -241.244374) (xy 129.949952 -241.26982) (xy 129.941788 -241.320054)
			(xy 129.925672 -241.368328) (xy 129.902021 -241.413391) (xy 129.871448 -241.454077) (xy 129.834744 -241.489332)
			(xy 129.79286 -241.518242) (xy 129.746881 -241.540059) (xy 129.697997 -241.554219) (xy 129.647476 -241.560353)
			(xy 129.596624 -241.558304) (xy 129.54676 -241.548124) (xy 129.499174 -241.530077) (xy 129.4551 -241.504631)
			(xy 129.415678 -241.472444) (xy 129.38193 -241.43435) (xy 129.354729 -241.391336) (xy 129.334781 -241.344516)
			(xy 129.322602 -241.295102) (xy 129.318507 -241.244374) (xy 128.999996 -241.244374) (xy 128.999501 -241.268981)
			(xy 128.991606 -241.317558) (xy 128.976022 -241.364239) (xy 128.953151 -241.407816) (xy 128.923586 -241.44716)
			(xy 128.888093 -241.481252) (xy 128.84759 -241.509208) (xy 128.803128 -241.530306) (xy 128.755857 -241.543998)
			(xy 128.707002 -241.54993) (xy 128.657827 -241.547949) (xy 128.609608 -241.538105) (xy 128.563592 -241.520653)
			(xy 128.520971 -241.496046) (xy 128.48285 -241.464921) (xy 128.450215 -241.428084) (xy 128.423912 -241.386488)
			(xy 128.404621 -241.341212) (xy 128.392844 -241.293428) (xy 128.388884 -241.244374) (xy 128.069952 -241.244374)
			(xy 128.069953 -241.269017) (xy 128.062302 -241.31767) (xy 128.047184 -241.364543) (xy 128.024967 -241.408498)
			(xy 127.996191 -241.448467) (xy 127.961553 -241.483479) (xy 127.921896 -241.512684) (xy 127.878183 -241.535374)
			(xy 127.854964 -241.543586) (xy 127.83947 -241.54892) (xy 127.82042 -241.575336) (xy 127.82042 -241.776758)
			(xy 127.820866 -241.786935) (xy 127.828774 -241.805691) (xy 127.843359 -241.819888) (xy 127.852678 -241.824002)
			(xy 127.94107 -241.858292) (xy 127.948273 -241.860885) (xy 127.96353 -241.862052) (xy 127.971042 -241.860578)
			(xy 127.976884 -241.859308) (xy 127.991929 -241.840888) (xy 128.026616 -241.808353) (xy 128.065794 -241.781392)
			(xy 128.108575 -241.760618) (xy 128.15399 -241.7465) (xy 128.201009 -241.73936) (xy 128.224788 -241.738912)
			(xy 128.249582 -241.739372) (xy 128.298559 -241.747128) (xy 128.34572 -241.76245) (xy 128.389903 -241.784961)
			(xy 128.430021 -241.814107) (xy 128.465086 -241.84917) (xy 128.494233 -241.889286) (xy 128.516746 -241.933469)
			(xy 128.532069 -241.980629) (xy 128.539827 -242.029606) (xy 128.539827 -242.05438) (xy 128.848607 -242.05438)
			(xy 128.852702 -242.003652) (xy 128.864881 -241.954238) (xy 128.884829 -241.907418) (xy 128.91203 -241.864404)
			(xy 128.945778 -241.82631) (xy 128.9852 -241.794123) (xy 129.029274 -241.768677) (xy 129.07686 -241.75063)
			(xy 129.126724 -241.74045) (xy 129.177576 -241.738401) (xy 129.228097 -241.744535) (xy 129.276981 -241.758695)
			(xy 129.32296 -241.780512) (xy 129.364844 -241.809422) (xy 129.401548 -241.844677) (xy 129.432121 -241.885363)
			(xy 129.455772 -241.930426) (xy 129.471888 -241.9787) (xy 129.480052 -242.028934) (xy 129.480564 -242.05438)
			(xy 130.728461 -242.05438) (xy 130.732556 -242.003652) (xy 130.744735 -241.954238) (xy 130.764683 -241.907418)
			(xy 130.791884 -241.864404) (xy 130.825632 -241.82631) (xy 130.865054 -241.794123) (xy 130.909128 -241.768677)
			(xy 130.956714 -241.75063) (xy 131.006578 -241.74045) (xy 131.05743 -241.738401) (xy 131.107951 -241.744535)
			(xy 131.156835 -241.758695) (xy 131.202814 -241.780512) (xy 131.244698 -241.809422) (xy 131.281402 -241.844677)
			(xy 131.311975 -241.885363) (xy 131.335626 -241.930426) (xy 131.351742 -241.9787) (xy 131.359906 -242.028934)
			(xy 131.360418 -242.05438) (xy 131.678946 -242.05438) (xy 131.682906 -242.005326) (xy 131.694683 -241.957542)
			(xy 131.713974 -241.912266) (xy 131.740277 -241.87067) (xy 131.772912 -241.833833) (xy 131.811033 -241.802708)
			(xy 131.853654 -241.778101) (xy 131.89967 -241.760649) (xy 131.947889 -241.750805) (xy 131.997064 -241.748824)
			(xy 132.045919 -241.754756) (xy 132.09319 -241.768448) (xy 132.137652 -241.789546) (xy 132.178155 -241.817502)
			(xy 132.213648 -241.851594) (xy 132.243213 -241.890938) (xy 132.266084 -241.934515) (xy 132.281668 -241.981196)
			(xy 132.289563 -242.029773) (xy 132.290058 -242.05438) (xy 132.608569 -242.05438) (xy 132.612664 -242.003652)
			(xy 132.624843 -241.954238) (xy 132.644791 -241.907418) (xy 132.671992 -241.864404) (xy 132.70574 -241.82631)
			(xy 132.745162 -241.794123) (xy 132.789236 -241.768677) (xy 132.836822 -241.75063) (xy 132.886686 -241.74045)
			(xy 132.937538 -241.738401) (xy 132.988059 -241.744535) (xy 133.036943 -241.758695) (xy 133.082922 -241.780512)
			(xy 133.124806 -241.809422) (xy 133.16151 -241.844677) (xy 133.192083 -241.885363) (xy 133.215734 -241.930426)
			(xy 133.23185 -241.9787) (xy 133.240014 -242.028934) (xy 133.240526 -242.05438) (xy 133.240014 -242.079826)
			(xy 133.23185 -242.13006) (xy 133.215734 -242.178334) (xy 133.192083 -242.223397) (xy 133.16151 -242.264083)
			(xy 133.124806 -242.299338) (xy 133.082922 -242.328248) (xy 133.036943 -242.350065) (xy 132.988059 -242.364225)
			(xy 132.937538 -242.370359) (xy 132.886686 -242.36831) (xy 132.836822 -242.35813) (xy 132.789236 -242.340083)
			(xy 132.745162 -242.314637) (xy 132.70574 -242.28245) (xy 132.671992 -242.244356) (xy 132.644791 -242.201342)
			(xy 132.624843 -242.154522) (xy 132.612664 -242.105108) (xy 132.608569 -242.05438) (xy 132.290058 -242.05438)
			(xy 132.289563 -242.078987) (xy 132.281668 -242.127564) (xy 132.266084 -242.174245) (xy 132.243213 -242.217822)
			(xy 132.213648 -242.257166) (xy 132.178155 -242.291258) (xy 132.137652 -242.319214) (xy 132.09319 -242.340312)
			(xy 132.045919 -242.354004) (xy 131.997064 -242.359936) (xy 131.947889 -242.357955) (xy 131.89967 -242.348111)
			(xy 131.853654 -242.330659) (xy 131.811033 -242.306052) (xy 131.772912 -242.274927) (xy 131.740277 -242.23809)
			(xy 131.713974 -242.196494) (xy 131.694683 -242.151218) (xy 131.682906 -242.103434) (xy 131.678946 -242.05438)
			(xy 131.360418 -242.05438) (xy 131.359906 -242.079826) (xy 131.351742 -242.13006) (xy 131.335626 -242.178334)
			(xy 131.311975 -242.223397) (xy 131.281402 -242.264083) (xy 131.244698 -242.299338) (xy 131.202814 -242.328248)
			(xy 131.156835 -242.350065) (xy 131.107951 -242.364225) (xy 131.05743 -242.370359) (xy 131.006578 -242.36831)
			(xy 130.956714 -242.35813) (xy 130.909128 -242.340083) (xy 130.865054 -242.314637) (xy 130.825632 -242.28245)
			(xy 130.791884 -242.244356) (xy 130.764683 -242.201342) (xy 130.744735 -242.154522) (xy 130.732556 -242.105108)
			(xy 130.728461 -242.05438) (xy 129.480564 -242.05438) (xy 129.480052 -242.079826) (xy 129.471888 -242.13006)
			(xy 129.455772 -242.178334) (xy 129.432121 -242.223397) (xy 129.401548 -242.264083) (xy 129.364844 -242.299338)
			(xy 129.32296 -242.328248) (xy 129.276981 -242.350065) (xy 129.228097 -242.364225) (xy 129.177576 -242.370359)
			(xy 129.126724 -242.36831) (xy 129.07686 -242.35813) (xy 129.029274 -242.340083) (xy 128.9852 -242.314637)
			(xy 128.945778 -242.28245) (xy 128.91203 -242.244356) (xy 128.884829 -242.201342) (xy 128.864881 -242.154522)
			(xy 128.852702 -242.105108) (xy 128.848607 -242.05438) (xy 128.539827 -242.05438) (xy 128.539827 -242.079194)
			(xy 128.532069 -242.128171) (xy 128.516746 -242.175331) (xy 128.494233 -242.219514) (xy 128.465086 -242.25963)
			(xy 128.430021 -242.294693) (xy 128.389903 -242.323839) (xy 128.34572 -242.34635) (xy 128.298559 -242.361672)
			(xy 128.249582 -242.369428) (xy 128.224788 -242.369848) (xy 128.19903 -242.369344) (xy 128.148196 -242.360991)
			(xy 128.099394 -242.34449) (xy 128.05392 -242.320282) (xy 128.012983 -242.289008) (xy 127.97767 -242.2515)
			(xy 127.948918 -242.208754) (xy 127.927491 -242.161906) (xy 127.920242 -242.137184) (xy 127.91567 -242.12042)
			(xy 127.888492 -242.099592) (xy 127.87122 -242.099592) (xy 127.861195 -242.100008) (xy 127.84267 -242.107674)
			(xy 127.82849 -242.121847) (xy 127.820814 -242.140368) (xy 127.82042 -242.150392) (xy 127.82042 -242.165378)
			(xy 127.819983 -242.175442) (xy 127.812251 -242.194028) (xy 127.805434 -242.201446) (xy 127.142494 -242.864386)
			(xy 127.438399 -242.864386) (xy 127.442494 -242.813658) (xy 127.454673 -242.764244) (xy 127.474621 -242.717424)
			(xy 127.501822 -242.67441) (xy 127.53557 -242.636316) (xy 127.574992 -242.604129) (xy 127.619066 -242.578683)
			(xy 127.666652 -242.560636) (xy 127.716516 -242.550456) (xy 127.767368 -242.548407) (xy 127.817889 -242.554541)
			(xy 127.866773 -242.568701) (xy 127.912752 -242.590518) (xy 127.954636 -242.619428) (xy 127.99134 -242.654683)
			(xy 128.021913 -242.695369) (xy 128.045564 -242.740432) (xy 128.06168 -242.788706) (xy 128.069844 -242.83894)
			(xy 128.070356 -242.864386) (xy 128.388884 -242.864386) (xy 128.392844 -242.815332) (xy 128.404621 -242.767548)
			(xy 128.423912 -242.722272) (xy 128.450215 -242.680676) (xy 128.48285 -242.643839) (xy 128.520971 -242.612714)
			(xy 128.563592 -242.588107) (xy 128.609608 -242.570655) (xy 128.657827 -242.560811) (xy 128.707002 -242.55883)
			(xy 128.755857 -242.564762) (xy 128.803128 -242.578454) (xy 128.84759 -242.599552) (xy 128.888093 -242.627508)
			(xy 128.923586 -242.6616) (xy 128.953151 -242.700944) (xy 128.976022 -242.744521) (xy 128.991606 -242.791202)
			(xy 128.999501 -242.839779) (xy 128.999996 -242.864386) (xy 129.318507 -242.864386) (xy 129.322602 -242.813658)
			(xy 129.334781 -242.764244) (xy 129.354729 -242.717424) (xy 129.38193 -242.67441) (xy 129.415678 -242.636316)
			(xy 129.4551 -242.604129) (xy 129.499174 -242.578683) (xy 129.54676 -242.560636) (xy 129.596624 -242.550456)
			(xy 129.647476 -242.548407) (xy 129.697997 -242.554541) (xy 129.746881 -242.568701) (xy 129.79286 -242.590518)
			(xy 129.834744 -242.619428) (xy 129.871448 -242.654683) (xy 129.902021 -242.695369) (xy 129.925672 -242.740432)
			(xy 129.941788 -242.788706) (xy 129.949952 -242.83894) (xy 129.950464 -242.864386) (xy 130.268992 -242.864386)
			(xy 130.272952 -242.815332) (xy 130.284729 -242.767548) (xy 130.30402 -242.722272) (xy 130.330323 -242.680676)
			(xy 130.362958 -242.643839) (xy 130.401079 -242.612714) (xy 130.4437 -242.588107) (xy 130.489716 -242.570655)
			(xy 130.537935 -242.560811) (xy 130.58711 -242.55883) (xy 130.635965 -242.564762) (xy 130.683236 -242.578454)
			(xy 130.727698 -242.599552) (xy 130.768201 -242.627508) (xy 130.803694 -242.6616) (xy 130.833259 -242.700944)
			(xy 130.85613 -242.744521) (xy 130.871714 -242.791202) (xy 130.879609 -242.839779) (xy 130.880104 -242.864386)
			(xy 131.198615 -242.864386) (xy 131.20271 -242.813658) (xy 131.214889 -242.764244) (xy 131.234837 -242.717424)
			(xy 131.262038 -242.67441) (xy 131.295786 -242.636316) (xy 131.335208 -242.604129) (xy 131.379282 -242.578683)
			(xy 131.426868 -242.560636) (xy 131.476732 -242.550456) (xy 131.527584 -242.548407) (xy 131.578105 -242.554541)
			(xy 131.626989 -242.568701) (xy 131.672968 -242.590518) (xy 131.714852 -242.619428) (xy 131.751556 -242.654683)
			(xy 131.782129 -242.695369) (xy 131.80578 -242.740432) (xy 131.821896 -242.788706) (xy 131.83006 -242.83894)
			(xy 131.830572 -242.864386) (xy 132.138415 -242.864386) (xy 132.14251 -242.813658) (xy 132.154689 -242.764244)
			(xy 132.174637 -242.717424) (xy 132.201838 -242.67441) (xy 132.235586 -242.636316) (xy 132.275008 -242.604129)
			(xy 132.319082 -242.578683) (xy 132.366668 -242.560636) (xy 132.416532 -242.550456) (xy 132.467384 -242.548407)
			(xy 132.517905 -242.554541) (xy 132.566789 -242.568701) (xy 132.612768 -242.590518) (xy 132.654652 -242.619428)
			(xy 132.691356 -242.654683) (xy 132.721929 -242.695369) (xy 132.74558 -242.740432) (xy 132.761696 -242.788706)
			(xy 132.76986 -242.83894) (xy 132.770372 -242.864386) (xy 132.76986 -242.889832) (xy 132.761696 -242.940066)
			(xy 132.74558 -242.98834) (xy 132.721929 -243.033403) (xy 132.691356 -243.074089) (xy 132.654652 -243.109344)
			(xy 132.612768 -243.138254) (xy 132.566789 -243.160071) (xy 132.517905 -243.174231) (xy 132.467384 -243.180365)
			(xy 132.416532 -243.178316) (xy 132.366668 -243.168136) (xy 132.319082 -243.150089) (xy 132.275008 -243.124643)
			(xy 132.235586 -243.092456) (xy 132.201838 -243.054362) (xy 132.174637 -243.011348) (xy 132.154689 -242.964528)
			(xy 132.14251 -242.915114) (xy 132.138415 -242.864386) (xy 131.830572 -242.864386) (xy 131.83006 -242.889832)
			(xy 131.821896 -242.940066) (xy 131.80578 -242.98834) (xy 131.782129 -243.033403) (xy 131.751556 -243.074089)
			(xy 131.714852 -243.109344) (xy 131.672968 -243.138254) (xy 131.626989 -243.160071) (xy 131.578105 -243.174231)
			(xy 131.527584 -243.180365) (xy 131.476732 -243.178316) (xy 131.426868 -243.168136) (xy 131.379282 -243.150089)
			(xy 131.335208 -243.124643) (xy 131.295786 -243.092456) (xy 131.262038 -243.054362) (xy 131.234837 -243.011348)
			(xy 131.214889 -242.964528) (xy 131.20271 -242.915114) (xy 131.198615 -242.864386) (xy 130.880104 -242.864386)
			(xy 130.879609 -242.888993) (xy 130.871714 -242.93757) (xy 130.85613 -242.984251) (xy 130.833259 -243.027828)
			(xy 130.803694 -243.067172) (xy 130.768201 -243.101264) (xy 130.727698 -243.12922) (xy 130.683236 -243.150318)
			(xy 130.635965 -243.16401) (xy 130.58711 -243.169942) (xy 130.537935 -243.167961) (xy 130.489716 -243.158117)
			(xy 130.4437 -243.140665) (xy 130.401079 -243.116058) (xy 130.362958 -243.084933) (xy 130.330323 -243.048096)
			(xy 130.30402 -243.0065) (xy 130.284729 -242.961224) (xy 130.272952 -242.91344) (xy 130.268992 -242.864386)
			(xy 129.950464 -242.864386) (xy 129.949952 -242.889832) (xy 129.941788 -242.940066) (xy 129.925672 -242.98834)
			(xy 129.902021 -243.033403) (xy 129.871448 -243.074089) (xy 129.834744 -243.109344) (xy 129.79286 -243.138254)
			(xy 129.746881 -243.160071) (xy 129.697997 -243.174231) (xy 129.647476 -243.180365) (xy 129.596624 -243.178316)
			(xy 129.54676 -243.168136) (xy 129.499174 -243.150089) (xy 129.4551 -243.124643) (xy 129.415678 -243.092456)
			(xy 129.38193 -243.054362) (xy 129.354729 -243.011348) (xy 129.334781 -242.964528) (xy 129.322602 -242.915114)
			(xy 129.318507 -242.864386) (xy 128.999996 -242.864386) (xy 128.999501 -242.888993) (xy 128.991606 -242.93757)
			(xy 128.976022 -242.984251) (xy 128.953151 -243.027828) (xy 128.923586 -243.067172) (xy 128.888093 -243.101264)
			(xy 128.84759 -243.12922) (xy 128.803128 -243.150318) (xy 128.755857 -243.16401) (xy 128.707002 -243.169942)
			(xy 128.657827 -243.167961) (xy 128.609608 -243.158117) (xy 128.563592 -243.140665) (xy 128.520971 -243.116058)
			(xy 128.48285 -243.084933) (xy 128.450215 -243.048096) (xy 128.423912 -243.0065) (xy 128.404621 -242.961224)
			(xy 128.392844 -242.91344) (xy 128.388884 -242.864386) (xy 128.070356 -242.864386) (xy 128.069844 -242.889832)
			(xy 128.06168 -242.940066) (xy 128.045564 -242.98834) (xy 128.021913 -243.033403) (xy 127.99134 -243.074089)
			(xy 127.954636 -243.109344) (xy 127.912752 -243.138254) (xy 127.866773 -243.160071) (xy 127.817889 -243.174231)
			(xy 127.767368 -243.180365) (xy 127.716516 -243.178316) (xy 127.666652 -243.168136) (xy 127.619066 -243.150089)
			(xy 127.574992 -243.124643) (xy 127.53557 -243.092456) (xy 127.501822 -243.054362) (xy 127.474621 -243.011348)
			(xy 127.454673 -242.964528) (xy 127.442494 -242.915114) (xy 127.438399 -242.864386) (xy 127.142494 -242.864386)
			(xy 127.125984 -242.880896) (xy 127.118618 -242.895628) (xy 127.117602 -242.904264) (xy 127.11426 -242.926454)
			(xy 127.101915 -242.969595) (xy 127.083391 -243.010466) (xy 127.059087 -243.048188) (xy 127.029525 -243.081947)
			(xy 127.0127 -243.096796) (xy 127.004675 -243.104368) (xy 126.995454 -243.124384) (xy 126.99492 -243.135404)
			(xy 126.99492 -243.674392) (xy 127.908553 -243.674392) (xy 127.912648 -243.623664) (xy 127.924827 -243.57425)
			(xy 127.944775 -243.52743) (xy 127.971976 -243.484416) (xy 128.005724 -243.446322) (xy 128.045146 -243.414135)
			(xy 128.08922 -243.388689) (xy 128.136806 -243.370642) (xy 128.18667 -243.360462) (xy 128.237522 -243.358413)
			(xy 128.288043 -243.364547) (xy 128.336927 -243.378707) (xy 128.382906 -243.400524) (xy 128.42479 -243.429434)
			(xy 128.461494 -243.464689) (xy 128.492067 -243.505375) (xy 128.515718 -243.550438) (xy 128.531834 -243.598712)
			(xy 128.539998 -243.648946) (xy 128.54051 -243.674392) (xy 128.848607 -243.674392) (xy 128.852702 -243.623664)
			(xy 128.864881 -243.57425) (xy 128.884829 -243.52743) (xy 128.91203 -243.484416) (xy 128.945778 -243.446322)
			(xy 128.9852 -243.414135) (xy 129.029274 -243.388689) (xy 129.07686 -243.370642) (xy 129.126724 -243.360462)
			(xy 129.177576 -243.358413) (xy 129.228097 -243.364547) (xy 129.276981 -243.378707) (xy 129.32296 -243.400524)
			(xy 129.364844 -243.429434) (xy 129.401548 -243.464689) (xy 129.432121 -243.505375) (xy 129.455772 -243.550438)
			(xy 129.471888 -243.598712) (xy 129.480052 -243.648946) (xy 129.480564 -243.674392) (xy 129.798838 -243.674392)
			(xy 129.802798 -243.625338) (xy 129.814575 -243.577554) (xy 129.833866 -243.532278) (xy 129.860169 -243.490682)
			(xy 129.892804 -243.453845) (xy 129.930925 -243.42272) (xy 129.973546 -243.398113) (xy 130.019562 -243.380661)
			(xy 130.067781 -243.370817) (xy 130.116956 -243.368836) (xy 130.165811 -243.374768) (xy 130.213082 -243.38846)
			(xy 130.257544 -243.409558) (xy 130.298047 -243.437514) (xy 130.33354 -243.471606) (xy 130.363105 -243.51095)
			(xy 130.385976 -243.554527) (xy 130.40156 -243.601208) (xy 130.409455 -243.649785) (xy 130.40995 -243.674392)
			(xy 130.728461 -243.674392) (xy 130.732556 -243.623664) (xy 130.744735 -243.57425) (xy 130.764683 -243.52743)
			(xy 130.791884 -243.484416) (xy 130.825632 -243.446322) (xy 130.865054 -243.414135) (xy 130.909128 -243.388689)
			(xy 130.956714 -243.370642) (xy 131.006578 -243.360462) (xy 131.05743 -243.358413) (xy 131.107951 -243.364547)
			(xy 131.156835 -243.378707) (xy 131.202814 -243.400524) (xy 131.244698 -243.429434) (xy 131.281402 -243.464689)
			(xy 131.311975 -243.505375) (xy 131.335626 -243.550438) (xy 131.351742 -243.598712) (xy 131.359906 -243.648946)
			(xy 131.360418 -243.674392) (xy 131.678946 -243.674392) (xy 131.682906 -243.625338) (xy 131.694683 -243.577554)
			(xy 131.713974 -243.532278) (xy 131.740277 -243.490682) (xy 131.772912 -243.453845) (xy 131.811033 -243.42272)
			(xy 131.853654 -243.398113) (xy 131.89967 -243.380661) (xy 131.947889 -243.370817) (xy 131.997064 -243.368836)
			(xy 132.045919 -243.374768) (xy 132.09319 -243.38846) (xy 132.137652 -243.409558) (xy 132.178155 -243.437514)
			(xy 132.213648 -243.471606) (xy 132.243213 -243.51095) (xy 132.266084 -243.554527) (xy 132.281668 -243.601208)
			(xy 132.289563 -243.649785) (xy 132.290058 -243.674392) (xy 132.608569 -243.674392) (xy 132.612664 -243.623664)
			(xy 132.624843 -243.57425) (xy 132.644791 -243.52743) (xy 132.671992 -243.484416) (xy 132.70574 -243.446322)
			(xy 132.745162 -243.414135) (xy 132.789236 -243.388689) (xy 132.836822 -243.370642) (xy 132.886686 -243.360462)
			(xy 132.937538 -243.358413) (xy 132.988059 -243.364547) (xy 133.036943 -243.378707) (xy 133.082922 -243.400524)
			(xy 133.124806 -243.429434) (xy 133.16151 -243.464689) (xy 133.192083 -243.505375) (xy 133.215734 -243.550438)
			(xy 133.23185 -243.598712) (xy 133.240014 -243.648946) (xy 133.240526 -243.674392) (xy 133.240014 -243.699838)
			(xy 133.23185 -243.750072) (xy 133.215734 -243.798346) (xy 133.192083 -243.843409) (xy 133.16151 -243.884095)
			(xy 133.124806 -243.91935) (xy 133.082922 -243.94826) (xy 133.036943 -243.970077) (xy 132.988059 -243.984237)
			(xy 132.937538 -243.990371) (xy 132.886686 -243.988322) (xy 132.836822 -243.978142) (xy 132.789236 -243.960095)
			(xy 132.745162 -243.934649) (xy 132.70574 -243.902462) (xy 132.671992 -243.864368) (xy 132.644791 -243.821354)
			(xy 132.624843 -243.774534) (xy 132.612664 -243.72512) (xy 132.608569 -243.674392) (xy 132.290058 -243.674392)
			(xy 132.289563 -243.698999) (xy 132.281668 -243.747576) (xy 132.266084 -243.794257) (xy 132.243213 -243.837834)
			(xy 132.213648 -243.877178) (xy 132.178155 -243.91127) (xy 132.137652 -243.939226) (xy 132.09319 -243.960324)
			(xy 132.045919 -243.974016) (xy 131.997064 -243.979948) (xy 131.947889 -243.977967) (xy 131.89967 -243.968123)
			(xy 131.853654 -243.950671) (xy 131.811033 -243.926064) (xy 131.772912 -243.894939) (xy 131.740277 -243.858102)
			(xy 131.713974 -243.816506) (xy 131.694683 -243.77123) (xy 131.682906 -243.723446) (xy 131.678946 -243.674392)
			(xy 131.360418 -243.674392) (xy 131.359906 -243.699838) (xy 131.351742 -243.750072) (xy 131.335626 -243.798346)
			(xy 131.311975 -243.843409) (xy 131.281402 -243.884095) (xy 131.244698 -243.91935) (xy 131.202814 -243.94826)
			(xy 131.156835 -243.970077) (xy 131.107951 -243.984237) (xy 131.05743 -243.990371) (xy 131.006578 -243.988322)
			(xy 130.956714 -243.978142) (xy 130.909128 -243.960095) (xy 130.865054 -243.934649) (xy 130.825632 -243.902462)
			(xy 130.791884 -243.864368) (xy 130.764683 -243.821354) (xy 130.744735 -243.774534) (xy 130.732556 -243.72512)
			(xy 130.728461 -243.674392) (xy 130.40995 -243.674392) (xy 130.409455 -243.698999) (xy 130.40156 -243.747576)
			(xy 130.385976 -243.794257) (xy 130.363105 -243.837834) (xy 130.33354 -243.877178) (xy 130.298047 -243.91127)
			(xy 130.257544 -243.939226) (xy 130.213082 -243.960324) (xy 130.165811 -243.974016) (xy 130.116956 -243.979948)
			(xy 130.067781 -243.977967) (xy 130.019562 -243.968123) (xy 129.973546 -243.950671) (xy 129.930925 -243.926064)
			(xy 129.892804 -243.894939) (xy 129.860169 -243.858102) (xy 129.833866 -243.816506) (xy 129.814575 -243.77123)
			(xy 129.802798 -243.723446) (xy 129.798838 -243.674392) (xy 129.480564 -243.674392) (xy 129.480052 -243.699838)
			(xy 129.471888 -243.750072) (xy 129.455772 -243.798346) (xy 129.432121 -243.843409) (xy 129.401548 -243.884095)
			(xy 129.364844 -243.91935) (xy 129.32296 -243.94826) (xy 129.276981 -243.970077) (xy 129.228097 -243.984237)
			(xy 129.177576 -243.990371) (xy 129.126724 -243.988322) (xy 129.07686 -243.978142) (xy 129.029274 -243.960095)
			(xy 128.9852 -243.934649) (xy 128.945778 -243.902462) (xy 128.91203 -243.864368) (xy 128.884829 -243.821354)
			(xy 128.864881 -243.774534) (xy 128.852702 -243.72512) (xy 128.848607 -243.674392) (xy 128.54051 -243.674392)
			(xy 128.539998 -243.699838) (xy 128.531834 -243.750072) (xy 128.515718 -243.798346) (xy 128.492067 -243.843409)
			(xy 128.461494 -243.884095) (xy 128.42479 -243.91935) (xy 128.382906 -243.94826) (xy 128.336927 -243.970077)
			(xy 128.288043 -243.984237) (xy 128.237522 -243.990371) (xy 128.18667 -243.988322) (xy 128.136806 -243.978142)
			(xy 128.08922 -243.960095) (xy 128.045146 -243.934649) (xy 128.005724 -243.902462) (xy 127.971976 -243.864368)
			(xy 127.944775 -243.821354) (xy 127.924827 -243.774534) (xy 127.912648 -243.72512) (xy 127.908553 -243.674392)
			(xy 126.99492 -243.674392) (xy 126.99492 -244.21338) (xy 126.995457 -244.2244) (xy 127.004673 -244.244419)
			(xy 127.0127 -244.251988) (xy 127.03072 -244.2679) (xy 127.062006 -244.304396) (xy 127.087182 -244.345348)
			(xy 127.105623 -244.389741) (xy 127.116874 -244.436477) (xy 127.120655 -244.484398) (xy 127.438399 -244.484398)
			(xy 127.442494 -244.43367) (xy 127.454673 -244.384256) (xy 127.474621 -244.337436) (xy 127.501822 -244.294422)
			(xy 127.53557 -244.256328) (xy 127.574992 -244.224141) (xy 127.619066 -244.198695) (xy 127.666652 -244.180648)
			(xy 127.716516 -244.170468) (xy 127.767368 -244.168419) (xy 127.817889 -244.174553) (xy 127.866773 -244.188713)
			(xy 127.912752 -244.21053) (xy 127.954636 -244.23944) (xy 127.99134 -244.274695) (xy 128.021913 -244.315381)
			(xy 128.045564 -244.360444) (xy 128.06168 -244.408718) (xy 128.069844 -244.458952) (xy 128.070356 -244.484398)
			(xy 128.388884 -244.484398) (xy 128.392844 -244.435344) (xy 128.404621 -244.38756) (xy 128.423912 -244.342284)
			(xy 128.450215 -244.300688) (xy 128.48285 -244.263851) (xy 128.520971 -244.232726) (xy 128.563592 -244.208119)
			(xy 128.609608 -244.190667) (xy 128.657827 -244.180823) (xy 128.707002 -244.178842) (xy 128.755857 -244.184774)
			(xy 128.803128 -244.198466) (xy 128.84759 -244.219564) (xy 128.888093 -244.24752) (xy 128.923586 -244.281612)
			(xy 128.953151 -244.320956) (xy 128.976022 -244.364533) (xy 128.991606 -244.411214) (xy 128.999501 -244.459791)
			(xy 128.999996 -244.484398) (xy 129.318507 -244.484398) (xy 129.322602 -244.43367) (xy 129.334781 -244.384256)
			(xy 129.354729 -244.337436) (xy 129.38193 -244.294422) (xy 129.415678 -244.256328) (xy 129.4551 -244.224141)
			(xy 129.499174 -244.198695) (xy 129.54676 -244.180648) (xy 129.596624 -244.170468) (xy 129.647476 -244.168419)
			(xy 129.697997 -244.174553) (xy 129.746881 -244.188713) (xy 129.79286 -244.21053) (xy 129.834744 -244.23944)
			(xy 129.871448 -244.274695) (xy 129.902021 -244.315381) (xy 129.925672 -244.360444) (xy 129.941788 -244.408718)
			(xy 129.949952 -244.458952) (xy 129.950464 -244.484398) (xy 131.198615 -244.484398) (xy 131.20271 -244.43367)
			(xy 131.214889 -244.384256) (xy 131.234837 -244.337436) (xy 131.262038 -244.294422) (xy 131.295786 -244.256328)
			(xy 131.335208 -244.224141) (xy 131.379282 -244.198695) (xy 131.426868 -244.180648) (xy 131.476732 -244.170468)
			(xy 131.527584 -244.168419) (xy 131.578105 -244.174553) (xy 131.626989 -244.188713) (xy 131.672968 -244.21053)
			(xy 131.714852 -244.23944) (xy 131.751556 -244.274695) (xy 131.782129 -244.315381) (xy 131.80578 -244.360444)
			(xy 131.821896 -244.408718) (xy 131.83006 -244.458952) (xy 131.830572 -244.484398) (xy 132.138415 -244.484398)
			(xy 132.14251 -244.43367) (xy 132.154689 -244.384256) (xy 132.174637 -244.337436) (xy 132.201838 -244.294422)
			(xy 132.235586 -244.256328) (xy 132.275008 -244.224141) (xy 132.319082 -244.198695) (xy 132.366668 -244.180648)
			(xy 132.416532 -244.170468) (xy 132.467384 -244.168419) (xy 132.517905 -244.174553) (xy 132.566789 -244.188713)
			(xy 132.612768 -244.21053) (xy 132.654652 -244.23944) (xy 132.691356 -244.274695) (xy 132.721929 -244.315381)
			(xy 132.74558 -244.360444) (xy 132.761696 -244.408718) (xy 132.76986 -244.458952) (xy 132.770372 -244.484398)
			(xy 132.76986 -244.509844) (xy 132.761696 -244.560078) (xy 132.74558 -244.608352) (xy 132.721929 -244.653415)
			(xy 132.691356 -244.694101) (xy 132.654652 -244.729356) (xy 132.612768 -244.758266) (xy 132.566789 -244.780083)
			(xy 132.517905 -244.794243) (xy 132.467384 -244.800377) (xy 132.416532 -244.798328) (xy 132.366668 -244.788148)
			(xy 132.319082 -244.770101) (xy 132.275008 -244.744655) (xy 132.235586 -244.712468) (xy 132.201838 -244.674374)
			(xy 132.174637 -244.63136) (xy 132.154689 -244.58454) (xy 132.14251 -244.535126) (xy 132.138415 -244.484398)
			(xy 131.830572 -244.484398) (xy 131.83006 -244.509844) (xy 131.821896 -244.560078) (xy 131.80578 -244.608352)
			(xy 131.782129 -244.653415) (xy 131.751556 -244.694101) (xy 131.714852 -244.729356) (xy 131.672968 -244.758266)
			(xy 131.626989 -244.780083) (xy 131.578105 -244.794243) (xy 131.527584 -244.800377) (xy 131.476732 -244.798328)
			(xy 131.426868 -244.788148) (xy 131.379282 -244.770101) (xy 131.335208 -244.744655) (xy 131.295786 -244.712468)
			(xy 131.262038 -244.674374) (xy 131.234837 -244.63136) (xy 131.214889 -244.58454) (xy 131.20271 -244.535126)
			(xy 131.198615 -244.484398) (xy 129.950464 -244.484398) (xy 129.949952 -244.509844) (xy 129.941788 -244.560078)
			(xy 129.925672 -244.608352) (xy 129.902021 -244.653415) (xy 129.871448 -244.694101) (xy 129.834744 -244.729356)
			(xy 129.79286 -244.758266) (xy 129.746881 -244.780083) (xy 129.697997 -244.794243) (xy 129.647476 -244.800377)
			(xy 129.596624 -244.798328) (xy 129.54676 -244.788148) (xy 129.499174 -244.770101) (xy 129.4551 -244.744655)
			(xy 129.415678 -244.712468) (xy 129.38193 -244.674374) (xy 129.354729 -244.63136) (xy 129.334781 -244.58454)
			(xy 129.322602 -244.535126) (xy 129.318507 -244.484398) (xy 128.999996 -244.484398) (xy 128.999501 -244.509005)
			(xy 128.991606 -244.557582) (xy 128.976022 -244.604263) (xy 128.953151 -244.64784) (xy 128.923586 -244.687184)
			(xy 128.888093 -244.721276) (xy 128.84759 -244.749232) (xy 128.803128 -244.77033) (xy 128.755857 -244.784022)
			(xy 128.707002 -244.789954) (xy 128.657827 -244.787973) (xy 128.609608 -244.778129) (xy 128.563592 -244.760677)
			(xy 128.520971 -244.73607) (xy 128.48285 -244.704945) (xy 128.450215 -244.668108) (xy 128.423912 -244.626512)
			(xy 128.404621 -244.581236) (xy 128.392844 -244.533452) (xy 128.388884 -244.484398) (xy 128.070356 -244.484398)
			(xy 128.069844 -244.509844) (xy 128.06168 -244.560078) (xy 128.045564 -244.608352) (xy 128.021913 -244.653415)
			(xy 127.99134 -244.694101) (xy 127.954636 -244.729356) (xy 127.912752 -244.758266) (xy 127.866773 -244.780083)
			(xy 127.817889 -244.794243) (xy 127.767368 -244.800377) (xy 127.716516 -244.798328) (xy 127.666652 -244.788148)
			(xy 127.619066 -244.770101) (xy 127.574992 -244.744655) (xy 127.53557 -244.712468) (xy 127.501822 -244.674374)
			(xy 127.474621 -244.63136) (xy 127.454673 -244.58454) (xy 127.442494 -244.535126) (xy 127.438399 -244.484398)
			(xy 127.120655 -244.484398) (xy 127.120655 -244.484399) (xy 127.116874 -244.532321) (xy 127.105624 -244.579057)
			(xy 127.087183 -244.62345) (xy 127.062008 -244.664401) (xy 127.030721 -244.700898) (xy 127.0127 -244.716808)
			(xy 127.004677 -244.72438) (xy 126.99546 -244.744397) (xy 126.99492 -244.755416) (xy 126.99492 -244.933724)
			(xy 126.99492 -244.93474) (xy 126.995627 -244.945494) (xy 127.004841 -244.964956) (xy 127.0127 -244.972332)
			(xy 127.019558 -244.977158) (xy 127.093726 -245.022116) (xy 127.101361 -245.026299) (xy 127.118409 -245.029773)
			(xy 127.13564 -245.02736) (xy 127.14351 -245.02364) (xy 127.165447 -245.012765) (xy 127.211921 -244.997363)
			(xy 127.260254 -244.989558) (xy 127.284734 -244.989096) (xy 127.290068 -244.989096) (xy 127.313786 -244.989956)
			(xy 127.360538 -244.998108) (xy 127.405465 -245.013398) (xy 127.447484 -245.035457) (xy 127.485583 -245.063754)
			(xy 127.518844 -245.097605) (xy 127.546466 -245.136196) (xy 127.567782 -245.178598) (xy 127.582279 -245.223787)
			(xy 127.589607 -245.270675) (xy 127.590042 -245.294404) (xy 127.908553 -245.294404) (xy 127.912648 -245.243676)
			(xy 127.924827 -245.194262) (xy 127.944775 -245.147442) (xy 127.971976 -245.104428) (xy 128.005724 -245.066334)
			(xy 128.045146 -245.034147) (xy 128.08922 -245.008701) (xy 128.136806 -244.990654) (xy 128.18667 -244.980474)
			(xy 128.237522 -244.978425) (xy 128.288043 -244.984559) (xy 128.336927 -244.998719) (xy 128.382906 -245.020536)
			(xy 128.42479 -245.049446) (xy 128.461494 -245.084701) (xy 128.492067 -245.125387) (xy 128.515718 -245.17045)
			(xy 128.531834 -245.218724) (xy 128.539998 -245.268958) (xy 128.54051 -245.294404) (xy 128.848607 -245.294404)
			(xy 128.852702 -245.243676) (xy 128.864881 -245.194262) (xy 128.884829 -245.147442) (xy 128.91203 -245.104428)
			(xy 128.945778 -245.066334) (xy 128.9852 -245.034147) (xy 129.029274 -245.008701) (xy 129.07686 -244.990654)
			(xy 129.126724 -244.980474) (xy 129.177576 -244.978425) (xy 129.228097 -244.984559) (xy 129.276981 -244.998719)
			(xy 129.32296 -245.020536) (xy 129.364844 -245.049446) (xy 129.401548 -245.084701) (xy 129.432121 -245.125387)
			(xy 129.455772 -245.17045) (xy 129.471888 -245.218724) (xy 129.480052 -245.268958) (xy 129.480564 -245.294404)
			(xy 129.798838 -245.294404) (xy 129.802798 -245.24535) (xy 129.814575 -245.197566) (xy 129.833866 -245.15229)
			(xy 129.860169 -245.110694) (xy 129.892804 -245.073857) (xy 129.930925 -245.042732) (xy 129.973546 -245.018125)
			(xy 130.019562 -245.000673) (xy 130.067781 -244.990829) (xy 130.116956 -244.988848) (xy 130.165811 -244.99478)
			(xy 130.213082 -245.008472) (xy 130.257544 -245.02957) (xy 130.298047 -245.057526) (xy 130.33354 -245.091618)
			(xy 130.363105 -245.130962) (xy 130.385976 -245.174539) (xy 130.40156 -245.22122) (xy 130.409455 -245.269797)
			(xy 130.40995 -245.294404) (xy 130.728461 -245.294404) (xy 130.732556 -245.243676) (xy 130.744735 -245.194262)
			(xy 130.764683 -245.147442) (xy 130.791884 -245.104428) (xy 130.825632 -245.066334) (xy 130.865054 -245.034147)
			(xy 130.909128 -245.008701) (xy 130.956714 -244.990654) (xy 131.006578 -244.980474) (xy 131.05743 -244.978425)
			(xy 131.107951 -244.984559) (xy 131.156835 -244.998719) (xy 131.202814 -245.020536) (xy 131.244698 -245.049446)
			(xy 131.281402 -245.084701) (xy 131.311975 -245.125387) (xy 131.335626 -245.17045) (xy 131.351742 -245.218724)
			(xy 131.359906 -245.268958) (xy 131.360418 -245.294404) (xy 131.678946 -245.294404) (xy 131.682906 -245.24535)
			(xy 131.694683 -245.197566) (xy 131.713974 -245.15229) (xy 131.740277 -245.110694) (xy 131.772912 -245.073857)
			(xy 131.811033 -245.042732) (xy 131.853654 -245.018125) (xy 131.89967 -245.000673) (xy 131.947889 -244.990829)
			(xy 131.997064 -244.988848) (xy 132.045919 -244.99478) (xy 132.09319 -245.008472) (xy 132.137652 -245.02957)
			(xy 132.178155 -245.057526) (xy 132.213648 -245.091618) (xy 132.243213 -245.130962) (xy 132.266084 -245.174539)
			(xy 132.281668 -245.22122) (xy 132.289563 -245.269797) (xy 132.290058 -245.294404) (xy 132.608569 -245.294404)
			(xy 132.612664 -245.243676) (xy 132.624843 -245.194262) (xy 132.644791 -245.147442) (xy 132.671992 -245.104428)
			(xy 132.70574 -245.066334) (xy 132.745162 -245.034147) (xy 132.789236 -245.008701) (xy 132.836822 -244.990654)
			(xy 132.886686 -244.980474) (xy 132.937538 -244.978425) (xy 132.988059 -244.984559) (xy 133.036943 -244.998719)
			(xy 133.082922 -245.020536) (xy 133.124806 -245.049446) (xy 133.16151 -245.084701) (xy 133.192083 -245.125387)
			(xy 133.215734 -245.17045) (xy 133.23185 -245.218724) (xy 133.240014 -245.268958) (xy 133.240526 -245.294404)
			(xy 133.240014 -245.31985) (xy 133.23185 -245.370084) (xy 133.215734 -245.418358) (xy 133.192083 -245.463421)
			(xy 133.16151 -245.504107) (xy 133.124806 -245.539362) (xy 133.082922 -245.568272) (xy 133.036943 -245.590089)
			(xy 132.988059 -245.604249) (xy 132.937538 -245.610383) (xy 132.886686 -245.608334) (xy 132.836822 -245.598154)
			(xy 132.789236 -245.580107) (xy 132.745162 -245.554661) (xy 132.70574 -245.522474) (xy 132.671992 -245.48438)
			(xy 132.644791 -245.441366) (xy 132.624843 -245.394546) (xy 132.612664 -245.345132) (xy 132.608569 -245.294404)
			(xy 132.290058 -245.294404) (xy 132.289563 -245.319011) (xy 132.281668 -245.367588) (xy 132.266084 -245.414269)
			(xy 132.243213 -245.457846) (xy 132.213648 -245.49719) (xy 132.178155 -245.531282) (xy 132.137652 -245.559238)
			(xy 132.09319 -245.580336) (xy 132.045919 -245.594028) (xy 131.997064 -245.59996) (xy 131.947889 -245.597979)
			(xy 131.89967 -245.588135) (xy 131.853654 -245.570683) (xy 131.811033 -245.546076) (xy 131.772912 -245.514951)
			(xy 131.740277 -245.478114) (xy 131.713974 -245.436518) (xy 131.694683 -245.391242) (xy 131.682906 -245.343458)
			(xy 131.678946 -245.294404) (xy 131.360418 -245.294404) (xy 131.359906 -245.31985) (xy 131.351742 -245.370084)
			(xy 131.335626 -245.418358) (xy 131.311975 -245.463421) (xy 131.281402 -245.504107) (xy 131.244698 -245.539362)
			(xy 131.202814 -245.568272) (xy 131.156835 -245.590089) (xy 131.107951 -245.604249) (xy 131.05743 -245.610383)
			(xy 131.006578 -245.608334) (xy 130.956714 -245.598154) (xy 130.909128 -245.580107) (xy 130.865054 -245.554661)
			(xy 130.825632 -245.522474) (xy 130.791884 -245.48438) (xy 130.764683 -245.441366) (xy 130.744735 -245.394546)
			(xy 130.732556 -245.345132) (xy 130.728461 -245.294404) (xy 130.40995 -245.294404) (xy 130.409455 -245.319011)
			(xy 130.40156 -245.367588) (xy 130.385976 -245.414269) (xy 130.363105 -245.457846) (xy 130.33354 -245.49719)
			(xy 130.298047 -245.531282) (xy 130.257544 -245.559238) (xy 130.213082 -245.580336) (xy 130.165811 -245.594028)
			(xy 130.116956 -245.59996) (xy 130.067781 -245.597979) (xy 130.019562 -245.588135) (xy 129.973546 -245.570683)
			(xy 129.930925 -245.546076) (xy 129.892804 -245.514951) (xy 129.860169 -245.478114) (xy 129.833866 -245.436518)
			(xy 129.814575 -245.391242) (xy 129.802798 -245.343458) (xy 129.798838 -245.294404) (xy 129.480564 -245.294404)
			(xy 129.480052 -245.31985) (xy 129.471888 -245.370084) (xy 129.455772 -245.418358) (xy 129.432121 -245.463421)
			(xy 129.401548 -245.504107) (xy 129.364844 -245.539362) (xy 129.32296 -245.568272) (xy 129.276981 -245.590089)
			(xy 129.228097 -245.604249) (xy 129.177576 -245.610383) (xy 129.126724 -245.608334) (xy 129.07686 -245.598154)
			(xy 129.029274 -245.580107) (xy 128.9852 -245.554661) (xy 128.945778 -245.522474) (xy 128.91203 -245.48438)
			(xy 128.884829 -245.441366) (xy 128.864881 -245.394546) (xy 128.852702 -245.345132) (xy 128.848607 -245.294404)
			(xy 128.54051 -245.294404) (xy 128.539998 -245.31985) (xy 128.531834 -245.370084) (xy 128.515718 -245.418358)
			(xy 128.492067 -245.463421) (xy 128.461494 -245.504107) (xy 128.42479 -245.539362) (xy 128.382906 -245.568272)
			(xy 128.336927 -245.590089) (xy 128.288043 -245.604249) (xy 128.237522 -245.610383) (xy 128.18667 -245.608334)
			(xy 128.136806 -245.598154) (xy 128.08922 -245.580107) (xy 128.045146 -245.554661) (xy 128.005724 -245.522474)
			(xy 127.971976 -245.48438) (xy 127.944775 -245.441366) (xy 127.924827 -245.394546) (xy 127.912648 -245.345132)
			(xy 127.908553 -245.294404) (xy 127.590042 -245.294404) (xy 127.589571 -245.318396) (xy 127.582065 -245.365789)
			(xy 127.567237 -245.411425) (xy 127.545454 -245.454179) (xy 127.517251 -245.493) (xy 127.483323 -245.526932)
			(xy 127.444505 -245.555138) (xy 127.401753 -245.576926) (xy 127.356118 -245.591758) (xy 127.308726 -245.599269)
			(xy 127.284734 -245.599712) (xy 127.28448 -245.599712) (xy 127.260042 -245.599233) (xy 127.21179 -245.591439)
			(xy 127.165404 -245.576037) (xy 127.14351 -245.565168) (xy 127.135642 -245.561432) (xy 127.11841 -245.55899)
			(xy 127.101365 -245.562505) (xy 127.093726 -245.566692) (xy 127.019558 -245.61165) (xy 127.0127 -245.616476)
			(xy 127.00484 -245.623848) (xy 126.995645 -245.643316) (xy 126.99492 -245.654068) (xy 126.99492 -245.833392)
			(xy 126.995459 -245.844411) (xy 127.004679 -245.864426) (xy 127.0127 -245.872) (xy 127.030719 -245.887912)
			(xy 127.062003 -245.924408) (xy 127.087177 -245.965359) (xy 127.105617 -246.009751) (xy 127.116866 -246.056486)
			(xy 127.120646 -246.104406) (xy 127.120646 -246.10441) (xy 127.438399 -246.10441) (xy 127.442494 -246.053682)
			(xy 127.454673 -246.004268) (xy 127.474621 -245.957448) (xy 127.501822 -245.914434) (xy 127.53557 -245.87634)
			(xy 127.574992 -245.844153) (xy 127.619066 -245.818707) (xy 127.666652 -245.80066) (xy 127.716516 -245.79048)
			(xy 127.767368 -245.788431) (xy 127.817889 -245.794565) (xy 127.866773 -245.808725) (xy 127.912752 -245.830542)
			(xy 127.954636 -245.859452) (xy 127.99134 -245.894707) (xy 128.021913 -245.935393) (xy 128.045564 -245.980456)
			(xy 128.06168 -246.02873) (xy 128.069844 -246.078964) (xy 128.070356 -246.10441) (xy 128.388884 -246.10441)
			(xy 128.392844 -246.055356) (xy 128.404621 -246.007572) (xy 128.423912 -245.962296) (xy 128.450215 -245.9207)
			(xy 128.48285 -245.883863) (xy 128.520971 -245.852738) (xy 128.563592 -245.828131) (xy 128.609608 -245.810679)
			(xy 128.657827 -245.800835) (xy 128.707002 -245.798854) (xy 128.755857 -245.804786) (xy 128.803128 -245.818478)
			(xy 128.84759 -245.839576) (xy 128.888093 -245.867532) (xy 128.923586 -245.901624) (xy 128.953151 -245.940968)
			(xy 128.976022 -245.984545) (xy 128.991606 -246.031226) (xy 128.999501 -246.079803) (xy 128.999996 -246.10441)
			(xy 129.318507 -246.10441) (xy 129.322602 -246.053682) (xy 129.334781 -246.004268) (xy 129.354729 -245.957448)
			(xy 129.38193 -245.914434) (xy 129.415678 -245.87634) (xy 129.4551 -245.844153) (xy 129.499174 -245.818707)
			(xy 129.54676 -245.80066) (xy 129.596624 -245.79048) (xy 129.647476 -245.788431) (xy 129.697997 -245.794565)
			(xy 129.746881 -245.808725) (xy 129.79286 -245.830542) (xy 129.834744 -245.859452) (xy 129.871448 -245.894707)
			(xy 129.902021 -245.935393) (xy 129.925672 -245.980456) (xy 129.941788 -246.02873) (xy 129.949952 -246.078964)
			(xy 129.950464 -246.10441) (xy 130.268992 -246.10441) (xy 130.272952 -246.055356) (xy 130.284729 -246.007572)
			(xy 130.30402 -245.962296) (xy 130.330323 -245.9207) (xy 130.362958 -245.883863) (xy 130.401079 -245.852738)
			(xy 130.4437 -245.828131) (xy 130.489716 -245.810679) (xy 130.537935 -245.800835) (xy 130.58711 -245.798854)
			(xy 130.635965 -245.804786) (xy 130.683236 -245.818478) (xy 130.727698 -245.839576) (xy 130.768201 -245.867532)
			(xy 130.803694 -245.901624) (xy 130.833259 -245.940968) (xy 130.85613 -245.984545) (xy 130.871714 -246.031226)
			(xy 130.879609 -246.079803) (xy 130.880104 -246.10441) (xy 131.198615 -246.10441) (xy 131.20271 -246.053682)
			(xy 131.214889 -246.004268) (xy 131.234837 -245.957448) (xy 131.262038 -245.914434) (xy 131.295786 -245.87634)
			(xy 131.335208 -245.844153) (xy 131.379282 -245.818707) (xy 131.426868 -245.80066) (xy 131.476732 -245.79048)
			(xy 131.527584 -245.788431) (xy 131.578105 -245.794565) (xy 131.626989 -245.808725) (xy 131.672968 -245.830542)
			(xy 131.714852 -245.859452) (xy 131.751556 -245.894707) (xy 131.782129 -245.935393) (xy 131.80578 -245.980456)
			(xy 131.821896 -246.02873) (xy 131.83006 -246.078964) (xy 131.830572 -246.10441) (xy 132.138415 -246.10441)
			(xy 132.14251 -246.053682) (xy 132.154689 -246.004268) (xy 132.174637 -245.957448) (xy 132.201838 -245.914434)
			(xy 132.235586 -245.87634) (xy 132.275008 -245.844153) (xy 132.319082 -245.818707) (xy 132.366668 -245.80066)
			(xy 132.416532 -245.79048) (xy 132.467384 -245.788431) (xy 132.517905 -245.794565) (xy 132.566789 -245.808725)
			(xy 132.612768 -245.830542) (xy 132.654652 -245.859452) (xy 132.691356 -245.894707) (xy 132.721929 -245.935393)
			(xy 132.74558 -245.980456) (xy 132.761696 -246.02873) (xy 132.76986 -246.078964) (xy 132.770372 -246.10441)
			(xy 132.76986 -246.129856) (xy 132.761696 -246.18009) (xy 132.74558 -246.228364) (xy 132.721929 -246.273427)
			(xy 132.691356 -246.314113) (xy 132.654652 -246.349368) (xy 132.612768 -246.378278) (xy 132.566789 -246.400095)
			(xy 132.517905 -246.414255) (xy 132.467384 -246.420389) (xy 132.416532 -246.41834) (xy 132.366668 -246.40816)
			(xy 132.319082 -246.390113) (xy 132.275008 -246.364667) (xy 132.235586 -246.33248) (xy 132.201838 -246.294386)
			(xy 132.174637 -246.251372) (xy 132.154689 -246.204552) (xy 132.14251 -246.155138) (xy 132.138415 -246.10441)
			(xy 131.830572 -246.10441) (xy 131.83006 -246.129856) (xy 131.821896 -246.18009) (xy 131.80578 -246.228364)
			(xy 131.782129 -246.273427) (xy 131.751556 -246.314113) (xy 131.714852 -246.349368) (xy 131.672968 -246.378278)
			(xy 131.626989 -246.400095) (xy 131.578105 -246.414255) (xy 131.527584 -246.420389) (xy 131.476732 -246.41834)
			(xy 131.426868 -246.40816) (xy 131.379282 -246.390113) (xy 131.335208 -246.364667) (xy 131.295786 -246.33248)
			(xy 131.262038 -246.294386) (xy 131.234837 -246.251372) (xy 131.214889 -246.204552) (xy 131.20271 -246.155138)
			(xy 131.198615 -246.10441) (xy 130.880104 -246.10441) (xy 130.879609 -246.129017) (xy 130.871714 -246.177594)
			(xy 130.85613 -246.224275) (xy 130.833259 -246.267852) (xy 130.803694 -246.307196) (xy 130.768201 -246.341288)
			(xy 130.727698 -246.369244) (xy 130.683236 -246.390342) (xy 130.635965 -246.404034) (xy 130.58711 -246.409966)
			(xy 130.537935 -246.407985) (xy 130.489716 -246.398141) (xy 130.4437 -246.380689) (xy 130.401079 -246.356082)
			(xy 130.362958 -246.324957) (xy 130.330323 -246.28812) (xy 130.30402 -246.246524) (xy 130.284729 -246.201248)
			(xy 130.272952 -246.153464) (xy 130.268992 -246.10441) (xy 129.950464 -246.10441) (xy 129.949952 -246.129856)
			(xy 129.941788 -246.18009) (xy 129.925672 -246.228364) (xy 129.902021 -246.273427) (xy 129.871448 -246.314113)
			(xy 129.834744 -246.349368) (xy 129.79286 -246.378278) (xy 129.746881 -246.400095) (xy 129.697997 -246.414255)
			(xy 129.647476 -246.420389) (xy 129.596624 -246.41834) (xy 129.54676 -246.40816) (xy 129.499174 -246.390113)
			(xy 129.4551 -246.364667) (xy 129.415678 -246.33248) (xy 129.38193 -246.294386) (xy 129.354729 -246.251372)
			(xy 129.334781 -246.204552) (xy 129.322602 -246.155138) (xy 129.318507 -246.10441) (xy 128.999996 -246.10441)
			(xy 128.999501 -246.129017) (xy 128.991606 -246.177594) (xy 128.976022 -246.224275) (xy 128.953151 -246.267852)
			(xy 128.923586 -246.307196) (xy 128.888093 -246.341288) (xy 128.84759 -246.369244) (xy 128.803128 -246.390342)
			(xy 128.755857 -246.404034) (xy 128.707002 -246.409966) (xy 128.657827 -246.407985) (xy 128.609608 -246.398141)
			(xy 128.563592 -246.380689) (xy 128.520971 -246.356082) (xy 128.48285 -246.324957) (xy 128.450215 -246.28812)
			(xy 128.423912 -246.246524) (xy 128.404621 -246.201248) (xy 128.392844 -246.153464) (xy 128.388884 -246.10441)
			(xy 128.070356 -246.10441) (xy 128.069844 -246.129856) (xy 128.06168 -246.18009) (xy 128.045564 -246.228364)
			(xy 128.021913 -246.273427) (xy 127.99134 -246.314113) (xy 127.954636 -246.349368) (xy 127.912752 -246.378278)
			(xy 127.866773 -246.400095) (xy 127.817889 -246.414255) (xy 127.767368 -246.420389) (xy 127.716516 -246.41834)
			(xy 127.666652 -246.40816) (xy 127.619066 -246.390113) (xy 127.574992 -246.364667) (xy 127.53557 -246.33248)
			(xy 127.501822 -246.294386) (xy 127.474621 -246.251372) (xy 127.454673 -246.204552) (xy 127.442494 -246.155138)
			(xy 127.438399 -246.10441) (xy 127.120646 -246.10441) (xy 127.116864 -246.152327) (xy 127.105613 -246.199061)
			(xy 127.087171 -246.243453) (xy 127.061996 -246.284402) (xy 127.03071 -246.320897) (xy 127.0127 -246.33682)
			(xy 127.004679 -246.344393) (xy 126.995467 -246.36441) (xy 126.99492 -246.375428) (xy 126.99492 -246.914416)
			(xy 127.908553 -246.914416) (xy 127.912648 -246.863688) (xy 127.924827 -246.814274) (xy 127.944775 -246.767454)
			(xy 127.971976 -246.72444) (xy 128.005724 -246.686346) (xy 128.045146 -246.654159) (xy 128.08922 -246.628713)
			(xy 128.136806 -246.610666) (xy 128.18667 -246.600486) (xy 128.237522 -246.598437) (xy 128.288043 -246.604571)
			(xy 128.336927 -246.618731) (xy 128.382906 -246.640548) (xy 128.42479 -246.669458) (xy 128.461494 -246.704713)
			(xy 128.492067 -246.745399) (xy 128.515718 -246.790462) (xy 128.531834 -246.838736) (xy 128.539998 -246.88897)
			(xy 128.54051 -246.914416) (xy 128.848607 -246.914416) (xy 128.852702 -246.863688) (xy 128.864881 -246.814274)
			(xy 128.884829 -246.767454) (xy 128.91203 -246.72444) (xy 128.945778 -246.686346) (xy 128.9852 -246.654159)
			(xy 129.029274 -246.628713) (xy 129.07686 -246.610666) (xy 129.126724 -246.600486) (xy 129.177576 -246.598437)
			(xy 129.228097 -246.604571) (xy 129.276981 -246.618731) (xy 129.32296 -246.640548) (xy 129.364844 -246.669458)
			(xy 129.401548 -246.704713) (xy 129.432121 -246.745399) (xy 129.455772 -246.790462) (xy 129.471888 -246.838736)
			(xy 129.480052 -246.88897) (xy 129.480564 -246.914416) (xy 130.728461 -246.914416) (xy 130.732556 -246.863688)
			(xy 130.744735 -246.814274) (xy 130.764683 -246.767454) (xy 130.791884 -246.72444) (xy 130.825632 -246.686346)
			(xy 130.865054 -246.654159) (xy 130.909128 -246.628713) (xy 130.956714 -246.610666) (xy 131.006578 -246.600486)
			(xy 131.05743 -246.598437) (xy 131.107951 -246.604571) (xy 131.156835 -246.618731) (xy 131.202814 -246.640548)
			(xy 131.244698 -246.669458) (xy 131.281402 -246.704713) (xy 131.311975 -246.745399) (xy 131.335626 -246.790462)
			(xy 131.351742 -246.838736) (xy 131.359906 -246.88897) (xy 131.360418 -246.914416) (xy 131.678946 -246.914416)
			(xy 131.682906 -246.865362) (xy 131.694683 -246.817578) (xy 131.713974 -246.772302) (xy 131.740277 -246.730706)
			(xy 131.772912 -246.693869) (xy 131.811033 -246.662744) (xy 131.853654 -246.638137) (xy 131.89967 -246.620685)
			(xy 131.947889 -246.610841) (xy 131.997064 -246.60886) (xy 132.045919 -246.614792) (xy 132.09319 -246.628484)
			(xy 132.137652 -246.649582) (xy 132.178155 -246.677538) (xy 132.213648 -246.71163) (xy 132.243213 -246.750974)
			(xy 132.266084 -246.794551) (xy 132.281668 -246.841232) (xy 132.289563 -246.889809) (xy 132.290058 -246.914416)
			(xy 132.608569 -246.914416) (xy 132.612664 -246.863688) (xy 132.624843 -246.814274) (xy 132.644791 -246.767454)
			(xy 132.671992 -246.72444) (xy 132.70574 -246.686346) (xy 132.745162 -246.654159) (xy 132.789236 -246.628713)
			(xy 132.836822 -246.610666) (xy 132.886686 -246.600486) (xy 132.937538 -246.598437) (xy 132.988059 -246.604571)
			(xy 133.036943 -246.618731) (xy 133.082922 -246.640548) (xy 133.124806 -246.669458) (xy 133.16151 -246.704713)
			(xy 133.192083 -246.745399) (xy 133.215734 -246.790462) (xy 133.23185 -246.838736) (xy 133.240014 -246.88897)
			(xy 133.240526 -246.914416) (xy 133.240014 -246.939862) (xy 133.23185 -246.990096) (xy 133.215734 -247.03837)
			(xy 133.192083 -247.083433) (xy 133.16151 -247.124119) (xy 133.124806 -247.159374) (xy 133.082922 -247.188284)
			(xy 133.036943 -247.210101) (xy 132.988059 -247.224261) (xy 132.937538 -247.230395) (xy 132.886686 -247.228346)
			(xy 132.836822 -247.218166) (xy 132.789236 -247.200119) (xy 132.745162 -247.174673) (xy 132.70574 -247.142486)
			(xy 132.671992 -247.104392) (xy 132.644791 -247.061378) (xy 132.624843 -247.014558) (xy 132.612664 -246.965144)
			(xy 132.608569 -246.914416) (xy 132.290058 -246.914416) (xy 132.289563 -246.939023) (xy 132.281668 -246.9876)
			(xy 132.266084 -247.034281) (xy 132.243213 -247.077858) (xy 132.213648 -247.117202) (xy 132.178155 -247.151294)
			(xy 132.137652 -247.17925) (xy 132.09319 -247.200348) (xy 132.045919 -247.21404) (xy 131.997064 -247.219972)
			(xy 131.947889 -247.217991) (xy 131.89967 -247.208147) (xy 131.853654 -247.190695) (xy 131.811033 -247.166088)
			(xy 131.772912 -247.134963) (xy 131.740277 -247.098126) (xy 131.713974 -247.05653) (xy 131.694683 -247.011254)
			(xy 131.682906 -246.96347) (xy 131.678946 -246.914416) (xy 131.360418 -246.914416) (xy 131.359906 -246.939862)
			(xy 131.351742 -246.990096) (xy 131.335626 -247.03837) (xy 131.311975 -247.083433) (xy 131.281402 -247.124119)
			(xy 131.244698 -247.159374) (xy 131.202814 -247.188284) (xy 131.156835 -247.210101) (xy 131.107951 -247.224261)
			(xy 131.05743 -247.230395) (xy 131.006578 -247.228346) (xy 130.956714 -247.218166) (xy 130.909128 -247.200119)
			(xy 130.865054 -247.174673) (xy 130.825632 -247.142486) (xy 130.791884 -247.104392) (xy 130.764683 -247.061378)
			(xy 130.744735 -247.014558) (xy 130.732556 -246.965144) (xy 130.728461 -246.914416) (xy 129.480564 -246.914416)
			(xy 129.480052 -246.939862) (xy 129.471888 -246.990096) (xy 129.455772 -247.03837) (xy 129.432121 -247.083433)
			(xy 129.401548 -247.124119) (xy 129.364844 -247.159374) (xy 129.32296 -247.188284) (xy 129.276981 -247.210101)
			(xy 129.228097 -247.224261) (xy 129.177576 -247.230395) (xy 129.126724 -247.228346) (xy 129.07686 -247.218166)
			(xy 129.029274 -247.200119) (xy 128.9852 -247.174673) (xy 128.945778 -247.142486) (xy 128.91203 -247.104392)
			(xy 128.884829 -247.061378) (xy 128.864881 -247.014558) (xy 128.852702 -246.965144) (xy 128.848607 -246.914416)
			(xy 128.54051 -246.914416) (xy 128.539998 -246.939862) (xy 128.531834 -246.990096) (xy 128.515718 -247.03837)
			(xy 128.492067 -247.083433) (xy 128.461494 -247.124119) (xy 128.42479 -247.159374) (xy 128.382906 -247.188284)
			(xy 128.336927 -247.210101) (xy 128.288043 -247.224261) (xy 128.237522 -247.230395) (xy 128.18667 -247.228346)
			(xy 128.136806 -247.218166) (xy 128.08922 -247.200119) (xy 128.045146 -247.174673) (xy 128.005724 -247.142486)
			(xy 127.971976 -247.104392) (xy 127.944775 -247.061378) (xy 127.924827 -247.014558) (xy 127.912648 -246.965144)
			(xy 127.908553 -246.914416) (xy 126.99492 -246.914416) (xy 126.99492 -247.453404) (xy 126.995462 -247.464421)
			(xy 127.004684 -247.484433) (xy 127.0127 -247.492012) (xy 127.030718 -247.507924) (xy 127.062001 -247.54442)
			(xy 127.087173 -247.58537) (xy 127.10561 -247.629761) (xy 127.116858 -247.676495) (xy 127.120637 -247.724414)
			(xy 127.120636 -247.724422) (xy 127.438399 -247.724422) (xy 127.442494 -247.673694) (xy 127.454673 -247.62428)
			(xy 127.474621 -247.57746) (xy 127.501822 -247.534446) (xy 127.53557 -247.496352) (xy 127.574992 -247.464165)
			(xy 127.619066 -247.438719) (xy 127.666652 -247.420672) (xy 127.716516 -247.410492) (xy 127.767368 -247.408443)
			(xy 127.817889 -247.414577) (xy 127.866773 -247.428737) (xy 127.912752 -247.450554) (xy 127.954636 -247.479464)
			(xy 127.99134 -247.514719) (xy 128.021913 -247.555405) (xy 128.045564 -247.600468) (xy 128.06168 -247.648742)
			(xy 128.069844 -247.698976) (xy 128.070356 -247.724422) (xy 128.388884 -247.724422) (xy 128.392844 -247.675368)
			(xy 128.404621 -247.627584) (xy 128.423912 -247.582308) (xy 128.450215 -247.540712) (xy 128.48285 -247.503875)
			(xy 128.520971 -247.47275) (xy 128.563592 -247.448143) (xy 128.609608 -247.430691) (xy 128.657827 -247.420847)
			(xy 128.707002 -247.418866) (xy 128.755857 -247.424798) (xy 128.803128 -247.43849) (xy 128.84759 -247.459588)
			(xy 128.888093 -247.487544) (xy 128.923586 -247.521636) (xy 128.953151 -247.56098) (xy 128.976022 -247.604557)
			(xy 128.991606 -247.651238) (xy 128.999501 -247.699815) (xy 128.999996 -247.724422) (xy 129.318507 -247.724422)
			(xy 129.322602 -247.673694) (xy 129.334781 -247.62428) (xy 129.354729 -247.57746) (xy 129.38193 -247.534446)
			(xy 129.415678 -247.496352) (xy 129.4551 -247.464165) (xy 129.499174 -247.438719) (xy 129.54676 -247.420672)
			(xy 129.596624 -247.410492) (xy 129.647476 -247.408443) (xy 129.697997 -247.414577) (xy 129.746881 -247.428737)
			(xy 129.79286 -247.450554) (xy 129.834744 -247.479464) (xy 129.871448 -247.514719) (xy 129.902021 -247.555405)
			(xy 129.925672 -247.600468) (xy 129.941788 -247.648742) (xy 129.949952 -247.698976) (xy 129.950464 -247.724422)
			(xy 130.268992 -247.724422) (xy 130.272952 -247.675368) (xy 130.284729 -247.627584) (xy 130.30402 -247.582308)
			(xy 130.330323 -247.540712) (xy 130.362958 -247.503875) (xy 130.401079 -247.47275) (xy 130.4437 -247.448143)
			(xy 130.489716 -247.430691) (xy 130.537935 -247.420847) (xy 130.58711 -247.418866) (xy 130.635965 -247.424798)
			(xy 130.683236 -247.43849) (xy 130.727698 -247.459588) (xy 130.768201 -247.487544) (xy 130.803694 -247.521636)
			(xy 130.833259 -247.56098) (xy 130.85613 -247.604557) (xy 130.871714 -247.651238) (xy 130.879609 -247.699815)
			(xy 130.880104 -247.724422) (xy 131.198615 -247.724422) (xy 131.20271 -247.673694) (xy 131.214889 -247.62428)
			(xy 131.234837 -247.57746) (xy 131.262038 -247.534446) (xy 131.295786 -247.496352) (xy 131.335208 -247.464165)
			(xy 131.379282 -247.438719) (xy 131.426868 -247.420672) (xy 131.476732 -247.410492) (xy 131.527584 -247.408443)
			(xy 131.578105 -247.414577) (xy 131.626989 -247.428737) (xy 131.672968 -247.450554) (xy 131.714852 -247.479464)
			(xy 131.751556 -247.514719) (xy 131.782129 -247.555405) (xy 131.80578 -247.600468) (xy 131.821896 -247.648742)
			(xy 131.83006 -247.698976) (xy 131.830572 -247.724422) (xy 132.138415 -247.724422) (xy 132.14251 -247.673694)
			(xy 132.154689 -247.62428) (xy 132.174637 -247.57746) (xy 132.201838 -247.534446) (xy 132.235586 -247.496352)
			(xy 132.275008 -247.464165) (xy 132.319082 -247.438719) (xy 132.366668 -247.420672) (xy 132.416532 -247.410492)
			(xy 132.467384 -247.408443) (xy 132.517905 -247.414577) (xy 132.566789 -247.428737) (xy 132.612768 -247.450554)
			(xy 132.654652 -247.479464) (xy 132.691356 -247.514719) (xy 132.721929 -247.555405) (xy 132.74558 -247.600468)
			(xy 132.761696 -247.648742) (xy 132.76986 -247.698976) (xy 132.770372 -247.724422) (xy 132.76986 -247.749868)
			(xy 132.761696 -247.800102) (xy 132.74558 -247.848376) (xy 132.721929 -247.893439) (xy 132.691356 -247.934125)
			(xy 132.654652 -247.96938) (xy 132.612768 -247.99829) (xy 132.566789 -248.020107) (xy 132.517905 -248.034267)
			(xy 132.467384 -248.040401) (xy 132.416532 -248.038352) (xy 132.366668 -248.028172) (xy 132.319082 -248.010125)
			(xy 132.275008 -247.984679) (xy 132.235586 -247.952492) (xy 132.201838 -247.914398) (xy 132.174637 -247.871384)
			(xy 132.154689 -247.824564) (xy 132.14251 -247.77515) (xy 132.138415 -247.724422) (xy 131.830572 -247.724422)
			(xy 131.83006 -247.749868) (xy 131.821896 -247.800102) (xy 131.80578 -247.848376) (xy 131.782129 -247.893439)
			(xy 131.751556 -247.934125) (xy 131.714852 -247.96938) (xy 131.672968 -247.99829) (xy 131.626989 -248.020107)
			(xy 131.578105 -248.034267) (xy 131.527584 -248.040401) (xy 131.476732 -248.038352) (xy 131.426868 -248.028172)
			(xy 131.379282 -248.010125) (xy 131.335208 -247.984679) (xy 131.295786 -247.952492) (xy 131.262038 -247.914398)
			(xy 131.234837 -247.871384) (xy 131.214889 -247.824564) (xy 131.20271 -247.77515) (xy 131.198615 -247.724422)
			(xy 130.880104 -247.724422) (xy 130.879609 -247.749029) (xy 130.871714 -247.797606) (xy 130.85613 -247.844287)
			(xy 130.833259 -247.887864) (xy 130.803694 -247.927208) (xy 130.768201 -247.9613) (xy 130.727698 -247.989256)
			(xy 130.683236 -248.010354) (xy 130.635965 -248.024046) (xy 130.58711 -248.029978) (xy 130.537935 -248.027997)
			(xy 130.489716 -248.018153) (xy 130.4437 -248.000701) (xy 130.401079 -247.976094) (xy 130.362958 -247.944969)
			(xy 130.330323 -247.908132) (xy 130.30402 -247.866536) (xy 130.284729 -247.82126) (xy 130.272952 -247.773476)
			(xy 130.268992 -247.724422) (xy 129.950464 -247.724422) (xy 129.949952 -247.749868) (xy 129.941788 -247.800102)
			(xy 129.925672 -247.848376) (xy 129.902021 -247.893439) (xy 129.871448 -247.934125) (xy 129.834744 -247.96938)
			(xy 129.79286 -247.99829) (xy 129.746881 -248.020107) (xy 129.697997 -248.034267) (xy 129.647476 -248.040401)
			(xy 129.596624 -248.038352) (xy 129.54676 -248.028172) (xy 129.499174 -248.010125) (xy 129.4551 -247.984679)
			(xy 129.415678 -247.952492) (xy 129.38193 -247.914398) (xy 129.354729 -247.871384) (xy 129.334781 -247.824564)
			(xy 129.322602 -247.77515) (xy 129.318507 -247.724422) (xy 128.999996 -247.724422) (xy 128.999501 -247.749029)
			(xy 128.991606 -247.797606) (xy 128.976022 -247.844287) (xy 128.953151 -247.887864) (xy 128.923586 -247.927208)
			(xy 128.888093 -247.9613) (xy 128.84759 -247.989256) (xy 128.803128 -248.010354) (xy 128.755857 -248.024046)
			(xy 128.707002 -248.029978) (xy 128.657827 -248.027997) (xy 128.609608 -248.018153) (xy 128.563592 -248.000701)
			(xy 128.520971 -247.976094) (xy 128.48285 -247.944969) (xy 128.450215 -247.908132) (xy 128.423912 -247.866536)
			(xy 128.404621 -247.82126) (xy 128.392844 -247.773476) (xy 128.388884 -247.724422) (xy 128.070356 -247.724422)
			(xy 128.069844 -247.749868) (xy 128.06168 -247.800102) (xy 128.045564 -247.848376) (xy 128.021913 -247.893439)
			(xy 127.99134 -247.934125) (xy 127.954636 -247.96938) (xy 127.912752 -247.99829) (xy 127.866773 -248.020107)
			(xy 127.817889 -248.034267) (xy 127.767368 -248.040401) (xy 127.716516 -248.038352) (xy 127.666652 -248.028172)
			(xy 127.619066 -248.010125) (xy 127.574992 -247.984679) (xy 127.53557 -247.952492) (xy 127.501822 -247.914398)
			(xy 127.474621 -247.871384) (xy 127.454673 -247.824564) (xy 127.442494 -247.77515) (xy 127.438399 -247.724422)
			(xy 127.120636 -247.724422) (xy 127.116854 -247.772333) (xy 127.105602 -247.819066) (xy 127.08716 -247.863455)
			(xy 127.061984 -247.904403) (xy 127.030698 -247.940896) (xy 127.0127 -247.956832) (xy 127.004681 -247.964406)
			(xy 126.995474 -247.984423) (xy 126.99492 -247.99544) (xy 126.99492 -248.173748) (xy 126.99492 -248.174764)
			(xy 126.995612 -248.185526) (xy 127.004807 -248.20501) (xy 127.0127 -248.212356) (xy 127.019558 -248.217182)
			(xy 127.093726 -248.26214) (xy 127.101362 -248.266321) (xy 127.118409 -248.269794) (xy 127.135639 -248.267382)
			(xy 127.14351 -248.263664) (xy 127.165447 -248.252791) (xy 127.211922 -248.237394) (xy 127.260255 -248.22959)
			(xy 127.284734 -248.22912) (xy 127.290068 -248.22912) (xy 127.313785 -248.22998) (xy 127.360535 -248.238133)
			(xy 127.405461 -248.253423) (xy 127.447479 -248.275482) (xy 127.485576 -248.303779) (xy 127.518835 -248.337631)
			(xy 127.546453 -248.376222) (xy 127.567766 -248.418623) (xy 127.58226 -248.463812) (xy 127.589585 -248.5107)
			(xy 127.590042 -248.534428) (xy 127.908553 -248.534428) (xy 127.912648 -248.4837) (xy 127.924827 -248.434286)
			(xy 127.944775 -248.387466) (xy 127.971976 -248.344452) (xy 128.005724 -248.306358) (xy 128.045146 -248.274171)
			(xy 128.08922 -248.248725) (xy 128.136806 -248.230678) (xy 128.18667 -248.220498) (xy 128.237522 -248.218449)
			(xy 128.288043 -248.224583) (xy 128.336927 -248.238743) (xy 128.382906 -248.26056) (xy 128.42479 -248.28947)
			(xy 128.461494 -248.324725) (xy 128.492067 -248.365411) (xy 128.515718 -248.410474) (xy 128.531834 -248.458748)
			(xy 128.539998 -248.508982) (xy 128.54051 -248.534428) (xy 128.848607 -248.534428) (xy 128.852702 -248.4837)
			(xy 128.864881 -248.434286) (xy 128.884829 -248.387466) (xy 128.91203 -248.344452) (xy 128.945778 -248.306358)
			(xy 128.9852 -248.274171) (xy 129.029274 -248.248725) (xy 129.07686 -248.230678) (xy 129.126724 -248.220498)
			(xy 129.177576 -248.218449) (xy 129.228097 -248.224583) (xy 129.276981 -248.238743) (xy 129.32296 -248.26056)
			(xy 129.364844 -248.28947) (xy 129.401548 -248.324725) (xy 129.432121 -248.365411) (xy 129.455772 -248.410474)
			(xy 129.471888 -248.458748) (xy 129.480052 -248.508982) (xy 129.480564 -248.534428) (xy 129.798838 -248.534428)
			(xy 129.802798 -248.485374) (xy 129.814575 -248.43759) (xy 129.833866 -248.392314) (xy 129.860169 -248.350718)
			(xy 129.892804 -248.313881) (xy 129.930925 -248.282756) (xy 129.973546 -248.258149) (xy 130.019562 -248.240697)
			(xy 130.067781 -248.230853) (xy 130.116956 -248.228872) (xy 130.165811 -248.234804) (xy 130.213082 -248.248496)
			(xy 130.257544 -248.269594) (xy 130.298047 -248.29755) (xy 130.33354 -248.331642) (xy 130.363105 -248.370986)
			(xy 130.385976 -248.414563) (xy 130.40156 -248.461244) (xy 130.409455 -248.509821) (xy 130.40995 -248.534428)
			(xy 130.728461 -248.534428) (xy 130.732556 -248.4837) (xy 130.744735 -248.434286) (xy 130.764683 -248.387466)
			(xy 130.791884 -248.344452) (xy 130.825632 -248.306358) (xy 130.865054 -248.274171) (xy 130.909128 -248.248725)
			(xy 130.956714 -248.230678) (xy 131.006578 -248.220498) (xy 131.05743 -248.218449) (xy 131.107951 -248.224583)
			(xy 131.156835 -248.238743) (xy 131.202814 -248.26056) (xy 131.244698 -248.28947) (xy 131.281402 -248.324725)
			(xy 131.311975 -248.365411) (xy 131.335626 -248.410474) (xy 131.351742 -248.458748) (xy 131.359906 -248.508982)
			(xy 131.360418 -248.534428) (xy 131.678946 -248.534428) (xy 131.682906 -248.485374) (xy 131.694683 -248.43759)
			(xy 131.713974 -248.392314) (xy 131.740277 -248.350718) (xy 131.772912 -248.313881) (xy 131.811033 -248.282756)
			(xy 131.853654 -248.258149) (xy 131.89967 -248.240697) (xy 131.947889 -248.230853) (xy 131.997064 -248.228872)
			(xy 132.045919 -248.234804) (xy 132.09319 -248.248496) (xy 132.137652 -248.269594) (xy 132.178155 -248.29755)
			(xy 132.213648 -248.331642) (xy 132.243213 -248.370986) (xy 132.266084 -248.414563) (xy 132.281668 -248.461244)
			(xy 132.289563 -248.509821) (xy 132.290058 -248.534428) (xy 132.608569 -248.534428) (xy 132.612664 -248.4837)
			(xy 132.624843 -248.434286) (xy 132.644791 -248.387466) (xy 132.671992 -248.344452) (xy 132.70574 -248.306358)
			(xy 132.745162 -248.274171) (xy 132.789236 -248.248725) (xy 132.836822 -248.230678) (xy 132.886686 -248.220498)
			(xy 132.937538 -248.218449) (xy 132.988059 -248.224583) (xy 133.036943 -248.238743) (xy 133.082922 -248.26056)
			(xy 133.124806 -248.28947) (xy 133.16151 -248.324725) (xy 133.192083 -248.365411) (xy 133.215734 -248.410474)
			(xy 133.23185 -248.458748) (xy 133.240014 -248.508982) (xy 133.240526 -248.534428) (xy 133.240014 -248.559874)
			(xy 133.23185 -248.610108) (xy 133.215734 -248.658382) (xy 133.192083 -248.703445) (xy 133.16151 -248.744131)
			(xy 133.124806 -248.779386) (xy 133.082922 -248.808296) (xy 133.036943 -248.830113) (xy 132.988059 -248.844273)
			(xy 132.937538 -248.850407) (xy 132.886686 -248.848358) (xy 132.836822 -248.838178) (xy 132.789236 -248.820131)
			(xy 132.745162 -248.794685) (xy 132.70574 -248.762498) (xy 132.671992 -248.724404) (xy 132.644791 -248.68139)
			(xy 132.624843 -248.63457) (xy 132.612664 -248.585156) (xy 132.608569 -248.534428) (xy 132.290058 -248.534428)
			(xy 132.289563 -248.559035) (xy 132.281668 -248.607612) (xy 132.266084 -248.654293) (xy 132.243213 -248.69787)
			(xy 132.213648 -248.737214) (xy 132.178155 -248.771306) (xy 132.137652 -248.799262) (xy 132.09319 -248.82036)
			(xy 132.045919 -248.834052) (xy 131.997064 -248.839984) (xy 131.947889 -248.838003) (xy 131.89967 -248.828159)
			(xy 131.853654 -248.810707) (xy 131.811033 -248.7861) (xy 131.772912 -248.754975) (xy 131.740277 -248.718138)
			(xy 131.713974 -248.676542) (xy 131.694683 -248.631266) (xy 131.682906 -248.583482) (xy 131.678946 -248.534428)
			(xy 131.360418 -248.534428) (xy 131.359906 -248.559874) (xy 131.351742 -248.610108) (xy 131.335626 -248.658382)
			(xy 131.311975 -248.703445) (xy 131.281402 -248.744131) (xy 131.244698 -248.779386) (xy 131.202814 -248.808296)
			(xy 131.156835 -248.830113) (xy 131.107951 -248.844273) (xy 131.05743 -248.850407) (xy 131.006578 -248.848358)
			(xy 130.956714 -248.838178) (xy 130.909128 -248.820131) (xy 130.865054 -248.794685) (xy 130.825632 -248.762498)
			(xy 130.791884 -248.724404) (xy 130.764683 -248.68139) (xy 130.744735 -248.63457) (xy 130.732556 -248.585156)
			(xy 130.728461 -248.534428) (xy 130.40995 -248.534428) (xy 130.409455 -248.559035) (xy 130.40156 -248.607612)
			(xy 130.385976 -248.654293) (xy 130.363105 -248.69787) (xy 130.33354 -248.737214) (xy 130.298047 -248.771306)
			(xy 130.257544 -248.799262) (xy 130.213082 -248.82036) (xy 130.165811 -248.834052) (xy 130.116956 -248.839984)
			(xy 130.067781 -248.838003) (xy 130.019562 -248.828159) (xy 129.973546 -248.810707) (xy 129.930925 -248.7861)
			(xy 129.892804 -248.754975) (xy 129.860169 -248.718138) (xy 129.833866 -248.676542) (xy 129.814575 -248.631266)
			(xy 129.802798 -248.583482) (xy 129.798838 -248.534428) (xy 129.480564 -248.534428) (xy 129.480052 -248.559874)
			(xy 129.471888 -248.610108) (xy 129.455772 -248.658382) (xy 129.432121 -248.703445) (xy 129.401548 -248.744131)
			(xy 129.364844 -248.779386) (xy 129.32296 -248.808296) (xy 129.276981 -248.830113) (xy 129.228097 -248.844273)
			(xy 129.177576 -248.850407) (xy 129.126724 -248.848358) (xy 129.07686 -248.838178) (xy 129.029274 -248.820131)
			(xy 128.9852 -248.794685) (xy 128.945778 -248.762498) (xy 128.91203 -248.724404) (xy 128.884829 -248.68139)
			(xy 128.864881 -248.63457) (xy 128.852702 -248.585156) (xy 128.848607 -248.534428) (xy 128.54051 -248.534428)
			(xy 128.539998 -248.559874) (xy 128.531834 -248.610108) (xy 128.515718 -248.658382) (xy 128.492067 -248.703445)
			(xy 128.461494 -248.744131) (xy 128.42479 -248.779386) (xy 128.382906 -248.808296) (xy 128.336927 -248.830113)
			(xy 128.288043 -248.844273) (xy 128.237522 -248.850407) (xy 128.18667 -248.848358) (xy 128.136806 -248.838178)
			(xy 128.08922 -248.820131) (xy 128.045146 -248.794685) (xy 128.005724 -248.762498) (xy 127.971976 -248.724404)
			(xy 127.944775 -248.68139) (xy 127.924827 -248.63457) (xy 127.912648 -248.585156) (xy 127.908553 -248.534428)
			(xy 127.590042 -248.534428) (xy 127.589569 -248.558419) (xy 127.58206 -248.605809) (xy 127.567231 -248.651442)
			(xy 127.545446 -248.694193) (xy 127.517243 -248.73301) (xy 127.483315 -248.766939) (xy 127.444498 -248.795143)
			(xy 127.401747 -248.816928) (xy 127.356115 -248.831759) (xy 127.308725 -248.839269) (xy 127.284734 -248.839736)
			(xy 127.28448 -248.839736) (xy 127.260041 -248.839257) (xy 127.21179 -248.831463) (xy 127.165403 -248.816063)
			(xy 127.14351 -248.805192) (xy 127.135643 -248.801455) (xy 127.11841 -248.799012) (xy 127.101365 -248.802527)
			(xy 127.093726 -248.806716) (xy 127.019558 -248.851674) (xy 127.0127 -248.8565) (xy 127.004844 -248.863873)
			(xy 126.995658 -248.883341) (xy 126.99492 -248.894092) (xy 126.99492 -249.073416) (xy 126.995464 -249.084432)
			(xy 127.00469 -249.10444) (xy 127.0127 -249.112024) (xy 127.030717 -249.127936) (xy 127.061998 -249.164431)
			(xy 127.087168 -249.205381) (xy 127.105604 -249.249772) (xy 127.11685 -249.296504) (xy 127.120628 -249.344422)
			(xy 127.120627 -249.344434) (xy 127.438399 -249.344434) (xy 127.442494 -249.293706) (xy 127.454673 -249.244292)
			(xy 127.474621 -249.197472) (xy 127.501822 -249.154458) (xy 127.53557 -249.116364) (xy 127.574992 -249.084177)
			(xy 127.619066 -249.058731) (xy 127.666652 -249.040684) (xy 127.716516 -249.030504) (xy 127.767368 -249.028455)
			(xy 127.817889 -249.034589) (xy 127.866773 -249.048749) (xy 127.912752 -249.070566) (xy 127.954636 -249.099476)
			(xy 127.99134 -249.134731) (xy 128.021913 -249.175417) (xy 128.045564 -249.22048) (xy 128.06168 -249.268754)
			(xy 128.069844 -249.318988) (xy 128.070356 -249.344434) (xy 128.388884 -249.344434) (xy 128.392844 -249.29538)
			(xy 128.404621 -249.247596) (xy 128.423912 -249.20232) (xy 128.450215 -249.160724) (xy 128.48285 -249.123887)
			(xy 128.520971 -249.092762) (xy 128.563592 -249.068155) (xy 128.609608 -249.050703) (xy 128.657827 -249.040859)
			(xy 128.707002 -249.038878) (xy 128.755857 -249.04481) (xy 128.803128 -249.058502) (xy 128.84759 -249.0796)
			(xy 128.888093 -249.107556) (xy 128.923586 -249.141648) (xy 128.953151 -249.180992) (xy 128.976022 -249.224569)
			(xy 128.991606 -249.27125) (xy 128.999501 -249.319827) (xy 128.999996 -249.344434) (xy 129.328938 -249.344434)
			(xy 129.332898 -249.29538) (xy 129.344675 -249.247596) (xy 129.363966 -249.20232) (xy 129.390269 -249.160724)
			(xy 129.422904 -249.123887) (xy 129.461025 -249.092762) (xy 129.503646 -249.068155) (xy 129.549662 -249.050703)
			(xy 129.597881 -249.040859) (xy 129.647056 -249.038878) (xy 129.695911 -249.04481) (xy 129.743182 -249.058502)
			(xy 129.787644 -249.0796) (xy 129.828147 -249.107556) (xy 129.86364 -249.141648) (xy 129.893205 -249.180992)
			(xy 129.916076 -249.224569) (xy 129.93166 -249.27125) (xy 129.939555 -249.319827) (xy 129.94005 -249.344434)
			(xy 131.198615 -249.344434) (xy 131.20271 -249.293706) (xy 131.214889 -249.244292) (xy 131.234837 -249.197472)
			(xy 131.262038 -249.154458) (xy 131.295786 -249.116364) (xy 131.335208 -249.084177) (xy 131.379282 -249.058731)
			(xy 131.426868 -249.040684) (xy 131.476732 -249.030504) (xy 131.527584 -249.028455) (xy 131.578105 -249.034589)
			(xy 131.626989 -249.048749) (xy 131.672968 -249.070566) (xy 131.714852 -249.099476) (xy 131.751556 -249.134731)
			(xy 131.782129 -249.175417) (xy 131.80578 -249.22048) (xy 131.821896 -249.268754) (xy 131.83006 -249.318988)
			(xy 131.830572 -249.344434) (xy 132.148846 -249.344434) (xy 132.152806 -249.29538) (xy 132.164583 -249.247596)
			(xy 132.183874 -249.20232) (xy 132.210177 -249.160724) (xy 132.242812 -249.123887) (xy 132.280933 -249.092762)
			(xy 132.323554 -249.068155) (xy 132.36957 -249.050703) (xy 132.417789 -249.040859) (xy 132.466964 -249.038878)
			(xy 132.515819 -249.04481) (xy 132.56309 -249.058502) (xy 132.607552 -249.0796) (xy 132.648055 -249.107556)
			(xy 132.683548 -249.141648) (xy 132.713113 -249.180992) (xy 132.735984 -249.224569) (xy 132.751568 -249.27125)
			(xy 132.759463 -249.319827) (xy 132.759958 -249.344434) (xy 132.759463 -249.369041) (xy 132.751568 -249.417618)
			(xy 132.735984 -249.464299) (xy 132.713113 -249.507876) (xy 132.683548 -249.54722) (xy 132.648055 -249.581312)
			(xy 132.607552 -249.609268) (xy 132.56309 -249.630366) (xy 132.515819 -249.644058) (xy 132.466964 -249.64999)
			(xy 132.417789 -249.648009) (xy 132.36957 -249.638165) (xy 132.323554 -249.620713) (xy 132.280933 -249.596106)
			(xy 132.242812 -249.564981) (xy 132.210177 -249.528144) (xy 132.183874 -249.486548) (xy 132.164583 -249.441272)
			(xy 132.152806 -249.393488) (xy 132.148846 -249.344434) (xy 131.830572 -249.344434) (xy 131.83006 -249.36988)
			(xy 131.821896 -249.420114) (xy 131.80578 -249.468388) (xy 131.782129 -249.513451) (xy 131.751556 -249.554137)
			(xy 131.714852 -249.589392) (xy 131.672968 -249.618302) (xy 131.626989 -249.640119) (xy 131.578105 -249.654279)
			(xy 131.527584 -249.660413) (xy 131.476732 -249.658364) (xy 131.426868 -249.648184) (xy 131.379282 -249.630137)
			(xy 131.335208 -249.604691) (xy 131.295786 -249.572504) (xy 131.262038 -249.53441) (xy 131.234837 -249.491396)
			(xy 131.214889 -249.444576) (xy 131.20271 -249.395162) (xy 131.198615 -249.344434) (xy 129.94005 -249.344434)
			(xy 129.939555 -249.369041) (xy 129.93166 -249.417618) (xy 129.916076 -249.464299) (xy 129.893205 -249.507876)
			(xy 129.86364 -249.54722) (xy 129.828147 -249.581312) (xy 129.787644 -249.609268) (xy 129.743182 -249.630366)
			(xy 129.695911 -249.644058) (xy 129.647056 -249.64999) (xy 129.597881 -249.648009) (xy 129.549662 -249.638165)
			(xy 129.503646 -249.620713) (xy 129.461025 -249.596106) (xy 129.422904 -249.564981) (xy 129.390269 -249.528144)
			(xy 129.363966 -249.486548) (xy 129.344675 -249.441272) (xy 129.332898 -249.393488) (xy 129.328938 -249.344434)
			(xy 128.999996 -249.344434) (xy 128.999501 -249.369041) (xy 128.991606 -249.417618) (xy 128.976022 -249.464299)
			(xy 128.953151 -249.507876) (xy 128.923586 -249.54722) (xy 128.888093 -249.581312) (xy 128.84759 -249.609268)
			(xy 128.803128 -249.630366) (xy 128.755857 -249.644058) (xy 128.707002 -249.64999) (xy 128.657827 -249.648009)
			(xy 128.609608 -249.638165) (xy 128.563592 -249.620713) (xy 128.520971 -249.596106) (xy 128.48285 -249.564981)
			(xy 128.450215 -249.528144) (xy 128.423912 -249.486548) (xy 128.404621 -249.441272) (xy 128.392844 -249.393488)
			(xy 128.388884 -249.344434) (xy 128.070356 -249.344434) (xy 128.069844 -249.36988) (xy 128.06168 -249.420114)
			(xy 128.045564 -249.468388) (xy 128.021913 -249.513451) (xy 127.99134 -249.554137) (xy 127.954636 -249.589392)
			(xy 127.912752 -249.618302) (xy 127.866773 -249.640119) (xy 127.817889 -249.654279) (xy 127.767368 -249.660413)
			(xy 127.716516 -249.658364) (xy 127.666652 -249.648184) (xy 127.619066 -249.630137) (xy 127.574992 -249.604691)
			(xy 127.53557 -249.572504) (xy 127.501822 -249.53441) (xy 127.474621 -249.491396) (xy 127.454673 -249.444576)
			(xy 127.442494 -249.395162) (xy 127.438399 -249.344434) (xy 127.120627 -249.344434) (xy 127.116843 -249.39234)
			(xy 127.10559 -249.43907) (xy 127.087148 -249.483458) (xy 127.061972 -249.524404) (xy 127.030686 -249.560895)
			(xy 127.0127 -249.576844) (xy 127.004683 -249.584418) (xy 126.99548 -249.604436) (xy 126.99492 -249.615452)
			(xy 126.99492 -250.15444) (xy 127.908553 -250.15444) (xy 127.912648 -250.103712) (xy 127.924827 -250.054298)
			(xy 127.944775 -250.007478) (xy 127.971976 -249.964464) (xy 128.005724 -249.92637) (xy 128.045146 -249.894183)
			(xy 128.08922 -249.868737) (xy 128.136806 -249.85069) (xy 128.18667 -249.84051) (xy 128.237522 -249.838461)
			(xy 128.288043 -249.844595) (xy 128.336927 -249.858755) (xy 128.382906 -249.880572) (xy 128.42479 -249.909482)
			(xy 128.461494 -249.944737) (xy 128.492067 -249.985423) (xy 128.515718 -250.030486) (xy 128.531834 -250.07876)
			(xy 128.539998 -250.128994) (xy 128.54051 -250.15444) (xy 128.859038 -250.15444) (xy 128.862998 -250.105386)
			(xy 128.874775 -250.057602) (xy 128.894066 -250.012326) (xy 128.920369 -249.97073) (xy 128.953004 -249.933893)
			(xy 128.991125 -249.902768) (xy 129.033746 -249.878161) (xy 129.079762 -249.860709) (xy 129.127981 -249.850865)
			(xy 129.177156 -249.848884) (xy 129.226011 -249.854816) (xy 129.273282 -249.868508) (xy 129.317744 -249.889606)
			(xy 129.358247 -249.917562) (xy 129.39374 -249.951654) (xy 129.423305 -249.990998) (xy 129.446176 -250.034575)
			(xy 129.46176 -250.081256) (xy 129.469655 -250.129833) (xy 129.47015 -250.15444) (xy 129.798838 -250.15444)
			(xy 129.802798 -250.105386) (xy 129.814575 -250.057602) (xy 129.833866 -250.012326) (xy 129.860169 -249.97073)
			(xy 129.892804 -249.933893) (xy 129.930925 -249.902768) (xy 129.973546 -249.878161) (xy 130.019562 -249.860709)
			(xy 130.067781 -249.850865) (xy 130.116956 -249.848884) (xy 130.165811 -249.854816) (xy 130.213082 -249.868508)
			(xy 130.257544 -249.889606) (xy 130.298047 -249.917562) (xy 130.33354 -249.951654) (xy 130.363105 -249.990998)
			(xy 130.385976 -250.034575) (xy 130.40156 -250.081256) (xy 130.409455 -250.129833) (xy 130.40995 -250.15444)
			(xy 130.728461 -250.15444) (xy 130.732556 -250.103712) (xy 130.744735 -250.054298) (xy 130.764683 -250.007478)
			(xy 130.791884 -249.964464) (xy 130.825632 -249.92637) (xy 130.865054 -249.894183) (xy 130.909128 -249.868737)
			(xy 130.956714 -249.85069) (xy 131.006578 -249.84051) (xy 131.05743 -249.838461) (xy 131.107951 -249.844595)
			(xy 131.156835 -249.858755) (xy 131.202814 -249.880572) (xy 131.244698 -249.909482) (xy 131.281402 -249.944737)
			(xy 131.311975 -249.985423) (xy 131.335626 -250.030486) (xy 131.351742 -250.07876) (xy 131.359906 -250.128994)
			(xy 131.360418 -250.15444) (xy 131.678946 -250.15444) (xy 131.682906 -250.105386) (xy 131.694683 -250.057602)
			(xy 131.713974 -250.012326) (xy 131.740277 -249.97073) (xy 131.772912 -249.933893) (xy 131.811033 -249.902768)
			(xy 131.853654 -249.878161) (xy 131.89967 -249.860709) (xy 131.947889 -249.850865) (xy 131.997064 -249.848884)
			(xy 132.045919 -249.854816) (xy 132.09319 -249.868508) (xy 132.137652 -249.889606) (xy 132.178155 -249.917562)
			(xy 132.213648 -249.951654) (xy 132.243213 -249.990998) (xy 132.266084 -250.034575) (xy 132.281668 -250.081256)
			(xy 132.289563 -250.129833) (xy 132.290058 -250.15444) (xy 132.619 -250.15444) (xy 132.62296 -250.105386)
			(xy 132.634737 -250.057602) (xy 132.654028 -250.012326) (xy 132.680331 -249.97073) (xy 132.712966 -249.933893)
			(xy 132.751087 -249.902768) (xy 132.793708 -249.878161) (xy 132.839724 -249.860709) (xy 132.887943 -249.850865)
			(xy 132.937118 -249.848884) (xy 132.985973 -249.854816) (xy 133.033244 -249.868508) (xy 133.077706 -249.889606)
			(xy 133.118209 -249.917562) (xy 133.153702 -249.951654) (xy 133.183267 -249.990998) (xy 133.206138 -250.034575)
			(xy 133.221722 -250.081256) (xy 133.229617 -250.129833) (xy 133.230112 -250.15444) (xy 133.229617 -250.179047)
			(xy 133.221722 -250.227624) (xy 133.206138 -250.274305) (xy 133.183267 -250.317882) (xy 133.153702 -250.357226)
			(xy 133.118209 -250.391318) (xy 133.077706 -250.419274) (xy 133.033244 -250.440372) (xy 132.985973 -250.454064)
			(xy 132.937118 -250.459996) (xy 132.887943 -250.458015) (xy 132.839724 -250.448171) (xy 132.793708 -250.430719)
			(xy 132.751087 -250.406112) (xy 132.712966 -250.374987) (xy 132.680331 -250.33815) (xy 132.654028 -250.296554)
			(xy 132.634737 -250.251278) (xy 132.62296 -250.203494) (xy 132.619 -250.15444) (xy 132.290058 -250.15444)
			(xy 132.289563 -250.179047) (xy 132.281668 -250.227624) (xy 132.266084 -250.274305) (xy 132.243213 -250.317882)
			(xy 132.213648 -250.357226) (xy 132.178155 -250.391318) (xy 132.137652 -250.419274) (xy 132.09319 -250.440372)
			(xy 132.045919 -250.454064) (xy 131.997064 -250.459996) (xy 131.947889 -250.458015) (xy 131.89967 -250.448171)
			(xy 131.853654 -250.430719) (xy 131.811033 -250.406112) (xy 131.772912 -250.374987) (xy 131.740277 -250.33815)
			(xy 131.713974 -250.296554) (xy 131.694683 -250.251278) (xy 131.682906 -250.203494) (xy 131.678946 -250.15444)
			(xy 131.360418 -250.15444) (xy 131.359906 -250.179886) (xy 131.351742 -250.23012) (xy 131.335626 -250.278394)
			(xy 131.311975 -250.323457) (xy 131.281402 -250.364143) (xy 131.244698 -250.399398) (xy 131.202814 -250.428308)
			(xy 131.156835 -250.450125) (xy 131.107951 -250.464285) (xy 131.05743 -250.470419) (xy 131.006578 -250.46837)
			(xy 130.956714 -250.45819) (xy 130.909128 -250.440143) (xy 130.865054 -250.414697) (xy 130.825632 -250.38251)
			(xy 130.791884 -250.344416) (xy 130.764683 -250.301402) (xy 130.744735 -250.254582) (xy 130.732556 -250.205168)
			(xy 130.728461 -250.15444) (xy 130.40995 -250.15444) (xy 130.409455 -250.179047) (xy 130.40156 -250.227624)
			(xy 130.385976 -250.274305) (xy 130.363105 -250.317882) (xy 130.33354 -250.357226) (xy 130.298047 -250.391318)
			(xy 130.257544 -250.419274) (xy 130.213082 -250.440372) (xy 130.165811 -250.454064) (xy 130.116956 -250.459996)
			(xy 130.067781 -250.458015) (xy 130.019562 -250.448171) (xy 129.973546 -250.430719) (xy 129.930925 -250.406112)
			(xy 129.892804 -250.374987) (xy 129.860169 -250.33815) (xy 129.833866 -250.296554) (xy 129.814575 -250.251278)
			(xy 129.802798 -250.203494) (xy 129.798838 -250.15444) (xy 129.47015 -250.15444) (xy 129.469655 -250.179047)
			(xy 129.46176 -250.227624) (xy 129.446176 -250.274305) (xy 129.423305 -250.317882) (xy 129.39374 -250.357226)
			(xy 129.358247 -250.391318) (xy 129.317744 -250.419274) (xy 129.273282 -250.440372) (xy 129.226011 -250.454064)
			(xy 129.177156 -250.459996) (xy 129.127981 -250.458015) (xy 129.079762 -250.448171) (xy 129.033746 -250.430719)
			(xy 128.991125 -250.406112) (xy 128.953004 -250.374987) (xy 128.920369 -250.33815) (xy 128.894066 -250.296554)
			(xy 128.874775 -250.251278) (xy 128.862998 -250.203494) (xy 128.859038 -250.15444) (xy 128.54051 -250.15444)
			(xy 128.539998 -250.179886) (xy 128.531834 -250.23012) (xy 128.515718 -250.278394) (xy 128.492067 -250.323457)
			(xy 128.461494 -250.364143) (xy 128.42479 -250.399398) (xy 128.382906 -250.428308) (xy 128.336927 -250.450125)
			(xy 128.288043 -250.464285) (xy 128.237522 -250.470419) (xy 128.18667 -250.46837) (xy 128.136806 -250.45819)
			(xy 128.08922 -250.440143) (xy 128.045146 -250.414697) (xy 128.005724 -250.38251) (xy 127.971976 -250.344416)
			(xy 127.944775 -250.301402) (xy 127.924827 -250.254582) (xy 127.912648 -250.205168) (xy 127.908553 -250.15444)
			(xy 126.99492 -250.15444) (xy 126.99492 -250.693428) (xy 126.995466 -250.704443) (xy 127.004695 -250.724448)
			(xy 127.0127 -250.732036) (xy 127.032476 -250.749593) (xy 127.066251 -250.79028) (xy 127.092506 -250.83618)
			(xy 127.110456 -250.885918) (xy 127.119563 -250.938007) (xy 127.120142 -250.964446) (xy 127.438399 -250.964446)
			(xy 127.442494 -250.913718) (xy 127.454673 -250.864304) (xy 127.474621 -250.817484) (xy 127.501822 -250.77447)
			(xy 127.53557 -250.736376) (xy 127.574992 -250.704189) (xy 127.619066 -250.678743) (xy 127.666652 -250.660696)
			(xy 127.716516 -250.650516) (xy 127.767368 -250.648467) (xy 127.817889 -250.654601) (xy 127.866773 -250.668761)
			(xy 127.912752 -250.690578) (xy 127.954636 -250.719488) (xy 127.99134 -250.754743) (xy 128.021913 -250.795429)
			(xy 128.045564 -250.840492) (xy 128.06168 -250.888766) (xy 128.069844 -250.939) (xy 128.070356 -250.964446)
			(xy 128.388884 -250.964446) (xy 128.392844 -250.915392) (xy 128.404621 -250.867608) (xy 128.423912 -250.822332)
			(xy 128.450215 -250.780736) (xy 128.48285 -250.743899) (xy 128.520971 -250.712774) (xy 128.563592 -250.688167)
			(xy 128.609608 -250.670715) (xy 128.657827 -250.660871) (xy 128.707002 -250.65889) (xy 128.755857 -250.664822)
			(xy 128.803128 -250.678514) (xy 128.84759 -250.699612) (xy 128.888093 -250.727568) (xy 128.923586 -250.76166)
			(xy 128.953151 -250.801004) (xy 128.976022 -250.844581) (xy 128.991606 -250.891262) (xy 128.999501 -250.939839)
			(xy 128.999996 -250.964446) (xy 129.318507 -250.964446) (xy 129.322602 -250.913718) (xy 129.334781 -250.864304)
			(xy 129.354729 -250.817484) (xy 129.38193 -250.77447) (xy 129.415678 -250.736376) (xy 129.4551 -250.704189)
			(xy 129.499174 -250.678743) (xy 129.54676 -250.660696) (xy 129.596624 -250.650516) (xy 129.647476 -250.648467)
			(xy 129.697997 -250.654601) (xy 129.746881 -250.668761) (xy 129.79286 -250.690578) (xy 129.834744 -250.719488)
			(xy 129.871448 -250.754743) (xy 129.902021 -250.795429) (xy 129.925672 -250.840492) (xy 129.941788 -250.888766)
			(xy 129.949952 -250.939) (xy 129.950464 -250.964446) (xy 130.268992 -250.964446) (xy 130.272952 -250.915392)
			(xy 130.284729 -250.867608) (xy 130.30402 -250.822332) (xy 130.330323 -250.780736) (xy 130.362958 -250.743899)
			(xy 130.401079 -250.712774) (xy 130.4437 -250.688167) (xy 130.489716 -250.670715) (xy 130.537935 -250.660871)
			(xy 130.58711 -250.65889) (xy 130.635965 -250.664822) (xy 130.683236 -250.678514) (xy 130.727698 -250.699612)
			(xy 130.768201 -250.727568) (xy 130.803694 -250.76166) (xy 130.833259 -250.801004) (xy 130.85613 -250.844581)
			(xy 130.871714 -250.891262) (xy 130.879609 -250.939839) (xy 130.880104 -250.964446) (xy 131.198615 -250.964446)
			(xy 131.20271 -250.913718) (xy 131.214889 -250.864304) (xy 131.234837 -250.817484) (xy 131.262038 -250.77447)
			(xy 131.295786 -250.736376) (xy 131.335208 -250.704189) (xy 131.379282 -250.678743) (xy 131.426868 -250.660696)
			(xy 131.476732 -250.650516) (xy 131.527584 -250.648467) (xy 131.578105 -250.654601) (xy 131.626989 -250.668761)
			(xy 131.672968 -250.690578) (xy 131.714852 -250.719488) (xy 131.751556 -250.754743) (xy 131.782129 -250.795429)
			(xy 131.80578 -250.840492) (xy 131.821896 -250.888766) (xy 131.83006 -250.939) (xy 131.830572 -250.964446)
			(xy 132.138415 -250.964446) (xy 132.14251 -250.913718) (xy 132.154689 -250.864304) (xy 132.174637 -250.817484)
			(xy 132.201838 -250.77447) (xy 132.235586 -250.736376) (xy 132.275008 -250.704189) (xy 132.319082 -250.678743)
			(xy 132.366668 -250.660696) (xy 132.416532 -250.650516) (xy 132.467384 -250.648467) (xy 132.517905 -250.654601)
			(xy 132.566789 -250.668761) (xy 132.612768 -250.690578) (xy 132.654652 -250.719488) (xy 132.691356 -250.754743)
			(xy 132.721929 -250.795429) (xy 132.74558 -250.840492) (xy 132.761696 -250.888766) (xy 132.76986 -250.939)
			(xy 132.770372 -250.964446) (xy 132.76986 -250.989892) (xy 132.761696 -251.040126) (xy 132.74558 -251.0884)
			(xy 132.721929 -251.133463) (xy 132.691356 -251.174149) (xy 132.654652 -251.209404) (xy 132.612768 -251.238314)
			(xy 132.566789 -251.260131) (xy 132.517905 -251.274291) (xy 132.467384 -251.280425) (xy 132.416532 -251.278376)
			(xy 132.366668 -251.268196) (xy 132.319082 -251.250149) (xy 132.275008 -251.224703) (xy 132.235586 -251.192516)
			(xy 132.201838 -251.154422) (xy 132.174637 -251.111408) (xy 132.154689 -251.064588) (xy 132.14251 -251.015174)
			(xy 132.138415 -250.964446) (xy 131.830572 -250.964446) (xy 131.83006 -250.989892) (xy 131.821896 -251.040126)
			(xy 131.80578 -251.0884) (xy 131.782129 -251.133463) (xy 131.751556 -251.174149) (xy 131.714852 -251.209404)
			(xy 131.672968 -251.238314) (xy 131.626989 -251.260131) (xy 131.578105 -251.274291) (xy 131.527584 -251.280425)
			(xy 131.476732 -251.278376) (xy 131.426868 -251.268196) (xy 131.379282 -251.250149) (xy 131.335208 -251.224703)
			(xy 131.295786 -251.192516) (xy 131.262038 -251.154422) (xy 131.234837 -251.111408) (xy 131.214889 -251.064588)
			(xy 131.20271 -251.015174) (xy 131.198615 -250.964446) (xy 130.880104 -250.964446) (xy 130.879609 -250.989053)
			(xy 130.871714 -251.03763) (xy 130.85613 -251.084311) (xy 130.833259 -251.127888) (xy 130.803694 -251.167232)
			(xy 130.768201 -251.201324) (xy 130.727698 -251.22928) (xy 130.683236 -251.250378) (xy 130.635965 -251.26407)
			(xy 130.58711 -251.270002) (xy 130.537935 -251.268021) (xy 130.489716 -251.258177) (xy 130.4437 -251.240725)
			(xy 130.401079 -251.216118) (xy 130.362958 -251.184993) (xy 130.330323 -251.148156) (xy 130.30402 -251.10656)
			(xy 130.284729 -251.061284) (xy 130.272952 -251.0135) (xy 130.268992 -250.964446) (xy 129.950464 -250.964446)
			(xy 129.949952 -250.989892) (xy 129.941788 -251.040126) (xy 129.925672 -251.0884) (xy 129.902021 -251.133463)
			(xy 129.871448 -251.174149) (xy 129.834744 -251.209404) (xy 129.79286 -251.238314) (xy 129.746881 -251.260131)
			(xy 129.697997 -251.274291) (xy 129.647476 -251.280425) (xy 129.596624 -251.278376) (xy 129.54676 -251.268196)
			(xy 129.499174 -251.250149) (xy 129.4551 -251.224703) (xy 129.415678 -251.192516) (xy 129.38193 -251.154422)
			(xy 129.354729 -251.111408) (xy 129.334781 -251.064588) (xy 129.322602 -251.015174) (xy 129.318507 -250.964446)
			(xy 128.999996 -250.964446) (xy 128.999501 -250.989053) (xy 128.991606 -251.03763) (xy 128.976022 -251.084311)
			(xy 128.953151 -251.127888) (xy 128.923586 -251.167232) (xy 128.888093 -251.201324) (xy 128.84759 -251.22928)
			(xy 128.803128 -251.250378) (xy 128.755857 -251.26407) (xy 128.707002 -251.270002) (xy 128.657827 -251.268021)
			(xy 128.609608 -251.258177) (xy 128.563592 -251.240725) (xy 128.520971 -251.216118) (xy 128.48285 -251.184993)
			(xy 128.450215 -251.148156) (xy 128.423912 -251.10656) (xy 128.404621 -251.061284) (xy 128.392844 -251.0135)
			(xy 128.388884 -250.964446) (xy 128.070356 -250.964446) (xy 128.069844 -250.989892) (xy 128.06168 -251.040126)
			(xy 128.045564 -251.0884) (xy 128.021913 -251.133463) (xy 127.99134 -251.174149) (xy 127.954636 -251.209404)
			(xy 127.912752 -251.238314) (xy 127.866773 -251.260131) (xy 127.817889 -251.274291) (xy 127.767368 -251.280425)
			(xy 127.716516 -251.278376) (xy 127.666652 -251.268196) (xy 127.619066 -251.250149) (xy 127.574992 -251.224703)
			(xy 127.53557 -251.192516) (xy 127.501822 -251.154422) (xy 127.474621 -251.111408) (xy 127.454673 -251.064588)
			(xy 127.442494 -251.015174) (xy 127.438399 -250.964446) (xy 127.120142 -250.964446) (xy 127.119668 -250.988436)
			(xy 127.112156 -251.035824) (xy 127.097325 -251.081454) (xy 127.07554 -251.124203) (xy 127.047336 -251.163018)
			(xy 127.013409 -251.196944) (xy 126.974593 -251.225146) (xy 126.931843 -251.24693) (xy 126.886212 -251.261759)
			(xy 126.838824 -251.269269) (xy 126.814834 -251.269754) (xy 126.799876 -251.269573) (xy 126.770104 -251.26665)
			(xy 126.755398 -251.263912) (xy 126.742952 -251.261372) (xy 126.718822 -251.268738) (xy 126.566676 -251.420884)
			(xy 126.559949 -251.428211) (xy 126.552212 -251.446513) (xy 126.55169 -251.456444) (xy 126.550928 -251.53747)
			(xy 126.558294 -251.555758) (xy 126.565152 -251.563124) (xy 126.580979 -251.580293) (xy 126.607764 -251.618541)
			(xy 126.628416 -251.66042) (xy 126.642455 -251.704954) (xy 126.649553 -251.751105) (xy 126.649988 -251.774452)
			(xy 127.908553 -251.774452) (xy 127.912648 -251.723724) (xy 127.924827 -251.67431) (xy 127.944775 -251.62749)
			(xy 127.971976 -251.584476) (xy 128.005724 -251.546382) (xy 128.045146 -251.514195) (xy 128.08922 -251.488749)
			(xy 128.136806 -251.470702) (xy 128.18667 -251.460522) (xy 128.237522 -251.458473) (xy 128.288043 -251.464607)
			(xy 128.336927 -251.478767) (xy 128.382906 -251.500584) (xy 128.42479 -251.529494) (xy 128.461494 -251.564749)
			(xy 128.492067 -251.605435) (xy 128.515718 -251.650498) (xy 128.531834 -251.698772) (xy 128.539998 -251.749006)
			(xy 128.54051 -251.774452) (xy 128.859038 -251.774452) (xy 128.862998 -251.725398) (xy 128.874775 -251.677614)
			(xy 128.894066 -251.632338) (xy 128.920369 -251.590742) (xy 128.953004 -251.553905) (xy 128.991125 -251.52278)
			(xy 129.033746 -251.498173) (xy 129.079762 -251.480721) (xy 129.127981 -251.470877) (xy 129.177156 -251.468896)
			(xy 129.226011 -251.474828) (xy 129.273282 -251.48852) (xy 129.317744 -251.509618) (xy 129.358247 -251.537574)
			(xy 129.39374 -251.571666) (xy 129.423305 -251.61101) (xy 129.446176 -251.654587) (xy 129.46176 -251.701268)
			(xy 129.469655 -251.749845) (xy 129.47015 -251.774452) (xy 130.728461 -251.774452) (xy 130.732556 -251.723724)
			(xy 130.744735 -251.67431) (xy 130.764683 -251.62749) (xy 130.791884 -251.584476) (xy 130.825632 -251.546382)
			(xy 130.865054 -251.514195) (xy 130.909128 -251.488749) (xy 130.956714 -251.470702) (xy 131.006578 -251.460522)
			(xy 131.05743 -251.458473) (xy 131.107951 -251.464607) (xy 131.156835 -251.478767) (xy 131.202814 -251.500584)
			(xy 131.244698 -251.529494) (xy 131.281402 -251.564749) (xy 131.311975 -251.605435) (xy 131.335626 -251.650498)
			(xy 131.351742 -251.698772) (xy 131.359906 -251.749006) (xy 131.360418 -251.774452) (xy 131.678946 -251.774452)
			(xy 131.682906 -251.725398) (xy 131.694683 -251.677614) (xy 131.713974 -251.632338) (xy 131.740277 -251.590742)
			(xy 131.772912 -251.553905) (xy 131.811033 -251.52278) (xy 131.853654 -251.498173) (xy 131.89967 -251.480721)
			(xy 131.947889 -251.470877) (xy 131.997064 -251.468896) (xy 132.045919 -251.474828) (xy 132.09319 -251.48852)
			(xy 132.137652 -251.509618) (xy 132.178155 -251.537574) (xy 132.213648 -251.571666) (xy 132.243213 -251.61101)
			(xy 132.266084 -251.654587) (xy 132.281668 -251.701268) (xy 132.289563 -251.749845) (xy 132.290058 -251.774452)
			(xy 132.619 -251.774452) (xy 132.62296 -251.725398) (xy 132.634737 -251.677614) (xy 132.654028 -251.632338)
			(xy 132.680331 -251.590742) (xy 132.712966 -251.553905) (xy 132.751087 -251.52278) (xy 132.793708 -251.498173)
			(xy 132.839724 -251.480721) (xy 132.887943 -251.470877) (xy 132.937118 -251.468896) (xy 132.985973 -251.474828)
			(xy 133.033244 -251.48852) (xy 133.077706 -251.509618) (xy 133.118209 -251.537574) (xy 133.153702 -251.571666)
			(xy 133.183267 -251.61101) (xy 133.206138 -251.654587) (xy 133.221722 -251.701268) (xy 133.229617 -251.749845)
			(xy 133.230112 -251.774452) (xy 133.229617 -251.799059) (xy 133.221722 -251.847636) (xy 133.206138 -251.894317)
			(xy 133.183267 -251.937894) (xy 133.153702 -251.977238) (xy 133.118209 -252.01133) (xy 133.077706 -252.039286)
			(xy 133.033244 -252.060384) (xy 132.985973 -252.074076) (xy 132.937118 -252.080008) (xy 132.887943 -252.078027)
			(xy 132.839724 -252.068183) (xy 132.793708 -252.050731) (xy 132.751087 -252.026124) (xy 132.712966 -251.994999)
			(xy 132.680331 -251.958162) (xy 132.654028 -251.916566) (xy 132.634737 -251.87129) (xy 132.62296 -251.823506)
			(xy 132.619 -251.774452) (xy 132.290058 -251.774452) (xy 132.289563 -251.799059) (xy 132.281668 -251.847636)
			(xy 132.266084 -251.894317) (xy 132.243213 -251.937894) (xy 132.213648 -251.977238) (xy 132.178155 -252.01133)
			(xy 132.137652 -252.039286) (xy 132.09319 -252.060384) (xy 132.045919 -252.074076) (xy 131.997064 -252.080008)
			(xy 131.947889 -252.078027) (xy 131.89967 -252.068183) (xy 131.853654 -252.050731) (xy 131.811033 -252.026124)
			(xy 131.772912 -251.994999) (xy 131.740277 -251.958162) (xy 131.713974 -251.916566) (xy 131.694683 -251.87129)
			(xy 131.682906 -251.823506) (xy 131.678946 -251.774452) (xy 131.360418 -251.774452) (xy 131.359906 -251.799898)
			(xy 131.351742 -251.850132) (xy 131.335626 -251.898406) (xy 131.311975 -251.943469) (xy 131.281402 -251.984155)
			(xy 131.244698 -252.01941) (xy 131.202814 -252.04832) (xy 131.156835 -252.070137) (xy 131.107951 -252.084297)
			(xy 131.05743 -252.090431) (xy 131.006578 -252.088382) (xy 130.956714 -252.078202) (xy 130.909128 -252.060155)
			(xy 130.865054 -252.034709) (xy 130.825632 -252.002522) (xy 130.791884 -251.964428) (xy 130.764683 -251.921414)
			(xy 130.744735 -251.874594) (xy 130.732556 -251.82518) (xy 130.728461 -251.774452) (xy 129.47015 -251.774452)
			(xy 129.469655 -251.799059) (xy 129.46176 -251.847636) (xy 129.446176 -251.894317) (xy 129.423305 -251.937894)
			(xy 129.39374 -251.977238) (xy 129.358247 -252.01133) (xy 129.317744 -252.039286) (xy 129.273282 -252.060384)
			(xy 129.226011 -252.074076) (xy 129.177156 -252.080008) (xy 129.127981 -252.078027) (xy 129.079762 -252.068183)
			(xy 129.033746 -252.050731) (xy 128.991125 -252.026124) (xy 128.953004 -251.994999) (xy 128.920369 -251.958162)
			(xy 128.894066 -251.916566) (xy 128.874775 -251.87129) (xy 128.862998 -251.823506) (xy 128.859038 -251.774452)
			(xy 128.54051 -251.774452) (xy 128.539998 -251.799898) (xy 128.531834 -251.850132) (xy 128.515718 -251.898406)
			(xy 128.492067 -251.943469) (xy 128.461494 -251.984155) (xy 128.42479 -252.01941) (xy 128.382906 -252.04832)
			(xy 128.336927 -252.070137) (xy 128.288043 -252.084297) (xy 128.237522 -252.090431) (xy 128.18667 -252.088382)
			(xy 128.136806 -252.078202) (xy 128.08922 -252.060155) (xy 128.045146 -252.034709) (xy 128.005724 -252.002522)
			(xy 127.971976 -251.964428) (xy 127.944775 -251.921414) (xy 127.924827 -251.874594) (xy 127.912648 -251.82518)
			(xy 127.908553 -251.774452) (xy 126.649988 -251.774452) (xy 126.649545 -251.798447) (xy 126.642044 -251.845847)
			(xy 126.62722 -251.89149) (xy 126.605437 -251.934251) (xy 126.577232 -251.973078) (xy 126.543299 -252.007013)
			(xy 126.504475 -252.035222) (xy 126.461716 -252.057009) (xy 126.416074 -252.071838) (xy 126.368675 -252.079343)
			(xy 126.34468 -252.07976) (xy 126.320917 -252.079306) (xy 126.273964 -252.071939) (xy 126.22872 -252.057387)
			(xy 126.186276 -252.036001) (xy 126.147659 -252.008297) (xy 126.1138 -251.974945) (xy 126.085517 -251.93675)
			(xy 126.063494 -251.894634) (xy 126.048261 -251.849614) (xy 126.040187 -251.802778) (xy 126.039372 -251.779024)
			(xy 126.039372 -251.775976) (xy 126.039372 -251.774452) (xy 126.040133 -251.743695) (xy 126.052414 -251.683418)
			(xy 126.063756 -251.654818) (xy 126.063756 -251.654564) (xy 126.068064 -251.642729) (xy 126.065811 -251.617674)
			(xy 126.059438 -251.606812) (xy 126.012702 -251.5362) (xy 126.005178 -251.526025) (xy 125.98292 -251.514055)
			(xy 125.970284 -251.51334) (xy 124.839222 -251.51334) (xy 124.826577 -251.514011) (xy 124.804314 -251.526005)
			(xy 124.796804 -251.5362) (xy 124.750068 -251.606812) (xy 124.743702 -251.617679) (xy 124.741442 -251.642729)
			(xy 124.74575 -251.654564) (xy 124.74575 -251.654818) (xy 124.757098 -251.683416) (xy 124.769376 -251.743694)
			(xy 124.770134 -251.774452) (xy 124.770134 -251.779024) (xy 124.769258 -251.804032) (xy 124.760361 -251.85327)
			(xy 124.743557 -251.9004) (xy 124.719293 -251.944159) (xy 124.688219 -251.983376) (xy 124.651167 -252.017002)
			(xy 124.609128 -252.044138) (xy 124.563228 -252.064056) (xy 124.514694 -252.076225) (xy 124.464826 -252.080317)
			(xy 124.414958 -252.076225) (xy 124.366424 -252.064056) (xy 124.320524 -252.044138) (xy 124.278485 -252.017002)
			(xy 124.241433 -251.983376) (xy 124.210359 -251.944159) (xy 124.186095 -251.9004) (xy 124.169291 -251.85327)
			(xy 124.160394 -251.804032) (xy 124.159518 -251.779024) (xy 124.159518 -251.775976) (xy 124.159518 -251.774452)
			(xy 124.16028 -251.743695) (xy 124.172562 -251.683419) (xy 124.183902 -251.654818) (xy 124.183902 -251.654564)
			(xy 124.188208 -251.642728) (xy 124.185957 -251.617673) (xy 124.179584 -251.606812) (xy 124.132848 -251.5362)
			(xy 124.125328 -251.526017) (xy 124.10307 -251.514027) (xy 124.09043 -251.51334) (xy 122.959114 -251.51334)
			(xy 122.94647 -251.514012) (xy 122.92421 -251.526009) (xy 122.916696 -251.5362) (xy 122.86996 -251.606812)
			(xy 122.863595 -251.617679) (xy 122.861335 -251.642729) (xy 122.865642 -251.654564) (xy 122.865642 -251.654818)
			(xy 122.876991 -251.683416) (xy 122.889269 -251.743694) (xy 122.890026 -251.774452) (xy 122.890026 -251.779024)
			(xy 122.88915 -251.804032) (xy 122.880253 -251.85327) (xy 122.863449 -251.9004) (xy 122.839185 -251.944159)
			(xy 122.808111 -251.983376) (xy 122.771059 -252.017002) (xy 122.72902 -252.044138) (xy 122.68312 -252.064056)
			(xy 122.634586 -252.076225) (xy 122.584718 -252.080317) (xy 122.53485 -252.076225) (xy 122.486316 -252.064056)
			(xy 122.440416 -252.044138) (xy 122.398377 -252.017002) (xy 122.361325 -251.983376) (xy 122.330251 -251.944159)
			(xy 122.305987 -251.9004) (xy 122.289183 -251.85327) (xy 122.280286 -251.804032) (xy 122.27941 -251.779024)
			(xy 122.27941 -251.775976) (xy 122.27941 -251.774452) (xy 122.280172 -251.743695) (xy 122.292454 -251.683418)
			(xy 122.303794 -251.654818) (xy 122.303794 -251.654564) (xy 122.308101 -251.642728) (xy 122.305849 -251.617673)
			(xy 122.299476 -251.606812) (xy 122.25274 -251.5362) (xy 122.245219 -251.526019) (xy 122.222962 -251.514032)
			(xy 122.210322 -251.51334) (xy 121.079006 -251.51334) (xy 121.066363 -251.514014) (xy 121.044106 -251.526012)
			(xy 121.036588 -251.5362) (xy 120.989852 -251.606812) (xy 120.983479 -251.617677) (xy 120.981214 -251.642732)
			(xy 120.985534 -251.654564) (xy 120.985534 -251.654818) (xy 120.996883 -251.683416) (xy 121.009161 -251.743694)
			(xy 121.009918 -251.774452) (xy 121.009918 -251.779024) (xy 121.009042 -251.804032) (xy 121.000145 -251.85327)
			(xy 120.983341 -251.9004) (xy 120.959077 -251.944159) (xy 120.928003 -251.983376) (xy 120.890951 -252.017002)
			(xy 120.848912 -252.044138) (xy 120.803012 -252.064056) (xy 120.754478 -252.076225) (xy 120.70461 -252.080317)
			(xy 120.654742 -252.076225) (xy 120.606208 -252.064056) (xy 120.560308 -252.044138) (xy 120.518269 -252.017002)
			(xy 120.481217 -251.983376) (xy 120.450143 -251.944159) (xy 120.425879 -251.9004) (xy 120.409075 -251.85327)
			(xy 120.400178 -251.804032) (xy 120.399302 -251.779024) (xy 120.399302 -251.775976) (xy 120.399302 -251.774452)
			(xy 120.400064 -251.743695) (xy 120.412345 -251.683418) (xy 120.423686 -251.654818) (xy 120.423686 -251.654564)
			(xy 120.427993 -251.642728) (xy 120.425741 -251.617674) (xy 120.419368 -251.606812) (xy 120.372632 -251.5362)
			(xy 120.36511 -251.52602) (xy 120.342853 -251.514037) (xy 120.330214 -251.51334) (xy 119.199152 -251.51334)
			(xy 119.186503 -251.514004) (xy 119.164228 -251.525991) (xy 119.156734 -251.5362) (xy 119.109998 -251.606812)
			(xy 119.10363 -251.617678) (xy 119.101368 -251.64273) (xy 119.10568 -251.654564) (xy 119.10568 -251.654818)
			(xy 119.117027 -251.683416) (xy 119.129304 -251.743694) (xy 119.130064 -251.774452) (xy 119.130064 -251.779024)
			(xy 119.129188 -251.804032) (xy 119.120291 -251.85327) (xy 119.103487 -251.9004) (xy 119.079223 -251.944159)
			(xy 119.048149 -251.983376) (xy 119.011097 -252.017002) (xy 118.969058 -252.044138) (xy 118.923158 -252.064056)
			(xy 118.874624 -252.076225) (xy 118.824756 -252.080317) (xy 118.774888 -252.076225) (xy 118.726354 -252.064056)
			(xy 118.680454 -252.044138) (xy 118.638415 -252.017002) (xy 118.601363 -251.983376) (xy 118.570289 -251.944159)
			(xy 118.546025 -251.9004) (xy 118.529221 -251.85327) (xy 118.520324 -251.804032) (xy 118.519448 -251.779024)
			(xy 118.519448 -251.775976) (xy 118.519448 -251.774452) (xy 118.520209 -251.743695) (xy 118.532489 -251.683417)
			(xy 118.543832 -251.654818) (xy 118.543832 -251.654564) (xy 118.548141 -251.642729) (xy 118.545888 -251.617674)
			(xy 118.539514 -251.606812) (xy 118.492778 -251.5362) (xy 118.48526 -251.526012) (xy 118.463003 -251.514009)
			(xy 118.45036 -251.51334) (xy 117.319044 -251.51334) (xy 117.306396 -251.514006) (xy 117.284124 -251.525995)
			(xy 117.276626 -251.5362) (xy 117.22989 -251.606812) (xy 117.223522 -251.617678) (xy 117.221261 -251.64273)
			(xy 117.225572 -251.654564) (xy 117.225572 -251.654818) (xy 117.23692 -251.683416) (xy 117.249196 -251.743694)
			(xy 117.249956 -251.774452) (xy 117.249956 -251.779024) (xy 117.24908 -251.804032) (xy 117.240183 -251.85327)
			(xy 117.223379 -251.9004) (xy 117.199115 -251.944159) (xy 117.168041 -251.983376) (xy 117.130989 -252.017002)
			(xy 117.08895 -252.044138) (xy 117.04305 -252.064056) (xy 116.994516 -252.076225) (xy 116.944648 -252.080317)
			(xy 116.89478 -252.076225) (xy 116.846246 -252.064056) (xy 116.800346 -252.044138) (xy 116.758307 -252.017002)
			(xy 116.721255 -251.983376) (xy 116.690181 -251.944159) (xy 116.665917 -251.9004) (xy 116.649113 -251.85327)
			(xy 116.640216 -251.804032) (xy 116.63934 -251.779024) (xy 116.63934 -251.775976) (xy 116.63934 -251.774452)
			(xy 116.640101 -251.743694) (xy 116.652381 -251.683417) (xy 116.663724 -251.654818) (xy 116.663724 -251.654564)
			(xy 116.668034 -251.642729) (xy 116.66578 -251.617674) (xy 116.659406 -251.606812) (xy 116.61267 -251.5362)
			(xy 116.605151 -251.526014) (xy 116.582894 -251.514014) (xy 116.570252 -251.51334) (xy 115.43919 -251.51334)
			(xy 115.426549 -251.514018) (xy 115.404298 -251.52602) (xy 115.396772 -251.5362) (xy 115.350036 -251.606812)
			(xy 115.343664 -251.617677) (xy 115.341401 -251.642731) (xy 115.345718 -251.654564) (xy 115.345718 -251.654818)
			(xy 115.357067 -251.683416) (xy 115.369346 -251.743693) (xy 115.370102 -251.774452) (xy 115.370102 -251.779024)
			(xy 115.369226 -251.804032) (xy 115.360329 -251.85327) (xy 115.343525 -251.9004) (xy 115.319261 -251.944159)
			(xy 115.288187 -251.983376) (xy 115.251135 -252.017002) (xy 115.209096 -252.044138) (xy 115.163196 -252.064056)
			(xy 115.114662 -252.076225) (xy 115.064794 -252.080317) (xy 115.014926 -252.076225) (xy 114.966392 -252.064056)
			(xy 114.920492 -252.044138) (xy 114.878453 -252.017002) (xy 114.841401 -251.983376) (xy 114.810327 -251.944159)
			(xy 114.786063 -251.9004) (xy 114.769259 -251.85327) (xy 114.760362 -251.804032) (xy 114.759486 -251.779024)
			(xy 114.759486 -251.775976) (xy 114.759486 -251.774452) (xy 114.760247 -251.743695) (xy 114.772529 -251.683418)
			(xy 114.78387 -251.654818) (xy 114.78387 -251.654564) (xy 114.788178 -251.642729) (xy 114.785926 -251.617674)
			(xy 114.779552 -251.606812) (xy 114.732816 -251.5362) (xy 114.725293 -251.526023) (xy 114.703036 -251.514046)
			(xy 114.690398 -251.51334) (xy 113.559082 -251.51334) (xy 113.546442 -251.514019) (xy 113.524194 -251.526023)
			(xy 113.516664 -251.5362) (xy 113.469928 -251.606812) (xy 113.463557 -251.617677) (xy 113.461294 -251.642731)
			(xy 113.46561 -251.654564) (xy 113.46561 -251.654818) (xy 113.47696 -251.683416) (xy 113.489239 -251.743693)
			(xy 113.489994 -251.774452) (xy 113.489994 -251.779024) (xy 113.489118 -251.804032) (xy 113.480221 -251.85327)
			(xy 113.463417 -251.9004) (xy 113.439153 -251.944159) (xy 113.408079 -251.983376) (xy 113.371027 -252.017002)
			(xy 113.328988 -252.044138) (xy 113.283088 -252.064056) (xy 113.234554 -252.076225) (xy 113.184686 -252.080317)
			(xy 113.134818 -252.076225) (xy 113.086284 -252.064056) (xy 113.040384 -252.044138) (xy 112.998345 -252.017002)
			(xy 112.961293 -251.983376) (xy 112.930219 -251.944159) (xy 112.905955 -251.9004) (xy 112.889151 -251.85327)
			(xy 112.880254 -251.804032) (xy 112.879378 -251.779024) (xy 112.879378 -251.775976) (xy 112.879378 -251.774452)
			(xy 112.880139 -251.743695) (xy 112.89242 -251.683418) (xy 112.903762 -251.654818) (xy 112.903762 -251.654564)
			(xy 112.90807 -251.642729) (xy 112.905817 -251.617674) (xy 112.899444 -251.606812) (xy 112.852708 -251.5362)
			(xy 112.845185 -251.526024) (xy 112.822927 -251.514051) (xy 112.81029 -251.51334) (xy 112.620044 -251.51334)
			(xy 112.595406 -251.529342) (xy 112.589056 -251.543058) (xy 112.577746 -251.56667) (xy 112.549042 -251.610452)
			(xy 112.514026 -251.649369) (xy 112.473507 -251.682521) (xy 112.428426 -251.709138) (xy 112.379827 -251.728603)
			(xy 112.328836 -251.740465) (xy 112.276636 -251.74445) (xy 112.224436 -251.740465) (xy 112.173445 -251.728603)
			(xy 112.124846 -251.709138) (xy 112.079765 -251.682521) (xy 112.039246 -251.649369) (xy 112.00423 -251.610452)
			(xy 111.975526 -251.56667) (xy 111.964216 -251.543058) (xy 111.957866 -251.529342) (xy 111.933228 -251.51334)
			(xy 111.73333 -251.51334) (xy 111.70793 -251.530104) (xy 111.701834 -251.544328) (xy 111.69088 -251.568997)
			(xy 111.662817 -251.615105) (xy 111.628332 -251.656629) (xy 111.588163 -251.692683) (xy 111.543167 -251.722496)
			(xy 111.494306 -251.745432) (xy 111.442624 -251.761) (xy 111.389224 -251.768868) (xy 111.335248 -251.768868)
			(xy 111.281848 -251.761) (xy 111.230166 -251.745432) (xy 111.181305 -251.722496) (xy 111.136309 -251.692683)
			(xy 111.09614 -251.656629) (xy 111.061655 -251.615105) (xy 111.033592 -251.568997) (xy 111.022638 -251.544328)
			(xy 111.016542 -251.530104) (xy 110.991142 -251.51334) (xy 109.80547 -251.51334) (xy 109.792832 -251.514022)
			(xy 109.770588 -251.526029) (xy 109.763052 -251.5362) (xy 109.716316 -251.606812) (xy 109.709946 -251.617677)
			(xy 109.707683 -251.642731) (xy 109.711998 -251.654564) (xy 109.711998 -251.654818) (xy 109.723345 -251.683416)
			(xy 109.73562 -251.743694) (xy 109.736382 -251.774452) (xy 109.736382 -251.779024) (xy 109.735506 -251.804032)
			(xy 109.726609 -251.85327) (xy 109.709805 -251.9004) (xy 109.685541 -251.944159) (xy 109.654467 -251.983376)
			(xy 109.617415 -252.017002) (xy 109.575376 -252.044138) (xy 109.529476 -252.064056) (xy 109.480942 -252.076225)
			(xy 109.431074 -252.080317) (xy 109.381206 -252.076225) (xy 109.332672 -252.064056) (xy 109.286772 -252.044138)
			(xy 109.244733 -252.017002) (xy 109.207681 -251.983376) (xy 109.176607 -251.944159) (xy 109.152343 -251.9004)
			(xy 109.135539 -251.85327) (xy 109.126642 -251.804032) (xy 109.125766 -251.779024) (xy 109.125766 -251.775976)
			(xy 109.125766 -251.774452) (xy 109.126527 -251.743695) (xy 109.138808 -251.683418) (xy 109.15015 -251.654818)
			(xy 109.15015 -251.654564) (xy 109.154458 -251.642729) (xy 109.152206 -251.617674) (xy 109.145832 -251.606812)
			(xy 109.099096 -251.5362) (xy 109.091572 -251.526026) (xy 109.069314 -251.514059) (xy 109.056678 -251.51334)
			(xy 107.925362 -251.51334) (xy 107.912725 -251.514024) (xy 107.890484 -251.526032) (xy 107.882944 -251.5362)
			(xy 107.836208 -251.606812) (xy 107.829839 -251.617678) (xy 107.827577 -251.64273) (xy 107.83189 -251.654564)
			(xy 107.83189 -251.654818) (xy 107.843237 -251.683416) (xy 107.855513 -251.743694) (xy 107.856274 -251.774452)
			(xy 107.856274 -251.779024) (xy 107.855398 -251.804032) (xy 107.846501 -251.85327) (xy 107.829697 -251.9004)
			(xy 107.805433 -251.944159) (xy 107.774359 -251.983376) (xy 107.737307 -252.017002) (xy 107.695268 -252.044138)
			(xy 107.649368 -252.064056) (xy 107.600834 -252.076225) (xy 107.550966 -252.080317) (xy 107.501098 -252.076225)
			(xy 107.452564 -252.064056) (xy 107.406664 -252.044138) (xy 107.364625 -252.017002) (xy 107.327573 -251.983376)
			(xy 107.296499 -251.944159) (xy 107.272235 -251.9004) (xy 107.255431 -251.85327) (xy 107.246534 -251.804032)
			(xy 107.245658 -251.779024) (xy 107.245658 -251.775976) (xy 107.245658 -251.774452) (xy 107.246419 -251.743695)
			(xy 107.2587 -251.683418) (xy 107.270042 -251.654818) (xy 107.270042 -251.654564) (xy 107.274351 -251.642729)
			(xy 107.272098 -251.617674) (xy 107.265724 -251.606812) (xy 107.218988 -251.5362) (xy 107.211471 -251.526011)
			(xy 107.189214 -251.514003) (xy 107.17657 -251.51334) (xy 106.045508 -251.51334) (xy 106.032865 -251.514014)
			(xy 106.010607 -251.526011) (xy 106.00309 -251.5362) (xy 105.956354 -251.606812) (xy 105.94998 -251.617677)
			(xy 105.947716 -251.642732) (xy 105.952036 -251.654564) (xy 105.952036 -251.654818) (xy 105.963385 -251.683416)
			(xy 105.975663 -251.743694) (xy 105.97642 -251.774452) (xy 105.97642 -251.779024) (xy 105.975544 -251.804032)
			(xy 105.966647 -251.85327) (xy 105.949843 -251.9004) (xy 105.925579 -251.944159) (xy 105.894505 -251.983376)
			(xy 105.857453 -252.017002) (xy 105.815414 -252.044138) (xy 105.769514 -252.064056) (xy 105.72098 -252.076225)
			(xy 105.671112 -252.080317) (xy 105.621244 -252.076225) (xy 105.57271 -252.064056) (xy 105.52681 -252.044138)
			(xy 105.484771 -252.017002) (xy 105.447719 -251.983376) (xy 105.416645 -251.944159) (xy 105.392381 -251.9004)
			(xy 105.375577 -251.85327) (xy 105.36668 -251.804032) (xy 105.365804 -251.779024) (xy 105.365804 -251.775976)
			(xy 105.365804 -251.774452) (xy 105.366566 -251.743695) (xy 105.378848 -251.683418) (xy 105.390188 -251.654818)
			(xy 105.390188 -251.654564) (xy 105.394494 -251.642728) (xy 105.392243 -251.617674) (xy 105.38587 -251.606812)
			(xy 105.339134 -251.5362) (xy 105.331613 -251.52602) (xy 105.309355 -251.514036) (xy 105.296716 -251.51334)
			(xy 104.1654 -251.51334) (xy 104.152758 -251.514015) (xy 104.130503 -251.526015) (xy 104.122982 -251.5362)
			(xy 104.076246 -251.606812) (xy 104.069873 -251.617677) (xy 104.067609 -251.642731) (xy 104.071928 -251.654564)
			(xy 104.071928 -251.654818) (xy 104.083277 -251.683416) (xy 104.095556 -251.743694) (xy 104.096312 -251.774452)
			(xy 104.096312 -251.779024) (xy 104.095436 -251.804032) (xy 104.086539 -251.85327) (xy 104.069735 -251.9004)
			(xy 104.045471 -251.944159) (xy 104.014397 -251.983376) (xy 103.977345 -252.017002) (xy 103.935306 -252.044138)
			(xy 103.889406 -252.064056) (xy 103.840872 -252.076225) (xy 103.791004 -252.080317) (xy 103.741136 -252.076225)
			(xy 103.692602 -252.064056) (xy 103.646702 -252.044138) (xy 103.604663 -252.017002) (xy 103.567611 -251.983376)
			(xy 103.536537 -251.944159) (xy 103.512273 -251.9004) (xy 103.495469 -251.85327) (xy 103.486572 -251.804032)
			(xy 103.485696 -251.779024) (xy 103.485696 -251.775976) (xy 103.485696 -251.774452) (xy 103.486458 -251.743695)
			(xy 103.498739 -251.683418) (xy 103.51008 -251.654818) (xy 103.51008 -251.654564) (xy 103.514387 -251.642728)
			(xy 103.512135 -251.617674) (xy 103.505762 -251.606812) (xy 103.459026 -251.5362) (xy 103.451504 -251.526021)
			(xy 103.429247 -251.51404) (xy 103.416608 -251.51334) (xy 102.285546 -251.51334) (xy 102.272898 -251.514005)
			(xy 102.250625 -251.525994) (xy 102.243128 -251.5362) (xy 102.196392 -251.606812) (xy 102.190024 -251.617678)
			(xy 102.187763 -251.64273) (xy 102.192074 -251.654564) (xy 102.192074 -251.654818) (xy 102.203421 -251.683416)
			(xy 102.215698 -251.743694) (xy 102.216458 -251.774452) (xy 102.216458 -251.779024) (xy 102.215582 -251.804032)
			(xy 102.206685 -251.85327) (xy 102.189881 -251.9004) (xy 102.165617 -251.944159) (xy 102.134543 -251.983376)
			(xy 102.097491 -252.017002) (xy 102.055452 -252.044138) (xy 102.009552 -252.064056) (xy 101.961018 -252.076225)
			(xy 101.91115 -252.080317) (xy 101.861282 -252.076225) (xy 101.812748 -252.064056) (xy 101.766848 -252.044138)
			(xy 101.724809 -252.017002) (xy 101.687757 -251.983376) (xy 101.656683 -251.944159) (xy 101.632419 -251.9004)
			(xy 101.615615 -251.85327) (xy 101.606718 -251.804032) (xy 101.605842 -251.779024) (xy 101.605842 -251.775976)
			(xy 101.605842 -251.774452) (xy 101.606603 -251.743694) (xy 101.618883 -251.683417) (xy 101.630226 -251.654818)
			(xy 101.630226 -251.654564) (xy 101.634536 -251.642729) (xy 101.632282 -251.617674) (xy 101.625908 -251.606812)
			(xy 101.579172 -251.5362) (xy 101.571654 -251.526013) (xy 101.549396 -251.514012) (xy 101.536754 -251.51334)
			(xy 101.345492 -251.51334) (xy 101.332851 -251.514017) (xy 101.310599 -251.526019) (xy 101.303074 -251.5362)
			(xy 101.256338 -251.606812) (xy 101.249966 -251.617677) (xy 101.247703 -251.642731) (xy 101.25202 -251.654564)
			(xy 101.25202 -251.654818) (xy 101.263369 -251.683416) (xy 101.275648 -251.743693) (xy 101.276404 -251.774452)
			(xy 101.276404 -251.779024) (xy 101.275571 -251.802995) (xy 101.267356 -251.850248) (xy 101.251853 -251.895636)
			(xy 101.229445 -251.938041) (xy 101.200682 -251.976421) (xy 101.166272 -252.009832) (xy 101.127061 -252.037452)
			(xy 101.084014 -252.058602) (xy 101.03819 -252.072761) (xy 101.01453 -252.076712) (xy 101.002084 -252.07849)
			(xy 100.971096 -252.080014) (xy 100.947038 -252.079564) (xy 100.899518 -252.072024) (xy 100.853765 -252.05713)
			(xy 100.810912 -252.035252) (xy 100.772016 -252.006929) (xy 100.738039 -251.97286) (xy 100.70982 -251.933889)
			(xy 100.698554 -251.912628) (xy 100.692966 -251.901452) (xy 100.673408 -251.886974) (xy 100.58019 -251.871988)
			(xy 100.579428 -251.871988) (xy 100.567983 -251.870968) (xy 100.546091 -251.877838) (xy 100.537264 -251.885196)
			(xy 100.536248 -251.886212) (xy 100.474526 -251.947934) (xy 100.46716 -251.955046) (xy 100.45954 -251.973842)
			(xy 100.45954 -252.217936) (xy 100.466906 -252.236224) (xy 100.474018 -252.243336) (xy 100.501196 -252.27153)
			(xy 100.517452 -252.279404) (xy 100.52685 -252.280166) (xy 100.551929 -252.28284) (xy 100.600784 -252.295352)
			(xy 100.64692 -252.31572) (xy 100.689083 -252.343388) (xy 100.72613 -252.377607) (xy 100.757052 -252.417447)
			(xy 100.78101 -252.461824) (xy 100.797353 -252.509534) (xy 100.805638 -252.559281) (xy 100.805638 -252.584458)
			(xy 101.135192 -252.584458) (xy 101.139152 -252.535404) (xy 101.150929 -252.48762) (xy 101.17022 -252.442344)
			(xy 101.196523 -252.400748) (xy 101.229158 -252.363911) (xy 101.267279 -252.332786) (xy 101.3099 -252.308179)
			(xy 101.355916 -252.290727) (xy 101.404135 -252.280883) (xy 101.45331 -252.278902) (xy 101.502165 -252.284834)
			(xy 101.549436 -252.298526) (xy 101.593898 -252.319624) (xy 101.634401 -252.34758) (xy 101.669894 -252.381672)
			(xy 101.696114 -252.416564) (xy 111.913673 -252.416564) (xy 111.917703 -252.364066) (xy 111.9297 -252.312798)
			(xy 111.949383 -252.263963) (xy 111.976289 -252.218704) (xy 112.009789 -252.178083) (xy 112.049097 -252.143052)
			(xy 112.093292 -252.114432) (xy 112.141337 -252.092893) (xy 112.192108 -252.078941) (xy 112.244413 -252.072903)
			(xy 112.297027 -252.07492) (xy 112.348717 -252.084944) (xy 112.39827 -252.102742) (xy 112.444526 -252.127895)
			(xy 112.4864 -252.159814) (xy 112.522912 -252.197752) (xy 112.553204 -252.240818) (xy 112.576567 -252.288003)
			(xy 112.592453 -252.338202) (xy 112.60049 -252.390238) (xy 112.600994 -252.416564) (xy 112.60049 -252.44289)
			(xy 112.592453 -252.494926) (xy 112.576567 -252.545125) (xy 112.557092 -252.584458) (xy 120.86896 -252.584458)
			(xy 120.87292 -252.535404) (xy 120.884697 -252.48762) (xy 120.903988 -252.442344) (xy 120.930291 -252.400748)
			(xy 120.962926 -252.363911) (xy 121.001047 -252.332786) (xy 121.043668 -252.308179) (xy 121.089684 -252.290727)
			(xy 121.137903 -252.280883) (xy 121.187078 -252.278902) (xy 121.235933 -252.284834) (xy 121.283204 -252.298526)
			(xy 121.327666 -252.319624) (xy 121.368169 -252.34758) (xy 121.403662 -252.381672) (xy 121.433227 -252.421016)
			(xy 121.456098 -252.464593) (xy 121.471682 -252.511274) (xy 121.479577 -252.559851) (xy 121.480072 -252.584458)
			(xy 122.748814 -252.584458) (xy 122.752774 -252.535404) (xy 122.764551 -252.48762) (xy 122.783842 -252.442344)
			(xy 122.810145 -252.400748) (xy 122.84278 -252.363911) (xy 122.880901 -252.332786) (xy 122.923522 -252.308179)
			(xy 122.969538 -252.290727) (xy 123.017757 -252.280883) (xy 123.066932 -252.278902) (xy 123.115787 -252.284834)
			(xy 123.163058 -252.298526) (xy 123.20752 -252.319624) (xy 123.248023 -252.34758) (xy 123.283516 -252.381672)
			(xy 123.313081 -252.421016) (xy 123.335952 -252.464593) (xy 123.351536 -252.511274) (xy 123.359431 -252.559851)
			(xy 123.359926 -252.584458) (xy 124.628922 -252.584458) (xy 124.632882 -252.535404) (xy 124.644659 -252.48762)
			(xy 124.66395 -252.442344) (xy 124.690253 -252.400748) (xy 124.722888 -252.363911) (xy 124.761009 -252.332786)
			(xy 124.80363 -252.308179) (xy 124.849646 -252.290727) (xy 124.897865 -252.280883) (xy 124.94704 -252.278902)
			(xy 124.995895 -252.284834) (xy 125.043166 -252.298526) (xy 125.087628 -252.319624) (xy 125.128131 -252.34758)
			(xy 125.163624 -252.381672) (xy 125.193189 -252.421016) (xy 125.21606 -252.464593) (xy 125.231644 -252.511274)
			(xy 125.239539 -252.559851) (xy 125.240034 -252.584458) (xy 126.50903 -252.584458) (xy 126.51299 -252.535404)
			(xy 126.524767 -252.48762) (xy 126.544058 -252.442344) (xy 126.570361 -252.400748) (xy 126.602996 -252.363911)
			(xy 126.641117 -252.332786) (xy 126.683738 -252.308179) (xy 126.729754 -252.290727) (xy 126.777973 -252.280883)
			(xy 126.827148 -252.278902) (xy 126.876003 -252.284834) (xy 126.923274 -252.298526) (xy 126.967736 -252.319624)
			(xy 127.008239 -252.34758) (xy 127.043732 -252.381672) (xy 127.073297 -252.421016) (xy 127.096168 -252.464593)
			(xy 127.111752 -252.511274) (xy 127.119647 -252.559851) (xy 127.120142 -252.584458) (xy 127.44883 -252.584458)
			(xy 127.45279 -252.535404) (xy 127.464567 -252.48762) (xy 127.483858 -252.442344) (xy 127.510161 -252.400748)
			(xy 127.542796 -252.363911) (xy 127.580917 -252.332786) (xy 127.623538 -252.308179) (xy 127.669554 -252.290727)
			(xy 127.717773 -252.280883) (xy 127.766948 -252.278902) (xy 127.815803 -252.284834) (xy 127.863074 -252.298526)
			(xy 127.907536 -252.319624) (xy 127.948039 -252.34758) (xy 127.983532 -252.381672) (xy 128.013097 -252.421016)
			(xy 128.035968 -252.464593) (xy 128.051552 -252.511274) (xy 128.059447 -252.559851) (xy 128.059942 -252.584458)
			(xy 128.388884 -252.584458) (xy 128.392844 -252.535404) (xy 128.404621 -252.48762) (xy 128.423912 -252.442344)
			(xy 128.450215 -252.400748) (xy 128.48285 -252.363911) (xy 128.520971 -252.332786) (xy 128.563592 -252.308179)
			(xy 128.609608 -252.290727) (xy 128.657827 -252.280883) (xy 128.707002 -252.278902) (xy 128.755857 -252.284834)
			(xy 128.803128 -252.298526) (xy 128.84759 -252.319624) (xy 128.888093 -252.34758) (xy 128.923586 -252.381672)
			(xy 128.953151 -252.421016) (xy 128.976022 -252.464593) (xy 128.991606 -252.511274) (xy 128.999501 -252.559851)
			(xy 128.999996 -252.584458) (xy 129.318507 -252.584458) (xy 129.322602 -252.53373) (xy 129.334781 -252.484316)
			(xy 129.354729 -252.437496) (xy 129.38193 -252.394482) (xy 129.415678 -252.356388) (xy 129.4551 -252.324201)
			(xy 129.499174 -252.298755) (xy 129.54676 -252.280708) (xy 129.596624 -252.270528) (xy 129.647476 -252.268479)
			(xy 129.697997 -252.274613) (xy 129.746881 -252.288773) (xy 129.79286 -252.31059) (xy 129.834744 -252.3395)
			(xy 129.871448 -252.374755) (xy 129.902021 -252.415441) (xy 129.925672 -252.460504) (xy 129.941788 -252.508778)
			(xy 129.949952 -252.559012) (xy 129.950464 -252.584458) (xy 130.268992 -252.584458) (xy 130.272952 -252.535404)
			(xy 130.284729 -252.48762) (xy 130.30402 -252.442344) (xy 130.330323 -252.400748) (xy 130.362958 -252.363911)
			(xy 130.401079 -252.332786) (xy 130.4437 -252.308179) (xy 130.489716 -252.290727) (xy 130.537935 -252.280883)
			(xy 130.58711 -252.278902) (xy 130.635965 -252.284834) (xy 130.683236 -252.298526) (xy 130.727698 -252.319624)
			(xy 130.768201 -252.34758) (xy 130.803694 -252.381672) (xy 130.833259 -252.421016) (xy 130.85613 -252.464593)
			(xy 130.871714 -252.511274) (xy 130.879609 -252.559851) (xy 130.880104 -252.584458) (xy 131.209046 -252.584458)
			(xy 131.213006 -252.535404) (xy 131.224783 -252.48762) (xy 131.244074 -252.442344) (xy 131.270377 -252.400748)
			(xy 131.303012 -252.363911) (xy 131.341133 -252.332786) (xy 131.383754 -252.308179) (xy 131.42977 -252.290727)
			(xy 131.477989 -252.280883) (xy 131.527164 -252.278902) (xy 131.576019 -252.284834) (xy 131.62329 -252.298526)
			(xy 131.667752 -252.319624) (xy 131.708255 -252.34758) (xy 131.743748 -252.381672) (xy 131.773313 -252.421016)
			(xy 131.796184 -252.464593) (xy 131.811768 -252.511274) (xy 131.819663 -252.559851) (xy 131.820158 -252.584458)
			(xy 132.138415 -252.584458) (xy 132.14251 -252.53373) (xy 132.154689 -252.484316) (xy 132.174637 -252.437496)
			(xy 132.201838 -252.394482) (xy 132.235586 -252.356388) (xy 132.275008 -252.324201) (xy 132.319082 -252.298755)
			(xy 132.366668 -252.280708) (xy 132.416532 -252.270528) (xy 132.467384 -252.268479) (xy 132.517905 -252.274613)
			(xy 132.566789 -252.288773) (xy 132.612768 -252.31059) (xy 132.654652 -252.3395) (xy 132.691356 -252.374755)
			(xy 132.721929 -252.415441) (xy 132.74558 -252.460504) (xy 132.761696 -252.508778) (xy 132.76986 -252.559012)
			(xy 132.770372 -252.584458) (xy 132.76986 -252.609904) (xy 132.761696 -252.660138) (xy 132.74558 -252.708412)
			(xy 132.721929 -252.753475) (xy 132.691356 -252.794161) (xy 132.654652 -252.829416) (xy 132.612768 -252.858326)
			(xy 132.566789 -252.880143) (xy 132.517905 -252.894303) (xy 132.467384 -252.900437) (xy 132.416532 -252.898388)
			(xy 132.366668 -252.888208) (xy 132.319082 -252.870161) (xy 132.275008 -252.844715) (xy 132.235586 -252.812528)
			(xy 132.201838 -252.774434) (xy 132.174637 -252.73142) (xy 132.154689 -252.6846) (xy 132.14251 -252.635186)
			(xy 132.138415 -252.584458) (xy 131.820158 -252.584458) (xy 131.819663 -252.609065) (xy 131.811768 -252.657642)
			(xy 131.796184 -252.704323) (xy 131.773313 -252.7479) (xy 131.743748 -252.787244) (xy 131.708255 -252.821336)
			(xy 131.667752 -252.849292) (xy 131.62329 -252.87039) (xy 131.576019 -252.884082) (xy 131.527164 -252.890014)
			(xy 131.477989 -252.888033) (xy 131.42977 -252.878189) (xy 131.383754 -252.860737) (xy 131.341133 -252.83613)
			(xy 131.303012 -252.805005) (xy 131.270377 -252.768168) (xy 131.244074 -252.726572) (xy 131.224783 -252.681296)
			(xy 131.213006 -252.633512) (xy 131.209046 -252.584458) (xy 130.880104 -252.584458) (xy 130.879609 -252.609065)
			(xy 130.871714 -252.657642) (xy 130.85613 -252.704323) (xy 130.833259 -252.7479) (xy 130.803694 -252.787244)
			(xy 130.768201 -252.821336) (xy 130.727698 -252.849292) (xy 130.683236 -252.87039) (xy 130.635965 -252.884082)
			(xy 130.58711 -252.890014) (xy 130.537935 -252.888033) (xy 130.489716 -252.878189) (xy 130.4437 -252.860737)
			(xy 130.401079 -252.83613) (xy 130.362958 -252.805005) (xy 130.330323 -252.768168) (xy 130.30402 -252.726572)
			(xy 130.284729 -252.681296) (xy 130.272952 -252.633512) (xy 130.268992 -252.584458) (xy 129.950464 -252.584458)
			(xy 129.949952 -252.609904) (xy 129.941788 -252.660138) (xy 129.925672 -252.708412) (xy 129.902021 -252.753475)
			(xy 129.871448 -252.794161) (xy 129.834744 -252.829416) (xy 129.79286 -252.858326) (xy 129.746881 -252.880143)
			(xy 129.697997 -252.894303) (xy 129.647476 -252.900437) (xy 129.596624 -252.898388) (xy 129.54676 -252.888208)
			(xy 129.499174 -252.870161) (xy 129.4551 -252.844715) (xy 129.415678 -252.812528) (xy 129.38193 -252.774434)
			(xy 129.354729 -252.73142) (xy 129.334781 -252.6846) (xy 129.322602 -252.635186) (xy 129.318507 -252.584458)
			(xy 128.999996 -252.584458) (xy 128.999501 -252.609065) (xy 128.991606 -252.657642) (xy 128.976022 -252.704323)
			(xy 128.953151 -252.7479) (xy 128.923586 -252.787244) (xy 128.888093 -252.821336) (xy 128.84759 -252.849292)
			(xy 128.803128 -252.87039) (xy 128.755857 -252.884082) (xy 128.707002 -252.890014) (xy 128.657827 -252.888033)
			(xy 128.609608 -252.878189) (xy 128.563592 -252.860737) (xy 128.520971 -252.83613) (xy 128.48285 -252.805005)
			(xy 128.450215 -252.768168) (xy 128.423912 -252.726572) (xy 128.404621 -252.681296) (xy 128.392844 -252.633512)
			(xy 128.388884 -252.584458) (xy 128.059942 -252.584458) (xy 128.059447 -252.609065) (xy 128.051552 -252.657642)
			(xy 128.035968 -252.704323) (xy 128.013097 -252.7479) (xy 127.983532 -252.787244) (xy 127.948039 -252.821336)
			(xy 127.907536 -252.849292) (xy 127.863074 -252.87039) (xy 127.815803 -252.884082) (xy 127.766948 -252.890014)
			(xy 127.717773 -252.888033) (xy 127.669554 -252.878189) (xy 127.623538 -252.860737) (xy 127.580917 -252.83613)
			(xy 127.542796 -252.805005) (xy 127.510161 -252.768168) (xy 127.483858 -252.726572) (xy 127.464567 -252.681296)
			(xy 127.45279 -252.633512) (xy 127.44883 -252.584458) (xy 127.120142 -252.584458) (xy 127.119647 -252.609065)
			(xy 127.111752 -252.657642) (xy 127.096168 -252.704323) (xy 127.073297 -252.7479) (xy 127.043732 -252.787244)
			(xy 127.008239 -252.821336) (xy 126.967736 -252.849292) (xy 126.923274 -252.87039) (xy 126.876003 -252.884082)
			(xy 126.827148 -252.890014) (xy 126.777973 -252.888033) (xy 126.729754 -252.878189) (xy 126.683738 -252.860737)
			(xy 126.641117 -252.83613) (xy 126.602996 -252.805005) (xy 126.570361 -252.768168) (xy 126.544058 -252.726572)
			(xy 126.524767 -252.681296) (xy 126.51299 -252.633512) (xy 126.50903 -252.584458) (xy 125.240034 -252.584458)
			(xy 125.239539 -252.609065) (xy 125.231644 -252.657642) (xy 125.21606 -252.704323) (xy 125.193189 -252.7479)
			(xy 125.163624 -252.787244) (xy 125.128131 -252.821336) (xy 125.087628 -252.849292) (xy 125.043166 -252.87039)
			(xy 124.995895 -252.884082) (xy 124.94704 -252.890014) (xy 124.897865 -252.888033) (xy 124.849646 -252.878189)
			(xy 124.80363 -252.860737) (xy 124.761009 -252.83613) (xy 124.722888 -252.805005) (xy 124.690253 -252.768168)
			(xy 124.66395 -252.726572) (xy 124.644659 -252.681296) (xy 124.632882 -252.633512) (xy 124.628922 -252.584458)
			(xy 123.359926 -252.584458) (xy 123.359431 -252.609065) (xy 123.351536 -252.657642) (xy 123.335952 -252.704323)
			(xy 123.313081 -252.7479) (xy 123.283516 -252.787244) (xy 123.248023 -252.821336) (xy 123.20752 -252.849292)
			(xy 123.163058 -252.87039) (xy 123.115787 -252.884082) (xy 123.066932 -252.890014) (xy 123.017757 -252.888033)
			(xy 122.969538 -252.878189) (xy 122.923522 -252.860737) (xy 122.880901 -252.83613) (xy 122.84278 -252.805005)
			(xy 122.810145 -252.768168) (xy 122.783842 -252.726572) (xy 122.764551 -252.681296) (xy 122.752774 -252.633512)
			(xy 122.748814 -252.584458) (xy 121.480072 -252.584458) (xy 121.479577 -252.609065) (xy 121.471682 -252.657642)
			(xy 121.456098 -252.704323) (xy 121.433227 -252.7479) (xy 121.403662 -252.787244) (xy 121.368169 -252.821336)
			(xy 121.327666 -252.849292) (xy 121.283204 -252.87039) (xy 121.235933 -252.884082) (xy 121.187078 -252.890014)
			(xy 121.137903 -252.888033) (xy 121.089684 -252.878189) (xy 121.043668 -252.860737) (xy 121.001047 -252.83613)
			(xy 120.962926 -252.805005) (xy 120.930291 -252.768168) (xy 120.903988 -252.726572) (xy 120.884697 -252.681296)
			(xy 120.87292 -252.633512) (xy 120.86896 -252.584458) (xy 112.557092 -252.584458) (xy 112.553204 -252.59231)
			(xy 112.522912 -252.635376) (xy 112.4864 -252.673314) (xy 112.444526 -252.705233) (xy 112.39827 -252.730386)
			(xy 112.348717 -252.748184) (xy 112.297027 -252.758208) (xy 112.244413 -252.760225) (xy 112.192108 -252.754187)
			(xy 112.141337 -252.740235) (xy 112.093292 -252.718696) (xy 112.049097 -252.690076) (xy 112.009789 -252.655045)
			(xy 111.976289 -252.614424) (xy 111.949383 -252.569165) (xy 111.9297 -252.52033) (xy 111.917703 -252.469062)
			(xy 111.913673 -252.416564) (xy 101.696114 -252.416564) (xy 101.699459 -252.421016) (xy 101.72233 -252.464593)
			(xy 101.737914 -252.511274) (xy 101.745809 -252.559851) (xy 101.746304 -252.584458) (xy 101.745809 -252.609065)
			(xy 101.737914 -252.657642) (xy 101.72233 -252.704323) (xy 101.699459 -252.7479) (xy 101.669894 -252.787244)
			(xy 101.634401 -252.821336) (xy 101.593898 -252.849292) (xy 101.549436 -252.87039) (xy 101.502165 -252.884082)
			(xy 101.45331 -252.890014) (xy 101.404135 -252.888033) (xy 101.355916 -252.878189) (xy 101.3099 -252.860737)
			(xy 101.267279 -252.83613) (xy 101.229158 -252.805005) (xy 101.196523 -252.768168) (xy 101.17022 -252.726572)
			(xy 101.150929 -252.681296) (xy 101.139152 -252.633512) (xy 101.135192 -252.584458) (xy 100.805638 -252.584458)
			(xy 100.805638 -252.609712) (xy 100.797355 -252.659459) (xy 100.781013 -252.707169) (xy 100.757056 -252.751547)
			(xy 100.726135 -252.791387) (xy 100.689089 -252.825607) (xy 100.646926 -252.853277) (xy 100.600791 -252.873645)
			(xy 100.551936 -252.886159) (xy 100.52685 -252.88875) (xy 100.517452 -252.889512) (xy 100.501196 -252.897386)
			(xy 100.474018 -252.92558) (xy 100.466906 -252.932692) (xy 100.45954 -252.95098) (xy 100.45954 -253.394464)
			(xy 101.605346 -253.394464) (xy 101.609306 -253.34541) (xy 101.621083 -253.297626) (xy 101.640374 -253.25235)
			(xy 101.666677 -253.210754) (xy 101.699312 -253.173917) (xy 101.737433 -253.142792) (xy 101.780054 -253.118185)
			(xy 101.82607 -253.100733) (xy 101.874289 -253.090889) (xy 101.923464 -253.088908) (xy 101.972319 -253.09484)
			(xy 102.01959 -253.108532) (xy 102.064052 -253.12963) (xy 102.104555 -253.157586) (xy 102.140048 -253.191678)
			(xy 102.169613 -253.231022) (xy 102.192484 -253.274599) (xy 102.208068 -253.32128) (xy 102.215963 -253.369857)
			(xy 102.216417 -253.392432) (xy 103.482152 -253.392432) (xy 103.486112 -253.343378) (xy 103.497889 -253.295594)
			(xy 103.51718 -253.250318) (xy 103.543483 -253.208722) (xy 103.576118 -253.171885) (xy 103.614239 -253.14076)
			(xy 103.65686 -253.116153) (xy 103.702876 -253.098701) (xy 103.751095 -253.088857) (xy 103.80027 -253.086876)
			(xy 103.849125 -253.092808) (xy 103.896396 -253.1065) (xy 103.940858 -253.127598) (xy 103.981361 -253.155554)
			(xy 104.016854 -253.189646) (xy 104.046419 -253.22899) (xy 104.06929 -253.272567) (xy 104.084874 -253.319248)
			(xy 104.092769 -253.367825) (xy 104.093264 -253.392432) (xy 105.362006 -253.392432) (xy 105.365966 -253.343378)
			(xy 105.377743 -253.295594) (xy 105.397034 -253.250318) (xy 105.423337 -253.208722) (xy 105.455972 -253.171885)
			(xy 105.494093 -253.14076) (xy 105.536714 -253.116153) (xy 105.58273 -253.098701) (xy 105.630949 -253.088857)
			(xy 105.680124 -253.086876) (xy 105.728979 -253.092808) (xy 105.77625 -253.1065) (xy 105.820712 -253.127598)
			(xy 105.861215 -253.155554) (xy 105.896708 -253.189646) (xy 105.926273 -253.22899) (xy 105.949144 -253.272567)
			(xy 105.964728 -253.319248) (xy 105.972623 -253.367825) (xy 105.973118 -253.392432) (xy 107.242114 -253.392432)
			(xy 107.246074 -253.343378) (xy 107.257851 -253.295594) (xy 107.277142 -253.250318) (xy 107.303445 -253.208722)
			(xy 107.33608 -253.171885) (xy 107.374201 -253.14076) (xy 107.416822 -253.116153) (xy 107.462838 -253.098701)
			(xy 107.511057 -253.088857) (xy 107.560232 -253.086876) (xy 107.609087 -253.092808) (xy 107.656358 -253.1065)
			(xy 107.70082 -253.127598) (xy 107.741323 -253.155554) (xy 107.776816 -253.189646) (xy 107.806381 -253.22899)
			(xy 107.829252 -253.272567) (xy 107.844836 -253.319248) (xy 107.852731 -253.367825) (xy 107.853226 -253.392432)
			(xy 109.122222 -253.392432) (xy 109.126182 -253.343378) (xy 109.137959 -253.295594) (xy 109.15725 -253.250318)
			(xy 109.183553 -253.208722) (xy 109.216188 -253.171885) (xy 109.254309 -253.14076) (xy 109.29693 -253.116153)
			(xy 109.342946 -253.098701) (xy 109.391165 -253.088857) (xy 109.44034 -253.086876) (xy 109.489195 -253.092808)
			(xy 109.536466 -253.1065) (xy 109.580928 -253.127598) (xy 109.621431 -253.155554) (xy 109.656924 -253.189646)
			(xy 109.686489 -253.22899) (xy 109.70936 -253.272567) (xy 109.724944 -253.319248) (xy 109.732839 -253.367825)
			(xy 109.733334 -253.392432) (xy 109.732839 -253.417039) (xy 109.730316 -253.432564) (xy 111.913673 -253.432564)
			(xy 111.917703 -253.380066) (xy 111.9297 -253.328798) (xy 111.949383 -253.279963) (xy 111.976289 -253.234704)
			(xy 112.009789 -253.194083) (xy 112.049097 -253.159052) (xy 112.093292 -253.130432) (xy 112.141337 -253.108893)
			(xy 112.192108 -253.094941) (xy 112.244413 -253.088903) (xy 112.297027 -253.09092) (xy 112.348717 -253.100944)
			(xy 112.39827 -253.118742) (xy 112.444526 -253.143895) (xy 112.4864 -253.175814) (xy 112.522912 -253.213752)
			(xy 112.553204 -253.256818) (xy 112.576567 -253.304003) (xy 112.592453 -253.354202) (xy 112.598358 -253.392432)
			(xy 112.882184 -253.392432) (xy 112.886144 -253.343378) (xy 112.897921 -253.295594) (xy 112.917212 -253.250318)
			(xy 112.943515 -253.208722) (xy 112.97615 -253.171885) (xy 113.014271 -253.14076) (xy 113.056892 -253.116153)
			(xy 113.102908 -253.098701) (xy 113.151127 -253.088857) (xy 113.200302 -253.086876) (xy 113.249157 -253.092808)
			(xy 113.296428 -253.1065) (xy 113.34089 -253.127598) (xy 113.381393 -253.155554) (xy 113.416886 -253.189646)
			(xy 113.446451 -253.22899) (xy 113.469322 -253.272567) (xy 113.484906 -253.319248) (xy 113.492801 -253.367825)
			(xy 113.493296 -253.392432) (xy 114.762038 -253.392432) (xy 114.765998 -253.343378) (xy 114.777775 -253.295594)
			(xy 114.797066 -253.250318) (xy 114.823369 -253.208722) (xy 114.856004 -253.171885) (xy 114.894125 -253.14076)
			(xy 114.936746 -253.116153) (xy 114.982762 -253.098701) (xy 115.030981 -253.088857) (xy 115.080156 -253.086876)
			(xy 115.129011 -253.092808) (xy 115.176282 -253.1065) (xy 115.220744 -253.127598) (xy 115.261247 -253.155554)
			(xy 115.29674 -253.189646) (xy 115.326305 -253.22899) (xy 115.349176 -253.272567) (xy 115.36476 -253.319248)
			(xy 115.372655 -253.367825) (xy 115.37315 -253.392432) (xy 116.642146 -253.392432) (xy 116.646106 -253.343378)
			(xy 116.657883 -253.295594) (xy 116.677174 -253.250318) (xy 116.703477 -253.208722) (xy 116.736112 -253.171885)
			(xy 116.774233 -253.14076) (xy 116.816854 -253.116153) (xy 116.86287 -253.098701) (xy 116.911089 -253.088857)
			(xy 116.960264 -253.086876) (xy 117.009119 -253.092808) (xy 117.05639 -253.1065) (xy 117.100852 -253.127598)
			(xy 117.141355 -253.155554) (xy 117.176848 -253.189646) (xy 117.206413 -253.22899) (xy 117.229284 -253.272567)
			(xy 117.244868 -253.319248) (xy 117.252763 -253.367825) (xy 117.253258 -253.392432) (xy 118.522 -253.392432)
			(xy 118.52596 -253.343378) (xy 118.537737 -253.295594) (xy 118.557028 -253.250318) (xy 118.583331 -253.208722)
			(xy 118.615966 -253.171885) (xy 118.654087 -253.14076) (xy 118.696708 -253.116153) (xy 118.742724 -253.098701)
			(xy 118.790943 -253.088857) (xy 118.840118 -253.086876) (xy 118.888973 -253.092808) (xy 118.936244 -253.1065)
			(xy 118.980706 -253.127598) (xy 119.021209 -253.155554) (xy 119.056702 -253.189646) (xy 119.086267 -253.22899)
			(xy 119.109138 -253.272567) (xy 119.124722 -253.319248) (xy 119.132617 -253.367825) (xy 119.133112 -253.392432)
			(xy 119.133071 -253.394464) (xy 122.278914 -253.394464) (xy 122.282874 -253.34541) (xy 122.294651 -253.297626)
			(xy 122.313942 -253.25235) (xy 122.340245 -253.210754) (xy 122.37288 -253.173917) (xy 122.411001 -253.142792)
			(xy 122.453622 -253.118185) (xy 122.499638 -253.100733) (xy 122.547857 -253.090889) (xy 122.597032 -253.088908)
			(xy 122.645887 -253.09484) (xy 122.693158 -253.108532) (xy 122.73762 -253.12963) (xy 122.778123 -253.157586)
			(xy 122.813616 -253.191678) (xy 122.843181 -253.231022) (xy 122.866052 -253.274599) (xy 122.881636 -253.32128)
			(xy 122.889531 -253.369857) (xy 122.890026 -253.394464) (xy 124.159022 -253.394464) (xy 124.162982 -253.34541)
			(xy 124.174759 -253.297626) (xy 124.19405 -253.25235) (xy 124.220353 -253.210754) (xy 124.252988 -253.173917)
			(xy 124.291109 -253.142792) (xy 124.33373 -253.118185) (xy 124.379746 -253.100733) (xy 124.427965 -253.090889)
			(xy 124.47714 -253.088908) (xy 124.525995 -253.09484) (xy 124.573266 -253.108532) (xy 124.617728 -253.12963)
			(xy 124.658231 -253.157586) (xy 124.693724 -253.191678) (xy 124.723289 -253.231022) (xy 124.74616 -253.274599)
			(xy 124.761744 -253.32128) (xy 124.769639 -253.369857) (xy 124.770134 -253.394464) (xy 126.038876 -253.394464)
			(xy 126.042836 -253.34541) (xy 126.054613 -253.297626) (xy 126.073904 -253.25235) (xy 126.100207 -253.210754)
			(xy 126.132842 -253.173917) (xy 126.170963 -253.142792) (xy 126.213584 -253.118185) (xy 126.2596 -253.100733)
			(xy 126.307819 -253.090889) (xy 126.356994 -253.088908) (xy 126.405849 -253.09484) (xy 126.45312 -253.108532)
			(xy 126.497582 -253.12963) (xy 126.538085 -253.157586) (xy 126.573578 -253.191678) (xy 126.603143 -253.231022)
			(xy 126.626014 -253.274599) (xy 126.641598 -253.32128) (xy 126.649493 -253.369857) (xy 126.649988 -253.394464)
			(xy 127.908553 -253.394464) (xy 127.912648 -253.343736) (xy 127.924827 -253.294322) (xy 127.944775 -253.247502)
			(xy 127.971976 -253.204488) (xy 128.005724 -253.166394) (xy 128.045146 -253.134207) (xy 128.08922 -253.108761)
			(xy 128.136806 -253.090714) (xy 128.18667 -253.080534) (xy 128.237522 -253.078485) (xy 128.288043 -253.084619)
			(xy 128.336927 -253.098779) (xy 128.382906 -253.120596) (xy 128.42479 -253.149506) (xy 128.461494 -253.184761)
			(xy 128.492067 -253.225447) (xy 128.515718 -253.27051) (xy 128.531834 -253.318784) (xy 128.539998 -253.369018)
			(xy 128.54051 -253.394464) (xy 128.848607 -253.394464) (xy 128.852702 -253.343736) (xy 128.864881 -253.294322)
			(xy 128.884829 -253.247502) (xy 128.91203 -253.204488) (xy 128.945778 -253.166394) (xy 128.9852 -253.134207)
			(xy 129.029274 -253.108761) (xy 129.07686 -253.090714) (xy 129.126724 -253.080534) (xy 129.177576 -253.078485)
			(xy 129.228097 -253.084619) (xy 129.276981 -253.098779) (xy 129.32296 -253.120596) (xy 129.364844 -253.149506)
			(xy 129.401548 -253.184761) (xy 129.432121 -253.225447) (xy 129.455772 -253.27051) (xy 129.471888 -253.318784)
			(xy 129.480052 -253.369018) (xy 129.480564 -253.394464) (xy 129.798838 -253.394464) (xy 129.802798 -253.34541)
			(xy 129.814575 -253.297626) (xy 129.833866 -253.25235) (xy 129.860169 -253.210754) (xy 129.892804 -253.173917)
			(xy 129.930925 -253.142792) (xy 129.973546 -253.118185) (xy 130.019562 -253.100733) (xy 130.067781 -253.090889)
			(xy 130.116956 -253.088908) (xy 130.165811 -253.09484) (xy 130.213082 -253.108532) (xy 130.257544 -253.12963)
			(xy 130.298047 -253.157586) (xy 130.33354 -253.191678) (xy 130.363105 -253.231022) (xy 130.385976 -253.274599)
			(xy 130.40156 -253.32128) (xy 130.409455 -253.369857) (xy 130.40995 -253.394464) (xy 130.728461 -253.394464)
			(xy 130.732556 -253.343736) (xy 130.744735 -253.294322) (xy 130.764683 -253.247502) (xy 130.791884 -253.204488)
			(xy 130.825632 -253.166394) (xy 130.865054 -253.134207) (xy 130.909128 -253.108761) (xy 130.956714 -253.090714)
			(xy 131.006578 -253.080534) (xy 131.05743 -253.078485) (xy 131.107951 -253.084619) (xy 131.156835 -253.098779)
			(xy 131.202814 -253.120596) (xy 131.244698 -253.149506) (xy 131.281402 -253.184761) (xy 131.311975 -253.225447)
			(xy 131.335626 -253.27051) (xy 131.351742 -253.318784) (xy 131.359906 -253.369018) (xy 131.360418 -253.394464)
			(xy 131.678946 -253.394464) (xy 131.682906 -253.34541) (xy 131.694683 -253.297626) (xy 131.713974 -253.25235)
			(xy 131.740277 -253.210754) (xy 131.772912 -253.173917) (xy 131.811033 -253.142792) (xy 131.853654 -253.118185)
			(xy 131.89967 -253.100733) (xy 131.947889 -253.090889) (xy 131.997064 -253.088908) (xy 132.045919 -253.09484)
			(xy 132.09319 -253.108532) (xy 132.137652 -253.12963) (xy 132.178155 -253.157586) (xy 132.213648 -253.191678)
			(xy 132.243213 -253.231022) (xy 132.266084 -253.274599) (xy 132.281668 -253.32128) (xy 132.289563 -253.369857)
			(xy 132.290058 -253.394464) (xy 132.608569 -253.394464) (xy 132.612664 -253.343736) (xy 132.624843 -253.294322)
			(xy 132.644791 -253.247502) (xy 132.671992 -253.204488) (xy 132.70574 -253.166394) (xy 132.745162 -253.134207)
			(xy 132.789236 -253.108761) (xy 132.836822 -253.090714) (xy 132.886686 -253.080534) (xy 132.937538 -253.078485)
			(xy 132.988059 -253.084619) (xy 133.036943 -253.098779) (xy 133.082922 -253.120596) (xy 133.124806 -253.149506)
			(xy 133.16151 -253.184761) (xy 133.192083 -253.225447) (xy 133.215734 -253.27051) (xy 133.23185 -253.318784)
			(xy 133.240014 -253.369018) (xy 133.240526 -253.394464) (xy 133.240014 -253.41991) (xy 133.23185 -253.470144)
			(xy 133.215734 -253.518418) (xy 133.192083 -253.563481) (xy 133.16151 -253.604167) (xy 133.124806 -253.639422)
			(xy 133.082922 -253.668332) (xy 133.036943 -253.690149) (xy 132.988059 -253.704309) (xy 132.937538 -253.710443)
			(xy 132.886686 -253.708394) (xy 132.836822 -253.698214) (xy 132.789236 -253.680167) (xy 132.745162 -253.654721)
			(xy 132.70574 -253.622534) (xy 132.671992 -253.58444) (xy 132.644791 -253.541426) (xy 132.624843 -253.494606)
			(xy 132.612664 -253.445192) (xy 132.608569 -253.394464) (xy 132.290058 -253.394464) (xy 132.289563 -253.419071)
			(xy 132.281668 -253.467648) (xy 132.266084 -253.514329) (xy 132.243213 -253.557906) (xy 132.213648 -253.59725)
			(xy 132.178155 -253.631342) (xy 132.137652 -253.659298) (xy 132.09319 -253.680396) (xy 132.045919 -253.694088)
			(xy 131.997064 -253.70002) (xy 131.947889 -253.698039) (xy 131.89967 -253.688195) (xy 131.853654 -253.670743)
			(xy 131.811033 -253.646136) (xy 131.772912 -253.615011) (xy 131.740277 -253.578174) (xy 131.713974 -253.536578)
			(xy 131.694683 -253.491302) (xy 131.682906 -253.443518) (xy 131.678946 -253.394464) (xy 131.360418 -253.394464)
			(xy 131.359906 -253.41991) (xy 131.351742 -253.470144) (xy 131.335626 -253.518418) (xy 131.311975 -253.563481)
			(xy 131.281402 -253.604167) (xy 131.244698 -253.639422) (xy 131.202814 -253.668332) (xy 131.156835 -253.690149)
			(xy 131.107951 -253.704309) (xy 131.05743 -253.710443) (xy 131.006578 -253.708394) (xy 130.956714 -253.698214)
			(xy 130.909128 -253.680167) (xy 130.865054 -253.654721) (xy 130.825632 -253.622534) (xy 130.791884 -253.58444)
			(xy 130.764683 -253.541426) (xy 130.744735 -253.494606) (xy 130.732556 -253.445192) (xy 130.728461 -253.394464)
			(xy 130.40995 -253.394464) (xy 130.409455 -253.419071) (xy 130.40156 -253.467648) (xy 130.385976 -253.514329)
			(xy 130.363105 -253.557906) (xy 130.33354 -253.59725) (xy 130.298047 -253.631342) (xy 130.257544 -253.659298)
			(xy 130.213082 -253.680396) (xy 130.165811 -253.694088) (xy 130.116956 -253.70002) (xy 130.067781 -253.698039)
			(xy 130.019562 -253.688195) (xy 129.973546 -253.670743) (xy 129.930925 -253.646136) (xy 129.892804 -253.615011)
			(xy 129.860169 -253.578174) (xy 129.833866 -253.536578) (xy 129.814575 -253.491302) (xy 129.802798 -253.443518)
			(xy 129.798838 -253.394464) (xy 129.480564 -253.394464) (xy 129.480052 -253.41991) (xy 129.471888 -253.470144)
			(xy 129.455772 -253.518418) (xy 129.432121 -253.563481) (xy 129.401548 -253.604167) (xy 129.364844 -253.639422)
			(xy 129.32296 -253.668332) (xy 129.276981 -253.690149) (xy 129.228097 -253.704309) (xy 129.177576 -253.710443)
			(xy 129.126724 -253.708394) (xy 129.07686 -253.698214) (xy 129.029274 -253.680167) (xy 128.9852 -253.654721)
			(xy 128.945778 -253.622534) (xy 128.91203 -253.58444) (xy 128.884829 -253.541426) (xy 128.864881 -253.494606)
			(xy 128.852702 -253.445192) (xy 128.848607 -253.394464) (xy 128.54051 -253.394464) (xy 128.539998 -253.41991)
			(xy 128.531834 -253.470144) (xy 128.515718 -253.518418) (xy 128.492067 -253.563481) (xy 128.461494 -253.604167)
			(xy 128.42479 -253.639422) (xy 128.382906 -253.668332) (xy 128.336927 -253.690149) (xy 128.288043 -253.704309)
			(xy 128.237522 -253.710443) (xy 128.18667 -253.708394) (xy 128.136806 -253.698214) (xy 128.08922 -253.680167)
			(xy 128.045146 -253.654721) (xy 128.005724 -253.622534) (xy 127.971976 -253.58444) (xy 127.944775 -253.541426)
			(xy 127.924827 -253.494606) (xy 127.912648 -253.445192) (xy 127.908553 -253.394464) (xy 126.649988 -253.394464)
			(xy 126.649493 -253.419071) (xy 126.641598 -253.467648) (xy 126.626014 -253.514329) (xy 126.603143 -253.557906)
			(xy 126.573578 -253.59725) (xy 126.538085 -253.631342) (xy 126.497582 -253.659298) (xy 126.45312 -253.680396)
			(xy 126.405849 -253.694088) (xy 126.356994 -253.70002) (xy 126.307819 -253.698039) (xy 126.2596 -253.688195)
			(xy 126.213584 -253.670743) (xy 126.170963 -253.646136) (xy 126.132842 -253.615011) (xy 126.100207 -253.578174)
			(xy 126.073904 -253.536578) (xy 126.054613 -253.491302) (xy 126.042836 -253.443518) (xy 126.038876 -253.394464)
			(xy 124.770134 -253.394464) (xy 124.769639 -253.419071) (xy 124.761744 -253.467648) (xy 124.74616 -253.514329)
			(xy 124.723289 -253.557906) (xy 124.693724 -253.59725) (xy 124.658231 -253.631342) (xy 124.617728 -253.659298)
			(xy 124.573266 -253.680396) (xy 124.525995 -253.694088) (xy 124.47714 -253.70002) (xy 124.427965 -253.698039)
			(xy 124.379746 -253.688195) (xy 124.33373 -253.670743) (xy 124.291109 -253.646136) (xy 124.252988 -253.615011)
			(xy 124.220353 -253.578174) (xy 124.19405 -253.536578) (xy 124.174759 -253.491302) (xy 124.162982 -253.443518)
			(xy 124.159022 -253.394464) (xy 122.890026 -253.394464) (xy 122.889531 -253.419071) (xy 122.881636 -253.467648)
			(xy 122.866052 -253.514329) (xy 122.843181 -253.557906) (xy 122.813616 -253.59725) (xy 122.778123 -253.631342)
			(xy 122.73762 -253.659298) (xy 122.693158 -253.680396) (xy 122.645887 -253.694088) (xy 122.597032 -253.70002)
			(xy 122.547857 -253.698039) (xy 122.499638 -253.688195) (xy 122.453622 -253.670743) (xy 122.411001 -253.646136)
			(xy 122.37288 -253.615011) (xy 122.340245 -253.578174) (xy 122.313942 -253.536578) (xy 122.294651 -253.491302)
			(xy 122.282874 -253.443518) (xy 122.278914 -253.394464) (xy 119.133071 -253.394464) (xy 119.132617 -253.417039)
			(xy 119.124722 -253.465616) (xy 119.109138 -253.512297) (xy 119.086267 -253.555874) (xy 119.056702 -253.595218)
			(xy 119.021209 -253.62931) (xy 118.980706 -253.657266) (xy 118.936244 -253.678364) (xy 118.888973 -253.692056)
			(xy 118.840118 -253.697988) (xy 118.790943 -253.696007) (xy 118.742724 -253.686163) (xy 118.696708 -253.668711)
			(xy 118.654087 -253.644104) (xy 118.615966 -253.612979) (xy 118.583331 -253.576142) (xy 118.557028 -253.534546)
			(xy 118.537737 -253.48927) (xy 118.52596 -253.441486) (xy 118.522 -253.392432) (xy 117.253258 -253.392432)
			(xy 117.252763 -253.417039) (xy 117.244868 -253.465616) (xy 117.229284 -253.512297) (xy 117.206413 -253.555874)
			(xy 117.176848 -253.595218) (xy 117.141355 -253.62931) (xy 117.100852 -253.657266) (xy 117.05639 -253.678364)
			(xy 117.009119 -253.692056) (xy 116.960264 -253.697988) (xy 116.911089 -253.696007) (xy 116.86287 -253.686163)
			(xy 116.816854 -253.668711) (xy 116.774233 -253.644104) (xy 116.736112 -253.612979) (xy 116.703477 -253.576142)
			(xy 116.677174 -253.534546) (xy 116.657883 -253.48927) (xy 116.646106 -253.441486) (xy 116.642146 -253.392432)
			(xy 115.37315 -253.392432) (xy 115.372655 -253.417039) (xy 115.36476 -253.465616) (xy 115.349176 -253.512297)
			(xy 115.326305 -253.555874) (xy 115.29674 -253.595218) (xy 115.261247 -253.62931) (xy 115.220744 -253.657266)
			(xy 115.176282 -253.678364) (xy 115.129011 -253.692056) (xy 115.080156 -253.697988) (xy 115.030981 -253.696007)
			(xy 114.982762 -253.686163) (xy 114.936746 -253.668711) (xy 114.894125 -253.644104) (xy 114.856004 -253.612979)
			(xy 114.823369 -253.576142) (xy 114.797066 -253.534546) (xy 114.777775 -253.48927) (xy 114.765998 -253.441486)
			(xy 114.762038 -253.392432) (xy 113.493296 -253.392432) (xy 113.492801 -253.417039) (xy 113.484906 -253.465616)
			(xy 113.469322 -253.512297) (xy 113.446451 -253.555874) (xy 113.416886 -253.595218) (xy 113.381393 -253.62931)
			(xy 113.34089 -253.657266) (xy 113.296428 -253.678364) (xy 113.249157 -253.692056) (xy 113.200302 -253.697988)
			(xy 113.151127 -253.696007) (xy 113.102908 -253.686163) (xy 113.056892 -253.668711) (xy 113.014271 -253.644104)
			(xy 112.97615 -253.612979) (xy 112.943515 -253.576142) (xy 112.917212 -253.534546) (xy 112.897921 -253.48927)
			(xy 112.886144 -253.441486) (xy 112.882184 -253.392432) (xy 112.598358 -253.392432) (xy 112.60049 -253.406238)
			(xy 112.600994 -253.432564) (xy 112.60049 -253.45889) (xy 112.592453 -253.510926) (xy 112.576567 -253.561125)
			(xy 112.553204 -253.60831) (xy 112.522912 -253.651376) (xy 112.4864 -253.689314) (xy 112.444526 -253.721233)
			(xy 112.39827 -253.746386) (xy 112.348717 -253.764184) (xy 112.297027 -253.774208) (xy 112.244413 -253.776225)
			(xy 112.192108 -253.770187) (xy 112.141337 -253.756235) (xy 112.093292 -253.734696) (xy 112.049097 -253.706076)
			(xy 112.009789 -253.671045) (xy 111.976289 -253.630424) (xy 111.949383 -253.585165) (xy 111.9297 -253.53633)
			(xy 111.917703 -253.485062) (xy 111.913673 -253.432564) (xy 109.730316 -253.432564) (xy 109.724944 -253.465616)
			(xy 109.70936 -253.512297) (xy 109.686489 -253.555874) (xy 109.656924 -253.595218) (xy 109.621431 -253.62931)
			(xy 109.580928 -253.657266) (xy 109.536466 -253.678364) (xy 109.489195 -253.692056) (xy 109.44034 -253.697988)
			(xy 109.391165 -253.696007) (xy 109.342946 -253.686163) (xy 109.29693 -253.668711) (xy 109.254309 -253.644104)
			(xy 109.216188 -253.612979) (xy 109.183553 -253.576142) (xy 109.15725 -253.534546) (xy 109.137959 -253.48927)
			(xy 109.126182 -253.441486) (xy 109.122222 -253.392432) (xy 107.853226 -253.392432) (xy 107.852731 -253.417039)
			(xy 107.844836 -253.465616) (xy 107.829252 -253.512297) (xy 107.806381 -253.555874) (xy 107.776816 -253.595218)
			(xy 107.741323 -253.62931) (xy 107.70082 -253.657266) (xy 107.656358 -253.678364) (xy 107.609087 -253.692056)
			(xy 107.560232 -253.697988) (xy 107.511057 -253.696007) (xy 107.462838 -253.686163) (xy 107.416822 -253.668711)
			(xy 107.374201 -253.644104) (xy 107.33608 -253.612979) (xy 107.303445 -253.576142) (xy 107.277142 -253.534546)
			(xy 107.257851 -253.48927) (xy 107.246074 -253.441486) (xy 107.242114 -253.392432) (xy 105.973118 -253.392432)
			(xy 105.972623 -253.417039) (xy 105.964728 -253.465616) (xy 105.949144 -253.512297) (xy 105.926273 -253.555874)
			(xy 105.896708 -253.595218) (xy 105.861215 -253.62931) (xy 105.820712 -253.657266) (xy 105.77625 -253.678364)
			(xy 105.728979 -253.692056) (xy 105.680124 -253.697988) (xy 105.630949 -253.696007) (xy 105.58273 -253.686163)
			(xy 105.536714 -253.668711) (xy 105.494093 -253.644104) (xy 105.455972 -253.612979) (xy 105.423337 -253.576142)
			(xy 105.397034 -253.534546) (xy 105.377743 -253.48927) (xy 105.365966 -253.441486) (xy 105.362006 -253.392432)
			(xy 104.093264 -253.392432) (xy 104.092769 -253.417039) (xy 104.084874 -253.465616) (xy 104.06929 -253.512297)
			(xy 104.046419 -253.555874) (xy 104.016854 -253.595218) (xy 103.981361 -253.62931) (xy 103.940858 -253.657266)
			(xy 103.896396 -253.678364) (xy 103.849125 -253.692056) (xy 103.80027 -253.697988) (xy 103.751095 -253.696007)
			(xy 103.702876 -253.686163) (xy 103.65686 -253.668711) (xy 103.614239 -253.644104) (xy 103.576118 -253.612979)
			(xy 103.543483 -253.576142) (xy 103.51718 -253.534546) (xy 103.497889 -253.48927) (xy 103.486112 -253.441486)
			(xy 103.482152 -253.392432) (xy 102.216417 -253.392432) (xy 102.216458 -253.394464) (xy 102.215963 -253.419071)
			(xy 102.208068 -253.467648) (xy 102.192484 -253.514329) (xy 102.169613 -253.557906) (xy 102.140048 -253.59725)
			(xy 102.104555 -253.631342) (xy 102.064052 -253.659298) (xy 102.01959 -253.680396) (xy 101.972319 -253.694088)
			(xy 101.923464 -253.70002) (xy 101.874289 -253.698039) (xy 101.82607 -253.688195) (xy 101.780054 -253.670743)
			(xy 101.737433 -253.646136) (xy 101.699312 -253.615011) (xy 101.666677 -253.578174) (xy 101.640374 -253.536578)
			(xy 101.621083 -253.491302) (xy 101.609306 -253.443518) (xy 101.605346 -253.394464) (xy 100.45954 -253.394464)
			(xy 100.45954 -253.837948) (xy 100.466906 -253.856236) (xy 100.474018 -253.863348) (xy 100.501196 -253.891542)
			(xy 100.517452 -253.899416) (xy 100.52685 -253.900178) (xy 100.551928 -253.902852) (xy 100.600781 -253.915364)
			(xy 100.646915 -253.935731) (xy 100.689077 -253.963399) (xy 100.726122 -253.997616) (xy 100.757042 -254.037454)
			(xy 100.780999 -254.08183) (xy 100.797342 -254.129538) (xy 100.805626 -254.179283) (xy 100.805626 -254.20447)
			(xy 101.135192 -254.20447) (xy 101.139152 -254.155416) (xy 101.150929 -254.107632) (xy 101.17022 -254.062356)
			(xy 101.196523 -254.02076) (xy 101.229158 -253.983923) (xy 101.267279 -253.952798) (xy 101.3099 -253.928191)
			(xy 101.355916 -253.910739) (xy 101.404135 -253.900895) (xy 101.45331 -253.898914) (xy 101.502165 -253.904846)
			(xy 101.549436 -253.918538) (xy 101.593898 -253.939636) (xy 101.634401 -253.967592) (xy 101.669894 -254.001684)
			(xy 101.699459 -254.041028) (xy 101.72233 -254.084605) (xy 101.737914 -254.131286) (xy 101.745809 -254.179863)
			(xy 101.746304 -254.20447) (xy 101.745809 -254.229077) (xy 101.737914 -254.277654) (xy 101.72233 -254.324335)
			(xy 101.699459 -254.367912) (xy 101.669894 -254.407256) (xy 101.634401 -254.441348) (xy 101.623946 -254.448564)
			(xy 111.913673 -254.448564) (xy 111.917703 -254.396066) (xy 111.9297 -254.344798) (xy 111.949383 -254.295963)
			(xy 111.976289 -254.250704) (xy 112.009789 -254.210083) (xy 112.049097 -254.175052) (xy 112.093292 -254.146432)
			(xy 112.141337 -254.124893) (xy 112.192108 -254.110941) (xy 112.244413 -254.104903) (xy 112.297027 -254.10692)
			(xy 112.348717 -254.116944) (xy 112.39827 -254.134742) (xy 112.444526 -254.159895) (xy 112.4864 -254.191814)
			(xy 112.49858 -254.20447) (xy 120.86896 -254.20447) (xy 120.87292 -254.155416) (xy 120.884697 -254.107632)
			(xy 120.903988 -254.062356) (xy 120.930291 -254.02076) (xy 120.962926 -253.983923) (xy 121.001047 -253.952798)
			(xy 121.043668 -253.928191) (xy 121.089684 -253.910739) (xy 121.137903 -253.900895) (xy 121.187078 -253.898914)
			(xy 121.235933 -253.904846) (xy 121.283204 -253.918538) (xy 121.327666 -253.939636) (xy 121.368169 -253.967592)
			(xy 121.403662 -254.001684) (xy 121.433227 -254.041028) (xy 121.456098 -254.084605) (xy 121.471682 -254.131286)
			(xy 121.479577 -254.179863) (xy 121.480072 -254.20447) (xy 122.748814 -254.20447) (xy 122.752774 -254.155416)
			(xy 122.764551 -254.107632) (xy 122.783842 -254.062356) (xy 122.810145 -254.02076) (xy 122.84278 -253.983923)
			(xy 122.880901 -253.952798) (xy 122.923522 -253.928191) (xy 122.969538 -253.910739) (xy 123.017757 -253.900895)
			(xy 123.066932 -253.898914) (xy 123.115787 -253.904846) (xy 123.163058 -253.918538) (xy 123.20752 -253.939636)
			(xy 123.248023 -253.967592) (xy 123.283516 -254.001684) (xy 123.313081 -254.041028) (xy 123.335952 -254.084605)
			(xy 123.351536 -254.131286) (xy 123.359431 -254.179863) (xy 123.359926 -254.20447) (xy 124.628922 -254.20447)
			(xy 124.632882 -254.155416) (xy 124.644659 -254.107632) (xy 124.66395 -254.062356) (xy 124.690253 -254.02076)
			(xy 124.722888 -253.983923) (xy 124.761009 -253.952798) (xy 124.80363 -253.928191) (xy 124.849646 -253.910739)
			(xy 124.897865 -253.900895) (xy 124.94704 -253.898914) (xy 124.995895 -253.904846) (xy 125.043166 -253.918538)
			(xy 125.087628 -253.939636) (xy 125.128131 -253.967592) (xy 125.163624 -254.001684) (xy 125.193189 -254.041028)
			(xy 125.21606 -254.084605) (xy 125.231644 -254.131286) (xy 125.239539 -254.179863) (xy 125.240034 -254.20447)
			(xy 126.50903 -254.20447) (xy 126.51299 -254.155416) (xy 126.524767 -254.107632) (xy 126.544058 -254.062356)
			(xy 126.570361 -254.02076) (xy 126.602996 -253.983923) (xy 126.641117 -253.952798) (xy 126.683738 -253.928191)
			(xy 126.729754 -253.910739) (xy 126.777973 -253.900895) (xy 126.827148 -253.898914) (xy 126.876003 -253.904846)
			(xy 126.923274 -253.918538) (xy 126.967736 -253.939636) (xy 127.008239 -253.967592) (xy 127.043732 -254.001684)
			(xy 127.073297 -254.041028) (xy 127.096168 -254.084605) (xy 127.111752 -254.131286) (xy 127.119647 -254.179863)
			(xy 127.120142 -254.20447) (xy 127.438399 -254.20447) (xy 127.442494 -254.153742) (xy 127.454673 -254.104328)
			(xy 127.474621 -254.057508) (xy 127.501822 -254.014494) (xy 127.53557 -253.9764) (xy 127.574992 -253.944213)
			(xy 127.619066 -253.918767) (xy 127.666652 -253.90072) (xy 127.716516 -253.89054) (xy 127.767368 -253.888491)
			(xy 127.817889 -253.894625) (xy 127.866773 -253.908785) (xy 127.912752 -253.930602) (xy 127.954636 -253.959512)
			(xy 127.99134 -253.994767) (xy 128.021913 -254.035453) (xy 128.045564 -254.080516) (xy 128.06168 -254.12879)
			(xy 128.069844 -254.179024) (xy 128.070356 -254.20447) (xy 128.388884 -254.20447) (xy 128.392844 -254.155416)
			(xy 128.404621 -254.107632) (xy 128.423912 -254.062356) (xy 128.450215 -254.02076) (xy 128.48285 -253.983923)
			(xy 128.520971 -253.952798) (xy 128.563592 -253.928191) (xy 128.609608 -253.910739) (xy 128.657827 -253.900895)
			(xy 128.707002 -253.898914) (xy 128.755857 -253.904846) (xy 128.803128 -253.918538) (xy 128.84759 -253.939636)
			(xy 128.888093 -253.967592) (xy 128.923586 -254.001684) (xy 128.953151 -254.041028) (xy 128.976022 -254.084605)
			(xy 128.991606 -254.131286) (xy 128.999501 -254.179863) (xy 128.999996 -254.20447) (xy 129.318507 -254.20447)
			(xy 129.322602 -254.153742) (xy 129.334781 -254.104328) (xy 129.354729 -254.057508) (xy 129.38193 -254.014494)
			(xy 129.415678 -253.9764) (xy 129.4551 -253.944213) (xy 129.499174 -253.918767) (xy 129.54676 -253.90072)
			(xy 129.596624 -253.89054) (xy 129.647476 -253.888491) (xy 129.697997 -253.894625) (xy 129.746881 -253.908785)
			(xy 129.79286 -253.930602) (xy 129.834744 -253.959512) (xy 129.871448 -253.994767) (xy 129.902021 -254.035453)
			(xy 129.925672 -254.080516) (xy 129.941788 -254.12879) (xy 129.949952 -254.179024) (xy 129.950464 -254.20447)
			(xy 131.198615 -254.20447) (xy 131.20271 -254.153742) (xy 131.214889 -254.104328) (xy 131.234837 -254.057508)
			(xy 131.262038 -254.014494) (xy 131.295786 -253.9764) (xy 131.335208 -253.944213) (xy 131.379282 -253.918767)
			(xy 131.426868 -253.90072) (xy 131.476732 -253.89054) (xy 131.527584 -253.888491) (xy 131.578105 -253.894625)
			(xy 131.626989 -253.908785) (xy 131.672968 -253.930602) (xy 131.714852 -253.959512) (xy 131.751556 -253.994767)
			(xy 131.782129 -254.035453) (xy 131.80578 -254.080516) (xy 131.821896 -254.12879) (xy 131.83006 -254.179024)
			(xy 131.830572 -254.20447) (xy 132.138415 -254.20447) (xy 132.14251 -254.153742) (xy 132.154689 -254.104328)
			(xy 132.174637 -254.057508) (xy 132.201838 -254.014494) (xy 132.235586 -253.9764) (xy 132.275008 -253.944213)
			(xy 132.319082 -253.918767) (xy 132.366668 -253.90072) (xy 132.416532 -253.89054) (xy 132.467384 -253.888491)
			(xy 132.517905 -253.894625) (xy 132.566789 -253.908785) (xy 132.612768 -253.930602) (xy 132.654652 -253.959512)
			(xy 132.691356 -253.994767) (xy 132.721929 -254.035453) (xy 132.74558 -254.080516) (xy 132.761696 -254.12879)
			(xy 132.76986 -254.179024) (xy 132.770372 -254.20447) (xy 132.76986 -254.229916) (xy 132.761696 -254.28015)
			(xy 132.74558 -254.328424) (xy 132.721929 -254.373487) (xy 132.691356 -254.414173) (xy 132.654652 -254.449428)
			(xy 132.612768 -254.478338) (xy 132.566789 -254.500155) (xy 132.517905 -254.514315) (xy 132.467384 -254.520449)
			(xy 132.416532 -254.5184) (xy 132.366668 -254.50822) (xy 132.319082 -254.490173) (xy 132.275008 -254.464727)
			(xy 132.235586 -254.43254) (xy 132.201838 -254.394446) (xy 132.174637 -254.351432) (xy 132.154689 -254.304612)
			(xy 132.14251 -254.255198) (xy 132.138415 -254.20447) (xy 131.830572 -254.20447) (xy 131.83006 -254.229916)
			(xy 131.821896 -254.28015) (xy 131.80578 -254.328424) (xy 131.782129 -254.373487) (xy 131.751556 -254.414173)
			(xy 131.714852 -254.449428) (xy 131.672968 -254.478338) (xy 131.626989 -254.500155) (xy 131.578105 -254.514315)
			(xy 131.527584 -254.520449) (xy 131.476732 -254.5184) (xy 131.426868 -254.50822) (xy 131.379282 -254.490173)
			(xy 131.335208 -254.464727) (xy 131.295786 -254.43254) (xy 131.262038 -254.394446) (xy 131.234837 -254.351432)
			(xy 131.214889 -254.304612) (xy 131.20271 -254.255198) (xy 131.198615 -254.20447) (xy 129.950464 -254.20447)
			(xy 129.949952 -254.229916) (xy 129.941788 -254.28015) (xy 129.925672 -254.328424) (xy 129.902021 -254.373487)
			(xy 129.871448 -254.414173) (xy 129.834744 -254.449428) (xy 129.79286 -254.478338) (xy 129.746881 -254.500155)
			(xy 129.697997 -254.514315) (xy 129.647476 -254.520449) (xy 129.596624 -254.5184) (xy 129.54676 -254.50822)
			(xy 129.499174 -254.490173) (xy 129.4551 -254.464727) (xy 129.415678 -254.43254) (xy 129.38193 -254.394446)
			(xy 129.354729 -254.351432) (xy 129.334781 -254.304612) (xy 129.322602 -254.255198) (xy 129.318507 -254.20447)
			(xy 128.999996 -254.20447) (xy 128.999501 -254.229077) (xy 128.991606 -254.277654) (xy 128.976022 -254.324335)
			(xy 128.953151 -254.367912) (xy 128.923586 -254.407256) (xy 128.888093 -254.441348) (xy 128.84759 -254.469304)
			(xy 128.803128 -254.490402) (xy 128.755857 -254.504094) (xy 128.707002 -254.510026) (xy 128.657827 -254.508045)
			(xy 128.609608 -254.498201) (xy 128.563592 -254.480749) (xy 128.520971 -254.456142) (xy 128.48285 -254.425017)
			(xy 128.450215 -254.38818) (xy 128.423912 -254.346584) (xy 128.404621 -254.301308) (xy 128.392844 -254.253524)
			(xy 128.388884 -254.20447) (xy 128.070356 -254.20447) (xy 128.069844 -254.229916) (xy 128.06168 -254.28015)
			(xy 128.045564 -254.328424) (xy 128.021913 -254.373487) (xy 127.99134 -254.414173) (xy 127.954636 -254.449428)
			(xy 127.912752 -254.478338) (xy 127.866773 -254.500155) (xy 127.817889 -254.514315) (xy 127.767368 -254.520449)
			(xy 127.716516 -254.5184) (xy 127.666652 -254.50822) (xy 127.619066 -254.490173) (xy 127.574992 -254.464727)
			(xy 127.53557 -254.43254) (xy 127.501822 -254.394446) (xy 127.474621 -254.351432) (xy 127.454673 -254.304612)
			(xy 127.442494 -254.255198) (xy 127.438399 -254.20447) (xy 127.120142 -254.20447) (xy 127.119647 -254.229077)
			(xy 127.111752 -254.277654) (xy 127.096168 -254.324335) (xy 127.073297 -254.367912) (xy 127.043732 -254.407256)
			(xy 127.008239 -254.441348) (xy 126.967736 -254.469304) (xy 126.923274 -254.490402) (xy 126.876003 -254.504094)
			(xy 126.827148 -254.510026) (xy 126.777973 -254.508045) (xy 126.729754 -254.498201) (xy 126.683738 -254.480749)
			(xy 126.641117 -254.456142) (xy 126.602996 -254.425017) (xy 126.570361 -254.38818) (xy 126.544058 -254.346584)
			(xy 126.524767 -254.301308) (xy 126.51299 -254.253524) (xy 126.50903 -254.20447) (xy 125.240034 -254.20447)
			(xy 125.239539 -254.229077) (xy 125.231644 -254.277654) (xy 125.21606 -254.324335) (xy 125.193189 -254.367912)
			(xy 125.163624 -254.407256) (xy 125.128131 -254.441348) (xy 125.087628 -254.469304) (xy 125.043166 -254.490402)
			(xy 124.995895 -254.504094) (xy 124.94704 -254.510026) (xy 124.897865 -254.508045) (xy 124.849646 -254.498201)
			(xy 124.80363 -254.480749) (xy 124.761009 -254.456142) (xy 124.722888 -254.425017) (xy 124.690253 -254.38818)
			(xy 124.66395 -254.346584) (xy 124.644659 -254.301308) (xy 124.632882 -254.253524) (xy 124.628922 -254.20447)
			(xy 123.359926 -254.20447) (xy 123.359431 -254.229077) (xy 123.351536 -254.277654) (xy 123.335952 -254.324335)
			(xy 123.313081 -254.367912) (xy 123.283516 -254.407256) (xy 123.248023 -254.441348) (xy 123.20752 -254.469304)
			(xy 123.163058 -254.490402) (xy 123.115787 -254.504094) (xy 123.066932 -254.510026) (xy 123.017757 -254.508045)
			(xy 122.969538 -254.498201) (xy 122.923522 -254.480749) (xy 122.880901 -254.456142) (xy 122.84278 -254.425017)
			(xy 122.810145 -254.38818) (xy 122.783842 -254.346584) (xy 122.764551 -254.301308) (xy 122.752774 -254.253524)
			(xy 122.748814 -254.20447) (xy 121.480072 -254.20447) (xy 121.479577 -254.229077) (xy 121.471682 -254.277654)
			(xy 121.456098 -254.324335) (xy 121.433227 -254.367912) (xy 121.403662 -254.407256) (xy 121.368169 -254.441348)
			(xy 121.327666 -254.469304) (xy 121.283204 -254.490402) (xy 121.235933 -254.504094) (xy 121.187078 -254.510026)
			(xy 121.137903 -254.508045) (xy 121.089684 -254.498201) (xy 121.043668 -254.480749) (xy 121.001047 -254.456142)
			(xy 120.962926 -254.425017) (xy 120.930291 -254.38818) (xy 120.903988 -254.346584) (xy 120.884697 -254.301308)
			(xy 120.87292 -254.253524) (xy 120.86896 -254.20447) (xy 112.49858 -254.20447) (xy 112.522912 -254.229752)
			(xy 112.553204 -254.272818) (xy 112.576567 -254.320003) (xy 112.592453 -254.370202) (xy 112.60049 -254.422238)
			(xy 112.600994 -254.448564) (xy 112.60049 -254.47489) (xy 112.592453 -254.526926) (xy 112.576567 -254.577125)
			(xy 112.553204 -254.62431) (xy 112.522912 -254.667376) (xy 112.4864 -254.705314) (xy 112.444526 -254.737233)
			(xy 112.39827 -254.762386) (xy 112.348717 -254.780184) (xy 112.297027 -254.790208) (xy 112.244413 -254.792225)
			(xy 112.192108 -254.786187) (xy 112.141337 -254.772235) (xy 112.093292 -254.750696) (xy 112.049097 -254.722076)
			(xy 112.009789 -254.687045) (xy 111.976289 -254.646424) (xy 111.949383 -254.601165) (xy 111.9297 -254.55233)
			(xy 111.917703 -254.501062) (xy 111.913673 -254.448564) (xy 101.623946 -254.448564) (xy 101.593898 -254.469304)
			(xy 101.549436 -254.490402) (xy 101.502165 -254.504094) (xy 101.45331 -254.510026) (xy 101.404135 -254.508045)
			(xy 101.355916 -254.498201) (xy 101.3099 -254.480749) (xy 101.267279 -254.456142) (xy 101.229158 -254.425017)
			(xy 101.196523 -254.38818) (xy 101.17022 -254.346584) (xy 101.150929 -254.301308) (xy 101.139152 -254.253524)
			(xy 101.135192 -254.20447) (xy 100.805626 -254.20447) (xy 100.805626 -254.229712) (xy 100.797343 -254.279457)
			(xy 100.781002 -254.327165) (xy 100.757045 -254.371542) (xy 100.726125 -254.41138) (xy 100.689081 -254.445598)
			(xy 100.646919 -254.473267) (xy 100.600786 -254.493634) (xy 100.551933 -254.506147) (xy 100.52685 -254.508762)
			(xy 100.517452 -254.509524) (xy 100.501196 -254.517398) (xy 100.474018 -254.545592) (xy 100.466906 -254.552704)
			(xy 100.45954 -254.570992) (xy 100.45954 -255.014476) (xy 101.605346 -255.014476) (xy 101.609306 -254.965422)
			(xy 101.621083 -254.917638) (xy 101.640374 -254.872362) (xy 101.666677 -254.830766) (xy 101.699312 -254.793929)
			(xy 101.737433 -254.762804) (xy 101.780054 -254.738197) (xy 101.82607 -254.720745) (xy 101.874289 -254.710901)
			(xy 101.923464 -254.70892) (xy 101.972319 -254.714852) (xy 102.01959 -254.728544) (xy 102.064052 -254.749642)
			(xy 102.104555 -254.777598) (xy 102.140048 -254.81169) (xy 102.169613 -254.851034) (xy 102.192484 -254.894611)
			(xy 102.208068 -254.941292) (xy 102.215963 -254.989869) (xy 102.216458 -255.014476) (xy 122.278914 -255.014476)
			(xy 122.282874 -254.965422) (xy 122.294651 -254.917638) (xy 122.313942 -254.872362) (xy 122.340245 -254.830766)
			(xy 122.37288 -254.793929) (xy 122.411001 -254.762804) (xy 122.453622 -254.738197) (xy 122.499638 -254.720745)
			(xy 122.547857 -254.710901) (xy 122.597032 -254.70892) (xy 122.645887 -254.714852) (xy 122.693158 -254.728544)
			(xy 122.73762 -254.749642) (xy 122.778123 -254.777598) (xy 122.813616 -254.81169) (xy 122.843181 -254.851034)
			(xy 122.866052 -254.894611) (xy 122.881636 -254.941292) (xy 122.889531 -254.989869) (xy 122.890026 -255.014476)
			(xy 124.159022 -255.014476) (xy 124.162982 -254.965422) (xy 124.174759 -254.917638) (xy 124.19405 -254.872362)
			(xy 124.220353 -254.830766) (xy 124.252988 -254.793929) (xy 124.291109 -254.762804) (xy 124.33373 -254.738197)
			(xy 124.379746 -254.720745) (xy 124.427965 -254.710901) (xy 124.47714 -254.70892) (xy 124.525995 -254.714852)
			(xy 124.573266 -254.728544) (xy 124.617728 -254.749642) (xy 124.658231 -254.777598) (xy 124.693724 -254.81169)
			(xy 124.723289 -254.851034) (xy 124.74616 -254.894611) (xy 124.761744 -254.941292) (xy 124.769639 -254.989869)
			(xy 124.770134 -255.014476) (xy 126.038876 -255.014476) (xy 126.042836 -254.965422) (xy 126.054613 -254.917638)
			(xy 126.073904 -254.872362) (xy 126.100207 -254.830766) (xy 126.132842 -254.793929) (xy 126.170963 -254.762804)
			(xy 126.213584 -254.738197) (xy 126.2596 -254.720745) (xy 126.307819 -254.710901) (xy 126.356994 -254.70892)
			(xy 126.405849 -254.714852) (xy 126.45312 -254.728544) (xy 126.497582 -254.749642) (xy 126.538085 -254.777598)
			(xy 126.573578 -254.81169) (xy 126.603143 -254.851034) (xy 126.626014 -254.894611) (xy 126.641598 -254.941292)
			(xy 126.649493 -254.989869) (xy 126.649988 -255.014476) (xy 127.908553 -255.014476) (xy 127.912648 -254.963748)
			(xy 127.924827 -254.914334) (xy 127.944775 -254.867514) (xy 127.971976 -254.8245) (xy 128.005724 -254.786406)
			(xy 128.045146 -254.754219) (xy 128.08922 -254.728773) (xy 128.136806 -254.710726) (xy 128.18667 -254.700546)
			(xy 128.237522 -254.698497) (xy 128.288043 -254.704631) (xy 128.336927 -254.718791) (xy 128.382906 -254.740608)
			(xy 128.42479 -254.769518) (xy 128.461494 -254.804773) (xy 128.492067 -254.845459) (xy 128.515718 -254.890522)
			(xy 128.531834 -254.938796) (xy 128.539998 -254.98903) (xy 128.54051 -255.014476) (xy 128.848607 -255.014476)
			(xy 128.852702 -254.963748) (xy 128.864881 -254.914334) (xy 128.884829 -254.867514) (xy 128.91203 -254.8245)
			(xy 128.945778 -254.786406) (xy 128.9852 -254.754219) (xy 129.029274 -254.728773) (xy 129.07686 -254.710726)
			(xy 129.126724 -254.700546) (xy 129.177576 -254.698497) (xy 129.228097 -254.704631) (xy 129.276981 -254.718791)
			(xy 129.32296 -254.740608) (xy 129.364844 -254.769518) (xy 129.401548 -254.804773) (xy 129.432121 -254.845459)
			(xy 129.455772 -254.890522) (xy 129.471888 -254.938796) (xy 129.480052 -254.98903) (xy 129.480564 -255.014476)
			(xy 129.798838 -255.014476) (xy 129.802798 -254.965422) (xy 129.814575 -254.917638) (xy 129.833866 -254.872362)
			(xy 129.860169 -254.830766) (xy 129.892804 -254.793929) (xy 129.930925 -254.762804) (xy 129.973546 -254.738197)
			(xy 130.019562 -254.720745) (xy 130.067781 -254.710901) (xy 130.116956 -254.70892) (xy 130.165811 -254.714852)
			(xy 130.213082 -254.728544) (xy 130.257544 -254.749642) (xy 130.298047 -254.777598) (xy 130.33354 -254.81169)
			(xy 130.363105 -254.851034) (xy 130.385976 -254.894611) (xy 130.40156 -254.941292) (xy 130.409455 -254.989869)
			(xy 130.40995 -255.014476) (xy 130.728461 -255.014476) (xy 130.732556 -254.963748) (xy 130.744735 -254.914334)
			(xy 130.764683 -254.867514) (xy 130.791884 -254.8245) (xy 130.825632 -254.786406) (xy 130.865054 -254.754219)
			(xy 130.909128 -254.728773) (xy 130.956714 -254.710726) (xy 131.006578 -254.700546) (xy 131.05743 -254.698497)
			(xy 131.107951 -254.704631) (xy 131.156835 -254.718791) (xy 131.202814 -254.740608) (xy 131.244698 -254.769518)
			(xy 131.281402 -254.804773) (xy 131.311975 -254.845459) (xy 131.335626 -254.890522) (xy 131.351742 -254.938796)
			(xy 131.359906 -254.98903) (xy 131.360418 -255.014476) (xy 131.678946 -255.014476) (xy 131.682906 -254.965422)
			(xy 131.694683 -254.917638) (xy 131.713974 -254.872362) (xy 131.740277 -254.830766) (xy 131.772912 -254.793929)
			(xy 131.811033 -254.762804) (xy 131.853654 -254.738197) (xy 131.89967 -254.720745) (xy 131.947889 -254.710901)
			(xy 131.997064 -254.70892) (xy 132.045919 -254.714852) (xy 132.09319 -254.728544) (xy 132.137652 -254.749642)
			(xy 132.178155 -254.777598) (xy 132.213648 -254.81169) (xy 132.243213 -254.851034) (xy 132.266084 -254.894611)
			(xy 132.281668 -254.941292) (xy 132.289563 -254.989869) (xy 132.290058 -255.014476) (xy 132.608569 -255.014476)
			(xy 132.612664 -254.963748) (xy 132.624843 -254.914334) (xy 132.644791 -254.867514) (xy 132.671992 -254.8245)
			(xy 132.70574 -254.786406) (xy 132.745162 -254.754219) (xy 132.789236 -254.728773) (xy 132.836822 -254.710726)
			(xy 132.886686 -254.700546) (xy 132.937538 -254.698497) (xy 132.988059 -254.704631) (xy 133.036943 -254.718791)
			(xy 133.082922 -254.740608) (xy 133.124806 -254.769518) (xy 133.16151 -254.804773) (xy 133.192083 -254.845459)
			(xy 133.215734 -254.890522) (xy 133.23185 -254.938796) (xy 133.240014 -254.98903) (xy 133.240526 -255.014476)
			(xy 133.240014 -255.039922) (xy 133.23185 -255.090156) (xy 133.215734 -255.13843) (xy 133.192083 -255.183493)
			(xy 133.16151 -255.224179) (xy 133.124806 -255.259434) (xy 133.082922 -255.288344) (xy 133.036943 -255.310161)
			(xy 132.988059 -255.324321) (xy 132.937538 -255.330455) (xy 132.886686 -255.328406) (xy 132.836822 -255.318226)
			(xy 132.789236 -255.300179) (xy 132.745162 -255.274733) (xy 132.70574 -255.242546) (xy 132.671992 -255.204452)
			(xy 132.644791 -255.161438) (xy 132.624843 -255.114618) (xy 132.612664 -255.065204) (xy 132.608569 -255.014476)
			(xy 132.290058 -255.014476) (xy 132.289563 -255.039083) (xy 132.281668 -255.08766) (xy 132.266084 -255.134341)
			(xy 132.243213 -255.177918) (xy 132.213648 -255.217262) (xy 132.178155 -255.251354) (xy 132.137652 -255.27931)
			(xy 132.09319 -255.300408) (xy 132.045919 -255.3141) (xy 131.997064 -255.320032) (xy 131.947889 -255.318051)
			(xy 131.89967 -255.308207) (xy 131.853654 -255.290755) (xy 131.811033 -255.266148) (xy 131.772912 -255.235023)
			(xy 131.740277 -255.198186) (xy 131.713974 -255.15659) (xy 131.694683 -255.111314) (xy 131.682906 -255.06353)
			(xy 131.678946 -255.014476) (xy 131.360418 -255.014476) (xy 131.359906 -255.039922) (xy 131.351742 -255.090156)
			(xy 131.335626 -255.13843) (xy 131.311975 -255.183493) (xy 131.281402 -255.224179) (xy 131.244698 -255.259434)
			(xy 131.202814 -255.288344) (xy 131.156835 -255.310161) (xy 131.107951 -255.324321) (xy 131.05743 -255.330455)
			(xy 131.006578 -255.328406) (xy 130.956714 -255.318226) (xy 130.909128 -255.300179) (xy 130.865054 -255.274733)
			(xy 130.825632 -255.242546) (xy 130.791884 -255.204452) (xy 130.764683 -255.161438) (xy 130.744735 -255.114618)
			(xy 130.732556 -255.065204) (xy 130.728461 -255.014476) (xy 130.40995 -255.014476) (xy 130.409455 -255.039083)
			(xy 130.40156 -255.08766) (xy 130.385976 -255.134341) (xy 130.363105 -255.177918) (xy 130.33354 -255.217262)
			(xy 130.298047 -255.251354) (xy 130.257544 -255.27931) (xy 130.213082 -255.300408) (xy 130.165811 -255.3141)
			(xy 130.116956 -255.320032) (xy 130.067781 -255.318051) (xy 130.019562 -255.308207) (xy 129.973546 -255.290755)
			(xy 129.930925 -255.266148) (xy 129.892804 -255.235023) (xy 129.860169 -255.198186) (xy 129.833866 -255.15659)
			(xy 129.814575 -255.111314) (xy 129.802798 -255.06353) (xy 129.798838 -255.014476) (xy 129.480564 -255.014476)
			(xy 129.480052 -255.039922) (xy 129.471888 -255.090156) (xy 129.455772 -255.13843) (xy 129.432121 -255.183493)
			(xy 129.401548 -255.224179) (xy 129.364844 -255.259434) (xy 129.32296 -255.288344) (xy 129.276981 -255.310161)
			(xy 129.228097 -255.324321) (xy 129.177576 -255.330455) (xy 129.126724 -255.328406) (xy 129.07686 -255.318226)
			(xy 129.029274 -255.300179) (xy 128.9852 -255.274733) (xy 128.945778 -255.242546) (xy 128.91203 -255.204452)
			(xy 128.884829 -255.161438) (xy 128.864881 -255.114618) (xy 128.852702 -255.065204) (xy 128.848607 -255.014476)
			(xy 128.54051 -255.014476) (xy 128.539998 -255.039922) (xy 128.531834 -255.090156) (xy 128.515718 -255.13843)
			(xy 128.492067 -255.183493) (xy 128.461494 -255.224179) (xy 128.42479 -255.259434) (xy 128.382906 -255.288344)
			(xy 128.336927 -255.310161) (xy 128.288043 -255.324321) (xy 128.237522 -255.330455) (xy 128.18667 -255.328406)
			(xy 128.136806 -255.318226) (xy 128.08922 -255.300179) (xy 128.045146 -255.274733) (xy 128.005724 -255.242546)
			(xy 127.971976 -255.204452) (xy 127.944775 -255.161438) (xy 127.924827 -255.114618) (xy 127.912648 -255.065204)
			(xy 127.908553 -255.014476) (xy 126.649988 -255.014476) (xy 126.649493 -255.039083) (xy 126.641598 -255.08766)
			(xy 126.626014 -255.134341) (xy 126.603143 -255.177918) (xy 126.573578 -255.217262) (xy 126.538085 -255.251354)
			(xy 126.497582 -255.27931) (xy 126.45312 -255.300408) (xy 126.405849 -255.3141) (xy 126.356994 -255.320032)
			(xy 126.307819 -255.318051) (xy 126.2596 -255.308207) (xy 126.213584 -255.290755) (xy 126.170963 -255.266148)
			(xy 126.132842 -255.235023) (xy 126.100207 -255.198186) (xy 126.073904 -255.15659) (xy 126.054613 -255.111314)
			(xy 126.042836 -255.06353) (xy 126.038876 -255.014476) (xy 124.770134 -255.014476) (xy 124.769639 -255.039083)
			(xy 124.761744 -255.08766) (xy 124.74616 -255.134341) (xy 124.723289 -255.177918) (xy 124.693724 -255.217262)
			(xy 124.658231 -255.251354) (xy 124.617728 -255.27931) (xy 124.573266 -255.300408) (xy 124.525995 -255.3141)
			(xy 124.47714 -255.320032) (xy 124.427965 -255.318051) (xy 124.379746 -255.308207) (xy 124.33373 -255.290755)
			(xy 124.291109 -255.266148) (xy 124.252988 -255.235023) (xy 124.220353 -255.198186) (xy 124.19405 -255.15659)
			(xy 124.174759 -255.111314) (xy 124.162982 -255.06353) (xy 124.159022 -255.014476) (xy 122.890026 -255.014476)
			(xy 122.889531 -255.039083) (xy 122.881636 -255.08766) (xy 122.866052 -255.134341) (xy 122.843181 -255.177918)
			(xy 122.813616 -255.217262) (xy 122.778123 -255.251354) (xy 122.73762 -255.27931) (xy 122.693158 -255.300408)
			(xy 122.645887 -255.3141) (xy 122.597032 -255.320032) (xy 122.547857 -255.318051) (xy 122.499638 -255.308207)
			(xy 122.453622 -255.290755) (xy 122.411001 -255.266148) (xy 122.37288 -255.235023) (xy 122.340245 -255.198186)
			(xy 122.313942 -255.15659) (xy 122.294651 -255.111314) (xy 122.282874 -255.06353) (xy 122.278914 -255.014476)
			(xy 102.216458 -255.014476) (xy 102.215963 -255.039083) (xy 102.208068 -255.08766) (xy 102.192484 -255.134341)
			(xy 102.169613 -255.177918) (xy 102.140048 -255.217262) (xy 102.104555 -255.251354) (xy 102.064052 -255.27931)
			(xy 102.01959 -255.300408) (xy 101.972319 -255.3141) (xy 101.923464 -255.320032) (xy 101.874289 -255.318051)
			(xy 101.82607 -255.308207) (xy 101.780054 -255.290755) (xy 101.737433 -255.266148) (xy 101.699312 -255.235023)
			(xy 101.666677 -255.198186) (xy 101.640374 -255.15659) (xy 101.621083 -255.111314) (xy 101.609306 -255.06353)
			(xy 101.605346 -255.014476) (xy 100.45954 -255.014476) (xy 100.45954 -255.45796) (xy 100.466906 -255.476248)
			(xy 100.474018 -255.48336) (xy 100.501196 -255.511554) (xy 100.517452 -255.519428) (xy 100.52685 -255.52019)
			(xy 100.551936 -255.522843) (xy 100.600811 -255.535322) (xy 100.646968 -255.555667) (xy 100.689152 -255.583324)
			(xy 100.726214 -255.617541) (xy 100.757146 -255.657387) (xy 100.781104 -255.701776) (xy 100.797438 -255.7495)
			(xy 100.805703 -255.799261) (xy 100.80625 -255.824482) (xy 101.135192 -255.824482) (xy 101.139152 -255.775428)
			(xy 101.150929 -255.727644) (xy 101.17022 -255.682368) (xy 101.196523 -255.640772) (xy 101.229158 -255.603935)
			(xy 101.267279 -255.57281) (xy 101.3099 -255.548203) (xy 101.355916 -255.530751) (xy 101.404135 -255.520907)
			(xy 101.45331 -255.518926) (xy 101.502165 -255.524858) (xy 101.549436 -255.53855) (xy 101.593898 -255.559648)
			(xy 101.634401 -255.587604) (xy 101.669894 -255.621696) (xy 101.699459 -255.66104) (xy 101.72233 -255.704617)
			(xy 101.737914 -255.751298) (xy 101.745809 -255.799875) (xy 101.746263 -255.82245) (xy 103.952052 -255.82245)
			(xy 103.956012 -255.773396) (xy 103.967789 -255.725612) (xy 103.98708 -255.680336) (xy 104.013383 -255.63874)
			(xy 104.046018 -255.601903) (xy 104.084139 -255.570778) (xy 104.12676 -255.546171) (xy 104.172776 -255.528719)
			(xy 104.220995 -255.518875) (xy 104.27017 -255.516894) (xy 104.319025 -255.522826) (xy 104.345001 -255.53035)
			(xy 105.146859 -255.53035) (xy 105.150889 -255.477852) (xy 105.162886 -255.426584) (xy 105.182569 -255.377749)
			(xy 105.209475 -255.33249) (xy 105.242975 -255.291869) (xy 105.282283 -255.256838) (xy 105.326478 -255.228218)
			(xy 105.374523 -255.206679) (xy 105.425294 -255.192727) (xy 105.477599 -255.186689) (xy 105.530213 -255.188706)
			(xy 105.581903 -255.19873) (xy 105.631456 -255.216528) (xy 105.677712 -255.241681) (xy 105.719586 -255.2736)
			(xy 105.756098 -255.311538) (xy 105.78639 -255.354604) (xy 105.809753 -255.401789) (xy 105.825639 -255.451988)
			(xy 105.833676 -255.504024) (xy 105.83418 -255.53035) (xy 106.061259 -255.53035) (xy 106.065289 -255.477852)
			(xy 106.077286 -255.426584) (xy 106.096969 -255.377749) (xy 106.123875 -255.33249) (xy 106.157375 -255.291869)
			(xy 106.196683 -255.256838) (xy 106.240878 -255.228218) (xy 106.288923 -255.206679) (xy 106.339694 -255.192727)
			(xy 106.391999 -255.186689) (xy 106.444613 -255.188706) (xy 106.496303 -255.19873) (xy 106.545856 -255.216528)
			(xy 106.592112 -255.241681) (xy 106.633986 -255.2736) (xy 106.670498 -255.311538) (xy 106.70079 -255.354604)
			(xy 106.724153 -255.401789) (xy 106.740039 -255.451988) (xy 106.748076 -255.504024) (xy 106.74858 -255.53035)
			(xy 117.096797 -255.53035) (xy 117.100827 -255.477852) (xy 117.112824 -255.426584) (xy 117.132507 -255.377749)
			(xy 117.159413 -255.33249) (xy 117.192913 -255.291869) (xy 117.232221 -255.256838) (xy 117.276416 -255.228218)
			(xy 117.324461 -255.206679) (xy 117.375232 -255.192727) (xy 117.427537 -255.186689) (xy 117.480151 -255.188706)
			(xy 117.531841 -255.19873) (xy 117.581394 -255.216528) (xy 117.62765 -255.241681) (xy 117.669524 -255.2736)
			(xy 117.706036 -255.311538) (xy 117.736328 -255.354604) (xy 117.759691 -255.401789) (xy 117.775577 -255.451988)
			(xy 117.783614 -255.504024) (xy 117.784118 -255.53035) (xy 117.783614 -255.556676) (xy 117.775577 -255.608712)
			(xy 117.759691 -255.658911) (xy 117.736328 -255.706096) (xy 117.706036 -255.749162) (xy 117.669524 -255.7871)
			(xy 117.62765 -255.819019) (xy 117.617604 -255.824482) (xy 120.86896 -255.824482) (xy 120.87292 -255.775428)
			(xy 120.884697 -255.727644) (xy 120.903988 -255.682368) (xy 120.930291 -255.640772) (xy 120.962926 -255.603935)
			(xy 121.001047 -255.57281) (xy 121.043668 -255.548203) (xy 121.089684 -255.530751) (xy 121.137903 -255.520907)
			(xy 121.187078 -255.518926) (xy 121.235933 -255.524858) (xy 121.283204 -255.53855) (xy 121.327666 -255.559648)
			(xy 121.368169 -255.587604) (xy 121.403662 -255.621696) (xy 121.433227 -255.66104) (xy 121.456098 -255.704617)
			(xy 121.471682 -255.751298) (xy 121.479577 -255.799875) (xy 121.480072 -255.824482) (xy 122.748814 -255.824482)
			(xy 122.752774 -255.775428) (xy 122.764551 -255.727644) (xy 122.783842 -255.682368) (xy 122.810145 -255.640772)
			(xy 122.84278 -255.603935) (xy 122.880901 -255.57281) (xy 122.923522 -255.548203) (xy 122.969538 -255.530751)
			(xy 123.017757 -255.520907) (xy 123.066932 -255.518926) (xy 123.115787 -255.524858) (xy 123.163058 -255.53855)
			(xy 123.20752 -255.559648) (xy 123.248023 -255.587604) (xy 123.283516 -255.621696) (xy 123.313081 -255.66104)
			(xy 123.335952 -255.704617) (xy 123.351536 -255.751298) (xy 123.359431 -255.799875) (xy 123.359926 -255.824482)
			(xy 124.628922 -255.824482) (xy 124.632882 -255.775428) (xy 124.644659 -255.727644) (xy 124.66395 -255.682368)
			(xy 124.690253 -255.640772) (xy 124.722888 -255.603935) (xy 124.761009 -255.57281) (xy 124.80363 -255.548203)
			(xy 124.849646 -255.530751) (xy 124.897865 -255.520907) (xy 124.94704 -255.518926) (xy 124.995895 -255.524858)
			(xy 125.043166 -255.53855) (xy 125.087628 -255.559648) (xy 125.128131 -255.587604) (xy 125.163624 -255.621696)
			(xy 125.193189 -255.66104) (xy 125.21606 -255.704617) (xy 125.231644 -255.751298) (xy 125.239539 -255.799875)
			(xy 125.240034 -255.824482) (xy 126.50903 -255.824482) (xy 126.51299 -255.775428) (xy 126.524767 -255.727644)
			(xy 126.544058 -255.682368) (xy 126.570361 -255.640772) (xy 126.602996 -255.603935) (xy 126.641117 -255.57281)
			(xy 126.683738 -255.548203) (xy 126.729754 -255.530751) (xy 126.777973 -255.520907) (xy 126.827148 -255.518926)
			(xy 126.876003 -255.524858) (xy 126.923274 -255.53855) (xy 126.967736 -255.559648) (xy 127.008239 -255.587604)
			(xy 127.043732 -255.621696) (xy 127.073297 -255.66104) (xy 127.096168 -255.704617) (xy 127.111752 -255.751298)
			(xy 127.119647 -255.799875) (xy 127.120142 -255.824482) (xy 127.438399 -255.824482) (xy 127.442494 -255.773754)
			(xy 127.454673 -255.72434) (xy 127.474621 -255.67752) (xy 127.501822 -255.634506) (xy 127.53557 -255.596412)
			(xy 127.574992 -255.564225) (xy 127.619066 -255.538779) (xy 127.666652 -255.520732) (xy 127.716516 -255.510552)
			(xy 127.767368 -255.508503) (xy 127.817889 -255.514637) (xy 127.866773 -255.528797) (xy 127.912752 -255.550614)
			(xy 127.954636 -255.579524) (xy 127.99134 -255.614779) (xy 128.021913 -255.655465) (xy 128.045564 -255.700528)
			(xy 128.06168 -255.748802) (xy 128.069844 -255.799036) (xy 128.070356 -255.824482) (xy 128.388884 -255.824482)
			(xy 128.392844 -255.775428) (xy 128.404621 -255.727644) (xy 128.423912 -255.682368) (xy 128.450215 -255.640772)
			(xy 128.48285 -255.603935) (xy 128.520971 -255.57281) (xy 128.563592 -255.548203) (xy 128.609608 -255.530751)
			(xy 128.657827 -255.520907) (xy 128.707002 -255.518926) (xy 128.755857 -255.524858) (xy 128.803128 -255.53855)
			(xy 128.84759 -255.559648) (xy 128.888093 -255.587604) (xy 128.923586 -255.621696) (xy 128.953151 -255.66104)
			(xy 128.976022 -255.704617) (xy 128.991606 -255.751298) (xy 128.999501 -255.799875) (xy 128.999996 -255.824482)
			(xy 129.318507 -255.824482) (xy 129.322602 -255.773754) (xy 129.334781 -255.72434) (xy 129.354729 -255.67752)
			(xy 129.38193 -255.634506) (xy 129.415678 -255.596412) (xy 129.4551 -255.564225) (xy 129.499174 -255.538779)
			(xy 129.54676 -255.520732) (xy 129.596624 -255.510552) (xy 129.647476 -255.508503) (xy 129.697997 -255.514637)
			(xy 129.746881 -255.528797) (xy 129.79286 -255.550614) (xy 129.834744 -255.579524) (xy 129.871448 -255.614779)
			(xy 129.902021 -255.655465) (xy 129.925672 -255.700528) (xy 129.941788 -255.748802) (xy 129.949952 -255.799036)
			(xy 129.950464 -255.824482) (xy 130.268992 -255.824482) (xy 130.272952 -255.775428) (xy 130.284729 -255.727644)
			(xy 130.30402 -255.682368) (xy 130.330323 -255.640772) (xy 130.362958 -255.603935) (xy 130.401079 -255.57281)
			(xy 130.4437 -255.548203) (xy 130.489716 -255.530751) (xy 130.537935 -255.520907) (xy 130.58711 -255.518926)
			(xy 130.635965 -255.524858) (xy 130.683236 -255.53855) (xy 130.727698 -255.559648) (xy 130.768201 -255.587604)
			(xy 130.803694 -255.621696) (xy 130.833259 -255.66104) (xy 130.85613 -255.704617) (xy 130.871714 -255.751298)
			(xy 130.879609 -255.799875) (xy 130.880104 -255.824482) (xy 131.198615 -255.824482) (xy 131.20271 -255.773754)
			(xy 131.214889 -255.72434) (xy 131.234837 -255.67752) (xy 131.262038 -255.634506) (xy 131.295786 -255.596412)
			(xy 131.335208 -255.564225) (xy 131.379282 -255.538779) (xy 131.426868 -255.520732) (xy 131.476732 -255.510552)
			(xy 131.527584 -255.508503) (xy 131.578105 -255.514637) (xy 131.626989 -255.528797) (xy 131.672968 -255.550614)
			(xy 131.714852 -255.579524) (xy 131.751556 -255.614779) (xy 131.782129 -255.655465) (xy 131.80578 -255.700528)
			(xy 131.821896 -255.748802) (xy 131.83006 -255.799036) (xy 131.830572 -255.824482) (xy 132.138415 -255.824482)
			(xy 132.14251 -255.773754) (xy 132.154689 -255.72434) (xy 132.174637 -255.67752) (xy 132.201838 -255.634506)
			(xy 132.235586 -255.596412) (xy 132.275008 -255.564225) (xy 132.319082 -255.538779) (xy 132.366668 -255.520732)
			(xy 132.416532 -255.510552) (xy 132.467384 -255.508503) (xy 132.517905 -255.514637) (xy 132.566789 -255.528797)
			(xy 132.612768 -255.550614) (xy 132.654652 -255.579524) (xy 132.691356 -255.614779) (xy 132.721929 -255.655465)
			(xy 132.74558 -255.700528) (xy 132.761696 -255.748802) (xy 132.76986 -255.799036) (xy 132.770372 -255.824482)
			(xy 132.76986 -255.849928) (xy 132.761696 -255.900162) (xy 132.74558 -255.948436) (xy 132.721929 -255.993499)
			(xy 132.691356 -256.034185) (xy 132.654652 -256.06944) (xy 132.612768 -256.09835) (xy 132.566789 -256.120167)
			(xy 132.517905 -256.134327) (xy 132.467384 -256.140461) (xy 132.416532 -256.138412) (xy 132.366668 -256.128232)
			(xy 132.319082 -256.110185) (xy 132.275008 -256.084739) (xy 132.235586 -256.052552) (xy 132.201838 -256.014458)
			(xy 132.174637 -255.971444) (xy 132.154689 -255.924624) (xy 132.14251 -255.87521) (xy 132.138415 -255.824482)
			(xy 131.830572 -255.824482) (xy 131.83006 -255.849928) (xy 131.821896 -255.900162) (xy 131.80578 -255.948436)
			(xy 131.782129 -255.993499) (xy 131.751556 -256.034185) (xy 131.714852 -256.06944) (xy 131.672968 -256.09835)
			(xy 131.626989 -256.120167) (xy 131.578105 -256.134327) (xy 131.527584 -256.140461) (xy 131.476732 -256.138412)
			(xy 131.426868 -256.128232) (xy 131.379282 -256.110185) (xy 131.335208 -256.084739) (xy 131.295786 -256.052552)
			(xy 131.262038 -256.014458) (xy 131.234837 -255.971444) (xy 131.214889 -255.924624) (xy 131.20271 -255.87521)
			(xy 131.198615 -255.824482) (xy 130.880104 -255.824482) (xy 130.879609 -255.849089) (xy 130.871714 -255.897666)
			(xy 130.85613 -255.944347) (xy 130.833259 -255.987924) (xy 130.803694 -256.027268) (xy 130.768201 -256.06136)
			(xy 130.727698 -256.089316) (xy 130.683236 -256.110414) (xy 130.635965 -256.124106) (xy 130.58711 -256.130038)
			(xy 130.537935 -256.128057) (xy 130.489716 -256.118213) (xy 130.4437 -256.100761) (xy 130.401079 -256.076154)
			(xy 130.362958 -256.045029) (xy 130.330323 -256.008192) (xy 130.30402 -255.966596) (xy 130.284729 -255.92132)
			(xy 130.272952 -255.873536) (xy 130.268992 -255.824482) (xy 129.950464 -255.824482) (xy 129.949952 -255.849928)
			(xy 129.941788 -255.900162) (xy 129.925672 -255.948436) (xy 129.902021 -255.993499) (xy 129.871448 -256.034185)
			(xy 129.834744 -256.06944) (xy 129.79286 -256.09835) (xy 129.746881 -256.120167) (xy 129.697997 -256.134327)
			(xy 129.647476 -256.140461) (xy 129.596624 -256.138412) (xy 129.54676 -256.128232) (xy 129.499174 -256.110185)
			(xy 129.4551 -256.084739) (xy 129.415678 -256.052552) (xy 129.38193 -256.014458) (xy 129.354729 -255.971444)
			(xy 129.334781 -255.924624) (xy 129.322602 -255.87521) (xy 129.318507 -255.824482) (xy 128.999996 -255.824482)
			(xy 128.999501 -255.849089) (xy 128.991606 -255.897666) (xy 128.976022 -255.944347) (xy 128.953151 -255.987924)
			(xy 128.923586 -256.027268) (xy 128.888093 -256.06136) (xy 128.84759 -256.089316) (xy 128.803128 -256.110414)
			(xy 128.755857 -256.124106) (xy 128.707002 -256.130038) (xy 128.657827 -256.128057) (xy 128.609608 -256.118213)
			(xy 128.563592 -256.100761) (xy 128.520971 -256.076154) (xy 128.48285 -256.045029) (xy 128.450215 -256.008192)
			(xy 128.423912 -255.966596) (xy 128.404621 -255.92132) (xy 128.392844 -255.873536) (xy 128.388884 -255.824482)
			(xy 128.070356 -255.824482) (xy 128.069844 -255.849928) (xy 128.06168 -255.900162) (xy 128.045564 -255.948436)
			(xy 128.021913 -255.993499) (xy 127.99134 -256.034185) (xy 127.954636 -256.06944) (xy 127.912752 -256.09835)
			(xy 127.866773 -256.120167) (xy 127.817889 -256.134327) (xy 127.767368 -256.140461) (xy 127.716516 -256.138412)
			(xy 127.666652 -256.128232) (xy 127.619066 -256.110185) (xy 127.574992 -256.084739) (xy 127.53557 -256.052552)
			(xy 127.501822 -256.014458) (xy 127.474621 -255.971444) (xy 127.454673 -255.924624) (xy 127.442494 -255.87521)
			(xy 127.438399 -255.824482) (xy 127.120142 -255.824482) (xy 127.119647 -255.849089) (xy 127.111752 -255.897666)
			(xy 127.096168 -255.944347) (xy 127.073297 -255.987924) (xy 127.043732 -256.027268) (xy 127.008239 -256.06136)
			(xy 126.967736 -256.089316) (xy 126.923274 -256.110414) (xy 126.876003 -256.124106) (xy 126.827148 -256.130038)
			(xy 126.777973 -256.128057) (xy 126.729754 -256.118213) (xy 126.683738 -256.100761) (xy 126.641117 -256.076154)
			(xy 126.602996 -256.045029) (xy 126.570361 -256.008192) (xy 126.544058 -255.966596) (xy 126.524767 -255.92132)
			(xy 126.51299 -255.873536) (xy 126.50903 -255.824482) (xy 125.240034 -255.824482) (xy 125.239539 -255.849089)
			(xy 125.231644 -255.897666) (xy 125.21606 -255.944347) (xy 125.193189 -255.987924) (xy 125.163624 -256.027268)
			(xy 125.128131 -256.06136) (xy 125.087628 -256.089316) (xy 125.043166 -256.110414) (xy 124.995895 -256.124106)
			(xy 124.94704 -256.130038) (xy 124.897865 -256.128057) (xy 124.849646 -256.118213) (xy 124.80363 -256.100761)
			(xy 124.761009 -256.076154) (xy 124.722888 -256.045029) (xy 124.690253 -256.008192) (xy 124.66395 -255.966596)
			(xy 124.644659 -255.92132) (xy 124.632882 -255.873536) (xy 124.628922 -255.824482) (xy 123.359926 -255.824482)
			(xy 123.359431 -255.849089) (xy 123.351536 -255.897666) (xy 123.335952 -255.944347) (xy 123.313081 -255.987924)
			(xy 123.283516 -256.027268) (xy 123.248023 -256.06136) (xy 123.20752 -256.089316) (xy 123.163058 -256.110414)
			(xy 123.115787 -256.124106) (xy 123.066932 -256.130038) (xy 123.017757 -256.128057) (xy 122.969538 -256.118213)
			(xy 122.923522 -256.100761) (xy 122.880901 -256.076154) (xy 122.84278 -256.045029) (xy 122.810145 -256.008192)
			(xy 122.783842 -255.966596) (xy 122.764551 -255.92132) (xy 122.752774 -255.873536) (xy 122.748814 -255.824482)
			(xy 121.480072 -255.824482) (xy 121.479577 -255.849089) (xy 121.471682 -255.897666) (xy 121.456098 -255.944347)
			(xy 121.433227 -255.987924) (xy 121.403662 -256.027268) (xy 121.368169 -256.06136) (xy 121.327666 -256.089316)
			(xy 121.283204 -256.110414) (xy 121.235933 -256.124106) (xy 121.187078 -256.130038) (xy 121.137903 -256.128057)
			(xy 121.089684 -256.118213) (xy 121.043668 -256.100761) (xy 121.001047 -256.076154) (xy 120.962926 -256.045029)
			(xy 120.930291 -256.008192) (xy 120.903988 -255.966596) (xy 120.884697 -255.92132) (xy 120.87292 -255.873536)
			(xy 120.86896 -255.824482) (xy 117.617604 -255.824482) (xy 117.581394 -255.844172) (xy 117.531841 -255.86197)
			(xy 117.480151 -255.871994) (xy 117.427537 -255.874011) (xy 117.375232 -255.867973) (xy 117.324461 -255.854021)
			(xy 117.276416 -255.832482) (xy 117.232221 -255.803862) (xy 117.192913 -255.768831) (xy 117.159413 -255.72821)
			(xy 117.132507 -255.682951) (xy 117.112824 -255.634116) (xy 117.100827 -255.582848) (xy 117.096797 -255.53035)
			(xy 106.74858 -255.53035) (xy 106.748076 -255.556676) (xy 106.740039 -255.608712) (xy 106.724153 -255.658911)
			(xy 106.70079 -255.706096) (xy 106.670498 -255.749162) (xy 106.633986 -255.7871) (xy 106.592112 -255.819019)
			(xy 106.545856 -255.844172) (xy 106.496303 -255.86197) (xy 106.444613 -255.871994) (xy 106.391999 -255.874011)
			(xy 106.339694 -255.867973) (xy 106.288923 -255.854021) (xy 106.240878 -255.832482) (xy 106.196683 -255.803862)
			(xy 106.157375 -255.768831) (xy 106.123875 -255.72821) (xy 106.096969 -255.682951) (xy 106.077286 -255.634116)
			(xy 106.065289 -255.582848) (xy 106.061259 -255.53035) (xy 105.83418 -255.53035) (xy 105.833676 -255.556676)
			(xy 105.825639 -255.608712) (xy 105.809753 -255.658911) (xy 105.78639 -255.706096) (xy 105.756098 -255.749162)
			(xy 105.719586 -255.7871) (xy 105.677712 -255.819019) (xy 105.631456 -255.844172) (xy 105.581903 -255.86197)
			(xy 105.530213 -255.871994) (xy 105.477599 -255.874011) (xy 105.425294 -255.867973) (xy 105.374523 -255.854021)
			(xy 105.326478 -255.832482) (xy 105.282283 -255.803862) (xy 105.242975 -255.768831) (xy 105.209475 -255.72821)
			(xy 105.182569 -255.682951) (xy 105.162886 -255.634116) (xy 105.150889 -255.582848) (xy 105.146859 -255.53035)
			(xy 104.345001 -255.53035) (xy 104.366296 -255.536518) (xy 104.410758 -255.557616) (xy 104.451261 -255.585572)
			(xy 104.486754 -255.619664) (xy 104.516319 -255.659008) (xy 104.53919 -255.702585) (xy 104.554774 -255.749266)
			(xy 104.562669 -255.797843) (xy 104.563164 -255.82245) (xy 104.562669 -255.847057) (xy 104.554774 -255.895634)
			(xy 104.53919 -255.942315) (xy 104.516319 -255.985892) (xy 104.486754 -256.025236) (xy 104.451261 -256.059328)
			(xy 104.410758 -256.087284) (xy 104.366296 -256.108382) (xy 104.319025 -256.122074) (xy 104.27017 -256.128006)
			(xy 104.220995 -256.126025) (xy 104.172776 -256.116181) (xy 104.12676 -256.098729) (xy 104.084139 -256.074122)
			(xy 104.046018 -256.042997) (xy 104.013383 -256.00616) (xy 103.98708 -255.964564) (xy 103.967789 -255.919288)
			(xy 103.956012 -255.871504) (xy 103.952052 -255.82245) (xy 101.746263 -255.82245) (xy 101.746304 -255.824482)
			(xy 101.745809 -255.849089) (xy 101.737914 -255.897666) (xy 101.72233 -255.944347) (xy 101.699459 -255.987924)
			(xy 101.669894 -256.027268) (xy 101.634401 -256.06136) (xy 101.593898 -256.089316) (xy 101.549436 -256.110414)
			(xy 101.502165 -256.124106) (xy 101.45331 -256.130038) (xy 101.404135 -256.128057) (xy 101.355916 -256.118213)
			(xy 101.3099 -256.100761) (xy 101.267279 -256.076154) (xy 101.229158 -256.045029) (xy 101.196523 -256.008192)
			(xy 101.17022 -255.966596) (xy 101.150929 -255.92132) (xy 101.139152 -255.873536) (xy 101.135192 -255.824482)
			(xy 100.80625 -255.824482) (xy 100.805861 -255.846837) (xy 100.799346 -255.89107) (xy 100.786453 -255.93388)
			(xy 100.777294 -255.954276) (xy 100.777294 -255.95453) (xy 100.773391 -255.964162) (xy 100.772833 -255.984918)
			(xy 100.780492 -256.004217) (xy 100.787454 -256.011934) (xy 101.628194 -256.852674) (xy 101.628702 -256.853182)
			(xy 101.636087 -256.859754) (xy 101.654386 -256.867182) (xy 101.664262 -256.86766) (xy 102.465886 -256.86766)
			(xy 102.478049 -256.866971) (xy 102.499678 -256.855836) (xy 102.507288 -256.846324) (xy 102.555294 -256.779268)
			(xy 102.561828 -256.769014) (xy 102.56542 -256.745004) (xy 102.562152 -256.733294) (xy 102.561898 -256.732786)
			(xy 102.554067 -256.708577) (xy 102.545644 -256.658403) (xy 102.545134 -256.632964) (xy 102.545656 -256.607709)
			(xy 102.553969 -256.557887) (xy 102.57037 -256.510113) (xy 102.594411 -256.46569) (xy 102.625435 -256.42583)
			(xy 102.662597 -256.39162) (xy 102.704883 -256.363994) (xy 102.751139 -256.343704) (xy 102.800104 -256.331304)
			(xy 102.850442 -256.327133) (xy 102.90078 -256.331304) (xy 102.949745 -256.343704) (xy 102.996001 -256.363994)
			(xy 103.038287 -256.39162) (xy 103.075449 -256.42583) (xy 103.106473 -256.46569) (xy 103.130514 -256.510113)
			(xy 103.146915 -256.557887) (xy 103.155228 -256.607709) (xy 103.15575 -256.632964) (xy 103.155247 -256.658403)
			(xy 103.146825 -256.70858) (xy 103.138986 -256.732786) (xy 103.138732 -256.733294) (xy 103.135501 -256.74501)
			(xy 103.139066 -256.769016) (xy 103.14559 -256.779268) (xy 103.193596 -256.846324) (xy 103.201217 -256.855821)
			(xy 103.22284 -256.866939) (xy 103.234998 -256.86766) (xy 105.14965 -256.86766) (xy 105.159309 -256.86726)
			(xy 105.177258 -256.860124) (xy 105.191261 -256.84682) (xy 105.195624 -256.838196) (xy 105.240836 -256.741422)
			(xy 105.237026 -256.712212) (xy 105.227374 -256.700782) (xy 105.212327 -256.682149) (xy 105.186998 -256.641503)
			(xy 105.167562 -256.597732) (xy 105.154395 -256.551686) (xy 105.147754 -256.504256) (xy 105.147364 -256.48031)
			(xy 105.147844 -256.454611) (xy 105.155505 -256.403787) (xy 105.170654 -256.354673) (xy 105.192955 -256.308365)
			(xy 105.221908 -256.265898) (xy 105.256868 -256.228221) (xy 105.297052 -256.196175) (xy 105.341564 -256.170476)
			(xy 105.389409 -256.151699) (xy 105.439518 -256.140261) (xy 105.490772 -256.136421) (xy 105.542026 -256.140261)
			(xy 105.592135 -256.151699) (xy 105.63998 -256.170476) (xy 105.684492 -256.196175) (xy 105.724676 -256.228221)
			(xy 105.759636 -256.265898) (xy 105.788589 -256.308365) (xy 105.81089 -256.354673) (xy 105.826039 -256.403787)
			(xy 105.8337 -256.454611) (xy 105.83418 -256.48031) (xy 105.833766 -256.504255) (xy 105.827119 -256.551681)
			(xy 105.813956 -256.597727) (xy 105.794532 -256.6415) (xy 105.769221 -256.682155) (xy 105.75417 -256.700782)
			(xy 105.744518 -256.712212) (xy 105.740708 -256.741422) (xy 105.78592 -256.838196) (xy 105.790367 -256.846759)
			(xy 105.804366 -256.860015) (xy 105.822256 -256.867204) (xy 105.831894 -256.86766) (xy 106.06405 -256.86766)
			(xy 106.073709 -256.86726) (xy 106.091658 -256.860124) (xy 106.105661 -256.84682) (xy 106.110024 -256.838196)
			(xy 106.155236 -256.741422) (xy 106.151426 -256.712212) (xy 106.141774 -256.700782) (xy 106.126727 -256.682149)
			(xy 106.101398 -256.641503) (xy 106.081962 -256.597732) (xy 106.068795 -256.551686) (xy 106.062154 -256.504256)
			(xy 106.061764 -256.48031) (xy 106.062244 -256.454611) (xy 106.069905 -256.403787) (xy 106.085054 -256.354673)
			(xy 106.107355 -256.308365) (xy 106.136308 -256.265898) (xy 106.171268 -256.228221) (xy 106.211452 -256.196175)
			(xy 106.255964 -256.170476) (xy 106.303809 -256.151699) (xy 106.353918 -256.140261) (xy 106.405172 -256.136421)
			(xy 106.456426 -256.140261) (xy 106.506535 -256.151699) (xy 106.55438 -256.170476) (xy 106.598892 -256.196175)
			(xy 106.639076 -256.228221) (xy 106.674036 -256.265898) (xy 106.702989 -256.308365) (xy 106.72529 -256.354673)
			(xy 106.735446 -256.3876) (xy 107.304081 -256.3876) (xy 107.308111 -256.335102) (xy 107.320108 -256.283834)
			(xy 107.339791 -256.234999) (xy 107.366697 -256.18974) (xy 107.400197 -256.149119) (xy 107.439505 -256.114088)
			(xy 107.4837 -256.085468) (xy 107.531745 -256.063929) (xy 107.582516 -256.049977) (xy 107.634821 -256.043939)
			(xy 107.687435 -256.045956) (xy 107.739125 -256.05598) (xy 107.788678 -256.073778) (xy 107.834934 -256.098931)
			(xy 107.876808 -256.13085) (xy 107.91332 -256.168788) (xy 107.943612 -256.211854) (xy 107.966975 -256.259039)
			(xy 107.982861 -256.309238) (xy 107.990898 -256.361274) (xy 107.991402 -256.3876) (xy 108.254041 -256.3876)
			(xy 108.258071 -256.335102) (xy 108.270068 -256.283834) (xy 108.289751 -256.234999) (xy 108.316657 -256.18974)
			(xy 108.350157 -256.149119) (xy 108.389465 -256.114088) (xy 108.43366 -256.085468) (xy 108.481705 -256.063929)
			(xy 108.532476 -256.049977) (xy 108.584781 -256.043939) (xy 108.637395 -256.045956) (xy 108.689085 -256.05598)
			(xy 108.738638 -256.073778) (xy 108.784894 -256.098931) (xy 108.826768 -256.13085) (xy 108.86328 -256.168788)
			(xy 108.893572 -256.211854) (xy 108.916935 -256.259039) (xy 108.932821 -256.309238) (xy 108.940858 -256.361274)
			(xy 108.941362 -256.3876) (xy 109.204001 -256.3876) (xy 109.208031 -256.335102) (xy 109.220028 -256.283834)
			(xy 109.239711 -256.234999) (xy 109.266617 -256.18974) (xy 109.300117 -256.149119) (xy 109.339425 -256.114088)
			(xy 109.38362 -256.085468) (xy 109.431665 -256.063929) (xy 109.482436 -256.049977) (xy 109.534741 -256.043939)
			(xy 109.587355 -256.045956) (xy 109.639045 -256.05598) (xy 109.688598 -256.073778) (xy 109.734854 -256.098931)
			(xy 109.776728 -256.13085) (xy 109.81324 -256.168788) (xy 109.843532 -256.211854) (xy 109.866895 -256.259039)
			(xy 109.882781 -256.309238) (xy 109.890818 -256.361274) (xy 109.891322 -256.3876) (xy 110.153961 -256.3876)
			(xy 110.157991 -256.335102) (xy 110.169988 -256.283834) (xy 110.189671 -256.234999) (xy 110.216577 -256.18974)
			(xy 110.250077 -256.149119) (xy 110.289385 -256.114088) (xy 110.33358 -256.085468) (xy 110.381625 -256.063929)
			(xy 110.432396 -256.049977) (xy 110.484701 -256.043939) (xy 110.537315 -256.045956) (xy 110.589005 -256.05598)
			(xy 110.638558 -256.073778) (xy 110.684814 -256.098931) (xy 110.726688 -256.13085) (xy 110.7632 -256.168788)
			(xy 110.793492 -256.211854) (xy 110.816855 -256.259039) (xy 110.832741 -256.309238) (xy 110.840778 -256.361274)
			(xy 110.841282 -256.3876) (xy 111.103921 -256.3876) (xy 111.107951 -256.335102) (xy 111.119948 -256.283834)
			(xy 111.139631 -256.234999) (xy 111.166537 -256.18974) (xy 111.200037 -256.149119) (xy 111.239345 -256.114088)
			(xy 111.28354 -256.085468) (xy 111.331585 -256.063929) (xy 111.382356 -256.049977) (xy 111.434661 -256.043939)
			(xy 111.487275 -256.045956) (xy 111.538965 -256.05598) (xy 111.588518 -256.073778) (xy 111.634774 -256.098931)
			(xy 111.676648 -256.13085) (xy 111.71316 -256.168788) (xy 111.743452 -256.211854) (xy 111.766815 -256.259039)
			(xy 111.782701 -256.309238) (xy 111.790738 -256.361274) (xy 111.791242 -256.3876) (xy 112.053881 -256.3876)
			(xy 112.057911 -256.335102) (xy 112.069908 -256.283834) (xy 112.089591 -256.234999) (xy 112.116497 -256.18974)
			(xy 112.149997 -256.149119) (xy 112.189305 -256.114088) (xy 112.2335 -256.085468) (xy 112.281545 -256.063929)
			(xy 112.332316 -256.049977) (xy 112.384621 -256.043939) (xy 112.437235 -256.045956) (xy 112.488925 -256.05598)
			(xy 112.538478 -256.073778) (xy 112.584734 -256.098931) (xy 112.626608 -256.13085) (xy 112.66312 -256.168788)
			(xy 112.693412 -256.211854) (xy 112.716775 -256.259039) (xy 112.732661 -256.309238) (xy 112.740698 -256.361274)
			(xy 112.741202 -256.3876) (xy 113.004095 -256.3876) (xy 113.008125 -256.335102) (xy 113.020122 -256.283834)
			(xy 113.039805 -256.234999) (xy 113.066711 -256.18974) (xy 113.100211 -256.149119) (xy 113.139519 -256.114088)
			(xy 113.183714 -256.085468) (xy 113.231759 -256.063929) (xy 113.28253 -256.049977) (xy 113.334835 -256.043939)
			(xy 113.387449 -256.045956) (xy 113.439139 -256.05598) (xy 113.488692 -256.073778) (xy 113.534948 -256.098931)
			(xy 113.576822 -256.13085) (xy 113.613334 -256.168788) (xy 113.643626 -256.211854) (xy 113.666989 -256.259039)
			(xy 113.682875 -256.309238) (xy 113.690912 -256.361274) (xy 113.691416 -256.3876) (xy 113.954055 -256.3876)
			(xy 113.958085 -256.335102) (xy 113.970082 -256.283834) (xy 113.989765 -256.234999) (xy 114.016671 -256.18974)
			(xy 114.050171 -256.149119) (xy 114.089479 -256.114088) (xy 114.133674 -256.085468) (xy 114.181719 -256.063929)
			(xy 114.23249 -256.049977) (xy 114.284795 -256.043939) (xy 114.337409 -256.045956) (xy 114.389099 -256.05598)
			(xy 114.438652 -256.073778) (xy 114.484908 -256.098931) (xy 114.526782 -256.13085) (xy 114.563294 -256.168788)
			(xy 114.593586 -256.211854) (xy 114.616949 -256.259039) (xy 114.632835 -256.309238) (xy 114.640872 -256.361274)
			(xy 114.641376 -256.3876) (xy 114.904015 -256.3876) (xy 114.908045 -256.335102) (xy 114.920042 -256.283834)
			(xy 114.939725 -256.234999) (xy 114.966631 -256.18974) (xy 115.000131 -256.149119) (xy 115.039439 -256.114088)
			(xy 115.083634 -256.085468) (xy 115.131679 -256.063929) (xy 115.18245 -256.049977) (xy 115.234755 -256.043939)
			(xy 115.287369 -256.045956) (xy 115.339059 -256.05598) (xy 115.388612 -256.073778) (xy 115.434868 -256.098931)
			(xy 115.476742 -256.13085) (xy 115.513254 -256.168788) (xy 115.543546 -256.211854) (xy 115.566909 -256.259039)
			(xy 115.582795 -256.309238) (xy 115.590832 -256.361274) (xy 115.591336 -256.3876) (xy 115.853975 -256.3876)
			(xy 115.858005 -256.335102) (xy 115.870002 -256.283834) (xy 115.889685 -256.234999) (xy 115.916591 -256.18974)
			(xy 115.950091 -256.149119) (xy 115.989399 -256.114088) (xy 116.033594 -256.085468) (xy 116.081639 -256.063929)
			(xy 116.13241 -256.049977) (xy 116.184715 -256.043939) (xy 116.237329 -256.045956) (xy 116.289019 -256.05598)
			(xy 116.338572 -256.073778) (xy 116.384828 -256.098931) (xy 116.426702 -256.13085) (xy 116.463214 -256.168788)
			(xy 116.493506 -256.211854) (xy 116.516869 -256.259039) (xy 116.532755 -256.309238) (xy 116.540792 -256.361274)
			(xy 116.541296 -256.3876) (xy 116.540792 -256.413926) (xy 116.532755 -256.465962) (xy 116.528214 -256.48031)
			(xy 117.096797 -256.48031) (xy 117.100827 -256.427812) (xy 117.112824 -256.376544) (xy 117.132507 -256.327709)
			(xy 117.159413 -256.28245) (xy 117.192913 -256.241829) (xy 117.232221 -256.206798) (xy 117.276416 -256.178178)
			(xy 117.324461 -256.156639) (xy 117.375232 -256.142687) (xy 117.427537 -256.136649) (xy 117.480151 -256.138666)
			(xy 117.531841 -256.14869) (xy 117.581394 -256.166488) (xy 117.62765 -256.191641) (xy 117.669524 -256.22356)
			(xy 117.706036 -256.261498) (xy 117.736328 -256.304564) (xy 117.759691 -256.351749) (xy 117.775577 -256.401948)
			(xy 117.783614 -256.453984) (xy 117.784118 -256.48031) (xy 117.783614 -256.506636) (xy 117.775577 -256.558672)
			(xy 117.759691 -256.608871) (xy 117.747007 -256.634488) (xy 122.278914 -256.634488) (xy 122.282874 -256.585434)
			(xy 122.294651 -256.53765) (xy 122.313942 -256.492374) (xy 122.340245 -256.450778) (xy 122.37288 -256.413941)
			(xy 122.411001 -256.382816) (xy 122.453622 -256.358209) (xy 122.499638 -256.340757) (xy 122.547857 -256.330913)
			(xy 122.597032 -256.328932) (xy 122.645887 -256.334864) (xy 122.693158 -256.348556) (xy 122.73762 -256.369654)
			(xy 122.778123 -256.39761) (xy 122.813616 -256.431702) (xy 122.843181 -256.471046) (xy 122.866052 -256.514623)
			(xy 122.881636 -256.561304) (xy 122.889531 -256.609881) (xy 122.890026 -256.634488) (xy 124.159022 -256.634488)
			(xy 124.162982 -256.585434) (xy 124.174759 -256.53765) (xy 124.19405 -256.492374) (xy 124.220353 -256.450778)
			(xy 124.252988 -256.413941) (xy 124.291109 -256.382816) (xy 124.33373 -256.358209) (xy 124.379746 -256.340757)
			(xy 124.427965 -256.330913) (xy 124.47714 -256.328932) (xy 124.525995 -256.334864) (xy 124.573266 -256.348556)
			(xy 124.617728 -256.369654) (xy 124.658231 -256.39761) (xy 124.693724 -256.431702) (xy 124.723289 -256.471046)
			(xy 124.74616 -256.514623) (xy 124.761744 -256.561304) (xy 124.769639 -256.609881) (xy 124.770134 -256.634488)
			(xy 126.038876 -256.634488) (xy 126.042836 -256.585434) (xy 126.054613 -256.53765) (xy 126.073904 -256.492374)
			(xy 126.100207 -256.450778) (xy 126.132842 -256.413941) (xy 126.170963 -256.382816) (xy 126.213584 -256.358209)
			(xy 126.2596 -256.340757) (xy 126.307819 -256.330913) (xy 126.356994 -256.328932) (xy 126.405849 -256.334864)
			(xy 126.45312 -256.348556) (xy 126.497582 -256.369654) (xy 126.538085 -256.39761) (xy 126.573578 -256.431702)
			(xy 126.603143 -256.471046) (xy 126.626014 -256.514623) (xy 126.641598 -256.561304) (xy 126.649493 -256.609881)
			(xy 126.649988 -256.634488) (xy 127.918984 -256.634488) (xy 127.922944 -256.585434) (xy 127.934721 -256.53765)
			(xy 127.954012 -256.492374) (xy 127.980315 -256.450778) (xy 128.01295 -256.413941) (xy 128.051071 -256.382816)
			(xy 128.093692 -256.358209) (xy 128.139708 -256.340757) (xy 128.187927 -256.330913) (xy 128.237102 -256.328932)
			(xy 128.285957 -256.334864) (xy 128.333228 -256.348556) (xy 128.37769 -256.369654) (xy 128.418193 -256.39761)
			(xy 128.453686 -256.431702) (xy 128.483251 -256.471046) (xy 128.506122 -256.514623) (xy 128.521706 -256.561304)
			(xy 128.529601 -256.609881) (xy 128.530096 -256.634488) (xy 128.848607 -256.634488) (xy 128.852702 -256.58376)
			(xy 128.864881 -256.534346) (xy 128.884829 -256.487526) (xy 128.91203 -256.444512) (xy 128.945778 -256.406418)
			(xy 128.9852 -256.374231) (xy 129.029274 -256.348785) (xy 129.07686 -256.330738) (xy 129.126724 -256.320558)
			(xy 129.177576 -256.318509) (xy 129.228097 -256.324643) (xy 129.276981 -256.338803) (xy 129.32296 -256.36062)
			(xy 129.364844 -256.38953) (xy 129.401548 -256.424785) (xy 129.432121 -256.465471) (xy 129.455772 -256.510534)
			(xy 129.471888 -256.558808) (xy 129.480052 -256.609042) (xy 129.480564 -256.634488) (xy 130.738892 -256.634488)
			(xy 130.742852 -256.585434) (xy 130.754629 -256.53765) (xy 130.77392 -256.492374) (xy 130.800223 -256.450778)
			(xy 130.832858 -256.413941) (xy 130.870979 -256.382816) (xy 130.9136 -256.358209) (xy 130.959616 -256.340757)
			(xy 131.007835 -256.330913) (xy 131.05701 -256.328932) (xy 131.105865 -256.334864) (xy 131.153136 -256.348556)
			(xy 131.197598 -256.369654) (xy 131.238101 -256.39761) (xy 131.273594 -256.431702) (xy 131.303159 -256.471046)
			(xy 131.32603 -256.514623) (xy 131.341614 -256.561304) (xy 131.349509 -256.609881) (xy 131.350004 -256.634488)
			(xy 131.678946 -256.634488) (xy 131.682906 -256.585434) (xy 131.694683 -256.53765) (xy 131.713974 -256.492374)
			(xy 131.740277 -256.450778) (xy 131.772912 -256.413941) (xy 131.811033 -256.382816) (xy 131.853654 -256.358209)
			(xy 131.89967 -256.340757) (xy 131.947889 -256.330913) (xy 131.997064 -256.328932) (xy 132.045919 -256.334864)
			(xy 132.09319 -256.348556) (xy 132.137652 -256.369654) (xy 132.178155 -256.39761) (xy 132.213648 -256.431702)
			(xy 132.243213 -256.471046) (xy 132.266084 -256.514623) (xy 132.281668 -256.561304) (xy 132.289563 -256.609881)
			(xy 132.290058 -256.634488) (xy 132.608569 -256.634488) (xy 132.612664 -256.58376) (xy 132.624843 -256.534346)
			(xy 132.644791 -256.487526) (xy 132.671992 -256.444512) (xy 132.70574 -256.406418) (xy 132.745162 -256.374231)
			(xy 132.789236 -256.348785) (xy 132.836822 -256.330738) (xy 132.886686 -256.320558) (xy 132.937538 -256.318509)
			(xy 132.988059 -256.324643) (xy 133.036943 -256.338803) (xy 133.082922 -256.36062) (xy 133.124806 -256.38953)
			(xy 133.16151 -256.424785) (xy 133.192083 -256.465471) (xy 133.215734 -256.510534) (xy 133.23185 -256.558808)
			(xy 133.240014 -256.609042) (xy 133.240526 -256.634488) (xy 133.240014 -256.659934) (xy 133.23185 -256.710168)
			(xy 133.215734 -256.758442) (xy 133.192083 -256.803505) (xy 133.16151 -256.844191) (xy 133.124806 -256.879446)
			(xy 133.082922 -256.908356) (xy 133.036943 -256.930173) (xy 132.988059 -256.944333) (xy 132.937538 -256.950467)
			(xy 132.886686 -256.948418) (xy 132.836822 -256.938238) (xy 132.789236 -256.920191) (xy 132.745162 -256.894745)
			(xy 132.70574 -256.862558) (xy 132.671992 -256.824464) (xy 132.644791 -256.78145) (xy 132.624843 -256.73463)
			(xy 132.612664 -256.685216) (xy 132.608569 -256.634488) (xy 132.290058 -256.634488) (xy 132.289563 -256.659095)
			(xy 132.281668 -256.707672) (xy 132.266084 -256.754353) (xy 132.243213 -256.79793) (xy 132.213648 -256.837274)
			(xy 132.178155 -256.871366) (xy 132.137652 -256.899322) (xy 132.09319 -256.92042) (xy 132.045919 -256.934112)
			(xy 131.997064 -256.940044) (xy 131.947889 -256.938063) (xy 131.89967 -256.928219) (xy 131.853654 -256.910767)
			(xy 131.811033 -256.88616) (xy 131.772912 -256.855035) (xy 131.740277 -256.818198) (xy 131.713974 -256.776602)
			(xy 131.694683 -256.731326) (xy 131.682906 -256.683542) (xy 131.678946 -256.634488) (xy 131.350004 -256.634488)
			(xy 131.349509 -256.659095) (xy 131.341614 -256.707672) (xy 131.32603 -256.754353) (xy 131.303159 -256.79793)
			(xy 131.273594 -256.837274) (xy 131.238101 -256.871366) (xy 131.197598 -256.899322) (xy 131.153136 -256.92042)
			(xy 131.105865 -256.934112) (xy 131.05701 -256.940044) (xy 131.007835 -256.938063) (xy 130.959616 -256.928219)
			(xy 130.9136 -256.910767) (xy 130.870979 -256.88616) (xy 130.832858 -256.855035) (xy 130.800223 -256.818198)
			(xy 130.77392 -256.776602) (xy 130.754629 -256.731326) (xy 130.742852 -256.683542) (xy 130.738892 -256.634488)
			(xy 129.480564 -256.634488) (xy 129.480052 -256.659934) (xy 129.471888 -256.710168) (xy 129.455772 -256.758442)
			(xy 129.432121 -256.803505) (xy 129.401548 -256.844191) (xy 129.364844 -256.879446) (xy 129.32296 -256.908356)
			(xy 129.276981 -256.930173) (xy 129.228097 -256.944333) (xy 129.177576 -256.950467) (xy 129.126724 -256.948418)
			(xy 129.07686 -256.938238) (xy 129.029274 -256.920191) (xy 128.9852 -256.894745) (xy 128.945778 -256.862558)
			(xy 128.91203 -256.824464) (xy 128.884829 -256.78145) (xy 128.864881 -256.73463) (xy 128.852702 -256.685216)
			(xy 128.848607 -256.634488) (xy 128.530096 -256.634488) (xy 128.529601 -256.659095) (xy 128.521706 -256.707672)
			(xy 128.506122 -256.754353) (xy 128.483251 -256.79793) (xy 128.453686 -256.837274) (xy 128.418193 -256.871366)
			(xy 128.37769 -256.899322) (xy 128.333228 -256.92042) (xy 128.285957 -256.934112) (xy 128.237102 -256.940044)
			(xy 128.187927 -256.938063) (xy 128.139708 -256.928219) (xy 128.093692 -256.910767) (xy 128.051071 -256.88616)
			(xy 128.01295 -256.855035) (xy 127.980315 -256.818198) (xy 127.954012 -256.776602) (xy 127.934721 -256.731326)
			(xy 127.922944 -256.683542) (xy 127.918984 -256.634488) (xy 126.649988 -256.634488) (xy 126.649493 -256.659095)
			(xy 126.641598 -256.707672) (xy 126.626014 -256.754353) (xy 126.603143 -256.79793) (xy 126.573578 -256.837274)
			(xy 126.538085 -256.871366) (xy 126.497582 -256.899322) (xy 126.45312 -256.92042) (xy 126.405849 -256.934112)
			(xy 126.356994 -256.940044) (xy 126.307819 -256.938063) (xy 126.2596 -256.928219) (xy 126.213584 -256.910767)
			(xy 126.170963 -256.88616) (xy 126.132842 -256.855035) (xy 126.100207 -256.818198) (xy 126.073904 -256.776602)
			(xy 126.054613 -256.731326) (xy 126.042836 -256.683542) (xy 126.038876 -256.634488) (xy 124.770134 -256.634488)
			(xy 124.769639 -256.659095) (xy 124.761744 -256.707672) (xy 124.74616 -256.754353) (xy 124.723289 -256.79793)
			(xy 124.693724 -256.837274) (xy 124.658231 -256.871366) (xy 124.617728 -256.899322) (xy 124.573266 -256.92042)
			(xy 124.525995 -256.934112) (xy 124.47714 -256.940044) (xy 124.427965 -256.938063) (xy 124.379746 -256.928219)
			(xy 124.33373 -256.910767) (xy 124.291109 -256.88616) (xy 124.252988 -256.855035) (xy 124.220353 -256.818198)
			(xy 124.19405 -256.776602) (xy 124.174759 -256.731326) (xy 124.162982 -256.683542) (xy 124.159022 -256.634488)
			(xy 122.890026 -256.634488) (xy 122.889531 -256.659095) (xy 122.881636 -256.707672) (xy 122.866052 -256.754353)
			(xy 122.843181 -256.79793) (xy 122.813616 -256.837274) (xy 122.778123 -256.871366) (xy 122.73762 -256.899322)
			(xy 122.693158 -256.92042) (xy 122.645887 -256.934112) (xy 122.597032 -256.940044) (xy 122.547857 -256.938063)
			(xy 122.499638 -256.928219) (xy 122.453622 -256.910767) (xy 122.411001 -256.88616) (xy 122.37288 -256.855035)
			(xy 122.340245 -256.818198) (xy 122.313942 -256.776602) (xy 122.294651 -256.731326) (xy 122.282874 -256.683542)
			(xy 122.278914 -256.634488) (xy 117.747007 -256.634488) (xy 117.736328 -256.656056) (xy 117.706036 -256.699122)
			(xy 117.669524 -256.73706) (xy 117.62765 -256.768979) (xy 117.581394 -256.794132) (xy 117.531841 -256.81193)
			(xy 117.480151 -256.821954) (xy 117.427537 -256.823971) (xy 117.375232 -256.817933) (xy 117.324461 -256.803981)
			(xy 117.276416 -256.782442) (xy 117.232221 -256.753822) (xy 117.192913 -256.718791) (xy 117.159413 -256.67817)
			(xy 117.132507 -256.632911) (xy 117.112824 -256.584076) (xy 117.100827 -256.532808) (xy 117.096797 -256.48031)
			(xy 116.528214 -256.48031) (xy 116.516869 -256.516161) (xy 116.493506 -256.563346) (xy 116.463214 -256.606412)
			(xy 116.426702 -256.64435) (xy 116.384828 -256.676269) (xy 116.338572 -256.701422) (xy 116.289019 -256.71922)
			(xy 116.237329 -256.729244) (xy 116.184715 -256.731261) (xy 116.13241 -256.725223) (xy 116.081639 -256.711271)
			(xy 116.033594 -256.689732) (xy 115.989399 -256.661112) (xy 115.950091 -256.626081) (xy 115.916591 -256.58546)
			(xy 115.889685 -256.540201) (xy 115.870002 -256.491366) (xy 115.858005 -256.440098) (xy 115.853975 -256.3876)
			(xy 115.591336 -256.3876) (xy 115.590832 -256.413926) (xy 115.582795 -256.465962) (xy 115.566909 -256.516161)
			(xy 115.543546 -256.563346) (xy 115.513254 -256.606412) (xy 115.476742 -256.64435) (xy 115.434868 -256.676269)
			(xy 115.388612 -256.701422) (xy 115.339059 -256.71922) (xy 115.287369 -256.729244) (xy 115.234755 -256.731261)
			(xy 115.18245 -256.725223) (xy 115.131679 -256.711271) (xy 115.083634 -256.689732) (xy 115.039439 -256.661112)
			(xy 115.000131 -256.626081) (xy 114.966631 -256.58546) (xy 114.939725 -256.540201) (xy 114.920042 -256.491366)
			(xy 114.908045 -256.440098) (xy 114.904015 -256.3876) (xy 114.641376 -256.3876) (xy 114.640872 -256.413926)
			(xy 114.632835 -256.465962) (xy 114.616949 -256.516161) (xy 114.593586 -256.563346) (xy 114.563294 -256.606412)
			(xy 114.526782 -256.64435) (xy 114.484908 -256.676269) (xy 114.438652 -256.701422) (xy 114.389099 -256.71922)
			(xy 114.337409 -256.729244) (xy 114.284795 -256.731261) (xy 114.23249 -256.725223) (xy 114.181719 -256.711271)
			(xy 114.133674 -256.689732) (xy 114.089479 -256.661112) (xy 114.050171 -256.626081) (xy 114.016671 -256.58546)
			(xy 113.989765 -256.540201) (xy 113.970082 -256.491366) (xy 113.958085 -256.440098) (xy 113.954055 -256.3876)
			(xy 113.691416 -256.3876) (xy 113.690912 -256.413926) (xy 113.682875 -256.465962) (xy 113.666989 -256.516161)
			(xy 113.643626 -256.563346) (xy 113.613334 -256.606412) (xy 113.576822 -256.64435) (xy 113.534948 -256.676269)
			(xy 113.488692 -256.701422) (xy 113.439139 -256.71922) (xy 113.387449 -256.729244) (xy 113.334835 -256.731261)
			(xy 113.28253 -256.725223) (xy 113.231759 -256.711271) (xy 113.183714 -256.689732) (xy 113.139519 -256.661112)
			(xy 113.100211 -256.626081) (xy 113.066711 -256.58546) (xy 113.039805 -256.540201) (xy 113.020122 -256.491366)
			(xy 113.008125 -256.440098) (xy 113.004095 -256.3876) (xy 112.741202 -256.3876) (xy 112.740698 -256.413926)
			(xy 112.732661 -256.465962) (xy 112.716775 -256.516161) (xy 112.693412 -256.563346) (xy 112.66312 -256.606412)
			(xy 112.626608 -256.64435) (xy 112.584734 -256.676269) (xy 112.538478 -256.701422) (xy 112.488925 -256.71922)
			(xy 112.437235 -256.729244) (xy 112.384621 -256.731261) (xy 112.332316 -256.725223) (xy 112.281545 -256.711271)
			(xy 112.2335 -256.689732) (xy 112.189305 -256.661112) (xy 112.149997 -256.626081) (xy 112.116497 -256.58546)
			(xy 112.089591 -256.540201) (xy 112.069908 -256.491366) (xy 112.057911 -256.440098) (xy 112.053881 -256.3876)
			(xy 111.791242 -256.3876) (xy 111.790738 -256.413926) (xy 111.782701 -256.465962) (xy 111.766815 -256.516161)
			(xy 111.743452 -256.563346) (xy 111.71316 -256.606412) (xy 111.676648 -256.64435) (xy 111.634774 -256.676269)
			(xy 111.588518 -256.701422) (xy 111.538965 -256.71922) (xy 111.487275 -256.729244) (xy 111.434661 -256.731261)
			(xy 111.382356 -256.725223) (xy 111.331585 -256.711271) (xy 111.28354 -256.689732) (xy 111.239345 -256.661112)
			(xy 111.200037 -256.626081) (xy 111.166537 -256.58546) (xy 111.139631 -256.540201) (xy 111.119948 -256.491366)
			(xy 111.107951 -256.440098) (xy 111.103921 -256.3876) (xy 110.841282 -256.3876) (xy 110.840778 -256.413926)
			(xy 110.832741 -256.465962) (xy 110.816855 -256.516161) (xy 110.793492 -256.563346) (xy 110.7632 -256.606412)
			(xy 110.726688 -256.64435) (xy 110.684814 -256.676269) (xy 110.638558 -256.701422) (xy 110.589005 -256.71922)
			(xy 110.537315 -256.729244) (xy 110.484701 -256.731261) (xy 110.432396 -256.725223) (xy 110.381625 -256.711271)
			(xy 110.33358 -256.689732) (xy 110.289385 -256.661112) (xy 110.250077 -256.626081) (xy 110.216577 -256.58546)
			(xy 110.189671 -256.540201) (xy 110.169988 -256.491366) (xy 110.157991 -256.440098) (xy 110.153961 -256.3876)
			(xy 109.891322 -256.3876) (xy 109.890818 -256.413926) (xy 109.882781 -256.465962) (xy 109.866895 -256.516161)
			(xy 109.843532 -256.563346) (xy 109.81324 -256.606412) (xy 109.776728 -256.64435) (xy 109.734854 -256.676269)
			(xy 109.688598 -256.701422) (xy 109.639045 -256.71922) (xy 109.587355 -256.729244) (xy 109.534741 -256.731261)
			(xy 109.482436 -256.725223) (xy 109.431665 -256.711271) (xy 109.38362 -256.689732) (xy 109.339425 -256.661112)
			(xy 109.300117 -256.626081) (xy 109.266617 -256.58546) (xy 109.239711 -256.540201) (xy 109.220028 -256.491366)
			(xy 109.208031 -256.440098) (xy 109.204001 -256.3876) (xy 108.941362 -256.3876) (xy 108.940858 -256.413926)
			(xy 108.932821 -256.465962) (xy 108.916935 -256.516161) (xy 108.893572 -256.563346) (xy 108.86328 -256.606412)
			(xy 108.826768 -256.64435) (xy 108.784894 -256.676269) (xy 108.738638 -256.701422) (xy 108.689085 -256.71922)
			(xy 108.637395 -256.729244) (xy 108.584781 -256.731261) (xy 108.532476 -256.725223) (xy 108.481705 -256.711271)
			(xy 108.43366 -256.689732) (xy 108.389465 -256.661112) (xy 108.350157 -256.626081) (xy 108.316657 -256.58546)
			(xy 108.289751 -256.540201) (xy 108.270068 -256.491366) (xy 108.258071 -256.440098) (xy 108.254041 -256.3876)
			(xy 107.991402 -256.3876) (xy 107.990898 -256.413926) (xy 107.982861 -256.465962) (xy 107.966975 -256.516161)
			(xy 107.943612 -256.563346) (xy 107.91332 -256.606412) (xy 107.876808 -256.64435) (xy 107.834934 -256.676269)
			(xy 107.788678 -256.701422) (xy 107.739125 -256.71922) (xy 107.687435 -256.729244) (xy 107.634821 -256.731261)
			(xy 107.582516 -256.725223) (xy 107.531745 -256.711271) (xy 107.4837 -256.689732) (xy 107.439505 -256.661112)
			(xy 107.400197 -256.626081) (xy 107.366697 -256.58546) (xy 107.339791 -256.540201) (xy 107.320108 -256.491366)
			(xy 107.308111 -256.440098) (xy 107.304081 -256.3876) (xy 106.735446 -256.3876) (xy 106.740439 -256.403787)
			(xy 106.7481 -256.454611) (xy 106.74858 -256.48031) (xy 106.748166 -256.504255) (xy 106.741519 -256.551681)
			(xy 106.728356 -256.597727) (xy 106.708932 -256.6415) (xy 106.683621 -256.682155) (xy 106.66857 -256.700782)
			(xy 106.658918 -256.712212) (xy 106.655108 -256.741422) (xy 106.70032 -256.838196) (xy 106.704767 -256.846759)
			(xy 106.718766 -256.860015) (xy 106.736656 -256.867204) (xy 106.746294 -256.86766) (xy 109.061758 -256.86766)
			(xy 109.071822 -256.868095) (xy 109.090406 -256.875831) (xy 109.097826 -256.882646) (xy 110.223554 -258.008374)
			(xy 110.224062 -258.008882) (xy 110.231445 -258.01546) (xy 110.249744 -258.022902) (xy 110.259622 -258.02336)
			(xy 110.923832 -258.02336) (xy 110.93647 -258.022678) (xy 110.958713 -258.01067) (xy 110.96625 -258.0005)
			(xy 111.019844 -257.918712) (xy 111.02213 -257.893312) (xy 111.01705 -257.881374) (xy 111.008161 -257.859788)
			(xy 110.995626 -257.81482) (xy 110.989278 -257.768571) (xy 110.988856 -257.74523) (xy 110.989336 -257.719531)
			(xy 110.996997 -257.668707) (xy 111.012146 -257.619593) (xy 111.034447 -257.573285) (xy 111.0634 -257.530818)
			(xy 111.09836 -257.493141) (xy 111.138544 -257.461095) (xy 111.183056 -257.435396) (xy 111.230901 -257.416619)
			(xy 111.28101 -257.405181) (xy 111.332264 -257.401341) (xy 111.383518 -257.405181) (xy 111.433627 -257.416619)
			(xy 111.481472 -257.435396) (xy 111.525984 -257.461095) (xy 111.566168 -257.493141) (xy 111.601128 -257.530818)
			(xy 111.630081 -257.573285) (xy 111.652382 -257.619593) (xy 111.667531 -257.668707) (xy 111.675192 -257.719531)
			(xy 111.675672 -257.74523) (xy 113.238283 -257.74523) (xy 113.242313 -257.692732) (xy 113.25431 -257.641464)
			(xy 113.273993 -257.592629) (xy 113.300899 -257.54737) (xy 113.334399 -257.506749) (xy 113.373707 -257.471718)
			(xy 113.417902 -257.443098) (xy 113.465947 -257.421559) (xy 113.516718 -257.407607) (xy 113.569023 -257.401569)
			(xy 113.621637 -257.403586) (xy 113.673327 -257.41361) (xy 113.72288 -257.431408) (xy 113.769136 -257.456561)
			(xy 113.81101 -257.48848) (xy 113.847522 -257.526418) (xy 113.877814 -257.569484) (xy 113.901177 -257.616669)
			(xy 113.917063 -257.666868) (xy 113.9251 -257.718904) (xy 113.925604 -257.74523) (xy 115.838227 -257.74523)
			(xy 115.842257 -257.692732) (xy 115.854254 -257.641464) (xy 115.873937 -257.592629) (xy 115.900843 -257.54737)
			(xy 115.934343 -257.506749) (xy 115.973651 -257.471718) (xy 116.017846 -257.443098) (xy 116.065891 -257.421559)
			(xy 116.116662 -257.407607) (xy 116.168967 -257.401569) (xy 116.221581 -257.403586) (xy 116.273271 -257.41361)
			(xy 116.319656 -257.43027) (xy 117.096797 -257.43027) (xy 117.100827 -257.377772) (xy 117.112824 -257.326504)
			(xy 117.132507 -257.277669) (xy 117.159413 -257.23241) (xy 117.192913 -257.191789) (xy 117.232221 -257.156758)
			(xy 117.276416 -257.128138) (xy 117.324461 -257.106599) (xy 117.375232 -257.092647) (xy 117.427537 -257.086609)
			(xy 117.480151 -257.088626) (xy 117.531841 -257.09865) (xy 117.581394 -257.116448) (xy 117.62765 -257.141601)
			(xy 117.669524 -257.17352) (xy 117.706036 -257.211458) (xy 117.736328 -257.254524) (xy 117.759691 -257.301709)
			(xy 117.775577 -257.351908) (xy 117.783614 -257.403944) (xy 117.784118 -257.43027) (xy 117.783614 -257.456596)
			(xy 117.775577 -257.508632) (xy 117.759691 -257.558831) (xy 117.736328 -257.606016) (xy 117.706036 -257.649082)
			(xy 117.669524 -257.68702) (xy 117.62765 -257.718939) (xy 117.581394 -257.744092) (xy 117.531841 -257.76189)
			(xy 117.480151 -257.771914) (xy 117.427537 -257.773931) (xy 117.375232 -257.767893) (xy 117.324461 -257.753941)
			(xy 117.276416 -257.732402) (xy 117.232221 -257.703782) (xy 117.192913 -257.668751) (xy 117.159413 -257.62813)
			(xy 117.132507 -257.582871) (xy 117.112824 -257.534036) (xy 117.100827 -257.482768) (xy 117.096797 -257.43027)
			(xy 116.319656 -257.43027) (xy 116.322824 -257.431408) (xy 116.36908 -257.456561) (xy 116.410954 -257.48848)
			(xy 116.447466 -257.526418) (xy 116.477758 -257.569484) (xy 116.501121 -257.616669) (xy 116.517007 -257.666868)
			(xy 116.525044 -257.718904) (xy 116.525548 -257.74523) (xy 116.525044 -257.771556) (xy 116.517007 -257.823592)
			(xy 116.501121 -257.873791) (xy 116.477758 -257.920976) (xy 116.471132 -257.930396) (xy 120.865649 -257.930396)
			(xy 120.869679 -257.877898) (xy 120.881676 -257.82663) (xy 120.901359 -257.777795) (xy 120.928265 -257.732536)
			(xy 120.961765 -257.691915) (xy 121.001073 -257.656884) (xy 121.045268 -257.628264) (xy 121.093313 -257.606725)
			(xy 121.144084 -257.592773) (xy 121.196389 -257.586735) (xy 121.249003 -257.588752) (xy 121.300693 -257.598776)
			(xy 121.350246 -257.616574) (xy 121.396502 -257.641727) (xy 121.438376 -257.673646) (xy 121.474888 -257.711584)
			(xy 121.50518 -257.75465) (xy 121.528543 -257.801835) (xy 121.544429 -257.852034) (xy 121.552466 -257.90407)
			(xy 121.55297 -257.930396) (xy 122.791223 -257.930396) (xy 122.795253 -257.877898) (xy 122.80725 -257.82663)
			(xy 122.826933 -257.777795) (xy 122.853839 -257.732536) (xy 122.887339 -257.691915) (xy 122.926647 -257.656884)
			(xy 122.970842 -257.628264) (xy 123.018887 -257.606725) (xy 123.069658 -257.592773) (xy 123.121963 -257.586735)
			(xy 123.174577 -257.588752) (xy 123.226267 -257.598776) (xy 123.27582 -257.616574) (xy 123.322076 -257.641727)
			(xy 123.36395 -257.673646) (xy 123.400462 -257.711584) (xy 123.430754 -257.75465) (xy 123.454117 -257.801835)
			(xy 123.470003 -257.852034) (xy 123.47804 -257.90407) (xy 123.478544 -257.930396) (xy 124.696223 -257.930396)
			(xy 124.700253 -257.877898) (xy 124.71225 -257.82663) (xy 124.731933 -257.777795) (xy 124.758839 -257.732536)
			(xy 124.792339 -257.691915) (xy 124.831647 -257.656884) (xy 124.875842 -257.628264) (xy 124.923887 -257.606725)
			(xy 124.974658 -257.592773) (xy 125.026963 -257.586735) (xy 125.079577 -257.588752) (xy 125.131267 -257.598776)
			(xy 125.18082 -257.616574) (xy 125.227076 -257.641727) (xy 125.26895 -257.673646) (xy 125.305462 -257.711584)
			(xy 125.335754 -257.75465) (xy 125.359117 -257.801835) (xy 125.375003 -257.852034) (xy 125.38304 -257.90407)
			(xy 125.383544 -257.930396) (xy 125.38304 -257.956722) (xy 125.375003 -258.008758) (xy 125.359117 -258.058957)
			(xy 125.335754 -258.106142) (xy 125.305462 -258.149208) (xy 125.26895 -258.187146) (xy 125.227076 -258.219065)
			(xy 125.18082 -258.244218) (xy 125.131267 -258.262016) (xy 125.079577 -258.27204) (xy 125.026963 -258.274057)
			(xy 124.974658 -258.268019) (xy 124.923887 -258.254067) (xy 124.875842 -258.232528) (xy 124.831647 -258.203908)
			(xy 124.792339 -258.168877) (xy 124.758839 -258.128256) (xy 124.731933 -258.082997) (xy 124.71225 -258.034162)
			(xy 124.700253 -257.982894) (xy 124.696223 -257.930396) (xy 123.478544 -257.930396) (xy 123.47804 -257.956722)
			(xy 123.470003 -258.008758) (xy 123.454117 -258.058957) (xy 123.430754 -258.106142) (xy 123.400462 -258.149208)
			(xy 123.36395 -258.187146) (xy 123.322076 -258.219065) (xy 123.27582 -258.244218) (xy 123.226267 -258.262016)
			(xy 123.174577 -258.27204) (xy 123.121963 -258.274057) (xy 123.069658 -258.268019) (xy 123.018887 -258.254067)
			(xy 122.970842 -258.232528) (xy 122.926647 -258.203908) (xy 122.887339 -258.168877) (xy 122.853839 -258.128256)
			(xy 122.826933 -258.082997) (xy 122.80725 -258.034162) (xy 122.795253 -257.982894) (xy 122.791223 -257.930396)
			(xy 121.55297 -257.930396) (xy 121.552466 -257.956722) (xy 121.544429 -258.008758) (xy 121.528543 -258.058957)
			(xy 121.50518 -258.106142) (xy 121.474888 -258.149208) (xy 121.438376 -258.187146) (xy 121.396502 -258.219065)
			(xy 121.350246 -258.244218) (xy 121.300693 -258.262016) (xy 121.249003 -258.27204) (xy 121.196389 -258.274057)
			(xy 121.144084 -258.268019) (xy 121.093313 -258.254067) (xy 121.045268 -258.232528) (xy 121.001073 -258.203908)
			(xy 120.961765 -258.168877) (xy 120.928265 -258.128256) (xy 120.901359 -258.082997) (xy 120.881676 -258.034162)
			(xy 120.869679 -257.982894) (xy 120.865649 -257.930396) (xy 116.471132 -257.930396) (xy 116.447466 -257.964042)
			(xy 116.410954 -258.00198) (xy 116.36908 -258.033899) (xy 116.322824 -258.059052) (xy 116.273271 -258.07685)
			(xy 116.221581 -258.086874) (xy 116.168967 -258.088891) (xy 116.116662 -258.082853) (xy 116.065891 -258.068901)
			(xy 116.017846 -258.047362) (xy 115.973651 -258.018742) (xy 115.934343 -257.983711) (xy 115.900843 -257.94309)
			(xy 115.873937 -257.897831) (xy 115.854254 -257.848996) (xy 115.842257 -257.797728) (xy 115.838227 -257.74523)
			(xy 113.925604 -257.74523) (xy 113.9251 -257.771556) (xy 113.917063 -257.823592) (xy 113.901177 -257.873791)
			(xy 113.877814 -257.920976) (xy 113.847522 -257.964042) (xy 113.81101 -258.00198) (xy 113.769136 -258.033899)
			(xy 113.72288 -258.059052) (xy 113.673327 -258.07685) (xy 113.621637 -258.086874) (xy 113.569023 -258.088891)
			(xy 113.516718 -258.082853) (xy 113.465947 -258.068901) (xy 113.417902 -258.047362) (xy 113.373707 -258.018742)
			(xy 113.334399 -257.983711) (xy 113.300899 -257.94309) (xy 113.273993 -257.897831) (xy 113.25431 -257.848996)
			(xy 113.242313 -257.797728) (xy 113.238283 -257.74523) (xy 111.675672 -257.74523) (xy 111.675197 -257.771138)
			(xy 111.667404 -257.822366) (xy 111.652001 -257.871841) (xy 111.629336 -257.918438) (xy 111.599926 -257.9611)
			(xy 111.564437 -257.998856) (xy 111.544354 -258.015232) (xy 111.535718 -258.02209) (xy 111.525812 -258.040886)
			(xy 111.520478 -258.127754) (xy 111.520273 -258.138045) (xy 111.527085 -258.157449) (xy 111.533686 -258.165346)
			(xy 111.534702 -258.166362) (xy 111.74857 -258.38023) (xy 117.096797 -258.38023) (xy 117.100827 -258.327732)
			(xy 117.112824 -258.276464) (xy 117.132507 -258.227629) (xy 117.159413 -258.18237) (xy 117.192913 -258.141749)
			(xy 117.232221 -258.106718) (xy 117.276416 -258.078098) (xy 117.324461 -258.056559) (xy 117.375232 -258.042607)
			(xy 117.427537 -258.036569) (xy 117.480151 -258.038586) (xy 117.531841 -258.04861) (xy 117.581394 -258.066408)
			(xy 117.62765 -258.091561) (xy 117.669524 -258.12348) (xy 117.706036 -258.161418) (xy 117.736328 -258.204484)
			(xy 117.759691 -258.251669) (xy 117.775577 -258.301868) (xy 117.783614 -258.353904) (xy 117.784118 -258.38023)
			(xy 117.783614 -258.406556) (xy 117.775577 -258.458592) (xy 117.759691 -258.508791) (xy 117.736328 -258.555976)
			(xy 117.706036 -258.599042) (xy 117.669524 -258.63698) (xy 117.62765 -258.668899) (xy 117.581394 -258.694052)
			(xy 117.531841 -258.71185) (xy 117.480151 -258.721874) (xy 117.427537 -258.723891) (xy 117.375232 -258.717853)
			(xy 117.324461 -258.703901) (xy 117.276416 -258.682362) (xy 117.232221 -258.653742) (xy 117.192913 -258.618711)
			(xy 117.159413 -258.57809) (xy 117.132507 -258.532831) (xy 117.112824 -258.483996) (xy 117.100827 -258.432728)
			(xy 117.096797 -258.38023) (xy 111.74857 -258.38023) (xy 112.435894 -259.067554) (xy 112.436402 -259.068062)
			(xy 112.443786 -259.074636) (xy 112.462085 -259.082067) (xy 112.471962 -259.08254) (xy 113.177828 -259.08254)
			(xy 113.186315 -259.08223) (xy 113.202353 -259.076676) (xy 113.215675 -259.06616) (xy 113.2205 -259.059172)
			(xy 113.27384 -258.976114) (xy 113.275618 -258.95046) (xy 113.27003 -258.938268) (xy 113.260142 -258.915651)
			(xy 113.246213 -258.868296) (xy 113.239187 -258.819438) (xy 113.238788 -258.794758) (xy 113.238788 -258.79044)
			(xy 113.239674 -258.763703) (xy 113.24871 -258.710978) (xy 113.265811 -258.660291) (xy 113.290565 -258.612869)
			(xy 113.322371 -258.569859) (xy 113.360462 -258.5323) (xy 113.403915 -258.5011) (xy 113.45168 -258.477016)
			(xy 113.502602 -258.460629) (xy 113.555449 -258.452335) (xy 113.608943 -258.452335) (xy 113.66179 -258.460629)
			(xy 113.712712 -258.477016) (xy 113.760477 -258.5011) (xy 113.80393 -258.5323) (xy 113.842021 -258.569859)
			(xy 113.873827 -258.612869) (xy 113.898581 -258.660291) (xy 113.915682 -258.710978) (xy 113.924718 -258.763703)
			(xy 113.925604 -258.79044) (xy 113.925604 -258.794758) (xy 113.925596 -258.795266) (xy 115.838227 -258.795266)
			(xy 115.842257 -258.742768) (xy 115.854254 -258.6915) (xy 115.873937 -258.642665) (xy 115.900843 -258.597406)
			(xy 115.934343 -258.556785) (xy 115.973651 -258.521754) (xy 116.017846 -258.493134) (xy 116.065891 -258.471595)
			(xy 116.116662 -258.457643) (xy 116.168967 -258.451605) (xy 116.221581 -258.453622) (xy 116.273271 -258.463646)
			(xy 116.322824 -258.481444) (xy 116.36908 -258.506597) (xy 116.410954 -258.538516) (xy 116.447466 -258.576454)
			(xy 116.477758 -258.61952) (xy 116.501121 -258.666705) (xy 116.517007 -258.716904) (xy 116.525044 -258.76894)
			(xy 116.525548 -258.795266) (xy 116.525044 -258.821592) (xy 116.523696 -258.830318) (xy 120.865649 -258.830318)
			(xy 120.869679 -258.77782) (xy 120.881676 -258.726552) (xy 120.901359 -258.677717) (xy 120.928265 -258.632458)
			(xy 120.961765 -258.591837) (xy 121.001073 -258.556806) (xy 121.045268 -258.528186) (xy 121.093313 -258.506647)
			(xy 121.144084 -258.492695) (xy 121.196389 -258.486657) (xy 121.249003 -258.488674) (xy 121.300693 -258.498698)
			(xy 121.350246 -258.516496) (xy 121.396502 -258.541649) (xy 121.438376 -258.573568) (xy 121.474888 -258.611506)
			(xy 121.50518 -258.654572) (xy 121.528543 -258.701757) (xy 121.544429 -258.751956) (xy 121.552466 -258.803992)
			(xy 121.55297 -258.830318) (xy 122.791223 -258.830318) (xy 122.795253 -258.77782) (xy 122.80725 -258.726552)
			(xy 122.826933 -258.677717) (xy 122.853839 -258.632458) (xy 122.887339 -258.591837) (xy 122.926647 -258.556806)
			(xy 122.970842 -258.528186) (xy 123.018887 -258.506647) (xy 123.069658 -258.492695) (xy 123.121963 -258.486657)
			(xy 123.174577 -258.488674) (xy 123.226267 -258.498698) (xy 123.27582 -258.516496) (xy 123.322076 -258.541649)
			(xy 123.36395 -258.573568) (xy 123.400462 -258.611506) (xy 123.430754 -258.654572) (xy 123.454117 -258.701757)
			(xy 123.470003 -258.751956) (xy 123.47804 -258.803992) (xy 123.478544 -258.830318) (xy 124.696223 -258.830318)
			(xy 124.700253 -258.77782) (xy 124.71225 -258.726552) (xy 124.731933 -258.677717) (xy 124.758839 -258.632458)
			(xy 124.792339 -258.591837) (xy 124.831647 -258.556806) (xy 124.875842 -258.528186) (xy 124.923887 -258.506647)
			(xy 124.974658 -258.492695) (xy 125.026963 -258.486657) (xy 125.079577 -258.488674) (xy 125.131267 -258.498698)
			(xy 125.18082 -258.516496) (xy 125.227076 -258.541649) (xy 125.26895 -258.573568) (xy 125.305462 -258.611506)
			(xy 125.335754 -258.654572) (xy 125.359117 -258.701757) (xy 125.375003 -258.751956) (xy 125.38304 -258.803992)
			(xy 125.383544 -258.830318) (xy 125.38304 -258.856644) (xy 125.375003 -258.90868) (xy 125.359117 -258.958879)
			(xy 125.335754 -259.006064) (xy 125.305462 -259.04913) (xy 125.26895 -259.087068) (xy 125.227076 -259.118987)
			(xy 125.18082 -259.14414) (xy 125.131267 -259.161938) (xy 125.079577 -259.171962) (xy 125.026963 -259.173979)
			(xy 124.974658 -259.167941) (xy 124.923887 -259.153989) (xy 124.875842 -259.13245) (xy 124.831647 -259.10383)
			(xy 124.792339 -259.068799) (xy 124.758839 -259.028178) (xy 124.731933 -258.982919) (xy 124.71225 -258.934084)
			(xy 124.700253 -258.882816) (xy 124.696223 -258.830318) (xy 123.478544 -258.830318) (xy 123.47804 -258.856644)
			(xy 123.470003 -258.90868) (xy 123.454117 -258.958879) (xy 123.430754 -259.006064) (xy 123.400462 -259.04913)
			(xy 123.36395 -259.087068) (xy 123.322076 -259.118987) (xy 123.27582 -259.14414) (xy 123.226267 -259.161938)
			(xy 123.174577 -259.171962) (xy 123.121963 -259.173979) (xy 123.069658 -259.167941) (xy 123.018887 -259.153989)
			(xy 122.970842 -259.13245) (xy 122.926647 -259.10383) (xy 122.887339 -259.068799) (xy 122.853839 -259.028178)
			(xy 122.826933 -258.982919) (xy 122.80725 -258.934084) (xy 122.795253 -258.882816) (xy 122.791223 -258.830318)
			(xy 121.55297 -258.830318) (xy 121.552466 -258.856644) (xy 121.544429 -258.90868) (xy 121.528543 -258.958879)
			(xy 121.50518 -259.006064) (xy 121.474888 -259.04913) (xy 121.438376 -259.087068) (xy 121.396502 -259.118987)
			(xy 121.350246 -259.14414) (xy 121.300693 -259.161938) (xy 121.249003 -259.171962) (xy 121.196389 -259.173979)
			(xy 121.144084 -259.167941) (xy 121.093313 -259.153989) (xy 121.045268 -259.13245) (xy 121.001073 -259.10383)
			(xy 120.961765 -259.068799) (xy 120.928265 -259.028178) (xy 120.901359 -258.982919) (xy 120.881676 -258.934084)
			(xy 120.869679 -258.882816) (xy 120.865649 -258.830318) (xy 116.523696 -258.830318) (xy 116.517007 -258.873628)
			(xy 116.501121 -258.923827) (xy 116.477758 -258.971012) (xy 116.447466 -259.014078) (xy 116.410954 -259.052016)
			(xy 116.36908 -259.083935) (xy 116.322824 -259.109088) (xy 116.273271 -259.126886) (xy 116.221581 -259.13691)
			(xy 116.168967 -259.138927) (xy 116.116662 -259.132889) (xy 116.065891 -259.118937) (xy 116.017846 -259.097398)
			(xy 115.973651 -259.068778) (xy 115.934343 -259.033747) (xy 115.900843 -258.993126) (xy 115.873937 -258.947867)
			(xy 115.854254 -258.899032) (xy 115.842257 -258.847764) (xy 115.838227 -258.795266) (xy 113.925596 -258.795266)
			(xy 113.925219 -258.819441) (xy 113.918221 -258.868307) (xy 113.904279 -258.915662) (xy 113.894362 -258.938268)
			(xy 113.888774 -258.95046) (xy 113.890552 -258.976114) (xy 113.943892 -259.059172) (xy 113.948748 -259.06613)
			(xy 113.962074 -259.07662) (xy 113.978086 -259.082208) (xy 113.986564 -259.08254) (xy 115.790218 -259.08254)
			(xy 115.800286 -259.082968) (xy 115.818882 -259.090691) (xy 115.826286 -259.097526) (xy 116.059204 -259.330444)
			(xy 117.096797 -259.330444) (xy 117.100827 -259.277946) (xy 117.112824 -259.226678) (xy 117.132507 -259.177843)
			(xy 117.159413 -259.132584) (xy 117.192913 -259.091963) (xy 117.232221 -259.056932) (xy 117.276416 -259.028312)
			(xy 117.324461 -259.006773) (xy 117.375232 -258.992821) (xy 117.427537 -258.986783) (xy 117.480151 -258.9888)
			(xy 117.531841 -258.998824) (xy 117.581394 -259.016622) (xy 117.62765 -259.041775) (xy 117.669524 -259.073694)
			(xy 117.706036 -259.111632) (xy 117.736328 -259.154698) (xy 117.759691 -259.201883) (xy 117.775577 -259.252082)
			(xy 117.783614 -259.304118) (xy 117.784118 -259.330444) (xy 117.783614 -259.35677) (xy 117.775577 -259.408806)
			(xy 117.759691 -259.459005) (xy 117.736328 -259.50619) (xy 117.706036 -259.549256) (xy 117.669524 -259.587194)
			(xy 117.62765 -259.619113) (xy 117.581394 -259.644266) (xy 117.531841 -259.662064) (xy 117.480151 -259.672088)
			(xy 117.427537 -259.674105) (xy 117.375232 -259.668067) (xy 117.324461 -259.654115) (xy 117.276416 -259.632576)
			(xy 117.232221 -259.603956) (xy 117.192913 -259.568925) (xy 117.159413 -259.528304) (xy 117.132507 -259.483045)
			(xy 117.112824 -259.43421) (xy 117.100827 -259.382942) (xy 117.096797 -259.330444) (xy 116.059204 -259.330444)
			(xy 116.223288 -259.494528) (xy 116.228747 -259.49965) (xy 116.241918 -259.506747) (xy 116.249196 -259.508498)
			(xy 116.24945 -259.508498) (xy 116.274134 -259.51389) (xy 116.321692 -259.530949) (xy 116.366237 -259.55479)
			(xy 116.406809 -259.5849) (xy 116.442533 -259.620628) (xy 116.472637 -259.661205) (xy 116.496471 -259.705754)
			(xy 116.50525 -259.73024) (xy 120.865649 -259.73024) (xy 120.869679 -259.677742) (xy 120.881676 -259.626474)
			(xy 120.901359 -259.577639) (xy 120.928265 -259.53238) (xy 120.961765 -259.491759) (xy 121.001073 -259.456728)
			(xy 121.045268 -259.428108) (xy 121.093313 -259.406569) (xy 121.144084 -259.392617) (xy 121.196389 -259.386579)
			(xy 121.249003 -259.388596) (xy 121.300693 -259.39862) (xy 121.350246 -259.416418) (xy 121.396502 -259.441571)
			(xy 121.438376 -259.47349) (xy 121.474888 -259.511428) (xy 121.50518 -259.554494) (xy 121.528543 -259.601679)
			(xy 121.544429 -259.651878) (xy 121.552466 -259.703914) (xy 121.55297 -259.73024) (xy 122.791223 -259.73024)
			(xy 122.795253 -259.677742) (xy 122.80725 -259.626474) (xy 122.826933 -259.577639) (xy 122.853839 -259.53238)
			(xy 122.887339 -259.491759) (xy 122.926647 -259.456728) (xy 122.970842 -259.428108) (xy 123.018887 -259.406569)
			(xy 123.069658 -259.392617) (xy 123.121963 -259.386579) (xy 123.174577 -259.388596) (xy 123.226267 -259.39862)
			(xy 123.27582 -259.416418) (xy 123.322076 -259.441571) (xy 123.36395 -259.47349) (xy 123.400462 -259.511428)
			(xy 123.430754 -259.554494) (xy 123.454117 -259.601679) (xy 123.470003 -259.651878) (xy 123.47804 -259.703914)
			(xy 123.478544 -259.73024) (xy 124.696223 -259.73024) (xy 124.700253 -259.677742) (xy 124.71225 -259.626474)
			(xy 124.731933 -259.577639) (xy 124.758839 -259.53238) (xy 124.792339 -259.491759) (xy 124.831647 -259.456728)
			(xy 124.875842 -259.428108) (xy 124.923887 -259.406569) (xy 124.974658 -259.392617) (xy 125.026963 -259.386579)
			(xy 125.079577 -259.388596) (xy 125.131267 -259.39862) (xy 125.18082 -259.416418) (xy 125.227076 -259.441571)
			(xy 125.26895 -259.47349) (xy 125.305462 -259.511428) (xy 125.335754 -259.554494) (xy 125.359117 -259.601679)
			(xy 125.375003 -259.651878) (xy 125.38304 -259.703914) (xy 125.383544 -259.73024) (xy 125.38304 -259.756566)
			(xy 125.375003 -259.808602) (xy 125.359117 -259.858801) (xy 125.335754 -259.905986) (xy 125.305462 -259.949052)
			(xy 125.26895 -259.98699) (xy 125.227076 -260.018909) (xy 125.18082 -260.044062) (xy 125.131267 -260.06186)
			(xy 125.079577 -260.071884) (xy 125.026963 -260.073901) (xy 124.974658 -260.067863) (xy 124.923887 -260.053911)
			(xy 124.875842 -260.032372) (xy 124.831647 -260.003752) (xy 124.792339 -259.968721) (xy 124.758839 -259.9281)
			(xy 124.731933 -259.882841) (xy 124.71225 -259.834006) (xy 124.700253 -259.782738) (xy 124.696223 -259.73024)
			(xy 123.478544 -259.73024) (xy 123.47804 -259.756566) (xy 123.470003 -259.808602) (xy 123.454117 -259.858801)
			(xy 123.430754 -259.905986) (xy 123.400462 -259.949052) (xy 123.36395 -259.98699) (xy 123.322076 -260.018909)
			(xy 123.27582 -260.044062) (xy 123.226267 -260.06186) (xy 123.174577 -260.071884) (xy 123.121963 -260.073901)
			(xy 123.069658 -260.067863) (xy 123.018887 -260.053911) (xy 122.970842 -260.032372) (xy 122.926647 -260.003752)
			(xy 122.887339 -259.968721) (xy 122.853839 -259.9281) (xy 122.826933 -259.882841) (xy 122.80725 -259.834006)
			(xy 122.795253 -259.782738) (xy 122.791223 -259.73024) (xy 121.55297 -259.73024) (xy 121.552466 -259.756566)
			(xy 121.544429 -259.808602) (xy 121.528543 -259.858801) (xy 121.50518 -259.905986) (xy 121.474888 -259.949052)
			(xy 121.438376 -259.98699) (xy 121.396502 -260.018909) (xy 121.350246 -260.044062) (xy 121.300693 -260.06186)
			(xy 121.249003 -260.071884) (xy 121.196389 -260.073901) (xy 121.144084 -260.067863) (xy 121.093313 -260.053911)
			(xy 121.045268 -260.032372) (xy 121.001073 -260.003752) (xy 120.961765 -259.968721) (xy 120.928265 -259.9281)
			(xy 120.901359 -259.882841) (xy 120.881676 -259.834006) (xy 120.869679 -259.782738) (xy 120.865649 -259.73024)
			(xy 116.50525 -259.73024) (xy 116.513523 -259.753314) (xy 116.518944 -259.777992) (xy 116.518944 -259.778246)
			(xy 116.520702 -259.78552) (xy 116.527807 -259.798683) (xy 116.532914 -259.804154) (xy 116.945156 -260.216396)
			(xy 116.951531 -260.222274) (xy 116.967172 -260.229733) (xy 116.984405 -260.231555) (xy 116.992908 -260.229858)
			(xy 117.090444 -260.206236) (xy 117.109494 -260.188456) (xy 117.113812 -260.175502) (xy 117.122544 -260.149878)
			(xy 117.146929 -260.101551) (xy 117.178603 -260.057653) (xy 117.216779 -260.019276) (xy 117.26051 -259.987372)
			(xy 117.308708 -259.962732) (xy 117.360179 -259.945969) (xy 117.413644 -259.937499) (xy 117.44071 -259.936996)
			(xy 117.467695 -259.937526) (xy 117.520999 -259.94597) (xy 117.572326 -259.962649) (xy 117.620412 -259.987151)
			(xy 117.664073 -260.018875) (xy 117.702235 -260.057037) (xy 117.733956 -260.1007) (xy 117.758457 -260.148787)
			(xy 117.775133 -260.200115) (xy 117.783575 -260.253419) (xy 117.784118 -260.280404) (xy 117.783602 -260.307465)
			(xy 117.775097 -260.360914) (xy 117.758313 -260.412368) (xy 117.733666 -260.460552) (xy 117.701766 -260.504274)
			(xy 117.663403 -260.542451) (xy 117.619527 -260.574138) (xy 117.571224 -260.59855) (xy 117.545612 -260.607302)
			(xy 117.532658 -260.61162) (xy 117.514878 -260.63067) (xy 117.491256 -260.728206) (xy 117.489558 -260.736709)
			(xy 117.491365 -260.753942) (xy 117.498853 -260.769568) (xy 117.504718 -260.775958) (xy 117.854984 -261.126224)
			(xy 121.638834 -261.126224) (xy 121.642794 -261.07717) (xy 121.654571 -261.029386) (xy 121.673862 -260.98411)
			(xy 121.700165 -260.942514) (xy 121.7328 -260.905677) (xy 121.770921 -260.874552) (xy 121.813542 -260.849945)
			(xy 121.859558 -260.832493) (xy 121.907777 -260.822649) (xy 121.956952 -260.820668) (xy 122.005807 -260.8266)
			(xy 122.053078 -260.840292) (xy 122.09754 -260.86139) (xy 122.138043 -260.889346) (xy 122.173536 -260.923438)
			(xy 122.203101 -260.962782) (xy 122.225972 -261.006359) (xy 122.241556 -261.05304) (xy 122.249451 -261.101617)
			(xy 122.249946 -261.126224) (xy 123.518942 -261.126224) (xy 123.522902 -261.07717) (xy 123.534679 -261.029386)
			(xy 123.55397 -260.98411) (xy 123.580273 -260.942514) (xy 123.612908 -260.905677) (xy 123.651029 -260.874552)
			(xy 123.69365 -260.849945) (xy 123.739666 -260.832493) (xy 123.787885 -260.822649) (xy 123.83706 -260.820668)
			(xy 123.885915 -260.8266) (xy 123.933186 -260.840292) (xy 123.977648 -260.86139) (xy 124.018151 -260.889346)
			(xy 124.053644 -260.923438) (xy 124.083209 -260.962782) (xy 124.10608 -261.006359) (xy 124.121664 -261.05304)
			(xy 124.129559 -261.101617) (xy 124.130054 -261.126224) (xy 125.39905 -261.126224) (xy 125.40301 -261.07717)
			(xy 125.414787 -261.029386) (xy 125.434078 -260.98411) (xy 125.460381 -260.942514) (xy 125.493016 -260.905677)
			(xy 125.531137 -260.874552) (xy 125.573758 -260.849945) (xy 125.619774 -260.832493) (xy 125.667993 -260.822649)
			(xy 125.717168 -260.820668) (xy 125.766023 -260.8266) (xy 125.813294 -260.840292) (xy 125.857756 -260.86139)
			(xy 125.898259 -260.889346) (xy 125.933752 -260.923438) (xy 125.963317 -260.962782) (xy 125.986188 -261.006359)
			(xy 126.001772 -261.05304) (xy 126.009667 -261.101617) (xy 126.010162 -261.126224) (xy 127.278904 -261.126224)
			(xy 127.282864 -261.07717) (xy 127.294641 -261.029386) (xy 127.313932 -260.98411) (xy 127.340235 -260.942514)
			(xy 127.37287 -260.905677) (xy 127.410991 -260.874552) (xy 127.453612 -260.849945) (xy 127.499628 -260.832493)
			(xy 127.547847 -260.822649) (xy 127.597022 -260.820668) (xy 127.645877 -260.8266) (xy 127.693148 -260.840292)
			(xy 127.73761 -260.86139) (xy 127.778113 -260.889346) (xy 127.813606 -260.923438) (xy 127.843171 -260.962782)
			(xy 127.866042 -261.006359) (xy 127.881626 -261.05304) (xy 127.889521 -261.101617) (xy 127.890016 -261.126224)
			(xy 128.218958 -261.126224) (xy 128.222918 -261.07717) (xy 128.234695 -261.029386) (xy 128.253986 -260.98411)
			(xy 128.280289 -260.942514) (xy 128.312924 -260.905677) (xy 128.351045 -260.874552) (xy 128.393666 -260.849945)
			(xy 128.439682 -260.832493) (xy 128.487901 -260.822649) (xy 128.537076 -260.820668) (xy 128.585931 -260.8266)
			(xy 128.633202 -260.840292) (xy 128.677664 -260.86139) (xy 128.718167 -260.889346) (xy 128.75366 -260.923438)
			(xy 128.783225 -260.962782) (xy 128.806096 -261.006359) (xy 128.82168 -261.05304) (xy 128.829575 -261.101617)
			(xy 128.83007 -261.126224) (xy 129.159012 -261.126224) (xy 129.162972 -261.07717) (xy 129.174749 -261.029386)
			(xy 129.19404 -260.98411) (xy 129.220343 -260.942514) (xy 129.252978 -260.905677) (xy 129.291099 -260.874552)
			(xy 129.33372 -260.849945) (xy 129.379736 -260.832493) (xy 129.427955 -260.822649) (xy 129.47713 -260.820668)
			(xy 129.525985 -260.8266) (xy 129.573256 -260.840292) (xy 129.617718 -260.86139) (xy 129.658221 -260.889346)
			(xy 129.693714 -260.923438) (xy 129.723279 -260.962782) (xy 129.74615 -261.006359) (xy 129.761734 -261.05304)
			(xy 129.769629 -261.101617) (xy 129.770124 -261.126224) (xy 130.099066 -261.126224) (xy 130.103026 -261.07717)
			(xy 130.114803 -261.029386) (xy 130.134094 -260.98411) (xy 130.160397 -260.942514) (xy 130.193032 -260.905677)
			(xy 130.231153 -260.874552) (xy 130.273774 -260.849945) (xy 130.31979 -260.832493) (xy 130.368009 -260.822649)
			(xy 130.417184 -260.820668) (xy 130.466039 -260.8266) (xy 130.51331 -260.840292) (xy 130.557772 -260.86139)
			(xy 130.598275 -260.889346) (xy 130.633768 -260.923438) (xy 130.663333 -260.962782) (xy 130.686204 -261.006359)
			(xy 130.701788 -261.05304) (xy 130.709683 -261.101617) (xy 130.710178 -261.126224) (xy 131.038866 -261.126224)
			(xy 131.042826 -261.07717) (xy 131.054603 -261.029386) (xy 131.073894 -260.98411) (xy 131.100197 -260.942514)
			(xy 131.132832 -260.905677) (xy 131.170953 -260.874552) (xy 131.213574 -260.849945) (xy 131.25959 -260.832493)
			(xy 131.307809 -260.822649) (xy 131.356984 -260.820668) (xy 131.405839 -260.8266) (xy 131.45311 -260.840292)
			(xy 131.497572 -260.86139) (xy 131.538075 -260.889346) (xy 131.573568 -260.923438) (xy 131.603133 -260.962782)
			(xy 131.626004 -261.006359) (xy 131.641588 -261.05304) (xy 131.649483 -261.101617) (xy 131.649978 -261.126224)
			(xy 131.97892 -261.126224) (xy 131.98288 -261.07717) (xy 131.994657 -261.029386) (xy 132.013948 -260.98411)
			(xy 132.040251 -260.942514) (xy 132.072886 -260.905677) (xy 132.111007 -260.874552) (xy 132.153628 -260.849945)
			(xy 132.199644 -260.832493) (xy 132.247863 -260.822649) (xy 132.297038 -260.820668) (xy 132.345893 -260.8266)
			(xy 132.393164 -260.840292) (xy 132.437626 -260.86139) (xy 132.478129 -260.889346) (xy 132.513622 -260.923438)
			(xy 132.543187 -260.962782) (xy 132.566058 -261.006359) (xy 132.581642 -261.05304) (xy 132.589537 -261.101617)
			(xy 132.590032 -261.126224) (xy 132.918974 -261.126224) (xy 132.922934 -261.07717) (xy 132.934711 -261.029386)
			(xy 132.954002 -260.98411) (xy 132.980305 -260.942514) (xy 133.01294 -260.905677) (xy 133.051061 -260.874552)
			(xy 133.093682 -260.849945) (xy 133.139698 -260.832493) (xy 133.187917 -260.822649) (xy 133.237092 -260.820668)
			(xy 133.285947 -260.8266) (xy 133.333218 -260.840292) (xy 133.37768 -260.86139) (xy 133.418183 -260.889346)
			(xy 133.453676 -260.923438) (xy 133.483241 -260.962782) (xy 133.506112 -261.006359) (xy 133.521696 -261.05304)
			(xy 133.529591 -261.101617) (xy 133.530086 -261.126224) (xy 133.529591 -261.150831) (xy 133.521696 -261.199408)
			(xy 133.506112 -261.246089) (xy 133.483241 -261.289666) (xy 133.453676 -261.32901) (xy 133.418183 -261.363102)
			(xy 133.37768 -261.391058) (xy 133.333218 -261.412156) (xy 133.285947 -261.425848) (xy 133.237092 -261.43178)
			(xy 133.187917 -261.429799) (xy 133.139698 -261.419955) (xy 133.093682 -261.402503) (xy 133.051061 -261.377896)
			(xy 133.01294 -261.346771) (xy 132.980305 -261.309934) (xy 132.954002 -261.268338) (xy 132.934711 -261.223062)
			(xy 132.922934 -261.175278) (xy 132.918974 -261.126224) (xy 132.590032 -261.126224) (xy 132.589537 -261.150831)
			(xy 132.581642 -261.199408) (xy 132.566058 -261.246089) (xy 132.543187 -261.289666) (xy 132.513622 -261.32901)
			(xy 132.478129 -261.363102) (xy 132.437626 -261.391058) (xy 132.393164 -261.412156) (xy 132.345893 -261.425848)
			(xy 132.297038 -261.43178) (xy 132.247863 -261.429799) (xy 132.199644 -261.419955) (xy 132.153628 -261.402503)
			(xy 132.111007 -261.377896) (xy 132.072886 -261.346771) (xy 132.040251 -261.309934) (xy 132.013948 -261.268338)
			(xy 131.994657 -261.223062) (xy 131.98288 -261.175278) (xy 131.97892 -261.126224) (xy 131.649978 -261.126224)
			(xy 131.649483 -261.150831) (xy 131.641588 -261.199408) (xy 131.626004 -261.246089) (xy 131.603133 -261.289666)
			(xy 131.573568 -261.32901) (xy 131.538075 -261.363102) (xy 131.497572 -261.391058) (xy 131.45311 -261.412156)
			(xy 131.405839 -261.425848) (xy 131.356984 -261.43178) (xy 131.307809 -261.429799) (xy 131.25959 -261.419955)
			(xy 131.213574 -261.402503) (xy 131.170953 -261.377896) (xy 131.132832 -261.346771) (xy 131.100197 -261.309934)
			(xy 131.073894 -261.268338) (xy 131.054603 -261.223062) (xy 131.042826 -261.175278) (xy 131.038866 -261.126224)
			(xy 130.710178 -261.126224) (xy 130.709683 -261.150831) (xy 130.701788 -261.199408) (xy 130.686204 -261.246089)
			(xy 130.663333 -261.289666) (xy 130.633768 -261.32901) (xy 130.598275 -261.363102) (xy 130.557772 -261.391058)
			(xy 130.51331 -261.412156) (xy 130.466039 -261.425848) (xy 130.417184 -261.43178) (xy 130.368009 -261.429799)
			(xy 130.31979 -261.419955) (xy 130.273774 -261.402503) (xy 130.231153 -261.377896) (xy 130.193032 -261.346771)
			(xy 130.160397 -261.309934) (xy 130.134094 -261.268338) (xy 130.114803 -261.223062) (xy 130.103026 -261.175278)
			(xy 130.099066 -261.126224) (xy 129.770124 -261.126224) (xy 129.769629 -261.150831) (xy 129.761734 -261.199408)
			(xy 129.74615 -261.246089) (xy 129.723279 -261.289666) (xy 129.693714 -261.32901) (xy 129.658221 -261.363102)
			(xy 129.617718 -261.391058) (xy 129.573256 -261.412156) (xy 129.525985 -261.425848) (xy 129.47713 -261.43178)
			(xy 129.427955 -261.429799) (xy 129.379736 -261.419955) (xy 129.33372 -261.402503) (xy 129.291099 -261.377896)
			(xy 129.252978 -261.346771) (xy 129.220343 -261.309934) (xy 129.19404 -261.268338) (xy 129.174749 -261.223062)
			(xy 129.162972 -261.175278) (xy 129.159012 -261.126224) (xy 128.83007 -261.126224) (xy 128.829575 -261.150831)
			(xy 128.82168 -261.199408) (xy 128.806096 -261.246089) (xy 128.783225 -261.289666) (xy 128.75366 -261.32901)
			(xy 128.718167 -261.363102) (xy 128.677664 -261.391058) (xy 128.633202 -261.412156) (xy 128.585931 -261.425848)
			(xy 128.537076 -261.43178) (xy 128.487901 -261.429799) (xy 128.439682 -261.419955) (xy 128.393666 -261.402503)
			(xy 128.351045 -261.377896) (xy 128.312924 -261.346771) (xy 128.280289 -261.309934) (xy 128.253986 -261.268338)
			(xy 128.234695 -261.223062) (xy 128.222918 -261.175278) (xy 128.218958 -261.126224) (xy 127.890016 -261.126224)
			(xy 127.889521 -261.150831) (xy 127.881626 -261.199408) (xy 127.866042 -261.246089) (xy 127.843171 -261.289666)
			(xy 127.813606 -261.32901) (xy 127.778113 -261.363102) (xy 127.73761 -261.391058) (xy 127.693148 -261.412156)
			(xy 127.645877 -261.425848) (xy 127.597022 -261.43178) (xy 127.547847 -261.429799) (xy 127.499628 -261.419955)
			(xy 127.453612 -261.402503) (xy 127.410991 -261.377896) (xy 127.37287 -261.346771) (xy 127.340235 -261.309934)
			(xy 127.313932 -261.268338) (xy 127.294641 -261.223062) (xy 127.282864 -261.175278) (xy 127.278904 -261.126224)
			(xy 126.010162 -261.126224) (xy 126.009667 -261.150831) (xy 126.001772 -261.199408) (xy 125.986188 -261.246089)
			(xy 125.963317 -261.289666) (xy 125.933752 -261.32901) (xy 125.898259 -261.363102) (xy 125.857756 -261.391058)
			(xy 125.813294 -261.412156) (xy 125.766023 -261.425848) (xy 125.717168 -261.43178) (xy 125.667993 -261.429799)
			(xy 125.619774 -261.419955) (xy 125.573758 -261.402503) (xy 125.531137 -261.377896) (xy 125.493016 -261.346771)
			(xy 125.460381 -261.309934) (xy 125.434078 -261.268338) (xy 125.414787 -261.223062) (xy 125.40301 -261.175278)
			(xy 125.39905 -261.126224) (xy 124.130054 -261.126224) (xy 124.129559 -261.150831) (xy 124.121664 -261.199408)
			(xy 124.10608 -261.246089) (xy 124.083209 -261.289666) (xy 124.053644 -261.32901) (xy 124.018151 -261.363102)
			(xy 123.977648 -261.391058) (xy 123.933186 -261.412156) (xy 123.885915 -261.425848) (xy 123.83706 -261.43178)
			(xy 123.787885 -261.429799) (xy 123.739666 -261.419955) (xy 123.69365 -261.402503) (xy 123.651029 -261.377896)
			(xy 123.612908 -261.346771) (xy 123.580273 -261.309934) (xy 123.55397 -261.268338) (xy 123.534679 -261.223062)
			(xy 123.522902 -261.175278) (xy 123.518942 -261.126224) (xy 122.249946 -261.126224) (xy 122.249451 -261.150831)
			(xy 122.241556 -261.199408) (xy 122.225972 -261.246089) (xy 122.203101 -261.289666) (xy 122.173536 -261.32901)
			(xy 122.138043 -261.363102) (xy 122.09754 -261.391058) (xy 122.053078 -261.412156) (xy 122.005807 -261.425848)
			(xy 121.956952 -261.43178) (xy 121.907777 -261.429799) (xy 121.859558 -261.419955) (xy 121.813542 -261.402503)
			(xy 121.770921 -261.377896) (xy 121.7328 -261.346771) (xy 121.700165 -261.309934) (xy 121.673862 -261.268338)
			(xy 121.654571 -261.223062) (xy 121.642794 -261.175278) (xy 121.638834 -261.126224) (xy 117.854984 -261.126224)
			(xy 118.206774 -261.478014) (xy 118.207282 -261.478522) (xy 118.214663 -261.485103) (xy 118.232963 -261.492548)
			(xy 118.242842 -261.493) (xy 118.795038 -261.493) (xy 118.805105 -261.49343) (xy 118.823699 -261.501154)
			(xy 118.831106 -261.507986) (xy 119.25935 -261.93623) (xy 122.108988 -261.93623) (xy 122.112948 -261.887176)
			(xy 122.124725 -261.839392) (xy 122.144016 -261.794116) (xy 122.170319 -261.75252) (xy 122.202954 -261.715683)
			(xy 122.241075 -261.684558) (xy 122.283696 -261.659951) (xy 122.329712 -261.642499) (xy 122.377931 -261.632655)
			(xy 122.427106 -261.630674) (xy 122.475961 -261.636606) (xy 122.523232 -261.650298) (xy 122.567694 -261.671396)
			(xy 122.608197 -261.699352) (xy 122.64369 -261.733444) (xy 122.673255 -261.772788) (xy 122.696126 -261.816365)
			(xy 122.71171 -261.863046) (xy 122.719605 -261.911623) (xy 122.7201 -261.93623) (xy 123.988842 -261.93623)
			(xy 123.992802 -261.887176) (xy 124.004579 -261.839392) (xy 124.02387 -261.794116) (xy 124.050173 -261.75252)
			(xy 124.082808 -261.715683) (xy 124.120929 -261.684558) (xy 124.16355 -261.659951) (xy 124.209566 -261.642499)
			(xy 124.257785 -261.632655) (xy 124.30696 -261.630674) (xy 124.355815 -261.636606) (xy 124.403086 -261.650298)
			(xy 124.447548 -261.671396) (xy 124.488051 -261.699352) (xy 124.523544 -261.733444) (xy 124.553109 -261.772788)
			(xy 124.57598 -261.816365) (xy 124.591564 -261.863046) (xy 124.599459 -261.911623) (xy 124.599954 -261.93623)
			(xy 125.86895 -261.93623) (xy 125.87291 -261.887176) (xy 125.884687 -261.839392) (xy 125.903978 -261.794116)
			(xy 125.930281 -261.75252) (xy 125.962916 -261.715683) (xy 126.001037 -261.684558) (xy 126.043658 -261.659951)
			(xy 126.089674 -261.642499) (xy 126.137893 -261.632655) (xy 126.187068 -261.630674) (xy 126.235923 -261.636606)
			(xy 126.283194 -261.650298) (xy 126.327656 -261.671396) (xy 126.368159 -261.699352) (xy 126.403652 -261.733444)
			(xy 126.433217 -261.772788) (xy 126.456088 -261.816365) (xy 126.471672 -261.863046) (xy 126.479567 -261.911623)
			(xy 126.480062 -261.93623) (xy 127.738627 -261.93623) (xy 127.742722 -261.885502) (xy 127.754901 -261.836088)
			(xy 127.774849 -261.789268) (xy 127.80205 -261.746254) (xy 127.835798 -261.70816) (xy 127.87522 -261.675973)
			(xy 127.919294 -261.650527) (xy 127.96688 -261.63248) (xy 128.016744 -261.6223) (xy 128.067596 -261.620251)
			(xy 128.118117 -261.626385) (xy 128.167001 -261.640545) (xy 128.21298 -261.662362) (xy 128.254864 -261.691272)
			(xy 128.291568 -261.726527) (xy 128.322141 -261.767213) (xy 128.345792 -261.812276) (xy 128.361908 -261.86055)
			(xy 128.370072 -261.910784) (xy 128.370584 -261.93623) (xy 128.688858 -261.93623) (xy 128.692818 -261.887176)
			(xy 128.704595 -261.839392) (xy 128.723886 -261.794116) (xy 128.750189 -261.75252) (xy 128.782824 -261.715683)
			(xy 128.820945 -261.684558) (xy 128.863566 -261.659951) (xy 128.909582 -261.642499) (xy 128.957801 -261.632655)
			(xy 129.006976 -261.630674) (xy 129.055831 -261.636606) (xy 129.103102 -261.650298) (xy 129.147564 -261.671396)
			(xy 129.188067 -261.699352) (xy 129.22356 -261.733444) (xy 129.253125 -261.772788) (xy 129.275996 -261.816365)
			(xy 129.29158 -261.863046) (xy 129.299475 -261.911623) (xy 129.29997 -261.93623) (xy 129.628912 -261.93623)
			(xy 129.632872 -261.887176) (xy 129.644649 -261.839392) (xy 129.66394 -261.794116) (xy 129.690243 -261.75252)
			(xy 129.722878 -261.715683) (xy 129.760999 -261.684558) (xy 129.80362 -261.659951) (xy 129.849636 -261.642499)
			(xy 129.897855 -261.632655) (xy 129.94703 -261.630674) (xy 129.995885 -261.636606) (xy 130.043156 -261.650298)
			(xy 130.087618 -261.671396) (xy 130.128121 -261.699352) (xy 130.163614 -261.733444) (xy 130.193179 -261.772788)
			(xy 130.21605 -261.816365) (xy 130.231634 -261.863046) (xy 130.239529 -261.911623) (xy 130.240024 -261.93623)
			(xy 130.568966 -261.93623) (xy 130.572926 -261.887176) (xy 130.584703 -261.839392) (xy 130.603994 -261.794116)
			(xy 130.630297 -261.75252) (xy 130.662932 -261.715683) (xy 130.701053 -261.684558) (xy 130.743674 -261.659951)
			(xy 130.78969 -261.642499) (xy 130.837909 -261.632655) (xy 130.887084 -261.630674) (xy 130.935939 -261.636606)
			(xy 130.98321 -261.650298) (xy 131.027672 -261.671396) (xy 131.068175 -261.699352) (xy 131.103668 -261.733444)
			(xy 131.133233 -261.772788) (xy 131.156104 -261.816365) (xy 131.171688 -261.863046) (xy 131.179583 -261.911623)
			(xy 131.180078 -261.93623) (xy 131.498589 -261.93623) (xy 131.502684 -261.885502) (xy 131.514863 -261.836088)
			(xy 131.534811 -261.789268) (xy 131.562012 -261.746254) (xy 131.59576 -261.70816) (xy 131.635182 -261.675973)
			(xy 131.679256 -261.650527) (xy 131.726842 -261.63248) (xy 131.776706 -261.6223) (xy 131.827558 -261.620251)
			(xy 131.878079 -261.626385) (xy 131.926963 -261.640545) (xy 131.972942 -261.662362) (xy 132.014826 -261.691272)
			(xy 132.05153 -261.726527) (xy 132.082103 -261.767213) (xy 132.105754 -261.812276) (xy 132.12187 -261.86055)
			(xy 132.130034 -261.910784) (xy 132.130546 -261.93623) (xy 132.44882 -261.93623) (xy 132.45278 -261.887176)
			(xy 132.464557 -261.839392) (xy 132.483848 -261.794116) (xy 132.510151 -261.75252) (xy 132.542786 -261.715683)
			(xy 132.580907 -261.684558) (xy 132.623528 -261.659951) (xy 132.669544 -261.642499) (xy 132.717763 -261.632655)
			(xy 132.766938 -261.630674) (xy 132.815793 -261.636606) (xy 132.863064 -261.650298) (xy 132.907526 -261.671396)
			(xy 132.948029 -261.699352) (xy 132.983522 -261.733444) (xy 133.013087 -261.772788) (xy 133.035958 -261.816365)
			(xy 133.051542 -261.863046) (xy 133.059437 -261.911623) (xy 133.059932 -261.93623) (xy 133.059437 -261.960837)
			(xy 133.051542 -262.009414) (xy 133.035958 -262.056095) (xy 133.013087 -262.099672) (xy 132.983522 -262.139016)
			(xy 132.948029 -262.173108) (xy 132.907526 -262.201064) (xy 132.863064 -262.222162) (xy 132.815793 -262.235854)
			(xy 132.766938 -262.241786) (xy 132.717763 -262.239805) (xy 132.669544 -262.229961) (xy 132.623528 -262.212509)
			(xy 132.580907 -262.187902) (xy 132.542786 -262.156777) (xy 132.510151 -262.11994) (xy 132.483848 -262.078344)
			(xy 132.464557 -262.033068) (xy 132.45278 -261.985284) (xy 132.44882 -261.93623) (xy 132.130546 -261.93623)
			(xy 132.130034 -261.961676) (xy 132.12187 -262.01191) (xy 132.105754 -262.060184) (xy 132.082103 -262.105247)
			(xy 132.05153 -262.145933) (xy 132.014826 -262.181188) (xy 131.972942 -262.210098) (xy 131.926963 -262.231915)
			(xy 131.878079 -262.246075) (xy 131.827558 -262.252209) (xy 131.776706 -262.25016) (xy 131.726842 -262.23998)
			(xy 131.679256 -262.221933) (xy 131.635182 -262.196487) (xy 131.59576 -262.1643) (xy 131.562012 -262.126206)
			(xy 131.534811 -262.083192) (xy 131.514863 -262.036372) (xy 131.502684 -261.986958) (xy 131.498589 -261.93623)
			(xy 131.180078 -261.93623) (xy 131.179583 -261.960837) (xy 131.171688 -262.009414) (xy 131.156104 -262.056095)
			(xy 131.133233 -262.099672) (xy 131.103668 -262.139016) (xy 131.068175 -262.173108) (xy 131.027672 -262.201064)
			(xy 130.98321 -262.222162) (xy 130.935939 -262.235854) (xy 130.887084 -262.241786) (xy 130.837909 -262.239805)
			(xy 130.78969 -262.229961) (xy 130.743674 -262.212509) (xy 130.701053 -262.187902) (xy 130.662932 -262.156777)
			(xy 130.630297 -262.11994) (xy 130.603994 -262.078344) (xy 130.584703 -262.033068) (xy 130.572926 -261.985284)
			(xy 130.568966 -261.93623) (xy 130.240024 -261.93623) (xy 130.239529 -261.960837) (xy 130.231634 -262.009414)
			(xy 130.21605 -262.056095) (xy 130.193179 -262.099672) (xy 130.163614 -262.139016) (xy 130.128121 -262.173108)
			(xy 130.087618 -262.201064) (xy 130.043156 -262.222162) (xy 129.995885 -262.235854) (xy 129.94703 -262.241786)
			(xy 129.897855 -262.239805) (xy 129.849636 -262.229961) (xy 129.80362 -262.212509) (xy 129.760999 -262.187902)
			(xy 129.722878 -262.156777) (xy 129.690243 -262.11994) (xy 129.66394 -262.078344) (xy 129.644649 -262.033068)
			(xy 129.632872 -261.985284) (xy 129.628912 -261.93623) (xy 129.29997 -261.93623) (xy 129.299475 -261.960837)
			(xy 129.29158 -262.009414) (xy 129.275996 -262.056095) (xy 129.253125 -262.099672) (xy 129.22356 -262.139016)
			(xy 129.188067 -262.173108) (xy 129.147564 -262.201064) (xy 129.103102 -262.222162) (xy 129.055831 -262.235854)
			(xy 129.006976 -262.241786) (xy 128.957801 -262.239805) (xy 128.909582 -262.229961) (xy 128.863566 -262.212509)
			(xy 128.820945 -262.187902) (xy 128.782824 -262.156777) (xy 128.750189 -262.11994) (xy 128.723886 -262.078344)
			(xy 128.704595 -262.033068) (xy 128.692818 -261.985284) (xy 128.688858 -261.93623) (xy 128.370584 -261.93623)
			(xy 128.370072 -261.961676) (xy 128.361908 -262.01191) (xy 128.345792 -262.060184) (xy 128.322141 -262.105247)
			(xy 128.291568 -262.145933) (xy 128.254864 -262.181188) (xy 128.21298 -262.210098) (xy 128.167001 -262.231915)
			(xy 128.118117 -262.246075) (xy 128.067596 -262.252209) (xy 128.016744 -262.25016) (xy 127.96688 -262.23998)
			(xy 127.919294 -262.221933) (xy 127.87522 -262.196487) (xy 127.835798 -262.1643) (xy 127.80205 -262.126206)
			(xy 127.774849 -262.083192) (xy 127.754901 -262.036372) (xy 127.742722 -261.986958) (xy 127.738627 -261.93623)
			(xy 126.480062 -261.93623) (xy 126.479567 -261.960837) (xy 126.471672 -262.009414) (xy 126.456088 -262.056095)
			(xy 126.433217 -262.099672) (xy 126.403652 -262.139016) (xy 126.368159 -262.173108) (xy 126.327656 -262.201064)
			(xy 126.283194 -262.222162) (xy 126.235923 -262.235854) (xy 126.187068 -262.241786) (xy 126.137893 -262.239805)
			(xy 126.089674 -262.229961) (xy 126.043658 -262.212509) (xy 126.001037 -262.187902) (xy 125.962916 -262.156777)
			(xy 125.930281 -262.11994) (xy 125.903978 -262.078344) (xy 125.884687 -262.033068) (xy 125.87291 -261.985284)
			(xy 125.86895 -261.93623) (xy 124.599954 -261.93623) (xy 124.599459 -261.960837) (xy 124.591564 -262.009414)
			(xy 124.57598 -262.056095) (xy 124.553109 -262.099672) (xy 124.523544 -262.139016) (xy 124.488051 -262.173108)
			(xy 124.447548 -262.201064) (xy 124.403086 -262.222162) (xy 124.355815 -262.235854) (xy 124.30696 -262.241786)
			(xy 124.257785 -262.239805) (xy 124.209566 -262.229961) (xy 124.16355 -262.212509) (xy 124.120929 -262.187902)
			(xy 124.082808 -262.156777) (xy 124.050173 -262.11994) (xy 124.02387 -262.078344) (xy 124.004579 -262.033068)
			(xy 123.992802 -261.985284) (xy 123.988842 -261.93623) (xy 122.7201 -261.93623) (xy 122.719605 -261.960837)
			(xy 122.71171 -262.009414) (xy 122.696126 -262.056095) (xy 122.673255 -262.099672) (xy 122.64369 -262.139016)
			(xy 122.608197 -262.173108) (xy 122.567694 -262.201064) (xy 122.523232 -262.222162) (xy 122.475961 -262.235854)
			(xy 122.427106 -262.241786) (xy 122.377931 -262.239805) (xy 122.329712 -262.229961) (xy 122.283696 -262.212509)
			(xy 122.241075 -262.187902) (xy 122.202954 -262.156777) (xy 122.170319 -262.11994) (xy 122.144016 -262.078344)
			(xy 122.124725 -262.033068) (xy 122.112948 -261.985284) (xy 122.108988 -261.93623) (xy 119.25935 -261.93623)
			(xy 120.256554 -262.933434) (xy 120.257062 -262.933942) (xy 120.264443 -262.940524) (xy 120.282742 -262.947973)
			(xy 120.292622 -262.94842) (xy 121.55043 -262.94842)
		)
		(stroke
			(width 0)
			(type solid)
		)
		(fill yes)
		(layer "In13.Cu")
		(net "PVDDCR_SOC_P1")
	)
	(gr_poly
		(pts
			(xy 195.82765 -342.06942) (xy 195.837717 -342.068988) (xy 195.85631 -342.061263) (xy 195.863718 -342.054434)
			(xy 196.230494 -341.687658) (xy 196.237335 -341.680257) (xy 196.245055 -341.661659) (xy 196.24548 -341.65159)
			(xy 196.24548 -327.340722) (xy 196.245309 -327.334713) (xy 196.242479 -327.323034) (xy 196.239892 -327.317608)
			(xy 196.238054 -327.314133) (xy 196.233462 -327.307752) (xy 196.230748 -327.304908) (xy 194.449446 -325.523606)
			(xy 194.442594 -325.51621) (xy 194.43485 -325.497612) (xy 194.43446 -325.487538) (xy 194.43446 -321.298062)
			(xy 194.434295 -321.292052) (xy 194.431477 -321.280367) (xy 194.428872 -321.274948) (xy 194.42703 -321.271476)
			(xy 194.422431 -321.265102) (xy 194.419728 -321.262248) (xy 193.776092 -320.618612) (xy 193.77324 -320.615907)
			(xy 193.76686 -320.611317) (xy 193.763392 -320.609468) (xy 193.757966 -320.606883) (xy 193.746286 -320.604053)
			(xy 193.740278 -320.60388) (xy 161.029142 -320.60388) (xy 161.019077 -320.603446) (xy 161.00049 -320.595714)
			(xy 160.993074 -320.588894) (xy 150.803102 -310.398922) (xy 150.795747 -310.39227) (xy 150.777446 -310.384686)
			(xy 150.767542 -310.38419) (xy 150.743158 -310.390286) (xy 150.737824 -310.39308) (xy 150.710441 -310.406652)
			(xy 150.652432 -310.425879) (xy 150.592104 -310.435636) (xy 150.561548 -310.43626) (xy 150.561294 -310.43626)
			(xy 150.534043 -310.435796) (xy 150.480095 -310.428038) (xy 150.427801 -310.412681) (xy 150.378224 -310.390038)
			(xy 150.332375 -310.360569) (xy 150.291187 -310.324874) (xy 150.255499 -310.283681) (xy 150.226036 -310.237828)
			(xy 150.2034 -310.188249) (xy 150.18805 -310.135952) (xy 150.1803 -310.082003) (xy 150.179786 -310.054752)
			(xy 150.179532 -310.054752) (xy 150.180179 -310.023188) (xy 150.190559 -309.960918) (xy 150.211044 -309.901205)
			(xy 150.225506 -309.873142) (xy 150.22576 -309.872888) (xy 150.229389 -309.865505) (xy 150.23225 -309.849314)
			(xy 150.231348 -309.841138) (xy 150.230332 -309.833518) (xy 150.222966 -309.818786) (xy 145.214594 -304.810414)
			(xy 145.207308 -304.803811) (xy 145.189184 -304.796234) (xy 145.169541 -304.796053) (xy 145.160238 -304.799238)
			(xy 145.073624 -304.83302) (xy 145.066755 -304.835929) (xy 145.054992 -304.845092) (xy 145.05051 -304.851054)
			(xy 145.041874 -304.863246) (xy 145.04162 -304.870358) (xy 145.041366 -304.879502) (xy 145.038098 -304.950071)
			(xy 145.024621 -305.090713) (xy 145.003271 -305.230377) (xy 144.974114 -305.368622) (xy 144.937242 -305.505012)
			(xy 144.892773 -305.639118) (xy 144.840846 -305.770516) (xy 144.781624 -305.898791) (xy 144.715296 -306.02354)
			(xy 144.642069 -306.144369) (xy 144.562175 -306.260897) (xy 144.475865 -306.372756) (xy 144.383413 -306.479594)
			(xy 144.285109 -306.581074) (xy 144.181263 -306.676875) (xy 144.072203 -306.766696) (xy 143.958274 -306.850254)
			(xy 143.839833 -306.927284) (xy 143.717255 -306.997544) (xy 143.590926 -307.060812) (xy 143.461245 -307.116889)
			(xy 143.328621 -307.165598) (xy 143.193472 -307.206786) (xy 143.056223 -307.240322) (xy 142.917308 -307.2661)
			(xy 142.777166 -307.284041) (xy 142.636237 -307.294085) (xy 142.494967 -307.296203) (xy 142.3538 -307.290388)
			(xy 142.213183 -307.276657) (xy 142.073558 -307.255055) (xy 141.935365 -307.225649) (xy 141.799042 -307.188531)
			(xy 141.665017 -307.14382) (xy 141.533713 -307.091656) (xy 141.405544 -307.032203) (xy 141.280915 -306.965649)
			(xy 141.160219 -306.892205) (xy 141.043835 -306.8121) (xy 140.932132 -306.725589) (xy 140.825461 -306.632944)
			(xy 140.724159 -306.534457) (xy 140.628545 -306.430439) (xy 140.538921 -306.321217) (xy 140.455569 -306.207137)
			(xy 140.378753 -306.088558) (xy 140.308714 -305.965853) (xy 140.245674 -305.83941) (xy 140.189831 -305.709629)
			(xy 140.141361 -305.576916) (xy 140.100417 -305.441693) (xy 140.067129 -305.304384) (xy 140.041601 -305.165423)
			(xy 140.032232 -305.095402) (xy 140.023734 -305.024022) (xy 140.013913 -304.880593) (xy 140.012301 -304.736838)
			(xy 140.018901 -304.593225) (xy 140.033693 -304.450224) (xy 140.056628 -304.308301) (xy 140.087632 -304.167919)
			(xy 140.126603 -304.029538) (xy 140.173415 -303.893608) (xy 140.227913 -303.760574) (xy 140.289921 -303.630869)
			(xy 140.359235 -303.504918) (xy 140.43563 -303.383131) (xy 140.518857 -303.265907) (xy 140.608642 -303.153627)
			(xy 140.704694 -303.046659) (xy 140.806699 -302.945351) (xy 140.914323 -302.850034) (xy 141.027216 -302.761021)
			(xy 141.145008 -302.6786) (xy 141.267316 -302.603042) (xy 141.393739 -302.534592) (xy 141.523866 -302.473475)
			(xy 141.65727 -302.41989) (xy 141.793518 -302.374012) (xy 141.932163 -302.33599) (xy 142.072754 -302.305949)
			(xy 142.214831 -302.283987) (xy 142.357931 -302.270176) (xy 142.429738 -302.266858) (xy 142.437358 -302.266604)
			(xy 142.451074 -302.262032) (xy 142.457424 -302.25746) (xy 142.463217 -302.25301) (xy 142.472241 -302.241532)
			(xy 142.475204 -302.234854) (xy 142.485618 -302.208184) (xy 142.508986 -302.147986) (xy 142.51215 -302.138682)
			(xy 142.511942 -302.119048) (xy 142.5044 -302.100919) (xy 142.49781 -302.09363) (xy 135.5725 -295.16832)
			(xy 135.565862 -295.1622) (xy 135.549474 -295.154654) (xy 135.531488 -295.153235) (xy 135.522716 -295.155366)
			(xy 135.468614 -295.170606) (xy 135.437118 -295.179496) (xy 135.430755 -295.181589) (xy 135.419312 -295.18854)
			(xy 135.414512 -295.193212) (xy 135.40994 -295.198038) (xy 135.40359 -295.209468) (xy 135.401812 -295.21658)
			(xy 135.395423 -295.241333) (xy 135.375529 -295.288421) (xy 135.34807 -295.331537) (xy 135.313811 -295.369475)
			(xy 135.27371 -295.401177) (xy 135.228889 -295.425754) (xy 135.180599 -295.442521) (xy 135.130191 -295.45101)
			(xy 135.104632 -295.45153) (xy 135.080637 -295.451086) (xy 135.033236 -295.443584) (xy 134.987593 -295.428758)
			(xy 134.94483 -295.406975) (xy 134.906003 -295.37877) (xy 134.872065 -295.344839) (xy 134.843853 -295.306016)
			(xy 134.822063 -295.263257) (xy 134.807229 -295.217617) (xy 134.799718 -295.170217) (xy 134.799324 -295.146222)
			(xy 134.799464 -295.133459) (xy 134.80163 -295.108026) (xy 134.803642 -295.095422) (xy 134.803388 -295.095422)
			(xy 134.808147 -295.070292) (xy 134.82493 -295.021982) (xy 134.849531 -294.977145) (xy 134.881263 -294.937037)
			(xy 134.919237 -294.90278) (xy 134.96239 -294.875333) (xy 135.009516 -294.855464) (xy 135.034274 -294.849042)
			(xy 135.034528 -294.849042) (xy 135.041041 -294.847192) (xy 135.052884 -294.84064) (xy 135.057896 -294.836088)
			(xy 135.062722 -294.83177) (xy 135.069326 -294.82034) (xy 135.080248 -294.78224) (xy 135.095488 -294.728138)
			(xy 135.097626 -294.719363) (xy 135.096244 -294.701367) (xy 135.088667 -294.684986) (xy 135.082534 -294.678354)
			(xy 134.974584 -294.570404) (xy 134.968126 -294.564489) (xy 134.952277 -294.557074) (xy 134.943596 -294.555926)
			(xy 134.870698 -294.553386) (xy 134.865778 -294.55334) (xy 134.856061 -294.554877) (xy 134.851394 -294.556434)
			(xy 134.84352 -294.559482) (xy 134.8359 -294.566086) (xy 134.814867 -294.583656) (xy 134.767838 -294.61178)
			(xy 134.716547 -294.631068) (xy 134.662638 -294.6409) (xy 134.63524 -294.641524) (xy 134.634732 -294.641524)
			(xy 134.610737 -294.64108) (xy 134.563336 -294.633578) (xy 134.517693 -294.618752) (xy 134.474932 -294.596969)
			(xy 134.436104 -294.568764) (xy 134.402167 -294.534832) (xy 134.373956 -294.496009) (xy 134.352166 -294.453251)
			(xy 134.337334 -294.40761) (xy 134.329824 -294.360211) (xy 134.329424 -294.336216) (xy 134.329424 -294.335708)
			(xy 134.330054 -294.308308) (xy 134.339866 -294.254392) (xy 134.359141 -294.203092) (xy 134.38726 -294.156055)
			(xy 134.404862 -294.135048) (xy 134.411466 -294.127428) (xy 134.414514 -294.119554) (xy 134.416109 -294.114896)
			(xy 134.417638 -294.105173) (xy 134.417562 -294.10025) (xy 134.415022 -294.027352) (xy 134.41383 -294.018683)
			(xy 134.406431 -294.002838) (xy 134.400544 -293.996364) (xy 134.247382 -293.843202) (xy 134.243179 -293.839167)
			(xy 134.2333 -293.832997) (xy 134.227824 -293.83101) (xy 134.217156 -293.827454) (xy 134.205218 -293.828978)
			(xy 134.195167 -293.830202) (xy 134.174957 -293.831472) (xy 134.164832 -293.831518) (xy 134.140837 -293.831074)
			(xy 134.093437 -293.823572) (xy 134.047794 -293.808746) (xy 134.005033 -293.786962) (xy 133.966206 -293.758758)
			(xy 133.93227 -293.724826) (xy 133.90406 -293.686003) (xy 133.88227 -293.643244) (xy 133.867438 -293.597604)
			(xy 133.859929 -293.550205) (xy 133.859524 -293.52621) (xy 133.859524 -293.525702) (xy 133.859954 -293.502727)
			(xy 133.866871 -293.4573) (xy 133.880517 -293.413423) (xy 133.900586 -293.372086) (xy 133.926623 -293.334224)
			(xy 133.958041 -293.300693) (xy 133.975856 -293.28618) (xy 133.980428 -293.282624) (xy 133.987286 -293.274242)
			(xy 133.999732 -293.249858) (xy 134.002314 -293.244431) (xy 134.005136 -293.232751) (xy 134.00532 -293.226744)
			(xy 134.00532 -293.0652) (xy 134.00532 -293.064184) (xy 134.004682 -293.053451) (xy 133.995605 -293.033981)
			(xy 133.987794 -293.026592) (xy 133.979412 -293.02075) (xy 133.902196 -292.977316) (xy 133.896303 -292.974262)
			(xy 133.883433 -292.97103) (xy 133.876796 -292.970966) (xy 133.863334 -292.970966) (xy 133.859778 -292.973252)
			(xy 133.85165 -292.978078) (xy 133.827764 -292.991717) (xy 133.77629 -293.011094) (xy 133.722178 -293.02094)
			(xy 133.694678 -293.021512) (xy 133.669424 -293.020989) (xy 133.619604 -293.012672) (xy 133.571833 -292.996269)
			(xy 133.527412 -292.972227) (xy 133.487555 -292.941202) (xy 133.453348 -292.90404) (xy 133.425723 -292.861755)
			(xy 133.405434 -292.8155) (xy 133.393036 -292.766536) (xy 133.388865 -292.7162) (xy 133.393036 -292.665864)
			(xy 133.405434 -292.6169) (xy 133.425723 -292.570645) (xy 133.453348 -292.52836) (xy 133.487555 -292.491198)
			(xy 133.527412 -292.460173) (xy 133.571833 -292.436131) (xy 133.619604 -292.419728) (xy 133.669424 -292.411411)
			(xy 133.694678 -292.410896) (xy 133.722178 -292.411478) (xy 133.77629 -292.421318) (xy 133.827768 -292.440684)
			(xy 133.85165 -292.45433) (xy 133.851904 -292.45433) (xy 133.857734 -292.457642) (xy 133.870606 -292.46138)
			(xy 133.877304 -292.461696) (xy 133.890258 -292.461696) (xy 133.979412 -292.411658) (xy 133.987794 -292.405816)
			(xy 133.995584 -292.398414) (xy 134.004646 -292.37895) (xy 134.00532 -292.368224) (xy 134.00532 -292.205664)
			(xy 134.005154 -292.199654) (xy 134.002335 -292.18797) (xy 133.999732 -292.18255) (xy 133.987286 -292.158166)
			(xy 133.980428 -292.149784) (xy 133.975856 -292.146228) (xy 133.95804 -292.131652) (xy 133.926576 -292.098054)
			(xy 133.900511 -292.060115) (xy 133.880435 -292.018693) (xy 133.866804 -291.974727) (xy 133.859926 -291.929213)
			(xy 133.859524 -291.906198) (xy 133.85992 -291.88318) (xy 133.866788 -291.837661) (xy 133.880412 -291.793689)
			(xy 133.900484 -291.752261) (xy 133.926549 -291.714317) (xy 133.958015 -291.680716) (xy 133.975856 -291.666168)
			(xy 133.980428 -291.662612) (xy 133.987286 -291.65423) (xy 133.999732 -291.629846) (xy 134.002313 -291.624419)
			(xy 134.005132 -291.612739) (xy 134.00532 -291.606732) (xy 134.00532 -291.445188) (xy 134.00532 -291.444172)
			(xy 134.004679 -291.43344) (xy 133.9956 -291.413973) (xy 133.987794 -291.40658) (xy 133.979412 -291.400738)
			(xy 133.902196 -291.357304) (xy 133.896303 -291.35425) (xy 133.883433 -291.351019) (xy 133.876796 -291.350954)
			(xy 133.863334 -291.350954) (xy 133.859778 -291.35324) (xy 133.85165 -291.358066) (xy 133.827764 -291.371706)
			(xy 133.77629 -291.391084) (xy 133.722178 -291.40093) (xy 133.694678 -291.4015) (xy 133.669425 -291.400977)
			(xy 133.619607 -291.39266) (xy 133.571837 -291.376258) (xy 133.527419 -291.352217) (xy 133.487563 -291.321193)
			(xy 133.453357 -291.284033) (xy 133.425733 -291.24175) (xy 133.405446 -291.195496) (xy 133.393048 -291.146535)
			(xy 133.388877 -291.0962) (xy 133.393048 -291.045865) (xy 133.405446 -290.996904) (xy 133.425733 -290.95065)
			(xy 133.453357 -290.908367) (xy 133.487563 -290.871207) (xy 133.527419 -290.840183) (xy 133.571837 -290.816142)
			(xy 133.619607 -290.79974) (xy 133.669425 -290.791423) (xy 133.694678 -290.790884) (xy 133.722178 -290.791466)
			(xy 133.776291 -290.801305) (xy 133.827769 -290.820671) (xy 133.85165 -290.834318) (xy 133.851904 -290.834318)
			(xy 133.857734 -290.837631) (xy 133.870606 -290.84137) (xy 133.877304 -290.841684) (xy 133.890258 -290.841684)
			(xy 133.979412 -290.791646) (xy 133.987794 -290.785804) (xy 133.995598 -290.778408) (xy 134.004693 -290.758944)
			(xy 134.00532 -290.748212) (xy 134.00532 -290.585652) (xy 134.005153 -290.579642) (xy 134.002331 -290.567959)
			(xy 133.999732 -290.562538) (xy 133.987286 -290.538154) (xy 133.980428 -290.529772) (xy 133.975856 -290.526216)
			(xy 133.95804 -290.51164) (xy 133.926578 -290.478042) (xy 133.900514 -290.440102) (xy 133.88044 -290.39868)
			(xy 133.866811 -290.354714) (xy 133.859934 -290.309201) (xy 133.859524 -290.286186) (xy 133.859921 -290.263169)
			(xy 133.86679 -290.217651) (xy 133.880416 -290.17368) (xy 133.900489 -290.132253) (xy 133.926554 -290.09431)
			(xy 133.958021 -290.060711) (xy 133.975856 -290.046156) (xy 133.980428 -290.0426) (xy 133.987286 -290.034218)
			(xy 133.999732 -290.009834) (xy 134.002311 -290.004406) (xy 134.005128 -289.992727) (xy 134.00532 -289.98672)
			(xy 134.00532 -289.825176) (xy 134.00532 -289.82416) (xy 134.004677 -289.813429) (xy 133.995594 -289.793966)
			(xy 133.987794 -289.786568) (xy 133.979412 -289.780726) (xy 133.902196 -289.737292) (xy 133.896303 -289.734238)
			(xy 133.883433 -289.731008) (xy 133.876796 -289.730942) (xy 133.863334 -289.730942) (xy 133.859778 -289.733228)
			(xy 133.85165 -289.738054) (xy 133.827764 -289.751694) (xy 133.77629 -289.771073) (xy 133.722178 -289.780919)
			(xy 133.694678 -289.781488) (xy 133.669426 -289.780965) (xy 133.61961 -289.772649) (xy 133.571842 -289.756247)
			(xy 133.527426 -289.732207) (xy 133.487571 -289.701185) (xy 133.453366 -289.664026) (xy 133.425744 -289.621744)
			(xy 133.405457 -289.575492) (xy 133.393059 -289.526533) (xy 133.388889 -289.4762) (xy 133.393059 -289.425867)
			(xy 133.405457 -289.376908) (xy 133.425744 -289.330656) (xy 133.453366 -289.288374) (xy 133.487571 -289.251215)
			(xy 133.527426 -289.220193) (xy 133.571842 -289.196153) (xy 133.61961 -289.179751) (xy 133.669426 -289.171435)
			(xy 133.694678 -289.170872) (xy 133.722178 -289.171454) (xy 133.776291 -289.181293) (xy 133.827769 -289.200658)
			(xy 133.85165 -289.214306) (xy 133.851904 -289.214306) (xy 133.857734 -289.21762) (xy 133.870606 -289.22136)
			(xy 133.877304 -289.221672) (xy 133.890258 -289.221672) (xy 133.979412 -289.171634) (xy 133.987794 -289.165792)
			(xy 133.995596 -289.158395) (xy 134.004686 -289.138931) (xy 134.00532 -289.1282) (xy 134.00532 -288.96564)
			(xy 134.005152 -288.959631) (xy 134.002327 -288.947949) (xy 133.999732 -288.942526) (xy 133.987286 -288.918142)
			(xy 133.980428 -288.90976) (xy 133.975856 -288.906204) (xy 133.958041 -288.891628) (xy 133.92658 -288.858029)
			(xy 133.900518 -288.820089) (xy 133.880445 -288.778667) (xy 133.866817 -288.734702) (xy 133.859943 -288.689189)
			(xy 133.859524 -288.666174) (xy 133.859922 -288.643157) (xy 133.866793 -288.59764) (xy 133.880419 -288.55367)
			(xy 133.900493 -288.512245) (xy 133.926559 -288.474303) (xy 133.958027 -288.440705) (xy 133.975856 -288.426144)
			(xy 133.980428 -288.422588) (xy 133.987286 -288.414206) (xy 133.999732 -288.389822) (xy 134.00231 -288.384394)
			(xy 134.005124 -288.372714) (xy 134.00532 -288.366708) (xy 134.00532 -288.205418) (xy 134.00532 -288.204402)
			(xy 134.004685 -288.193667) (xy 133.995613 -288.174192) (xy 133.987794 -288.16681) (xy 133.979412 -288.160968)
			(xy 133.902196 -288.117534) (xy 133.896295 -288.114502) (xy 133.88343 -288.111276) (xy 133.876796 -288.111184)
			(xy 133.863334 -288.111184) (xy 133.859778 -288.11347) (xy 133.85165 -288.118296) (xy 133.827763 -288.131935)
			(xy 133.776289 -288.151311) (xy 133.722178 -288.161156) (xy 133.694678 -288.16173) (xy 133.669422 -288.161207)
			(xy 133.6196 -288.152889) (xy 133.571825 -288.136485) (xy 133.527403 -288.112442) (xy 133.487543 -288.081416)
			(xy 133.453333 -288.044251) (xy 133.425707 -288.001964) (xy 133.405417 -287.955706) (xy 133.393018 -287.906739)
			(xy 133.388847 -287.8564) (xy 133.393018 -287.806061) (xy 133.405417 -287.757094) (xy 133.425707 -287.710836)
			(xy 133.453333 -287.668549) (xy 133.487543 -287.631384) (xy 133.527403 -287.600358) (xy 133.571825 -287.576315)
			(xy 133.6196 -287.559911) (xy 133.669422 -287.551593) (xy 133.694678 -287.551114) (xy 133.722178 -287.551696)
			(xy 133.77629 -287.561536) (xy 133.827767 -287.580903) (xy 133.85165 -287.594548) (xy 133.851904 -287.594548)
			(xy 133.857733 -287.597865) (xy 133.870605 -287.601609) (xy 133.877304 -287.601914) (xy 133.890258 -287.601914)
			(xy 133.979412 -287.551876) (xy 133.987794 -287.546034) (xy 133.995587 -287.538633) (xy 134.004655 -287.519169)
			(xy 134.00532 -287.508442) (xy 134.00532 -287.345628) (xy 134.00515 -287.339619) (xy 134.002323 -287.327939)
			(xy 133.999732 -287.322514) (xy 133.98754 -287.298384) (xy 133.980682 -287.290002) (xy 133.97611 -287.286446)
			(xy 133.958265 -287.271887) (xy 133.926744 -287.23831) (xy 133.900625 -287.200379) (xy 133.880502 -287.158954)
			(xy 133.866832 -287.114976) (xy 133.859924 -287.069443) (xy 133.859524 -287.046416) (xy 133.859524 -287.046162)
			(xy 133.859955 -287.022925) (xy 133.866992 -286.976988) (xy 133.880912 -286.932649) (xy 133.901395 -286.890932)
			(xy 133.927965 -286.852804) (xy 133.96001 -286.819145) (xy 133.978142 -286.804608) (xy 133.984746 -286.799274)
			(xy 133.999732 -286.76981) (xy 134.002309 -286.764382) (xy 134.00512 -286.752702) (xy 134.00532 -286.746696)
			(xy 134.00532 -286.585406) (xy 134.00532 -286.58439) (xy 134.004683 -286.573656) (xy 133.995608 -286.554184)
			(xy 133.987794 -286.546798) (xy 133.979412 -286.540956) (xy 133.902196 -286.497522) (xy 133.896294 -286.49449)
			(xy 133.88343 -286.491266) (xy 133.876796 -286.491172) (xy 133.863334 -286.491172) (xy 133.859778 -286.493458)
			(xy 133.85165 -286.498284) (xy 133.827763 -286.511923) (xy 133.77629 -286.5313) (xy 133.722178 -286.541145)
			(xy 133.694678 -286.541718) (xy 133.669423 -286.541195) (xy 133.619602 -286.532878) (xy 133.57183 -286.516475)
			(xy 133.527409 -286.492432) (xy 133.487551 -286.461407) (xy 133.453343 -286.424244) (xy 133.425718 -286.381958)
			(xy 133.405429 -286.335702) (xy 133.39303 -286.286737) (xy 133.388859 -286.2364) (xy 133.39303 -286.186063)
			(xy 133.405429 -286.137098) (xy 133.425718 -286.090842) (xy 133.453343 -286.048556) (xy 133.487551 -286.011393)
			(xy 133.527409 -285.980368) (xy 133.57183 -285.956325) (xy 133.619602 -285.939922) (xy 133.669423 -285.931605)
			(xy 133.694678 -285.931102) (xy 133.722178 -285.931684) (xy 133.77629 -285.941524) (xy 133.827768 -285.96089)
			(xy 133.85165 -285.974536) (xy 133.851904 -285.974536) (xy 133.857733 -285.977853) (xy 133.870605 -285.981598)
			(xy 133.877304 -285.981902) (xy 133.890258 -285.981902) (xy 133.979412 -285.931864) (xy 133.987794 -285.926022)
			(xy 133.995585 -285.918621) (xy 134.004649 -285.899156) (xy 134.00532 -285.88843) (xy 134.00532 -285.72587)
			(xy 134.005155 -285.71986) (xy 134.002337 -285.708175) (xy 133.999732 -285.702756) (xy 133.987286 -285.678372)
			(xy 133.980428 -285.66999) (xy 133.975856 -285.666434) (xy 133.958039 -285.651858) (xy 133.926575 -285.618261)
			(xy 133.900509 -285.580321) (xy 133.880433 -285.538899) (xy 133.866801 -285.494933) (xy 133.859921 -285.44942)
			(xy 133.859524 -285.426404) (xy 133.85992 -285.403386) (xy 133.866786 -285.357867) (xy 133.88041 -285.313894)
			(xy 133.900482 -285.272465) (xy 133.926546 -285.23452) (xy 133.958012 -285.200919) (xy 133.975856 -285.186374)
			(xy 133.980428 -285.182818) (xy 133.987286 -285.174436) (xy 133.999732 -285.150052) (xy 134.002313 -285.144625)
			(xy 134.005134 -285.132945) (xy 134.00532 -285.126938) (xy 134.00532 -284.965394) (xy 134.00532 -284.964378)
			(xy 134.00468 -284.953646) (xy 133.995602 -284.934177) (xy 133.987794 -284.926786) (xy 133.979412 -284.920944)
			(xy 133.902196 -284.87751) (xy 133.896303 -284.874456) (xy 133.883433 -284.871224) (xy 133.876796 -284.87116)
			(xy 133.863334 -284.87116) (xy 133.859778 -284.873446) (xy 133.85165 -284.878272) (xy 133.827764 -284.891912)
			(xy 133.77629 -284.911289) (xy 133.722178 -284.921135) (xy 133.694678 -284.921706) (xy 133.669424 -284.921183)
			(xy 133.619605 -284.912866) (xy 133.571835 -284.896464) (xy 133.527416 -284.872422) (xy 133.487559 -284.841398)
			(xy 133.453352 -284.804237) (xy 133.425728 -284.761952) (xy 133.40544 -284.715698) (xy 133.393042 -284.666736)
			(xy 133.388871 -284.6164) (xy 133.393042 -284.566064) (xy 133.40544 -284.517102) (xy 133.425728 -284.470848)
			(xy 133.453352 -284.428563) (xy 133.487559 -284.391402) (xy 133.527416 -284.360378) (xy 133.571835 -284.336336)
			(xy 133.619605 -284.319934) (xy 133.669424 -284.311617) (xy 133.694678 -284.31109) (xy 133.722178 -284.311672)
			(xy 133.776291 -284.321512) (xy 133.827768 -284.340877) (xy 133.85165 -284.354524) (xy 133.851904 -284.354524)
			(xy 133.857734 -284.357837) (xy 133.870606 -284.361575) (xy 133.877304 -284.36189) (xy 133.890258 -284.36189)
			(xy 133.979412 -284.311852) (xy 133.987794 -284.30601) (xy 133.995599 -284.298614) (xy 134.004696 -284.279151)
			(xy 134.00532 -284.268418) (xy 134.00532 -284.105858) (xy 134.005154 -284.099848) (xy 134.002333 -284.088164)
			(xy 133.999732 -284.082744) (xy 133.987286 -284.05836) (xy 133.980428 -284.049978) (xy 133.975856 -284.046422)
			(xy 133.95804 -284.031846) (xy 133.926577 -283.998248) (xy 133.900513 -283.960308) (xy 133.880438 -283.918886)
			(xy 133.866807 -283.874921) (xy 133.85993 -283.829407) (xy 133.859524 -283.806392) (xy 133.859921 -283.783375)
			(xy 133.866789 -283.737856) (xy 133.880414 -283.693884) (xy 133.900486 -283.652457) (xy 133.926551 -283.614513)
			(xy 133.958018 -283.580913) (xy 133.975856 -283.566362) (xy 133.980428 -283.562806) (xy 133.987286 -283.554424)
			(xy 133.999732 -283.53004) (xy 134.002312 -283.524612) (xy 134.00513 -283.512933) (xy 134.00532 -283.506926)
			(xy 134.00532 -283.345382) (xy 134.00532 -283.344366) (xy 134.004678 -283.333635) (xy 133.995597 -283.31417)
			(xy 133.987794 -283.306774) (xy 133.979412 -283.300932) (xy 133.902196 -283.257498) (xy 133.896303 -283.254444)
			(xy 133.883433 -283.251213) (xy 133.876796 -283.251148) (xy 133.863334 -283.251148) (xy 133.859778 -283.253434)
			(xy 133.85165 -283.25826) (xy 133.827764 -283.2719) (xy 133.77629 -283.291278) (xy 133.722178 -283.301125)
			(xy 133.694678 -283.301694) (xy 133.669425 -283.301171) (xy 133.619608 -283.292855) (xy 133.57184 -283.276453)
			(xy 133.527422 -283.252412) (xy 133.487567 -283.221389) (xy 133.453362 -283.184229) (xy 133.425739 -283.141947)
			(xy 133.405452 -283.095694) (xy 133.393054 -283.046734) (xy 133.388883 -282.9964) (xy 133.393054 -282.946066)
			(xy 133.405452 -282.897106) (xy 133.425739 -282.850853) (xy 133.453362 -282.808571) (xy 133.487567 -282.771411)
			(xy 133.527422 -282.740388) (xy 133.57184 -282.716347) (xy 133.619608 -282.699945) (xy 133.669425 -282.691629)
			(xy 133.694678 -282.691078) (xy 133.722178 -282.69166) (xy 133.776291 -282.701499) (xy 133.827769 -282.720864)
			(xy 133.85165 -282.734512) (xy 133.851904 -282.734512) (xy 133.857734 -282.737825) (xy 133.870606 -282.741565)
			(xy 133.877304 -282.741878) (xy 133.890258 -282.741878) (xy 133.979412 -282.69184) (xy 133.987794 -282.685998)
			(xy 133.995597 -282.678601) (xy 134.00469 -282.659138) (xy 134.00532 -282.648406) (xy 134.00532 -282.485846)
			(xy 134.005152 -282.479836) (xy 134.002329 -282.468154) (xy 133.999732 -282.462732) (xy 133.987286 -282.438348)
			(xy 133.980428 -282.429966) (xy 133.975856 -282.42641) (xy 133.958041 -282.411834) (xy 133.926579 -282.378235)
			(xy 133.900516 -282.340295) (xy 133.880443 -282.298874) (xy 133.866814 -282.254908) (xy 133.859938 -282.209395)
			(xy 133.859524 -282.18638) (xy 133.859922 -282.163363) (xy 133.866791 -282.117845) (xy 133.880417 -282.073875)
			(xy 133.900491 -282.032449) (xy 133.926557 -281.994507) (xy 133.958024 -281.960908) (xy 133.975856 -281.94635)
			(xy 133.980428 -281.942794) (xy 133.987286 -281.934412) (xy 133.999732 -281.910028) (xy 134.002311 -281.9046)
			(xy 134.005126 -281.892921) (xy 134.00532 -281.886914) (xy 134.00532 -281.72537) (xy 134.00532 -281.724354)
			(xy 134.004676 -281.713624) (xy 133.995592 -281.694162) (xy 133.987794 -281.686762) (xy 133.979412 -281.68092)
			(xy 133.902196 -281.637486) (xy 133.896295 -281.634451) (xy 133.88343 -281.631222) (xy 133.876796 -281.631136)
			(xy 133.863334 -281.631136) (xy 133.859778 -281.633422) (xy 133.85165 -281.638248) (xy 133.827764 -281.651888)
			(xy 133.77629 -281.671267) (xy 133.722178 -281.681114) (xy 133.694678 -281.681682) (xy 133.669426 -281.681159)
			(xy 133.619611 -281.672843) (xy 133.571845 -281.656442) (xy 133.527429 -281.632402) (xy 133.487575 -281.60138)
			(xy 133.453371 -281.564222) (xy 133.425749 -281.521941) (xy 133.405463 -281.47569) (xy 133.393065 -281.426732)
			(xy 133.388895 -281.3764) (xy 133.393065 -281.326068) (xy 133.405463 -281.27711) (xy 133.425749 -281.230859)
			(xy 133.453371 -281.188578) (xy 133.487575 -281.15142) (xy 133.527429 -281.120398) (xy 133.571845 -281.096358)
			(xy 133.619611 -281.079957) (xy 133.669426 -281.071641) (xy 133.694678 -281.071066) (xy 133.722178 -281.071647)
			(xy 133.776291 -281.081486) (xy 133.82777 -281.100851) (xy 133.85165 -281.1145) (xy 133.851904 -281.1145)
			(xy 133.857734 -281.117814) (xy 133.870606 -281.121554) (xy 133.877304 -281.121866) (xy 133.890258 -281.121866)
			(xy 133.979412 -281.071828) (xy 133.987794 -281.065986) (xy 133.995595 -281.058588) (xy 134.004683 -281.039125)
			(xy 134.00532 -281.028394) (xy 134.00532 -280.865834) (xy 134.005151 -280.859825) (xy 134.002325 -280.848144)
			(xy 133.999732 -280.84272) (xy 133.987286 -280.818336) (xy 133.980428 -280.809954) (xy 133.975856 -280.806398)
			(xy 133.958041 -280.791822) (xy 133.926581 -280.758223) (xy 133.900519 -280.720283) (xy 133.880448 -280.678861)
			(xy 133.866821 -280.634895) (xy 133.859947 -280.589383) (xy 133.859524 -280.566368) (xy 133.859922 -280.543351)
			(xy 133.866794 -280.497835) (xy 133.880421 -280.453866) (xy 133.900496 -280.412441) (xy 133.926562 -280.3745)
			(xy 133.95803 -280.340903) (xy 133.975856 -280.326338) (xy 133.980428 -280.322782) (xy 133.987286 -280.3144)
			(xy 133.999732 -280.290016) (xy 134.002309 -280.284588) (xy 134.005122 -280.272908) (xy 134.00532 -280.266902)
			(xy 134.00532 -280.105358) (xy 134.00532 -280.104342) (xy 134.004673 -280.093613) (xy 133.995587 -280.074155)
			(xy 133.987794 -280.06675) (xy 133.979412 -280.060908) (xy 133.902196 -280.017474) (xy 133.896295 -280.014439)
			(xy 133.88343 -280.011212) (xy 133.876796 -280.011124) (xy 133.863334 -280.011124) (xy 133.859778 -280.01341)
			(xy 133.85165 -280.018236) (xy 133.827764 -280.031877) (xy 133.776291 -280.051256) (xy 133.722178 -280.061103)
			(xy 133.694678 -280.06167) (xy 133.669427 -280.061147) (xy 133.619614 -280.052831) (xy 133.571849 -280.036431)
			(xy 133.527435 -280.012392) (xy 133.487584 -279.981371) (xy 133.453381 -279.944215) (xy 133.42576 -279.901935)
			(xy 133.405474 -279.855686) (xy 133.393077 -279.80673) (xy 133.388907 -279.7564) (xy 133.393077 -279.70607)
			(xy 133.405474 -279.657114) (xy 133.42576 -279.610865) (xy 133.453381 -279.568585) (xy 133.487584 -279.531429)
			(xy 133.527435 -279.500408) (xy 133.571849 -279.476369) (xy 133.619614 -279.459969) (xy 133.669427 -279.451653)
			(xy 133.694678 -279.451054) (xy 133.722178 -279.451635) (xy 133.776291 -279.461474) (xy 133.82777 -279.480838)
			(xy 133.85165 -279.494488) (xy 133.851904 -279.494488) (xy 133.857733 -279.497803) (xy 133.870606 -279.501544)
			(xy 133.877304 -279.501854) (xy 133.890258 -279.501854) (xy 133.979412 -279.451816) (xy 133.987794 -279.445974)
			(xy 133.995593 -279.438576) (xy 134.004677 -279.419112) (xy 134.00532 -279.408382) (xy 134.00532 -279.245822)
			(xy 134.00515 -279.239813) (xy 134.002321 -279.228133) (xy 133.999732 -279.222708) (xy 133.987286 -279.198324)
			(xy 133.980428 -279.189942) (xy 133.975856 -279.186386) (xy 133.958042 -279.17181) (xy 133.926583 -279.13821)
			(xy 133.900523 -279.10027) (xy 133.880453 -279.058848) (xy 133.866828 -279.014883) (xy 133.859955 -278.96937)
			(xy 133.859524 -278.946356) (xy 133.859923 -278.92334) (xy 133.866796 -278.877824) (xy 133.880425 -278.833856)
			(xy 133.9005 -278.792433) (xy 133.926567 -278.754493) (xy 133.958035 -278.720897) (xy 133.975856 -278.706326)
			(xy 133.980428 -278.70277) (xy 133.987286 -278.694388) (xy 133.999732 -278.670004) (xy 134.002308 -278.664576)
			(xy 134.005118 -278.652896) (xy 134.00532 -278.64689) (xy 134.00532 -278.485346) (xy 134.00532 -278.48433)
			(xy 134.004671 -278.473602) (xy 133.995581 -278.454148) (xy 133.987794 -278.446738) (xy 133.979412 -278.440896)
			(xy 133.902196 -278.397462) (xy 133.896295 -278.394428) (xy 133.88343 -278.391201) (xy 133.876796 -278.391112)
			(xy 133.863334 -278.391112) (xy 133.859778 -278.393398) (xy 133.85165 -278.398224) (xy 133.827764 -278.411865)
			(xy 133.776291 -278.431246) (xy 133.722179 -278.441093) (xy 133.694678 -278.441658) (xy 133.66942 -278.441135)
			(xy 133.619593 -278.432817) (xy 133.571814 -278.416412) (xy 133.527387 -278.392366) (xy 133.487524 -278.361336)
			(xy 133.453311 -278.324169) (xy 133.425682 -278.281877) (xy 133.40539 -278.235615) (xy 133.39299 -278.186644)
			(xy 133.388818 -278.1363) (xy 133.39299 -278.085956) (xy 133.40539 -278.036985) (xy 133.425682 -277.990723)
			(xy 133.453311 -277.948431) (xy 133.487524 -277.911264) (xy 133.527387 -277.880234) (xy 133.571814 -277.856188)
			(xy 133.619593 -277.839783) (xy 133.66942 -277.831465) (xy 133.694678 -277.831042) (xy 133.722178 -277.831623)
			(xy 133.776292 -277.841462) (xy 133.827771 -277.860824) (xy 133.85165 -277.874476) (xy 133.851904 -277.874476)
			(xy 133.857733 -277.877791) (xy 133.870606 -277.881533) (xy 133.877304 -277.881842) (xy 133.890258 -277.881842)
			(xy 133.979412 -277.831804) (xy 133.987794 -277.825962) (xy 133.995591 -277.818563) (xy 134.00467 -277.799099)
			(xy 134.00532 -277.78837) (xy 134.00532 -277.62581) (xy 134.005148 -277.619802) (xy 134.002317 -277.608123)
			(xy 133.999732 -277.602696) (xy 133.987286 -277.578312) (xy 133.980428 -277.56993) (xy 133.975856 -277.566374)
			(xy 133.958042 -277.551797) (xy 133.926585 -277.518198) (xy 133.900526 -277.480257) (xy 133.880458 -277.438835)
			(xy 133.866834 -277.39487) (xy 133.859964 -277.349358) (xy 133.859524 -277.326344) (xy 133.859924 -277.303328)
			(xy 133.866799 -277.257814) (xy 133.880429 -277.213847) (xy 133.900505 -277.172425) (xy 133.926573 -277.134487)
			(xy 133.958041 -277.100892) (xy 133.975856 -277.086314) (xy 133.980428 -277.082758) (xy 133.987286 -277.074376)
			(xy 133.999732 -277.049992) (xy 134.002317 -277.044566) (xy 134.005147 -277.032886) (xy 134.00532 -277.026878)
			(xy 134.00532 -276.865334) (xy 134.00532 -276.864318) (xy 134.004688 -276.853582) (xy 133.99562 -276.834101)
			(xy 133.987794 -276.826726) (xy 133.979412 -276.820884) (xy 133.902196 -276.77745) (xy 133.896295 -276.774417)
			(xy 133.88343 -276.771191) (xy 133.876796 -276.7711) (xy 133.863334 -276.7711) (xy 133.859778 -276.773386)
			(xy 133.85165 -276.778212) (xy 133.827764 -276.791854) (xy 133.776291 -276.811235) (xy 133.722179 -276.821083)
			(xy 133.694678 -276.821646) (xy 133.669421 -276.821123) (xy 133.619596 -276.812805) (xy 133.571819 -276.7964)
			(xy 133.527394 -276.772356) (xy 133.487532 -276.741327) (xy 133.453321 -276.704161) (xy 133.425693 -276.661871)
			(xy 133.405402 -276.615611) (xy 133.393002 -276.566642) (xy 133.388831 -276.5163) (xy 133.393002 -276.465958)
			(xy 133.405402 -276.416989) (xy 133.425693 -276.370729) (xy 133.453321 -276.328439) (xy 133.487532 -276.291273)
			(xy 133.527394 -276.260244) (xy 133.571819 -276.2362) (xy 133.619596 -276.219795) (xy 133.669421 -276.211477)
			(xy 133.694678 -276.21103) (xy 133.722178 -276.211611) (xy 133.776292 -276.221449) (xy 133.827772 -276.240811)
			(xy 133.85165 -276.254464) (xy 133.851904 -276.254464) (xy 133.857733 -276.25778) (xy 133.870606 -276.261523)
			(xy 133.877304 -276.26183) (xy 133.890258 -276.26183) (xy 133.979412 -276.211792) (xy 133.987794 -276.20595)
			(xy 133.99559 -276.19855) (xy 134.004664 -276.179086) (xy 134.00532 -276.168358) (xy 134.00532 -276.005798)
			(xy 134.005147 -275.99979) (xy 134.002313 -275.988113) (xy 133.999732 -275.982684) (xy 133.987286 -275.9583)
			(xy 133.980428 -275.949918) (xy 133.975856 -275.946362) (xy 133.958038 -275.931787) (xy 133.92657 -275.89819)
			(xy 133.900501 -275.860251) (xy 133.880421 -275.818829) (xy 133.866785 -275.774863) (xy 133.859901 -275.729348)
			(xy 133.859524 -275.706332) (xy 133.859925 -275.683317) (xy 133.866801 -275.637803) (xy 133.880432 -275.593837)
			(xy 133.90051 -275.552417) (xy 133.926578 -275.51448) (xy 133.958047 -275.480887) (xy 133.975856 -275.466302)
			(xy 133.980428 -275.462746) (xy 133.987286 -275.454364) (xy 133.999732 -275.42998) (xy 134.002316 -275.424553)
			(xy 134.005143 -275.412874) (xy 134.00532 -275.406866) (xy 134.00532 -275.245322) (xy 134.00532 -275.244306)
			(xy 134.004686 -275.233571) (xy 133.995615 -275.214094) (xy 133.987794 -275.206714) (xy 133.979412 -275.200872)
			(xy 133.902196 -275.157438) (xy 133.896295 -275.154405) (xy 133.88343 -275.15118) (xy 133.876796 -275.151088)
			(xy 133.863334 -275.151088) (xy 133.859778 -275.153374) (xy 133.85165 -275.1582) (xy 133.827763 -275.171839)
			(xy 133.776289 -275.191214) (xy 133.722178 -275.201059) (xy 133.694678 -275.201634) (xy 133.669422 -275.201111)
			(xy 133.619599 -275.192793) (xy 133.571824 -275.176389) (xy 133.5274 -275.152346) (xy 133.48754 -275.121318)
			(xy 133.45333 -275.084154) (xy 133.425703 -275.041866) (xy 133.405414 -274.995607) (xy 133.393014 -274.94664)
			(xy 133.388843 -274.8963) (xy 133.393014 -274.84596) (xy 133.405414 -274.796993) (xy 133.425703 -274.750734)
			(xy 133.45333 -274.708446) (xy 133.48754 -274.671282) (xy 133.5274 -274.640254) (xy 133.571824 -274.616211)
			(xy 133.619599 -274.599807) (xy 133.669422 -274.591489) (xy 133.694678 -274.591018) (xy 133.722178 -274.591599)
			(xy 133.776292 -274.601437) (xy 133.827772 -274.620798) (xy 133.85165 -274.634452) (xy 133.851904 -274.634452)
			(xy 133.857733 -274.637768) (xy 133.870605 -274.641512) (xy 133.877304 -274.641818) (xy 133.890258 -274.641818)
			(xy 133.979412 -274.59178) (xy 133.987794 -274.585938) (xy 133.995587 -274.578537) (xy 134.004657 -274.559073)
			(xy 134.00532 -274.548346) (xy 134.00532 -274.385786) (xy 134.005157 -274.379775) (xy 134.002342 -274.368089)
			(xy 133.999732 -274.362672) (xy 133.987286 -274.338288) (xy 133.980428 -274.329906) (xy 133.975856 -274.32635)
			(xy 133.958038 -274.311775) (xy 133.926572 -274.278177) (xy 133.900504 -274.240238) (xy 133.880426 -274.198816)
			(xy 133.866792 -274.15485) (xy 133.85991 -274.109336) (xy 133.859524 -274.08632) (xy 133.859919 -274.063302)
			(xy 133.866783 -274.017781) (xy 133.880405 -273.973806) (xy 133.900475 -273.932376) (xy 133.926539 -273.894429)
			(xy 133.958005 -273.860826) (xy 133.975856 -273.84629) (xy 133.980428 -273.842734) (xy 133.987286 -273.834352)
			(xy 133.999732 -273.809968) (xy 134.002315 -273.804541) (xy 134.005139 -273.792862) (xy 134.00532 -273.786854)
			(xy 134.00532 -273.62531) (xy 134.00532 -273.624294) (xy 134.004683 -273.61356) (xy 133.995609 -273.594087)
			(xy 133.987794 -273.586702) (xy 133.979412 -273.58086) (xy 133.902196 -273.537426) (xy 133.896294 -273.534394)
			(xy 133.88343 -273.531169) (xy 133.876796 -273.531076) (xy 133.863334 -273.531076) (xy 133.859778 -273.533362)
			(xy 133.85165 -273.538188) (xy 133.827763 -273.551827) (xy 133.77629 -273.571203) (xy 133.722178 -273.581049)
			(xy 133.694678 -273.581622) (xy 133.669423 -273.581099) (xy 133.619602 -273.572782) (xy 133.571829 -273.556378)
			(xy 133.527407 -273.532336) (xy 133.487548 -273.50131) (xy 133.45334 -273.464147) (xy 133.425714 -273.42186)
			(xy 133.405425 -273.375603) (xy 133.393026 -273.326638) (xy 133.388855 -273.2763) (xy 133.393026 -273.225962)
			(xy 133.405425 -273.176997) (xy 133.425714 -273.13074) (xy 133.45334 -273.088453) (xy 133.487548 -273.05129)
			(xy 133.527407 -273.020264) (xy 133.571829 -272.996222) (xy 133.619601 -272.979818) (xy 133.669423 -272.971501)
			(xy 133.694678 -272.971006) (xy 133.722178 -272.971588) (xy 133.77629 -272.981428) (xy 133.827768 -273.000795)
			(xy 133.85165 -273.01444) (xy 133.851904 -273.01444) (xy 133.857733 -273.017757) (xy 133.870605 -273.021502)
			(xy 133.877304 -273.021806) (xy 133.890258 -273.021806) (xy 133.979412 -272.971768) (xy 133.987794 -272.965926)
			(xy 133.995586 -272.958525) (xy 134.004651 -272.93906) (xy 134.00532 -272.928334) (xy 134.00532 -272.765774)
			(xy 134.005156 -272.759764) (xy 134.002338 -272.748078) (xy 133.999732 -272.74266) (xy 133.987286 -272.718276)
			(xy 133.980428 -272.709894) (xy 133.975856 -272.706338) (xy 133.958039 -272.691763) (xy 133.926574 -272.658165)
			(xy 133.900508 -272.620225) (xy 133.880431 -272.578804) (xy 133.866798 -272.534838) (xy 133.859918 -272.489324)
			(xy 133.859524 -272.466308) (xy 133.859919 -272.44329) (xy 133.866786 -272.39777) (xy 133.880409 -272.353797)
			(xy 133.90048 -272.312368) (xy 133.926544 -272.274422) (xy 133.95801 -272.24082) (xy 133.975856 -272.226278)
			(xy 133.980428 -272.222722) (xy 133.987286 -272.21434) (xy 133.999732 -272.189956) (xy 134.002314 -272.184529)
			(xy 134.005135 -272.172849) (xy 134.00532 -272.166842) (xy 134.00532 -272.005298) (xy 134.00532 -272.004282)
			(xy 134.004681 -271.993549) (xy 133.995604 -271.974079) (xy 133.987794 -271.96669) (xy 133.979412 -271.960848)
			(xy 133.902196 -271.917414) (xy 133.896303 -271.91436) (xy 133.883433 -271.911128) (xy 133.876796 -271.911064)
			(xy 133.863334 -271.911064) (xy 133.859778 -271.91335) (xy 133.85165 -271.918176) (xy 133.827764 -271.931816)
			(xy 133.77629 -271.951193) (xy 133.722178 -271.961038) (xy 133.694678 -271.96161) (xy 133.669424 -271.961087)
			(xy 133.619604 -271.95277) (xy 133.571833 -271.936367) (xy 133.527414 -271.912326) (xy 133.487556 -271.881301)
			(xy 133.453349 -271.844139) (xy 133.425725 -271.801854) (xy 133.405436 -271.755599) (xy 133.393038 -271.706636)
			(xy 133.388867 -271.6563) (xy 133.393038 -271.605964) (xy 133.405436 -271.557001) (xy 133.425725 -271.510746)
			(xy 133.453349 -271.468461) (xy 133.487556 -271.431299) (xy 133.527414 -271.400274) (xy 133.571833 -271.376233)
			(xy 133.619604 -271.35983) (xy 133.669424 -271.351513) (xy 133.694678 -271.350994) (xy 133.722178 -271.351576)
			(xy 133.77629 -271.361416) (xy 133.827768 -271.380781) (xy 133.85165 -271.394428) (xy 133.851904 -271.394428)
			(xy 133.857734 -271.39774) (xy 133.870606 -271.401479) (xy 133.877304 -271.401794) (xy 133.890258 -271.401794)
			(xy 133.979412 -271.351756) (xy 133.987794 -271.345914) (xy 133.995584 -271.338512) (xy 134.004644 -271.319048)
			(xy 134.00532 -271.308322) (xy 134.00532 -271.145762) (xy 134.005154 -271.139752) (xy 134.002334 -271.128068)
			(xy 133.999732 -271.122648) (xy 133.987286 -271.098264) (xy 133.980428 -271.089882) (xy 133.975856 -271.086326)
			(xy 133.95804 -271.07175) (xy 133.926576 -271.038152) (xy 133.900511 -271.000213) (xy 133.880436 -270.958791)
			(xy 133.866805 -270.914825) (xy 133.859927 -270.869311) (xy 133.859524 -270.846296) (xy 133.85992 -270.823279)
			(xy 133.866788 -270.777759) (xy 133.880413 -270.733788) (xy 133.900485 -270.69236) (xy 133.92655 -270.654416)
			(xy 133.958016 -270.620815) (xy 133.975856 -270.606266) (xy 133.980428 -270.60271) (xy 133.987286 -270.594328)
			(xy 133.999732 -270.569944) (xy 134.002312 -270.564516) (xy 134.005131 -270.552837) (xy 134.00532 -270.54683)
			(xy 134.00532 -270.385286) (xy 134.00532 -270.38427) (xy 134.004679 -270.373538) (xy 133.995599 -270.354072)
			(xy 133.987794 -270.346678) (xy 133.979412 -270.340836) (xy 133.902196 -270.297402) (xy 133.896303 -270.294348)
			(xy 133.883433 -270.291117) (xy 133.876796 -270.291052) (xy 133.863334 -270.291052) (xy 133.859778 -270.293338)
			(xy 133.85165 -270.298164) (xy 133.827764 -270.311804) (xy 133.77629 -270.331182) (xy 133.722178 -270.341028)
			(xy 133.694678 -270.341598) (xy 133.669425 -270.341075) (xy 133.619607 -270.332758) (xy 133.571838 -270.316356)
			(xy 133.52742 -270.292315) (xy 133.487565 -270.261292) (xy 133.453359 -270.224132) (xy 133.425735 -270.181849)
			(xy 133.405448 -270.135596) (xy 133.39305 -270.086634) (xy 133.388879 -270.0363) (xy 133.39305 -269.985966)
			(xy 133.405448 -269.937004) (xy 133.425735 -269.890751) (xy 133.453359 -269.848468) (xy 133.487565 -269.811308)
			(xy 133.52742 -269.780285) (xy 133.571838 -269.756244) (xy 133.619607 -269.739842) (xy 133.669425 -269.731525)
			(xy 133.694678 -269.730982) (xy 133.722178 -269.731564) (xy 133.776291 -269.741403) (xy 133.827769 -269.760768)
			(xy 133.85165 -269.774416) (xy 133.851904 -269.774416) (xy 133.857734 -269.777729) (xy 133.870606 -269.781468)
			(xy 133.877304 -269.781782) (xy 133.890258 -269.781782) (xy 133.979412 -269.731744) (xy 133.987794 -269.725902)
			(xy 133.995598 -269.718506) (xy 134.004692 -269.699042) (xy 134.00532 -269.68831) (xy 134.00532 -269.52575)
			(xy 134.005153 -269.51974) (xy 134.00233 -269.508058) (xy 133.999732 -269.502636) (xy 133.987286 -269.478252)
			(xy 133.980428 -269.46987) (xy 133.975856 -269.466314) (xy 133.95804 -269.451738) (xy 133.926578 -269.41814)
			(xy 133.900515 -269.3802) (xy 133.880441 -269.338778) (xy 133.866812 -269.294812) (xy 133.859936 -269.249299)
			(xy 133.859524 -269.226284) (xy 133.859921 -269.203267) (xy 133.866791 -269.157749) (xy 133.880416 -269.113778)
			(xy 133.900489 -269.072352) (xy 133.926555 -269.034409) (xy 133.958022 -269.00081) (xy 133.975856 -268.986254)
			(xy 133.980428 -268.982698) (xy 133.987286 -268.974316) (xy 133.999732 -268.949932) (xy 134.002311 -268.944504)
			(xy 134.005127 -268.932825) (xy 134.00532 -268.926818) (xy 134.00532 -268.765274) (xy 134.00532 -268.764258)
			(xy 134.004677 -268.753527) (xy 133.995594 -268.734065) (xy 133.987794 -268.726666) (xy 133.979412 -268.720824)
			(xy 133.902196 -268.67739) (xy 133.896303 -268.674336) (xy 133.883432 -268.671106) (xy 133.876796 -268.67104)
			(xy 133.863334 -268.67104) (xy 133.859778 -268.673326) (xy 133.85165 -268.678152) (xy 133.827764 -268.691793)
			(xy 133.77629 -268.711171) (xy 133.722178 -268.721018) (xy 133.694678 -268.721586) (xy 133.669426 -268.721063)
			(xy 133.61961 -268.712747) (xy 133.571843 -268.696345) (xy 133.527427 -268.672305) (xy 133.487573 -268.641283)
			(xy 133.453368 -268.604124) (xy 133.425746 -268.561843) (xy 133.405459 -268.515592) (xy 133.393061 -268.466632)
			(xy 133.388891 -268.4163) (xy 133.393061 -268.365968) (xy 133.405459 -268.317008) (xy 133.425746 -268.270757)
			(xy 133.453368 -268.228476) (xy 133.487573 -268.191317) (xy 133.527427 -268.160295) (xy 133.571843 -268.136255)
			(xy 133.61961 -268.119853) (xy 133.669426 -268.111537) (xy 133.694678 -268.11097) (xy 133.722178 -268.111552)
			(xy 133.776291 -268.121391) (xy 133.827769 -268.140755) (xy 133.85165 -268.154404) (xy 133.851904 -268.154404)
			(xy 133.857734 -268.157718) (xy 133.870606 -268.161458) (xy 133.877304 -268.16177) (xy 133.890258 -268.16177)
			(xy 133.979412 -268.111732) (xy 133.987794 -268.10589) (xy 133.995596 -268.098493) (xy 134.004685 -268.079029)
			(xy 134.00532 -268.068298) (xy 134.00532 -267.905738) (xy 134.005151 -267.899729) (xy 134.002326 -267.888047)
			(xy 133.999732 -267.882624) (xy 133.99008 -267.863574) (xy 133.99008 -267.857478) (xy 133.98627 -267.853922)
			(xy 133.966998 -267.839468) (xy 133.932834 -267.80551) (xy 133.904426 -267.766607) (xy 133.882481 -267.723726)
			(xy 133.867542 -267.677931) (xy 133.859982 -267.630357) (xy 133.859524 -267.606272) (xy 133.859524 -267.606018)
			(xy 133.8601 -267.578996) (xy 133.869602 -267.525793) (xy 133.888312 -267.475091) (xy 133.915649 -267.42847)
			(xy 133.950758 -267.387383) (xy 133.971284 -267.369798) (xy 133.977737 -267.363342) (xy 133.986003 -267.34708)
			(xy 133.988094 -267.328958) (xy 133.98627 -267.320014) (xy 133.985762 -267.31849) (xy 133.975094 -267.282676)
			(xy 133.975094 -267.282168) (xy 133.951726 -267.194792) (xy 133.951726 -267.194284) (xy 133.943852 -267.161772)
			(xy 133.94309 -267.157962) (xy 133.942836 -267.156184) (xy 133.942074 -267.152628) (xy 133.94055 -267.144754)
			(xy 133.9342 -267.136118) (xy 133.930781 -267.131588) (xy 133.922318 -267.124028) (xy 133.917436 -267.121132)
			(xy 133.84911 -267.083286) (xy 133.844184 -267.080752) (xy 133.833547 -267.077667) (xy 133.828028 -267.07719)
			(xy 133.816598 -267.076428) (xy 133.811518 -267.07846) (xy 133.783578 -267.089216) (xy 133.724862 -267.100856)
			(xy 133.694932 -267.101574) (xy 133.694678 -267.101574) (xy 133.669427 -267.101051) (xy 133.619613 -267.092735)
			(xy 133.571848 -267.076334) (xy 133.527433 -267.052295) (xy 133.487581 -267.021274) (xy 133.453377 -266.984117)
			(xy 133.425756 -266.941837) (xy 133.40547 -266.895588) (xy 133.393073 -266.84663) (xy 133.388903 -266.7963)
			(xy 133.393073 -266.74597) (xy 133.40547 -266.697012) (xy 133.425756 -266.650763) (xy 133.453378 -266.608483)
			(xy 133.487581 -266.571326) (xy 133.527433 -266.540305) (xy 133.571848 -266.516266) (xy 133.619613 -266.499865)
			(xy 133.669427 -266.491549) (xy 133.694678 -266.490958) (xy 133.722178 -266.491539) (xy 133.776291 -266.501378)
			(xy 133.82777 -266.520742) (xy 133.85165 -266.534392) (xy 133.851904 -266.534392) (xy 133.857733 -266.537706)
			(xy 133.870606 -266.541447) (xy 133.877304 -266.541758) (xy 133.890258 -266.541758) (xy 133.979412 -266.49172)
			(xy 133.987794 -266.485878) (xy 133.995594 -266.47848) (xy 134.004679 -266.459016) (xy 134.00532 -266.448286)
			(xy 134.00532 -266.285726) (xy 134.00515 -266.279717) (xy 134.002322 -266.268037) (xy 133.999732 -266.262612)
			(xy 133.984746 -266.233148) (xy 133.978142 -266.227814) (xy 133.958391 -266.211917) (xy 133.923951 -266.174713)
			(xy 133.896132 -266.13233) (xy 133.875697 -266.085934) (xy 133.863209 -266.036799) (xy 133.85901 -265.986276)
			(xy 133.863217 -265.935753) (xy 133.875713 -265.88662) (xy 133.896155 -265.840226) (xy 133.923982 -265.797848)
			(xy 133.958428 -265.76065) (xy 133.978142 -265.744706) (xy 133.984746 -265.739372) (xy 133.999732 -265.709908)
			(xy 134.002308 -265.70448) (xy 134.005119 -265.6928) (xy 134.00532 -265.686794) (xy 134.00532 -265.52525)
			(xy 134.00532 -265.524234) (xy 134.004672 -265.513506) (xy 133.995583 -265.49405) (xy 133.987794 -265.486642)
			(xy 133.979412 -265.4808) (xy 133.902196 -265.437366) (xy 133.896295 -265.434332) (xy 133.88343 -265.431105)
			(xy 133.876796 -265.431016) (xy 133.863334 -265.431016) (xy 133.859778 -265.433302) (xy 133.85165 -265.438128)
			(xy 133.827764 -265.451769) (xy 133.776291 -265.471149) (xy 133.722178 -265.480997) (xy 133.694678 -265.481562)
			(xy 133.669428 -265.481039) (xy 133.619616 -265.472724) (xy 133.571853 -265.456323) (xy 133.52744 -265.432285)
			(xy 133.487589 -265.401265) (xy 133.453387 -265.36411) (xy 133.425767 -265.321831) (xy 133.405482 -265.275584)
			(xy 133.393085 -265.226628) (xy 133.388915 -265.1763) (xy 133.393085 -265.125972) (xy 133.405482 -265.077016)
			(xy 133.425767 -265.030769) (xy 133.453387 -264.98849) (xy 133.487589 -264.951335) (xy 133.52744 -264.920315)
			(xy 133.571853 -264.896277) (xy 133.619616 -264.879876) (xy 133.669428 -264.871561) (xy 133.694678 -264.870946)
			(xy 133.722178 -264.871527) (xy 133.776292 -264.881366) (xy 133.827771 -264.900729) (xy 133.85165 -264.91438)
			(xy 133.859778 -264.919206) (xy 133.863334 -264.921492) (xy 133.876796 -264.921492) (xy 133.883426 -264.921373)
			(xy 133.896284 -264.918148) (xy 133.902196 -264.915142) (xy 133.979412 -264.871708) (xy 133.987794 -264.865866)
			(xy 133.995592 -264.858467) (xy 134.004672 -264.839003) (xy 134.00532 -264.828274) (xy 134.00532 -264.665714)
			(xy 134.005149 -264.659705) (xy 134.002318 -264.648026) (xy 133.999732 -264.6426) (xy 133.984746 -264.613136)
			(xy 133.978142 -264.607802) (xy 133.958384 -264.591905) (xy 133.92393 -264.554698) (xy 133.896096 -264.512311)
			(xy 133.875649 -264.465908) (xy 133.863149 -264.416763) (xy 133.85894 -264.366229) (xy 133.863139 -264.315695)
			(xy 133.875629 -264.266548) (xy 133.896068 -264.220141) (xy 133.923894 -264.177748) (xy 133.958341 -264.140535)
			(xy 133.978142 -264.124694) (xy 133.984746 -264.11936) (xy 133.999732 -264.089896) (xy 134.002318 -264.08447)
			(xy 134.005149 -264.07279) (xy 134.00532 -264.066782) (xy 134.00532 -263.905238) (xy 134.00532 -263.904222)
			(xy 134.004689 -263.893485) (xy 133.995622 -263.874004) (xy 133.987794 -263.86663) (xy 133.979412 -263.860788)
			(xy 133.902196 -263.817354) (xy 133.896295 -263.814321) (xy 133.88343 -263.811094) (xy 133.876796 -263.811004)
			(xy 133.863334 -263.811004) (xy 133.859778 -263.81329) (xy 133.85165 -263.818116) (xy 133.827764 -263.831758)
			(xy 133.776291 -263.851138) (xy 133.722179 -263.860986) (xy 133.694678 -263.86155) (xy 133.670928 -263.861097)
			(xy 133.624 -263.853738) (xy 133.578779 -263.839201) (xy 133.536354 -263.817836) (xy 133.497749 -263.79016)
			(xy 133.463895 -263.756839) (xy 133.43561 -263.718678) (xy 133.413575 -263.676598) (xy 133.398322 -263.631612)
			(xy 133.390219 -263.584808) (xy 133.38937 -263.561068) (xy 133.38937 -263.555734) (xy 133.389758 -263.534449)
			(xy 133.395713 -263.492296) (xy 133.40747 -263.45138) (xy 133.415786 -263.431782) (xy 133.420104 -263.421876)
			(xy 133.42112 -263.419844) (xy 133.420358 -263.407652) (xy 133.419691 -263.401302) (xy 133.415563 -263.389223)
			(xy 133.41223 -263.383776) (xy 133.36524 -263.311132) (xy 133.359838 -263.303792) (xy 133.344991 -263.293249)
			(xy 133.336284 -263.290558) (xy 133.323076 -263.28878) (xy 133.130798 -263.28878) (xy 133.127064 -263.28881)
			(xy 133.119669 -263.289832) (xy 133.116066 -263.290812) (xy 133.108223 -263.293575) (xy 133.094738 -263.303286)
			(xy 133.08965 -263.309862) (xy 133.088126 -263.311894) (xy 133.034532 -263.394444) (xy 133.033516 -263.406636)
			(xy 133.042152 -263.425686) (xy 133.051116 -263.446273) (xy 133.063777 -263.489352) (xy 133.070191 -263.533792)
			(xy 133.0706 -263.556242) (xy 133.070113 -263.581052) (xy 133.062351 -263.63006) (xy 133.047018 -263.67725)
			(xy 133.024491 -263.721461) (xy 132.995326 -263.761604) (xy 132.96024 -263.79669) (xy 132.920097 -263.825855)
			(xy 132.875886 -263.848382) (xy 132.828696 -263.863715) (xy 132.779688 -263.871477) (xy 132.730068 -263.871477)
			(xy 132.68106 -263.863715) (xy 132.63387 -263.848382) (xy 132.589659 -263.825855) (xy 132.549516 -263.79669)
			(xy 132.51443 -263.761604) (xy 132.485265 -263.721461) (xy 132.462738 -263.67725) (xy 132.447405 -263.63006)
			(xy 132.439643 -263.581052) (xy 132.439156 -263.556242) (xy 132.439587 -263.533794) (xy 132.44601 -263.489357)
			(xy 132.458647 -263.446274) (xy 132.467604 -263.425686) (xy 132.47624 -263.406636) (xy 132.475224 -263.394444)
			(xy 132.42163 -263.311894) (xy 132.420106 -263.309862) (xy 132.415017 -263.303286) (xy 132.401532 -263.293579)
			(xy 132.39369 -263.290812) (xy 132.390088 -263.289827) (xy 132.382692 -263.288801) (xy 132.378958 -263.28878)
			(xy 132.190744 -263.28878) (xy 132.18701 -263.288806) (xy 132.179612 -263.289822) (xy 132.176012 -263.290812)
			(xy 132.168174 -263.293582) (xy 132.154701 -263.303301) (xy 132.149596 -263.309862) (xy 132.148072 -263.311894)
			(xy 132.094478 -263.394444) (xy 132.093462 -263.406636) (xy 132.102098 -263.425686) (xy 132.110993 -263.446246)
			(xy 132.123548 -263.489247) (xy 132.129903 -263.53359) (xy 132.130292 -263.555988) (xy 132.130292 -263.556242)
			(xy 132.129806 -263.581032) (xy 132.12205 -263.63) (xy 132.106729 -263.677153) (xy 132.08422 -263.721328)
			(xy 132.055078 -263.761439) (xy 132.020021 -263.796496) (xy 131.97991 -263.825638) (xy 131.935735 -263.848147)
			(xy 131.888582 -263.863468) (xy 131.839614 -263.871224) (xy 131.790034 -263.871224) (xy 131.741066 -263.863468)
			(xy 131.693913 -263.848147) (xy 131.649738 -263.825638) (xy 131.609627 -263.796496) (xy 131.57457 -263.761439)
			(xy 131.545428 -263.721328) (xy 131.522919 -263.677153) (xy 131.507598 -263.63) (xy 131.499842 -263.581032)
			(xy 131.499356 -263.556242) (xy 131.499356 -263.555988) (xy 131.499744 -263.533589) (xy 131.50608 -263.489241)
			(xy 131.518636 -263.446238) (xy 131.52755 -263.425686) (xy 131.536186 -263.406636) (xy 131.53517 -263.394444)
			(xy 131.481576 -263.311894) (xy 131.480052 -263.309862) (xy 131.474966 -263.303282) (xy 131.461485 -263.293563)
			(xy 131.453636 -263.290812) (xy 131.450034 -263.289831) (xy 131.442637 -263.288813) (xy 131.438904 -263.28878)
			(xy 130.310636 -263.28878) (xy 130.306902 -263.288807) (xy 130.299505 -263.289824) (xy 130.295904 -263.290812)
			(xy 130.288067 -263.293583) (xy 130.274595 -263.303303) (xy 130.269488 -263.309862) (xy 130.267964 -263.311894)
			(xy 130.21437 -263.394444) (xy 130.213354 -263.406636) (xy 130.22199 -263.425686) (xy 130.230885 -263.446246)
			(xy 130.24344 -263.489247) (xy 130.249796 -263.53359) (xy 130.250184 -263.555988) (xy 130.250184 -263.556242)
			(xy 130.249698 -263.581032) (xy 130.241942 -263.63) (xy 130.226621 -263.677153) (xy 130.204112 -263.721328)
			(xy 130.17497 -263.761439) (xy 130.139913 -263.796496) (xy 130.099802 -263.825638) (xy 130.055627 -263.848147)
			(xy 130.008474 -263.863468) (xy 129.959506 -263.871224) (xy 129.909926 -263.871224) (xy 129.860958 -263.863468)
			(xy 129.813805 -263.848147) (xy 129.76963 -263.825638) (xy 129.729519 -263.796496) (xy 129.694462 -263.761439)
			(xy 129.66532 -263.721328) (xy 129.642811 -263.677153) (xy 129.62749 -263.63) (xy 129.619734 -263.581032)
			(xy 129.619248 -263.556242) (xy 129.619248 -263.555988) (xy 129.619636 -263.533589) (xy 129.625971 -263.489241)
			(xy 129.638527 -263.446238) (xy 129.647442 -263.425686) (xy 129.656078 -263.406636) (xy 129.655062 -263.394444)
			(xy 129.601468 -263.311894) (xy 129.599944 -263.309862) (xy 129.594858 -263.303283) (xy 129.581376 -263.293566)
			(xy 129.573528 -263.290812) (xy 129.569926 -263.289832) (xy 129.562529 -263.288815) (xy 129.558796 -263.28878)
			(xy 129.366264 -263.28878) (xy 129.353056 -263.290558) (xy 129.344371 -263.293291) (xy 129.329536 -263.303828)
			(xy 129.3241 -263.311132) (xy 129.27711 -263.383776) (xy 129.273792 -263.389228) (xy 129.269679 -263.401307)
			(xy 129.268982 -263.407652) (xy 129.26822 -263.419844) (xy 129.269236 -263.421876) (xy 129.273554 -263.431782)
			(xy 129.281836 -263.451257) (xy 129.293557 -263.491921) (xy 129.299553 -263.533814) (xy 129.29997 -263.554972)
			(xy 129.29997 -263.55548) (xy 129.29997 -263.561068) (xy 129.299074 -263.586062) (xy 129.290146 -263.635268)
			(xy 129.273319 -263.682362) (xy 129.249043 -263.726084) (xy 129.217966 -263.765266) (xy 129.18092 -263.798861)
			(xy 129.138895 -263.825969) (xy 129.093014 -263.845867) (xy 129.044504 -263.858023) (xy 128.994662 -263.862111)
			(xy 128.94482 -263.858023) (xy 128.89631 -263.845867) (xy 128.850429 -263.825969) (xy 128.808404 -263.798861)
			(xy 128.771358 -263.765266) (xy 128.740281 -263.726084) (xy 128.716005 -263.682362) (xy 128.699178 -263.635268)
			(xy 128.69025 -263.586062) (xy 128.689354 -263.561068) (xy 128.689354 -263.555734) (xy 128.689742 -263.534449)
			(xy 128.695697 -263.492295) (xy 128.707453 -263.451379) (xy 128.71577 -263.431782) (xy 128.720088 -263.421876)
			(xy 128.721104 -263.419844) (xy 128.720342 -263.407652) (xy 128.719676 -263.401301) (xy 128.715555 -263.389219)
			(xy 128.712214 -263.383776) (xy 128.665224 -263.311132) (xy 128.659822 -263.303794) (xy 128.644973 -263.293255)
			(xy 128.636268 -263.290558) (xy 128.62306 -263.28878) (xy 128.430782 -263.28878) (xy 128.427049 -263.288811)
			(xy 128.419654 -263.289835) (xy 128.41605 -263.290812) (xy 128.408209 -263.293577) (xy 128.394727 -263.303291)
			(xy 128.389634 -263.309862) (xy 128.38811 -263.311894) (xy 128.334516 -263.394444) (xy 128.3335 -263.406636)
			(xy 128.342136 -263.425686) (xy 128.351098 -263.446274) (xy 128.363756 -263.489352) (xy 128.370168 -263.533792)
			(xy 128.370584 -263.556242) (xy 128.370097 -263.581052) (xy 128.362335 -263.63006) (xy 128.347002 -263.67725)
			(xy 128.324475 -263.721461) (xy 128.29531 -263.761604) (xy 128.260224 -263.79669) (xy 128.220081 -263.825855)
			(xy 128.17587 -263.848382) (xy 128.12868 -263.863715) (xy 128.079672 -263.871477) (xy 128.030052 -263.871477)
			(xy 127.981044 -263.863715) (xy 127.933854 -263.848382) (xy 127.889643 -263.825855) (xy 127.8495 -263.79669)
			(xy 127.814414 -263.761604) (xy 127.785249 -263.721461) (xy 127.762722 -263.67725) (xy 127.747389 -263.63006)
			(xy 127.739627 -263.581052) (xy 127.73914 -263.556242) (xy 127.739571 -263.533794) (xy 127.745993 -263.489357)
			(xy 127.75863 -263.446274) (xy 127.767588 -263.425686) (xy 127.776224 -263.406636) (xy 127.775208 -263.394444)
			(xy 127.721614 -263.311894) (xy 127.72009 -263.309862) (xy 127.715 -263.303288) (xy 127.701514 -263.293585)
			(xy 127.693674 -263.290812) (xy 127.690072 -263.289828) (xy 127.682676 -263.288805) (xy 127.678942 -263.28878)
			(xy 127.48641 -263.28878) (xy 127.473202 -263.290558) (xy 127.464512 -263.293285) (xy 127.449666 -263.303815)
			(xy 127.444246 -263.311132) (xy 127.397256 -263.383776) (xy 127.393941 -263.38923) (xy 127.389833 -263.401309)
			(xy 127.389128 -263.407652) (xy 127.388366 -263.419844) (xy 127.389382 -263.421876) (xy 127.3937 -263.431782)
			(xy 127.401981 -263.451257) (xy 127.4137 -263.491921) (xy 127.419695 -263.533814) (xy 127.420116 -263.554972)
			(xy 127.420116 -263.55548) (xy 127.420116 -263.561068) (xy 127.41922 -263.586062) (xy 127.410292 -263.635268)
			(xy 127.393465 -263.682362) (xy 127.369189 -263.726084) (xy 127.338112 -263.765266) (xy 127.301066 -263.798861)
			(xy 127.259041 -263.825969) (xy 127.21316 -263.845867) (xy 127.16465 -263.858023) (xy 127.114808 -263.862111)
			(xy 127.064966 -263.858023) (xy 127.016456 -263.845867) (xy 126.970575 -263.825969) (xy 126.92855 -263.798861)
			(xy 126.891504 -263.765266) (xy 126.860427 -263.726084) (xy 126.836151 -263.682362) (xy 126.819324 -263.635268)
			(xy 126.810396 -263.586062) (xy 126.8095 -263.561068) (xy 126.8095 -263.555734) (xy 126.809889 -263.534449)
			(xy 126.815844 -263.492296) (xy 126.827601 -263.45138) (xy 126.835916 -263.431782) (xy 126.840234 -263.421876)
			(xy 126.84125 -263.419844) (xy 126.840488 -263.407652) (xy 126.839822 -263.401302) (xy 126.835696 -263.389221)
			(xy 126.83236 -263.383776) (xy 126.78537 -263.311132) (xy 126.77997 -263.303789) (xy 126.765126 -263.293238)
			(xy 126.756414 -263.290558) (xy 126.743206 -263.28878) (xy 125.606302 -263.28878) (xy 125.593094 -263.290558)
			(xy 125.584405 -263.293286) (xy 125.569561 -263.303817) (xy 125.564138 -263.311132) (xy 125.517148 -263.383776)
			(xy 125.513833 -263.38923) (xy 125.509726 -263.401309) (xy 125.50902 -263.407652) (xy 125.508258 -263.419844)
			(xy 125.509274 -263.421876) (xy 125.513592 -263.431782) (xy 125.521873 -263.451257) (xy 125.533593 -263.491921)
			(xy 125.539588 -263.533814) (xy 125.540008 -263.554972) (xy 125.540008 -263.55548) (xy 125.540008 -263.561068)
			(xy 125.539112 -263.586062) (xy 125.530184 -263.635268) (xy 125.513357 -263.682362) (xy 125.489081 -263.726084)
			(xy 125.458004 -263.765266) (xy 125.420958 -263.798861) (xy 125.378933 -263.825969) (xy 125.333052 -263.845867)
			(xy 125.284542 -263.858023) (xy 125.2347 -263.862111) (xy 125.184858 -263.858023) (xy 125.136348 -263.845867)
			(xy 125.090467 -263.825969) (xy 125.048442 -263.798861) (xy 125.011396 -263.765266) (xy 124.980319 -263.726084)
			(xy 124.956043 -263.682362) (xy 124.939216 -263.635268) (xy 124.930288 -263.586062) (xy 124.929392 -263.561068)
			(xy 124.929392 -263.555734) (xy 124.929781 -263.534449) (xy 124.935736 -263.492296) (xy 124.947493 -263.45138)
			(xy 124.955808 -263.431782) (xy 124.960126 -263.421876) (xy 124.961142 -263.419844) (xy 124.96038 -263.407652)
			(xy 124.959713 -263.401302) (xy 124.955587 -263.389222) (xy 124.952252 -263.383776) (xy 124.905262 -263.311132)
			(xy 124.899862 -263.30379) (xy 124.885016 -263.293241) (xy 124.876306 -263.290558) (xy 124.863098 -263.28878)
			(xy 123.726448 -263.28878) (xy 123.71324 -263.290558) (xy 123.704557 -263.293294) (xy 123.689725 -263.303833)
			(xy 123.684284 -263.311132) (xy 123.637294 -263.383776) (xy 123.633977 -263.389229) (xy 123.629866 -263.401308)
			(xy 123.629166 -263.407652) (xy 123.628404 -263.419844) (xy 123.62942 -263.421876) (xy 123.633738 -263.431782)
			(xy 123.642018 -263.451257) (xy 123.653736 -263.491922) (xy 123.65973 -263.533814) (xy 123.660154 -263.554972)
			(xy 123.660154 -263.55548) (xy 123.660154 -263.561068) (xy 123.659258 -263.586062) (xy 123.65033 -263.635268)
			(xy 123.633503 -263.682362) (xy 123.609227 -263.726084) (xy 123.57815 -263.765266) (xy 123.541104 -263.798861)
			(xy 123.499079 -263.825969) (xy 123.453198 -263.845867) (xy 123.404688 -263.858023) (xy 123.354846 -263.862111)
			(xy 123.305004 -263.858023) (xy 123.256494 -263.845867) (xy 123.210613 -263.825969) (xy 123.168588 -263.798861)
			(xy 123.131542 -263.765266) (xy 123.100465 -263.726084) (xy 123.076189 -263.682362) (xy 123.059362 -263.635268)
			(xy 123.050434 -263.586062) (xy 123.049538 -263.561068) (xy 123.049538 -263.555734) (xy 123.049927 -263.534449)
			(xy 123.055883 -263.492296) (xy 123.067641 -263.451381) (xy 123.075954 -263.431782) (xy 123.080272 -263.421876)
			(xy 123.081288 -263.419844) (xy 123.080526 -263.407652) (xy 123.07986 -263.401301) (xy 123.075738 -263.389219)
			(xy 123.072398 -263.383776) (xy 123.025408 -263.311132) (xy 123.020004 -263.303796) (xy 123.005155 -263.293262)
			(xy 122.996452 -263.290558) (xy 122.983244 -263.28878) (xy 121.84634 -263.28878) (xy 121.833132 -263.290558)
			(xy 121.824449 -263.293295) (xy 121.80962 -263.303835) (xy 121.804176 -263.311132) (xy 121.757186 -263.383776)
			(xy 121.753869 -263.389229) (xy 121.749759 -263.401308) (xy 121.749058 -263.407652) (xy 121.748296 -263.419844)
			(xy 121.749312 -263.421876) (xy 121.75363 -263.431782) (xy 121.76191 -263.451257) (xy 121.773628 -263.491922)
			(xy 121.779623 -263.533814) (xy 121.780046 -263.554972) (xy 121.780046 -263.55548) (xy 121.780046 -263.561068)
			(xy 121.77915 -263.586062) (xy 121.770222 -263.635268) (xy 121.753395 -263.682362) (xy 121.729119 -263.726084)
			(xy 121.698042 -263.765266) (xy 121.660996 -263.798861) (xy 121.618971 -263.825969) (xy 121.57309 -263.845867)
			(xy 121.52458 -263.858023) (xy 121.474738 -263.862111) (xy 121.424896 -263.858023) (xy 121.376386 -263.845867)
			(xy 121.330505 -263.825969) (xy 121.28848 -263.798861) (xy 121.251434 -263.765266) (xy 121.220357 -263.726084)
			(xy 121.196081 -263.682362) (xy 121.179254 -263.635268) (xy 121.170326 -263.586062) (xy 121.16943 -263.561068)
			(xy 121.16943 -263.555734) (xy 121.169819 -263.534449) (xy 121.175774 -263.492296) (xy 121.187533 -263.451381)
			(xy 121.195846 -263.431782) (xy 121.200164 -263.421876) (xy 121.20118 -263.419844) (xy 121.200418 -263.407652)
			(xy 121.199752 -263.401301) (xy 121.195629 -263.38922) (xy 121.19229 -263.383776) (xy 121.1453 -263.311132)
			(xy 121.139896 -263.303797) (xy 121.125045 -263.293265) (xy 121.116344 -263.290558) (xy 121.103136 -263.28878)
			(xy 119.893842 -263.28878) (xy 119.883777 -263.288346) (xy 119.86519 -263.280614) (xy 119.857774 -263.273794)
			(xy 118.523512 -261.939532) (xy 118.520661 -261.936826) (xy 118.514283 -261.932232) (xy 118.510812 -261.930388)
			(xy 118.505384 -261.92781) (xy 118.493704 -261.924997) (xy 118.487698 -261.9248) (xy 117.917722 -261.9248)
			(xy 117.907658 -261.924362) (xy 117.889074 -261.916628) (xy 117.881654 -261.909814) (xy 117.552978 -261.581138)
			(xy 117.548361 -261.576788) (xy 117.537437 -261.570345) (xy 117.531388 -261.568438) (xy 117.519958 -261.564882)
			(xy 117.507258 -261.567168) (xy 117.490792 -261.570241) (xy 117.457458 -261.573549) (xy 117.44071 -261.573772)
			(xy 117.413723 -261.573271) (xy 117.360414 -261.564828) (xy 117.309082 -261.54815) (xy 117.260992 -261.523646)
			(xy 117.217327 -261.49192) (xy 117.179163 -261.453753) (xy 117.147441 -261.410086) (xy 117.12294 -261.361994)
			(xy 117.106266 -261.310661) (xy 117.097827 -261.257351) (xy 117.097302 -261.230364) (xy 117.097528 -261.213616)
			(xy 117.100836 -261.180282) (xy 117.103906 -261.163816) (xy 117.106192 -261.151116) (xy 117.102636 -261.139686)
			(xy 117.100676 -261.133658) (xy 117.094255 -261.122735) (xy 117.089936 -261.118096) (xy 116.222526 -260.250686)
			(xy 116.219423 -260.247424) (xy 116.214315 -260.240013) (xy 116.212366 -260.235954) (xy 116.209861 -260.230866)
			(xy 116.202932 -260.221893) (xy 116.19865 -260.218174) (xy 116.175028 -260.198362) (xy 116.169057 -260.193718)
			(xy 116.155097 -260.18791) (xy 116.147596 -260.186932) (xy 116.120885 -260.183697) (xy 116.068859 -260.16999)
			(xy 116.019604 -260.148344) (xy 115.974324 -260.119287) (xy 115.934124 -260.08353) (xy 115.899988 -260.041945)
			(xy 115.872748 -259.995549) (xy 115.85307 -259.945475) (xy 115.841435 -259.892947) (xy 115.83924 -259.86613)
			(xy 115.838732 -259.85597) (xy 115.834922 -259.847588) (xy 115.83295 -259.843382) (xy 115.827713 -259.83571)
			(xy 115.824508 -259.832348) (xy 115.556792 -259.564632) (xy 115.553941 -259.561927) (xy 115.547562 -259.557335)
			(xy 115.544092 -259.555488) (xy 115.538666 -259.552902) (xy 115.526986 -259.550071) (xy 115.520978 -259.5499)
			(xy 113.982754 -259.5499) (xy 113.97427 -259.550214) (xy 113.95824 -259.555775) (xy 113.944929 -259.566296)
			(xy 113.940082 -259.573268) (xy 113.894108 -259.646674) (xy 113.890829 -259.652267) (xy 113.886856 -259.664604)
			(xy 113.886234 -259.671058) (xy 113.886234 -259.673598) (xy 113.886996 -259.686552) (xy 113.891314 -259.695696)
			(xy 113.902139 -259.719133) (xy 113.917415 -259.768446) (xy 113.925132 -259.81949) (xy 113.925604 -259.845302)
			(xy 113.925124 -259.871001) (xy 113.917463 -259.921825) (xy 113.902314 -259.970939) (xy 113.880013 -260.017247)
			(xy 113.85106 -260.059714) (xy 113.8161 -260.097391) (xy 113.775916 -260.129437) (xy 113.731404 -260.155136)
			(xy 113.683559 -260.173913) (xy 113.63345 -260.185351) (xy 113.582196 -260.189192) (xy 113.530942 -260.185351)
			(xy 113.480833 -260.173913) (xy 113.432988 -260.155136) (xy 113.388476 -260.129437) (xy 113.348292 -260.097391)
			(xy 113.313332 -260.059714) (xy 113.284379 -260.017247) (xy 113.262078 -259.970939) (xy 113.246929 -259.921825)
			(xy 113.239268 -259.871001) (xy 113.238788 -259.845302) (xy 113.239252 -259.819489) (xy 113.246975 -259.768445)
			(xy 113.262247 -259.719131) (xy 113.273078 -259.695696) (xy 113.275679 -259.689953) (xy 113.278251 -259.677616)
			(xy 113.278158 -259.671312) (xy 113.277396 -259.65785) (xy 113.224564 -259.573776) (xy 113.219759 -259.566663)
			(xy 113.206394 -259.555907) (xy 113.190215 -259.550199) (xy 113.181638 -259.5499) (xy 112.182402 -259.5499)
			(xy 112.172332 -259.549477) (xy 112.153727 -259.541763) (xy 112.146334 -259.534914) (xy 111.663226 -259.051806)
			(xy 111.660223 -259.048924) (xy 111.653457 -259.044075) (xy 111.649764 -259.042154) (xy 111.645086 -259.039952)
			(xy 111.635103 -259.037269) (xy 111.629952 -259.03682) (xy 111.596678 -259.03682) (xy 111.592606 -259.036872)
			(xy 111.584563 -259.038147) (xy 111.580676 -259.03936) (xy 111.57588 -259.041108) (xy 111.567053 -259.04623)
			(xy 111.56315 -259.04952) (xy 111.562642 -259.050028) (xy 111.543599 -259.066632) (xy 111.501555 -259.094649)
			(xy 111.455862 -259.116206) (xy 111.407505 -259.13084) (xy 111.357526 -259.138233) (xy 111.332264 -259.138674)
			(xy 111.305282 -259.138142) (xy 111.251982 -259.129695) (xy 111.20066 -259.113013) (xy 111.15258 -259.088509)
			(xy 111.108925 -259.056785) (xy 111.07077 -259.018622) (xy 111.039055 -258.97496) (xy 111.01456 -258.926875)
			(xy 110.997889 -258.87555) (xy 110.989452 -258.822248) (xy 110.988856 -258.795266) (xy 110.989343 -258.769399)
			(xy 110.997119 -258.718252) (xy 111.00435 -258.693412) (xy 111.007906 -258.681982) (xy 111.005874 -258.670044)
			(xy 111.004736 -258.664229) (xy 111.000109 -258.653323) (xy 110.99673 -258.648454) (xy 110.948216 -258.582668)
			(xy 110.943644 -258.57708) (xy 110.936493 -258.570415) (xy 110.918595 -258.562593) (xy 110.908846 -258.56184)
			(xy 110.170722 -258.56184) (xy 110.164713 -258.56201) (xy 110.153032 -258.564836) (xy 110.147608 -258.567428)
			(xy 110.144133 -258.569267) (xy 110.137754 -258.57386) (xy 110.134908 -258.576572) (xy 109.155992 -259.555488)
			(xy 109.153287 -259.55834) (xy 109.148697 -259.564719) (xy 109.146848 -259.568188) (xy 109.144268 -259.573615)
			(xy 109.141452 -259.585295) (xy 109.14126 -259.591302) (xy 109.14126 -259.695442) (xy 109.145578 -259.705094)
			(xy 109.155038 -259.727245) (xy 109.168371 -259.773529) (xy 109.175125 -259.821219) (xy 109.17555 -259.845302)
			(xy 110.988351 -259.845302) (xy 110.992381 -259.792804) (xy 111.004378 -259.741536) (xy 111.024061 -259.692701)
			(xy 111.050967 -259.647442) (xy 111.084467 -259.606821) (xy 111.123775 -259.57179) (xy 111.16797 -259.54317)
			(xy 111.216015 -259.521631) (xy 111.266786 -259.507679) (xy 111.319091 -259.501641) (xy 111.371705 -259.503658)
			(xy 111.423395 -259.513682) (xy 111.472948 -259.53148) (xy 111.519204 -259.556633) (xy 111.561078 -259.588552)
			(xy 111.59759 -259.62649) (xy 111.627882 -259.669556) (xy 111.651245 -259.716741) (xy 111.667131 -259.76694)
			(xy 111.675168 -259.818976) (xy 111.675672 -259.845302) (xy 111.675168 -259.871628) (xy 111.667131 -259.923664)
			(xy 111.651245 -259.973863) (xy 111.627882 -260.021048) (xy 111.59759 -260.064114) (xy 111.561078 -260.102052)
			(xy 111.519204 -260.133971) (xy 111.472948 -260.159124) (xy 111.423395 -260.176922) (xy 111.371705 -260.186946)
			(xy 111.319091 -260.188963) (xy 111.266786 -260.182925) (xy 111.216015 -260.168973) (xy 111.16797 -260.147434)
			(xy 111.123775 -260.118814) (xy 111.084467 -260.083783) (xy 111.050967 -260.043162) (xy 111.024061 -259.997903)
			(xy 111.004378 -259.949068) (xy 110.992381 -259.8978) (xy 110.988351 -259.845302) (xy 109.17555 -259.845302)
			(xy 109.175147 -259.869387) (xy 109.168411 -259.917083) (xy 109.155057 -259.963365) (xy 109.145578 -259.98551)
			(xy 109.14126 -259.995162) (xy 109.14126 -260.999224) (xy 109.141777 -261.009078) (xy 109.149309 -261.027297)
			(xy 109.16314 -261.041345) (xy 109.171994 -261.045706) (xy 109.246162 -261.077964) (xy 109.257592 -261.08279)
			(xy 109.264497 -261.085477) (xy 109.279213 -261.087145) (xy 109.286548 -261.086092) (xy 109.29366 -261.084822)
			(xy 109.306868 -261.078472) (xy 109.312456 -261.073138) (xy 109.33168 -261.05569) (xy 109.374401 -261.026192)
			(xy 109.421073 -261.003457) (xy 109.470634 -260.988003) (xy 109.521957 -260.98018) (xy 109.547914 -260.979666)
			(xy 109.573614 -260.980147) (xy 109.62444 -260.98781) (xy 109.673556 -261.002962) (xy 109.719866 -261.025265)
			(xy 109.762334 -261.054221) (xy 109.800012 -261.089183) (xy 109.832059 -261.12937) (xy 109.857759 -261.173884)
			(xy 109.876537 -261.221732) (xy 109.887974 -261.271843) (xy 109.891814 -261.323074) (xy 110.153961 -261.323074)
			(xy 110.157991 -261.270576) (xy 110.169988 -261.219308) (xy 110.189671 -261.170473) (xy 110.216577 -261.125214)
			(xy 110.250077 -261.084593) (xy 110.289385 -261.049562) (xy 110.33358 -261.020942) (xy 110.381625 -260.999403)
			(xy 110.432396 -260.985451) (xy 110.484701 -260.979413) (xy 110.537315 -260.98143) (xy 110.589005 -260.991454)
			(xy 110.638558 -261.009252) (xy 110.684814 -261.034405) (xy 110.726688 -261.066324) (xy 110.7632 -261.104262)
			(xy 110.793492 -261.147328) (xy 110.816855 -261.194513) (xy 110.832741 -261.244712) (xy 110.840778 -261.296748)
			(xy 110.841282 -261.323074) (xy 111.103921 -261.323074) (xy 111.107951 -261.270576) (xy 111.119948 -261.219308)
			(xy 111.139631 -261.170473) (xy 111.166537 -261.125214) (xy 111.200037 -261.084593) (xy 111.239345 -261.049562)
			(xy 111.28354 -261.020942) (xy 111.331585 -260.999403) (xy 111.382356 -260.985451) (xy 111.434661 -260.979413)
			(xy 111.487275 -260.98143) (xy 111.538965 -260.991454) (xy 111.588518 -261.009252) (xy 111.634774 -261.034405)
			(xy 111.676648 -261.066324) (xy 111.71316 -261.104262) (xy 111.743452 -261.147328) (xy 111.766815 -261.194513)
			(xy 111.782701 -261.244712) (xy 111.790738 -261.296748) (xy 111.791242 -261.323074) (xy 112.053881 -261.323074)
			(xy 112.057911 -261.270576) (xy 112.069908 -261.219308) (xy 112.089591 -261.170473) (xy 112.116497 -261.125214)
			(xy 112.149997 -261.084593) (xy 112.189305 -261.049562) (xy 112.2335 -261.020942) (xy 112.281545 -260.999403)
			(xy 112.332316 -260.985451) (xy 112.384621 -260.979413) (xy 112.437235 -260.98143) (xy 112.488925 -260.991454)
			(xy 112.538478 -261.009252) (xy 112.584734 -261.034405) (xy 112.626608 -261.066324) (xy 112.66312 -261.104262)
			(xy 112.693412 -261.147328) (xy 112.716775 -261.194513) (xy 112.732661 -261.244712) (xy 112.740698 -261.296748)
			(xy 112.741202 -261.323074) (xy 113.004095 -261.323074) (xy 113.008125 -261.270576) (xy 113.020122 -261.219308)
			(xy 113.039805 -261.170473) (xy 113.066711 -261.125214) (xy 113.100211 -261.084593) (xy 113.139519 -261.049562)
			(xy 113.183714 -261.020942) (xy 113.231759 -260.999403) (xy 113.28253 -260.985451) (xy 113.334835 -260.979413)
			(xy 113.387449 -260.98143) (xy 113.439139 -260.991454) (xy 113.488692 -261.009252) (xy 113.534948 -261.034405)
			(xy 113.576822 -261.066324) (xy 113.613334 -261.104262) (xy 113.643626 -261.147328) (xy 113.666989 -261.194513)
			(xy 113.682875 -261.244712) (xy 113.690912 -261.296748) (xy 113.691416 -261.323074) (xy 113.954055 -261.323074)
			(xy 113.958085 -261.270576) (xy 113.970082 -261.219308) (xy 113.989765 -261.170473) (xy 114.016671 -261.125214)
			(xy 114.050171 -261.084593) (xy 114.089479 -261.049562) (xy 114.133674 -261.020942) (xy 114.181719 -260.999403)
			(xy 114.23249 -260.985451) (xy 114.284795 -260.979413) (xy 114.337409 -260.98143) (xy 114.389099 -260.991454)
			(xy 114.438652 -261.009252) (xy 114.484908 -261.034405) (xy 114.526782 -261.066324) (xy 114.563294 -261.104262)
			(xy 114.593586 -261.147328) (xy 114.616949 -261.194513) (xy 114.632835 -261.244712) (xy 114.640872 -261.296748)
			(xy 114.641376 -261.323074) (xy 114.904015 -261.323074) (xy 114.908045 -261.270576) (xy 114.920042 -261.219308)
			(xy 114.939725 -261.170473) (xy 114.966631 -261.125214) (xy 115.000131 -261.084593) (xy 115.039439 -261.049562)
			(xy 115.083634 -261.020942) (xy 115.131679 -260.999403) (xy 115.18245 -260.985451) (xy 115.234755 -260.979413)
			(xy 115.287369 -260.98143) (xy 115.339059 -260.991454) (xy 115.388612 -261.009252) (xy 115.434868 -261.034405)
			(xy 115.476742 -261.066324) (xy 115.513254 -261.104262) (xy 115.543546 -261.147328) (xy 115.566909 -261.194513)
			(xy 115.582795 -261.244712) (xy 115.590832 -261.296748) (xy 115.591336 -261.323074) (xy 115.853975 -261.323074)
			(xy 115.858005 -261.270576) (xy 115.870002 -261.219308) (xy 115.889685 -261.170473) (xy 115.916591 -261.125214)
			(xy 115.950091 -261.084593) (xy 115.989399 -261.049562) (xy 116.033594 -261.020942) (xy 116.081639 -260.999403)
			(xy 116.13241 -260.985451) (xy 116.184715 -260.979413) (xy 116.237329 -260.98143) (xy 116.289019 -260.991454)
			(xy 116.338572 -261.009252) (xy 116.384828 -261.034405) (xy 116.426702 -261.066324) (xy 116.463214 -261.104262)
			(xy 116.493506 -261.147328) (xy 116.516869 -261.194513) (xy 116.532755 -261.244712) (xy 116.540792 -261.296748)
			(xy 116.541296 -261.323074) (xy 116.540792 -261.3494) (xy 116.532755 -261.401436) (xy 116.516869 -261.451635)
			(xy 116.493506 -261.49882) (xy 116.463214 -261.541886) (xy 116.426702 -261.579824) (xy 116.384828 -261.611743)
			(xy 116.338572 -261.636896) (xy 116.289019 -261.654694) (xy 116.237329 -261.664718) (xy 116.184715 -261.666735)
			(xy 116.13241 -261.660697) (xy 116.081639 -261.646745) (xy 116.033594 -261.625206) (xy 115.989399 -261.596586)
			(xy 115.950091 -261.561555) (xy 115.916591 -261.520934) (xy 115.889685 -261.475675) (xy 115.870002 -261.42684)
			(xy 115.858005 -261.375572) (xy 115.853975 -261.323074) (xy 115.591336 -261.323074) (xy 115.590832 -261.3494)
			(xy 115.582795 -261.401436) (xy 115.566909 -261.451635) (xy 115.543546 -261.49882) (xy 115.513254 -261.541886)
			(xy 115.476742 -261.579824) (xy 115.434868 -261.611743) (xy 115.388612 -261.636896) (xy 115.339059 -261.654694)
			(xy 115.287369 -261.664718) (xy 115.234755 -261.666735) (xy 115.18245 -261.660697) (xy 115.131679 -261.646745)
			(xy 115.083634 -261.625206) (xy 115.039439 -261.596586) (xy 115.000131 -261.561555) (xy 114.966631 -261.520934)
			(xy 114.939725 -261.475675) (xy 114.920042 -261.42684) (xy 114.908045 -261.375572) (xy 114.904015 -261.323074)
			(xy 114.641376 -261.323074) (xy 114.640872 -261.3494) (xy 114.632835 -261.401436) (xy 114.616949 -261.451635)
			(xy 114.593586 -261.49882) (xy 114.563294 -261.541886) (xy 114.526782 -261.579824) (xy 114.484908 -261.611743)
			(xy 114.438652 -261.636896) (xy 114.389099 -261.654694) (xy 114.337409 -261.664718) (xy 114.284795 -261.666735)
			(xy 114.23249 -261.660697) (xy 114.181719 -261.646745) (xy 114.133674 -261.625206) (xy 114.089479 -261.596586)
			(xy 114.050171 -261.561555) (xy 114.016671 -261.520934) (xy 113.989765 -261.475675) (xy 113.970082 -261.42684)
			(xy 113.958085 -261.375572) (xy 113.954055 -261.323074) (xy 113.691416 -261.323074) (xy 113.690912 -261.3494)
			(xy 113.682875 -261.401436) (xy 113.666989 -261.451635) (xy 113.643626 -261.49882) (xy 113.613334 -261.541886)
			(xy 113.576822 -261.579824) (xy 113.534948 -261.611743) (xy 113.488692 -261.636896) (xy 113.439139 -261.654694)
			(xy 113.387449 -261.664718) (xy 113.334835 -261.666735) (xy 113.28253 -261.660697) (xy 113.231759 -261.646745)
			(xy 113.183714 -261.625206) (xy 113.139519 -261.596586) (xy 113.100211 -261.561555) (xy 113.066711 -261.520934)
			(xy 113.039805 -261.475675) (xy 113.020122 -261.42684) (xy 113.008125 -261.375572) (xy 113.004095 -261.323074)
			(xy 112.741202 -261.323074) (xy 112.740698 -261.3494) (xy 112.732661 -261.401436) (xy 112.716775 -261.451635)
			(xy 112.693412 -261.49882) (xy 112.66312 -261.541886) (xy 112.626608 -261.579824) (xy 112.584734 -261.611743)
			(xy 112.538478 -261.636896) (xy 112.488925 -261.654694) (xy 112.437235 -261.664718) (xy 112.384621 -261.666735)
			(xy 112.332316 -261.660697) (xy 112.281545 -261.646745) (xy 112.2335 -261.625206) (xy 112.189305 -261.596586)
			(xy 112.149997 -261.561555) (xy 112.116497 -261.520934) (xy 112.089591 -261.475675) (xy 112.069908 -261.42684)
			(xy 112.057911 -261.375572) (xy 112.053881 -261.323074) (xy 111.791242 -261.323074) (xy 111.790738 -261.3494)
			(xy 111.782701 -261.401436) (xy 111.766815 -261.451635) (xy 111.743452 -261.49882) (xy 111.71316 -261.541886)
			(xy 111.676648 -261.579824) (xy 111.634774 -261.611743) (xy 111.588518 -261.636896) (xy 111.538965 -261.654694)
			(xy 111.487275 -261.664718) (xy 111.434661 -261.666735) (xy 111.382356 -261.660697) (xy 111.331585 -261.646745)
			(xy 111.28354 -261.625206) (xy 111.239345 -261.596586) (xy 111.200037 -261.561555) (xy 111.166537 -261.520934)
			(xy 111.139631 -261.475675) (xy 111.119948 -261.42684) (xy 111.107951 -261.375572) (xy 111.103921 -261.323074)
			(xy 110.841282 -261.323074) (xy 110.840778 -261.3494) (xy 110.832741 -261.401436) (xy 110.816855 -261.451635)
			(xy 110.793492 -261.49882) (xy 110.7632 -261.541886) (xy 110.726688 -261.579824) (xy 110.684814 -261.611743)
			(xy 110.638558 -261.636896) (xy 110.589005 -261.654694) (xy 110.537315 -261.664718) (xy 110.484701 -261.666735)
			(xy 110.432396 -261.660697) (xy 110.381625 -261.646745) (xy 110.33358 -261.625206) (xy 110.289385 -261.596586)
			(xy 110.250077 -261.561555) (xy 110.216577 -261.520934) (xy 110.189671 -261.475675) (xy 110.169988 -261.42684)
			(xy 110.157991 -261.375572) (xy 110.153961 -261.323074) (xy 109.891814 -261.323074) (xy 109.891816 -261.3231)
			(xy 109.887974 -261.374357) (xy 109.876537 -261.424468) (xy 109.857759 -261.472316) (xy 109.832059 -261.51683)
			(xy 109.800012 -261.557017) (xy 109.762334 -261.591979) (xy 109.719866 -261.620935) (xy 109.673556 -261.643238)
			(xy 109.62444 -261.65839) (xy 109.573614 -261.666053) (xy 109.547914 -261.666482) (xy 109.547914 -261.666736)
			(xy 109.520613 -261.66621) (xy 109.4667 -261.657568) (xy 109.414835 -261.640499) (xy 109.366326 -261.615434)
			(xy 109.322397 -261.583006) (xy 109.284157 -261.544031) (xy 109.252569 -261.499494) (xy 109.240066 -261.47522)
			(xy 109.239558 -261.474712) (xy 109.239304 -261.47395) (xy 109.236535 -261.468874) (xy 109.229099 -261.460021)
			(xy 109.224572 -261.456424) (xy 109.220254 -261.453122) (xy 109.208824 -261.448296) (xy 109.152436 -261.438898)
			(xy 109.121194 -261.433818) (xy 109.109127 -261.43256) (xy 109.08606 -261.439976) (xy 109.076998 -261.448042)
			(xy 108.615226 -261.909814) (xy 108.607828 -261.916658) (xy 108.589228 -261.924379) (xy 108.579158 -261.9248)
			(xy 105.908348 -261.9248) (xy 105.896024 -261.925397) (xy 105.874201 -261.936852) (xy 105.866692 -261.946644)
			(xy 105.866184 -261.947406) (xy 105.818686 -262.015478) (xy 105.815402 -262.020496) (xy 105.811033 -262.031661)
			(xy 105.81005 -262.037576) (xy 105.808526 -262.04926) (xy 105.813098 -262.061452) (xy 105.822901 -262.089992)
			(xy 105.833498 -262.149393) (xy 105.83418 -262.179562) (xy 105.83418 -262.180324) (xy 117.096797 -262.180324)
			(xy 117.100827 -262.127826) (xy 117.112824 -262.076558) (xy 117.132507 -262.027723) (xy 117.159413 -261.982464)
			(xy 117.192913 -261.941843) (xy 117.232221 -261.906812) (xy 117.276416 -261.878192) (xy 117.324461 -261.856653)
			(xy 117.375232 -261.842701) (xy 117.427537 -261.836663) (xy 117.480151 -261.83868) (xy 117.531841 -261.848704)
			(xy 117.581394 -261.866502) (xy 117.62765 -261.891655) (xy 117.669524 -261.923574) (xy 117.706036 -261.961512)
			(xy 117.736328 -262.004578) (xy 117.759691 -262.051763) (xy 117.775577 -262.101962) (xy 117.783614 -262.153998)
			(xy 117.784118 -262.180324) (xy 117.783614 -262.20665) (xy 117.775577 -262.258686) (xy 117.759691 -262.308885)
			(xy 117.736328 -262.35607) (xy 117.706036 -262.399136) (xy 117.669524 -262.437074) (xy 117.62765 -262.468993)
			(xy 117.581394 -262.494146) (xy 117.531841 -262.511944) (xy 117.480151 -262.521968) (xy 117.427537 -262.523985)
			(xy 117.375232 -262.517947) (xy 117.324461 -262.503995) (xy 117.276416 -262.482456) (xy 117.232221 -262.453836)
			(xy 117.192913 -262.418805) (xy 117.159413 -262.378184) (xy 117.132507 -262.332925) (xy 117.112824 -262.28409)
			(xy 117.100827 -262.232822) (xy 117.096797 -262.180324) (xy 105.83418 -262.180324) (xy 105.8337 -262.206023)
			(xy 105.826039 -262.256847) (xy 105.81089 -262.305961) (xy 105.788589 -262.352269) (xy 105.759636 -262.394736)
			(xy 105.724676 -262.432413) (xy 105.684492 -262.464459) (xy 105.63998 -262.490158) (xy 105.592135 -262.508935)
			(xy 105.542026 -262.520373) (xy 105.490772 -262.524214) (xy 105.439518 -262.520373) (xy 105.389409 -262.508935)
			(xy 105.341564 -262.490158) (xy 105.297052 -262.464459) (xy 105.256868 -262.432413) (xy 105.221908 -262.394736)
			(xy 105.192955 -262.352269) (xy 105.170654 -262.305961) (xy 105.155505 -262.256847) (xy 105.147844 -262.206023)
			(xy 105.147364 -262.180324) (xy 105.147364 -262.179562) (xy 105.148015 -262.14939) (xy 105.158616 -262.089985)
			(xy 105.168446 -262.061452) (xy 105.168446 -262.061198) (xy 105.170463 -262.05526) (xy 105.171867 -262.042801)
			(xy 105.17124 -262.03656) (xy 105.169716 -262.025384) (xy 105.11536 -261.947406) (xy 105.114852 -261.946644)
			(xy 105.107241 -261.936972) (xy 105.08548 -261.925557) (xy 105.073196 -261.9248) (xy 105.047542 -261.9248)
			(xy 105.041533 -261.924968) (xy 105.029851 -261.927794) (xy 105.024428 -261.930388) (xy 105.020952 -261.932225)
			(xy 105.014568 -261.936813) (xy 105.011728 -261.939532) (xy 104.379268 -262.571992) (xy 104.374147 -262.577451)
			(xy 104.367051 -262.590623) (xy 104.365298 -262.5979) (xy 104.363774 -262.60552) (xy 104.365552 -262.62076)
			(xy 104.3686 -262.627872) (xy 104.380011 -262.65646) (xy 104.392433 -262.716736) (xy 104.393238 -262.747506)
			(xy 104.393238 -262.75284) (xy 104.392453 -262.776371) (xy 104.384536 -262.82278) (xy 104.369591 -262.867424)
			(xy 104.347971 -262.909246) (xy 104.320188 -262.947254) (xy 104.286902 -262.980547) (xy 104.248899 -263.008338)
			(xy 104.207082 -263.029966) (xy 104.162441 -263.044921) (xy 104.116033 -263.052847) (xy 104.092502 -263.053576)
			(xy 104.087422 -263.053576) (xy 104.056589 -263.052777) (xy 103.996186 -263.040357) (xy 103.967534 -263.028938)
			(xy 103.960422 -263.02589) (xy 103.945182 -263.024112) (xy 103.937562 -263.025636) (xy 103.930287 -263.027392)
			(xy 103.917122 -263.034496) (xy 103.911654 -263.039606) (xy 103.104696 -263.846564) (xy 111.234223 -263.846564)
			(xy 111.238253 -263.794066) (xy 111.25025 -263.742798) (xy 111.269933 -263.693963) (xy 111.296839 -263.648704)
			(xy 111.330339 -263.608083) (xy 111.369647 -263.573052) (xy 111.413842 -263.544432) (xy 111.461887 -263.522893)
			(xy 111.512658 -263.508941) (xy 111.564963 -263.502903) (xy 111.617577 -263.50492) (xy 111.669267 -263.514944)
			(xy 111.71882 -263.532742) (xy 111.765076 -263.557895) (xy 111.80695 -263.589814) (xy 111.843462 -263.627752)
			(xy 111.873754 -263.670818) (xy 111.897117 -263.718003) (xy 111.913003 -263.768202) (xy 111.92104 -263.820238)
			(xy 111.921544 -263.846564) (xy 111.92104 -263.87289) (xy 111.913003 -263.924926) (xy 111.897117 -263.975125)
			(xy 111.873754 -264.02231) (xy 111.843462 -264.065376) (xy 111.80695 -264.103314) (xy 111.765076 -264.135233)
			(xy 111.71882 -264.160386) (xy 111.669267 -264.178184) (xy 111.617577 -264.188208) (xy 111.564963 -264.190225)
			(xy 111.512658 -264.184187) (xy 111.461887 -264.170235) (xy 111.413842 -264.148696) (xy 111.369647 -264.120076)
			(xy 111.330339 -264.085045) (xy 111.296839 -264.044424) (xy 111.269933 -263.999165) (xy 111.25025 -263.95033)
			(xy 111.238253 -263.899062) (xy 111.234223 -263.846564) (xy 103.104696 -263.846564) (xy 102.58298 -264.36828)
			(xy 103.782126 -264.36828) (xy 103.786086 -264.319226) (xy 103.797863 -264.271442) (xy 103.817154 -264.226166)
			(xy 103.843457 -264.18457) (xy 103.876092 -264.147733) (xy 103.914213 -264.116608) (xy 103.956834 -264.092001)
			(xy 104.00285 -264.074549) (xy 104.051069 -264.064705) (xy 104.100244 -264.062724) (xy 104.149099 -264.068656)
			(xy 104.19637 -264.082348) (xy 104.240832 -264.103446) (xy 104.281335 -264.131402) (xy 104.316828 -264.165494)
			(xy 104.346393 -264.204838) (xy 104.369264 -264.248415) (xy 104.384848 -264.295096) (xy 104.392743 -264.343673)
			(xy 104.393238 -264.36828) (xy 105.662234 -264.36828) (xy 105.666194 -264.319226) (xy 105.677971 -264.271442)
			(xy 105.697262 -264.226166) (xy 105.723565 -264.18457) (xy 105.7562 -264.147733) (xy 105.794321 -264.116608)
			(xy 105.836942 -264.092001) (xy 105.882958 -264.074549) (xy 105.931177 -264.064705) (xy 105.980352 -264.062724)
			(xy 106.029207 -264.068656) (xy 106.076478 -264.082348) (xy 106.12094 -264.103446) (xy 106.161443 -264.131402)
			(xy 106.196936 -264.165494) (xy 106.226501 -264.204838) (xy 106.249372 -264.248415) (xy 106.264956 -264.295096)
			(xy 106.272851 -264.343673) (xy 106.273346 -264.36828) (xy 107.542088 -264.36828) (xy 107.546048 -264.319226)
			(xy 107.557825 -264.271442) (xy 107.577116 -264.226166) (xy 107.603419 -264.18457) (xy 107.636054 -264.147733)
			(xy 107.674175 -264.116608) (xy 107.716796 -264.092001) (xy 107.762812 -264.074549) (xy 107.811031 -264.064705)
			(xy 107.860206 -264.062724) (xy 107.909061 -264.068656) (xy 107.956332 -264.082348) (xy 108.000794 -264.103446)
			(xy 108.041297 -264.131402) (xy 108.07679 -264.165494) (xy 108.106355 -264.204838) (xy 108.129226 -264.248415)
			(xy 108.14481 -264.295096) (xy 108.152705 -264.343673) (xy 108.1532 -264.36828) (xy 115.062012 -264.36828)
			(xy 115.065972 -264.319226) (xy 115.077749 -264.271442) (xy 115.09704 -264.226166) (xy 115.123343 -264.18457)
			(xy 115.155978 -264.147733) (xy 115.194099 -264.116608) (xy 115.23672 -264.092001) (xy 115.282736 -264.074549)
			(xy 115.330955 -264.064705) (xy 115.38013 -264.062724) (xy 115.428985 -264.068656) (xy 115.476256 -264.082348)
			(xy 115.520718 -264.103446) (xy 115.561221 -264.131402) (xy 115.596714 -264.165494) (xy 115.626279 -264.204838)
			(xy 115.64915 -264.248415) (xy 115.664734 -264.295096) (xy 115.672629 -264.343673) (xy 115.673124 -264.36828)
			(xy 116.94212 -264.36828) (xy 116.94608 -264.319226) (xy 116.957857 -264.271442) (xy 116.977148 -264.226166)
			(xy 117.003451 -264.18457) (xy 117.036086 -264.147733) (xy 117.074207 -264.116608) (xy 117.116828 -264.092001)
			(xy 117.162844 -264.074549) (xy 117.211063 -264.064705) (xy 117.260238 -264.062724) (xy 117.309093 -264.068656)
			(xy 117.356364 -264.082348) (xy 117.400826 -264.103446) (xy 117.441329 -264.131402) (xy 117.476822 -264.165494)
			(xy 117.506387 -264.204838) (xy 117.529258 -264.248415) (xy 117.544842 -264.295096) (xy 117.552737 -264.343673)
			(xy 117.553232 -264.36828) (xy 118.821974 -264.36828) (xy 118.825934 -264.319226) (xy 118.837711 -264.271442)
			(xy 118.857002 -264.226166) (xy 118.883305 -264.18457) (xy 118.91594 -264.147733) (xy 118.954061 -264.116608)
			(xy 118.996682 -264.092001) (xy 119.042698 -264.074549) (xy 119.090917 -264.064705) (xy 119.140092 -264.062724)
			(xy 119.188947 -264.068656) (xy 119.236218 -264.082348) (xy 119.28068 -264.103446) (xy 119.321183 -264.131402)
			(xy 119.356676 -264.165494) (xy 119.386241 -264.204838) (xy 119.409112 -264.248415) (xy 119.424696 -264.295096)
			(xy 119.432591 -264.343673) (xy 119.433086 -264.36828) (xy 120.699796 -264.36828) (xy 120.703756 -264.319226)
			(xy 120.715533 -264.271442) (xy 120.734824 -264.226166) (xy 120.761127 -264.18457) (xy 120.793762 -264.147733)
			(xy 120.831883 -264.116608) (xy 120.874504 -264.092001) (xy 120.92052 -264.074549) (xy 120.968739 -264.064705)
			(xy 121.017914 -264.062724) (xy 121.066769 -264.068656) (xy 121.11404 -264.082348) (xy 121.158502 -264.103446)
			(xy 121.199005 -264.131402) (xy 121.234498 -264.165494) (xy 121.264063 -264.204838) (xy 121.286934 -264.248415)
			(xy 121.302518 -264.295096) (xy 121.310413 -264.343673) (xy 121.310867 -264.366248) (xy 122.578888 -264.366248)
			(xy 122.582848 -264.317194) (xy 122.594625 -264.26941) (xy 122.613916 -264.224134) (xy 122.640219 -264.182538)
			(xy 122.672854 -264.145701) (xy 122.710975 -264.114576) (xy 122.753596 -264.089969) (xy 122.799612 -264.072517)
			(xy 122.847831 -264.062673) (xy 122.897006 -264.060692) (xy 122.945861 -264.066624) (xy 122.993132 -264.080316)
			(xy 123.037594 -264.101414) (xy 123.078097 -264.12937) (xy 123.11359 -264.163462) (xy 123.143155 -264.202806)
			(xy 123.166026 -264.246383) (xy 123.18161 -264.293064) (xy 123.189505 -264.341641) (xy 123.19 -264.366248)
			(xy 124.458996 -264.366248) (xy 124.462956 -264.317194) (xy 124.474733 -264.26941) (xy 124.494024 -264.224134)
			(xy 124.520327 -264.182538) (xy 124.552962 -264.145701) (xy 124.591083 -264.114576) (xy 124.633704 -264.089969)
			(xy 124.67972 -264.072517) (xy 124.727939 -264.062673) (xy 124.777114 -264.060692) (xy 124.825969 -264.066624)
			(xy 124.87324 -264.080316) (xy 124.917702 -264.101414) (xy 124.958205 -264.12937) (xy 124.993698 -264.163462)
			(xy 125.023263 -264.202806) (xy 125.046134 -264.246383) (xy 125.061718 -264.293064) (xy 125.069613 -264.341641)
			(xy 125.070108 -264.366248) (xy 126.33885 -264.366248) (xy 126.34281 -264.317194) (xy 126.354587 -264.26941)
			(xy 126.373878 -264.224134) (xy 126.400181 -264.182538) (xy 126.432816 -264.145701) (xy 126.470937 -264.114576)
			(xy 126.513558 -264.089969) (xy 126.559574 -264.072517) (xy 126.607793 -264.062673) (xy 126.656968 -264.060692)
			(xy 126.705823 -264.066624) (xy 126.753094 -264.080316) (xy 126.797556 -264.101414) (xy 126.838059 -264.12937)
			(xy 126.873552 -264.163462) (xy 126.903117 -264.202806) (xy 126.925988 -264.246383) (xy 126.941572 -264.293064)
			(xy 126.949467 -264.341641) (xy 126.949962 -264.366248) (xy 128.208527 -264.366248) (xy 128.212622 -264.31552)
			(xy 128.224801 -264.266106) (xy 128.244749 -264.219286) (xy 128.27195 -264.176272) (xy 128.305698 -264.138178)
			(xy 128.34512 -264.105991) (xy 128.389194 -264.080545) (xy 128.43678 -264.062498) (xy 128.486644 -264.052318)
			(xy 128.537496 -264.050269) (xy 128.588017 -264.056403) (xy 128.636901 -264.070563) (xy 128.68288 -264.09238)
			(xy 128.724764 -264.12129) (xy 128.761468 -264.156545) (xy 128.792041 -264.197231) (xy 128.815692 -264.242294)
			(xy 128.831808 -264.290568) (xy 128.839972 -264.340802) (xy 128.840484 -264.366248) (xy 129.148581 -264.366248)
			(xy 129.152676 -264.31552) (xy 129.164855 -264.266106) (xy 129.184803 -264.219286) (xy 129.212004 -264.176272)
			(xy 129.245752 -264.138178) (xy 129.285174 -264.105991) (xy 129.329248 -264.080545) (xy 129.376834 -264.062498)
			(xy 129.426698 -264.052318) (xy 129.47755 -264.050269) (xy 129.528071 -264.056403) (xy 129.576955 -264.070563)
			(xy 129.622934 -264.09238) (xy 129.664818 -264.12129) (xy 129.701522 -264.156545) (xy 129.732095 -264.197231)
			(xy 129.755746 -264.242294) (xy 129.771862 -264.290568) (xy 129.780026 -264.340802) (xy 129.780538 -264.366248)
			(xy 130.099066 -264.366248) (xy 130.103026 -264.317194) (xy 130.114803 -264.26941) (xy 130.134094 -264.224134)
			(xy 130.160397 -264.182538) (xy 130.193032 -264.145701) (xy 130.231153 -264.114576) (xy 130.273774 -264.089969)
			(xy 130.31979 -264.072517) (xy 130.368009 -264.062673) (xy 130.417184 -264.060692) (xy 130.466039 -264.066624)
			(xy 130.51331 -264.080316) (xy 130.557772 -264.101414) (xy 130.598275 -264.12937) (xy 130.633768 -264.163462)
			(xy 130.663333 -264.202806) (xy 130.686204 -264.246383) (xy 130.701788 -264.293064) (xy 130.709683 -264.341641)
			(xy 130.710178 -264.366248) (xy 131.028435 -264.366248) (xy 131.03253 -264.31552) (xy 131.044709 -264.266106)
			(xy 131.064657 -264.219286) (xy 131.091858 -264.176272) (xy 131.125606 -264.138178) (xy 131.165028 -264.105991)
			(xy 131.209102 -264.080545) (xy 131.256688 -264.062498) (xy 131.306552 -264.052318) (xy 131.357404 -264.050269)
			(xy 131.407925 -264.056403) (xy 131.456809 -264.070563) (xy 131.502788 -264.09238) (xy 131.544672 -264.12129)
			(xy 131.581376 -264.156545) (xy 131.611949 -264.197231) (xy 131.6356 -264.242294) (xy 131.651716 -264.290568)
			(xy 131.65988 -264.340802) (xy 131.660392 -264.366248) (xy 131.97892 -264.366248) (xy 131.98288 -264.317194)
			(xy 131.994657 -264.26941) (xy 132.013948 -264.224134) (xy 132.040251 -264.182538) (xy 132.072886 -264.145701)
			(xy 132.111007 -264.114576) (xy 132.153628 -264.089969) (xy 132.199644 -264.072517) (xy 132.247863 -264.062673)
			(xy 132.297038 -264.060692) (xy 132.345893 -264.066624) (xy 132.393164 -264.080316) (xy 132.437626 -264.101414)
			(xy 132.478129 -264.12937) (xy 132.513622 -264.163462) (xy 132.543187 -264.202806) (xy 132.566058 -264.246383)
			(xy 132.581642 -264.293064) (xy 132.589537 -264.341641) (xy 132.590032 -264.366248) (xy 132.908543 -264.366248)
			(xy 132.912638 -264.31552) (xy 132.924817 -264.266106) (xy 132.944765 -264.219286) (xy 132.971966 -264.176272)
			(xy 133.005714 -264.138178) (xy 133.045136 -264.105991) (xy 133.08921 -264.080545) (xy 133.136796 -264.062498)
			(xy 133.18666 -264.052318) (xy 133.237512 -264.050269) (xy 133.288033 -264.056403) (xy 133.336917 -264.070563)
			(xy 133.382896 -264.09238) (xy 133.42478 -264.12129) (xy 133.461484 -264.156545) (xy 133.492057 -264.197231)
			(xy 133.515708 -264.242294) (xy 133.531824 -264.290568) (xy 133.539988 -264.340802) (xy 133.5405 -264.366248)
			(xy 133.539988 -264.391694) (xy 133.531824 -264.441928) (xy 133.515708 -264.490202) (xy 133.492057 -264.535265)
			(xy 133.461484 -264.575951) (xy 133.42478 -264.611206) (xy 133.382896 -264.640116) (xy 133.336917 -264.661933)
			(xy 133.288033 -264.676093) (xy 133.237512 -264.682227) (xy 133.18666 -264.680178) (xy 133.136796 -264.669998)
			(xy 133.08921 -264.651951) (xy 133.045136 -264.626505) (xy 133.005714 -264.594318) (xy 132.971966 -264.556224)
			(xy 132.944765 -264.51321) (xy 132.924817 -264.46639) (xy 132.912638 -264.416976) (xy 132.908543 -264.366248)
			(xy 132.590032 -264.366248) (xy 132.589537 -264.390855) (xy 132.581642 -264.439432) (xy 132.566058 -264.486113)
			(xy 132.543187 -264.52969) (xy 132.513622 -264.569034) (xy 132.478129 -264.603126) (xy 132.437626 -264.631082)
			(xy 132.393164 -264.65218) (xy 132.345893 -264.665872) (xy 132.297038 -264.671804) (xy 132.247863 -264.669823)
			(xy 132.199644 -264.659979) (xy 132.153628 -264.642527) (xy 132.111007 -264.61792) (xy 132.072886 -264.586795)
			(xy 132.040251 -264.549958) (xy 132.013948 -264.508362) (xy 131.994657 -264.463086) (xy 131.98288 -264.415302)
			(xy 131.97892 -264.366248) (xy 131.660392 -264.366248) (xy 131.65988 -264.391694) (xy 131.651716 -264.441928)
			(xy 131.6356 -264.490202) (xy 131.611949 -264.535265) (xy 131.581376 -264.575951) (xy 131.544672 -264.611206)
			(xy 131.502788 -264.640116) (xy 131.456809 -264.661933) (xy 131.407925 -264.676093) (xy 131.357404 -264.682227)
			(xy 131.306552 -264.680178) (xy 131.256688 -264.669998) (xy 131.209102 -264.651951) (xy 131.165028 -264.626505)
			(xy 131.125606 -264.594318) (xy 131.091858 -264.556224) (xy 131.064657 -264.51321) (xy 131.044709 -264.46639)
			(xy 131.03253 -264.416976) (xy 131.028435 -264.366248) (xy 130.710178 -264.366248) (xy 130.709683 -264.390855)
			(xy 130.701788 -264.439432) (xy 130.686204 -264.486113) (xy 130.663333 -264.52969) (xy 130.633768 -264.569034)
			(xy 130.598275 -264.603126) (xy 130.557772 -264.631082) (xy 130.51331 -264.65218) (xy 130.466039 -264.665872)
			(xy 130.417184 -264.671804) (xy 130.368009 -264.669823) (xy 130.31979 -264.659979) (xy 130.273774 -264.642527)
			(xy 130.231153 -264.61792) (xy 130.193032 -264.586795) (xy 130.160397 -264.549958) (xy 130.134094 -264.508362)
			(xy 130.114803 -264.463086) (xy 130.103026 -264.415302) (xy 130.099066 -264.366248) (xy 129.780538 -264.366248)
			(xy 129.780026 -264.391694) (xy 129.771862 -264.441928) (xy 129.755746 -264.490202) (xy 129.732095 -264.535265)
			(xy 129.701522 -264.575951) (xy 129.664818 -264.611206) (xy 129.622934 -264.640116) (xy 129.576955 -264.661933)
			(xy 129.528071 -264.676093) (xy 129.47755 -264.682227) (xy 129.426698 -264.680178) (xy 129.376834 -264.669998)
			(xy 129.329248 -264.651951) (xy 129.285174 -264.626505) (xy 129.245752 -264.594318) (xy 129.212004 -264.556224)
			(xy 129.184803 -264.51321) (xy 129.164855 -264.46639) (xy 129.152676 -264.416976) (xy 129.148581 -264.366248)
			(xy 128.840484 -264.366248) (xy 128.839972 -264.391694) (xy 128.831808 -264.441928) (xy 128.815692 -264.490202)
			(xy 128.792041 -264.535265) (xy 128.761468 -264.575951) (xy 128.724764 -264.611206) (xy 128.68288 -264.640116)
			(xy 128.636901 -264.661933) (xy 128.588017 -264.676093) (xy 128.537496 -264.682227) (xy 128.486644 -264.680178)
			(xy 128.43678 -264.669998) (xy 128.389194 -264.651951) (xy 128.34512 -264.626505) (xy 128.305698 -264.594318)
			(xy 128.27195 -264.556224) (xy 128.244749 -264.51321) (xy 128.224801 -264.46639) (xy 128.212622 -264.416976)
			(xy 128.208527 -264.366248) (xy 126.949962 -264.366248) (xy 126.949467 -264.390855) (xy 126.941572 -264.439432)
			(xy 126.925988 -264.486113) (xy 126.903117 -264.52969) (xy 126.873552 -264.569034) (xy 126.838059 -264.603126)
			(xy 126.797556 -264.631082) (xy 126.753094 -264.65218) (xy 126.705823 -264.665872) (xy 126.656968 -264.671804)
			(xy 126.607793 -264.669823) (xy 126.559574 -264.659979) (xy 126.513558 -264.642527) (xy 126.470937 -264.61792)
			(xy 126.432816 -264.586795) (xy 126.400181 -264.549958) (xy 126.373878 -264.508362) (xy 126.354587 -264.463086)
			(xy 126.34281 -264.415302) (xy 126.33885 -264.366248) (xy 125.070108 -264.366248) (xy 125.069613 -264.390855)
			(xy 125.061718 -264.439432) (xy 125.046134 -264.486113) (xy 125.023263 -264.52969) (xy 124.993698 -264.569034)
			(xy 124.958205 -264.603126) (xy 124.917702 -264.631082) (xy 124.87324 -264.65218) (xy 124.825969 -264.665872)
			(xy 124.777114 -264.671804) (xy 124.727939 -264.669823) (xy 124.67972 -264.659979) (xy 124.633704 -264.642527)
			(xy 124.591083 -264.61792) (xy 124.552962 -264.586795) (xy 124.520327 -264.549958) (xy 124.494024 -264.508362)
			(xy 124.474733 -264.463086) (xy 124.462956 -264.415302) (xy 124.458996 -264.366248) (xy 123.19 -264.366248)
			(xy 123.189505 -264.390855) (xy 123.18161 -264.439432) (xy 123.166026 -264.486113) (xy 123.143155 -264.52969)
			(xy 123.11359 -264.569034) (xy 123.078097 -264.603126) (xy 123.037594 -264.631082) (xy 122.993132 -264.65218)
			(xy 122.945861 -264.665872) (xy 122.897006 -264.671804) (xy 122.847831 -264.669823) (xy 122.799612 -264.659979)
			(xy 122.753596 -264.642527) (xy 122.710975 -264.61792) (xy 122.672854 -264.586795) (xy 122.640219 -264.549958)
			(xy 122.613916 -264.508362) (xy 122.594625 -264.463086) (xy 122.582848 -264.415302) (xy 122.578888 -264.366248)
			(xy 121.310867 -264.366248) (xy 121.310908 -264.36828) (xy 121.310413 -264.392887) (xy 121.302518 -264.441464)
			(xy 121.286934 -264.488145) (xy 121.264063 -264.531722) (xy 121.234498 -264.571066) (xy 121.199005 -264.605158)
			(xy 121.158502 -264.633114) (xy 121.11404 -264.654212) (xy 121.066769 -264.667904) (xy 121.017914 -264.673836)
			(xy 120.968739 -264.671855) (xy 120.92052 -264.662011) (xy 120.874504 -264.644559) (xy 120.831883 -264.619952)
			(xy 120.793762 -264.588827) (xy 120.761127 -264.55199) (xy 120.734824 -264.510394) (xy 120.715533 -264.465118)
			(xy 120.703756 -264.417334) (xy 120.699796 -264.36828) (xy 119.433086 -264.36828) (xy 119.432591 -264.392887)
			(xy 119.424696 -264.441464) (xy 119.409112 -264.488145) (xy 119.386241 -264.531722) (xy 119.356676 -264.571066)
			(xy 119.321183 -264.605158) (xy 119.28068 -264.633114) (xy 119.236218 -264.654212) (xy 119.188947 -264.667904)
			(xy 119.140092 -264.673836) (xy 119.090917 -264.671855) (xy 119.042698 -264.662011) (xy 118.996682 -264.644559)
			(xy 118.954061 -264.619952) (xy 118.91594 -264.588827) (xy 118.883305 -264.55199) (xy 118.857002 -264.510394)
			(xy 118.837711 -264.465118) (xy 118.825934 -264.417334) (xy 118.821974 -264.36828) (xy 117.553232 -264.36828)
			(xy 117.552737 -264.392887) (xy 117.544842 -264.441464) (xy 117.529258 -264.488145) (xy 117.506387 -264.531722)
			(xy 117.476822 -264.571066) (xy 117.441329 -264.605158) (xy 117.400826 -264.633114) (xy 117.356364 -264.654212)
			(xy 117.309093 -264.667904) (xy 117.260238 -264.673836) (xy 117.211063 -264.671855) (xy 117.162844 -264.662011)
			(xy 117.116828 -264.644559) (xy 117.074207 -264.619952) (xy 117.036086 -264.588827) (xy 117.003451 -264.55199)
			(xy 116.977148 -264.510394) (xy 116.957857 -264.465118) (xy 116.94608 -264.417334) (xy 116.94212 -264.36828)
			(xy 115.673124 -264.36828) (xy 115.672629 -264.392887) (xy 115.664734 -264.441464) (xy 115.64915 -264.488145)
			(xy 115.626279 -264.531722) (xy 115.596714 -264.571066) (xy 115.561221 -264.605158) (xy 115.520718 -264.633114)
			(xy 115.476256 -264.654212) (xy 115.428985 -264.667904) (xy 115.38013 -264.673836) (xy 115.330955 -264.671855)
			(xy 115.282736 -264.662011) (xy 115.23672 -264.644559) (xy 115.194099 -264.619952) (xy 115.155978 -264.588827)
			(xy 115.123343 -264.55199) (xy 115.09704 -264.510394) (xy 115.077749 -264.465118) (xy 115.065972 -264.417334)
			(xy 115.062012 -264.36828) (xy 108.1532 -264.36828) (xy 108.152705 -264.392887) (xy 108.14481 -264.441464)
			(xy 108.129226 -264.488145) (xy 108.106355 -264.531722) (xy 108.07679 -264.571066) (xy 108.041297 -264.605158)
			(xy 108.000794 -264.633114) (xy 107.956332 -264.654212) (xy 107.909061 -264.667904) (xy 107.860206 -264.673836)
			(xy 107.811031 -264.671855) (xy 107.762812 -264.662011) (xy 107.716796 -264.644559) (xy 107.674175 -264.619952)
			(xy 107.636054 -264.588827) (xy 107.603419 -264.55199) (xy 107.577116 -264.510394) (xy 107.557825 -264.465118)
			(xy 107.546048 -264.417334) (xy 107.542088 -264.36828) (xy 106.273346 -264.36828) (xy 106.272851 -264.392887)
			(xy 106.264956 -264.441464) (xy 106.249372 -264.488145) (xy 106.226501 -264.531722) (xy 106.196936 -264.571066)
			(xy 106.161443 -264.605158) (xy 106.12094 -264.633114) (xy 106.076478 -264.654212) (xy 106.029207 -264.667904)
			(xy 105.980352 -264.673836) (xy 105.931177 -264.671855) (xy 105.882958 -264.662011) (xy 105.836942 -264.644559)
			(xy 105.794321 -264.619952) (xy 105.7562 -264.588827) (xy 105.723565 -264.55199) (xy 105.697262 -264.510394)
			(xy 105.677971 -264.465118) (xy 105.666194 -264.417334) (xy 105.662234 -264.36828) (xy 104.393238 -264.36828)
			(xy 104.392743 -264.392887) (xy 104.384848 -264.441464) (xy 104.369264 -264.488145) (xy 104.346393 -264.531722)
			(xy 104.316828 -264.571066) (xy 104.281335 -264.605158) (xy 104.240832 -264.633114) (xy 104.19637 -264.654212)
			(xy 104.149099 -264.667904) (xy 104.100244 -264.673836) (xy 104.051069 -264.671855) (xy 104.00285 -264.662011)
			(xy 103.956834 -264.644559) (xy 103.914213 -264.619952) (xy 103.876092 -264.588827) (xy 103.843457 -264.55199)
			(xy 103.817154 -264.510394) (xy 103.797863 -264.465118) (xy 103.786086 -264.417334) (xy 103.782126 -264.36828)
			(xy 102.58298 -264.36828) (xy 102.515162 -264.436098) (xy 102.507542 -264.44575) (xy 102.504748 -264.450576)
			(xy 102.503478 -264.453878) (xy 102.502716 -264.456926) (xy 102.494946 -264.480316) (xy 102.472938 -264.524414)
			(xy 102.444135 -264.564407) (xy 102.409284 -264.599254) (xy 102.369289 -264.628054) (xy 102.325188 -264.650057)
			(xy 102.301802 -264.65784) (xy 102.298754 -264.658602) (xy 102.295452 -264.659872) (xy 102.290626 -264.662666)
			(xy 102.280974 -264.670286) (xy 102.088696 -264.862564) (xy 111.234223 -264.862564) (xy 111.238253 -264.810066)
			(xy 111.25025 -264.758798) (xy 111.269933 -264.709963) (xy 111.296839 -264.664704) (xy 111.330339 -264.624083)
			(xy 111.369647 -264.589052) (xy 111.413842 -264.560432) (xy 111.461887 -264.538893) (xy 111.512658 -264.524941)
			(xy 111.564963 -264.518903) (xy 111.617577 -264.52092) (xy 111.669267 -264.530944) (xy 111.71882 -264.548742)
			(xy 111.765076 -264.573895) (xy 111.80695 -264.605814) (xy 111.843462 -264.643752) (xy 111.873754 -264.686818)
			(xy 111.897117 -264.734003) (xy 111.913003 -264.784202) (xy 111.92104 -264.836238) (xy 111.921544 -264.862564)
			(xy 111.92104 -264.88889) (xy 111.913003 -264.940926) (xy 111.897117 -264.991125) (xy 111.873754 -265.03831)
			(xy 111.843462 -265.081376) (xy 111.80695 -265.119314) (xy 111.765076 -265.151233) (xy 111.719063 -265.176254)
			(xy 121.168934 -265.176254) (xy 121.172894 -265.1272) (xy 121.184671 -265.079416) (xy 121.203962 -265.03414)
			(xy 121.230265 -264.992544) (xy 121.2629 -264.955707) (xy 121.301021 -264.924582) (xy 121.343642 -264.899975)
			(xy 121.389658 -264.882523) (xy 121.437877 -264.872679) (xy 121.487052 -264.870698) (xy 121.535907 -264.87663)
			(xy 121.583178 -264.890322) (xy 121.62764 -264.91142) (xy 121.668143 -264.939376) (xy 121.703636 -264.973468)
			(xy 121.733201 -265.012812) (xy 121.756072 -265.056389) (xy 121.771656 -265.10307) (xy 121.779551 -265.151647)
			(xy 121.780046 -265.176254) (xy 123.049042 -265.176254) (xy 123.053002 -265.1272) (xy 123.064779 -265.079416)
			(xy 123.08407 -265.03414) (xy 123.110373 -264.992544) (xy 123.143008 -264.955707) (xy 123.181129 -264.924582)
			(xy 123.22375 -264.899975) (xy 123.269766 -264.882523) (xy 123.317985 -264.872679) (xy 123.36716 -264.870698)
			(xy 123.416015 -264.87663) (xy 123.463286 -264.890322) (xy 123.507748 -264.91142) (xy 123.548251 -264.939376)
			(xy 123.583744 -264.973468) (xy 123.613309 -265.012812) (xy 123.63618 -265.056389) (xy 123.651764 -265.10307)
			(xy 123.659659 -265.151647) (xy 123.660154 -265.176254) (xy 124.928896 -265.176254) (xy 124.932856 -265.1272)
			(xy 124.944633 -265.079416) (xy 124.963924 -265.03414) (xy 124.990227 -264.992544) (xy 125.022862 -264.955707)
			(xy 125.060983 -264.924582) (xy 125.103604 -264.899975) (xy 125.14962 -264.882523) (xy 125.197839 -264.872679)
			(xy 125.247014 -264.870698) (xy 125.295869 -264.87663) (xy 125.34314 -264.890322) (xy 125.387602 -264.91142)
			(xy 125.428105 -264.939376) (xy 125.463598 -264.973468) (xy 125.493163 -265.012812) (xy 125.516034 -265.056389)
			(xy 125.531618 -265.10307) (xy 125.539513 -265.151647) (xy 125.540008 -265.176254) (xy 126.809004 -265.176254)
			(xy 126.812964 -265.1272) (xy 126.824741 -265.079416) (xy 126.844032 -265.03414) (xy 126.870335 -264.992544)
			(xy 126.90297 -264.955707) (xy 126.941091 -264.924582) (xy 126.983712 -264.899975) (xy 127.029728 -264.882523)
			(xy 127.077947 -264.872679) (xy 127.127122 -264.870698) (xy 127.175977 -264.87663) (xy 127.223248 -264.890322)
			(xy 127.26771 -264.91142) (xy 127.308213 -264.939376) (xy 127.343706 -264.973468) (xy 127.373271 -265.012812)
			(xy 127.396142 -265.056389) (xy 127.411726 -265.10307) (xy 127.419621 -265.151647) (xy 127.420116 -265.176254)
			(xy 127.738627 -265.176254) (xy 127.742722 -265.125526) (xy 127.754901 -265.076112) (xy 127.774849 -265.029292)
			(xy 127.80205 -264.986278) (xy 127.835798 -264.948184) (xy 127.87522 -264.915997) (xy 127.919294 -264.890551)
			(xy 127.96688 -264.872504) (xy 128.016744 -264.862324) (xy 128.067596 -264.860275) (xy 128.118117 -264.866409)
			(xy 128.167001 -264.880569) (xy 128.21298 -264.902386) (xy 128.254864 -264.931296) (xy 128.291568 -264.966551)
			(xy 128.322141 -265.007237) (xy 128.345792 -265.0523) (xy 128.361908 -265.100574) (xy 128.370072 -265.150808)
			(xy 128.370584 -265.176254) (xy 128.688858 -265.176254) (xy 128.692818 -265.1272) (xy 128.704595 -265.079416)
			(xy 128.723886 -265.03414) (xy 128.750189 -264.992544) (xy 128.782824 -264.955707) (xy 128.820945 -264.924582)
			(xy 128.863566 -264.899975) (xy 128.909582 -264.882523) (xy 128.957801 -264.872679) (xy 129.006976 -264.870698)
			(xy 129.055831 -264.87663) (xy 129.103102 -264.890322) (xy 129.147564 -264.91142) (xy 129.188067 -264.939376)
			(xy 129.22356 -264.973468) (xy 129.253125 -265.012812) (xy 129.275996 -265.056389) (xy 129.29158 -265.10307)
			(xy 129.299475 -265.151647) (xy 129.29997 -265.176254) (xy 129.628912 -265.176254) (xy 129.632872 -265.1272)
			(xy 129.644649 -265.079416) (xy 129.66394 -265.03414) (xy 129.690243 -264.992544) (xy 129.722878 -264.955707)
			(xy 129.760999 -264.924582) (xy 129.80362 -264.899975) (xy 129.849636 -264.882523) (xy 129.897855 -264.872679)
			(xy 129.94703 -264.870698) (xy 129.995885 -264.87663) (xy 130.043156 -264.890322) (xy 130.087618 -264.91142)
			(xy 130.128121 -264.939376) (xy 130.163614 -264.973468) (xy 130.193179 -265.012812) (xy 130.21605 -265.056389)
			(xy 130.231634 -265.10307) (xy 130.239529 -265.151647) (xy 130.240024 -265.176254) (xy 130.568966 -265.176254)
			(xy 130.572926 -265.1272) (xy 130.584703 -265.079416) (xy 130.603994 -265.03414) (xy 130.630297 -264.992544)
			(xy 130.662932 -264.955707) (xy 130.701053 -264.924582) (xy 130.743674 -264.899975) (xy 130.78969 -264.882523)
			(xy 130.837909 -264.872679) (xy 130.887084 -264.870698) (xy 130.935939 -264.87663) (xy 130.98321 -264.890322)
			(xy 131.027672 -264.91142) (xy 131.068175 -264.939376) (xy 131.103668 -264.973468) (xy 131.133233 -265.012812)
			(xy 131.156104 -265.056389) (xy 131.171688 -265.10307) (xy 131.179583 -265.151647) (xy 131.180078 -265.176254)
			(xy 131.498589 -265.176254) (xy 131.502684 -265.125526) (xy 131.514863 -265.076112) (xy 131.534811 -265.029292)
			(xy 131.562012 -264.986278) (xy 131.59576 -264.948184) (xy 131.635182 -264.915997) (xy 131.679256 -264.890551)
			(xy 131.726842 -264.872504) (xy 131.776706 -264.862324) (xy 131.827558 -264.860275) (xy 131.878079 -264.866409)
			(xy 131.926963 -264.880569) (xy 131.972942 -264.902386) (xy 132.014826 -264.931296) (xy 132.05153 -264.966551)
			(xy 132.082103 -265.007237) (xy 132.105754 -265.0523) (xy 132.12187 -265.100574) (xy 132.130034 -265.150808)
			(xy 132.130546 -265.176254) (xy 132.44882 -265.176254) (xy 132.45278 -265.1272) (xy 132.464557 -265.079416)
			(xy 132.483848 -265.03414) (xy 132.510151 -264.992544) (xy 132.542786 -264.955707) (xy 132.580907 -264.924582)
			(xy 132.623528 -264.899975) (xy 132.669544 -264.882523) (xy 132.717763 -264.872679) (xy 132.766938 -264.870698)
			(xy 132.815793 -264.87663) (xy 132.863064 -264.890322) (xy 132.907526 -264.91142) (xy 132.948029 -264.939376)
			(xy 132.983522 -264.973468) (xy 133.013087 -265.012812) (xy 133.035958 -265.056389) (xy 133.051542 -265.10307)
			(xy 133.059437 -265.151647) (xy 133.059932 -265.176254) (xy 133.059437 -265.200861) (xy 133.051542 -265.249438)
			(xy 133.035958 -265.296119) (xy 133.013087 -265.339696) (xy 132.983522 -265.37904) (xy 132.948029 -265.413132)
			(xy 132.907526 -265.441088) (xy 132.863064 -265.462186) (xy 132.815793 -265.475878) (xy 132.766938 -265.48181)
			(xy 132.717763 -265.479829) (xy 132.669544 -265.469985) (xy 132.623528 -265.452533) (xy 132.580907 -265.427926)
			(xy 132.542786 -265.396801) (xy 132.510151 -265.359964) (xy 132.483848 -265.318368) (xy 132.464557 -265.273092)
			(xy 132.45278 -265.225308) (xy 132.44882 -265.176254) (xy 132.130546 -265.176254) (xy 132.130034 -265.2017)
			(xy 132.12187 -265.251934) (xy 132.105754 -265.300208) (xy 132.082103 -265.345271) (xy 132.05153 -265.385957)
			(xy 132.014826 -265.421212) (xy 131.972942 -265.450122) (xy 131.926963 -265.471939) (xy 131.878079 -265.486099)
			(xy 131.827558 -265.492233) (xy 131.776706 -265.490184) (xy 131.726842 -265.480004) (xy 131.679256 -265.461957)
			(xy 131.635182 -265.436511) (xy 131.59576 -265.404324) (xy 131.562012 -265.36623) (xy 131.534811 -265.323216)
			(xy 131.514863 -265.276396) (xy 131.502684 -265.226982) (xy 131.498589 -265.176254) (xy 131.180078 -265.176254)
			(xy 131.179583 -265.200861) (xy 131.171688 -265.249438) (xy 131.156104 -265.296119) (xy 131.133233 -265.339696)
			(xy 131.103668 -265.37904) (xy 131.068175 -265.413132) (xy 131.027672 -265.441088) (xy 130.98321 -265.462186)
			(xy 130.935939 -265.475878) (xy 130.887084 -265.48181) (xy 130.837909 -265.479829) (xy 130.78969 -265.469985)
			(xy 130.743674 -265.452533) (xy 130.701053 -265.427926) (xy 130.662932 -265.396801) (xy 130.630297 -265.359964)
			(xy 130.603994 -265.318368) (xy 130.584703 -265.273092) (xy 130.572926 -265.225308) (xy 130.568966 -265.176254)
			(xy 130.240024 -265.176254) (xy 130.239529 -265.200861) (xy 130.231634 -265.249438) (xy 130.21605 -265.296119)
			(xy 130.193179 -265.339696) (xy 130.163614 -265.37904) (xy 130.128121 -265.413132) (xy 130.087618 -265.441088)
			(xy 130.043156 -265.462186) (xy 129.995885 -265.475878) (xy 129.94703 -265.48181) (xy 129.897855 -265.479829)
			(xy 129.849636 -265.469985) (xy 129.80362 -265.452533) (xy 129.760999 -265.427926) (xy 129.722878 -265.396801)
			(xy 129.690243 -265.359964) (xy 129.66394 -265.318368) (xy 129.644649 -265.273092) (xy 129.632872 -265.225308)
			(xy 129.628912 -265.176254) (xy 129.29997 -265.176254) (xy 129.299475 -265.200861) (xy 129.29158 -265.249438)
			(xy 129.275996 -265.296119) (xy 129.253125 -265.339696) (xy 129.22356 -265.37904) (xy 129.188067 -265.413132)
			(xy 129.147564 -265.441088) (xy 129.103102 -265.462186) (xy 129.055831 -265.475878) (xy 129.006976 -265.48181)
			(xy 128.957801 -265.479829) (xy 128.909582 -265.469985) (xy 128.863566 -265.452533) (xy 128.820945 -265.427926)
			(xy 128.782824 -265.396801) (xy 128.750189 -265.359964) (xy 128.723886 -265.318368) (xy 128.704595 -265.273092)
			(xy 128.692818 -265.225308) (xy 128.688858 -265.176254) (xy 128.370584 -265.176254) (xy 128.370072 -265.2017)
			(xy 128.361908 -265.251934) (xy 128.345792 -265.300208) (xy 128.322141 -265.345271) (xy 128.291568 -265.385957)
			(xy 128.254864 -265.421212) (xy 128.21298 -265.450122) (xy 128.167001 -265.471939) (xy 128.118117 -265.486099)
			(xy 128.067596 -265.492233) (xy 128.016744 -265.490184) (xy 127.96688 -265.480004) (xy 127.919294 -265.461957)
			(xy 127.87522 -265.436511) (xy 127.835798 -265.404324) (xy 127.80205 -265.36623) (xy 127.774849 -265.323216)
			(xy 127.754901 -265.276396) (xy 127.742722 -265.226982) (xy 127.738627 -265.176254) (xy 127.420116 -265.176254)
			(xy 127.419621 -265.200861) (xy 127.411726 -265.249438) (xy 127.396142 -265.296119) (xy 127.373271 -265.339696)
			(xy 127.343706 -265.37904) (xy 127.308213 -265.413132) (xy 127.26771 -265.441088) (xy 127.223248 -265.462186)
			(xy 127.175977 -265.475878) (xy 127.127122 -265.48181) (xy 127.077947 -265.479829) (xy 127.029728 -265.469985)
			(xy 126.983712 -265.452533) (xy 126.941091 -265.427926) (xy 126.90297 -265.396801) (xy 126.870335 -265.359964)
			(xy 126.844032 -265.318368) (xy 126.824741 -265.273092) (xy 126.812964 -265.225308) (xy 126.809004 -265.176254)
			(xy 125.540008 -265.176254) (xy 125.539513 -265.200861) (xy 125.531618 -265.249438) (xy 125.516034 -265.296119)
			(xy 125.493163 -265.339696) (xy 125.463598 -265.37904) (xy 125.428105 -265.413132) (xy 125.387602 -265.441088)
			(xy 125.34314 -265.462186) (xy 125.295869 -265.475878) (xy 125.247014 -265.48181) (xy 125.197839 -265.479829)
			(xy 125.14962 -265.469985) (xy 125.103604 -265.452533) (xy 125.060983 -265.427926) (xy 125.022862 -265.396801)
			(xy 124.990227 -265.359964) (xy 124.963924 -265.318368) (xy 124.944633 -265.273092) (xy 124.932856 -265.225308)
			(xy 124.928896 -265.176254) (xy 123.660154 -265.176254) (xy 123.659659 -265.200861) (xy 123.651764 -265.249438)
			(xy 123.63618 -265.296119) (xy 123.613309 -265.339696) (xy 123.583744 -265.37904) (xy 123.548251 -265.413132)
			(xy 123.507748 -265.441088) (xy 123.463286 -265.462186) (xy 123.416015 -265.475878) (xy 123.36716 -265.48181)
			(xy 123.317985 -265.479829) (xy 123.269766 -265.469985) (xy 123.22375 -265.452533) (xy 123.181129 -265.427926)
			(xy 123.143008 -265.396801) (xy 123.110373 -265.359964) (xy 123.08407 -265.318368) (xy 123.064779 -265.273092)
			(xy 123.053002 -265.225308) (xy 123.049042 -265.176254) (xy 121.780046 -265.176254) (xy 121.779551 -265.200861)
			(xy 121.771656 -265.249438) (xy 121.756072 -265.296119) (xy 121.733201 -265.339696) (xy 121.703636 -265.37904)
			(xy 121.668143 -265.413132) (xy 121.62764 -265.441088) (xy 121.583178 -265.462186) (xy 121.535907 -265.475878)
			(xy 121.487052 -265.48181) (xy 121.437877 -265.479829) (xy 121.389658 -265.469985) (xy 121.343642 -265.452533)
			(xy 121.301021 -265.427926) (xy 121.2629 -265.396801) (xy 121.230265 -265.359964) (xy 121.203962 -265.318368)
			(xy 121.184671 -265.273092) (xy 121.172894 -265.225308) (xy 121.168934 -265.176254) (xy 111.719063 -265.176254)
			(xy 111.71882 -265.176386) (xy 111.669267 -265.194184) (xy 111.617577 -265.204208) (xy 111.564963 -265.206225)
			(xy 111.512658 -265.200187) (xy 111.461887 -265.186235) (xy 111.413842 -265.164696) (xy 111.369647 -265.136076)
			(xy 111.330339 -265.101045) (xy 111.296839 -265.060424) (xy 111.269933 -265.015165) (xy 111.25025 -264.96633)
			(xy 111.238253 -264.915062) (xy 111.234223 -264.862564) (xy 102.088696 -264.862564) (xy 102.004114 -264.947146)
			(xy 101.998223 -264.953489) (xy 101.990705 -264.96907) (xy 101.989382 -264.977626) (xy 101.98862 -264.986262)
			(xy 101.992684 -265.003026) (xy 101.99751 -265.010646) (xy 102.009054 -265.029245) (xy 102.027278 -265.069046)
			(xy 102.039637 -265.111039) (xy 102.045876 -265.154367) (xy 102.046278 -265.176254) (xy 102.045835 -265.200249)
			(xy 102.038334 -265.247648) (xy 102.023509 -265.29329) (xy 102.001726 -265.33605) (xy 101.97352 -265.374876)
			(xy 101.939588 -265.40881) (xy 101.900764 -265.437017) (xy 101.858005 -265.458803) (xy 101.812364 -265.47363)
			(xy 101.764965 -265.481134) (xy 101.74097 -265.481562) (xy 101.719082 -265.481184) (xy 101.675756 -265.474933)
			(xy 101.633765 -265.462563) (xy 101.593968 -265.444328) (xy 101.575362 -265.432794) (xy 101.567833 -265.428335)
			(xy 101.550817 -265.424305) (xy 101.542088 -265.42492) (xy 101.533706 -265.425682) (xy 101.518212 -265.433048)
			(xy 101.066092 -265.885168) (xy 101.063386 -265.888019) (xy 101.058793 -265.894398) (xy 101.056948 -265.897868)
			(xy 101.054365 -265.903295) (xy 101.051545 -265.914975) (xy 101.05136 -265.920982) (xy 101.05136 -265.98626)
			(xy 101.90532 -265.98626) (xy 101.90928 -265.937206) (xy 101.921057 -265.889422) (xy 101.940348 -265.844146)
			(xy 101.966651 -265.80255) (xy 101.999286 -265.765713) (xy 102.037407 -265.734588) (xy 102.080028 -265.709981)
			(xy 102.126044 -265.692529) (xy 102.174263 -265.682685) (xy 102.223438 -265.680704) (xy 102.272293 -265.686636)
			(xy 102.319564 -265.700328) (xy 102.364026 -265.721426) (xy 102.404529 -265.749382) (xy 102.440022 -265.783474)
			(xy 102.469587 -265.822818) (xy 102.492458 -265.866395) (xy 102.508042 -265.913076) (xy 102.515937 -265.961653)
			(xy 102.516432 -265.98626) (xy 102.515937 -266.010867) (xy 102.508042 -266.059444) (xy 102.492458 -266.106125)
			(xy 102.469587 -266.149702) (xy 102.440022 -266.189046) (xy 102.404529 -266.223138) (xy 102.364026 -266.251094)
			(xy 102.319564 -266.272192) (xy 102.272293 -266.285884) (xy 102.223438 -266.291816) (xy 102.174263 -266.289835)
			(xy 102.126044 -266.279991) (xy 102.080028 -266.262539) (xy 102.037407 -266.237932) (xy 101.999286 -266.206807)
			(xy 101.966651 -266.16997) (xy 101.940348 -266.128374) (xy 101.921057 -266.083098) (xy 101.90928 -266.035314)
			(xy 101.90532 -265.98626) (xy 101.05136 -265.98626) (xy 101.05136 -266.60602) (xy 101.051557 -266.612687)
			(xy 101.055034 -266.625559) (xy 101.058218 -266.63142) (xy 101.069641 -266.649961) (xy 101.087692 -266.689591)
			(xy 101.09993 -266.731384) (xy 101.106107 -266.774492) (xy 101.106478 -266.796266) (xy 101.105797 -266.825448)
			(xy 101.09467 -266.882742) (xy 101.08438 -266.910058) (xy 101.08438 -266.910566) (xy 101.081954 -266.917472)
			(xy 101.080657 -266.932045) (xy 101.08184 -266.939268) (xy 101.08184 -266.939522) (xy 101.083595 -266.946798)
			(xy 101.090696 -266.959965) (xy 101.09581 -266.96543) (xy 101.288342 -267.157962) (xy 101.293844 -267.162943)
			(xy 101.307013 -267.169775) (xy 101.31425 -267.171424) (xy 101.323902 -267.17244) (xy 101.440742 -267.17244)
			(xy 101.441504 -267.17244) (xy 101.450167 -267.171971) (xy 101.466426 -267.165952) (xy 101.47974 -267.154845)
			(xy 101.48443 -267.147548) (xy 101.487224 -267.14196) (xy 101.524816 -267.056616) (xy 101.527532 -267.049785)
			(xy 101.529334 -267.035202) (xy 101.528372 -267.027914) (xy 101.527356 -267.02131) (xy 101.521006 -267.008102)
			(xy 101.515672 -267.00226) (xy 101.50071 -266.985286) (xy 101.475441 -266.947755) (xy 101.455983 -266.906907)
			(xy 101.442761 -266.863636) (xy 101.436065 -266.818889) (xy 101.435662 -266.796266) (xy 101.436184 -266.771011)
			(xy 101.444497 -266.721189) (xy 101.460898 -266.673415) (xy 101.484939 -266.628992) (xy 101.515963 -266.589132)
			(xy 101.553125 -266.554922) (xy 101.595411 -266.527296) (xy 101.641667 -266.507006) (xy 101.690632 -266.494606)
			(xy 101.74097 -266.490435) (xy 101.791308 -266.494606) (xy 101.840273 -266.507006) (xy 101.886529 -266.527296)
			(xy 101.928815 -266.554922) (xy 101.965977 -266.589132) (xy 101.997001 -266.628992) (xy 102.021042 -266.673415)
			(xy 102.037443 -266.721189) (xy 102.045756 -266.771011) (xy 102.046278 -266.796266) (xy 102.045869 -266.81889)
			(xy 102.039191 -266.863641) (xy 102.025977 -266.906916) (xy 102.006516 -266.947764) (xy 101.981235 -266.985289)
			(xy 101.966268 -267.00226) (xy 101.966014 -267.002514) (xy 101.96126 -267.008093) (xy 101.954813 -267.021247)
			(xy 101.953314 -267.028422) (xy 101.952298 -267.03528) (xy 101.954076 -267.049758) (xy 101.994716 -267.14196)
			(xy 101.99751 -267.147548) (xy 102.002231 -267.154819) (xy 102.015537 -267.165912) (xy 102.031781 -267.171933)
			(xy 102.040436 -267.17244) (xy 102.859078 -267.17244) (xy 102.86873 -267.171424) (xy 102.875974 -267.169797)
			(xy 102.889143 -267.162956) (xy 102.894638 -267.157962) (xy 103.31323 -266.73937) (xy 103.321358 -266.728702)
			(xy 103.32466 -266.723114) (xy 103.326438 -266.716764) (xy 103.333912 -266.691272) (xy 103.35642 -266.643158)
			(xy 103.386915 -266.599665) (xy 103.424476 -266.562106) (xy 103.467971 -266.531613) (xy 103.516086 -266.509107)
			(xy 103.541576 -266.501626) (xy 103.547926 -266.499848) (xy 103.553514 -266.496546) (xy 103.564182 -266.488418)
			(xy 103.723694 -266.328906) (xy 103.730431 -266.322671) (xy 103.747089 -266.314986) (xy 103.756206 -266.31392)
			(xy 103.768144 -266.313158) (xy 103.778558 -266.306808) (xy 103.78436 -266.303109) (xy 103.793897 -266.293199)
			(xy 103.797354 -266.28725) (xy 103.803704 -266.275566) (xy 103.839772 -266.207494) (xy 103.842753 -266.201386)
			(xy 103.845721 -266.188127) (xy 103.845614 -266.181332) (xy 103.845106 -266.16787) (xy 103.837232 -266.156186)
			(xy 103.837232 -266.155932) (xy 103.825065 -266.137002) (xy 103.805819 -266.096325) (xy 103.792739 -266.053268)
			(xy 103.786109 -266.00876) (xy 103.78567 -265.98626) (xy 103.786192 -265.961005) (xy 103.794505 -265.911183)
			(xy 103.810906 -265.863409) (xy 103.834947 -265.818986) (xy 103.865971 -265.779126) (xy 103.903133 -265.744916)
			(xy 103.945419 -265.71729) (xy 103.991675 -265.697) (xy 104.04064 -265.6846) (xy 104.090978 -265.680429)
			(xy 104.141316 -265.6846) (xy 104.190281 -265.697) (xy 104.236537 -265.71729) (xy 104.278823 -265.744916)
			(xy 104.315985 -265.779126) (xy 104.347009 -265.818986) (xy 104.37105 -265.863409) (xy 104.387451 -265.911183)
			(xy 104.395764 -265.961005) (xy 104.396286 -265.98626) (xy 105.665282 -265.98626) (xy 105.669242 -265.937206)
			(xy 105.681019 -265.889422) (xy 105.70031 -265.844146) (xy 105.726613 -265.80255) (xy 105.759248 -265.765713)
			(xy 105.797369 -265.734588) (xy 105.83999 -265.709981) (xy 105.886006 -265.692529) (xy 105.934225 -265.682685)
			(xy 105.9834 -265.680704) (xy 106.032255 -265.686636) (xy 106.079526 -265.700328) (xy 106.123988 -265.721426)
			(xy 106.164491 -265.749382) (xy 106.199984 -265.783474) (xy 106.229549 -265.822818) (xy 106.25242 -265.866395)
			(xy 106.268004 -265.913076) (xy 106.275899 -265.961653) (xy 106.276394 -265.98626) (xy 106.275899 -266.010867)
			(xy 106.268004 -266.059444) (xy 106.25242 -266.106125) (xy 106.229549 -266.149702) (xy 106.199984 -266.189046)
			(xy 106.164491 -266.223138) (xy 106.123988 -266.251094) (xy 106.079526 -266.272192) (xy 106.032255 -266.285884)
			(xy 105.9834 -266.291816) (xy 105.934225 -266.289835) (xy 105.886006 -266.279991) (xy 105.83999 -266.262539)
			(xy 105.797369 -266.237932) (xy 105.759248 -266.206807) (xy 105.726613 -266.16997) (xy 105.70031 -266.128374)
			(xy 105.681019 -266.083098) (xy 105.669242 -266.035314) (xy 105.665282 -265.98626) (xy 104.396286 -265.98626)
			(xy 104.395892 -266.008764) (xy 104.389289 -266.053285) (xy 104.376206 -266.09635) (xy 104.356929 -266.137021)
			(xy 104.344724 -266.155932) (xy 104.344724 -266.156186) (xy 104.34447 -266.156186) (xy 104.340893 -266.162019)
			(xy 104.336638 -266.17502) (xy 104.336088 -266.18184) (xy 104.33558 -266.195556) (xy 104.385618 -266.288774)
			(xy 104.390384 -266.296197) (xy 104.40392 -266.307487) (xy 104.420493 -266.31349) (xy 104.429306 -266.31392)
			(xy 105.261918 -266.31392) (xy 105.271986 -266.314347) (xy 105.290584 -266.322068) (xy 105.297986 -266.328906)
			(xy 105.445814 -266.476734) (xy 105.449685 -266.4804) (xy 105.458651 -266.486167) (xy 105.463594 -266.488164)
			(xy 105.4735 -266.491974) (xy 105.484422 -266.491466) (xy 105.500932 -266.490958) (xy 105.524923 -266.491431)
			(xy 105.572312 -266.498941) (xy 105.617944 -266.513771) (xy 105.660695 -266.535555) (xy 105.699512 -266.563759)
			(xy 105.73344 -266.597686) (xy 105.761644 -266.636503) (xy 105.783429 -266.679254) (xy 105.798259 -266.724886)
			(xy 105.805769 -266.772275) (xy 105.80624 -266.796266) (xy 105.805732 -266.812776) (xy 105.805224 -266.823698)
			(xy 105.809034 -266.833604) (xy 105.811059 -266.838533) (xy 105.816825 -266.847491) (xy 105.820464 -266.851384)
			(xy 105.982262 -267.013182) (xy 105.987762 -267.018167) (xy 106.00093 -267.025005) (xy 106.00817 -267.026644)
			(xy 106.017822 -267.02766) (xy 106.884978 -267.02766) (xy 106.89463 -267.026644) (xy 106.901875 -267.025018)
			(xy 106.915046 -267.018179) (xy 106.920538 -267.013182) (xy 107.063032 -266.870688) (xy 107.066916 -266.866551)
			(xy 107.072939 -266.856937) (xy 107.07497 -266.851638) (xy 107.07878 -266.84097) (xy 107.07751 -266.829286)
			(xy 107.075732 -266.797028) (xy 107.075732 -266.794996) (xy 107.0763 -266.771073) (xy 107.083967 -266.723841)
			(xy 107.098911 -266.678384) (xy 107.120763 -266.635815) (xy 107.14899 -266.597177) (xy 107.1829 -266.563416)
			(xy 107.221662 -266.535359) (xy 107.264327 -266.513694) (xy 107.309849 -266.498951) (xy 107.357115 -266.491492)
			(xy 107.38104 -266.490958) (xy 107.381294 -266.490958) (xy 107.41406 -266.492736) (xy 107.425744 -266.494006)
			(xy 107.436412 -266.490196) (xy 107.441721 -266.488187) (xy 107.451332 -266.482152) (xy 107.455462 -266.478258)
			(xy 107.612434 -266.321286) (xy 107.618836 -266.314301) (xy 107.626412 -266.296948) (xy 107.627166 -266.287504)
			(xy 107.62996 -266.21867) (xy 107.630127 -266.213896) (xy 107.628855 -266.20443) (xy 107.62742 -266.199874)
			(xy 107.624372 -266.191238) (xy 107.618022 -266.183618) (xy 107.601101 -266.162771) (xy 107.574094 -266.11637)
			(xy 107.55561 -266.065964) (xy 107.546218 -266.013104) (xy 107.545632 -265.98626) (xy 107.546154 -265.961005)
			(xy 107.554467 -265.911183) (xy 107.570868 -265.863409) (xy 107.594909 -265.818986) (xy 107.625933 -265.779126)
			(xy 107.663095 -265.744916) (xy 107.705381 -265.71729) (xy 107.751637 -265.697) (xy 107.800602 -265.6846)
			(xy 107.85094 -265.680429) (xy 107.901278 -265.6846) (xy 107.950243 -265.697) (xy 107.996499 -265.71729)
			(xy 108.038785 -265.744916) (xy 108.075947 -265.779126) (xy 108.106971 -265.818986) (xy 108.131012 -265.863409)
			(xy 108.147413 -265.911183) (xy 108.155726 -265.961005) (xy 108.156248 -265.98626) (xy 109.425244 -265.98626)
			(xy 109.429204 -265.937206) (xy 109.440981 -265.889422) (xy 109.460272 -265.844146) (xy 109.486575 -265.80255)
			(xy 109.51921 -265.765713) (xy 109.557331 -265.734588) (xy 109.599952 -265.709981) (xy 109.645968 -265.692529)
			(xy 109.694187 -265.682685) (xy 109.743362 -265.680704) (xy 109.792217 -265.686636) (xy 109.839488 -265.700328)
			(xy 109.88395 -265.721426) (xy 109.924453 -265.749382) (xy 109.959946 -265.783474) (xy 109.989511 -265.822818)
			(xy 110.012382 -265.866395) (xy 110.027966 -265.913076) (xy 110.035861 -265.961653) (xy 110.036356 -265.98626)
			(xy 110.035861 -266.010867) (xy 110.027966 -266.059444) (xy 110.012382 -266.106125) (xy 109.989511 -266.149702)
			(xy 109.959946 -266.189046) (xy 109.924453 -266.223138) (xy 109.88395 -266.251094) (xy 109.839488 -266.272192)
			(xy 109.792217 -266.285884) (xy 109.743362 -266.291816) (xy 109.694187 -266.289835) (xy 109.645968 -266.279991)
			(xy 109.599952 -266.262539) (xy 109.557331 -266.237932) (xy 109.51921 -266.206807) (xy 109.486575 -266.16997)
			(xy 109.460272 -266.128374) (xy 109.440981 -266.083098) (xy 109.429204 -266.035314) (xy 109.425244 -265.98626)
			(xy 108.156248 -265.98626) (xy 108.155478 -266.016546) (xy 108.143442 -266.075914) (xy 108.132372 -266.104116)
			(xy 108.132118 -266.104624) (xy 108.132118 -266.104878) (xy 108.130011 -266.110536) (xy 108.128206 -266.122473)
			(xy 108.128562 -266.1285) (xy 108.129832 -266.141454) (xy 108.163614 -266.192254) (xy 108.183934 -266.222734)
			(xy 108.191452 -266.232792) (xy 108.21356 -266.244636) (xy 108.226098 -266.24534) (xy 108.784898 -266.24534)
			(xy 108.794967 -266.245764) (xy 108.813569 -266.253482) (xy 108.820966 -266.260326) (xy 109.071664 -266.511024)
			(xy 109.077412 -266.516408) (xy 109.091383 -266.523657) (xy 109.099096 -266.525248) (xy 109.106716 -266.526518)
			(xy 109.121702 -266.524486) (xy 109.129322 -266.52093) (xy 109.150006 -266.511498) (xy 109.193466 -266.498165)
			(xy 109.238419 -266.491405) (xy 109.261148 -266.490958) (xy 109.285138 -266.491432) (xy 109.332526 -266.498944)
			(xy 109.378155 -266.513775) (xy 109.420904 -266.535561) (xy 109.459719 -266.563764) (xy 109.493645 -266.597692)
			(xy 109.521847 -266.636508) (xy 109.54363 -266.679258) (xy 109.558459 -266.724888) (xy 109.565969 -266.772276)
			(xy 109.566456 -266.796266) (xy 109.566025 -266.818955) (xy 109.559265 -266.863828) (xy 109.54592 -266.9072)
			(xy 109.536484 -266.927838) (xy 109.536484 -266.928346) (xy 109.53623 -266.9286) (xy 109.533286 -266.935639)
			(xy 109.531221 -266.950747) (xy 109.532166 -266.958318) (xy 109.53369 -266.966192) (xy 109.540802 -266.980162)
			(xy 109.599222 -267.038582) (xy 109.60472 -267.043571) (xy 109.617886 -267.050419) (xy 109.62513 -267.052044)
			(xy 109.634782 -267.05306) (xy 110.811818 -267.05306) (xy 110.82147 -267.052044) (xy 110.828712 -267.050413)
			(xy 110.841876 -267.043566) (xy 110.847378 -267.038582) (xy 111.658654 -266.227306) (xy 111.666055 -266.220467)
			(xy 111.684653 -266.212752) (xy 111.694722 -266.21232) (xy 113.09731 -266.21232) (xy 113.109287 -266.211671)
			(xy 113.130624 -266.20079) (xy 113.138204 -266.191492) (xy 113.186972 -266.124944) (xy 113.190349 -266.120005)
			(xy 113.194972 -266.108973) (xy 113.196116 -266.1031) (xy 113.197894 -266.09167) (xy 113.194084 -266.079732)
			(xy 113.18722 -266.056975) (xy 113.179821 -266.010025) (xy 113.179352 -265.98626) (xy 113.179874 -265.961005)
			(xy 113.188187 -265.911183) (xy 113.204588 -265.863409) (xy 113.228629 -265.818986) (xy 113.259653 -265.779126)
			(xy 113.296815 -265.744916) (xy 113.339101 -265.71729) (xy 113.385357 -265.697) (xy 113.434322 -265.6846)
			(xy 113.48466 -265.680429) (xy 113.534998 -265.6846) (xy 113.583963 -265.697) (xy 113.630219 -265.71729)
			(xy 113.672505 -265.744916) (xy 113.709667 -265.779126) (xy 113.740691 -265.818986) (xy 113.764732 -265.863409)
			(xy 113.781133 -265.911183) (xy 113.789446 -265.961005) (xy 113.789968 -265.98626) (xy 113.789497 -266.010025)
			(xy 113.782102 -266.056976) (xy 113.775236 -266.079732) (xy 113.775236 -266.079986) (xy 113.773566 -266.085736)
			(xy 113.772668 -266.097673) (xy 113.773458 -266.103608) (xy 113.775236 -266.115038) (xy 113.831116 -266.191492)
			(xy 113.838718 -266.200757) (xy 113.860046 -266.211622) (xy 113.87201 -266.21232) (xy 114.977418 -266.21232)
			(xy 114.989394 -266.211669) (xy 115.010728 -266.200786) (xy 115.018312 -266.191492) (xy 115.06708 -266.124944)
			(xy 115.070457 -266.120005) (xy 115.075079 -266.108972) (xy 115.076224 -266.1031) (xy 115.078002 -266.09167)
			(xy 115.074192 -266.079732) (xy 115.067327 -266.056975) (xy 115.059928 -266.010025) (xy 115.05946 -265.98626)
			(xy 115.059982 -265.961005) (xy 115.068295 -265.911183) (xy 115.084696 -265.863409) (xy 115.108737 -265.818986)
			(xy 115.139761 -265.779126) (xy 115.176923 -265.744916) (xy 115.219209 -265.71729) (xy 115.265465 -265.697)
			(xy 115.31443 -265.6846) (xy 115.364768 -265.680429) (xy 115.415106 -265.6846) (xy 115.464071 -265.697)
			(xy 115.510327 -265.71729) (xy 115.552613 -265.744916) (xy 115.589775 -265.779126) (xy 115.620799 -265.818986)
			(xy 115.64484 -265.863409) (xy 115.661241 -265.911183) (xy 115.669554 -265.961005) (xy 115.670076 -265.98626)
			(xy 116.938818 -265.98626) (xy 116.942778 -265.937206) (xy 116.954555 -265.889422) (xy 116.973846 -265.844146)
			(xy 117.000149 -265.80255) (xy 117.032784 -265.765713) (xy 117.070905 -265.734588) (xy 117.113526 -265.709981)
			(xy 117.159542 -265.692529) (xy 117.207761 -265.682685) (xy 117.256936 -265.680704) (xy 117.305791 -265.686636)
			(xy 117.353062 -265.700328) (xy 117.397524 -265.721426) (xy 117.438027 -265.749382) (xy 117.47352 -265.783474)
			(xy 117.503085 -265.822818) (xy 117.525956 -265.866395) (xy 117.54154 -265.913076) (xy 117.549435 -265.961653)
			(xy 117.54993 -265.98626) (xy 117.549435 -266.010867) (xy 117.54154 -266.059444) (xy 117.525956 -266.106125)
			(xy 117.503085 -266.149702) (xy 117.47352 -266.189046) (xy 117.438027 -266.223138) (xy 117.397524 -266.251094)
			(xy 117.353062 -266.272192) (xy 117.305791 -266.285884) (xy 117.256936 -266.291816) (xy 117.207761 -266.289835)
			(xy 117.159542 -266.279991) (xy 117.113526 -266.262539) (xy 117.070905 -266.237932) (xy 117.032784 -266.206807)
			(xy 117.000149 -266.16997) (xy 116.973846 -266.128374) (xy 116.954555 -266.083098) (xy 116.942778 -266.035314)
			(xy 116.938818 -265.98626) (xy 115.670076 -265.98626) (xy 115.669563 -266.012479) (xy 115.660667 -266.064155)
			(xy 115.643077 -266.113553) (xy 115.617311 -266.159222) (xy 115.584126 -266.199821) (xy 115.564666 -266.2174)
			(xy 115.564158 -266.2174) (xy 115.56365 -266.217908) (xy 115.559902 -266.221324) (xy 115.55375 -266.229386)
			(xy 115.551458 -266.23391) (xy 115.54714 -266.243054) (xy 115.543838 -266.330176) (xy 115.544154 -266.33953)
			(xy 115.550816 -266.357007) (xy 115.556792 -266.364212) (xy 115.557046 -266.364466) (xy 115.55857 -266.36599)
			(xy 115.68684 -266.49426) (xy 115.691983 -266.499022) (xy 115.704215 -266.505854) (xy 115.71097 -266.507722)
			(xy 115.717828 -266.5095) (xy 115.731544 -266.508738) (xy 115.738656 -266.506452) (xy 115.761999 -266.499226)
			(xy 115.810237 -266.491441) (xy 115.834668 -266.490958) (xy 115.858662 -266.491426) (xy 115.906059 -266.498928)
			(xy 115.9517 -266.513752) (xy 115.994459 -266.535534) (xy 116.033285 -266.563736) (xy 116.067221 -266.597664)
			(xy 116.095432 -266.636484) (xy 116.117222 -266.679239) (xy 116.132056 -266.724876) (xy 116.139569 -266.772272)
			(xy 116.139976 -266.796266) (xy 116.139496 -266.820697) (xy 116.131713 -266.868936) (xy 116.124482 -266.892278)
			(xy 116.124482 -266.892532) (xy 116.122512 -266.89928) (xy 116.12188 -266.913315) (xy 116.123212 -266.920218)
			(xy 116.12499 -266.927076) (xy 116.131594 -266.939014) (xy 116.238782 -267.046202) (xy 116.244279 -267.051194)
			(xy 116.257443 -267.058049) (xy 116.26469 -267.059664) (xy 116.274342 -267.06068) (xy 117.281198 -267.06068)
			(xy 117.29085 -267.059664) (xy 117.298094 -267.058037) (xy 117.311263 -267.051195) (xy 117.316758 -267.046202)
			(xy 117.414294 -266.948666) (xy 117.41926 -266.94342) (xy 117.426227 -266.930774) (xy 117.42801 -266.923774)
			(xy 117.429534 -266.916916) (xy 117.428772 -266.903454) (xy 117.426232 -266.896088) (xy 117.418402 -266.871879)
			(xy 117.40998 -266.821704) (xy 117.409468 -266.796266) (xy 117.409941 -266.772276) (xy 117.417451 -266.724887)
			(xy 117.432281 -266.679256) (xy 117.454066 -266.636506) (xy 117.48227 -266.59769) (xy 117.516198 -266.563763)
			(xy 117.555015 -266.535561) (xy 117.597765 -266.513778) (xy 117.643397 -266.498949) (xy 117.690786 -266.49144)
			(xy 117.714776 -266.490958) (xy 117.740215 -266.491462) (xy 117.790391 -266.499886) (xy 117.814598 -266.507722)
			(xy 117.814852 -266.507722) (xy 117.821561 -266.509862) (xy 117.835609 -266.51076) (xy 117.842538 -266.5095)
			(xy 117.84965 -266.507722) (xy 117.862096 -266.500864) (xy 118.067074 -266.295886) (xy 118.074472 -266.289042)
			(xy 118.093072 -266.281321) (xy 118.103142 -266.2809) (xy 118.76659 -266.2809) (xy 118.770908 -266.280646)
			(xy 118.781148 -266.279284) (xy 118.799368 -266.269586) (xy 118.806214 -266.26185) (xy 118.810278 -266.256008)
			(xy 118.854982 -266.181332) (xy 118.858179 -266.175533) (xy 118.861791 -266.1628) (xy 118.862094 -266.156186)
			(xy 118.862348 -266.142978) (xy 118.855998 -266.13104) (xy 118.844521 -266.108648) (xy 118.828235 -266.061043)
			(xy 118.819951 -266.011416) (xy 118.819422 -265.98626) (xy 118.819944 -265.961005) (xy 118.828257 -265.911183)
			(xy 118.844658 -265.863409) (xy 118.868699 -265.818986) (xy 118.899723 -265.779126) (xy 118.936885 -265.744916)
			(xy 118.979171 -265.71729) (xy 119.025427 -265.697) (xy 119.074392 -265.6846) (xy 119.12473 -265.680429)
			(xy 119.175068 -265.6846) (xy 119.224033 -265.697) (xy 119.270289 -265.71729) (xy 119.312575 -265.744916)
			(xy 119.349737 -265.779126) (xy 119.380761 -265.818986) (xy 119.404802 -265.863409) (xy 119.421203 -265.911183)
			(xy 119.429516 -265.961005) (xy 119.430038 -265.98626) (xy 120.699034 -265.98626) (xy 120.702994 -265.937206)
			(xy 120.714771 -265.889422) (xy 120.734062 -265.844146) (xy 120.760365 -265.80255) (xy 120.793 -265.765713)
			(xy 120.831121 -265.734588) (xy 120.873742 -265.709981) (xy 120.919758 -265.692529) (xy 120.967977 -265.682685)
			(xy 121.017152 -265.680704) (xy 121.066007 -265.686636) (xy 121.113278 -265.700328) (xy 121.15774 -265.721426)
			(xy 121.198243 -265.749382) (xy 121.233736 -265.783474) (xy 121.263301 -265.822818) (xy 121.286172 -265.866395)
			(xy 121.301756 -265.913076) (xy 121.309651 -265.961653) (xy 121.310146 -265.98626) (xy 121.309651 -266.010867)
			(xy 121.301756 -266.059444) (xy 121.286172 -266.106125) (xy 121.263301 -266.149702) (xy 121.233736 -266.189046)
			(xy 121.198243 -266.223138) (xy 121.15774 -266.251094) (xy 121.113278 -266.272192) (xy 121.066007 -266.285884)
			(xy 121.017152 -266.291816) (xy 120.967977 -266.289835) (xy 120.919758 -266.279991) (xy 120.873742 -266.262539)
			(xy 120.831121 -266.237932) (xy 120.793 -266.206807) (xy 120.760365 -266.16997) (xy 120.734062 -266.128374)
			(xy 120.714771 -266.083098) (xy 120.702994 -266.035314) (xy 120.699034 -265.98626) (xy 119.430038 -265.98626)
			(xy 119.429461 -266.013206) (xy 119.419994 -266.066261) (xy 119.401365 -266.116832) (xy 119.374152 -266.16335)
			(xy 119.339199 -266.204371) (xy 119.318786 -266.221972) (xy 119.314744 -266.22545) (xy 119.308084 -266.233775)
			(xy 119.305578 -266.238482) (xy 119.300752 -266.24788) (xy 119.29872 -266.291568) (xy 119.296688 -266.336018)
			(xy 119.297022 -266.346128) (xy 119.304611 -266.36486) (xy 119.31142 -266.37234) (xy 119.436896 -266.497816)
			(xy 119.442141 -266.502784) (xy 119.454786 -266.509757) (xy 119.461788 -266.511532) (xy 119.468646 -266.513056)
			(xy 119.482616 -266.51204) (xy 119.489982 -266.5095) (xy 119.515286 -266.500894) (xy 119.567909 -266.491573)
			(xy 119.59463 -266.490958) (xy 119.618621 -266.491431) (xy 119.666011 -266.49894) (xy 119.711643 -266.51377)
			(xy 119.754394 -266.535555) (xy 119.793211 -266.563758) (xy 119.827139 -266.597686) (xy 119.855343 -266.636503)
			(xy 119.877128 -266.679253) (xy 119.891959 -266.724885) (xy 119.899469 -266.772275) (xy 119.899938 -266.796266)
			(xy 119.899368 -266.822928) (xy 119.890035 -266.87543) (xy 119.881396 -266.90066) (xy 119.881396 -266.901168)
			(xy 119.881142 -266.901422) (xy 119.879059 -266.908211) (xy 119.878286 -266.922387) (xy 119.879618 -266.929362)
			(xy 119.881142 -266.936474) (xy 119.888 -266.94892) (xy 119.959882 -267.020802) (xy 119.965379 -267.025794)
			(xy 119.978543 -267.032649) (xy 119.98579 -267.034264) (xy 119.995442 -267.03528) (xy 120.877838 -267.03528)
			(xy 120.88749 -267.034264) (xy 120.894731 -267.032632) (xy 120.907893 -267.025783) (xy 120.913398 -267.020802)
			(xy 121.159524 -266.774676) (xy 121.16213 -266.771927) (xy 121.166589 -266.765804) (xy 121.168414 -266.762484)
			(xy 121.172224 -266.755372) (xy 121.173494 -266.747244) (xy 121.177775 -266.723808) (xy 121.192646 -266.678549)
			(xy 121.214369 -266.636151) (xy 121.242416 -266.597644) (xy 121.276107 -266.563963) (xy 121.314622 -266.535926)
			(xy 121.357026 -266.514214) (xy 121.402288 -266.499355) (xy 121.425716 -266.495022) (xy 121.433844 -266.493752)
			(xy 121.440956 -266.489942) (xy 121.444286 -266.488135) (xy 121.450406 -266.483667) (xy 121.453148 -266.481052)
			(xy 121.645934 -266.288266) (xy 121.653331 -266.281418) (xy 121.67193 -266.273685) (xy 121.682002 -266.27328)
			(xy 122.522488 -266.27328) (xy 122.525282 -266.27328) (xy 122.534712 -266.272389) (xy 122.551947 -266.264567)
			(xy 122.55881 -266.25804) (xy 122.561604 -266.254738) (xy 122.564652 -266.250674) (xy 122.583702 -266.219686)
			(xy 122.611134 -266.174728) (xy 122.614318 -266.16912) (xy 122.61804 -266.156777) (xy 122.6185 -266.150344)
			(xy 122.619008 -266.13739) (xy 122.612912 -266.125452) (xy 122.602342 -266.103834) (xy 122.587398 -266.058094)
			(xy 122.579831 -266.010574) (xy 122.579384 -265.986514) (xy 122.579384 -265.980926) (xy 122.580244 -265.957208)
			(xy 122.588398 -265.910456) (xy 122.603688 -265.865529) (xy 122.625747 -265.82351) (xy 122.654043 -265.78541)
			(xy 122.687894 -265.752149) (xy 122.726485 -265.724527) (xy 122.768886 -265.70321) (xy 122.814075 -265.688712)
			(xy 122.860963 -265.681382) (xy 122.884692 -265.680952) (xy 122.908685 -265.681422) (xy 122.95608 -265.688927)
			(xy 123.001717 -265.703753) (xy 123.044474 -265.725536) (xy 123.083297 -265.753738) (xy 123.117231 -265.787666)
			(xy 123.145439 -265.826485) (xy 123.167229 -265.869238) (xy 123.182062 -265.914873) (xy 123.189574 -265.962267)
			(xy 123.19 -265.98626) (xy 124.458996 -265.98626) (xy 124.462956 -265.937206) (xy 124.474733 -265.889422)
			(xy 124.494024 -265.844146) (xy 124.520327 -265.80255) (xy 124.552962 -265.765713) (xy 124.591083 -265.734588)
			(xy 124.633704 -265.709981) (xy 124.67972 -265.692529) (xy 124.727939 -265.682685) (xy 124.777114 -265.680704)
			(xy 124.825969 -265.686636) (xy 124.87324 -265.700328) (xy 124.917702 -265.721426) (xy 124.958205 -265.749382)
			(xy 124.993698 -265.783474) (xy 125.023263 -265.822818) (xy 125.046134 -265.866395) (xy 125.061718 -265.913076)
			(xy 125.069613 -265.961653) (xy 125.070108 -265.98626) (xy 126.33885 -265.98626) (xy 126.34281 -265.937206)
			(xy 126.354587 -265.889422) (xy 126.373878 -265.844146) (xy 126.400181 -265.80255) (xy 126.432816 -265.765713)
			(xy 126.470937 -265.734588) (xy 126.513558 -265.709981) (xy 126.559574 -265.692529) (xy 126.607793 -265.682685)
			(xy 126.656968 -265.680704) (xy 126.705823 -265.686636) (xy 126.753094 -265.700328) (xy 126.797556 -265.721426)
			(xy 126.838059 -265.749382) (xy 126.873552 -265.783474) (xy 126.903117 -265.822818) (xy 126.925988 -265.866395)
			(xy 126.941572 -265.913076) (xy 126.949467 -265.961653) (xy 126.949962 -265.98626) (xy 128.208527 -265.98626)
			(xy 128.212622 -265.935532) (xy 128.224801 -265.886118) (xy 128.244749 -265.839298) (xy 128.27195 -265.796284)
			(xy 128.305698 -265.75819) (xy 128.34512 -265.726003) (xy 128.389194 -265.700557) (xy 128.43678 -265.68251)
			(xy 128.486644 -265.67233) (xy 128.537496 -265.670281) (xy 128.588017 -265.676415) (xy 128.636901 -265.690575)
			(xy 128.68288 -265.712392) (xy 128.724764 -265.741302) (xy 128.761468 -265.776557) (xy 128.792041 -265.817243)
			(xy 128.815692 -265.862306) (xy 128.831808 -265.91058) (xy 128.839972 -265.960814) (xy 128.840484 -265.98626)
			(xy 129.159012 -265.98626) (xy 129.162972 -265.937206) (xy 129.174749 -265.889422) (xy 129.19404 -265.844146)
			(xy 129.220343 -265.80255) (xy 129.252978 -265.765713) (xy 129.291099 -265.734588) (xy 129.33372 -265.709981)
			(xy 129.379736 -265.692529) (xy 129.427955 -265.682685) (xy 129.47713 -265.680704) (xy 129.525985 -265.686636)
			(xy 129.573256 -265.700328) (xy 129.617718 -265.721426) (xy 129.658221 -265.749382) (xy 129.693714 -265.783474)
			(xy 129.723279 -265.822818) (xy 129.74615 -265.866395) (xy 129.761734 -265.913076) (xy 129.769629 -265.961653)
			(xy 129.770124 -265.98626) (xy 131.028435 -265.98626) (xy 131.03253 -265.935532) (xy 131.044709 -265.886118)
			(xy 131.064657 -265.839298) (xy 131.091858 -265.796284) (xy 131.125606 -265.75819) (xy 131.165028 -265.726003)
			(xy 131.209102 -265.700557) (xy 131.256688 -265.68251) (xy 131.306552 -265.67233) (xy 131.357404 -265.670281)
			(xy 131.407925 -265.676415) (xy 131.456809 -265.690575) (xy 131.502788 -265.712392) (xy 131.544672 -265.741302)
			(xy 131.581376 -265.776557) (xy 131.611949 -265.817243) (xy 131.6356 -265.862306) (xy 131.651716 -265.91058)
			(xy 131.65988 -265.960814) (xy 131.660392 -265.98626) (xy 131.97892 -265.98626) (xy 131.98288 -265.937206)
			(xy 131.994657 -265.889422) (xy 132.013948 -265.844146) (xy 132.040251 -265.80255) (xy 132.072886 -265.765713)
			(xy 132.111007 -265.734588) (xy 132.153628 -265.709981) (xy 132.199644 -265.692529) (xy 132.247863 -265.682685)
			(xy 132.297038 -265.680704) (xy 132.345893 -265.686636) (xy 132.393164 -265.700328) (xy 132.437626 -265.721426)
			(xy 132.478129 -265.749382) (xy 132.513622 -265.783474) (xy 132.543187 -265.822818) (xy 132.566058 -265.866395)
			(xy 132.581642 -265.913076) (xy 132.589537 -265.961653) (xy 132.590032 -265.98626) (xy 132.918974 -265.98626)
			(xy 132.922934 -265.937206) (xy 132.934711 -265.889422) (xy 132.954002 -265.844146) (xy 132.980305 -265.80255)
			(xy 133.01294 -265.765713) (xy 133.051061 -265.734588) (xy 133.093682 -265.709981) (xy 133.139698 -265.692529)
			(xy 133.187917 -265.682685) (xy 133.237092 -265.680704) (xy 133.285947 -265.686636) (xy 133.333218 -265.700328)
			(xy 133.37768 -265.721426) (xy 133.418183 -265.749382) (xy 133.453676 -265.783474) (xy 133.483241 -265.822818)
			(xy 133.506112 -265.866395) (xy 133.521696 -265.913076) (xy 133.529591 -265.961653) (xy 133.530086 -265.98626)
			(xy 133.529591 -266.010867) (xy 133.521696 -266.059444) (xy 133.506112 -266.106125) (xy 133.483241 -266.149702)
			(xy 133.453676 -266.189046) (xy 133.418183 -266.223138) (xy 133.37768 -266.251094) (xy 133.333218 -266.272192)
			(xy 133.285947 -266.285884) (xy 133.237092 -266.291816) (xy 133.187917 -266.289835) (xy 133.139698 -266.279991)
			(xy 133.093682 -266.262539) (xy 133.051061 -266.237932) (xy 133.01294 -266.206807) (xy 132.980305 -266.16997)
			(xy 132.954002 -266.128374) (xy 132.934711 -266.083098) (xy 132.922934 -266.035314) (xy 132.918974 -265.98626)
			(xy 132.590032 -265.98626) (xy 132.589537 -266.010867) (xy 132.581642 -266.059444) (xy 132.566058 -266.106125)
			(xy 132.543187 -266.149702) (xy 132.513622 -266.189046) (xy 132.478129 -266.223138) (xy 132.437626 -266.251094)
			(xy 132.393164 -266.272192) (xy 132.345893 -266.285884) (xy 132.297038 -266.291816) (xy 132.247863 -266.289835)
			(xy 132.199644 -266.279991) (xy 132.153628 -266.262539) (xy 132.111007 -266.237932) (xy 132.072886 -266.206807)
			(xy 132.040251 -266.16997) (xy 132.013948 -266.128374) (xy 131.994657 -266.083098) (xy 131.98288 -266.035314)
			(xy 131.97892 -265.98626) (xy 131.660392 -265.98626) (xy 131.65988 -266.011706) (xy 131.651716 -266.06194)
			(xy 131.6356 -266.110214) (xy 131.611949 -266.155277) (xy 131.581376 -266.195963) (xy 131.544672 -266.231218)
			(xy 131.502788 -266.260128) (xy 131.456809 -266.281945) (xy 131.407925 -266.296105) (xy 131.357404 -266.302239)
			(xy 131.306552 -266.30019) (xy 131.256688 -266.29001) (xy 131.209102 -266.271963) (xy 131.165028 -266.246517)
			(xy 131.125606 -266.21433) (xy 131.091858 -266.176236) (xy 131.064657 -266.133222) (xy 131.044709 -266.086402)
			(xy 131.03253 -266.036988) (xy 131.028435 -265.98626) (xy 129.770124 -265.98626) (xy 129.769629 -266.010867)
			(xy 129.761734 -266.059444) (xy 129.74615 -266.106125) (xy 129.723279 -266.149702) (xy 129.693714 -266.189046)
			(xy 129.658221 -266.223138) (xy 129.617718 -266.251094) (xy 129.573256 -266.272192) (xy 129.525985 -266.285884)
			(xy 129.47713 -266.291816) (xy 129.427955 -266.289835) (xy 129.379736 -266.279991) (xy 129.33372 -266.262539)
			(xy 129.291099 -266.237932) (xy 129.252978 -266.206807) (xy 129.220343 -266.16997) (xy 129.19404 -266.128374)
			(xy 129.174749 -266.083098) (xy 129.162972 -266.035314) (xy 129.159012 -265.98626) (xy 128.840484 -265.98626)
			(xy 128.839972 -266.011706) (xy 128.831808 -266.06194) (xy 128.815692 -266.110214) (xy 128.792041 -266.155277)
			(xy 128.761468 -266.195963) (xy 128.724764 -266.231218) (xy 128.68288 -266.260128) (xy 128.636901 -266.281945)
			(xy 128.588017 -266.296105) (xy 128.537496 -266.302239) (xy 128.486644 -266.30019) (xy 128.43678 -266.29001)
			(xy 128.389194 -266.271963) (xy 128.34512 -266.246517) (xy 128.305698 -266.21433) (xy 128.27195 -266.176236)
			(xy 128.244749 -266.133222) (xy 128.224801 -266.086402) (xy 128.212622 -266.036988) (xy 128.208527 -265.98626)
			(xy 126.949962 -265.98626) (xy 126.949467 -266.010867) (xy 126.941572 -266.059444) (xy 126.925988 -266.106125)
			(xy 126.903117 -266.149702) (xy 126.873552 -266.189046) (xy 126.838059 -266.223138) (xy 126.797556 -266.251094)
			(xy 126.753094 -266.272192) (xy 126.705823 -266.285884) (xy 126.656968 -266.291816) (xy 126.607793 -266.289835)
			(xy 126.559574 -266.279991) (xy 126.513558 -266.262539) (xy 126.470937 -266.237932) (xy 126.432816 -266.206807)
			(xy 126.400181 -266.16997) (xy 126.373878 -266.128374) (xy 126.354587 -266.083098) (xy 126.34281 -266.035314)
			(xy 126.33885 -265.98626) (xy 125.070108 -265.98626) (xy 125.069613 -266.010867) (xy 125.061718 -266.059444)
			(xy 125.046134 -266.106125) (xy 125.023263 -266.149702) (xy 124.993698 -266.189046) (xy 124.958205 -266.223138)
			(xy 124.917702 -266.251094) (xy 124.87324 -266.272192) (xy 124.825969 -266.285884) (xy 124.777114 -266.291816)
			(xy 124.727939 -266.289835) (xy 124.67972 -266.279991) (xy 124.633704 -266.262539) (xy 124.591083 -266.237932)
			(xy 124.552962 -266.206807) (xy 124.520327 -266.16997) (xy 124.494024 -266.128374) (xy 124.474733 -266.083098)
			(xy 124.462956 -266.035314) (xy 124.458996 -265.98626) (xy 123.19 -265.98626) (xy 123.189861 -265.999023)
			(xy 123.187696 -266.024456) (xy 123.185682 -266.03706) (xy 123.185936 -266.03706) (xy 123.181166 -266.062124)
			(xy 123.164398 -266.110307) (xy 123.139858 -266.155035) (xy 123.108228 -266.195064) (xy 123.08967 -266.212574)
			(xy 123.081796 -266.219686) (xy 123.077478 -266.229084) (xy 123.075472 -266.233798) (xy 123.073174 -266.24378)
			(xy 123.072906 -266.248896) (xy 123.07189 -266.289028) (xy 123.071128 -266.323826) (xy 123.071607 -266.333791)
			(xy 123.079188 -266.352223) (xy 123.08586 -266.35964) (xy 123.217178 -266.490958) (xy 123.222153 -266.495645)
			(xy 123.233998 -266.502458) (xy 123.240546 -266.50442) (xy 123.24715 -266.505944) (xy 123.260866 -266.50569)
			(xy 123.26747 -266.503658) (xy 123.288512 -266.49778) (xy 123.331733 -266.4914) (xy 123.353576 -266.490958)
			(xy 123.358148 -266.490958) (xy 123.381803 -266.491662) (xy 123.428477 -266.499475) (xy 123.473387 -266.514395)
			(xy 123.515457 -266.536064) (xy 123.553681 -266.563965) (xy 123.587143 -266.597428) (xy 123.615042 -266.635653)
			(xy 123.63671 -266.677724) (xy 123.651628 -266.722635) (xy 123.659439 -266.769309) (xy 123.660154 -266.792964)
			(xy 123.660154 -266.796774) (xy 123.659746 -266.818808) (xy 123.653366 -266.862412) (xy 123.647454 -266.883642)
			(xy 123.645422 -266.890246) (xy 123.645168 -266.903962) (xy 123.646692 -266.910566) (xy 123.648605 -266.917135)
			(xy 123.655429 -266.928987) (xy 123.660154 -266.933934) (xy 123.884182 -267.157962) (xy 123.889681 -267.162949)
			(xy 123.902847 -267.169796) (xy 123.91009 -267.171424) (xy 123.919742 -267.17244) (xy 124.934472 -267.17244)
			(xy 124.935234 -267.17244) (xy 124.943895 -267.171966) (xy 124.960146 -267.165941) (xy 124.973452 -267.154832)
			(xy 124.97816 -267.147548) (xy 124.980954 -267.14196) (xy 125.018546 -267.056616) (xy 125.021261 -267.049785)
			(xy 125.023062 -267.035202) (xy 125.022102 -267.027914) (xy 125.021086 -267.02131) (xy 125.014736 -267.008102)
			(xy 125.009402 -267.00226) (xy 124.994439 -266.985287) (xy 124.969167 -266.947756) (xy 124.949707 -266.906908)
			(xy 124.936484 -266.863637) (xy 124.929787 -266.818889) (xy 124.929392 -266.796266) (xy 124.929914 -266.771011)
			(xy 124.938227 -266.721189) (xy 124.954628 -266.673415) (xy 124.978669 -266.628992) (xy 125.009693 -266.589132)
			(xy 125.046855 -266.554922) (xy 125.089141 -266.527296) (xy 125.135397 -266.507006) (xy 125.184362 -266.494606)
			(xy 125.2347 -266.490435) (xy 125.285038 -266.494606) (xy 125.334003 -266.507006) (xy 125.380259 -266.527296)
			(xy 125.422545 -266.554922) (xy 125.459707 -266.589132) (xy 125.490731 -266.628992) (xy 125.514772 -266.673415)
			(xy 125.531173 -266.721189) (xy 125.539486 -266.771011) (xy 125.540008 -266.796266) (xy 125.5396 -266.81889)
			(xy 125.532922 -266.863642) (xy 125.519709 -266.906917) (xy 125.500249 -266.947767) (xy 125.47497 -266.985294)
			(xy 125.459998 -267.00226) (xy 125.459744 -267.002514) (xy 125.454967 -267.008077) (xy 125.448512 -267.021238)
			(xy 125.447044 -267.028422) (xy 125.446028 -267.03528) (xy 125.447806 -267.049758) (xy 125.488446 -267.14196)
			(xy 125.49124 -267.147548) (xy 125.495957 -267.154826) (xy 125.50926 -267.165937) (xy 125.525506 -267.17198)
			(xy 125.534166 -267.17244) (xy 125.874526 -267.17244) (xy 125.875288 -267.17244) (xy 125.883944 -267.171958)
			(xy 125.900182 -267.165921) (xy 125.913473 -267.154808) (xy 125.918214 -267.147548) (xy 125.921008 -267.14196)
			(xy 125.9586 -267.056616) (xy 125.961317 -267.049785) (xy 125.963119 -267.035202) (xy 125.962156 -267.027914)
			(xy 125.96114 -267.02131) (xy 125.95479 -267.008102) (xy 125.949456 -267.00226) (xy 125.934495 -266.985286)
			(xy 125.909227 -266.947754) (xy 125.88977 -266.906906) (xy 125.876549 -266.863635) (xy 125.869853 -266.818888)
			(xy 125.869446 -266.796266) (xy 125.869968 -266.771011) (xy 125.878281 -266.721189) (xy 125.894682 -266.673415)
			(xy 125.918723 -266.628992) (xy 125.949747 -266.589132) (xy 125.986909 -266.554922) (xy 126.029195 -266.527296)
			(xy 126.075451 -266.507006) (xy 126.124416 -266.494606) (xy 126.174754 -266.490435) (xy 126.225092 -266.494606)
			(xy 126.274057 -266.507006) (xy 126.320313 -266.527296) (xy 126.362599 -266.554922) (xy 126.399761 -266.589132)
			(xy 126.430785 -266.628992) (xy 126.454826 -266.673415) (xy 126.471227 -266.721189) (xy 126.47954 -266.771011)
			(xy 126.480062 -266.796266) (xy 126.809004 -266.796266) (xy 126.812964 -266.747212) (xy 126.824741 -266.699428)
			(xy 126.844032 -266.654152) (xy 126.870335 -266.612556) (xy 126.90297 -266.575719) (xy 126.941091 -266.544594)
			(xy 126.983712 -266.519987) (xy 127.029728 -266.502535) (xy 127.077947 -266.492691) (xy 127.127122 -266.49071)
			(xy 127.175977 -266.496642) (xy 127.223248 -266.510334) (xy 127.26771 -266.531432) (xy 127.308213 -266.559388)
			(xy 127.343706 -266.59348) (xy 127.373271 -266.632824) (xy 127.396142 -266.676401) (xy 127.411726 -266.723082)
			(xy 127.419621 -266.771659) (xy 127.420116 -266.796266) (xy 127.738627 -266.796266) (xy 127.742722 -266.745538)
			(xy 127.754901 -266.696124) (xy 127.774849 -266.649304) (xy 127.80205 -266.60629) (xy 127.835798 -266.568196)
			(xy 127.87522 -266.536009) (xy 127.919294 -266.510563) (xy 127.96688 -266.492516) (xy 128.016744 -266.482336)
			(xy 128.067596 -266.480287) (xy 128.118117 -266.486421) (xy 128.167001 -266.500581) (xy 128.21298 -266.522398)
			(xy 128.254864 -266.551308) (xy 128.291568 -266.586563) (xy 128.322141 -266.627249) (xy 128.345792 -266.672312)
			(xy 128.361908 -266.720586) (xy 128.370072 -266.77082) (xy 128.370584 -266.796266) (xy 128.688858 -266.796266)
			(xy 128.692818 -266.747212) (xy 128.704595 -266.699428) (xy 128.723886 -266.654152) (xy 128.750189 -266.612556)
			(xy 128.782824 -266.575719) (xy 128.820945 -266.544594) (xy 128.863566 -266.519987) (xy 128.909582 -266.502535)
			(xy 128.957801 -266.492691) (xy 129.006976 -266.49071) (xy 129.055831 -266.496642) (xy 129.103102 -266.510334)
			(xy 129.147564 -266.531432) (xy 129.188067 -266.559388) (xy 129.22356 -266.59348) (xy 129.253125 -266.632824)
			(xy 129.275996 -266.676401) (xy 129.29158 -266.723082) (xy 129.299475 -266.771659) (xy 129.29997 -266.796266)
			(xy 129.618481 -266.796266) (xy 129.622576 -266.745538) (xy 129.634755 -266.696124) (xy 129.654703 -266.649304)
			(xy 129.681904 -266.60629) (xy 129.715652 -266.568196) (xy 129.755074 -266.536009) (xy 129.799148 -266.510563)
			(xy 129.846734 -266.492516) (xy 129.896598 -266.482336) (xy 129.94745 -266.480287) (xy 129.997971 -266.486421)
			(xy 130.046855 -266.500581) (xy 130.092834 -266.522398) (xy 130.134718 -266.551308) (xy 130.171422 -266.586563)
			(xy 130.201995 -266.627249) (xy 130.225646 -266.672312) (xy 130.241762 -266.720586) (xy 130.249926 -266.77082)
			(xy 130.250438 -266.796266) (xy 130.568966 -266.796266) (xy 130.572926 -266.747212) (xy 130.584703 -266.699428)
			(xy 130.603994 -266.654152) (xy 130.630297 -266.612556) (xy 130.662932 -266.575719) (xy 130.701053 -266.544594)
			(xy 130.743674 -266.519987) (xy 130.78969 -266.502535) (xy 130.837909 -266.492691) (xy 130.887084 -266.49071)
			(xy 130.935939 -266.496642) (xy 130.98321 -266.510334) (xy 131.027672 -266.531432) (xy 131.068175 -266.559388)
			(xy 131.103668 -266.59348) (xy 131.133233 -266.632824) (xy 131.156104 -266.676401) (xy 131.171688 -266.723082)
			(xy 131.179583 -266.771659) (xy 131.180078 -266.796266) (xy 131.498589 -266.796266) (xy 131.502684 -266.745538)
			(xy 131.514863 -266.696124) (xy 131.534811 -266.649304) (xy 131.562012 -266.60629) (xy 131.59576 -266.568196)
			(xy 131.635182 -266.536009) (xy 131.679256 -266.510563) (xy 131.726842 -266.492516) (xy 131.776706 -266.482336)
			(xy 131.827558 -266.480287) (xy 131.878079 -266.486421) (xy 131.926963 -266.500581) (xy 131.972942 -266.522398)
			(xy 132.014826 -266.551308) (xy 132.05153 -266.586563) (xy 132.082103 -266.627249) (xy 132.105754 -266.672312)
			(xy 132.12187 -266.720586) (xy 132.130034 -266.77082) (xy 132.130546 -266.796266) (xy 132.438643 -266.796266)
			(xy 132.442738 -266.745538) (xy 132.454917 -266.696124) (xy 132.474865 -266.649304) (xy 132.502066 -266.60629)
			(xy 132.535814 -266.568196) (xy 132.575236 -266.536009) (xy 132.61931 -266.510563) (xy 132.666896 -266.492516)
			(xy 132.71676 -266.482336) (xy 132.767612 -266.480287) (xy 132.818133 -266.486421) (xy 132.867017 -266.500581)
			(xy 132.912996 -266.522398) (xy 132.95488 -266.551308) (xy 132.991584 -266.586563) (xy 133.022157 -266.627249)
			(xy 133.045808 -266.672312) (xy 133.061924 -266.720586) (xy 133.070088 -266.77082) (xy 133.0706 -266.796266)
			(xy 133.070088 -266.821712) (xy 133.061924 -266.871946) (xy 133.045808 -266.92022) (xy 133.022157 -266.965283)
			(xy 132.991584 -267.005969) (xy 132.95488 -267.041224) (xy 132.912996 -267.070134) (xy 132.867017 -267.091951)
			(xy 132.818133 -267.106111) (xy 132.767612 -267.112245) (xy 132.71676 -267.110196) (xy 132.666896 -267.100016)
			(xy 132.61931 -267.081969) (xy 132.575236 -267.056523) (xy 132.535814 -267.024336) (xy 132.502066 -266.986242)
			(xy 132.474865 -266.943228) (xy 132.454917 -266.896408) (xy 132.442738 -266.846994) (xy 132.438643 -266.796266)
			(xy 132.130546 -266.796266) (xy 132.130034 -266.821712) (xy 132.12187 -266.871946) (xy 132.105754 -266.92022)
			(xy 132.082103 -266.965283) (xy 132.05153 -267.005969) (xy 132.014826 -267.041224) (xy 131.972942 -267.070134)
			(xy 131.926963 -267.091951) (xy 131.878079 -267.106111) (xy 131.827558 -267.112245) (xy 131.776706 -267.110196)
			(xy 131.726842 -267.100016) (xy 131.679256 -267.081969) (xy 131.635182 -267.056523) (xy 131.59576 -267.024336)
			(xy 131.562012 -266.986242) (xy 131.534811 -266.943228) (xy 131.514863 -266.896408) (xy 131.502684 -266.846994)
			(xy 131.498589 -266.796266) (xy 131.180078 -266.796266) (xy 131.179583 -266.820873) (xy 131.171688 -266.86945)
			(xy 131.156104 -266.916131) (xy 131.133233 -266.959708) (xy 131.103668 -266.999052) (xy 131.068175 -267.033144)
			(xy 131.027672 -267.0611) (xy 130.98321 -267.082198) (xy 130.935939 -267.09589) (xy 130.887084 -267.101822)
			(xy 130.837909 -267.099841) (xy 130.78969 -267.089997) (xy 130.743674 -267.072545) (xy 130.701053 -267.047938)
			(xy 130.662932 -267.016813) (xy 130.630297 -266.979976) (xy 130.603994 -266.93838) (xy 130.584703 -266.893104)
			(xy 130.572926 -266.84532) (xy 130.568966 -266.796266) (xy 130.250438 -266.796266) (xy 130.249926 -266.821712)
			(xy 130.241762 -266.871946) (xy 130.225646 -266.92022) (xy 130.201995 -266.965283) (xy 130.171422 -267.005969)
			(xy 130.134718 -267.041224) (xy 130.092834 -267.070134) (xy 130.046855 -267.091951) (xy 129.997971 -267.106111)
			(xy 129.94745 -267.112245) (xy 129.896598 -267.110196) (xy 129.846734 -267.100016) (xy 129.799148 -267.081969)
			(xy 129.755074 -267.056523) (xy 129.715652 -267.024336) (xy 129.681904 -266.986242) (xy 129.654703 -266.943228)
			(xy 129.634755 -266.896408) (xy 129.622576 -266.846994) (xy 129.618481 -266.796266) (xy 129.29997 -266.796266)
			(xy 129.299475 -266.820873) (xy 129.29158 -266.86945) (xy 129.275996 -266.916131) (xy 129.253125 -266.959708)
			(xy 129.22356 -266.999052) (xy 129.188067 -267.033144) (xy 129.147564 -267.0611) (xy 129.103102 -267.082198)
			(xy 129.055831 -267.09589) (xy 129.006976 -267.101822) (xy 128.957801 -267.099841) (xy 128.909582 -267.089997)
			(xy 128.863566 -267.072545) (xy 128.820945 -267.047938) (xy 128.782824 -267.016813) (xy 128.750189 -266.979976)
			(xy 128.723886 -266.93838) (xy 128.704595 -266.893104) (xy 128.692818 -266.84532) (xy 128.688858 -266.796266)
			(xy 128.370584 -266.796266) (xy 128.370072 -266.821712) (xy 128.361908 -266.871946) (xy 128.345792 -266.92022)
			(xy 128.322141 -266.965283) (xy 128.291568 -267.005969) (xy 128.254864 -267.041224) (xy 128.21298 -267.070134)
			(xy 128.167001 -267.091951) (xy 128.118117 -267.106111) (xy 128.067596 -267.112245) (xy 128.016744 -267.110196)
			(xy 127.96688 -267.100016) (xy 127.919294 -267.081969) (xy 127.87522 -267.056523) (xy 127.835798 -267.024336)
			(xy 127.80205 -266.986242) (xy 127.774849 -266.943228) (xy 127.754901 -266.896408) (xy 127.742722 -266.846994)
			(xy 127.738627 -266.796266) (xy 127.420116 -266.796266) (xy 127.419621 -266.820873) (xy 127.411726 -266.86945)
			(xy 127.396142 -266.916131) (xy 127.373271 -266.959708) (xy 127.343706 -266.999052) (xy 127.308213 -267.033144)
			(xy 127.26771 -267.0611) (xy 127.223248 -267.082198) (xy 127.175977 -267.09589) (xy 127.127122 -267.101822)
			(xy 127.077947 -267.099841) (xy 127.029728 -267.089997) (xy 126.983712 -267.072545) (xy 126.941091 -267.047938)
			(xy 126.90297 -267.016813) (xy 126.870335 -266.979976) (xy 126.844032 -266.93838) (xy 126.824741 -266.893104)
			(xy 126.812964 -266.84532) (xy 126.809004 -266.796266) (xy 126.480062 -266.796266) (xy 126.479926 -266.809029)
			(xy 126.477768 -266.834464) (xy 126.475744 -266.847066) (xy 126.475998 -266.847066) (xy 126.471161 -266.872467)
			(xy 126.454097 -266.921273) (xy 126.429061 -266.966512) (xy 126.39677 -267.006891) (xy 126.358143 -267.04126)
			(xy 126.314283 -267.068638) (xy 126.290578 -267.078968) (xy 126.29007 -267.078968) (xy 126.289816 -267.079222)
			(xy 126.284157 -267.081762) (xy 126.274146 -267.089082) (xy 126.270004 -267.0937) (xy 126.266448 -267.098272)
			(xy 126.261114 -267.109448) (xy 126.242826 -267.200634) (xy 126.2415 -267.212615) (xy 126.248806 -267.235549)
			(xy 126.256796 -267.244576) (xy 126.380748 -267.368528) (xy 126.387711 -267.374991) (xy 126.405066 -267.382689)
			(xy 126.41453 -267.383514) (xy 126.423928 -267.383768) (xy 126.441962 -267.377672) (xy 126.449328 -267.371576)
			(xy 126.470073 -267.355064) (xy 126.516073 -267.328708) (xy 126.565929 -267.310677) (xy 126.618146 -267.301512)
			(xy 126.644654 -267.300964) (xy 126.66865 -267.301407) (xy 126.716053 -267.308908) (xy 126.761699 -267.323732)
			(xy 126.804463 -267.345514) (xy 126.843293 -267.373718) (xy 126.877233 -267.40765) (xy 126.905447 -267.446474)
			(xy 126.92724 -267.489233) (xy 126.942075 -267.534875) (xy 126.949587 -267.582276) (xy 126.949962 -267.606272)
			(xy 128.218958 -267.606272) (xy 128.222918 -267.557218) (xy 128.234695 -267.509434) (xy 128.253986 -267.464158)
			(xy 128.280289 -267.422562) (xy 128.312924 -267.385725) (xy 128.351045 -267.3546) (xy 128.393666 -267.329993)
			(xy 128.439682 -267.312541) (xy 128.487901 -267.302697) (xy 128.537076 -267.300716) (xy 128.585931 -267.306648)
			(xy 128.633202 -267.32034) (xy 128.677664 -267.341438) (xy 128.718167 -267.369394) (xy 128.75366 -267.403486)
			(xy 128.783225 -267.44283) (xy 128.806096 -267.486407) (xy 128.82168 -267.533088) (xy 128.829575 -267.581665)
			(xy 128.83007 -267.606272) (xy 129.148581 -267.606272) (xy 129.152676 -267.555544) (xy 129.164855 -267.50613)
			(xy 129.184803 -267.45931) (xy 129.212004 -267.416296) (xy 129.245752 -267.378202) (xy 129.285174 -267.346015)
			(xy 129.329248 -267.320569) (xy 129.376834 -267.302522) (xy 129.426698 -267.292342) (xy 129.47755 -267.290293)
			(xy 129.528071 -267.296427) (xy 129.576955 -267.310587) (xy 129.622934 -267.332404) (xy 129.664818 -267.361314)
			(xy 129.701522 -267.396569) (xy 129.732095 -267.437255) (xy 129.755746 -267.482318) (xy 129.771862 -267.530592)
			(xy 129.780026 -267.580826) (xy 129.780538 -267.606272) (xy 130.099066 -267.606272) (xy 130.103026 -267.557218)
			(xy 130.114803 -267.509434) (xy 130.134094 -267.464158) (xy 130.160397 -267.422562) (xy 130.193032 -267.385725)
			(xy 130.231153 -267.3546) (xy 130.273774 -267.329993) (xy 130.31979 -267.312541) (xy 130.368009 -267.302697)
			(xy 130.417184 -267.300716) (xy 130.466039 -267.306648) (xy 130.51331 -267.32034) (xy 130.557772 -267.341438)
			(xy 130.598275 -267.369394) (xy 130.633768 -267.403486) (xy 130.663333 -267.44283) (xy 130.686204 -267.486407)
			(xy 130.701788 -267.533088) (xy 130.709683 -267.581665) (xy 130.710178 -267.606272) (xy 131.038866 -267.606272)
			(xy 131.042826 -267.557218) (xy 131.054603 -267.509434) (xy 131.073894 -267.464158) (xy 131.100197 -267.422562)
			(xy 131.132832 -267.385725) (xy 131.170953 -267.3546) (xy 131.213574 -267.329993) (xy 131.25959 -267.312541)
			(xy 131.307809 -267.302697) (xy 131.356984 -267.300716) (xy 131.405839 -267.306648) (xy 131.45311 -267.32034)
			(xy 131.497572 -267.341438) (xy 131.538075 -267.369394) (xy 131.573568 -267.403486) (xy 131.603133 -267.44283)
			(xy 131.626004 -267.486407) (xy 131.641588 -267.533088) (xy 131.649483 -267.581665) (xy 131.649978 -267.606272)
			(xy 131.97892 -267.606272) (xy 131.98288 -267.557218) (xy 131.994657 -267.509434) (xy 132.013948 -267.464158)
			(xy 132.040251 -267.422562) (xy 132.072886 -267.385725) (xy 132.111007 -267.3546) (xy 132.153628 -267.329993)
			(xy 132.199644 -267.312541) (xy 132.247863 -267.302697) (xy 132.297038 -267.300716) (xy 132.345893 -267.306648)
			(xy 132.393164 -267.32034) (xy 132.437626 -267.341438) (xy 132.478129 -267.369394) (xy 132.513622 -267.403486)
			(xy 132.543187 -267.44283) (xy 132.566058 -267.486407) (xy 132.581642 -267.533088) (xy 132.589537 -267.581665)
			(xy 132.590032 -267.606272) (xy 132.908543 -267.606272) (xy 132.912638 -267.555544) (xy 132.924817 -267.50613)
			(xy 132.944765 -267.45931) (xy 132.971966 -267.416296) (xy 133.005714 -267.378202) (xy 133.045136 -267.346015)
			(xy 133.08921 -267.320569) (xy 133.136796 -267.302522) (xy 133.18666 -267.292342) (xy 133.237512 -267.290293)
			(xy 133.288033 -267.296427) (xy 133.336917 -267.310587) (xy 133.382896 -267.332404) (xy 133.42478 -267.361314)
			(xy 133.461484 -267.396569) (xy 133.492057 -267.437255) (xy 133.515708 -267.482318) (xy 133.531824 -267.530592)
			(xy 133.539988 -267.580826) (xy 133.5405 -267.606272) (xy 133.539988 -267.631718) (xy 133.531824 -267.681952)
			(xy 133.515708 -267.730226) (xy 133.492057 -267.775289) (xy 133.461484 -267.815975) (xy 133.42478 -267.85123)
			(xy 133.382896 -267.88014) (xy 133.336917 -267.901957) (xy 133.288033 -267.916117) (xy 133.237512 -267.922251)
			(xy 133.18666 -267.920202) (xy 133.136796 -267.910022) (xy 133.08921 -267.891975) (xy 133.045136 -267.866529)
			(xy 133.005714 -267.834342) (xy 132.971966 -267.796248) (xy 132.944765 -267.753234) (xy 132.924817 -267.706414)
			(xy 132.912638 -267.657) (xy 132.908543 -267.606272) (xy 132.590032 -267.606272) (xy 132.589537 -267.630879)
			(xy 132.581642 -267.679456) (xy 132.566058 -267.726137) (xy 132.543187 -267.769714) (xy 132.513622 -267.809058)
			(xy 132.478129 -267.84315) (xy 132.437626 -267.871106) (xy 132.393164 -267.892204) (xy 132.345893 -267.905896)
			(xy 132.297038 -267.911828) (xy 132.247863 -267.909847) (xy 132.199644 -267.900003) (xy 132.153628 -267.882551)
			(xy 132.111007 -267.857944) (xy 132.072886 -267.826819) (xy 132.040251 -267.789982) (xy 132.013948 -267.748386)
			(xy 131.994657 -267.70311) (xy 131.98288 -267.655326) (xy 131.97892 -267.606272) (xy 131.649978 -267.606272)
			(xy 131.649483 -267.630879) (xy 131.641588 -267.679456) (xy 131.626004 -267.726137) (xy 131.603133 -267.769714)
			(xy 131.573568 -267.809058) (xy 131.538075 -267.84315) (xy 131.497572 -267.871106) (xy 131.45311 -267.892204)
			(xy 131.405839 -267.905896) (xy 131.356984 -267.911828) (xy 131.307809 -267.909847) (xy 131.25959 -267.900003)
			(xy 131.213574 -267.882551) (xy 131.170953 -267.857944) (xy 131.132832 -267.826819) (xy 131.100197 -267.789982)
			(xy 131.073894 -267.748386) (xy 131.054603 -267.70311) (xy 131.042826 -267.655326) (xy 131.038866 -267.606272)
			(xy 130.710178 -267.606272) (xy 130.709683 -267.630879) (xy 130.701788 -267.679456) (xy 130.686204 -267.726137)
			(xy 130.663333 -267.769714) (xy 130.633768 -267.809058) (xy 130.598275 -267.84315) (xy 130.557772 -267.871106)
			(xy 130.51331 -267.892204) (xy 130.466039 -267.905896) (xy 130.417184 -267.911828) (xy 130.368009 -267.909847)
			(xy 130.31979 -267.900003) (xy 130.273774 -267.882551) (xy 130.231153 -267.857944) (xy 130.193032 -267.826819)
			(xy 130.160397 -267.789982) (xy 130.134094 -267.748386) (xy 130.114803 -267.70311) (xy 130.103026 -267.655326)
			(xy 130.099066 -267.606272) (xy 129.780538 -267.606272) (xy 129.780026 -267.631718) (xy 129.771862 -267.681952)
			(xy 129.755746 -267.730226) (xy 129.732095 -267.775289) (xy 129.701522 -267.815975) (xy 129.664818 -267.85123)
			(xy 129.622934 -267.88014) (xy 129.576955 -267.901957) (xy 129.528071 -267.916117) (xy 129.47755 -267.922251)
			(xy 129.426698 -267.920202) (xy 129.376834 -267.910022) (xy 129.329248 -267.891975) (xy 129.285174 -267.866529)
			(xy 129.245752 -267.834342) (xy 129.212004 -267.796248) (xy 129.184803 -267.753234) (xy 129.164855 -267.706414)
			(xy 129.152676 -267.657) (xy 129.148581 -267.606272) (xy 128.83007 -267.606272) (xy 128.829575 -267.630879)
			(xy 128.82168 -267.679456) (xy 128.806096 -267.726137) (xy 128.783225 -267.769714) (xy 128.75366 -267.809058)
			(xy 128.718167 -267.84315) (xy 128.677664 -267.871106) (xy 128.633202 -267.892204) (xy 128.585931 -267.905896)
			(xy 128.537076 -267.911828) (xy 128.487901 -267.909847) (xy 128.439682 -267.900003) (xy 128.393666 -267.882551)
			(xy 128.351045 -267.857944) (xy 128.312924 -267.826819) (xy 128.280289 -267.789982) (xy 128.253986 -267.748386)
			(xy 128.234695 -267.70311) (xy 128.222918 -267.655326) (xy 128.218958 -267.606272) (xy 126.949962 -267.606272)
			(xy 126.949822 -267.619035) (xy 126.947657 -267.644468) (xy 126.945644 -267.657072) (xy 126.945898 -267.657072)
			(xy 126.940881 -267.683433) (xy 126.922861 -267.733972) (xy 126.896309 -267.780598) (xy 126.879604 -267.801598)
			(xy 126.873741 -267.809179) (xy 126.867603 -267.827321) (xy 126.867666 -267.836904) (xy 126.86792 -267.846048)
			(xy 126.87554 -267.86332) (xy 127.109728 -268.097508) (xy 127.112927 -268.1006) (xy 127.120212 -268.105707)
			(xy 127.124206 -268.107668) (xy 127.13208 -268.111224) (xy 127.141224 -268.111986) (xy 127.164825 -268.114486)
			(xy 127.2109 -268.125854) (xy 127.254664 -268.144211) (xy 127.295061 -268.169116) (xy 127.331121 -268.199968)
			(xy 127.361975 -268.236027) (xy 127.386882 -268.276423) (xy 127.405241 -268.320185) (xy 127.416611 -268.36626)
			(xy 127.4191 -268.389862) (xy 127.419862 -268.399006) (xy 127.423418 -268.40688) (xy 127.425401 -268.41086)
			(xy 127.429209 -268.416278) (xy 127.749058 -268.416278) (xy 127.753018 -268.367224) (xy 127.764795 -268.31944)
			(xy 127.784086 -268.274164) (xy 127.810389 -268.232568) (xy 127.843024 -268.195731) (xy 127.881145 -268.164606)
			(xy 127.923766 -268.139999) (xy 127.969782 -268.122547) (xy 128.018001 -268.112703) (xy 128.067176 -268.110722)
			(xy 128.116031 -268.116654) (xy 128.163302 -268.130346) (xy 128.207764 -268.151444) (xy 128.248267 -268.1794)
			(xy 128.28376 -268.213492) (xy 128.313325 -268.252836) (xy 128.336196 -268.296413) (xy 128.35178 -268.343094)
			(xy 128.359675 -268.391671) (xy 128.36017 -268.416278) (xy 128.688858 -268.416278) (xy 128.692818 -268.367224)
			(xy 128.704595 -268.31944) (xy 128.723886 -268.274164) (xy 128.750189 -268.232568) (xy 128.782824 -268.195731)
			(xy 128.820945 -268.164606) (xy 128.863566 -268.139999) (xy 128.909582 -268.122547) (xy 128.957801 -268.112703)
			(xy 129.006976 -268.110722) (xy 129.055831 -268.116654) (xy 129.103102 -268.130346) (xy 129.147564 -268.151444)
			(xy 129.188067 -268.1794) (xy 129.22356 -268.213492) (xy 129.253125 -268.252836) (xy 129.275996 -268.296413)
			(xy 129.29158 -268.343094) (xy 129.299475 -268.391671) (xy 129.29997 -268.416278) (xy 129.628912 -268.416278)
			(xy 129.632872 -268.367224) (xy 129.644649 -268.31944) (xy 129.66394 -268.274164) (xy 129.690243 -268.232568)
			(xy 129.722878 -268.195731) (xy 129.760999 -268.164606) (xy 129.80362 -268.139999) (xy 129.849636 -268.122547)
			(xy 129.897855 -268.112703) (xy 129.94703 -268.110722) (xy 129.995885 -268.116654) (xy 130.043156 -268.130346)
			(xy 130.087618 -268.151444) (xy 130.128121 -268.1794) (xy 130.163614 -268.213492) (xy 130.193179 -268.252836)
			(xy 130.21605 -268.296413) (xy 130.231634 -268.343094) (xy 130.239529 -268.391671) (xy 130.240024 -268.416278)
			(xy 131.50902 -268.416278) (xy 131.51298 -268.367224) (xy 131.524757 -268.31944) (xy 131.544048 -268.274164)
			(xy 131.570351 -268.232568) (xy 131.602986 -268.195731) (xy 131.641107 -268.164606) (xy 131.683728 -268.139999)
			(xy 131.729744 -268.122547) (xy 131.777963 -268.112703) (xy 131.827138 -268.110722) (xy 131.875993 -268.116654)
			(xy 131.923264 -268.130346) (xy 131.967726 -268.151444) (xy 132.008229 -268.1794) (xy 132.043722 -268.213492)
			(xy 132.073287 -268.252836) (xy 132.096158 -268.296413) (xy 132.111742 -268.343094) (xy 132.119637 -268.391671)
			(xy 132.120132 -268.416278) (xy 132.44882 -268.416278) (xy 132.45278 -268.367224) (xy 132.464557 -268.31944)
			(xy 132.483848 -268.274164) (xy 132.510151 -268.232568) (xy 132.542786 -268.195731) (xy 132.580907 -268.164606)
			(xy 132.623528 -268.139999) (xy 132.669544 -268.122547) (xy 132.717763 -268.112703) (xy 132.766938 -268.110722)
			(xy 132.815793 -268.116654) (xy 132.863064 -268.130346) (xy 132.907526 -268.151444) (xy 132.948029 -268.1794)
			(xy 132.983522 -268.213492) (xy 133.013087 -268.252836) (xy 133.035958 -268.296413) (xy 133.051542 -268.343094)
			(xy 133.059437 -268.391671) (xy 133.059932 -268.416278) (xy 133.059437 -268.440885) (xy 133.051542 -268.489462)
			(xy 133.035958 -268.536143) (xy 133.013087 -268.57972) (xy 132.983522 -268.619064) (xy 132.948029 -268.653156)
			(xy 132.907526 -268.681112) (xy 132.863064 -268.70221) (xy 132.815793 -268.715902) (xy 132.766938 -268.721834)
			(xy 132.717763 -268.719853) (xy 132.669544 -268.710009) (xy 132.623528 -268.692557) (xy 132.580907 -268.66795)
			(xy 132.542786 -268.636825) (xy 132.510151 -268.599988) (xy 132.483848 -268.558392) (xy 132.464557 -268.513116)
			(xy 132.45278 -268.465332) (xy 132.44882 -268.416278) (xy 132.120132 -268.416278) (xy 132.119637 -268.440885)
			(xy 132.111742 -268.489462) (xy 132.096158 -268.536143) (xy 132.073287 -268.57972) (xy 132.043722 -268.619064)
			(xy 132.008229 -268.653156) (xy 131.967726 -268.681112) (xy 131.923264 -268.70221) (xy 131.875993 -268.715902)
			(xy 131.827138 -268.721834) (xy 131.777963 -268.719853) (xy 131.729744 -268.710009) (xy 131.683728 -268.692557)
			(xy 131.641107 -268.66795) (xy 131.602986 -268.636825) (xy 131.570351 -268.599988) (xy 131.544048 -268.558392)
			(xy 131.524757 -268.513116) (xy 131.51298 -268.465332) (xy 131.50902 -268.416278) (xy 130.240024 -268.416278)
			(xy 130.239529 -268.440885) (xy 130.231634 -268.489462) (xy 130.21605 -268.536143) (xy 130.193179 -268.57972)
			(xy 130.163614 -268.619064) (xy 130.128121 -268.653156) (xy 130.087618 -268.681112) (xy 130.043156 -268.70221)
			(xy 129.995885 -268.715902) (xy 129.94703 -268.721834) (xy 129.897855 -268.719853) (xy 129.849636 -268.710009)
			(xy 129.80362 -268.692557) (xy 129.760999 -268.66795) (xy 129.722878 -268.636825) (xy 129.690243 -268.599988)
			(xy 129.66394 -268.558392) (xy 129.644649 -268.513116) (xy 129.632872 -268.465332) (xy 129.628912 -268.416278)
			(xy 129.29997 -268.416278) (xy 129.299475 -268.440885) (xy 129.29158 -268.489462) (xy 129.275996 -268.536143)
			(xy 129.253125 -268.57972) (xy 129.22356 -268.619064) (xy 129.188067 -268.653156) (xy 129.147564 -268.681112)
			(xy 129.103102 -268.70221) (xy 129.055831 -268.715902) (xy 129.006976 -268.721834) (xy 128.957801 -268.719853)
			(xy 128.909582 -268.710009) (xy 128.863566 -268.692557) (xy 128.820945 -268.66795) (xy 128.782824 -268.636825)
			(xy 128.750189 -268.599988) (xy 128.723886 -268.558392) (xy 128.704595 -268.513116) (xy 128.692818 -268.465332)
			(xy 128.688858 -268.416278) (xy 128.36017 -268.416278) (xy 128.359675 -268.440885) (xy 128.35178 -268.489462)
			(xy 128.336196 -268.536143) (xy 128.313325 -268.57972) (xy 128.28376 -268.619064) (xy 128.248267 -268.653156)
			(xy 128.207764 -268.681112) (xy 128.163302 -268.70221) (xy 128.116031 -268.715902) (xy 128.067176 -268.721834)
			(xy 128.018001 -268.719853) (xy 127.969782 -268.710009) (xy 127.923766 -268.692557) (xy 127.881145 -268.66795)
			(xy 127.843024 -268.636825) (xy 127.810389 -268.599988) (xy 127.784086 -268.558392) (xy 127.764795 -268.513116)
			(xy 127.753018 -268.465332) (xy 127.749058 -268.416278) (xy 127.429209 -268.416278) (xy 127.430514 -268.418135)
			(xy 127.433578 -268.421358) (xy 128.039114 -269.026894) (xy 128.045971 -269.034288) (xy 128.053721 -269.052887)
			(xy 128.0541 -269.062962) (xy 128.0541 -269.226284) (xy 128.218958 -269.226284) (xy 128.222918 -269.17723)
			(xy 128.234695 -269.129446) (xy 128.253986 -269.08417) (xy 128.280289 -269.042574) (xy 128.312924 -269.005737)
			(xy 128.351045 -268.974612) (xy 128.393666 -268.950005) (xy 128.439682 -268.932553) (xy 128.487901 -268.922709)
			(xy 128.537076 -268.920728) (xy 128.585931 -268.92666) (xy 128.633202 -268.940352) (xy 128.677664 -268.96145)
			(xy 128.718167 -268.989406) (xy 128.75366 -269.023498) (xy 128.783225 -269.062842) (xy 128.806096 -269.106419)
			(xy 128.82168 -269.1531) (xy 128.829575 -269.201677) (xy 128.83007 -269.226284) (xy 129.148581 -269.226284)
			(xy 129.152676 -269.175556) (xy 129.164855 -269.126142) (xy 129.184803 -269.079322) (xy 129.212004 -269.036308)
			(xy 129.245752 -268.998214) (xy 129.285174 -268.966027) (xy 129.329248 -268.940581) (xy 129.376834 -268.922534)
			(xy 129.426698 -268.912354) (xy 129.47755 -268.910305) (xy 129.528071 -268.916439) (xy 129.576955 -268.930599)
			(xy 129.622934 -268.952416) (xy 129.664818 -268.981326) (xy 129.701522 -269.016581) (xy 129.732095 -269.057267)
			(xy 129.755746 -269.10233) (xy 129.771862 -269.150604) (xy 129.780026 -269.200838) (xy 129.780538 -269.226284)
			(xy 130.099066 -269.226284) (xy 130.103026 -269.17723) (xy 130.114803 -269.129446) (xy 130.134094 -269.08417)
			(xy 130.160397 -269.042574) (xy 130.193032 -269.005737) (xy 130.231153 -268.974612) (xy 130.273774 -268.950005)
			(xy 130.31979 -268.932553) (xy 130.368009 -268.922709) (xy 130.417184 -268.920728) (xy 130.466039 -268.92666)
			(xy 130.51331 -268.940352) (xy 130.557772 -268.96145) (xy 130.598275 -268.989406) (xy 130.633768 -269.023498)
			(xy 130.663333 -269.062842) (xy 130.686204 -269.106419) (xy 130.701788 -269.1531) (xy 130.709683 -269.201677)
			(xy 130.710178 -269.226284) (xy 131.038866 -269.226284) (xy 131.042826 -269.17723) (xy 131.054603 -269.129446)
			(xy 131.073894 -269.08417) (xy 131.100197 -269.042574) (xy 131.132832 -269.005737) (xy 131.170953 -268.974612)
			(xy 131.213574 -268.950005) (xy 131.25959 -268.932553) (xy 131.307809 -268.922709) (xy 131.356984 -268.920728)
			(xy 131.405839 -268.92666) (xy 131.45311 -268.940352) (xy 131.497572 -268.96145) (xy 131.538075 -268.989406)
			(xy 131.573568 -269.023498) (xy 131.603133 -269.062842) (xy 131.626004 -269.106419) (xy 131.641588 -269.1531)
			(xy 131.649483 -269.201677) (xy 131.649978 -269.226284) (xy 131.97892 -269.226284) (xy 131.98288 -269.17723)
			(xy 131.994657 -269.129446) (xy 132.013948 -269.08417) (xy 132.040251 -269.042574) (xy 132.072886 -269.005737)
			(xy 132.111007 -268.974612) (xy 132.153628 -268.950005) (xy 132.199644 -268.932553) (xy 132.247863 -268.922709)
			(xy 132.297038 -268.920728) (xy 132.345893 -268.92666) (xy 132.393164 -268.940352) (xy 132.437626 -268.96145)
			(xy 132.478129 -268.989406) (xy 132.513622 -269.023498) (xy 132.543187 -269.062842) (xy 132.566058 -269.106419)
			(xy 132.581642 -269.1531) (xy 132.589537 -269.201677) (xy 132.590032 -269.226284) (xy 132.908543 -269.226284)
			(xy 132.912638 -269.175556) (xy 132.924817 -269.126142) (xy 132.944765 -269.079322) (xy 132.971966 -269.036308)
			(xy 133.005714 -268.998214) (xy 133.045136 -268.966027) (xy 133.08921 -268.940581) (xy 133.136796 -268.922534)
			(xy 133.18666 -268.912354) (xy 133.237512 -268.910305) (xy 133.288033 -268.916439) (xy 133.336917 -268.930599)
			(xy 133.382896 -268.952416) (xy 133.42478 -268.981326) (xy 133.461484 -269.016581) (xy 133.492057 -269.057267)
			(xy 133.515708 -269.10233) (xy 133.531824 -269.150604) (xy 133.539988 -269.200838) (xy 133.5405 -269.226284)
			(xy 133.539988 -269.25173) (xy 133.531824 -269.301964) (xy 133.515708 -269.350238) (xy 133.492057 -269.395301)
			(xy 133.461484 -269.435987) (xy 133.42478 -269.471242) (xy 133.382896 -269.500152) (xy 133.336917 -269.521969)
			(xy 133.288033 -269.536129) (xy 133.237512 -269.542263) (xy 133.18666 -269.540214) (xy 133.136796 -269.530034)
			(xy 133.08921 -269.511987) (xy 133.045136 -269.486541) (xy 133.005714 -269.454354) (xy 132.971966 -269.41626)
			(xy 132.944765 -269.373246) (xy 132.924817 -269.326426) (xy 132.912638 -269.277012) (xy 132.908543 -269.226284)
			(xy 132.590032 -269.226284) (xy 132.589537 -269.250891) (xy 132.581642 -269.299468) (xy 132.566058 -269.346149)
			(xy 132.543187 -269.389726) (xy 132.513622 -269.42907) (xy 132.478129 -269.463162) (xy 132.437626 -269.491118)
			(xy 132.393164 -269.512216) (xy 132.345893 -269.525908) (xy 132.297038 -269.53184) (xy 132.247863 -269.529859)
			(xy 132.199644 -269.520015) (xy 132.153628 -269.502563) (xy 132.111007 -269.477956) (xy 132.072886 -269.446831)
			(xy 132.040251 -269.409994) (xy 132.013948 -269.368398) (xy 131.994657 -269.323122) (xy 131.98288 -269.275338)
			(xy 131.97892 -269.226284) (xy 131.649978 -269.226284) (xy 131.649483 -269.250891) (xy 131.641588 -269.299468)
			(xy 131.626004 -269.346149) (xy 131.603133 -269.389726) (xy 131.573568 -269.42907) (xy 131.538075 -269.463162)
			(xy 131.497572 -269.491118) (xy 131.45311 -269.512216) (xy 131.405839 -269.525908) (xy 131.356984 -269.53184)
			(xy 131.307809 -269.529859) (xy 131.25959 -269.520015) (xy 131.213574 -269.502563) (xy 131.170953 -269.477956)
			(xy 131.132832 -269.446831) (xy 131.100197 -269.409994) (xy 131.073894 -269.368398) (xy 131.054603 -269.323122)
			(xy 131.042826 -269.275338) (xy 131.038866 -269.226284) (xy 130.710178 -269.226284) (xy 130.709683 -269.250891)
			(xy 130.701788 -269.299468) (xy 130.686204 -269.346149) (xy 130.663333 -269.389726) (xy 130.633768 -269.42907)
			(xy 130.598275 -269.463162) (xy 130.557772 -269.491118) (xy 130.51331 -269.512216) (xy 130.466039 -269.525908)
			(xy 130.417184 -269.53184) (xy 130.368009 -269.529859) (xy 130.31979 -269.520015) (xy 130.273774 -269.502563)
			(xy 130.231153 -269.477956) (xy 130.193032 -269.446831) (xy 130.160397 -269.409994) (xy 130.134094 -269.368398)
			(xy 130.114803 -269.323122) (xy 130.103026 -269.275338) (xy 130.099066 -269.226284) (xy 129.780538 -269.226284)
			(xy 129.780026 -269.25173) (xy 129.771862 -269.301964) (xy 129.755746 -269.350238) (xy 129.732095 -269.395301)
			(xy 129.701522 -269.435987) (xy 129.664818 -269.471242) (xy 129.622934 -269.500152) (xy 129.576955 -269.521969)
			(xy 129.528071 -269.536129) (xy 129.47755 -269.542263) (xy 129.426698 -269.540214) (xy 129.376834 -269.530034)
			(xy 129.329248 -269.511987) (xy 129.285174 -269.486541) (xy 129.245752 -269.454354) (xy 129.212004 -269.41626)
			(xy 129.184803 -269.373246) (xy 129.164855 -269.326426) (xy 129.152676 -269.277012) (xy 129.148581 -269.226284)
			(xy 128.83007 -269.226284) (xy 128.829575 -269.250891) (xy 128.82168 -269.299468) (xy 128.806096 -269.346149)
			(xy 128.783225 -269.389726) (xy 128.75366 -269.42907) (xy 128.718167 -269.463162) (xy 128.677664 -269.491118)
			(xy 128.633202 -269.512216) (xy 128.585931 -269.525908) (xy 128.537076 -269.53184) (xy 128.487901 -269.529859)
			(xy 128.439682 -269.520015) (xy 128.393666 -269.502563) (xy 128.351045 -269.477956) (xy 128.312924 -269.446831)
			(xy 128.280289 -269.409994) (xy 128.253986 -269.368398) (xy 128.234695 -269.323122) (xy 128.222918 -269.275338)
			(xy 128.218958 -269.226284) (xy 128.0541 -269.226284) (xy 128.0541 -269.679674) (xy 128.054476 -269.688778)
			(xy 128.060858 -269.70583) (xy 128.066546 -269.712948) (xy 128.073658 -269.72133) (xy 128.100095 -269.723434)
			(xy 128.151767 -269.735363) (xy 128.200716 -269.755766) (xy 128.245563 -269.784067) (xy 128.285046 -269.819469)
			(xy 128.318053 -269.860976) (xy 128.343653 -269.907419) (xy 128.361126 -269.957488) (xy 128.36998 -270.009774)
			(xy 128.370584 -270.03629) (xy 128.688858 -270.03629) (xy 128.692818 -269.987236) (xy 128.704595 -269.939452)
			(xy 128.723886 -269.894176) (xy 128.750189 -269.85258) (xy 128.782824 -269.815743) (xy 128.820945 -269.784618)
			(xy 128.863566 -269.760011) (xy 128.909582 -269.742559) (xy 128.957801 -269.732715) (xy 129.006976 -269.730734)
			(xy 129.055831 -269.736666) (xy 129.103102 -269.750358) (xy 129.147564 -269.771456) (xy 129.188067 -269.799412)
			(xy 129.22356 -269.833504) (xy 129.253125 -269.872848) (xy 129.275996 -269.916425) (xy 129.29158 -269.963106)
			(xy 129.299475 -270.011683) (xy 129.29997 -270.03629) (xy 129.618481 -270.03629) (xy 129.622576 -269.985562)
			(xy 129.634755 -269.936148) (xy 129.654703 -269.889328) (xy 129.681904 -269.846314) (xy 129.715652 -269.80822)
			(xy 129.755074 -269.776033) (xy 129.799148 -269.750587) (xy 129.846734 -269.73254) (xy 129.896598 -269.72236)
			(xy 129.94745 -269.720311) (xy 129.997971 -269.726445) (xy 130.046855 -269.740605) (xy 130.092834 -269.762422)
			(xy 130.134718 -269.791332) (xy 130.171422 -269.826587) (xy 130.201995 -269.867273) (xy 130.225646 -269.912336)
			(xy 130.241762 -269.96061) (xy 130.249926 -270.010844) (xy 130.250438 -270.03629) (xy 130.568966 -270.03629)
			(xy 130.572926 -269.987236) (xy 130.584703 -269.939452) (xy 130.603994 -269.894176) (xy 130.630297 -269.85258)
			(xy 130.662932 -269.815743) (xy 130.701053 -269.784618) (xy 130.743674 -269.760011) (xy 130.78969 -269.742559)
			(xy 130.837909 -269.732715) (xy 130.887084 -269.730734) (xy 130.935939 -269.736666) (xy 130.98321 -269.750358)
			(xy 131.027672 -269.771456) (xy 131.068175 -269.799412) (xy 131.103668 -269.833504) (xy 131.133233 -269.872848)
			(xy 131.156104 -269.916425) (xy 131.171688 -269.963106) (xy 131.179583 -270.011683) (xy 131.180078 -270.03629)
			(xy 131.498589 -270.03629) (xy 131.502684 -269.985562) (xy 131.514863 -269.936148) (xy 131.534811 -269.889328)
			(xy 131.562012 -269.846314) (xy 131.59576 -269.80822) (xy 131.635182 -269.776033) (xy 131.679256 -269.750587)
			(xy 131.726842 -269.73254) (xy 131.776706 -269.72236) (xy 131.827558 -269.720311) (xy 131.878079 -269.726445)
			(xy 131.926963 -269.740605) (xy 131.972942 -269.762422) (xy 132.014826 -269.791332) (xy 132.05153 -269.826587)
			(xy 132.082103 -269.867273) (xy 132.105754 -269.912336) (xy 132.12187 -269.96061) (xy 132.130034 -270.010844)
			(xy 132.130546 -270.03629) (xy 132.438643 -270.03629) (xy 132.442738 -269.985562) (xy 132.454917 -269.936148)
			(xy 132.474865 -269.889328) (xy 132.502066 -269.846314) (xy 132.535814 -269.80822) (xy 132.575236 -269.776033)
			(xy 132.61931 -269.750587) (xy 132.666896 -269.73254) (xy 132.71676 -269.72236) (xy 132.767612 -269.720311)
			(xy 132.818133 -269.726445) (xy 132.867017 -269.740605) (xy 132.912996 -269.762422) (xy 132.95488 -269.791332)
			(xy 132.991584 -269.826587) (xy 133.022157 -269.867273) (xy 133.045808 -269.912336) (xy 133.061924 -269.96061)
			(xy 133.070088 -270.010844) (xy 133.0706 -270.03629) (xy 133.070088 -270.061736) (xy 133.061924 -270.11197)
			(xy 133.045808 -270.160244) (xy 133.022157 -270.205307) (xy 132.991584 -270.245993) (xy 132.95488 -270.281248)
			(xy 132.912996 -270.310158) (xy 132.867017 -270.331975) (xy 132.818133 -270.346135) (xy 132.767612 -270.352269)
			(xy 132.71676 -270.35022) (xy 132.666896 -270.34004) (xy 132.61931 -270.321993) (xy 132.575236 -270.296547)
			(xy 132.535814 -270.26436) (xy 132.502066 -270.226266) (xy 132.474865 -270.183252) (xy 132.454917 -270.136432)
			(xy 132.442738 -270.087018) (xy 132.438643 -270.03629) (xy 132.130546 -270.03629) (xy 132.130034 -270.061736)
			(xy 132.12187 -270.11197) (xy 132.105754 -270.160244) (xy 132.082103 -270.205307) (xy 132.05153 -270.245993)
			(xy 132.014826 -270.281248) (xy 131.972942 -270.310158) (xy 131.926963 -270.331975) (xy 131.878079 -270.346135)
			(xy 131.827558 -270.352269) (xy 131.776706 -270.35022) (xy 131.726842 -270.34004) (xy 131.679256 -270.321993)
			(xy 131.635182 -270.296547) (xy 131.59576 -270.26436) (xy 131.562012 -270.226266) (xy 131.534811 -270.183252)
			(xy 131.514863 -270.136432) (xy 131.502684 -270.087018) (xy 131.498589 -270.03629) (xy 131.180078 -270.03629)
			(xy 131.179583 -270.060897) (xy 131.171688 -270.109474) (xy 131.156104 -270.156155) (xy 131.133233 -270.199732)
			(xy 131.103668 -270.239076) (xy 131.068175 -270.273168) (xy 131.027672 -270.301124) (xy 130.98321 -270.322222)
			(xy 130.935939 -270.335914) (xy 130.887084 -270.341846) (xy 130.837909 -270.339865) (xy 130.78969 -270.330021)
			(xy 130.743674 -270.312569) (xy 130.701053 -270.287962) (xy 130.662932 -270.256837) (xy 130.630297 -270.22)
			(xy 130.603994 -270.178404) (xy 130.584703 -270.133128) (xy 130.572926 -270.085344) (xy 130.568966 -270.03629)
			(xy 130.250438 -270.03629) (xy 130.249926 -270.061736) (xy 130.241762 -270.11197) (xy 130.225646 -270.160244)
			(xy 130.201995 -270.205307) (xy 130.171422 -270.245993) (xy 130.134718 -270.281248) (xy 130.092834 -270.310158)
			(xy 130.046855 -270.331975) (xy 129.997971 -270.346135) (xy 129.94745 -270.352269) (xy 129.896598 -270.35022)
			(xy 129.846734 -270.34004) (xy 129.799148 -270.321993) (xy 129.755074 -270.296547) (xy 129.715652 -270.26436)
			(xy 129.681904 -270.226266) (xy 129.654703 -270.183252) (xy 129.634755 -270.136432) (xy 129.622576 -270.087018)
			(xy 129.618481 -270.03629) (xy 129.29997 -270.03629) (xy 129.299475 -270.060897) (xy 129.29158 -270.109474)
			(xy 129.275996 -270.156155) (xy 129.253125 -270.199732) (xy 129.22356 -270.239076) (xy 129.188067 -270.273168)
			(xy 129.147564 -270.301124) (xy 129.103102 -270.322222) (xy 129.055831 -270.335914) (xy 129.006976 -270.341846)
			(xy 128.957801 -270.339865) (xy 128.909582 -270.330021) (xy 128.863566 -270.312569) (xy 128.820945 -270.287962)
			(xy 128.782824 -270.256837) (xy 128.750189 -270.22) (xy 128.723886 -270.178404) (xy 128.704595 -270.133128)
			(xy 128.692818 -270.085344) (xy 128.688858 -270.03629) (xy 128.370584 -270.03629) (xy 128.370103 -270.061451)
			(xy 128.362135 -270.111138) (xy 128.346382 -270.158931) (xy 128.323245 -270.203619) (xy 128.293309 -270.244069)
			(xy 128.257334 -270.279255) (xy 128.216231 -270.308287) (xy 128.171041 -270.330427) (xy 128.122911 -270.345116)
			(xy 128.098042 -270.348964) (xy 128.091438 -270.34998) (xy 128.082489 -270.351581) (xy 128.066486 -270.360179)
			(xy 128.060196 -270.366744) (xy 128.0541 -270.373856) (xy 128.0541 -270.846296) (xy 128.208527 -270.846296)
			(xy 128.212622 -270.795568) (xy 128.224801 -270.746154) (xy 128.244749 -270.699334) (xy 128.27195 -270.65632)
			(xy 128.305698 -270.618226) (xy 128.34512 -270.586039) (xy 128.389194 -270.560593) (xy 128.43678 -270.542546)
			(xy 128.486644 -270.532366) (xy 128.537496 -270.530317) (xy 128.588017 -270.536451) (xy 128.636901 -270.550611)
			(xy 128.68288 -270.572428) (xy 128.724764 -270.601338) (xy 128.761468 -270.636593) (xy 128.792041 -270.677279)
			(xy 128.815692 -270.722342) (xy 128.831808 -270.770616) (xy 128.839972 -270.82085) (xy 128.840484 -270.846296)
			(xy 129.148581 -270.846296) (xy 129.152676 -270.795568) (xy 129.164855 -270.746154) (xy 129.184803 -270.699334)
			(xy 129.212004 -270.65632) (xy 129.245752 -270.618226) (xy 129.285174 -270.586039) (xy 129.329248 -270.560593)
			(xy 129.376834 -270.542546) (xy 129.426698 -270.532366) (xy 129.47755 -270.530317) (xy 129.528071 -270.536451)
			(xy 129.576955 -270.550611) (xy 129.622934 -270.572428) (xy 129.664818 -270.601338) (xy 129.701522 -270.636593)
			(xy 129.732095 -270.677279) (xy 129.755746 -270.722342) (xy 129.771862 -270.770616) (xy 129.780026 -270.82085)
			(xy 129.780538 -270.846296) (xy 131.028435 -270.846296) (xy 131.03253 -270.795568) (xy 131.044709 -270.746154)
			(xy 131.064657 -270.699334) (xy 131.091858 -270.65632) (xy 131.125606 -270.618226) (xy 131.165028 -270.586039)
			(xy 131.209102 -270.560593) (xy 131.256688 -270.542546) (xy 131.306552 -270.532366) (xy 131.357404 -270.530317)
			(xy 131.407925 -270.536451) (xy 131.456809 -270.550611) (xy 131.502788 -270.572428) (xy 131.544672 -270.601338)
			(xy 131.581376 -270.636593) (xy 131.611949 -270.677279) (xy 131.6356 -270.722342) (xy 131.651716 -270.770616)
			(xy 131.65988 -270.82085) (xy 131.660392 -270.846296) (xy 131.97892 -270.846296) (xy 131.98288 -270.797242)
			(xy 131.994657 -270.749458) (xy 132.013948 -270.704182) (xy 132.040251 -270.662586) (xy 132.072886 -270.625749)
			(xy 132.111007 -270.594624) (xy 132.153628 -270.570017) (xy 132.199644 -270.552565) (xy 132.247863 -270.542721)
			(xy 132.297038 -270.54074) (xy 132.345893 -270.546672) (xy 132.393164 -270.560364) (xy 132.437626 -270.581462)
			(xy 132.478129 -270.609418) (xy 132.513622 -270.64351) (xy 132.543187 -270.682854) (xy 132.566058 -270.726431)
			(xy 132.581642 -270.773112) (xy 132.589537 -270.821689) (xy 132.590032 -270.846296) (xy 132.908543 -270.846296)
			(xy 132.912638 -270.795568) (xy 132.924817 -270.746154) (xy 132.944765 -270.699334) (xy 132.971966 -270.65632)
			(xy 133.005714 -270.618226) (xy 133.045136 -270.586039) (xy 133.08921 -270.560593) (xy 133.136796 -270.542546)
			(xy 133.18666 -270.532366) (xy 133.237512 -270.530317) (xy 133.288033 -270.536451) (xy 133.336917 -270.550611)
			(xy 133.382896 -270.572428) (xy 133.42478 -270.601338) (xy 133.461484 -270.636593) (xy 133.492057 -270.677279)
			(xy 133.515708 -270.722342) (xy 133.531824 -270.770616) (xy 133.539988 -270.82085) (xy 133.5405 -270.846296)
			(xy 133.539988 -270.871742) (xy 133.531824 -270.921976) (xy 133.515708 -270.97025) (xy 133.492057 -271.015313)
			(xy 133.461484 -271.055999) (xy 133.42478 -271.091254) (xy 133.382896 -271.120164) (xy 133.336917 -271.141981)
			(xy 133.288033 -271.156141) (xy 133.237512 -271.162275) (xy 133.18666 -271.160226) (xy 133.136796 -271.150046)
			(xy 133.08921 -271.131999) (xy 133.045136 -271.106553) (xy 133.005714 -271.074366) (xy 132.971966 -271.036272)
			(xy 132.944765 -270.993258) (xy 132.924817 -270.946438) (xy 132.912638 -270.897024) (xy 132.908543 -270.846296)
			(xy 132.590032 -270.846296) (xy 132.589537 -270.870903) (xy 132.581642 -270.91948) (xy 132.566058 -270.966161)
			(xy 132.543187 -271.009738) (xy 132.513622 -271.049082) (xy 132.478129 -271.083174) (xy 132.437626 -271.11113)
			(xy 132.393164 -271.132228) (xy 132.345893 -271.14592) (xy 132.297038 -271.151852) (xy 132.247863 -271.149871)
			(xy 132.199644 -271.140027) (xy 132.153628 -271.122575) (xy 132.111007 -271.097968) (xy 132.072886 -271.066843)
			(xy 132.040251 -271.030006) (xy 132.013948 -270.98841) (xy 131.994657 -270.943134) (xy 131.98288 -270.89535)
			(xy 131.97892 -270.846296) (xy 131.660392 -270.846296) (xy 131.65988 -270.871742) (xy 131.651716 -270.921976)
			(xy 131.6356 -270.97025) (xy 131.611949 -271.015313) (xy 131.581376 -271.055999) (xy 131.544672 -271.091254)
			(xy 131.502788 -271.120164) (xy 131.456809 -271.141981) (xy 131.407925 -271.156141) (xy 131.357404 -271.162275)
			(xy 131.306552 -271.160226) (xy 131.256688 -271.150046) (xy 131.209102 -271.131999) (xy 131.165028 -271.106553)
			(xy 131.125606 -271.074366) (xy 131.091858 -271.036272) (xy 131.064657 -270.993258) (xy 131.044709 -270.946438)
			(xy 131.03253 -270.897024) (xy 131.028435 -270.846296) (xy 129.780538 -270.846296) (xy 129.780026 -270.871742)
			(xy 129.771862 -270.921976) (xy 129.755746 -270.97025) (xy 129.732095 -271.015313) (xy 129.701522 -271.055999)
			(xy 129.664818 -271.091254) (xy 129.622934 -271.120164) (xy 129.576955 -271.141981) (xy 129.528071 -271.156141)
			(xy 129.47755 -271.162275) (xy 129.426698 -271.160226) (xy 129.376834 -271.150046) (xy 129.329248 -271.131999)
			(xy 129.285174 -271.106553) (xy 129.245752 -271.074366) (xy 129.212004 -271.036272) (xy 129.184803 -270.993258)
			(xy 129.164855 -270.946438) (xy 129.152676 -270.897024) (xy 129.148581 -270.846296) (xy 128.840484 -270.846296)
			(xy 128.839972 -270.871742) (xy 128.831808 -270.921976) (xy 128.815692 -270.97025) (xy 128.792041 -271.015313)
			(xy 128.761468 -271.055999) (xy 128.724764 -271.091254) (xy 128.68288 -271.120164) (xy 128.636901 -271.141981)
			(xy 128.588017 -271.156141) (xy 128.537496 -271.162275) (xy 128.486644 -271.160226) (xy 128.43678 -271.150046)
			(xy 128.389194 -271.131999) (xy 128.34512 -271.106553) (xy 128.305698 -271.074366) (xy 128.27195 -271.036272)
			(xy 128.244749 -270.993258) (xy 128.224801 -270.946438) (xy 128.212622 -270.897024) (xy 128.208527 -270.846296)
			(xy 128.0541 -270.846296) (xy 128.0541 -271.299686) (xy 128.054478 -271.308789) (xy 128.060863 -271.325838)
			(xy 128.066546 -271.33296) (xy 128.072642 -271.340072) (xy 128.098042 -271.343628) (xy 128.122893 -271.34755)
			(xy 128.171008 -271.362245) (xy 128.216183 -271.384386) (xy 128.257273 -271.413412) (xy 128.293239 -271.448589)
			(xy 128.32317 -271.489025) (xy 128.346307 -271.533698) (xy 128.362065 -271.581474) (xy 128.370046 -271.631146)
			(xy 128.370045 -271.656302) (xy 128.688858 -271.656302) (xy 128.692818 -271.607248) (xy 128.704595 -271.559464)
			(xy 128.723886 -271.514188) (xy 128.750189 -271.472592) (xy 128.782824 -271.435755) (xy 128.820945 -271.40463)
			(xy 128.863566 -271.380023) (xy 128.909582 -271.362571) (xy 128.957801 -271.352727) (xy 129.006976 -271.350746)
			(xy 129.055831 -271.356678) (xy 129.103102 -271.37037) (xy 129.147564 -271.391468) (xy 129.188067 -271.419424)
			(xy 129.22356 -271.453516) (xy 129.253125 -271.49286) (xy 129.275996 -271.536437) (xy 129.29158 -271.583118)
			(xy 129.299475 -271.631695) (xy 129.29997 -271.656302) (xy 129.618481 -271.656302) (xy 129.622576 -271.605574)
			(xy 129.634755 -271.55616) (xy 129.654703 -271.50934) (xy 129.681904 -271.466326) (xy 129.715652 -271.428232)
			(xy 129.755074 -271.396045) (xy 129.799148 -271.370599) (xy 129.846734 -271.352552) (xy 129.896598 -271.342372)
			(xy 129.94745 -271.340323) (xy 129.997971 -271.346457) (xy 130.046855 -271.360617) (xy 130.092834 -271.382434)
			(xy 130.134718 -271.411344) (xy 130.171422 -271.446599) (xy 130.201995 -271.487285) (xy 130.225646 -271.532348)
			(xy 130.241762 -271.580622) (xy 130.249926 -271.630856) (xy 130.250438 -271.656302) (xy 130.568966 -271.656302)
			(xy 130.572926 -271.607248) (xy 130.584703 -271.559464) (xy 130.603994 -271.514188) (xy 130.630297 -271.472592)
			(xy 130.662932 -271.435755) (xy 130.701053 -271.40463) (xy 130.743674 -271.380023) (xy 130.78969 -271.362571)
			(xy 130.837909 -271.352727) (xy 130.887084 -271.350746) (xy 130.935939 -271.356678) (xy 130.98321 -271.37037)
			(xy 131.027672 -271.391468) (xy 131.068175 -271.419424) (xy 131.103668 -271.453516) (xy 131.133233 -271.49286)
			(xy 131.156104 -271.536437) (xy 131.171688 -271.583118) (xy 131.179583 -271.631695) (xy 131.180078 -271.656302)
			(xy 131.498589 -271.656302) (xy 131.502684 -271.605574) (xy 131.514863 -271.55616) (xy 131.534811 -271.50934)
			(xy 131.562012 -271.466326) (xy 131.59576 -271.428232) (xy 131.635182 -271.396045) (xy 131.679256 -271.370599)
			(xy 131.726842 -271.352552) (xy 131.776706 -271.342372) (xy 131.827558 -271.340323) (xy 131.878079 -271.346457)
			(xy 131.926963 -271.360617) (xy 131.972942 -271.382434) (xy 132.014826 -271.411344) (xy 132.05153 -271.446599)
			(xy 132.082103 -271.487285) (xy 132.105754 -271.532348) (xy 132.12187 -271.580622) (xy 132.130034 -271.630856)
			(xy 132.130546 -271.656302) (xy 132.438643 -271.656302) (xy 132.442738 -271.605574) (xy 132.454917 -271.55616)
			(xy 132.474865 -271.50934) (xy 132.502066 -271.466326) (xy 132.535814 -271.428232) (xy 132.575236 -271.396045)
			(xy 132.61931 -271.370599) (xy 132.666896 -271.352552) (xy 132.71676 -271.342372) (xy 132.767612 -271.340323)
			(xy 132.818133 -271.346457) (xy 132.867017 -271.360617) (xy 132.912996 -271.382434) (xy 132.95488 -271.411344)
			(xy 132.991584 -271.446599) (xy 133.022157 -271.487285) (xy 133.045808 -271.532348) (xy 133.061924 -271.580622)
			(xy 133.070088 -271.630856) (xy 133.0706 -271.656302) (xy 133.070088 -271.681748) (xy 133.061924 -271.731982)
			(xy 133.045808 -271.780256) (xy 133.022157 -271.825319) (xy 132.991584 -271.866005) (xy 132.95488 -271.90126)
			(xy 132.912996 -271.93017) (xy 132.867017 -271.951987) (xy 132.818133 -271.966147) (xy 132.767612 -271.972281)
			(xy 132.71676 -271.970232) (xy 132.666896 -271.960052) (xy 132.61931 -271.942005) (xy 132.575236 -271.916559)
			(xy 132.535814 -271.884372) (xy 132.502066 -271.846278) (xy 132.474865 -271.803264) (xy 132.454917 -271.756444)
			(xy 132.442738 -271.70703) (xy 132.438643 -271.656302) (xy 132.130546 -271.656302) (xy 132.130034 -271.681748)
			(xy 132.12187 -271.731982) (xy 132.105754 -271.780256) (xy 132.082103 -271.825319) (xy 132.05153 -271.866005)
			(xy 132.014826 -271.90126) (xy 131.972942 -271.93017) (xy 131.926963 -271.951987) (xy 131.878079 -271.966147)
			(xy 131.827558 -271.972281) (xy 131.776706 -271.970232) (xy 131.726842 -271.960052) (xy 131.679256 -271.942005)
			(xy 131.635182 -271.916559) (xy 131.59576 -271.884372) (xy 131.562012 -271.846278) (xy 131.534811 -271.803264)
			(xy 131.514863 -271.756444) (xy 131.502684 -271.70703) (xy 131.498589 -271.656302) (xy 131.180078 -271.656302)
			(xy 131.179583 -271.680909) (xy 131.171688 -271.729486) (xy 131.156104 -271.776167) (xy 131.133233 -271.819744)
			(xy 131.103668 -271.859088) (xy 131.068175 -271.89318) (xy 131.027672 -271.921136) (xy 130.98321 -271.942234)
			(xy 130.935939 -271.955926) (xy 130.887084 -271.961858) (xy 130.837909 -271.959877) (xy 130.78969 -271.950033)
			(xy 130.743674 -271.932581) (xy 130.701053 -271.907974) (xy 130.662932 -271.876849) (xy 130.630297 -271.840012)
			(xy 130.603994 -271.798416) (xy 130.584703 -271.75314) (xy 130.572926 -271.705356) (xy 130.568966 -271.656302)
			(xy 130.250438 -271.656302) (xy 130.249926 -271.681748) (xy 130.241762 -271.731982) (xy 130.225646 -271.780256)
			(xy 130.201995 -271.825319) (xy 130.171422 -271.866005) (xy 130.134718 -271.90126) (xy 130.092834 -271.93017)
			(xy 130.046855 -271.951987) (xy 129.997971 -271.966147) (xy 129.94745 -271.972281) (xy 129.896598 -271.970232)
			(xy 129.846734 -271.960052) (xy 129.799148 -271.942005) (xy 129.755074 -271.916559) (xy 129.715652 -271.884372)
			(xy 129.681904 -271.846278) (xy 129.654703 -271.803264) (xy 129.634755 -271.756444) (xy 129.622576 -271.70703)
			(xy 129.618481 -271.656302) (xy 129.29997 -271.656302) (xy 129.299475 -271.680909) (xy 129.29158 -271.729486)
			(xy 129.275996 -271.776167) (xy 129.253125 -271.819744) (xy 129.22356 -271.859088) (xy 129.188067 -271.89318)
			(xy 129.147564 -271.921136) (xy 129.103102 -271.942234) (xy 129.055831 -271.955926) (xy 129.006976 -271.961858)
			(xy 128.957801 -271.959877) (xy 128.909582 -271.950033) (xy 128.863566 -271.932581) (xy 128.820945 -271.907974)
			(xy 128.782824 -271.876849) (xy 128.750189 -271.840012) (xy 128.723886 -271.798416) (xy 128.704595 -271.75314)
			(xy 128.692818 -271.705356) (xy 128.688858 -271.656302) (xy 128.370045 -271.656302) (xy 128.370045 -271.681455)
			(xy 128.362065 -271.731126) (xy 128.346307 -271.778903) (xy 128.323169 -271.823575) (xy 128.293239 -271.864012)
			(xy 128.257273 -271.899188) (xy 128.216182 -271.928215) (xy 128.171008 -271.950355) (xy 128.122893 -271.96505)
			(xy 128.098042 -271.968976) (xy 128.091438 -271.969992) (xy 128.082489 -271.971593) (xy 128.066488 -271.980193)
			(xy 128.060196 -271.986756) (xy 128.0541 -271.993868) (xy 128.0541 -272.466308) (xy 128.208527 -272.466308)
			(xy 128.212622 -272.41558) (xy 128.224801 -272.366166) (xy 128.244749 -272.319346) (xy 128.27195 -272.276332)
			(xy 128.305698 -272.238238) (xy 128.34512 -272.206051) (xy 128.389194 -272.180605) (xy 128.43678 -272.162558)
			(xy 128.486644 -272.152378) (xy 128.537496 -272.150329) (xy 128.588017 -272.156463) (xy 128.636901 -272.170623)
			(xy 128.68288 -272.19244) (xy 128.724764 -272.22135) (xy 128.761468 -272.256605) (xy 128.792041 -272.297291)
			(xy 128.815692 -272.342354) (xy 128.831808 -272.390628) (xy 128.839972 -272.440862) (xy 128.840484 -272.466308)
			(xy 129.148581 -272.466308) (xy 129.152676 -272.41558) (xy 129.164855 -272.366166) (xy 129.184803 -272.319346)
			(xy 129.212004 -272.276332) (xy 129.245752 -272.238238) (xy 129.285174 -272.206051) (xy 129.329248 -272.180605)
			(xy 129.376834 -272.162558) (xy 129.426698 -272.152378) (xy 129.47755 -272.150329) (xy 129.528071 -272.156463)
			(xy 129.576955 -272.170623) (xy 129.622934 -272.19244) (xy 129.664818 -272.22135) (xy 129.701522 -272.256605)
			(xy 129.732095 -272.297291) (xy 129.755746 -272.342354) (xy 129.771862 -272.390628) (xy 129.780026 -272.440862)
			(xy 129.780538 -272.466308) (xy 130.099066 -272.466308) (xy 130.103026 -272.417254) (xy 130.114803 -272.36947)
			(xy 130.134094 -272.324194) (xy 130.160397 -272.282598) (xy 130.193032 -272.245761) (xy 130.231153 -272.214636)
			(xy 130.273774 -272.190029) (xy 130.31979 -272.172577) (xy 130.368009 -272.162733) (xy 130.417184 -272.160752)
			(xy 130.466039 -272.166684) (xy 130.51331 -272.180376) (xy 130.557772 -272.201474) (xy 130.598275 -272.22943)
			(xy 130.633768 -272.263522) (xy 130.663333 -272.302866) (xy 130.686204 -272.346443) (xy 130.701788 -272.393124)
			(xy 130.709683 -272.441701) (xy 130.710178 -272.466308) (xy 131.028435 -272.466308) (xy 131.03253 -272.41558)
			(xy 131.044709 -272.366166) (xy 131.064657 -272.319346) (xy 131.091858 -272.276332) (xy 131.125606 -272.238238)
			(xy 131.165028 -272.206051) (xy 131.209102 -272.180605) (xy 131.256688 -272.162558) (xy 131.306552 -272.152378)
			(xy 131.357404 -272.150329) (xy 131.407925 -272.156463) (xy 131.456809 -272.170623) (xy 131.502788 -272.19244)
			(xy 131.544672 -272.22135) (xy 131.581376 -272.256605) (xy 131.611949 -272.297291) (xy 131.6356 -272.342354)
			(xy 131.651716 -272.390628) (xy 131.65988 -272.440862) (xy 131.660392 -272.466308) (xy 131.97892 -272.466308)
			(xy 131.98288 -272.417254) (xy 131.994657 -272.36947) (xy 132.013948 -272.324194) (xy 132.040251 -272.282598)
			(xy 132.072886 -272.245761) (xy 132.111007 -272.214636) (xy 132.153628 -272.190029) (xy 132.199644 -272.172577)
			(xy 132.247863 -272.162733) (xy 132.297038 -272.160752) (xy 132.345893 -272.166684) (xy 132.393164 -272.180376)
			(xy 132.437626 -272.201474) (xy 132.478129 -272.22943) (xy 132.513622 -272.263522) (xy 132.543187 -272.302866)
			(xy 132.566058 -272.346443) (xy 132.581642 -272.393124) (xy 132.589537 -272.441701) (xy 132.590032 -272.466308)
			(xy 132.908543 -272.466308) (xy 132.912638 -272.41558) (xy 132.924817 -272.366166) (xy 132.944765 -272.319346)
			(xy 132.971966 -272.276332) (xy 133.005714 -272.238238) (xy 133.045136 -272.206051) (xy 133.08921 -272.180605)
			(xy 133.136796 -272.162558) (xy 133.18666 -272.152378) (xy 133.237512 -272.150329) (xy 133.288033 -272.156463)
			(xy 133.336917 -272.170623) (xy 133.382896 -272.19244) (xy 133.42478 -272.22135) (xy 133.461484 -272.256605)
			(xy 133.492057 -272.297291) (xy 133.515708 -272.342354) (xy 133.531824 -272.390628) (xy 133.539988 -272.440862)
			(xy 133.5405 -272.466308) (xy 133.539988 -272.491754) (xy 133.531824 -272.541988) (xy 133.515708 -272.590262)
			(xy 133.492057 -272.635325) (xy 133.461484 -272.676011) (xy 133.42478 -272.711266) (xy 133.382896 -272.740176)
			(xy 133.336917 -272.761993) (xy 133.288033 -272.776153) (xy 133.237512 -272.782287) (xy 133.18666 -272.780238)
			(xy 133.136796 -272.770058) (xy 133.08921 -272.752011) (xy 133.045136 -272.726565) (xy 133.005714 -272.694378)
			(xy 132.971966 -272.656284) (xy 132.944765 -272.61327) (xy 132.924817 -272.56645) (xy 132.912638 -272.517036)
			(xy 132.908543 -272.466308) (xy 132.590032 -272.466308) (xy 132.589537 -272.490915) (xy 132.581642 -272.539492)
			(xy 132.566058 -272.586173) (xy 132.543187 -272.62975) (xy 132.513622 -272.669094) (xy 132.478129 -272.703186)
			(xy 132.437626 -272.731142) (xy 132.393164 -272.75224) (xy 132.345893 -272.765932) (xy 132.297038 -272.771864)
			(xy 132.247863 -272.769883) (xy 132.199644 -272.760039) (xy 132.153628 -272.742587) (xy 132.111007 -272.71798)
			(xy 132.072886 -272.686855) (xy 132.040251 -272.650018) (xy 132.013948 -272.608422) (xy 131.994657 -272.563146)
			(xy 131.98288 -272.515362) (xy 131.97892 -272.466308) (xy 131.660392 -272.466308) (xy 131.65988 -272.491754)
			(xy 131.651716 -272.541988) (xy 131.6356 -272.590262) (xy 131.611949 -272.635325) (xy 131.581376 -272.676011)
			(xy 131.544672 -272.711266) (xy 131.502788 -272.740176) (xy 131.456809 -272.761993) (xy 131.407925 -272.776153)
			(xy 131.357404 -272.782287) (xy 131.306552 -272.780238) (xy 131.256688 -272.770058) (xy 131.209102 -272.752011)
			(xy 131.165028 -272.726565) (xy 131.125606 -272.694378) (xy 131.091858 -272.656284) (xy 131.064657 -272.61327)
			(xy 131.044709 -272.56645) (xy 131.03253 -272.517036) (xy 131.028435 -272.466308) (xy 130.710178 -272.466308)
			(xy 130.709683 -272.490915) (xy 130.701788 -272.539492) (xy 130.686204 -272.586173) (xy 130.663333 -272.62975)
			(xy 130.633768 -272.669094) (xy 130.598275 -272.703186) (xy 130.557772 -272.731142) (xy 130.51331 -272.75224)
			(xy 130.466039 -272.765932) (xy 130.417184 -272.771864) (xy 130.368009 -272.769883) (xy 130.31979 -272.760039)
			(xy 130.273774 -272.742587) (xy 130.231153 -272.71798) (xy 130.193032 -272.686855) (xy 130.160397 -272.650018)
			(xy 130.134094 -272.608422) (xy 130.114803 -272.563146) (xy 130.103026 -272.515362) (xy 130.099066 -272.466308)
			(xy 129.780538 -272.466308) (xy 129.780026 -272.491754) (xy 129.771862 -272.541988) (xy 129.755746 -272.590262)
			(xy 129.732095 -272.635325) (xy 129.701522 -272.676011) (xy 129.664818 -272.711266) (xy 129.622934 -272.740176)
			(xy 129.576955 -272.761993) (xy 129.528071 -272.776153) (xy 129.47755 -272.782287) (xy 129.426698 -272.780238)
			(xy 129.376834 -272.770058) (xy 129.329248 -272.752011) (xy 129.285174 -272.726565) (xy 129.245752 -272.694378)
			(xy 129.212004 -272.656284) (xy 129.184803 -272.61327) (xy 129.164855 -272.56645) (xy 129.152676 -272.517036)
			(xy 129.148581 -272.466308) (xy 128.840484 -272.466308) (xy 128.839972 -272.491754) (xy 128.831808 -272.541988)
			(xy 128.815692 -272.590262) (xy 128.792041 -272.635325) (xy 128.761468 -272.676011) (xy 128.724764 -272.711266)
			(xy 128.68288 -272.740176) (xy 128.636901 -272.761993) (xy 128.588017 -272.776153) (xy 128.537496 -272.782287)
			(xy 128.486644 -272.780238) (xy 128.43678 -272.770058) (xy 128.389194 -272.752011) (xy 128.34512 -272.726565)
			(xy 128.305698 -272.694378) (xy 128.27195 -272.656284) (xy 128.244749 -272.61327) (xy 128.224801 -272.56645)
			(xy 128.212622 -272.517036) (xy 128.208527 -272.466308) (xy 128.0541 -272.466308) (xy 128.0541 -272.919698)
			(xy 128.05448 -272.9288) (xy 128.060868 -272.945847) (xy 128.066546 -272.952972) (xy 128.072642 -272.960084)
			(xy 128.098042 -272.96364) (xy 128.122892 -272.967562) (xy 128.171005 -272.982257) (xy 128.216178 -273.004397)
			(xy 128.257267 -273.033422) (xy 128.293231 -273.068598) (xy 128.32316 -273.109033) (xy 128.346297 -273.153704)
			(xy 128.362054 -273.201479) (xy 128.370034 -273.251149) (xy 128.370034 -273.276314) (xy 128.688858 -273.276314)
			(xy 128.692818 -273.22726) (xy 128.704595 -273.179476) (xy 128.723886 -273.1342) (xy 128.750189 -273.092604)
			(xy 128.782824 -273.055767) (xy 128.820945 -273.024642) (xy 128.863566 -273.000035) (xy 128.909582 -272.982583)
			(xy 128.957801 -272.972739) (xy 129.006976 -272.970758) (xy 129.055831 -272.97669) (xy 129.103102 -272.990382)
			(xy 129.147564 -273.01148) (xy 129.188067 -273.039436) (xy 129.22356 -273.073528) (xy 129.253125 -273.112872)
			(xy 129.275996 -273.156449) (xy 129.29158 -273.20313) (xy 129.299475 -273.251707) (xy 129.29997 -273.276314)
			(xy 129.618481 -273.276314) (xy 129.622576 -273.225586) (xy 129.634755 -273.176172) (xy 129.654703 -273.129352)
			(xy 129.681904 -273.086338) (xy 129.715652 -273.048244) (xy 129.755074 -273.016057) (xy 129.799148 -272.990611)
			(xy 129.846734 -272.972564) (xy 129.896598 -272.962384) (xy 129.94745 -272.960335) (xy 129.997971 -272.966469)
			(xy 130.046855 -272.980629) (xy 130.092834 -273.002446) (xy 130.134718 -273.031356) (xy 130.171422 -273.066611)
			(xy 130.201995 -273.107297) (xy 130.225646 -273.15236) (xy 130.241762 -273.200634) (xy 130.249926 -273.250868)
			(xy 130.250438 -273.276314) (xy 131.498589 -273.276314) (xy 131.502684 -273.225586) (xy 131.514863 -273.176172)
			(xy 131.534811 -273.129352) (xy 131.562012 -273.086338) (xy 131.59576 -273.048244) (xy 131.635182 -273.016057)
			(xy 131.679256 -272.990611) (xy 131.726842 -272.972564) (xy 131.776706 -272.962384) (xy 131.827558 -272.960335)
			(xy 131.878079 -272.966469) (xy 131.926963 -272.980629) (xy 131.972942 -273.002446) (xy 132.014826 -273.031356)
			(xy 132.05153 -273.066611) (xy 132.082103 -273.107297) (xy 132.105754 -273.15236) (xy 132.12187 -273.200634)
			(xy 132.130034 -273.250868) (xy 132.130546 -273.276314) (xy 132.438643 -273.276314) (xy 132.442738 -273.225586)
			(xy 132.454917 -273.176172) (xy 132.474865 -273.129352) (xy 132.502066 -273.086338) (xy 132.535814 -273.048244)
			(xy 132.575236 -273.016057) (xy 132.61931 -272.990611) (xy 132.666896 -272.972564) (xy 132.71676 -272.962384)
			(xy 132.767612 -272.960335) (xy 132.818133 -272.966469) (xy 132.867017 -272.980629) (xy 132.912996 -273.002446)
			(xy 132.95488 -273.031356) (xy 132.991584 -273.066611) (xy 133.022157 -273.107297) (xy 133.045808 -273.15236)
			(xy 133.061924 -273.200634) (xy 133.070088 -273.250868) (xy 133.0706 -273.276314) (xy 133.070088 -273.30176)
			(xy 133.061924 -273.351994) (xy 133.045808 -273.400268) (xy 133.022157 -273.445331) (xy 132.991584 -273.486017)
			(xy 132.95488 -273.521272) (xy 132.912996 -273.550182) (xy 132.867017 -273.571999) (xy 132.818133 -273.586159)
			(xy 132.767612 -273.592293) (xy 132.71676 -273.590244) (xy 132.666896 -273.580064) (xy 132.61931 -273.562017)
			(xy 132.575236 -273.536571) (xy 132.535814 -273.504384) (xy 132.502066 -273.46629) (xy 132.474865 -273.423276)
			(xy 132.454917 -273.376456) (xy 132.442738 -273.327042) (xy 132.438643 -273.276314) (xy 132.130546 -273.276314)
			(xy 132.130034 -273.30176) (xy 132.12187 -273.351994) (xy 132.105754 -273.400268) (xy 132.082103 -273.445331)
			(xy 132.05153 -273.486017) (xy 132.014826 -273.521272) (xy 131.972942 -273.550182) (xy 131.926963 -273.571999)
			(xy 131.878079 -273.586159) (xy 131.827558 -273.592293) (xy 131.776706 -273.590244) (xy 131.726842 -273.580064)
			(xy 131.679256 -273.562017) (xy 131.635182 -273.536571) (xy 131.59576 -273.504384) (xy 131.562012 -273.46629)
			(xy 131.534811 -273.423276) (xy 131.514863 -273.376456) (xy 131.502684 -273.327042) (xy 131.498589 -273.276314)
			(xy 130.250438 -273.276314) (xy 130.249926 -273.30176) (xy 130.241762 -273.351994) (xy 130.225646 -273.400268)
			(xy 130.201995 -273.445331) (xy 130.171422 -273.486017) (xy 130.134718 -273.521272) (xy 130.092834 -273.550182)
			(xy 130.046855 -273.571999) (xy 129.997971 -273.586159) (xy 129.94745 -273.592293) (xy 129.896598 -273.590244)
			(xy 129.846734 -273.580064) (xy 129.799148 -273.562017) (xy 129.755074 -273.536571) (xy 129.715652 -273.504384)
			(xy 129.681904 -273.46629) (xy 129.654703 -273.423276) (xy 129.634755 -273.376456) (xy 129.622576 -273.327042)
			(xy 129.618481 -273.276314) (xy 129.29997 -273.276314) (xy 129.299475 -273.300921) (xy 129.29158 -273.349498)
			(xy 129.275996 -273.396179) (xy 129.253125 -273.439756) (xy 129.22356 -273.4791) (xy 129.188067 -273.513192)
			(xy 129.147564 -273.541148) (xy 129.103102 -273.562246) (xy 129.055831 -273.575938) (xy 129.006976 -273.58187)
			(xy 128.957801 -273.579889) (xy 128.909582 -273.570045) (xy 128.863566 -273.552593) (xy 128.820945 -273.527986)
			(xy 128.782824 -273.496861) (xy 128.750189 -273.460024) (xy 128.723886 -273.418428) (xy 128.704595 -273.373152)
			(xy 128.692818 -273.325368) (xy 128.688858 -273.276314) (xy 128.370034 -273.276314) (xy 128.370034 -273.301455)
			(xy 128.362053 -273.351125) (xy 128.346295 -273.3989) (xy 128.323158 -273.44357) (xy 128.293229 -273.484005)
			(xy 128.257264 -273.51918) (xy 128.216175 -273.548205) (xy 128.171002 -273.570345) (xy 128.122889 -273.585038)
			(xy 128.098042 -273.588988) (xy 128.091438 -273.590004) (xy 128.082487 -273.591602) (xy 128.066475 -273.600191)
			(xy 128.060196 -273.606768) (xy 128.0541 -273.61388) (xy 128.0541 -274.08632) (xy 128.208527 -274.08632)
			(xy 128.212622 -274.035592) (xy 128.224801 -273.986178) (xy 128.244749 -273.939358) (xy 128.27195 -273.896344)
			(xy 128.305698 -273.85825) (xy 128.34512 -273.826063) (xy 128.389194 -273.800617) (xy 128.43678 -273.78257)
			(xy 128.486644 -273.77239) (xy 128.537496 -273.770341) (xy 128.588017 -273.776475) (xy 128.636901 -273.790635)
			(xy 128.68288 -273.812452) (xy 128.724764 -273.841362) (xy 128.761468 -273.876617) (xy 128.792041 -273.917303)
			(xy 128.815692 -273.962366) (xy 128.831808 -274.01064) (xy 128.839972 -274.060874) (xy 128.840484 -274.08632)
			(xy 129.148581 -274.08632) (xy 129.152676 -274.035592) (xy 129.164855 -273.986178) (xy 129.184803 -273.939358)
			(xy 129.212004 -273.896344) (xy 129.245752 -273.85825) (xy 129.285174 -273.826063) (xy 129.329248 -273.800617)
			(xy 129.376834 -273.78257) (xy 129.426698 -273.77239) (xy 129.47755 -273.770341) (xy 129.528071 -273.776475)
			(xy 129.576955 -273.790635) (xy 129.622934 -273.812452) (xy 129.664818 -273.841362) (xy 129.701522 -273.876617)
			(xy 129.732095 -273.917303) (xy 129.755746 -273.962366) (xy 129.771862 -274.01064) (xy 129.780026 -274.060874)
			(xy 129.780538 -274.08632) (xy 130.099066 -274.08632) (xy 130.103026 -274.037266) (xy 130.114803 -273.989482)
			(xy 130.134094 -273.944206) (xy 130.160397 -273.90261) (xy 130.193032 -273.865773) (xy 130.231153 -273.834648)
			(xy 130.273774 -273.810041) (xy 130.31979 -273.792589) (xy 130.368009 -273.782745) (xy 130.417184 -273.780764)
			(xy 130.466039 -273.786696) (xy 130.51331 -273.800388) (xy 130.557772 -273.821486) (xy 130.598275 -273.849442)
			(xy 130.633768 -273.883534) (xy 130.663333 -273.922878) (xy 130.686204 -273.966455) (xy 130.701788 -274.013136)
			(xy 130.709683 -274.061713) (xy 130.710178 -274.08632) (xy 131.028435 -274.08632) (xy 131.03253 -274.035592)
			(xy 131.044709 -273.986178) (xy 131.064657 -273.939358) (xy 131.091858 -273.896344) (xy 131.125606 -273.85825)
			(xy 131.165028 -273.826063) (xy 131.209102 -273.800617) (xy 131.256688 -273.78257) (xy 131.306552 -273.77239)
			(xy 131.357404 -273.770341) (xy 131.407925 -273.776475) (xy 131.456809 -273.790635) (xy 131.502788 -273.812452)
			(xy 131.544672 -273.841362) (xy 131.581376 -273.876617) (xy 131.611949 -273.917303) (xy 131.6356 -273.962366)
			(xy 131.651716 -274.01064) (xy 131.65988 -274.060874) (xy 131.660392 -274.08632) (xy 131.97892 -274.08632)
			(xy 131.98288 -274.037266) (xy 131.994657 -273.989482) (xy 132.013948 -273.944206) (xy 132.040251 -273.90261)
			(xy 132.072886 -273.865773) (xy 132.111007 -273.834648) (xy 132.153628 -273.810041) (xy 132.199644 -273.792589)
			(xy 132.247863 -273.782745) (xy 132.297038 -273.780764) (xy 132.345893 -273.786696) (xy 132.393164 -273.800388)
			(xy 132.437626 -273.821486) (xy 132.478129 -273.849442) (xy 132.513622 -273.883534) (xy 132.543187 -273.922878)
			(xy 132.566058 -273.966455) (xy 132.581642 -274.013136) (xy 132.589537 -274.061713) (xy 132.590032 -274.08632)
			(xy 132.908543 -274.08632) (xy 132.912638 -274.035592) (xy 132.924817 -273.986178) (xy 132.944765 -273.939358)
			(xy 132.971966 -273.896344) (xy 133.005714 -273.85825) (xy 133.045136 -273.826063) (xy 133.08921 -273.800617)
			(xy 133.136796 -273.78257) (xy 133.18666 -273.77239) (xy 133.237512 -273.770341) (xy 133.288033 -273.776475)
			(xy 133.336917 -273.790635) (xy 133.382896 -273.812452) (xy 133.42478 -273.841362) (xy 133.461484 -273.876617)
			(xy 133.492057 -273.917303) (xy 133.515708 -273.962366) (xy 133.531824 -274.01064) (xy 133.539988 -274.060874)
			(xy 133.5405 -274.08632) (xy 133.539988 -274.111766) (xy 133.531824 -274.162) (xy 133.515708 -274.210274)
			(xy 133.492057 -274.255337) (xy 133.461484 -274.296023) (xy 133.42478 -274.331278) (xy 133.382896 -274.360188)
			(xy 133.336917 -274.382005) (xy 133.288033 -274.396165) (xy 133.237512 -274.402299) (xy 133.18666 -274.40025)
			(xy 133.136796 -274.39007) (xy 133.08921 -274.372023) (xy 133.045136 -274.346577) (xy 133.005714 -274.31439)
			(xy 132.971966 -274.276296) (xy 132.944765 -274.233282) (xy 132.924817 -274.186462) (xy 132.912638 -274.137048)
			(xy 132.908543 -274.08632) (xy 132.590032 -274.08632) (xy 132.589537 -274.110927) (xy 132.581642 -274.159504)
			(xy 132.566058 -274.206185) (xy 132.543187 -274.249762) (xy 132.513622 -274.289106) (xy 132.478129 -274.323198)
			(xy 132.437626 -274.351154) (xy 132.393164 -274.372252) (xy 132.345893 -274.385944) (xy 132.297038 -274.391876)
			(xy 132.247863 -274.389895) (xy 132.199644 -274.380051) (xy 132.153628 -274.362599) (xy 132.111007 -274.337992)
			(xy 132.072886 -274.306867) (xy 132.040251 -274.27003) (xy 132.013948 -274.228434) (xy 131.994657 -274.183158)
			(xy 131.98288 -274.135374) (xy 131.97892 -274.08632) (xy 131.660392 -274.08632) (xy 131.65988 -274.111766)
			(xy 131.651716 -274.162) (xy 131.6356 -274.210274) (xy 131.611949 -274.255337) (xy 131.581376 -274.296023)
			(xy 131.544672 -274.331278) (xy 131.502788 -274.360188) (xy 131.456809 -274.382005) (xy 131.407925 -274.396165)
			(xy 131.357404 -274.402299) (xy 131.306552 -274.40025) (xy 131.256688 -274.39007) (xy 131.209102 -274.372023)
			(xy 131.165028 -274.346577) (xy 131.125606 -274.31439) (xy 131.091858 -274.276296) (xy 131.064657 -274.233282)
			(xy 131.044709 -274.186462) (xy 131.03253 -274.137048) (xy 131.028435 -274.08632) (xy 130.710178 -274.08632)
			(xy 130.709683 -274.110927) (xy 130.701788 -274.159504) (xy 130.686204 -274.206185) (xy 130.663333 -274.249762)
			(xy 130.633768 -274.289106) (xy 130.598275 -274.323198) (xy 130.557772 -274.351154) (xy 130.51331 -274.372252)
			(xy 130.466039 -274.385944) (xy 130.417184 -274.391876) (xy 130.368009 -274.389895) (xy 130.31979 -274.380051)
			(xy 130.273774 -274.362599) (xy 130.231153 -274.337992) (xy 130.193032 -274.306867) (xy 130.160397 -274.27003)
			(xy 130.134094 -274.228434) (xy 130.114803 -274.183158) (xy 130.103026 -274.135374) (xy 130.099066 -274.08632)
			(xy 129.780538 -274.08632) (xy 129.780026 -274.111766) (xy 129.771862 -274.162) (xy 129.755746 -274.210274)
			(xy 129.732095 -274.255337) (xy 129.701522 -274.296023) (xy 129.664818 -274.331278) (xy 129.622934 -274.360188)
			(xy 129.576955 -274.382005) (xy 129.528071 -274.396165) (xy 129.47755 -274.402299) (xy 129.426698 -274.40025)
			(xy 129.376834 -274.39007) (xy 129.329248 -274.372023) (xy 129.285174 -274.346577) (xy 129.245752 -274.31439)
			(xy 129.212004 -274.276296) (xy 129.184803 -274.233282) (xy 129.164855 -274.186462) (xy 129.152676 -274.137048)
			(xy 129.148581 -274.08632) (xy 128.840484 -274.08632) (xy 128.839972 -274.111766) (xy 128.831808 -274.162)
			(xy 128.815692 -274.210274) (xy 128.792041 -274.255337) (xy 128.761468 -274.296023) (xy 128.724764 -274.331278)
			(xy 128.68288 -274.360188) (xy 128.636901 -274.382005) (xy 128.588017 -274.396165) (xy 128.537496 -274.402299)
			(xy 128.486644 -274.40025) (xy 128.43678 -274.39007) (xy 128.389194 -274.372023) (xy 128.34512 -274.346577)
			(xy 128.305698 -274.31439) (xy 128.27195 -274.276296) (xy 128.244749 -274.233282) (xy 128.224801 -274.186462)
			(xy 128.212622 -274.137048) (xy 128.208527 -274.08632) (xy 128.0541 -274.08632) (xy 128.0541 -274.53971)
			(xy 128.054482 -274.548811) (xy 128.060873 -274.565855) (xy 128.066546 -274.572984) (xy 128.072642 -274.580096)
			(xy 128.098042 -274.583652) (xy 128.122891 -274.587574) (xy 128.171002 -274.602268) (xy 128.216173 -274.624408)
			(xy 128.25726 -274.653432) (xy 128.293223 -274.688607) (xy 128.323151 -274.729041) (xy 128.346286 -274.77371)
			(xy 128.362043 -274.821483) (xy 128.370022 -274.871151) (xy 128.370022 -274.896326) (xy 128.688858 -274.896326)
			(xy 128.692818 -274.847272) (xy 128.704595 -274.799488) (xy 128.723886 -274.754212) (xy 128.750189 -274.712616)
			(xy 128.782824 -274.675779) (xy 128.820945 -274.644654) (xy 128.863566 -274.620047) (xy 128.909582 -274.602595)
			(xy 128.957801 -274.592751) (xy 129.006976 -274.59077) (xy 129.055831 -274.596702) (xy 129.103102 -274.610394)
			(xy 129.147564 -274.631492) (xy 129.188067 -274.659448) (xy 129.22356 -274.69354) (xy 129.253125 -274.732884)
			(xy 129.275996 -274.776461) (xy 129.29158 -274.823142) (xy 129.299475 -274.871719) (xy 129.29997 -274.896326)
			(xy 129.618481 -274.896326) (xy 129.622576 -274.845598) (xy 129.634755 -274.796184) (xy 129.654703 -274.749364)
			(xy 129.681904 -274.70635) (xy 129.715652 -274.668256) (xy 129.755074 -274.636069) (xy 129.799148 -274.610623)
			(xy 129.846734 -274.592576) (xy 129.896598 -274.582396) (xy 129.94745 -274.580347) (xy 129.997971 -274.586481)
			(xy 130.046855 -274.600641) (xy 130.092834 -274.622458) (xy 130.134718 -274.651368) (xy 130.171422 -274.686623)
			(xy 130.201995 -274.727309) (xy 130.225646 -274.772372) (xy 130.241762 -274.820646) (xy 130.249926 -274.87088)
			(xy 130.250438 -274.896326) (xy 130.568966 -274.896326) (xy 130.572926 -274.847272) (xy 130.584703 -274.799488)
			(xy 130.603994 -274.754212) (xy 130.630297 -274.712616) (xy 130.662932 -274.675779) (xy 130.701053 -274.644654)
			(xy 130.743674 -274.620047) (xy 130.78969 -274.602595) (xy 130.837909 -274.592751) (xy 130.887084 -274.59077)
			(xy 130.935939 -274.596702) (xy 130.98321 -274.610394) (xy 131.027672 -274.631492) (xy 131.068175 -274.659448)
			(xy 131.103668 -274.69354) (xy 131.133233 -274.732884) (xy 131.156104 -274.776461) (xy 131.171688 -274.823142)
			(xy 131.179583 -274.871719) (xy 131.180078 -274.896326) (xy 131.498589 -274.896326) (xy 131.502684 -274.845598)
			(xy 131.514863 -274.796184) (xy 131.534811 -274.749364) (xy 131.562012 -274.70635) (xy 131.59576 -274.668256)
			(xy 131.635182 -274.636069) (xy 131.679256 -274.610623) (xy 131.726842 -274.592576) (xy 131.776706 -274.582396)
			(xy 131.827558 -274.580347) (xy 131.878079 -274.586481) (xy 131.926963 -274.600641) (xy 131.972942 -274.622458)
			(xy 132.014826 -274.651368) (xy 132.05153 -274.686623) (xy 132.082103 -274.727309) (xy 132.105754 -274.772372)
			(xy 132.12187 -274.820646) (xy 132.130034 -274.87088) (xy 132.130546 -274.896326) (xy 132.438643 -274.896326)
			(xy 132.442738 -274.845598) (xy 132.454917 -274.796184) (xy 132.474865 -274.749364) (xy 132.502066 -274.70635)
			(xy 132.535814 -274.668256) (xy 132.575236 -274.636069) (xy 132.61931 -274.610623) (xy 132.666896 -274.592576)
			(xy 132.71676 -274.582396) (xy 132.767612 -274.580347) (xy 132.818133 -274.586481) (xy 132.867017 -274.600641)
			(xy 132.912996 -274.622458) (xy 132.95488 -274.651368) (xy 132.991584 -274.686623) (xy 133.022157 -274.727309)
			(xy 133.045808 -274.772372) (xy 133.061924 -274.820646) (xy 133.070088 -274.87088) (xy 133.0706 -274.896326)
			(xy 133.070088 -274.921772) (xy 133.061924 -274.972006) (xy 133.045808 -275.02028) (xy 133.022157 -275.065343)
			(xy 132.991584 -275.106029) (xy 132.95488 -275.141284) (xy 132.912996 -275.170194) (xy 132.867017 -275.192011)
			(xy 132.818133 -275.206171) (xy 132.767612 -275.212305) (xy 132.71676 -275.210256) (xy 132.666896 -275.200076)
			(xy 132.61931 -275.182029) (xy 132.575236 -275.156583) (xy 132.535814 -275.124396) (xy 132.502066 -275.086302)
			(xy 132.474865 -275.043288) (xy 132.454917 -274.996468) (xy 132.442738 -274.947054) (xy 132.438643 -274.896326)
			(xy 132.130546 -274.896326) (xy 132.130034 -274.921772) (xy 132.12187 -274.972006) (xy 132.105754 -275.02028)
			(xy 132.082103 -275.065343) (xy 132.05153 -275.106029) (xy 132.014826 -275.141284) (xy 131.972942 -275.170194)
			(xy 131.926963 -275.192011) (xy 131.878079 -275.206171) (xy 131.827558 -275.212305) (xy 131.776706 -275.210256)
			(xy 131.726842 -275.200076) (xy 131.679256 -275.182029) (xy 131.635182 -275.156583) (xy 131.59576 -275.124396)
			(xy 131.562012 -275.086302) (xy 131.534811 -275.043288) (xy 131.514863 -274.996468) (xy 131.502684 -274.947054)
			(xy 131.498589 -274.896326) (xy 131.180078 -274.896326) (xy 131.179583 -274.920933) (xy 131.171688 -274.96951)
			(xy 131.156104 -275.016191) (xy 131.133233 -275.059768) (xy 131.103668 -275.099112) (xy 131.068175 -275.133204)
			(xy 131.027672 -275.16116) (xy 130.98321 -275.182258) (xy 130.935939 -275.19595) (xy 130.887084 -275.201882)
			(xy 130.837909 -275.199901) (xy 130.78969 -275.190057) (xy 130.743674 -275.172605) (xy 130.701053 -275.147998)
			(xy 130.662932 -275.116873) (xy 130.630297 -275.080036) (xy 130.603994 -275.03844) (xy 130.584703 -274.993164)
			(xy 130.572926 -274.94538) (xy 130.568966 -274.896326) (xy 130.250438 -274.896326) (xy 130.249926 -274.921772)
			(xy 130.241762 -274.972006) (xy 130.225646 -275.02028) (xy 130.201995 -275.065343) (xy 130.171422 -275.106029)
			(xy 130.134718 -275.141284) (xy 130.092834 -275.170194) (xy 130.046855 -275.192011) (xy 129.997971 -275.206171)
			(xy 129.94745 -275.212305) (xy 129.896598 -275.210256) (xy 129.846734 -275.200076) (xy 129.799148 -275.182029)
			(xy 129.755074 -275.156583) (xy 129.715652 -275.124396) (xy 129.681904 -275.086302) (xy 129.654703 -275.043288)
			(xy 129.634755 -274.996468) (xy 129.622576 -274.947054) (xy 129.618481 -274.896326) (xy 129.29997 -274.896326)
			(xy 129.299475 -274.920933) (xy 129.29158 -274.96951) (xy 129.275996 -275.016191) (xy 129.253125 -275.059768)
			(xy 129.22356 -275.099112) (xy 129.188067 -275.133204) (xy 129.147564 -275.16116) (xy 129.103102 -275.182258)
			(xy 129.055831 -275.19595) (xy 129.006976 -275.201882) (xy 128.957801 -275.199901) (xy 128.909582 -275.190057)
			(xy 128.863566 -275.172605) (xy 128.820945 -275.147998) (xy 128.782824 -275.116873) (xy 128.750189 -275.080036)
			(xy 128.723886 -275.03844) (xy 128.704595 -274.993164) (xy 128.692818 -274.94538) (xy 128.688858 -274.896326)
			(xy 128.370022 -274.896326) (xy 128.370022 -274.921456) (xy 128.362041 -274.971124) (xy 128.346284 -275.018897)
			(xy 128.323147 -275.063565) (xy 128.293219 -275.103998) (xy 128.257255 -275.139172) (xy 128.216167 -275.168196)
			(xy 128.170996 -275.190334) (xy 128.122885 -275.205027) (xy 128.098042 -275.209) (xy 128.091438 -275.210016)
			(xy 128.082487 -275.211614) (xy 128.066476 -275.220205) (xy 128.060196 -275.22678) (xy 128.0541 -275.233892)
			(xy 128.0541 -275.706332) (xy 128.208527 -275.706332) (xy 128.212622 -275.655604) (xy 128.224801 -275.60619)
			(xy 128.244749 -275.55937) (xy 128.27195 -275.516356) (xy 128.305698 -275.478262) (xy 128.34512 -275.446075)
			(xy 128.389194 -275.420629) (xy 128.43678 -275.402582) (xy 128.486644 -275.392402) (xy 128.537496 -275.390353)
			(xy 128.588017 -275.396487) (xy 128.636901 -275.410647) (xy 128.68288 -275.432464) (xy 128.724764 -275.461374)
			(xy 128.761468 -275.496629) (xy 128.792041 -275.537315) (xy 128.815692 -275.582378) (xy 128.831808 -275.630652)
			(xy 128.839972 -275.680886) (xy 128.840484 -275.706332) (xy 129.148581 -275.706332) (xy 129.152676 -275.655604)
			(xy 129.164855 -275.60619) (xy 129.184803 -275.55937) (xy 129.212004 -275.516356) (xy 129.245752 -275.478262)
			(xy 129.285174 -275.446075) (xy 129.329248 -275.420629) (xy 129.376834 -275.402582) (xy 129.426698 -275.392402)
			(xy 129.47755 -275.390353) (xy 129.528071 -275.396487) (xy 129.576955 -275.410647) (xy 129.622934 -275.432464)
			(xy 129.664818 -275.461374) (xy 129.701522 -275.496629) (xy 129.732095 -275.537315) (xy 129.755746 -275.582378)
			(xy 129.771862 -275.630652) (xy 129.780026 -275.680886) (xy 129.780538 -275.706332) (xy 131.028435 -275.706332)
			(xy 131.03253 -275.655604) (xy 131.044709 -275.60619) (xy 131.064657 -275.55937) (xy 131.091858 -275.516356)
			(xy 131.125606 -275.478262) (xy 131.165028 -275.446075) (xy 131.209102 -275.420629) (xy 131.256688 -275.402582)
			(xy 131.306552 -275.392402) (xy 131.357404 -275.390353) (xy 131.407925 -275.396487) (xy 131.456809 -275.410647)
			(xy 131.502788 -275.432464) (xy 131.544672 -275.461374) (xy 131.581376 -275.496629) (xy 131.611949 -275.537315)
			(xy 131.6356 -275.582378) (xy 131.651716 -275.630652) (xy 131.65988 -275.680886) (xy 131.660392 -275.706332)
			(xy 131.97892 -275.706332) (xy 131.98288 -275.657278) (xy 131.994657 -275.609494) (xy 132.013948 -275.564218)
			(xy 132.040251 -275.522622) (xy 132.072886 -275.485785) (xy 132.111007 -275.45466) (xy 132.153628 -275.430053)
			(xy 132.199644 -275.412601) (xy 132.247863 -275.402757) (xy 132.297038 -275.400776) (xy 132.345893 -275.406708)
			(xy 132.393164 -275.4204) (xy 132.437626 -275.441498) (xy 132.478129 -275.469454) (xy 132.513622 -275.503546)
			(xy 132.543187 -275.54289) (xy 132.566058 -275.586467) (xy 132.581642 -275.633148) (xy 132.589537 -275.681725)
			(xy 132.590032 -275.706332) (xy 132.908543 -275.706332) (xy 132.912638 -275.655604) (xy 132.924817 -275.60619)
			(xy 132.944765 -275.55937) (xy 132.971966 -275.516356) (xy 133.005714 -275.478262) (xy 133.045136 -275.446075)
			(xy 133.08921 -275.420629) (xy 133.136796 -275.402582) (xy 133.18666 -275.392402) (xy 133.237512 -275.390353)
			(xy 133.288033 -275.396487) (xy 133.336917 -275.410647) (xy 133.382896 -275.432464) (xy 133.42478 -275.461374)
			(xy 133.461484 -275.496629) (xy 133.492057 -275.537315) (xy 133.515708 -275.582378) (xy 133.531824 -275.630652)
			(xy 133.539988 -275.680886) (xy 133.5405 -275.706332) (xy 133.539988 -275.731778) (xy 133.531824 -275.782012)
			(xy 133.515708 -275.830286) (xy 133.492057 -275.875349) (xy 133.461484 -275.916035) (xy 133.42478 -275.95129)
			(xy 133.382896 -275.9802) (xy 133.336917 -276.002017) (xy 133.288033 -276.016177) (xy 133.237512 -276.022311)
			(xy 133.18666 -276.020262) (xy 133.136796 -276.010082) (xy 133.08921 -275.992035) (xy 133.045136 -275.966589)
			(xy 133.005714 -275.934402) (xy 132.971966 -275.896308) (xy 132.944765 -275.853294) (xy 132.924817 -275.806474)
			(xy 132.912638 -275.75706) (xy 132.908543 -275.706332) (xy 132.590032 -275.706332) (xy 132.589537 -275.730939)
			(xy 132.581642 -275.779516) (xy 132.566058 -275.826197) (xy 132.543187 -275.869774) (xy 132.513622 -275.909118)
			(xy 132.478129 -275.94321) (xy 132.437626 -275.971166) (xy 132.393164 -275.992264) (xy 132.345893 -276.005956)
			(xy 132.297038 -276.011888) (xy 132.247863 -276.009907) (xy 132.199644 -276.000063) (xy 132.153628 -275.982611)
			(xy 132.111007 -275.958004) (xy 132.072886 -275.926879) (xy 132.040251 -275.890042) (xy 132.013948 -275.848446)
			(xy 131.994657 -275.80317) (xy 131.98288 -275.755386) (xy 131.97892 -275.706332) (xy 131.660392 -275.706332)
			(xy 131.65988 -275.731778) (xy 131.651716 -275.782012) (xy 131.6356 -275.830286) (xy 131.611949 -275.875349)
			(xy 131.581376 -275.916035) (xy 131.544672 -275.95129) (xy 131.502788 -275.9802) (xy 131.456809 -276.002017)
			(xy 131.407925 -276.016177) (xy 131.357404 -276.022311) (xy 131.306552 -276.020262) (xy 131.256688 -276.010082)
			(xy 131.209102 -275.992035) (xy 131.165028 -275.966589) (xy 131.125606 -275.934402) (xy 131.091858 -275.896308)
			(xy 131.064657 -275.853294) (xy 131.044709 -275.806474) (xy 131.03253 -275.75706) (xy 131.028435 -275.706332)
			(xy 129.780538 -275.706332) (xy 129.780026 -275.731778) (xy 129.771862 -275.782012) (xy 129.755746 -275.830286)
			(xy 129.732095 -275.875349) (xy 129.701522 -275.916035) (xy 129.664818 -275.95129) (xy 129.622934 -275.9802)
			(xy 129.576955 -276.002017) (xy 129.528071 -276.016177) (xy 129.47755 -276.022311) (xy 129.426698 -276.020262)
			(xy 129.376834 -276.010082) (xy 129.329248 -275.992035) (xy 129.285174 -275.966589) (xy 129.245752 -275.934402)
			(xy 129.212004 -275.896308) (xy 129.184803 -275.853294) (xy 129.164855 -275.806474) (xy 129.152676 -275.75706)
			(xy 129.148581 -275.706332) (xy 128.840484 -275.706332) (xy 128.839972 -275.731778) (xy 128.831808 -275.782012)
			(xy 128.815692 -275.830286) (xy 128.792041 -275.875349) (xy 128.761468 -275.916035) (xy 128.724764 -275.95129)
			(xy 128.68288 -275.9802) (xy 128.636901 -276.002017) (xy 128.588017 -276.016177) (xy 128.537496 -276.022311)
			(xy 128.486644 -276.020262) (xy 128.43678 -276.010082) (xy 128.389194 -275.992035) (xy 128.34512 -275.966589)
			(xy 128.305698 -275.934402) (xy 128.27195 -275.896308) (xy 128.244749 -275.853294) (xy 128.224801 -275.806474)
			(xy 128.212622 -275.75706) (xy 128.208527 -275.706332) (xy 128.0541 -275.706332) (xy 128.0541 -276.159722)
			(xy 128.054467 -276.168829) (xy 128.060836 -276.185893) (xy 128.066546 -276.192996) (xy 128.072642 -276.200108)
			(xy 128.098042 -276.203664) (xy 128.122891 -276.207586) (xy 128.171 -276.22228) (xy 128.216169 -276.244419)
			(xy 128.257254 -276.273443) (xy 128.293215 -276.308616) (xy 128.323142 -276.349048) (xy 128.346276 -276.393716)
			(xy 128.362032 -276.441488) (xy 128.37001 -276.491154) (xy 128.37001 -276.516338) (xy 128.688858 -276.516338)
			(xy 128.692818 -276.467284) (xy 128.704595 -276.4195) (xy 128.723886 -276.374224) (xy 128.750189 -276.332628)
			(xy 128.782824 -276.295791) (xy 128.820945 -276.264666) (xy 128.863566 -276.240059) (xy 128.909582 -276.222607)
			(xy 128.957801 -276.212763) (xy 129.006976 -276.210782) (xy 129.055831 -276.216714) (xy 129.103102 -276.230406)
			(xy 129.147564 -276.251504) (xy 129.188067 -276.27946) (xy 129.22356 -276.313552) (xy 129.253125 -276.352896)
			(xy 129.275996 -276.396473) (xy 129.29158 -276.443154) (xy 129.299475 -276.491731) (xy 129.29997 -276.516338)
			(xy 129.618481 -276.516338) (xy 129.622576 -276.46561) (xy 129.634755 -276.416196) (xy 129.654703 -276.369376)
			(xy 129.681904 -276.326362) (xy 129.715652 -276.288268) (xy 129.755074 -276.256081) (xy 129.799148 -276.230635)
			(xy 129.846734 -276.212588) (xy 129.896598 -276.202408) (xy 129.94745 -276.200359) (xy 129.997971 -276.206493)
			(xy 130.046855 -276.220653) (xy 130.092834 -276.24247) (xy 130.134718 -276.27138) (xy 130.171422 -276.306635)
			(xy 130.201995 -276.347321) (xy 130.225646 -276.392384) (xy 130.241762 -276.440658) (xy 130.249926 -276.490892)
			(xy 130.250438 -276.516338) (xy 130.568966 -276.516338) (xy 130.572926 -276.467284) (xy 130.584703 -276.4195)
			(xy 130.603994 -276.374224) (xy 130.630297 -276.332628) (xy 130.662932 -276.295791) (xy 130.701053 -276.264666)
			(xy 130.743674 -276.240059) (xy 130.78969 -276.222607) (xy 130.837909 -276.212763) (xy 130.887084 -276.210782)
			(xy 130.935939 -276.216714) (xy 130.98321 -276.230406) (xy 131.027672 -276.251504) (xy 131.068175 -276.27946)
			(xy 131.103668 -276.313552) (xy 131.133233 -276.352896) (xy 131.156104 -276.396473) (xy 131.171688 -276.443154)
			(xy 131.179583 -276.491731) (xy 131.180078 -276.516338) (xy 131.498589 -276.516338) (xy 131.502684 -276.46561)
			(xy 131.514863 -276.416196) (xy 131.534811 -276.369376) (xy 131.562012 -276.326362) (xy 131.59576 -276.288268)
			(xy 131.635182 -276.256081) (xy 131.679256 -276.230635) (xy 131.726842 -276.212588) (xy 131.776706 -276.202408)
			(xy 131.827558 -276.200359) (xy 131.878079 -276.206493) (xy 131.926963 -276.220653) (xy 131.972942 -276.24247)
			(xy 132.014826 -276.27138) (xy 132.05153 -276.306635) (xy 132.082103 -276.347321) (xy 132.105754 -276.392384)
			(xy 132.12187 -276.440658) (xy 132.130034 -276.490892) (xy 132.130546 -276.516338) (xy 132.438643 -276.516338)
			(xy 132.442738 -276.46561) (xy 132.454917 -276.416196) (xy 132.474865 -276.369376) (xy 132.502066 -276.326362)
			(xy 132.535814 -276.288268) (xy 132.575236 -276.256081) (xy 132.61931 -276.230635) (xy 132.666896 -276.212588)
			(xy 132.71676 -276.202408) (xy 132.767612 -276.200359) (xy 132.818133 -276.206493) (xy 132.867017 -276.220653)
			(xy 132.912996 -276.24247) (xy 132.95488 -276.27138) (xy 132.991584 -276.306635) (xy 133.022157 -276.347321)
			(xy 133.045808 -276.392384) (xy 133.061924 -276.440658) (xy 133.070088 -276.490892) (xy 133.0706 -276.516338)
			(xy 133.070088 -276.541784) (xy 133.061924 -276.592018) (xy 133.045808 -276.640292) (xy 133.022157 -276.685355)
			(xy 132.991584 -276.726041) (xy 132.95488 -276.761296) (xy 132.912996 -276.790206) (xy 132.867017 -276.812023)
			(xy 132.818133 -276.826183) (xy 132.767612 -276.832317) (xy 132.71676 -276.830268) (xy 132.666896 -276.820088)
			(xy 132.61931 -276.802041) (xy 132.575236 -276.776595) (xy 132.535814 -276.744408) (xy 132.502066 -276.706314)
			(xy 132.474865 -276.6633) (xy 132.454917 -276.61648) (xy 132.442738 -276.567066) (xy 132.438643 -276.516338)
			(xy 132.130546 -276.516338) (xy 132.130034 -276.541784) (xy 132.12187 -276.592018) (xy 132.105754 -276.640292)
			(xy 132.082103 -276.685355) (xy 132.05153 -276.726041) (xy 132.014826 -276.761296) (xy 131.972942 -276.790206)
			(xy 131.926963 -276.812023) (xy 131.878079 -276.826183) (xy 131.827558 -276.832317) (xy 131.776706 -276.830268)
			(xy 131.726842 -276.820088) (xy 131.679256 -276.802041) (xy 131.635182 -276.776595) (xy 131.59576 -276.744408)
			(xy 131.562012 -276.706314) (xy 131.534811 -276.6633) (xy 131.514863 -276.61648) (xy 131.502684 -276.567066)
			(xy 131.498589 -276.516338) (xy 131.180078 -276.516338) (xy 131.179583 -276.540945) (xy 131.171688 -276.589522)
			(xy 131.156104 -276.636203) (xy 131.133233 -276.67978) (xy 131.103668 -276.719124) (xy 131.068175 -276.753216)
			(xy 131.027672 -276.781172) (xy 130.98321 -276.80227) (xy 130.935939 -276.815962) (xy 130.887084 -276.821894)
			(xy 130.837909 -276.819913) (xy 130.78969 -276.810069) (xy 130.743674 -276.792617) (xy 130.701053 -276.76801)
			(xy 130.662932 -276.736885) (xy 130.630297 -276.700048) (xy 130.603994 -276.658452) (xy 130.584703 -276.613176)
			(xy 130.572926 -276.565392) (xy 130.568966 -276.516338) (xy 130.250438 -276.516338) (xy 130.249926 -276.541784)
			(xy 130.241762 -276.592018) (xy 130.225646 -276.640292) (xy 130.201995 -276.685355) (xy 130.171422 -276.726041)
			(xy 130.134718 -276.761296) (xy 130.092834 -276.790206) (xy 130.046855 -276.812023) (xy 129.997971 -276.826183)
			(xy 129.94745 -276.832317) (xy 129.896598 -276.830268) (xy 129.846734 -276.820088) (xy 129.799148 -276.802041)
			(xy 129.755074 -276.776595) (xy 129.715652 -276.744408) (xy 129.681904 -276.706314) (xy 129.654703 -276.6633)
			(xy 129.634755 -276.61648) (xy 129.622576 -276.567066) (xy 129.618481 -276.516338) (xy 129.29997 -276.516338)
			(xy 129.299475 -276.540945) (xy 129.29158 -276.589522) (xy 129.275996 -276.636203) (xy 129.253125 -276.67978)
			(xy 129.22356 -276.719124) (xy 129.188067 -276.753216) (xy 129.147564 -276.781172) (xy 129.103102 -276.80227)
			(xy 129.055831 -276.815962) (xy 129.006976 -276.821894) (xy 128.957801 -276.819913) (xy 128.909582 -276.810069)
			(xy 128.863566 -276.792617) (xy 128.820945 -276.76801) (xy 128.782824 -276.736885) (xy 128.750189 -276.700048)
			(xy 128.723886 -276.658452) (xy 128.704595 -276.613176) (xy 128.692818 -276.565392) (xy 128.688858 -276.516338)
			(xy 128.37001 -276.516338) (xy 128.37001 -276.541457) (xy 128.362029 -276.591122) (xy 128.346272 -276.638894)
			(xy 128.323136 -276.683561) (xy 128.293209 -276.723992) (xy 128.257246 -276.759164) (xy 128.21616 -276.788186)
			(xy 128.17099 -276.810324) (xy 128.12288 -276.825016) (xy 128.098042 -276.829012) (xy 128.091438 -276.830028)
			(xy 128.082487 -276.831626) (xy 128.066478 -276.840219) (xy 128.060196 -276.846792) (xy 128.0541 -276.853904)
			(xy 128.0541 -277.326344) (xy 128.208527 -277.326344) (xy 128.212622 -277.275616) (xy 128.224801 -277.226202)
			(xy 128.244749 -277.179382) (xy 128.27195 -277.136368) (xy 128.305698 -277.098274) (xy 128.34512 -277.066087)
			(xy 128.389194 -277.040641) (xy 128.43678 -277.022594) (xy 128.486644 -277.012414) (xy 128.537496 -277.010365)
			(xy 128.588017 -277.016499) (xy 128.636901 -277.030659) (xy 128.68288 -277.052476) (xy 128.724764 -277.081386)
			(xy 128.761468 -277.116641) (xy 128.792041 -277.157327) (xy 128.815692 -277.20239) (xy 128.831808 -277.250664)
			(xy 128.839972 -277.300898) (xy 128.840484 -277.326344) (xy 129.148581 -277.326344) (xy 129.152676 -277.275616)
			(xy 129.164855 -277.226202) (xy 129.184803 -277.179382) (xy 129.212004 -277.136368) (xy 129.245752 -277.098274)
			(xy 129.285174 -277.066087) (xy 129.329248 -277.040641) (xy 129.376834 -277.022594) (xy 129.426698 -277.012414)
			(xy 129.47755 -277.010365) (xy 129.528071 -277.016499) (xy 129.576955 -277.030659) (xy 129.622934 -277.052476)
			(xy 129.664818 -277.081386) (xy 129.701522 -277.116641) (xy 129.732095 -277.157327) (xy 129.755746 -277.20239)
			(xy 129.771862 -277.250664) (xy 129.780026 -277.300898) (xy 129.780538 -277.326344) (xy 130.099066 -277.326344)
			(xy 130.103026 -277.27729) (xy 130.114803 -277.229506) (xy 130.134094 -277.18423) (xy 130.160397 -277.142634)
			(xy 130.193032 -277.105797) (xy 130.231153 -277.074672) (xy 130.273774 -277.050065) (xy 130.31979 -277.032613)
			(xy 130.368009 -277.022769) (xy 130.417184 -277.020788) (xy 130.466039 -277.02672) (xy 130.51331 -277.040412)
			(xy 130.557772 -277.06151) (xy 130.598275 -277.089466) (xy 130.633768 -277.123558) (xy 130.663333 -277.162902)
			(xy 130.686204 -277.206479) (xy 130.701788 -277.25316) (xy 130.709683 -277.301737) (xy 130.710178 -277.326344)
			(xy 131.028435 -277.326344) (xy 131.03253 -277.275616) (xy 131.044709 -277.226202) (xy 131.064657 -277.179382)
			(xy 131.091858 -277.136368) (xy 131.125606 -277.098274) (xy 131.165028 -277.066087) (xy 131.209102 -277.040641)
			(xy 131.256688 -277.022594) (xy 131.306552 -277.012414) (xy 131.357404 -277.010365) (xy 131.407925 -277.016499)
			(xy 131.456809 -277.030659) (xy 131.502788 -277.052476) (xy 131.544672 -277.081386) (xy 131.581376 -277.116641)
			(xy 131.611949 -277.157327) (xy 131.6356 -277.20239) (xy 131.651716 -277.250664) (xy 131.65988 -277.300898)
			(xy 131.660392 -277.326344) (xy 131.97892 -277.326344) (xy 131.98288 -277.27729) (xy 131.994657 -277.229506)
			(xy 132.013948 -277.18423) (xy 132.040251 -277.142634) (xy 132.072886 -277.105797) (xy 132.111007 -277.074672)
			(xy 132.153628 -277.050065) (xy 132.199644 -277.032613) (xy 132.247863 -277.022769) (xy 132.297038 -277.020788)
			(xy 132.345893 -277.02672) (xy 132.393164 -277.040412) (xy 132.437626 -277.06151) (xy 132.478129 -277.089466)
			(xy 132.513622 -277.123558) (xy 132.543187 -277.162902) (xy 132.566058 -277.206479) (xy 132.581642 -277.25316)
			(xy 132.589537 -277.301737) (xy 132.590032 -277.326344) (xy 132.908543 -277.326344) (xy 132.912638 -277.275616)
			(xy 132.924817 -277.226202) (xy 132.944765 -277.179382) (xy 132.971966 -277.136368) (xy 133.005714 -277.098274)
			(xy 133.045136 -277.066087) (xy 133.08921 -277.040641) (xy 133.136796 -277.022594) (xy 133.18666 -277.012414)
			(xy 133.237512 -277.010365) (xy 133.288033 -277.016499) (xy 133.336917 -277.030659) (xy 133.382896 -277.052476)
			(xy 133.42478 -277.081386) (xy 133.461484 -277.116641) (xy 133.492057 -277.157327) (xy 133.515708 -277.20239)
			(xy 133.531824 -277.250664) (xy 133.539988 -277.300898) (xy 133.5405 -277.326344) (xy 133.539988 -277.35179)
			(xy 133.531824 -277.402024) (xy 133.515708 -277.450298) (xy 133.492057 -277.495361) (xy 133.461484 -277.536047)
			(xy 133.42478 -277.571302) (xy 133.382896 -277.600212) (xy 133.336917 -277.622029) (xy 133.288033 -277.636189)
			(xy 133.237512 -277.642323) (xy 133.18666 -277.640274) (xy 133.136796 -277.630094) (xy 133.08921 -277.612047)
			(xy 133.045136 -277.586601) (xy 133.005714 -277.554414) (xy 132.971966 -277.51632) (xy 132.944765 -277.473306)
			(xy 132.924817 -277.426486) (xy 132.912638 -277.377072) (xy 132.908543 -277.326344) (xy 132.590032 -277.326344)
			(xy 132.589537 -277.350951) (xy 132.581642 -277.399528) (xy 132.566058 -277.446209) (xy 132.543187 -277.489786)
			(xy 132.513622 -277.52913) (xy 132.478129 -277.563222) (xy 132.437626 -277.591178) (xy 132.393164 -277.612276)
			(xy 132.345893 -277.625968) (xy 132.297038 -277.6319) (xy 132.247863 -277.629919) (xy 132.199644 -277.620075)
			(xy 132.153628 -277.602623) (xy 132.111007 -277.578016) (xy 132.072886 -277.546891) (xy 132.040251 -277.510054)
			(xy 132.013948 -277.468458) (xy 131.994657 -277.423182) (xy 131.98288 -277.375398) (xy 131.97892 -277.326344)
			(xy 131.660392 -277.326344) (xy 131.65988 -277.35179) (xy 131.651716 -277.402024) (xy 131.6356 -277.450298)
			(xy 131.611949 -277.495361) (xy 131.581376 -277.536047) (xy 131.544672 -277.571302) (xy 131.502788 -277.600212)
			(xy 131.456809 -277.622029) (xy 131.407925 -277.636189) (xy 131.357404 -277.642323) (xy 131.306552 -277.640274)
			(xy 131.256688 -277.630094) (xy 131.209102 -277.612047) (xy 131.165028 -277.586601) (xy 131.125606 -277.554414)
			(xy 131.091858 -277.51632) (xy 131.064657 -277.473306) (xy 131.044709 -277.426486) (xy 131.03253 -277.377072)
			(xy 131.028435 -277.326344) (xy 130.710178 -277.326344) (xy 130.709683 -277.350951) (xy 130.701788 -277.399528)
			(xy 130.686204 -277.446209) (xy 130.663333 -277.489786) (xy 130.633768 -277.52913) (xy 130.598275 -277.563222)
			(xy 130.557772 -277.591178) (xy 130.51331 -277.612276) (xy 130.466039 -277.625968) (xy 130.417184 -277.6319)
			(xy 130.368009 -277.629919) (xy 130.31979 -277.620075) (xy 130.273774 -277.602623) (xy 130.231153 -277.578016)
			(xy 130.193032 -277.546891) (xy 130.160397 -277.510054) (xy 130.134094 -277.468458) (xy 130.114803 -277.423182)
			(xy 130.103026 -277.375398) (xy 130.099066 -277.326344) (xy 129.780538 -277.326344) (xy 129.780026 -277.35179)
			(xy 129.771862 -277.402024) (xy 129.755746 -277.450298) (xy 129.732095 -277.495361) (xy 129.701522 -277.536047)
			(xy 129.664818 -277.571302) (xy 129.622934 -277.600212) (xy 129.576955 -277.622029) (xy 129.528071 -277.636189)
			(xy 129.47755 -277.642323) (xy 129.426698 -277.640274) (xy 129.376834 -277.630094) (xy 129.329248 -277.612047)
			(xy 129.285174 -277.586601) (xy 129.245752 -277.554414) (xy 129.212004 -277.51632) (xy 129.184803 -277.473306)
			(xy 129.164855 -277.426486) (xy 129.152676 -277.377072) (xy 129.148581 -277.326344) (xy 128.840484 -277.326344)
			(xy 128.839972 -277.35179) (xy 128.831808 -277.402024) (xy 128.815692 -277.450298) (xy 128.792041 -277.495361)
			(xy 128.761468 -277.536047) (xy 128.724764 -277.571302) (xy 128.68288 -277.600212) (xy 128.636901 -277.622029)
			(xy 128.588017 -277.636189) (xy 128.537496 -277.642323) (xy 128.486644 -277.640274) (xy 128.43678 -277.630094)
			(xy 128.389194 -277.612047) (xy 128.34512 -277.586601) (xy 128.305698 -277.554414) (xy 128.27195 -277.51632)
			(xy 128.244749 -277.473306) (xy 128.224801 -277.426486) (xy 128.212622 -277.377072) (xy 128.208527 -277.326344)
			(xy 128.0541 -277.326344) (xy 128.0541 -277.779734) (xy 128.054469 -277.78884) (xy 128.060841 -277.805901)
			(xy 128.066546 -277.813008) (xy 128.072642 -277.82012) (xy 128.098042 -277.823676) (xy 128.12289 -277.827598)
			(xy 128.170997 -277.842292) (xy 128.216164 -277.86443) (xy 128.257248 -277.893453) (xy 128.293207 -277.928625)
			(xy 128.323133 -277.969056) (xy 128.346266 -278.013722) (xy 128.362021 -278.061492) (xy 128.369999 -278.111156)
			(xy 128.369998 -278.13635) (xy 128.688858 -278.13635) (xy 128.692818 -278.087296) (xy 128.704595 -278.039512)
			(xy 128.723886 -277.994236) (xy 128.750189 -277.95264) (xy 128.782824 -277.915803) (xy 128.820945 -277.884678)
			(xy 128.863566 -277.860071) (xy 128.909582 -277.842619) (xy 128.957801 -277.832775) (xy 129.006976 -277.830794)
			(xy 129.055831 -277.836726) (xy 129.103102 -277.850418) (xy 129.147564 -277.871516) (xy 129.188067 -277.899472)
			(xy 129.22356 -277.933564) (xy 129.253125 -277.972908) (xy 129.275996 -278.016485) (xy 129.29158 -278.063166)
			(xy 129.299475 -278.111743) (xy 129.29997 -278.13635) (xy 129.618481 -278.13635) (xy 129.622576 -278.085622)
			(xy 129.634755 -278.036208) (xy 129.654703 -277.989388) (xy 129.681904 -277.946374) (xy 129.715652 -277.90828)
			(xy 129.755074 -277.876093) (xy 129.799148 -277.850647) (xy 129.846734 -277.8326) (xy 129.896598 -277.82242)
			(xy 129.94745 -277.820371) (xy 129.997971 -277.826505) (xy 130.046855 -277.840665) (xy 130.092834 -277.862482)
			(xy 130.134718 -277.891392) (xy 130.171422 -277.926647) (xy 130.201995 -277.967333) (xy 130.225646 -278.012396)
			(xy 130.241762 -278.06067) (xy 130.249926 -278.110904) (xy 130.250438 -278.13635) (xy 131.498589 -278.13635)
			(xy 131.502684 -278.085622) (xy 131.514863 -278.036208) (xy 131.534811 -277.989388) (xy 131.562012 -277.946374)
			(xy 131.59576 -277.90828) (xy 131.635182 -277.876093) (xy 131.679256 -277.850647) (xy 131.726842 -277.8326)
			(xy 131.776706 -277.82242) (xy 131.827558 -277.820371) (xy 131.878079 -277.826505) (xy 131.926963 -277.840665)
			(xy 131.972942 -277.862482) (xy 132.014826 -277.891392) (xy 132.05153 -277.926647) (xy 132.082103 -277.967333)
			(xy 132.105754 -278.012396) (xy 132.12187 -278.06067) (xy 132.130034 -278.110904) (xy 132.130546 -278.13635)
			(xy 132.438643 -278.13635) (xy 132.442738 -278.085622) (xy 132.454917 -278.036208) (xy 132.474865 -277.989388)
			(xy 132.502066 -277.946374) (xy 132.535814 -277.90828) (xy 132.575236 -277.876093) (xy 132.61931 -277.850647)
			(xy 132.666896 -277.8326) (xy 132.71676 -277.82242) (xy 132.767612 -277.820371) (xy 132.818133 -277.826505)
			(xy 132.867017 -277.840665) (xy 132.912996 -277.862482) (xy 132.95488 -277.891392) (xy 132.991584 -277.926647)
			(xy 133.022157 -277.967333) (xy 133.045808 -278.012396) (xy 133.061924 -278.06067) (xy 133.070088 -278.110904)
			(xy 133.0706 -278.13635) (xy 133.070088 -278.161796) (xy 133.061924 -278.21203) (xy 133.045808 -278.260304)
			(xy 133.022157 -278.305367) (xy 132.991584 -278.346053) (xy 132.95488 -278.381308) (xy 132.912996 -278.410218)
			(xy 132.867017 -278.432035) (xy 132.818133 -278.446195) (xy 132.767612 -278.452329) (xy 132.71676 -278.45028)
			(xy 132.666896 -278.4401) (xy 132.61931 -278.422053) (xy 132.575236 -278.396607) (xy 132.535814 -278.36442)
			(xy 132.502066 -278.326326) (xy 132.474865 -278.283312) (xy 132.454917 -278.236492) (xy 132.442738 -278.187078)
			(xy 132.438643 -278.13635) (xy 132.130546 -278.13635) (xy 132.130034 -278.161796) (xy 132.12187 -278.21203)
			(xy 132.105754 -278.260304) (xy 132.082103 -278.305367) (xy 132.05153 -278.346053) (xy 132.014826 -278.381308)
			(xy 131.972942 -278.410218) (xy 131.926963 -278.432035) (xy 131.878079 -278.446195) (xy 131.827558 -278.452329)
			(xy 131.776706 -278.45028) (xy 131.726842 -278.4401) (xy 131.679256 -278.422053) (xy 131.635182 -278.396607)
			(xy 131.59576 -278.36442) (xy 131.562012 -278.326326) (xy 131.534811 -278.283312) (xy 131.514863 -278.236492)
			(xy 131.502684 -278.187078) (xy 131.498589 -278.13635) (xy 130.250438 -278.13635) (xy 130.249926 -278.161796)
			(xy 130.241762 -278.21203) (xy 130.225646 -278.260304) (xy 130.201995 -278.305367) (xy 130.171422 -278.346053)
			(xy 130.134718 -278.381308) (xy 130.092834 -278.410218) (xy 130.046855 -278.432035) (xy 129.997971 -278.446195)
			(xy 129.94745 -278.452329) (xy 129.896598 -278.45028) (xy 129.846734 -278.4401) (xy 129.799148 -278.422053)
			(xy 129.755074 -278.396607) (xy 129.715652 -278.36442) (xy 129.681904 -278.326326) (xy 129.654703 -278.283312)
			(xy 129.634755 -278.236492) (xy 129.622576 -278.187078) (xy 129.618481 -278.13635) (xy 129.29997 -278.13635)
			(xy 129.299475 -278.160957) (xy 129.29158 -278.209534) (xy 129.275996 -278.256215) (xy 129.253125 -278.299792)
			(xy 129.22356 -278.339136) (xy 129.188067 -278.373228) (xy 129.147564 -278.401184) (xy 129.103102 -278.422282)
			(xy 129.055831 -278.435974) (xy 129.006976 -278.441906) (xy 128.957801 -278.439925) (xy 128.909582 -278.430081)
			(xy 128.863566 -278.412629) (xy 128.820945 -278.388022) (xy 128.782824 -278.356897) (xy 128.750189 -278.32006)
			(xy 128.723886 -278.278464) (xy 128.704595 -278.233188) (xy 128.692818 -278.185404) (xy 128.688858 -278.13635)
			(xy 128.369998 -278.13635) (xy 128.369998 -278.161457) (xy 128.362017 -278.211121) (xy 128.34626 -278.258891)
			(xy 128.323126 -278.303556) (xy 128.293198 -278.343985) (xy 128.257237 -278.379156) (xy 128.216152 -278.408177)
			(xy 128.170984 -278.430313) (xy 128.122876 -278.445005) (xy 128.098042 -278.449024) (xy 128.091438 -278.45004)
			(xy 128.082488 -278.451639) (xy 128.06648 -278.460232) (xy 128.060196 -278.466804) (xy 128.0541 -278.473916)
			(xy 128.0541 -278.946356) (xy 128.208527 -278.946356) (xy 128.212622 -278.895628) (xy 128.224801 -278.846214)
			(xy 128.244749 -278.799394) (xy 128.27195 -278.75638) (xy 128.305698 -278.718286) (xy 128.34512 -278.686099)
			(xy 128.389194 -278.660653) (xy 128.43678 -278.642606) (xy 128.486644 -278.632426) (xy 128.537496 -278.630377)
			(xy 128.588017 -278.636511) (xy 128.636901 -278.650671) (xy 128.68288 -278.672488) (xy 128.724764 -278.701398)
			(xy 128.761468 -278.736653) (xy 128.792041 -278.777339) (xy 128.815692 -278.822402) (xy 128.831808 -278.870676)
			(xy 128.839972 -278.92091) (xy 128.840484 -278.946356) (xy 129.148581 -278.946356) (xy 129.152676 -278.895628)
			(xy 129.164855 -278.846214) (xy 129.184803 -278.799394) (xy 129.212004 -278.75638) (xy 129.245752 -278.718286)
			(xy 129.285174 -278.686099) (xy 129.329248 -278.660653) (xy 129.376834 -278.642606) (xy 129.426698 -278.632426)
			(xy 129.47755 -278.630377) (xy 129.528071 -278.636511) (xy 129.576955 -278.650671) (xy 129.622934 -278.672488)
			(xy 129.664818 -278.701398) (xy 129.701522 -278.736653) (xy 129.732095 -278.777339) (xy 129.755746 -278.822402)
			(xy 129.771862 -278.870676) (xy 129.780026 -278.92091) (xy 129.780538 -278.946356) (xy 130.099066 -278.946356)
			(xy 130.103026 -278.897302) (xy 130.114803 -278.849518) (xy 130.134094 -278.804242) (xy 130.160397 -278.762646)
			(xy 130.193032 -278.725809) (xy 130.231153 -278.694684) (xy 130.273774 -278.670077) (xy 130.31979 -278.652625)
			(xy 130.368009 -278.642781) (xy 130.417184 -278.6408) (xy 130.466039 -278.646732) (xy 130.51331 -278.660424)
			(xy 130.557772 -278.681522) (xy 130.598275 -278.709478) (xy 130.633768 -278.74357) (xy 130.663333 -278.782914)
			(xy 130.686204 -278.826491) (xy 130.701788 -278.873172) (xy 130.709683 -278.921749) (xy 130.710178 -278.946356)
			(xy 131.028435 -278.946356) (xy 131.03253 -278.895628) (xy 131.044709 -278.846214) (xy 131.064657 -278.799394)
			(xy 131.091858 -278.75638) (xy 131.125606 -278.718286) (xy 131.165028 -278.686099) (xy 131.209102 -278.660653)
			(xy 131.256688 -278.642606) (xy 131.306552 -278.632426) (xy 131.357404 -278.630377) (xy 131.407925 -278.636511)
			(xy 131.456809 -278.650671) (xy 131.502788 -278.672488) (xy 131.544672 -278.701398) (xy 131.581376 -278.736653)
			(xy 131.611949 -278.777339) (xy 131.6356 -278.822402) (xy 131.651716 -278.870676) (xy 131.65988 -278.92091)
			(xy 131.660392 -278.946356) (xy 131.97892 -278.946356) (xy 131.98288 -278.897302) (xy 131.994657 -278.849518)
			(xy 132.013948 -278.804242) (xy 132.040251 -278.762646) (xy 132.072886 -278.725809) (xy 132.111007 -278.694684)
			(xy 132.153628 -278.670077) (xy 132.199644 -278.652625) (xy 132.247863 -278.642781) (xy 132.297038 -278.6408)
			(xy 132.345893 -278.646732) (xy 132.393164 -278.660424) (xy 132.437626 -278.681522) (xy 132.478129 -278.709478)
			(xy 132.513622 -278.74357) (xy 132.543187 -278.782914) (xy 132.566058 -278.826491) (xy 132.581642 -278.873172)
			(xy 132.589537 -278.921749) (xy 132.590032 -278.946356) (xy 132.908543 -278.946356) (xy 132.912638 -278.895628)
			(xy 132.924817 -278.846214) (xy 132.944765 -278.799394) (xy 132.971966 -278.75638) (xy 133.005714 -278.718286)
			(xy 133.045136 -278.686099) (xy 133.08921 -278.660653) (xy 133.136796 -278.642606) (xy 133.18666 -278.632426)
			(xy 133.237512 -278.630377) (xy 133.288033 -278.636511) (xy 133.336917 -278.650671) (xy 133.382896 -278.672488)
			(xy 133.42478 -278.701398) (xy 133.461484 -278.736653) (xy 133.492057 -278.777339) (xy 133.515708 -278.822402)
			(xy 133.531824 -278.870676) (xy 133.539988 -278.92091) (xy 133.5405 -278.946356) (xy 133.539988 -278.971802)
			(xy 133.531824 -279.022036) (xy 133.515708 -279.07031) (xy 133.492057 -279.115373) (xy 133.461484 -279.156059)
			(xy 133.42478 -279.191314) (xy 133.382896 -279.220224) (xy 133.336917 -279.242041) (xy 133.288033 -279.256201)
			(xy 133.237512 -279.262335) (xy 133.18666 -279.260286) (xy 133.136796 -279.250106) (xy 133.08921 -279.232059)
			(xy 133.045136 -279.206613) (xy 133.005714 -279.174426) (xy 132.971966 -279.136332) (xy 132.944765 -279.093318)
			(xy 132.924817 -279.046498) (xy 132.912638 -278.997084) (xy 132.908543 -278.946356) (xy 132.590032 -278.946356)
			(xy 132.589537 -278.970963) (xy 132.581642 -279.01954) (xy 132.566058 -279.066221) (xy 132.543187 -279.109798)
			(xy 132.513622 -279.149142) (xy 132.478129 -279.183234) (xy 132.437626 -279.21119) (xy 132.393164 -279.232288)
			(xy 132.345893 -279.24598) (xy 132.297038 -279.251912) (xy 132.247863 -279.249931) (xy 132.199644 -279.240087)
			(xy 132.153628 -279.222635) (xy 132.111007 -279.198028) (xy 132.072886 -279.166903) (xy 132.040251 -279.130066)
			(xy 132.013948 -279.08847) (xy 131.994657 -279.043194) (xy 131.98288 -278.99541) (xy 131.97892 -278.946356)
			(xy 131.660392 -278.946356) (xy 131.65988 -278.971802) (xy 131.651716 -279.022036) (xy 131.6356 -279.07031)
			(xy 131.611949 -279.115373) (xy 131.581376 -279.156059) (xy 131.544672 -279.191314) (xy 131.502788 -279.220224)
			(xy 131.456809 -279.242041) (xy 131.407925 -279.256201) (xy 131.357404 -279.262335) (xy 131.306552 -279.260286)
			(xy 131.256688 -279.250106) (xy 131.209102 -279.232059) (xy 131.165028 -279.206613) (xy 131.125606 -279.174426)
			(xy 131.091858 -279.136332) (xy 131.064657 -279.093318) (xy 131.044709 -279.046498) (xy 131.03253 -278.997084)
			(xy 131.028435 -278.946356) (xy 130.710178 -278.946356) (xy 130.709683 -278.970963) (xy 130.701788 -279.01954)
			(xy 130.686204 -279.066221) (xy 130.663333 -279.109798) (xy 130.633768 -279.149142) (xy 130.598275 -279.183234)
			(xy 130.557772 -279.21119) (xy 130.51331 -279.232288) (xy 130.466039 -279.24598) (xy 130.417184 -279.251912)
			(xy 130.368009 -279.249931) (xy 130.31979 -279.240087) (xy 130.273774 -279.222635) (xy 130.231153 -279.198028)
			(xy 130.193032 -279.166903) (xy 130.160397 -279.130066) (xy 130.134094 -279.08847) (xy 130.114803 -279.043194)
			(xy 130.103026 -278.99541) (xy 130.099066 -278.946356) (xy 129.780538 -278.946356) (xy 129.780026 -278.971802)
			(xy 129.771862 -279.022036) (xy 129.755746 -279.07031) (xy 129.732095 -279.115373) (xy 129.701522 -279.156059)
			(xy 129.664818 -279.191314) (xy 129.622934 -279.220224) (xy 129.576955 -279.242041) (xy 129.528071 -279.256201)
			(xy 129.47755 -279.262335) (xy 129.426698 -279.260286) (xy 129.376834 -279.250106) (xy 129.329248 -279.232059)
			(xy 129.285174 -279.206613) (xy 129.245752 -279.174426) (xy 129.212004 -279.136332) (xy 129.184803 -279.093318)
			(xy 129.164855 -279.046498) (xy 129.152676 -278.997084) (xy 129.148581 -278.946356) (xy 128.840484 -278.946356)
			(xy 128.839972 -278.971802) (xy 128.831808 -279.022036) (xy 128.815692 -279.07031) (xy 128.792041 -279.115373)
			(xy 128.761468 -279.156059) (xy 128.724764 -279.191314) (xy 128.68288 -279.220224) (xy 128.636901 -279.242041)
			(xy 128.588017 -279.256201) (xy 128.537496 -279.262335) (xy 128.486644 -279.260286) (xy 128.43678 -279.250106)
			(xy 128.389194 -279.232059) (xy 128.34512 -279.206613) (xy 128.305698 -279.174426) (xy 128.27195 -279.136332)
			(xy 128.244749 -279.093318) (xy 128.224801 -279.046498) (xy 128.212622 -278.997084) (xy 128.208527 -278.946356)
			(xy 128.0541 -278.946356) (xy 128.0541 -279.399746) (xy 128.054471 -279.408852) (xy 128.060846 -279.42591)
			(xy 128.066546 -279.43302) (xy 128.072642 -279.440132) (xy 128.098042 -279.443688) (xy 128.122897 -279.447611)
			(xy 128.171018 -279.462306) (xy 128.216198 -279.484449) (xy 128.257294 -279.513478) (xy 128.293265 -279.548659)
			(xy 128.3232 -279.5891) (xy 128.346341 -279.633777) (xy 128.362103 -279.68156) (xy 128.370085 -279.731237)
			(xy 128.370085 -279.756362) (xy 128.688858 -279.756362) (xy 128.692818 -279.707308) (xy 128.704595 -279.659524)
			(xy 128.723886 -279.614248) (xy 128.750189 -279.572652) (xy 128.782824 -279.535815) (xy 128.820945 -279.50469)
			(xy 128.863566 -279.480083) (xy 128.909582 -279.462631) (xy 128.957801 -279.452787) (xy 129.006976 -279.450806)
			(xy 129.055831 -279.456738) (xy 129.103102 -279.47043) (xy 129.147564 -279.491528) (xy 129.188067 -279.519484)
			(xy 129.22356 -279.553576) (xy 129.253125 -279.59292) (xy 129.275996 -279.636497) (xy 129.29158 -279.683178)
			(xy 129.299475 -279.731755) (xy 129.29997 -279.756362) (xy 129.618481 -279.756362) (xy 129.622576 -279.705634)
			(xy 129.634755 -279.65622) (xy 129.654703 -279.6094) (xy 129.681904 -279.566386) (xy 129.715652 -279.528292)
			(xy 129.755074 -279.496105) (xy 129.799148 -279.470659) (xy 129.846734 -279.452612) (xy 129.896598 -279.442432)
			(xy 129.94745 -279.440383) (xy 129.997971 -279.446517) (xy 130.046855 -279.460677) (xy 130.092834 -279.482494)
			(xy 130.134718 -279.511404) (xy 130.171422 -279.546659) (xy 130.201995 -279.587345) (xy 130.225646 -279.632408)
			(xy 130.241762 -279.680682) (xy 130.249926 -279.730916) (xy 130.250438 -279.756362) (xy 130.568966 -279.756362)
			(xy 130.572926 -279.707308) (xy 130.584703 -279.659524) (xy 130.603994 -279.614248) (xy 130.630297 -279.572652)
			(xy 130.662932 -279.535815) (xy 130.701053 -279.50469) (xy 130.743674 -279.480083) (xy 130.78969 -279.462631)
			(xy 130.837909 -279.452787) (xy 130.887084 -279.450806) (xy 130.935939 -279.456738) (xy 130.98321 -279.47043)
			(xy 131.027672 -279.491528) (xy 131.068175 -279.519484) (xy 131.103668 -279.553576) (xy 131.133233 -279.59292)
			(xy 131.156104 -279.636497) (xy 131.171688 -279.683178) (xy 131.179583 -279.731755) (xy 131.180078 -279.756362)
			(xy 131.498589 -279.756362) (xy 131.502684 -279.705634) (xy 131.514863 -279.65622) (xy 131.534811 -279.6094)
			(xy 131.562012 -279.566386) (xy 131.59576 -279.528292) (xy 131.635182 -279.496105) (xy 131.679256 -279.470659)
			(xy 131.726842 -279.452612) (xy 131.776706 -279.442432) (xy 131.827558 -279.440383) (xy 131.878079 -279.446517)
			(xy 131.926963 -279.460677) (xy 131.972942 -279.482494) (xy 132.014826 -279.511404) (xy 132.05153 -279.546659)
			(xy 132.082103 -279.587345) (xy 132.105754 -279.632408) (xy 132.12187 -279.680682) (xy 132.130034 -279.730916)
			(xy 132.130546 -279.756362) (xy 132.438643 -279.756362) (xy 132.442738 -279.705634) (xy 132.454917 -279.65622)
			(xy 132.474865 -279.6094) (xy 132.502066 -279.566386) (xy 132.535814 -279.528292) (xy 132.575236 -279.496105)
			(xy 132.61931 -279.470659) (xy 132.666896 -279.452612) (xy 132.71676 -279.442432) (xy 132.767612 -279.440383)
			(xy 132.818133 -279.446517) (xy 132.867017 -279.460677) (xy 132.912996 -279.482494) (xy 132.95488 -279.511404)
			(xy 132.991584 -279.546659) (xy 133.022157 -279.587345) (xy 133.045808 -279.632408) (xy 133.061924 -279.680682)
			(xy 133.070088 -279.730916) (xy 133.0706 -279.756362) (xy 133.070088 -279.781808) (xy 133.061924 -279.832042)
			(xy 133.045808 -279.880316) (xy 133.022157 -279.925379) (xy 132.991584 -279.966065) (xy 132.95488 -280.00132)
			(xy 132.912996 -280.03023) (xy 132.867017 -280.052047) (xy 132.818133 -280.066207) (xy 132.767612 -280.072341)
			(xy 132.71676 -280.070292) (xy 132.666896 -280.060112) (xy 132.61931 -280.042065) (xy 132.575236 -280.016619)
			(xy 132.535814 -279.984432) (xy 132.502066 -279.946338) (xy 132.474865 -279.903324) (xy 132.454917 -279.856504)
			(xy 132.442738 -279.80709) (xy 132.438643 -279.756362) (xy 132.130546 -279.756362) (xy 132.130034 -279.781808)
			(xy 132.12187 -279.832042) (xy 132.105754 -279.880316) (xy 132.082103 -279.925379) (xy 132.05153 -279.966065)
			(xy 132.014826 -280.00132) (xy 131.972942 -280.03023) (xy 131.926963 -280.052047) (xy 131.878079 -280.066207)
			(xy 131.827558 -280.072341) (xy 131.776706 -280.070292) (xy 131.726842 -280.060112) (xy 131.679256 -280.042065)
			(xy 131.635182 -280.016619) (xy 131.59576 -279.984432) (xy 131.562012 -279.946338) (xy 131.534811 -279.903324)
			(xy 131.514863 -279.856504) (xy 131.502684 -279.80709) (xy 131.498589 -279.756362) (xy 131.180078 -279.756362)
			(xy 131.179583 -279.780969) (xy 131.171688 -279.829546) (xy 131.156104 -279.876227) (xy 131.133233 -279.919804)
			(xy 131.103668 -279.959148) (xy 131.068175 -279.99324) (xy 131.027672 -280.021196) (xy 130.98321 -280.042294)
			(xy 130.935939 -280.055986) (xy 130.887084 -280.061918) (xy 130.837909 -280.059937) (xy 130.78969 -280.050093)
			(xy 130.743674 -280.032641) (xy 130.701053 -280.008034) (xy 130.662932 -279.976909) (xy 130.630297 -279.940072)
			(xy 130.603994 -279.898476) (xy 130.584703 -279.8532) (xy 130.572926 -279.805416) (xy 130.568966 -279.756362)
			(xy 130.250438 -279.756362) (xy 130.249926 -279.781808) (xy 130.241762 -279.832042) (xy 130.225646 -279.880316)
			(xy 130.201995 -279.925379) (xy 130.171422 -279.966065) (xy 130.134718 -280.00132) (xy 130.092834 -280.03023)
			(xy 130.046855 -280.052047) (xy 129.997971 -280.066207) (xy 129.94745 -280.072341) (xy 129.896598 -280.070292)
			(xy 129.846734 -280.060112) (xy 129.799148 -280.042065) (xy 129.755074 -280.016619) (xy 129.715652 -279.984432)
			(xy 129.681904 -279.946338) (xy 129.654703 -279.903324) (xy 129.634755 -279.856504) (xy 129.622576 -279.80709)
			(xy 129.618481 -279.756362) (xy 129.29997 -279.756362) (xy 129.299475 -279.780969) (xy 129.29158 -279.829546)
			(xy 129.275996 -279.876227) (xy 129.253125 -279.919804) (xy 129.22356 -279.959148) (xy 129.188067 -279.99324)
			(xy 129.147564 -280.021196) (xy 129.103102 -280.042294) (xy 129.055831 -280.055986) (xy 129.006976 -280.061918)
			(xy 128.957801 -280.059937) (xy 128.909582 -280.050093) (xy 128.863566 -280.032641) (xy 128.820945 -280.008034)
			(xy 128.782824 -279.976909) (xy 128.750189 -279.940072) (xy 128.723886 -279.898476) (xy 128.704595 -279.8532)
			(xy 128.692818 -279.805416) (xy 128.688858 -279.756362) (xy 128.370085 -279.756362) (xy 128.370085 -279.781552)
			(xy 128.362105 -279.83123) (xy 128.346345 -279.879013) (xy 128.323206 -279.923692) (xy 128.293272 -279.964134)
			(xy 128.257302 -279.999315) (xy 128.216207 -280.028346) (xy 128.171027 -280.05049) (xy 128.122907 -280.065187)
			(xy 128.098042 -280.069036) (xy 128.091438 -280.070052) (xy 128.082488 -280.071652) (xy 128.066482 -280.080247)
			(xy 128.060196 -280.086816) (xy 128.0541 -280.093928) (xy 128.0541 -280.566368) (xy 128.208527 -280.566368)
			(xy 128.212622 -280.51564) (xy 128.224801 -280.466226) (xy 128.244749 -280.419406) (xy 128.27195 -280.376392)
			(xy 128.305698 -280.338298) (xy 128.34512 -280.306111) (xy 128.389194 -280.280665) (xy 128.43678 -280.262618)
			(xy 128.486644 -280.252438) (xy 128.537496 -280.250389) (xy 128.588017 -280.256523) (xy 128.636901 -280.270683)
			(xy 128.68288 -280.2925) (xy 128.724764 -280.32141) (xy 128.761468 -280.356665) (xy 128.792041 -280.397351)
			(xy 128.815692 -280.442414) (xy 128.831808 -280.490688) (xy 128.839972 -280.540922) (xy 128.840484 -280.566368)
			(xy 129.148581 -280.566368) (xy 129.152676 -280.51564) (xy 129.164855 -280.466226) (xy 129.184803 -280.419406)
			(xy 129.212004 -280.376392) (xy 129.245752 -280.338298) (xy 129.285174 -280.306111) (xy 129.329248 -280.280665)
			(xy 129.376834 -280.262618) (xy 129.426698 -280.252438) (xy 129.47755 -280.250389) (xy 129.528071 -280.256523)
			(xy 129.576955 -280.270683) (xy 129.622934 -280.2925) (xy 129.664818 -280.32141) (xy 129.701522 -280.356665)
			(xy 129.732095 -280.397351) (xy 129.755746 -280.442414) (xy 129.771862 -280.490688) (xy 129.780026 -280.540922)
			(xy 129.780538 -280.566368) (xy 131.028435 -280.566368) (xy 131.03253 -280.51564) (xy 131.044709 -280.466226)
			(xy 131.064657 -280.419406) (xy 131.091858 -280.376392) (xy 131.125606 -280.338298) (xy 131.165028 -280.306111)
			(xy 131.209102 -280.280665) (xy 131.256688 -280.262618) (xy 131.306552 -280.252438) (xy 131.357404 -280.250389)
			(xy 131.407925 -280.256523) (xy 131.456809 -280.270683) (xy 131.502788 -280.2925) (xy 131.544672 -280.32141)
			(xy 131.581376 -280.356665) (xy 131.611949 -280.397351) (xy 131.6356 -280.442414) (xy 131.651716 -280.490688)
			(xy 131.65988 -280.540922) (xy 131.660392 -280.566368) (xy 131.97892 -280.566368) (xy 131.98288 -280.517314)
			(xy 131.994657 -280.46953) (xy 132.013948 -280.424254) (xy 132.040251 -280.382658) (xy 132.072886 -280.345821)
			(xy 132.111007 -280.314696) (xy 132.153628 -280.290089) (xy 132.199644 -280.272637) (xy 132.247863 -280.262793)
			(xy 132.297038 -280.260812) (xy 132.345893 -280.266744) (xy 132.393164 -280.280436) (xy 132.437626 -280.301534)
			(xy 132.478129 -280.32949) (xy 132.513622 -280.363582) (xy 132.543187 -280.402926) (xy 132.566058 -280.446503)
			(xy 132.581642 -280.493184) (xy 132.589537 -280.541761) (xy 132.590032 -280.566368) (xy 132.908543 -280.566368)
			(xy 132.912638 -280.51564) (xy 132.924817 -280.466226) (xy 132.944765 -280.419406) (xy 132.971966 -280.376392)
			(xy 133.005714 -280.338298) (xy 133.045136 -280.306111) (xy 133.08921 -280.280665) (xy 133.136796 -280.262618)
			(xy 133.18666 -280.252438) (xy 133.237512 -280.250389) (xy 133.288033 -280.256523) (xy 133.336917 -280.270683)
			(xy 133.382896 -280.2925) (xy 133.42478 -280.32141) (xy 133.461484 -280.356665) (xy 133.492057 -280.397351)
			(xy 133.515708 -280.442414) (xy 133.531824 -280.490688) (xy 133.539988 -280.540922) (xy 133.5405 -280.566368)
			(xy 133.539988 -280.591814) (xy 133.531824 -280.642048) (xy 133.515708 -280.690322) (xy 133.492057 -280.735385)
			(xy 133.461484 -280.776071) (xy 133.42478 -280.811326) (xy 133.382896 -280.840236) (xy 133.336917 -280.862053)
			(xy 133.288033 -280.876213) (xy 133.237512 -280.882347) (xy 133.18666 -280.880298) (xy 133.136796 -280.870118)
			(xy 133.08921 -280.852071) (xy 133.045136 -280.826625) (xy 133.005714 -280.794438) (xy 132.971966 -280.756344)
			(xy 132.944765 -280.71333) (xy 132.924817 -280.66651) (xy 132.912638 -280.617096) (xy 132.908543 -280.566368)
			(xy 132.590032 -280.566368) (xy 132.589537 -280.590975) (xy 132.581642 -280.639552) (xy 132.566058 -280.686233)
			(xy 132.543187 -280.72981) (xy 132.513622 -280.769154) (xy 132.478129 -280.803246) (xy 132.437626 -280.831202)
			(xy 132.393164 -280.8523) (xy 132.345893 -280.865992) (xy 132.297038 -280.871924) (xy 132.247863 -280.869943)
			(xy 132.199644 -280.860099) (xy 132.153628 -280.842647) (xy 132.111007 -280.81804) (xy 132.072886 -280.786915)
			(xy 132.040251 -280.750078) (xy 132.013948 -280.708482) (xy 131.994657 -280.663206) (xy 131.98288 -280.615422)
			(xy 131.97892 -280.566368) (xy 131.660392 -280.566368) (xy 131.65988 -280.591814) (xy 131.651716 -280.642048)
			(xy 131.6356 -280.690322) (xy 131.611949 -280.735385) (xy 131.581376 -280.776071) (xy 131.544672 -280.811326)
			(xy 131.502788 -280.840236) (xy 131.456809 -280.862053) (xy 131.407925 -280.876213) (xy 131.357404 -280.882347)
			(xy 131.306552 -280.880298) (xy 131.256688 -280.870118) (xy 131.209102 -280.852071) (xy 131.165028 -280.826625)
			(xy 131.125606 -280.794438) (xy 131.091858 -280.756344) (xy 131.064657 -280.71333) (xy 131.044709 -280.66651)
			(xy 131.03253 -280.617096) (xy 131.028435 -280.566368) (xy 129.780538 -280.566368) (xy 129.780026 -280.591814)
			(xy 129.771862 -280.642048) (xy 129.755746 -280.690322) (xy 129.732095 -280.735385) (xy 129.701522 -280.776071)
			(xy 129.664818 -280.811326) (xy 129.622934 -280.840236) (xy 129.576955 -280.862053) (xy 129.528071 -280.876213)
			(xy 129.47755 -280.882347) (xy 129.426698 -280.880298) (xy 129.376834 -280.870118) (xy 129.329248 -280.852071)
			(xy 129.285174 -280.826625) (xy 129.245752 -280.794438) (xy 129.212004 -280.756344) (xy 129.184803 -280.71333)
			(xy 129.164855 -280.66651) (xy 129.152676 -280.617096) (xy 129.148581 -280.566368) (xy 128.840484 -280.566368)
			(xy 128.839972 -280.591814) (xy 128.831808 -280.642048) (xy 128.815692 -280.690322) (xy 128.792041 -280.735385)
			(xy 128.761468 -280.776071) (xy 128.724764 -280.811326) (xy 128.68288 -280.840236) (xy 128.636901 -280.862053)
			(xy 128.588017 -280.876213) (xy 128.537496 -280.882347) (xy 128.486644 -280.880298) (xy 128.43678 -280.870118)
			(xy 128.389194 -280.852071) (xy 128.34512 -280.826625) (xy 128.305698 -280.794438) (xy 128.27195 -280.756344)
			(xy 128.244749 -280.71333) (xy 128.224801 -280.66651) (xy 128.212622 -280.617096) (xy 128.208527 -280.566368)
			(xy 128.0541 -280.566368) (xy 128.0541 -281.019758) (xy 128.054473 -281.028863) (xy 128.060851 -281.045918)
			(xy 128.066546 -281.053032) (xy 128.072642 -281.060144) (xy 128.098042 -281.0637) (xy 128.122896 -281.067622)
			(xy 128.171015 -281.082318) (xy 128.216193 -281.10446) (xy 128.257288 -281.133488) (xy 128.293257 -281.168668)
			(xy 128.323191 -281.209107) (xy 128.346331 -281.253783) (xy 128.362091 -281.301564) (xy 128.370073 -281.35124)
			(xy 128.370073 -281.376374) (xy 128.688858 -281.376374) (xy 128.692818 -281.32732) (xy 128.704595 -281.279536)
			(xy 128.723886 -281.23426) (xy 128.750189 -281.192664) (xy 128.782824 -281.155827) (xy 128.820945 -281.124702)
			(xy 128.863566 -281.100095) (xy 128.909582 -281.082643) (xy 128.957801 -281.072799) (xy 129.006976 -281.070818)
			(xy 129.055831 -281.07675) (xy 129.103102 -281.090442) (xy 129.147564 -281.11154) (xy 129.188067 -281.139496)
			(xy 129.22356 -281.173588) (xy 129.253125 -281.212932) (xy 129.275996 -281.256509) (xy 129.29158 -281.30319)
			(xy 129.299475 -281.351767) (xy 129.29997 -281.376374) (xy 129.618481 -281.376374) (xy 129.622576 -281.325646)
			(xy 129.634755 -281.276232) (xy 129.654703 -281.229412) (xy 129.681904 -281.186398) (xy 129.715652 -281.148304)
			(xy 129.755074 -281.116117) (xy 129.799148 -281.090671) (xy 129.846734 -281.072624) (xy 129.896598 -281.062444)
			(xy 129.94745 -281.060395) (xy 129.997971 -281.066529) (xy 130.046855 -281.080689) (xy 130.092834 -281.102506)
			(xy 130.134718 -281.131416) (xy 130.171422 -281.166671) (xy 130.201995 -281.207357) (xy 130.225646 -281.25242)
			(xy 130.241762 -281.300694) (xy 130.249926 -281.350928) (xy 130.250438 -281.376374) (xy 130.568966 -281.376374)
			(xy 130.572926 -281.32732) (xy 130.584703 -281.279536) (xy 130.603994 -281.23426) (xy 130.630297 -281.192664)
			(xy 130.662932 -281.155827) (xy 130.701053 -281.124702) (xy 130.743674 -281.100095) (xy 130.78969 -281.082643)
			(xy 130.837909 -281.072799) (xy 130.887084 -281.070818) (xy 130.935939 -281.07675) (xy 130.98321 -281.090442)
			(xy 131.027672 -281.11154) (xy 131.068175 -281.139496) (xy 131.103668 -281.173588) (xy 131.133233 -281.212932)
			(xy 131.156104 -281.256509) (xy 131.171688 -281.30319) (xy 131.179583 -281.351767) (xy 131.180078 -281.376374)
			(xy 131.498589 -281.376374) (xy 131.502684 -281.325646) (xy 131.514863 -281.276232) (xy 131.534811 -281.229412)
			(xy 131.562012 -281.186398) (xy 131.59576 -281.148304) (xy 131.635182 -281.116117) (xy 131.679256 -281.090671)
			(xy 131.726842 -281.072624) (xy 131.776706 -281.062444) (xy 131.827558 -281.060395) (xy 131.878079 -281.066529)
			(xy 131.926963 -281.080689) (xy 131.972942 -281.102506) (xy 132.014826 -281.131416) (xy 132.05153 -281.166671)
			(xy 132.082103 -281.207357) (xy 132.105754 -281.25242) (xy 132.12187 -281.300694) (xy 132.130034 -281.350928)
			(xy 132.130546 -281.376374) (xy 132.438643 -281.376374) (xy 132.442738 -281.325646) (xy 132.454917 -281.276232)
			(xy 132.474865 -281.229412) (xy 132.502066 -281.186398) (xy 132.535814 -281.148304) (xy 132.575236 -281.116117)
			(xy 132.61931 -281.090671) (xy 132.666896 -281.072624) (xy 132.71676 -281.062444) (xy 132.767612 -281.060395)
			(xy 132.818133 -281.066529) (xy 132.867017 -281.080689) (xy 132.912996 -281.102506) (xy 132.95488 -281.131416)
			(xy 132.991584 -281.166671) (xy 133.022157 -281.207357) (xy 133.045808 -281.25242) (xy 133.061924 -281.300694)
			(xy 133.070088 -281.350928) (xy 133.0706 -281.376374) (xy 133.070088 -281.40182) (xy 133.061924 -281.452054)
			(xy 133.045808 -281.500328) (xy 133.022157 -281.545391) (xy 132.991584 -281.586077) (xy 132.95488 -281.621332)
			(xy 132.912996 -281.650242) (xy 132.867017 -281.672059) (xy 132.818133 -281.686219) (xy 132.767612 -281.692353)
			(xy 132.71676 -281.690304) (xy 132.666896 -281.680124) (xy 132.61931 -281.662077) (xy 132.575236 -281.636631)
			(xy 132.535814 -281.604444) (xy 132.502066 -281.56635) (xy 132.474865 -281.523336) (xy 132.454917 -281.476516)
			(xy 132.442738 -281.427102) (xy 132.438643 -281.376374) (xy 132.130546 -281.376374) (xy 132.130034 -281.40182)
			(xy 132.12187 -281.452054) (xy 132.105754 -281.500328) (xy 132.082103 -281.545391) (xy 132.05153 -281.586077)
			(xy 132.014826 -281.621332) (xy 131.972942 -281.650242) (xy 131.926963 -281.672059) (xy 131.878079 -281.686219)
			(xy 131.827558 -281.692353) (xy 131.776706 -281.690304) (xy 131.726842 -281.680124) (xy 131.679256 -281.662077)
			(xy 131.635182 -281.636631) (xy 131.59576 -281.604444) (xy 131.562012 -281.56635) (xy 131.534811 -281.523336)
			(xy 131.514863 -281.476516) (xy 131.502684 -281.427102) (xy 131.498589 -281.376374) (xy 131.180078 -281.376374)
			(xy 131.179583 -281.400981) (xy 131.171688 -281.449558) (xy 131.156104 -281.496239) (xy 131.133233 -281.539816)
			(xy 131.103668 -281.57916) (xy 131.068175 -281.613252) (xy 131.027672 -281.641208) (xy 130.98321 -281.662306)
			(xy 130.935939 -281.675998) (xy 130.887084 -281.68193) (xy 130.837909 -281.679949) (xy 130.78969 -281.670105)
			(xy 130.743674 -281.652653) (xy 130.701053 -281.628046) (xy 130.662932 -281.596921) (xy 130.630297 -281.560084)
			(xy 130.603994 -281.518488) (xy 130.584703 -281.473212) (xy 130.572926 -281.425428) (xy 130.568966 -281.376374)
			(xy 130.250438 -281.376374) (xy 130.249926 -281.40182) (xy 130.241762 -281.452054) (xy 130.225646 -281.500328)
			(xy 130.201995 -281.545391) (xy 130.171422 -281.586077) (xy 130.134718 -281.621332) (xy 130.092834 -281.650242)
			(xy 130.046855 -281.672059) (xy 129.997971 -281.686219) (xy 129.94745 -281.692353) (xy 129.896598 -281.690304)
			(xy 129.846734 -281.680124) (xy 129.799148 -281.662077) (xy 129.755074 -281.636631) (xy 129.715652 -281.604444)
			(xy 129.681904 -281.56635) (xy 129.654703 -281.523336) (xy 129.634755 -281.476516) (xy 129.622576 -281.427102)
			(xy 129.618481 -281.376374) (xy 129.29997 -281.376374) (xy 129.299475 -281.400981) (xy 129.29158 -281.449558)
			(xy 129.275996 -281.496239) (xy 129.253125 -281.539816) (xy 129.22356 -281.57916) (xy 129.188067 -281.613252)
			(xy 129.147564 -281.641208) (xy 129.103102 -281.662306) (xy 129.055831 -281.675998) (xy 129.006976 -281.68193)
			(xy 128.957801 -281.679949) (xy 128.909582 -281.670105) (xy 128.863566 -281.652653) (xy 128.820945 -281.628046)
			(xy 128.782824 -281.596921) (xy 128.750189 -281.560084) (xy 128.723886 -281.518488) (xy 128.704595 -281.473212)
			(xy 128.692818 -281.425428) (xy 128.688858 -281.376374) (xy 128.370073 -281.376374) (xy 128.370073 -281.401553)
			(xy 128.362093 -281.451229) (xy 128.346334 -281.49901) (xy 128.323195 -281.543687) (xy 128.293262 -281.584127)
			(xy 128.257293 -281.619307) (xy 128.2162 -281.648336) (xy 128.171021 -281.67048) (xy 128.122903 -281.685176)
			(xy 128.098042 -281.689048) (xy 128.091438 -281.690064) (xy 128.082488 -281.691664) (xy 128.066484 -281.70026)
			(xy 128.060196 -281.706828) (xy 128.0541 -281.71394) (xy 128.0541 -282.18638) (xy 128.208527 -282.18638)
			(xy 128.212622 -282.135652) (xy 128.224801 -282.086238) (xy 128.244749 -282.039418) (xy 128.27195 -281.996404)
			(xy 128.305698 -281.95831) (xy 128.34512 -281.926123) (xy 128.389194 -281.900677) (xy 128.43678 -281.88263)
			(xy 128.486644 -281.87245) (xy 128.537496 -281.870401) (xy 128.588017 -281.876535) (xy 128.636901 -281.890695)
			(xy 128.68288 -281.912512) (xy 128.724764 -281.941422) (xy 128.761468 -281.976677) (xy 128.792041 -282.017363)
			(xy 128.815692 -282.062426) (xy 128.831808 -282.1107) (xy 128.839972 -282.160934) (xy 128.840484 -282.18638)
			(xy 129.148581 -282.18638) (xy 129.152676 -282.135652) (xy 129.164855 -282.086238) (xy 129.184803 -282.039418)
			(xy 129.212004 -281.996404) (xy 129.245752 -281.95831) (xy 129.285174 -281.926123) (xy 129.329248 -281.900677)
			(xy 129.376834 -281.88263) (xy 129.426698 -281.87245) (xy 129.47755 -281.870401) (xy 129.528071 -281.876535)
			(xy 129.576955 -281.890695) (xy 129.622934 -281.912512) (xy 129.664818 -281.941422) (xy 129.701522 -281.976677)
			(xy 129.732095 -282.017363) (xy 129.755746 -282.062426) (xy 129.771862 -282.1107) (xy 129.780026 -282.160934)
			(xy 129.780538 -282.18638) (xy 130.099066 -282.18638) (xy 130.103026 -282.137326) (xy 130.114803 -282.089542)
			(xy 130.134094 -282.044266) (xy 130.160397 -282.00267) (xy 130.193032 -281.965833) (xy 130.231153 -281.934708)
			(xy 130.273774 -281.910101) (xy 130.31979 -281.892649) (xy 130.368009 -281.882805) (xy 130.417184 -281.880824)
			(xy 130.466039 -281.886756) (xy 130.51331 -281.900448) (xy 130.557772 -281.921546) (xy 130.598275 -281.949502)
			(xy 130.633768 -281.983594) (xy 130.663333 -282.022938) (xy 130.686204 -282.066515) (xy 130.701788 -282.113196)
			(xy 130.709683 -282.161773) (xy 130.710178 -282.18638) (xy 131.028435 -282.18638) (xy 131.03253 -282.135652)
			(xy 131.044709 -282.086238) (xy 131.064657 -282.039418) (xy 131.091858 -281.996404) (xy 131.125606 -281.95831)
			(xy 131.165028 -281.926123) (xy 131.209102 -281.900677) (xy 131.256688 -281.88263) (xy 131.306552 -281.87245)
			(xy 131.357404 -281.870401) (xy 131.407925 -281.876535) (xy 131.456809 -281.890695) (xy 131.502788 -281.912512)
			(xy 131.544672 -281.941422) (xy 131.581376 -281.976677) (xy 131.611949 -282.017363) (xy 131.6356 -282.062426)
			(xy 131.651716 -282.1107) (xy 131.65988 -282.160934) (xy 131.660392 -282.18638) (xy 131.97892 -282.18638)
			(xy 131.98288 -282.137326) (xy 131.994657 -282.089542) (xy 132.013948 -282.044266) (xy 132.040251 -282.00267)
			(xy 132.072886 -281.965833) (xy 132.111007 -281.934708) (xy 132.153628 -281.910101) (xy 132.199644 -281.892649)
			(xy 132.247863 -281.882805) (xy 132.297038 -281.880824) (xy 132.345893 -281.886756) (xy 132.393164 -281.900448)
			(xy 132.437626 -281.921546) (xy 132.478129 -281.949502) (xy 132.513622 -281.983594) (xy 132.543187 -282.022938)
			(xy 132.566058 -282.066515) (xy 132.581642 -282.113196) (xy 132.589537 -282.161773) (xy 132.590032 -282.18638)
			(xy 132.908543 -282.18638) (xy 132.912638 -282.135652) (xy 132.924817 -282.086238) (xy 132.944765 -282.039418)
			(xy 132.971966 -281.996404) (xy 133.005714 -281.95831) (xy 133.045136 -281.926123) (xy 133.08921 -281.900677)
			(xy 133.136796 -281.88263) (xy 133.18666 -281.87245) (xy 133.237512 -281.870401) (xy 133.288033 -281.876535)
			(xy 133.336917 -281.890695) (xy 133.382896 -281.912512) (xy 133.42478 -281.941422) (xy 133.461484 -281.976677)
			(xy 133.492057 -282.017363) (xy 133.515708 -282.062426) (xy 133.531824 -282.1107) (xy 133.539988 -282.160934)
			(xy 133.5405 -282.18638) (xy 133.539988 -282.211826) (xy 133.531824 -282.26206) (xy 133.515708 -282.310334)
			(xy 133.492057 -282.355397) (xy 133.461484 -282.396083) (xy 133.42478 -282.431338) (xy 133.382896 -282.460248)
			(xy 133.336917 -282.482065) (xy 133.288033 -282.496225) (xy 133.237512 -282.502359) (xy 133.18666 -282.50031)
			(xy 133.136796 -282.49013) (xy 133.08921 -282.472083) (xy 133.045136 -282.446637) (xy 133.005714 -282.41445)
			(xy 132.971966 -282.376356) (xy 132.944765 -282.333342) (xy 132.924817 -282.286522) (xy 132.912638 -282.237108)
			(xy 132.908543 -282.18638) (xy 132.590032 -282.18638) (xy 132.589537 -282.210987) (xy 132.581642 -282.259564)
			(xy 132.566058 -282.306245) (xy 132.543187 -282.349822) (xy 132.513622 -282.389166) (xy 132.478129 -282.423258)
			(xy 132.437626 -282.451214) (xy 132.393164 -282.472312) (xy 132.345893 -282.486004) (xy 132.297038 -282.491936)
			(xy 132.247863 -282.489955) (xy 132.199644 -282.480111) (xy 132.153628 -282.462659) (xy 132.111007 -282.438052)
			(xy 132.072886 -282.406927) (xy 132.040251 -282.37009) (xy 132.013948 -282.328494) (xy 131.994657 -282.283218)
			(xy 131.98288 -282.235434) (xy 131.97892 -282.18638) (xy 131.660392 -282.18638) (xy 131.65988 -282.211826)
			(xy 131.651716 -282.26206) (xy 131.6356 -282.310334) (xy 131.611949 -282.355397) (xy 131.581376 -282.396083)
			(xy 131.544672 -282.431338) (xy 131.502788 -282.460248) (xy 131.456809 -282.482065) (xy 131.407925 -282.496225)
			(xy 131.357404 -282.502359) (xy 131.306552 -282.50031) (xy 131.256688 -282.49013) (xy 131.209102 -282.472083)
			(xy 131.165028 -282.446637) (xy 131.125606 -282.41445) (xy 131.091858 -282.376356) (xy 131.064657 -282.333342)
			(xy 131.044709 -282.286522) (xy 131.03253 -282.237108) (xy 131.028435 -282.18638) (xy 130.710178 -282.18638)
			(xy 130.709683 -282.210987) (xy 130.701788 -282.259564) (xy 130.686204 -282.306245) (xy 130.663333 -282.349822)
			(xy 130.633768 -282.389166) (xy 130.598275 -282.423258) (xy 130.557772 -282.451214) (xy 130.51331 -282.472312)
			(xy 130.466039 -282.486004) (xy 130.417184 -282.491936) (xy 130.368009 -282.489955) (xy 130.31979 -282.480111)
			(xy 130.273774 -282.462659) (xy 130.231153 -282.438052) (xy 130.193032 -282.406927) (xy 130.160397 -282.37009)
			(xy 130.134094 -282.328494) (xy 130.114803 -282.283218) (xy 130.103026 -282.235434) (xy 130.099066 -282.18638)
			(xy 129.780538 -282.18638) (xy 129.780026 -282.211826) (xy 129.771862 -282.26206) (xy 129.755746 -282.310334)
			(xy 129.732095 -282.355397) (xy 129.701522 -282.396083) (xy 129.664818 -282.431338) (xy 129.622934 -282.460248)
			(xy 129.576955 -282.482065) (xy 129.528071 -282.496225) (xy 129.47755 -282.502359) (xy 129.426698 -282.50031)
			(xy 129.376834 -282.49013) (xy 129.329248 -282.472083) (xy 129.285174 -282.446637) (xy 129.245752 -282.41445)
			(xy 129.212004 -282.376356) (xy 129.184803 -282.333342) (xy 129.164855 -282.286522) (xy 129.152676 -282.237108)
			(xy 129.148581 -282.18638) (xy 128.840484 -282.18638) (xy 128.839972 -282.211826) (xy 128.831808 -282.26206)
			(xy 128.815692 -282.310334) (xy 128.792041 -282.355397) (xy 128.761468 -282.396083) (xy 128.724764 -282.431338)
			(xy 128.68288 -282.460248) (xy 128.636901 -282.482065) (xy 128.588017 -282.496225) (xy 128.537496 -282.502359)
			(xy 128.486644 -282.50031) (xy 128.43678 -282.49013) (xy 128.389194 -282.472083) (xy 128.34512 -282.446637)
			(xy 128.305698 -282.41445) (xy 128.27195 -282.376356) (xy 128.244749 -282.333342) (xy 128.224801 -282.286522)
			(xy 128.212622 -282.237108) (xy 128.208527 -282.18638) (xy 128.0541 -282.18638) (xy 128.0541 -282.63977)
			(xy 128.054475 -282.648874) (xy 128.060856 -282.665927) (xy 128.066546 -282.673044) (xy 128.072642 -282.680156)
			(xy 128.098042 -282.683712) (xy 128.122895 -282.687634) (xy 128.171012 -282.702329) (xy 128.216189 -282.724471)
			(xy 128.257282 -282.753498) (xy 128.29325 -282.788677) (xy 128.323182 -282.829115) (xy 128.346321 -282.873789)
			(xy 128.36208 -282.921569) (xy 128.370061 -282.971243) (xy 128.370061 -282.996386) (xy 128.688858 -282.996386)
			(xy 128.692818 -282.947332) (xy 128.704595 -282.899548) (xy 128.723886 -282.854272) (xy 128.750189 -282.812676)
			(xy 128.782824 -282.775839) (xy 128.820945 -282.744714) (xy 128.863566 -282.720107) (xy 128.909582 -282.702655)
			(xy 128.957801 -282.692811) (xy 129.006976 -282.69083) (xy 129.055831 -282.696762) (xy 129.103102 -282.710454)
			(xy 129.147564 -282.731552) (xy 129.188067 -282.759508) (xy 129.22356 -282.7936) (xy 129.253125 -282.832944)
			(xy 129.275996 -282.876521) (xy 129.29158 -282.923202) (xy 129.299475 -282.971779) (xy 129.29997 -282.996386)
			(xy 129.618481 -282.996386) (xy 129.622576 -282.945658) (xy 129.634755 -282.896244) (xy 129.654703 -282.849424)
			(xy 129.681904 -282.80641) (xy 129.715652 -282.768316) (xy 129.755074 -282.736129) (xy 129.799148 -282.710683)
			(xy 129.846734 -282.692636) (xy 129.896598 -282.682456) (xy 129.94745 -282.680407) (xy 129.997971 -282.686541)
			(xy 130.046855 -282.700701) (xy 130.092834 -282.722518) (xy 130.134718 -282.751428) (xy 130.171422 -282.786683)
			(xy 130.201995 -282.827369) (xy 130.225646 -282.872432) (xy 130.241762 -282.920706) (xy 130.249926 -282.97094)
			(xy 130.250438 -282.996386) (xy 131.498589 -282.996386) (xy 131.502684 -282.945658) (xy 131.514863 -282.896244)
			(xy 131.534811 -282.849424) (xy 131.562012 -282.80641) (xy 131.59576 -282.768316) (xy 131.635182 -282.736129)
			(xy 131.679256 -282.710683) (xy 131.726842 -282.692636) (xy 131.776706 -282.682456) (xy 131.827558 -282.680407)
			(xy 131.878079 -282.686541) (xy 131.926963 -282.700701) (xy 131.972942 -282.722518) (xy 132.014826 -282.751428)
			(xy 132.05153 -282.786683) (xy 132.082103 -282.827369) (xy 132.105754 -282.872432) (xy 132.12187 -282.920706)
			(xy 132.130034 -282.97094) (xy 132.130546 -282.996386) (xy 132.438643 -282.996386) (xy 132.442738 -282.945658)
			(xy 132.454917 -282.896244) (xy 132.474865 -282.849424) (xy 132.502066 -282.80641) (xy 132.535814 -282.768316)
			(xy 132.575236 -282.736129) (xy 132.61931 -282.710683) (xy 132.666896 -282.692636) (xy 132.71676 -282.682456)
			(xy 132.767612 -282.680407) (xy 132.818133 -282.686541) (xy 132.867017 -282.700701) (xy 132.912996 -282.722518)
			(xy 132.95488 -282.751428) (xy 132.991584 -282.786683) (xy 133.022157 -282.827369) (xy 133.045808 -282.872432)
			(xy 133.061924 -282.920706) (xy 133.070088 -282.97094) (xy 133.0706 -282.996386) (xy 133.070088 -283.021832)
			(xy 133.061924 -283.072066) (xy 133.045808 -283.12034) (xy 133.022157 -283.165403) (xy 132.991584 -283.206089)
			(xy 132.95488 -283.241344) (xy 132.912996 -283.270254) (xy 132.867017 -283.292071) (xy 132.818133 -283.306231)
			(xy 132.767612 -283.312365) (xy 132.71676 -283.310316) (xy 132.666896 -283.300136) (xy 132.61931 -283.282089)
			(xy 132.575236 -283.256643) (xy 132.535814 -283.224456) (xy 132.502066 -283.186362) (xy 132.474865 -283.143348)
			(xy 132.454917 -283.096528) (xy 132.442738 -283.047114) (xy 132.438643 -282.996386) (xy 132.130546 -282.996386)
			(xy 132.130034 -283.021832) (xy 132.12187 -283.072066) (xy 132.105754 -283.12034) (xy 132.082103 -283.165403)
			(xy 132.05153 -283.206089) (xy 132.014826 -283.241344) (xy 131.972942 -283.270254) (xy 131.926963 -283.292071)
			(xy 131.878079 -283.306231) (xy 131.827558 -283.312365) (xy 131.776706 -283.310316) (xy 131.726842 -283.300136)
			(xy 131.679256 -283.282089) (xy 131.635182 -283.256643) (xy 131.59576 -283.224456) (xy 131.562012 -283.186362)
			(xy 131.534811 -283.143348) (xy 131.514863 -283.096528) (xy 131.502684 -283.047114) (xy 131.498589 -282.996386)
			(xy 130.250438 -282.996386) (xy 130.249926 -283.021832) (xy 130.241762 -283.072066) (xy 130.225646 -283.12034)
			(xy 130.201995 -283.165403) (xy 130.171422 -283.206089) (xy 130.134718 -283.241344) (xy 130.092834 -283.270254)
			(xy 130.046855 -283.292071) (xy 129.997971 -283.306231) (xy 129.94745 -283.312365) (xy 129.896598 -283.310316)
			(xy 129.846734 -283.300136) (xy 129.799148 -283.282089) (xy 129.755074 -283.256643) (xy 129.715652 -283.224456)
			(xy 129.681904 -283.186362) (xy 129.654703 -283.143348) (xy 129.634755 -283.096528) (xy 129.622576 -283.047114)
			(xy 129.618481 -282.996386) (xy 129.29997 -282.996386) (xy 129.299475 -283.020993) (xy 129.29158 -283.06957)
			(xy 129.275996 -283.116251) (xy 129.253125 -283.159828) (xy 129.22356 -283.199172) (xy 129.188067 -283.233264)
			(xy 129.147564 -283.26122) (xy 129.103102 -283.282318) (xy 129.055831 -283.29601) (xy 129.006976 -283.301942)
			(xy 128.957801 -283.299961) (xy 128.909582 -283.290117) (xy 128.863566 -283.272665) (xy 128.820945 -283.248058)
			(xy 128.782824 -283.216933) (xy 128.750189 -283.180096) (xy 128.723886 -283.1385) (xy 128.704595 -283.093224)
			(xy 128.692818 -283.04544) (xy 128.688858 -282.996386) (xy 128.370061 -282.996386) (xy 128.370061 -283.021554)
			(xy 128.362081 -283.071228) (xy 128.346322 -283.119007) (xy 128.323184 -283.163682) (xy 128.293252 -283.20412)
			(xy 128.257284 -283.239299) (xy 128.216192 -283.268327) (xy 128.171015 -283.290469) (xy 128.122898 -283.305165)
			(xy 128.098042 -283.30906) (xy 128.091438 -283.310076) (xy 128.082489 -283.311677) (xy 128.066485 -283.320274)
			(xy 128.060196 -283.32684) (xy 128.0541 -283.333952) (xy 128.0541 -283.806392) (xy 128.208527 -283.806392)
			(xy 128.212622 -283.755664) (xy 128.224801 -283.70625) (xy 128.244749 -283.65943) (xy 128.27195 -283.616416)
			(xy 128.305698 -283.578322) (xy 128.34512 -283.546135) (xy 128.389194 -283.520689) (xy 128.43678 -283.502642)
			(xy 128.486644 -283.492462) (xy 128.537496 -283.490413) (xy 128.588017 -283.496547) (xy 128.636901 -283.510707)
			(xy 128.68288 -283.532524) (xy 128.724764 -283.561434) (xy 128.761468 -283.596689) (xy 128.792041 -283.637375)
			(xy 128.815692 -283.682438) (xy 128.831808 -283.730712) (xy 128.839972 -283.780946) (xy 128.840484 -283.806392)
			(xy 129.148581 -283.806392) (xy 129.152676 -283.755664) (xy 129.164855 -283.70625) (xy 129.184803 -283.65943)
			(xy 129.212004 -283.616416) (xy 129.245752 -283.578322) (xy 129.285174 -283.546135) (xy 129.329248 -283.520689)
			(xy 129.376834 -283.502642) (xy 129.426698 -283.492462) (xy 129.47755 -283.490413) (xy 129.528071 -283.496547)
			(xy 129.576955 -283.510707) (xy 129.622934 -283.532524) (xy 129.664818 -283.561434) (xy 129.701522 -283.596689)
			(xy 129.732095 -283.637375) (xy 129.755746 -283.682438) (xy 129.771862 -283.730712) (xy 129.780026 -283.780946)
			(xy 129.780538 -283.806392) (xy 130.099066 -283.806392) (xy 130.103026 -283.757338) (xy 130.114803 -283.709554)
			(xy 130.134094 -283.664278) (xy 130.160397 -283.622682) (xy 130.193032 -283.585845) (xy 130.231153 -283.55472)
			(xy 130.273774 -283.530113) (xy 130.31979 -283.512661) (xy 130.368009 -283.502817) (xy 130.417184 -283.500836)
			(xy 130.466039 -283.506768) (xy 130.51331 -283.52046) (xy 130.557772 -283.541558) (xy 130.598275 -283.569514)
			(xy 130.633768 -283.603606) (xy 130.663333 -283.64295) (xy 130.686204 -283.686527) (xy 130.701788 -283.733208)
			(xy 130.709683 -283.781785) (xy 130.710178 -283.806392) (xy 131.028435 -283.806392) (xy 131.03253 -283.755664)
			(xy 131.044709 -283.70625) (xy 131.064657 -283.65943) (xy 131.091858 -283.616416) (xy 131.125606 -283.578322)
			(xy 131.165028 -283.546135) (xy 131.209102 -283.520689) (xy 131.256688 -283.502642) (xy 131.306552 -283.492462)
			(xy 131.357404 -283.490413) (xy 131.407925 -283.496547) (xy 131.456809 -283.510707) (xy 131.502788 -283.532524)
			(xy 131.544672 -283.561434) (xy 131.581376 -283.596689) (xy 131.611949 -283.637375) (xy 131.6356 -283.682438)
			(xy 131.651716 -283.730712) (xy 131.65988 -283.780946) (xy 131.660392 -283.806392) (xy 131.97892 -283.806392)
			(xy 131.98288 -283.757338) (xy 131.994657 -283.709554) (xy 132.013948 -283.664278) (xy 132.040251 -283.622682)
			(xy 132.072886 -283.585845) (xy 132.111007 -283.55472) (xy 132.153628 -283.530113) (xy 132.199644 -283.512661)
			(xy 132.247863 -283.502817) (xy 132.297038 -283.500836) (xy 132.345893 -283.506768) (xy 132.393164 -283.52046)
			(xy 132.437626 -283.541558) (xy 132.478129 -283.569514) (xy 132.513622 -283.603606) (xy 132.543187 -283.64295)
			(xy 132.566058 -283.686527) (xy 132.581642 -283.733208) (xy 132.589537 -283.781785) (xy 132.590032 -283.806392)
			(xy 132.908543 -283.806392) (xy 132.912638 -283.755664) (xy 132.924817 -283.70625) (xy 132.944765 -283.65943)
			(xy 132.971966 -283.616416) (xy 133.005714 -283.578322) (xy 133.045136 -283.546135) (xy 133.08921 -283.520689)
			(xy 133.136796 -283.502642) (xy 133.18666 -283.492462) (xy 133.237512 -283.490413) (xy 133.288033 -283.496547)
			(xy 133.336917 -283.510707) (xy 133.382896 -283.532524) (xy 133.42478 -283.561434) (xy 133.461484 -283.596689)
			(xy 133.492057 -283.637375) (xy 133.515708 -283.682438) (xy 133.531824 -283.730712) (xy 133.539988 -283.780946)
			(xy 133.5405 -283.806392) (xy 133.539988 -283.831838) (xy 133.531824 -283.882072) (xy 133.515708 -283.930346)
			(xy 133.492057 -283.975409) (xy 133.461484 -284.016095) (xy 133.42478 -284.05135) (xy 133.382896 -284.08026)
			(xy 133.336917 -284.102077) (xy 133.288033 -284.116237) (xy 133.237512 -284.122371) (xy 133.18666 -284.120322)
			(xy 133.136796 -284.110142) (xy 133.08921 -284.092095) (xy 133.045136 -284.066649) (xy 133.005714 -284.034462)
			(xy 132.971966 -283.996368) (xy 132.944765 -283.953354) (xy 132.924817 -283.906534) (xy 132.912638 -283.85712)
			(xy 132.908543 -283.806392) (xy 132.590032 -283.806392) (xy 132.589537 -283.830999) (xy 132.581642 -283.879576)
			(xy 132.566058 -283.926257) (xy 132.543187 -283.969834) (xy 132.513622 -284.009178) (xy 132.478129 -284.04327)
			(xy 132.437626 -284.071226) (xy 132.393164 -284.092324) (xy 132.345893 -284.106016) (xy 132.297038 -284.111948)
			(xy 132.247863 -284.109967) (xy 132.199644 -284.100123) (xy 132.153628 -284.082671) (xy 132.111007 -284.058064)
			(xy 132.072886 -284.026939) (xy 132.040251 -283.990102) (xy 132.013948 -283.948506) (xy 131.994657 -283.90323)
			(xy 131.98288 -283.855446) (xy 131.97892 -283.806392) (xy 131.660392 -283.806392) (xy 131.65988 -283.831838)
			(xy 131.651716 -283.882072) (xy 131.6356 -283.930346) (xy 131.611949 -283.975409) (xy 131.581376 -284.016095)
			(xy 131.544672 -284.05135) (xy 131.502788 -284.08026) (xy 131.456809 -284.102077) (xy 131.407925 -284.116237)
			(xy 131.357404 -284.122371) (xy 131.306552 -284.120322) (xy 131.256688 -284.110142) (xy 131.209102 -284.092095)
			(xy 131.165028 -284.066649) (xy 131.125606 -284.034462) (xy 131.091858 -283.996368) (xy 131.064657 -283.953354)
			(xy 131.044709 -283.906534) (xy 131.03253 -283.85712) (xy 131.028435 -283.806392) (xy 130.710178 -283.806392)
			(xy 130.709683 -283.830999) (xy 130.701788 -283.879576) (xy 130.686204 -283.926257) (xy 130.663333 -283.969834)
			(xy 130.633768 -284.009178) (xy 130.598275 -284.04327) (xy 130.557772 -284.071226) (xy 130.51331 -284.092324)
			(xy 130.466039 -284.106016) (xy 130.417184 -284.111948) (xy 130.368009 -284.109967) (xy 130.31979 -284.100123)
			(xy 130.273774 -284.082671) (xy 130.231153 -284.058064) (xy 130.193032 -284.026939) (xy 130.160397 -283.990102)
			(xy 130.134094 -283.948506) (xy 130.114803 -283.90323) (xy 130.103026 -283.855446) (xy 130.099066 -283.806392)
			(xy 129.780538 -283.806392) (xy 129.780026 -283.831838) (xy 129.771862 -283.882072) (xy 129.755746 -283.930346)
			(xy 129.732095 -283.975409) (xy 129.701522 -284.016095) (xy 129.664818 -284.05135) (xy 129.622934 -284.08026)
			(xy 129.576955 -284.102077) (xy 129.528071 -284.116237) (xy 129.47755 -284.122371) (xy 129.426698 -284.120322)
			(xy 129.376834 -284.110142) (xy 129.329248 -284.092095) (xy 129.285174 -284.066649) (xy 129.245752 -284.034462)
			(xy 129.212004 -283.996368) (xy 129.184803 -283.953354) (xy 129.164855 -283.906534) (xy 129.152676 -283.85712)
			(xy 129.148581 -283.806392) (xy 128.840484 -283.806392) (xy 128.839972 -283.831838) (xy 128.831808 -283.882072)
			(xy 128.815692 -283.930346) (xy 128.792041 -283.975409) (xy 128.761468 -284.016095) (xy 128.724764 -284.05135)
			(xy 128.68288 -284.08026) (xy 128.636901 -284.102077) (xy 128.588017 -284.116237) (xy 128.537496 -284.122371)
			(xy 128.486644 -284.120322) (xy 128.43678 -284.110142) (xy 128.389194 -284.092095) (xy 128.34512 -284.066649)
			(xy 128.305698 -284.034462) (xy 128.27195 -283.996368) (xy 128.244749 -283.953354) (xy 128.224801 -283.906534)
			(xy 128.212622 -283.85712) (xy 128.208527 -283.806392) (xy 128.0541 -283.806392) (xy 128.0541 -284.259782)
			(xy 128.054477 -284.268885) (xy 128.060861 -284.285935) (xy 128.066546 -284.293056) (xy 128.072642 -284.300168)
			(xy 128.098042 -284.303724) (xy 128.122894 -284.307646) (xy 128.171009 -284.322341) (xy 128.216184 -284.344482)
			(xy 128.257275 -284.373509) (xy 128.293242 -284.408686) (xy 128.323173 -284.449123) (xy 128.34631 -284.493795)
			(xy 128.362069 -284.541573) (xy 128.370049 -284.591245) (xy 128.370049 -284.616398) (xy 128.688858 -284.616398)
			(xy 128.692818 -284.567344) (xy 128.704595 -284.51956) (xy 128.723886 -284.474284) (xy 128.750189 -284.432688)
			(xy 128.782824 -284.395851) (xy 128.820945 -284.364726) (xy 128.863566 -284.340119) (xy 128.909582 -284.322667)
			(xy 128.957801 -284.312823) (xy 129.006976 -284.310842) (xy 129.055831 -284.316774) (xy 129.103102 -284.330466)
			(xy 129.147564 -284.351564) (xy 129.188067 -284.37952) (xy 129.22356 -284.413612) (xy 129.253125 -284.452956)
			(xy 129.275996 -284.496533) (xy 129.29158 -284.543214) (xy 129.299475 -284.591791) (xy 129.29997 -284.616398)
			(xy 129.618481 -284.616398) (xy 129.622576 -284.56567) (xy 129.634755 -284.516256) (xy 129.654703 -284.469436)
			(xy 129.681904 -284.426422) (xy 129.715652 -284.388328) (xy 129.755074 -284.356141) (xy 129.799148 -284.330695)
			(xy 129.846734 -284.312648) (xy 129.896598 -284.302468) (xy 129.94745 -284.300419) (xy 129.997971 -284.306553)
			(xy 130.046855 -284.320713) (xy 130.092834 -284.34253) (xy 130.134718 -284.37144) (xy 130.171422 -284.406695)
			(xy 130.201995 -284.447381) (xy 130.225646 -284.492444) (xy 130.241762 -284.540718) (xy 130.249926 -284.590952)
			(xy 130.250438 -284.616398) (xy 130.568966 -284.616398) (xy 130.572926 -284.567344) (xy 130.584703 -284.51956)
			(xy 130.603994 -284.474284) (xy 130.630297 -284.432688) (xy 130.662932 -284.395851) (xy 130.701053 -284.364726)
			(xy 130.743674 -284.340119) (xy 130.78969 -284.322667) (xy 130.837909 -284.312823) (xy 130.887084 -284.310842)
			(xy 130.935939 -284.316774) (xy 130.98321 -284.330466) (xy 131.027672 -284.351564) (xy 131.068175 -284.37952)
			(xy 131.103668 -284.413612) (xy 131.133233 -284.452956) (xy 131.156104 -284.496533) (xy 131.171688 -284.543214)
			(xy 131.179583 -284.591791) (xy 131.180078 -284.616398) (xy 131.498589 -284.616398) (xy 131.502684 -284.56567)
			(xy 131.514863 -284.516256) (xy 131.534811 -284.469436) (xy 131.562012 -284.426422) (xy 131.59576 -284.388328)
			(xy 131.635182 -284.356141) (xy 131.679256 -284.330695) (xy 131.726842 -284.312648) (xy 131.776706 -284.302468)
			(xy 131.827558 -284.300419) (xy 131.878079 -284.306553) (xy 131.926963 -284.320713) (xy 131.972942 -284.34253)
			(xy 132.014826 -284.37144) (xy 132.05153 -284.406695) (xy 132.082103 -284.447381) (xy 132.105754 -284.492444)
			(xy 132.12187 -284.540718) (xy 132.130034 -284.590952) (xy 132.130546 -284.616398) (xy 132.438643 -284.616398)
			(xy 132.442738 -284.56567) (xy 132.454917 -284.516256) (xy 132.474865 -284.469436) (xy 132.502066 -284.426422)
			(xy 132.535814 -284.388328) (xy 132.575236 -284.356141) (xy 132.61931 -284.330695) (xy 132.666896 -284.312648)
			(xy 132.71676 -284.302468) (xy 132.767612 -284.300419) (xy 132.818133 -284.306553) (xy 132.867017 -284.320713)
			(xy 132.912996 -284.34253) (xy 132.95488 -284.37144) (xy 132.991584 -284.406695) (xy 133.022157 -284.447381)
			(xy 133.045808 -284.492444) (xy 133.061924 -284.540718) (xy 133.070088 -284.590952) (xy 133.0706 -284.616398)
			(xy 133.070088 -284.641844) (xy 133.061924 -284.692078) (xy 133.045808 -284.740352) (xy 133.022157 -284.785415)
			(xy 132.991584 -284.826101) (xy 132.95488 -284.861356) (xy 132.912996 -284.890266) (xy 132.867017 -284.912083)
			(xy 132.818133 -284.926243) (xy 132.767612 -284.932377) (xy 132.71676 -284.930328) (xy 132.666896 -284.920148)
			(xy 132.61931 -284.902101) (xy 132.575236 -284.876655) (xy 132.535814 -284.844468) (xy 132.502066 -284.806374)
			(xy 132.474865 -284.76336) (xy 132.454917 -284.71654) (xy 132.442738 -284.667126) (xy 132.438643 -284.616398)
			(xy 132.130546 -284.616398) (xy 132.130034 -284.641844) (xy 132.12187 -284.692078) (xy 132.105754 -284.740352)
			(xy 132.082103 -284.785415) (xy 132.05153 -284.826101) (xy 132.014826 -284.861356) (xy 131.972942 -284.890266)
			(xy 131.926963 -284.912083) (xy 131.878079 -284.926243) (xy 131.827558 -284.932377) (xy 131.776706 -284.930328)
			(xy 131.726842 -284.920148) (xy 131.679256 -284.902101) (xy 131.635182 -284.876655) (xy 131.59576 -284.844468)
			(xy 131.562012 -284.806374) (xy 131.534811 -284.76336) (xy 131.514863 -284.71654) (xy 131.502684 -284.667126)
			(xy 131.498589 -284.616398) (xy 131.180078 -284.616398) (xy 131.179583 -284.641005) (xy 131.171688 -284.689582)
			(xy 131.156104 -284.736263) (xy 131.133233 -284.77984) (xy 131.103668 -284.819184) (xy 131.068175 -284.853276)
			(xy 131.027672 -284.881232) (xy 130.98321 -284.90233) (xy 130.935939 -284.916022) (xy 130.887084 -284.921954)
			(xy 130.837909 -284.919973) (xy 130.78969 -284.910129) (xy 130.743674 -284.892677) (xy 130.701053 -284.86807)
			(xy 130.662932 -284.836945) (xy 130.630297 -284.800108) (xy 130.603994 -284.758512) (xy 130.584703 -284.713236)
			(xy 130.572926 -284.665452) (xy 130.568966 -284.616398) (xy 130.250438 -284.616398) (xy 130.249926 -284.641844)
			(xy 130.241762 -284.692078) (xy 130.225646 -284.740352) (xy 130.201995 -284.785415) (xy 130.171422 -284.826101)
			(xy 130.134718 -284.861356) (xy 130.092834 -284.890266) (xy 130.046855 -284.912083) (xy 129.997971 -284.926243)
			(xy 129.94745 -284.932377) (xy 129.896598 -284.930328) (xy 129.846734 -284.920148) (xy 129.799148 -284.902101)
			(xy 129.755074 -284.876655) (xy 129.715652 -284.844468) (xy 129.681904 -284.806374) (xy 129.654703 -284.76336)
			(xy 129.634755 -284.71654) (xy 129.622576 -284.667126) (xy 129.618481 -284.616398) (xy 129.29997 -284.616398)
			(xy 129.299475 -284.641005) (xy 129.29158 -284.689582) (xy 129.275996 -284.736263) (xy 129.253125 -284.77984)
			(xy 129.22356 -284.819184) (xy 129.188067 -284.853276) (xy 129.147564 -284.881232) (xy 129.103102 -284.90233)
			(xy 129.055831 -284.916022) (xy 129.006976 -284.921954) (xy 128.957801 -284.919973) (xy 128.909582 -284.910129)
			(xy 128.863566 -284.892677) (xy 128.820945 -284.86807) (xy 128.782824 -284.836945) (xy 128.750189 -284.800108)
			(xy 128.723886 -284.758512) (xy 128.704595 -284.713236) (xy 128.692818 -284.665452) (xy 128.688858 -284.616398)
			(xy 128.370049 -284.616398) (xy 128.370049 -284.641554) (xy 128.362069 -284.691227) (xy 128.346311 -284.739004)
			(xy 128.323173 -284.783677) (xy 128.293242 -284.824114) (xy 128.257276 -284.859291) (xy 128.216185 -284.888318)
			(xy 128.17101 -284.910459) (xy 128.122894 -284.925153) (xy 128.098042 -284.929072) (xy 128.091438 -284.930088)
			(xy 128.082489 -284.931689) (xy 128.066487 -284.940288) (xy 128.060196 -284.946852) (xy 128.0541 -284.953964)
			(xy 128.0541 -285.426404) (xy 128.208527 -285.426404) (xy 128.212622 -285.375676) (xy 128.224801 -285.326262)
			(xy 128.244749 -285.279442) (xy 128.27195 -285.236428) (xy 128.305698 -285.198334) (xy 128.34512 -285.166147)
			(xy 128.389194 -285.140701) (xy 128.43678 -285.122654) (xy 128.486644 -285.112474) (xy 128.537496 -285.110425)
			(xy 128.588017 -285.116559) (xy 128.636901 -285.130719) (xy 128.68288 -285.152536) (xy 128.724764 -285.181446)
			(xy 128.761468 -285.216701) (xy 128.792041 -285.257387) (xy 128.815692 -285.30245) (xy 128.831808 -285.350724)
			(xy 128.839972 -285.400958) (xy 128.840484 -285.426404) (xy 129.148581 -285.426404) (xy 129.152676 -285.375676)
			(xy 129.164855 -285.326262) (xy 129.184803 -285.279442) (xy 129.212004 -285.236428) (xy 129.245752 -285.198334)
			(xy 129.285174 -285.166147) (xy 129.329248 -285.140701) (xy 129.376834 -285.122654) (xy 129.426698 -285.112474)
			(xy 129.47755 -285.110425) (xy 129.528071 -285.116559) (xy 129.576955 -285.130719) (xy 129.622934 -285.152536)
			(xy 129.664818 -285.181446) (xy 129.701522 -285.216701) (xy 129.732095 -285.257387) (xy 129.755746 -285.30245)
			(xy 129.771862 -285.350724) (xy 129.780026 -285.400958) (xy 129.780538 -285.426404) (xy 131.028435 -285.426404)
			(xy 131.03253 -285.375676) (xy 131.044709 -285.326262) (xy 131.064657 -285.279442) (xy 131.091858 -285.236428)
			(xy 131.125606 -285.198334) (xy 131.165028 -285.166147) (xy 131.209102 -285.140701) (xy 131.256688 -285.122654)
			(xy 131.306552 -285.112474) (xy 131.357404 -285.110425) (xy 131.407925 -285.116559) (xy 131.456809 -285.130719)
			(xy 131.502788 -285.152536) (xy 131.544672 -285.181446) (xy 131.581376 -285.216701) (xy 131.611949 -285.257387)
			(xy 131.6356 -285.30245) (xy 131.651716 -285.350724) (xy 131.65988 -285.400958) (xy 131.660392 -285.426404)
			(xy 131.97892 -285.426404) (xy 131.98288 -285.37735) (xy 131.994657 -285.329566) (xy 132.013948 -285.28429)
			(xy 132.040251 -285.242694) (xy 132.072886 -285.205857) (xy 132.111007 -285.174732) (xy 132.153628 -285.150125)
			(xy 132.199644 -285.132673) (xy 132.247863 -285.122829) (xy 132.297038 -285.120848) (xy 132.345893 -285.12678)
			(xy 132.393164 -285.140472) (xy 132.437626 -285.16157) (xy 132.478129 -285.189526) (xy 132.513622 -285.223618)
			(xy 132.543187 -285.262962) (xy 132.566058 -285.306539) (xy 132.581642 -285.35322) (xy 132.589537 -285.401797)
			(xy 132.590032 -285.426404) (xy 132.908543 -285.426404) (xy 132.912638 -285.375676) (xy 132.924817 -285.326262)
			(xy 132.944765 -285.279442) (xy 132.971966 -285.236428) (xy 133.005714 -285.198334) (xy 133.045136 -285.166147)
			(xy 133.08921 -285.140701) (xy 133.136796 -285.122654) (xy 133.18666 -285.112474) (xy 133.237512 -285.110425)
			(xy 133.288033 -285.116559) (xy 133.336917 -285.130719) (xy 133.382896 -285.152536) (xy 133.42478 -285.181446)
			(xy 133.461484 -285.216701) (xy 133.492057 -285.257387) (xy 133.515708 -285.30245) (xy 133.531824 -285.350724)
			(xy 133.539988 -285.400958) (xy 133.5405 -285.426404) (xy 133.539988 -285.45185) (xy 133.531824 -285.502084)
			(xy 133.515708 -285.550358) (xy 133.492057 -285.595421) (xy 133.461484 -285.636107) (xy 133.42478 -285.671362)
			(xy 133.382896 -285.700272) (xy 133.336917 -285.722089) (xy 133.288033 -285.736249) (xy 133.237512 -285.742383)
			(xy 133.18666 -285.740334) (xy 133.136796 -285.730154) (xy 133.08921 -285.712107) (xy 133.045136 -285.686661)
			(xy 133.005714 -285.654474) (xy 132.971966 -285.61638) (xy 132.944765 -285.573366) (xy 132.924817 -285.526546)
			(xy 132.912638 -285.477132) (xy 132.908543 -285.426404) (xy 132.590032 -285.426404) (xy 132.589537 -285.451011)
			(xy 132.581642 -285.499588) (xy 132.566058 -285.546269) (xy 132.543187 -285.589846) (xy 132.513622 -285.62919)
			(xy 132.478129 -285.663282) (xy 132.437626 -285.691238) (xy 132.393164 -285.712336) (xy 132.345893 -285.726028)
			(xy 132.297038 -285.73196) (xy 132.247863 -285.729979) (xy 132.199644 -285.720135) (xy 132.153628 -285.702683)
			(xy 132.111007 -285.678076) (xy 132.072886 -285.646951) (xy 132.040251 -285.610114) (xy 132.013948 -285.568518)
			(xy 131.994657 -285.523242) (xy 131.98288 -285.475458) (xy 131.97892 -285.426404) (xy 131.660392 -285.426404)
			(xy 131.65988 -285.45185) (xy 131.651716 -285.502084) (xy 131.6356 -285.550358) (xy 131.611949 -285.595421)
			(xy 131.581376 -285.636107) (xy 131.544672 -285.671362) (xy 131.502788 -285.700272) (xy 131.456809 -285.722089)
			(xy 131.407925 -285.736249) (xy 131.357404 -285.742383) (xy 131.306552 -285.740334) (xy 131.256688 -285.730154)
			(xy 131.209102 -285.712107) (xy 131.165028 -285.686661) (xy 131.125606 -285.654474) (xy 131.091858 -285.61638)
			(xy 131.064657 -285.573366) (xy 131.044709 -285.526546) (xy 131.03253 -285.477132) (xy 131.028435 -285.426404)
			(xy 129.780538 -285.426404) (xy 129.780026 -285.45185) (xy 129.771862 -285.502084) (xy 129.755746 -285.550358)
			(xy 129.732095 -285.595421) (xy 129.701522 -285.636107) (xy 129.664818 -285.671362) (xy 129.622934 -285.700272)
			(xy 129.576955 -285.722089) (xy 129.528071 -285.736249) (xy 129.47755 -285.742383) (xy 129.426698 -285.740334)
			(xy 129.376834 -285.730154) (xy 129.329248 -285.712107) (xy 129.285174 -285.686661) (xy 129.245752 -285.654474)
			(xy 129.212004 -285.61638) (xy 129.184803 -285.573366) (xy 129.164855 -285.526546) (xy 129.152676 -285.477132)
			(xy 129.148581 -285.426404) (xy 128.840484 -285.426404) (xy 128.839972 -285.45185) (xy 128.831808 -285.502084)
			(xy 128.815692 -285.550358) (xy 128.792041 -285.595421) (xy 128.761468 -285.636107) (xy 128.724764 -285.671362)
			(xy 128.68288 -285.700272) (xy 128.636901 -285.722089) (xy 128.588017 -285.736249) (xy 128.537496 -285.742383)
			(xy 128.486644 -285.740334) (xy 128.43678 -285.730154) (xy 128.389194 -285.712107) (xy 128.34512 -285.686661)
			(xy 128.305698 -285.654474) (xy 128.27195 -285.61638) (xy 128.244749 -285.573366) (xy 128.224801 -285.526546)
			(xy 128.212622 -285.477132) (xy 128.208527 -285.426404) (xy 128.0541 -285.426404) (xy 128.0541 -285.879794)
			(xy 128.054479 -285.888896) (xy 128.060866 -285.905944) (xy 128.066546 -285.913068) (xy 128.072642 -285.92018)
			(xy 128.098042 -285.923736) (xy 128.122893 -285.927658) (xy 128.171006 -285.942353) (xy 128.216179 -285.964493)
			(xy 128.257269 -285.993519) (xy 128.293234 -286.028695) (xy 128.323163 -286.06913) (xy 128.3463 -286.113802)
			(xy 128.362058 -286.161577) (xy 128.370038 -286.211248) (xy 128.370038 -286.23641) (xy 128.688858 -286.23641)
			(xy 128.692818 -286.187356) (xy 128.704595 -286.139572) (xy 128.723886 -286.094296) (xy 128.750189 -286.0527)
			(xy 128.782824 -286.015863) (xy 128.820945 -285.984738) (xy 128.863566 -285.960131) (xy 128.909582 -285.942679)
			(xy 128.957801 -285.932835) (xy 129.006976 -285.930854) (xy 129.055831 -285.936786) (xy 129.103102 -285.950478)
			(xy 129.147564 -285.971576) (xy 129.188067 -285.999532) (xy 129.22356 -286.033624) (xy 129.253125 -286.072968)
			(xy 129.275996 -286.116545) (xy 129.29158 -286.163226) (xy 129.299475 -286.211803) (xy 129.29997 -286.23641)
			(xy 129.618481 -286.23641) (xy 129.622576 -286.185682) (xy 129.634755 -286.136268) (xy 129.654703 -286.089448)
			(xy 129.681904 -286.046434) (xy 129.715652 -286.00834) (xy 129.755074 -285.976153) (xy 129.799148 -285.950707)
			(xy 129.846734 -285.93266) (xy 129.896598 -285.92248) (xy 129.94745 -285.920431) (xy 129.997971 -285.926565)
			(xy 130.046855 -285.940725) (xy 130.092834 -285.962542) (xy 130.134718 -285.991452) (xy 130.171422 -286.026707)
			(xy 130.201995 -286.067393) (xy 130.225646 -286.112456) (xy 130.241762 -286.16073) (xy 130.249926 -286.210964)
			(xy 130.250438 -286.23641) (xy 130.568966 -286.23641) (xy 130.572926 -286.187356) (xy 130.584703 -286.139572)
			(xy 130.603994 -286.094296) (xy 130.630297 -286.0527) (xy 130.662932 -286.015863) (xy 130.701053 -285.984738)
			(xy 130.743674 -285.960131) (xy 130.78969 -285.942679) (xy 130.837909 -285.932835) (xy 130.887084 -285.930854)
			(xy 130.935939 -285.936786) (xy 130.98321 -285.950478) (xy 131.027672 -285.971576) (xy 131.068175 -285.999532)
			(xy 131.103668 -286.033624) (xy 131.133233 -286.072968) (xy 131.156104 -286.116545) (xy 131.171688 -286.163226)
			(xy 131.179583 -286.211803) (xy 131.180078 -286.23641) (xy 131.498589 -286.23641) (xy 131.502684 -286.185682)
			(xy 131.514863 -286.136268) (xy 131.534811 -286.089448) (xy 131.562012 -286.046434) (xy 131.59576 -286.00834)
			(xy 131.635182 -285.976153) (xy 131.679256 -285.950707) (xy 131.726842 -285.93266) (xy 131.776706 -285.92248)
			(xy 131.827558 -285.920431) (xy 131.878079 -285.926565) (xy 131.926963 -285.940725) (xy 131.972942 -285.962542)
			(xy 132.014826 -285.991452) (xy 132.05153 -286.026707) (xy 132.082103 -286.067393) (xy 132.105754 -286.112456)
			(xy 132.12187 -286.16073) (xy 132.130034 -286.210964) (xy 132.130546 -286.23641) (xy 132.438643 -286.23641)
			(xy 132.442738 -286.185682) (xy 132.454917 -286.136268) (xy 132.474865 -286.089448) (xy 132.502066 -286.046434)
			(xy 132.535814 -286.00834) (xy 132.575236 -285.976153) (xy 132.61931 -285.950707) (xy 132.666896 -285.93266)
			(xy 132.71676 -285.92248) (xy 132.767612 -285.920431) (xy 132.818133 -285.926565) (xy 132.867017 -285.940725)
			(xy 132.912996 -285.962542) (xy 132.95488 -285.991452) (xy 132.991584 -286.026707) (xy 133.022157 -286.067393)
			(xy 133.045808 -286.112456) (xy 133.061924 -286.16073) (xy 133.070088 -286.210964) (xy 133.0706 -286.23641)
			(xy 133.070088 -286.261856) (xy 133.061924 -286.31209) (xy 133.045808 -286.360364) (xy 133.022157 -286.405427)
			(xy 132.991584 -286.446113) (xy 132.95488 -286.481368) (xy 132.912996 -286.510278) (xy 132.867017 -286.532095)
			(xy 132.818133 -286.546255) (xy 132.767612 -286.552389) (xy 132.71676 -286.55034) (xy 132.666896 -286.54016)
			(xy 132.61931 -286.522113) (xy 132.575236 -286.496667) (xy 132.535814 -286.46448) (xy 132.502066 -286.426386)
			(xy 132.474865 -286.383372) (xy 132.454917 -286.336552) (xy 132.442738 -286.287138) (xy 132.438643 -286.23641)
			(xy 132.130546 -286.23641) (xy 132.130034 -286.261856) (xy 132.12187 -286.31209) (xy 132.105754 -286.360364)
			(xy 132.082103 -286.405427) (xy 132.05153 -286.446113) (xy 132.014826 -286.481368) (xy 131.972942 -286.510278)
			(xy 131.926963 -286.532095) (xy 131.878079 -286.546255) (xy 131.827558 -286.552389) (xy 131.776706 -286.55034)
			(xy 131.726842 -286.54016) (xy 131.679256 -286.522113) (xy 131.635182 -286.496667) (xy 131.59576 -286.46448)
			(xy 131.562012 -286.426386) (xy 131.534811 -286.383372) (xy 131.514863 -286.336552) (xy 131.502684 -286.287138)
			(xy 131.498589 -286.23641) (xy 131.180078 -286.23641) (xy 131.179583 -286.261017) (xy 131.171688 -286.309594)
			(xy 131.156104 -286.356275) (xy 131.133233 -286.399852) (xy 131.103668 -286.439196) (xy 131.068175 -286.473288)
			(xy 131.027672 -286.501244) (xy 130.98321 -286.522342) (xy 130.935939 -286.536034) (xy 130.887084 -286.541966)
			(xy 130.837909 -286.539985) (xy 130.78969 -286.530141) (xy 130.743674 -286.512689) (xy 130.701053 -286.488082)
			(xy 130.662932 -286.456957) (xy 130.630297 -286.42012) (xy 130.603994 -286.378524) (xy 130.584703 -286.333248)
			(xy 130.572926 -286.285464) (xy 130.568966 -286.23641) (xy 130.250438 -286.23641) (xy 130.249926 -286.261856)
			(xy 130.241762 -286.31209) (xy 130.225646 -286.360364) (xy 130.201995 -286.405427) (xy 130.171422 -286.446113)
			(xy 130.134718 -286.481368) (xy 130.092834 -286.510278) (xy 130.046855 -286.532095) (xy 129.997971 -286.546255)
			(xy 129.94745 -286.552389) (xy 129.896598 -286.55034) (xy 129.846734 -286.54016) (xy 129.799148 -286.522113)
			(xy 129.755074 -286.496667) (xy 129.715652 -286.46448) (xy 129.681904 -286.426386) (xy 129.654703 -286.383372)
			(xy 129.634755 -286.336552) (xy 129.622576 -286.287138) (xy 129.618481 -286.23641) (xy 129.29997 -286.23641)
			(xy 129.299475 -286.261017) (xy 129.29158 -286.309594) (xy 129.275996 -286.356275) (xy 129.253125 -286.399852)
			(xy 129.22356 -286.439196) (xy 129.188067 -286.473288) (xy 129.147564 -286.501244) (xy 129.103102 -286.522342)
			(xy 129.055831 -286.536034) (xy 129.006976 -286.541966) (xy 128.957801 -286.539985) (xy 128.909582 -286.530141)
			(xy 128.863566 -286.512689) (xy 128.820945 -286.488082) (xy 128.782824 -286.456957) (xy 128.750189 -286.42012)
			(xy 128.723886 -286.378524) (xy 128.704595 -286.333248) (xy 128.692818 -286.285464) (xy 128.688858 -286.23641)
			(xy 128.370038 -286.23641) (xy 128.370038 -286.261555) (xy 128.362057 -286.311225) (xy 128.346299 -286.359001)
			(xy 128.323162 -286.403672) (xy 128.293232 -286.444107) (xy 128.257267 -286.479283) (xy 128.216177 -286.508308)
			(xy 128.171004 -286.530448) (xy 128.12289 -286.545142) (xy 128.098042 -286.549084) (xy 128.091438 -286.5501)
			(xy 128.082487 -286.551698) (xy 128.066474 -286.560286) (xy 128.060196 -286.566864) (xy 128.0541 -286.573976)
			(xy 128.0541 -287.046162) (xy 128.208527 -287.046162) (xy 128.212622 -286.995434) (xy 128.224801 -286.94602)
			(xy 128.244749 -286.8992) (xy 128.27195 -286.856186) (xy 128.305698 -286.818092) (xy 128.34512 -286.785905)
			(xy 128.389194 -286.760459) (xy 128.43678 -286.742412) (xy 128.486644 -286.732232) (xy 128.537496 -286.730183)
			(xy 128.588017 -286.736317) (xy 128.636901 -286.750477) (xy 128.68288 -286.772294) (xy 128.724764 -286.801204)
			(xy 128.761468 -286.836459) (xy 128.792041 -286.877145) (xy 128.815692 -286.922208) (xy 128.831808 -286.970482)
			(xy 128.839972 -287.020716) (xy 128.840484 -287.046162) (xy 129.148581 -287.046162) (xy 129.152676 -286.995434)
			(xy 129.164855 -286.94602) (xy 129.184803 -286.8992) (xy 129.212004 -286.856186) (xy 129.245752 -286.818092)
			(xy 129.285174 -286.785905) (xy 129.329248 -286.760459) (xy 129.376834 -286.742412) (xy 129.426698 -286.732232)
			(xy 129.47755 -286.730183) (xy 129.528071 -286.736317) (xy 129.576955 -286.750477) (xy 129.622934 -286.772294)
			(xy 129.664818 -286.801204) (xy 129.701522 -286.836459) (xy 129.732095 -286.877145) (xy 129.755746 -286.922208)
			(xy 129.771862 -286.970482) (xy 129.780026 -287.020716) (xy 129.780538 -287.046162) (xy 129.780533 -287.046416)
			(xy 130.099066 -287.046416) (xy 130.103026 -286.997362) (xy 130.114803 -286.949578) (xy 130.134094 -286.904302)
			(xy 130.160397 -286.862706) (xy 130.193032 -286.825869) (xy 130.231153 -286.794744) (xy 130.273774 -286.770137)
			(xy 130.31979 -286.752685) (xy 130.368009 -286.742841) (xy 130.417184 -286.74086) (xy 130.466039 -286.746792)
			(xy 130.51331 -286.760484) (xy 130.557772 -286.781582) (xy 130.598275 -286.809538) (xy 130.633768 -286.84363)
			(xy 130.663333 -286.882974) (xy 130.686204 -286.926551) (xy 130.701788 -286.973232) (xy 130.709683 -287.021809)
			(xy 130.710173 -287.046162) (xy 131.028435 -287.046162) (xy 131.03253 -286.995434) (xy 131.044709 -286.94602)
			(xy 131.064657 -286.8992) (xy 131.091858 -286.856186) (xy 131.125606 -286.818092) (xy 131.165028 -286.785905)
			(xy 131.209102 -286.760459) (xy 131.256688 -286.742412) (xy 131.306552 -286.732232) (xy 131.357404 -286.730183)
			(xy 131.407925 -286.736317) (xy 131.456809 -286.750477) (xy 131.502788 -286.772294) (xy 131.544672 -286.801204)
			(xy 131.581376 -286.836459) (xy 131.611949 -286.877145) (xy 131.6356 -286.922208) (xy 131.651716 -286.970482)
			(xy 131.65988 -287.020716) (xy 131.660392 -287.046162) (xy 131.97892 -287.046162) (xy 131.98288 -286.997108)
			(xy 131.994657 -286.949324) (xy 132.013948 -286.904048) (xy 132.040251 -286.862452) (xy 132.072886 -286.825615)
			(xy 132.111007 -286.79449) (xy 132.153628 -286.769883) (xy 132.199644 -286.752431) (xy 132.247863 -286.742587)
			(xy 132.297038 -286.740606) (xy 132.345893 -286.746538) (xy 132.393164 -286.76023) (xy 132.437626 -286.781328)
			(xy 132.478129 -286.809284) (xy 132.513622 -286.843376) (xy 132.543187 -286.88272) (xy 132.566058 -286.926297)
			(xy 132.581642 -286.972978) (xy 132.589537 -287.021555) (xy 132.590032 -287.046162) (xy 132.908543 -287.046162)
			(xy 132.912638 -286.995434) (xy 132.924817 -286.94602) (xy 132.944765 -286.8992) (xy 132.971966 -286.856186)
			(xy 133.005714 -286.818092) (xy 133.045136 -286.785905) (xy 133.08921 -286.760459) (xy 133.136796 -286.742412)
			(xy 133.18666 -286.732232) (xy 133.237512 -286.730183) (xy 133.288033 -286.736317) (xy 133.336917 -286.750477)
			(xy 133.382896 -286.772294) (xy 133.42478 -286.801204) (xy 133.461484 -286.836459) (xy 133.492057 -286.877145)
			(xy 133.515708 -286.922208) (xy 133.531824 -286.970482) (xy 133.539988 -287.020716) (xy 133.5405 -287.046162)
			(xy 133.539988 -287.071608) (xy 133.531824 -287.121842) (xy 133.515708 -287.170116) (xy 133.492057 -287.215179)
			(xy 133.461484 -287.255865) (xy 133.42478 -287.29112) (xy 133.382896 -287.32003) (xy 133.336917 -287.341847)
			(xy 133.288033 -287.356007) (xy 133.237512 -287.362141) (xy 133.18666 -287.360092) (xy 133.136796 -287.349912)
			(xy 133.08921 -287.331865) (xy 133.045136 -287.306419) (xy 133.005714 -287.274232) (xy 132.971966 -287.236138)
			(xy 132.944765 -287.193124) (xy 132.924817 -287.146304) (xy 132.912638 -287.09689) (xy 132.908543 -287.046162)
			(xy 132.590032 -287.046162) (xy 132.589537 -287.070769) (xy 132.581642 -287.119346) (xy 132.566058 -287.166027)
			(xy 132.543187 -287.209604) (xy 132.513622 -287.248948) (xy 132.478129 -287.28304) (xy 132.437626 -287.310996)
			(xy 132.393164 -287.332094) (xy 132.345893 -287.345786) (xy 132.297038 -287.351718) (xy 132.247863 -287.349737)
			(xy 132.199644 -287.339893) (xy 132.153628 -287.322441) (xy 132.111007 -287.297834) (xy 132.072886 -287.266709)
			(xy 132.040251 -287.229872) (xy 132.013948 -287.188276) (xy 131.994657 -287.143) (xy 131.98288 -287.095216)
			(xy 131.97892 -287.046162) (xy 131.660392 -287.046162) (xy 131.65988 -287.071608) (xy 131.651716 -287.121842)
			(xy 131.6356 -287.170116) (xy 131.611949 -287.215179) (xy 131.581376 -287.255865) (xy 131.544672 -287.29112)
			(xy 131.502788 -287.32003) (xy 131.456809 -287.341847) (xy 131.407925 -287.356007) (xy 131.357404 -287.362141)
			(xy 131.306552 -287.360092) (xy 131.256688 -287.349912) (xy 131.209102 -287.331865) (xy 131.165028 -287.306419)
			(xy 131.125606 -287.274232) (xy 131.091858 -287.236138) (xy 131.064657 -287.193124) (xy 131.044709 -287.146304)
			(xy 131.03253 -287.09689) (xy 131.028435 -287.046162) (xy 130.710173 -287.046162) (xy 130.710178 -287.046416)
			(xy 130.709683 -287.071023) (xy 130.701788 -287.1196) (xy 130.686204 -287.166281) (xy 130.663333 -287.209858)
			(xy 130.633768 -287.249202) (xy 130.598275 -287.283294) (xy 130.557772 -287.31125) (xy 130.51331 -287.332348)
			(xy 130.466039 -287.34604) (xy 130.417184 -287.351972) (xy 130.368009 -287.349991) (xy 130.31979 -287.340147)
			(xy 130.273774 -287.322695) (xy 130.231153 -287.298088) (xy 130.193032 -287.266963) (xy 130.160397 -287.230126)
			(xy 130.134094 -287.18853) (xy 130.114803 -287.143254) (xy 130.103026 -287.09547) (xy 130.099066 -287.046416)
			(xy 129.780533 -287.046416) (xy 129.780026 -287.071608) (xy 129.771862 -287.121842) (xy 129.755746 -287.170116)
			(xy 129.732095 -287.215179) (xy 129.701522 -287.255865) (xy 129.664818 -287.29112) (xy 129.622934 -287.32003)
			(xy 129.576955 -287.341847) (xy 129.528071 -287.356007) (xy 129.47755 -287.362141) (xy 129.426698 -287.360092)
			(xy 129.376834 -287.349912) (xy 129.329248 -287.331865) (xy 129.285174 -287.306419) (xy 129.245752 -287.274232)
			(xy 129.212004 -287.236138) (xy 129.184803 -287.193124) (xy 129.164855 -287.146304) (xy 129.152676 -287.09689)
			(xy 129.148581 -287.046162) (xy 128.840484 -287.046162) (xy 128.839972 -287.071608) (xy 128.831808 -287.121842)
			(xy 128.815692 -287.170116) (xy 128.792041 -287.215179) (xy 128.761468 -287.255865) (xy 128.724764 -287.29112)
			(xy 128.68288 -287.32003) (xy 128.636901 -287.341847) (xy 128.588017 -287.356007) (xy 128.537496 -287.362141)
			(xy 128.486644 -287.360092) (xy 128.43678 -287.349912) (xy 128.389194 -287.331865) (xy 128.34512 -287.306419)
			(xy 128.305698 -287.274232) (xy 128.27195 -287.236138) (xy 128.244749 -287.193124) (xy 128.224801 -287.146304)
			(xy 128.212622 -287.09689) (xy 128.208527 -287.046162) (xy 128.0541 -287.046162) (xy 128.0541 -287.499806)
			(xy 128.054481 -287.508908) (xy 128.060871 -287.525952) (xy 128.066546 -287.53308) (xy 128.072642 -287.540192)
			(xy 128.098042 -287.543748) (xy 128.122892 -287.54767) (xy 128.171003 -287.562364) (xy 128.216175 -287.584504)
			(xy 128.257262 -287.613529) (xy 128.293226 -287.648704) (xy 128.323154 -287.689138) (xy 128.34629 -287.733808)
			(xy 128.362047 -287.781582) (xy 128.370026 -287.83125) (xy 128.370026 -287.856422) (xy 128.688858 -287.856422)
			(xy 128.692818 -287.807368) (xy 128.704595 -287.759584) (xy 128.723886 -287.714308) (xy 128.750189 -287.672712)
			(xy 128.782824 -287.635875) (xy 128.820945 -287.60475) (xy 128.863566 -287.580143) (xy 128.909582 -287.562691)
			(xy 128.957801 -287.552847) (xy 129.006976 -287.550866) (xy 129.055831 -287.556798) (xy 129.103102 -287.57049)
			(xy 129.147564 -287.591588) (xy 129.188067 -287.619544) (xy 129.22356 -287.653636) (xy 129.253125 -287.69298)
			(xy 129.275996 -287.736557) (xy 129.29158 -287.783238) (xy 129.299475 -287.831815) (xy 129.29997 -287.856422)
			(xy 129.618481 -287.856422) (xy 129.622576 -287.805694) (xy 129.634755 -287.75628) (xy 129.654703 -287.70946)
			(xy 129.681904 -287.666446) (xy 129.715652 -287.628352) (xy 129.755074 -287.596165) (xy 129.799148 -287.570719)
			(xy 129.846734 -287.552672) (xy 129.896598 -287.542492) (xy 129.94745 -287.540443) (xy 129.997971 -287.546577)
			(xy 130.046855 -287.560737) (xy 130.092834 -287.582554) (xy 130.134718 -287.611464) (xy 130.171422 -287.646719)
			(xy 130.201995 -287.687405) (xy 130.225646 -287.732468) (xy 130.241762 -287.780742) (xy 130.249926 -287.830976)
			(xy 130.250438 -287.856422) (xy 131.498589 -287.856422) (xy 131.502684 -287.805694) (xy 131.514863 -287.75628)
			(xy 131.534811 -287.70946) (xy 131.562012 -287.666446) (xy 131.59576 -287.628352) (xy 131.635182 -287.596165)
			(xy 131.679256 -287.570719) (xy 131.726842 -287.552672) (xy 131.776706 -287.542492) (xy 131.827558 -287.540443)
			(xy 131.878079 -287.546577) (xy 131.926963 -287.560737) (xy 131.972942 -287.582554) (xy 132.014826 -287.611464)
			(xy 132.05153 -287.646719) (xy 132.082103 -287.687405) (xy 132.105754 -287.732468) (xy 132.12187 -287.780742)
			(xy 132.130034 -287.830976) (xy 132.130546 -287.856422) (xy 132.438643 -287.856422) (xy 132.442738 -287.805694)
			(xy 132.454917 -287.75628) (xy 132.474865 -287.70946) (xy 132.502066 -287.666446) (xy 132.535814 -287.628352)
			(xy 132.575236 -287.596165) (xy 132.61931 -287.570719) (xy 132.666896 -287.552672) (xy 132.71676 -287.542492)
			(xy 132.767612 -287.540443) (xy 132.818133 -287.546577) (xy 132.867017 -287.560737) (xy 132.912996 -287.582554)
			(xy 132.95488 -287.611464) (xy 132.991584 -287.646719) (xy 133.022157 -287.687405) (xy 133.045808 -287.732468)
			(xy 133.061924 -287.780742) (xy 133.070088 -287.830976) (xy 133.0706 -287.856422) (xy 133.070088 -287.881868)
			(xy 133.061924 -287.932102) (xy 133.045808 -287.980376) (xy 133.022157 -288.025439) (xy 132.991584 -288.066125)
			(xy 132.95488 -288.10138) (xy 132.912996 -288.13029) (xy 132.867017 -288.152107) (xy 132.818133 -288.166267)
			(xy 132.767612 -288.172401) (xy 132.71676 -288.170352) (xy 132.666896 -288.160172) (xy 132.61931 -288.142125)
			(xy 132.575236 -288.116679) (xy 132.535814 -288.084492) (xy 132.502066 -288.046398) (xy 132.474865 -288.003384)
			(xy 132.454917 -287.956564) (xy 132.442738 -287.90715) (xy 132.438643 -287.856422) (xy 132.130546 -287.856422)
			(xy 132.130034 -287.881868) (xy 132.12187 -287.932102) (xy 132.105754 -287.980376) (xy 132.082103 -288.025439)
			(xy 132.05153 -288.066125) (xy 132.014826 -288.10138) (xy 131.972942 -288.13029) (xy 131.926963 -288.152107)
			(xy 131.878079 -288.166267) (xy 131.827558 -288.172401) (xy 131.776706 -288.170352) (xy 131.726842 -288.160172)
			(xy 131.679256 -288.142125) (xy 131.635182 -288.116679) (xy 131.59576 -288.084492) (xy 131.562012 -288.046398)
			(xy 131.534811 -288.003384) (xy 131.514863 -287.956564) (xy 131.502684 -287.90715) (xy 131.498589 -287.856422)
			(xy 130.250438 -287.856422) (xy 130.249926 -287.881868) (xy 130.241762 -287.932102) (xy 130.225646 -287.980376)
			(xy 130.201995 -288.025439) (xy 130.171422 -288.066125) (xy 130.134718 -288.10138) (xy 130.092834 -288.13029)
			(xy 130.046855 -288.152107) (xy 129.997971 -288.166267) (xy 129.94745 -288.172401) (xy 129.896598 -288.170352)
			(xy 129.846734 -288.160172) (xy 129.799148 -288.142125) (xy 129.755074 -288.116679) (xy 129.715652 -288.084492)
			(xy 129.681904 -288.046398) (xy 129.654703 -288.003384) (xy 129.634755 -287.956564) (xy 129.622576 -287.90715)
			(xy 129.618481 -287.856422) (xy 129.29997 -287.856422) (xy 129.299475 -287.881029) (xy 129.29158 -287.929606)
			(xy 129.275996 -287.976287) (xy 129.253125 -288.019864) (xy 129.22356 -288.059208) (xy 129.188067 -288.0933)
			(xy 129.147564 -288.121256) (xy 129.103102 -288.142354) (xy 129.055831 -288.156046) (xy 129.006976 -288.161978)
			(xy 128.957801 -288.159997) (xy 128.909582 -288.150153) (xy 128.863566 -288.132701) (xy 128.820945 -288.108094)
			(xy 128.782824 -288.076969) (xy 128.750189 -288.040132) (xy 128.723886 -287.998536) (xy 128.704595 -287.95326)
			(xy 128.692818 -287.905476) (xy 128.688858 -287.856422) (xy 128.370026 -287.856422) (xy 128.370026 -287.881556)
			(xy 128.362045 -287.931224) (xy 128.346288 -287.978998) (xy 128.323151 -288.023667) (xy 128.293222 -288.064101)
			(xy 128.257258 -288.099275) (xy 128.21617 -288.128299) (xy 128.170998 -288.150438) (xy 128.122886 -288.165131)
			(xy 128.098042 -288.169096) (xy 128.091438 -288.170112) (xy 128.082487 -288.17171) (xy 128.066476 -288.1803)
			(xy 128.060196 -288.186876) (xy 128.0541 -288.193988) (xy 128.0541 -288.666174) (xy 128.208527 -288.666174)
			(xy 128.212622 -288.615446) (xy 128.224801 -288.566032) (xy 128.244749 -288.519212) (xy 128.27195 -288.476198)
			(xy 128.305698 -288.438104) (xy 128.34512 -288.405917) (xy 128.389194 -288.380471) (xy 128.43678 -288.362424)
			(xy 128.486644 -288.352244) (xy 128.537496 -288.350195) (xy 128.588017 -288.356329) (xy 128.636901 -288.370489)
			(xy 128.68288 -288.392306) (xy 128.724764 -288.421216) (xy 128.761468 -288.456471) (xy 128.792041 -288.497157)
			(xy 128.815692 -288.54222) (xy 128.831808 -288.590494) (xy 128.839972 -288.640728) (xy 128.840484 -288.666174)
			(xy 129.148581 -288.666174) (xy 129.152676 -288.615446) (xy 129.164855 -288.566032) (xy 129.184803 -288.519212)
			(xy 129.212004 -288.476198) (xy 129.245752 -288.438104) (xy 129.285174 -288.405917) (xy 129.329248 -288.380471)
			(xy 129.376834 -288.362424) (xy 129.426698 -288.352244) (xy 129.47755 -288.350195) (xy 129.528071 -288.356329)
			(xy 129.576955 -288.370489) (xy 129.622934 -288.392306) (xy 129.664818 -288.421216) (xy 129.701522 -288.456471)
			(xy 129.732095 -288.497157) (xy 129.755746 -288.54222) (xy 129.771862 -288.590494) (xy 129.780026 -288.640728)
			(xy 129.780538 -288.666174) (xy 130.099066 -288.666174) (xy 130.103026 -288.61712) (xy 130.114803 -288.569336)
			(xy 130.134094 -288.52406) (xy 130.160397 -288.482464) (xy 130.193032 -288.445627) (xy 130.231153 -288.414502)
			(xy 130.273774 -288.389895) (xy 130.31979 -288.372443) (xy 130.368009 -288.362599) (xy 130.417184 -288.360618)
			(xy 130.466039 -288.36655) (xy 130.51331 -288.380242) (xy 130.557772 -288.40134) (xy 130.598275 -288.429296)
			(xy 130.633768 -288.463388) (xy 130.663333 -288.502732) (xy 130.686204 -288.546309) (xy 130.701788 -288.59299)
			(xy 130.709683 -288.641567) (xy 130.710178 -288.666174) (xy 131.028435 -288.666174) (xy 131.03253 -288.615446)
			(xy 131.044709 -288.566032) (xy 131.064657 -288.519212) (xy 131.091858 -288.476198) (xy 131.125606 -288.438104)
			(xy 131.165028 -288.405917) (xy 131.209102 -288.380471) (xy 131.256688 -288.362424) (xy 131.306552 -288.352244)
			(xy 131.357404 -288.350195) (xy 131.407925 -288.356329) (xy 131.456809 -288.370489) (xy 131.502788 -288.392306)
			(xy 131.544672 -288.421216) (xy 131.581376 -288.456471) (xy 131.611949 -288.497157) (xy 131.6356 -288.54222)
			(xy 131.651716 -288.590494) (xy 131.65988 -288.640728) (xy 131.660392 -288.666174) (xy 131.97892 -288.666174)
			(xy 131.98288 -288.61712) (xy 131.994657 -288.569336) (xy 132.013948 -288.52406) (xy 132.040251 -288.482464)
			(xy 132.072886 -288.445627) (xy 132.111007 -288.414502) (xy 132.153628 -288.389895) (xy 132.199644 -288.372443)
			(xy 132.247863 -288.362599) (xy 132.297038 -288.360618) (xy 132.345893 -288.36655) (xy 132.393164 -288.380242)
			(xy 132.437626 -288.40134) (xy 132.478129 -288.429296) (xy 132.513622 -288.463388) (xy 132.543187 -288.502732)
			(xy 132.566058 -288.546309) (xy 132.581642 -288.59299) (xy 132.589537 -288.641567) (xy 132.590032 -288.666174)
			(xy 132.908543 -288.666174) (xy 132.912638 -288.615446) (xy 132.924817 -288.566032) (xy 132.944765 -288.519212)
			(xy 132.971966 -288.476198) (xy 133.005714 -288.438104) (xy 133.045136 -288.405917) (xy 133.08921 -288.380471)
			(xy 133.136796 -288.362424) (xy 133.18666 -288.352244) (xy 133.237512 -288.350195) (xy 133.288033 -288.356329)
			(xy 133.336917 -288.370489) (xy 133.382896 -288.392306) (xy 133.42478 -288.421216) (xy 133.461484 -288.456471)
			(xy 133.492057 -288.497157) (xy 133.515708 -288.54222) (xy 133.531824 -288.590494) (xy 133.539988 -288.640728)
			(xy 133.5405 -288.666174) (xy 133.539988 -288.69162) (xy 133.531824 -288.741854) (xy 133.515708 -288.790128)
			(xy 133.492057 -288.835191) (xy 133.461484 -288.875877) (xy 133.42478 -288.911132) (xy 133.382896 -288.940042)
			(xy 133.336917 -288.961859) (xy 133.288033 -288.976019) (xy 133.237512 -288.982153) (xy 133.18666 -288.980104)
			(xy 133.136796 -288.969924) (xy 133.08921 -288.951877) (xy 133.045136 -288.926431) (xy 133.005714 -288.894244)
			(xy 132.971966 -288.85615) (xy 132.944765 -288.813136) (xy 132.924817 -288.766316) (xy 132.912638 -288.716902)
			(xy 132.908543 -288.666174) (xy 132.590032 -288.666174) (xy 132.589537 -288.690781) (xy 132.581642 -288.739358)
			(xy 132.566058 -288.786039) (xy 132.543187 -288.829616) (xy 132.513622 -288.86896) (xy 132.478129 -288.903052)
			(xy 132.437626 -288.931008) (xy 132.393164 -288.952106) (xy 132.345893 -288.965798) (xy 132.297038 -288.97173)
			(xy 132.247863 -288.969749) (xy 132.199644 -288.959905) (xy 132.153628 -288.942453) (xy 132.111007 -288.917846)
			(xy 132.072886 -288.886721) (xy 132.040251 -288.849884) (xy 132.013948 -288.808288) (xy 131.994657 -288.763012)
			(xy 131.98288 -288.715228) (xy 131.97892 -288.666174) (xy 131.660392 -288.666174) (xy 131.65988 -288.69162)
			(xy 131.651716 -288.741854) (xy 131.6356 -288.790128) (xy 131.611949 -288.835191) (xy 131.581376 -288.875877)
			(xy 131.544672 -288.911132) (xy 131.502788 -288.940042) (xy 131.456809 -288.961859) (xy 131.407925 -288.976019)
			(xy 131.357404 -288.982153) (xy 131.306552 -288.980104) (xy 131.256688 -288.969924) (xy 131.209102 -288.951877)
			(xy 131.165028 -288.926431) (xy 131.125606 -288.894244) (xy 131.091858 -288.85615) (xy 131.064657 -288.813136)
			(xy 131.044709 -288.766316) (xy 131.03253 -288.716902) (xy 131.028435 -288.666174) (xy 130.710178 -288.666174)
			(xy 130.709683 -288.690781) (xy 130.701788 -288.739358) (xy 130.686204 -288.786039) (xy 130.663333 -288.829616)
			(xy 130.633768 -288.86896) (xy 130.598275 -288.903052) (xy 130.557772 -288.931008) (xy 130.51331 -288.952106)
			(xy 130.466039 -288.965798) (xy 130.417184 -288.97173) (xy 130.368009 -288.969749) (xy 130.31979 -288.959905)
			(xy 130.273774 -288.942453) (xy 130.231153 -288.917846) (xy 130.193032 -288.886721) (xy 130.160397 -288.849884)
			(xy 130.134094 -288.808288) (xy 130.114803 -288.763012) (xy 130.103026 -288.715228) (xy 130.099066 -288.666174)
			(xy 129.780538 -288.666174) (xy 129.780026 -288.69162) (xy 129.771862 -288.741854) (xy 129.755746 -288.790128)
			(xy 129.732095 -288.835191) (xy 129.701522 -288.875877) (xy 129.664818 -288.911132) (xy 129.622934 -288.940042)
			(xy 129.576955 -288.961859) (xy 129.528071 -288.976019) (xy 129.47755 -288.982153) (xy 129.426698 -288.980104)
			(xy 129.376834 -288.969924) (xy 129.329248 -288.951877) (xy 129.285174 -288.926431) (xy 129.245752 -288.894244)
			(xy 129.212004 -288.85615) (xy 129.184803 -288.813136) (xy 129.164855 -288.766316) (xy 129.152676 -288.716902)
			(xy 129.148581 -288.666174) (xy 128.840484 -288.666174) (xy 128.839972 -288.69162) (xy 128.831808 -288.741854)
			(xy 128.815692 -288.790128) (xy 128.792041 -288.835191) (xy 128.761468 -288.875877) (xy 128.724764 -288.911132)
			(xy 128.68288 -288.940042) (xy 128.636901 -288.961859) (xy 128.588017 -288.976019) (xy 128.537496 -288.982153)
			(xy 128.486644 -288.980104) (xy 128.43678 -288.969924) (xy 128.389194 -288.951877) (xy 128.34512 -288.926431)
			(xy 128.305698 -288.894244) (xy 128.27195 -288.85615) (xy 128.244749 -288.813136) (xy 128.224801 -288.766316)
			(xy 128.212622 -288.716902) (xy 128.208527 -288.666174) (xy 128.0541 -288.666174) (xy 128.0541 -289.119564)
			(xy 128.054474 -289.128668) (xy 128.060854 -289.145723) (xy 128.066546 -289.152838) (xy 128.072642 -289.15995)
			(xy 128.098042 -289.163506) (xy 128.122895 -289.167428) (xy 128.171013 -289.182124) (xy 128.216191 -289.204265)
			(xy 128.257285 -289.233293) (xy 128.293253 -289.268472) (xy 128.323187 -289.308911) (xy 128.346326 -289.353586)
			(xy 128.362086 -289.401366) (xy 128.370067 -289.451041) (xy 128.370067 -289.47618) (xy 128.688858 -289.47618)
			(xy 128.692818 -289.427126) (xy 128.704595 -289.379342) (xy 128.723886 -289.334066) (xy 128.750189 -289.29247)
			(xy 128.782824 -289.255633) (xy 128.820945 -289.224508) (xy 128.863566 -289.199901) (xy 128.909582 -289.182449)
			(xy 128.957801 -289.172605) (xy 129.006976 -289.170624) (xy 129.055831 -289.176556) (xy 129.103102 -289.190248)
			(xy 129.147564 -289.211346) (xy 129.188067 -289.239302) (xy 129.22356 -289.273394) (xy 129.253125 -289.312738)
			(xy 129.275996 -289.356315) (xy 129.29158 -289.402996) (xy 129.299475 -289.451573) (xy 129.29997 -289.47618)
			(xy 129.618481 -289.47618) (xy 129.622576 -289.425452) (xy 129.634755 -289.376038) (xy 129.654703 -289.329218)
			(xy 129.681904 -289.286204) (xy 129.715652 -289.24811) (xy 129.755074 -289.215923) (xy 129.799148 -289.190477)
			(xy 129.846734 -289.17243) (xy 129.896598 -289.16225) (xy 129.94745 -289.160201) (xy 129.997971 -289.166335)
			(xy 130.046855 -289.180495) (xy 130.092834 -289.202312) (xy 130.134718 -289.231222) (xy 130.171422 -289.266477)
			(xy 130.201995 -289.307163) (xy 130.225646 -289.352226) (xy 130.241762 -289.4005) (xy 130.249926 -289.450734)
			(xy 130.250438 -289.47618) (xy 130.568966 -289.47618) (xy 130.572926 -289.427126) (xy 130.584703 -289.379342)
			(xy 130.603994 -289.334066) (xy 130.630297 -289.29247) (xy 130.662932 -289.255633) (xy 130.701053 -289.224508)
			(xy 130.743674 -289.199901) (xy 130.78969 -289.182449) (xy 130.837909 -289.172605) (xy 130.887084 -289.170624)
			(xy 130.935939 -289.176556) (xy 130.98321 -289.190248) (xy 131.027672 -289.211346) (xy 131.068175 -289.239302)
			(xy 131.103668 -289.273394) (xy 131.133233 -289.312738) (xy 131.156104 -289.356315) (xy 131.171688 -289.402996)
			(xy 131.179583 -289.451573) (xy 131.180078 -289.47618) (xy 131.498589 -289.47618) (xy 131.502684 -289.425452)
			(xy 131.514863 -289.376038) (xy 131.534811 -289.329218) (xy 131.562012 -289.286204) (xy 131.59576 -289.24811)
			(xy 131.635182 -289.215923) (xy 131.679256 -289.190477) (xy 131.726842 -289.17243) (xy 131.776706 -289.16225)
			(xy 131.827558 -289.160201) (xy 131.878079 -289.166335) (xy 131.926963 -289.180495) (xy 131.972942 -289.202312)
			(xy 132.014826 -289.231222) (xy 132.05153 -289.266477) (xy 132.082103 -289.307163) (xy 132.105754 -289.352226)
			(xy 132.12187 -289.4005) (xy 132.130034 -289.450734) (xy 132.130546 -289.47618) (xy 132.438643 -289.47618)
			(xy 132.442738 -289.425452) (xy 132.454917 -289.376038) (xy 132.474865 -289.329218) (xy 132.502066 -289.286204)
			(xy 132.535814 -289.24811) (xy 132.575236 -289.215923) (xy 132.61931 -289.190477) (xy 132.666896 -289.17243)
			(xy 132.71676 -289.16225) (xy 132.767612 -289.160201) (xy 132.818133 -289.166335) (xy 132.867017 -289.180495)
			(xy 132.912996 -289.202312) (xy 132.95488 -289.231222) (xy 132.991584 -289.266477) (xy 133.022157 -289.307163)
			(xy 133.045808 -289.352226) (xy 133.061924 -289.4005) (xy 133.070088 -289.450734) (xy 133.0706 -289.47618)
			(xy 133.070088 -289.501626) (xy 133.061924 -289.55186) (xy 133.045808 -289.600134) (xy 133.022157 -289.645197)
			(xy 132.991584 -289.685883) (xy 132.95488 -289.721138) (xy 132.912996 -289.750048) (xy 132.867017 -289.771865)
			(xy 132.818133 -289.786025) (xy 132.767612 -289.792159) (xy 132.71676 -289.79011) (xy 132.666896 -289.77993)
			(xy 132.61931 -289.761883) (xy 132.575236 -289.736437) (xy 132.535814 -289.70425) (xy 132.502066 -289.666156)
			(xy 132.474865 -289.623142) (xy 132.454917 -289.576322) (xy 132.442738 -289.526908) (xy 132.438643 -289.47618)
			(xy 132.130546 -289.47618) (xy 132.130034 -289.501626) (xy 132.12187 -289.55186) (xy 132.105754 -289.600134)
			(xy 132.082103 -289.645197) (xy 132.05153 -289.685883) (xy 132.014826 -289.721138) (xy 131.972942 -289.750048)
			(xy 131.926963 -289.771865) (xy 131.878079 -289.786025) (xy 131.827558 -289.792159) (xy 131.776706 -289.79011)
			(xy 131.726842 -289.77993) (xy 131.679256 -289.761883) (xy 131.635182 -289.736437) (xy 131.59576 -289.70425)
			(xy 131.562012 -289.666156) (xy 131.534811 -289.623142) (xy 131.514863 -289.576322) (xy 131.502684 -289.526908)
			(xy 131.498589 -289.47618) (xy 131.180078 -289.47618) (xy 131.179583 -289.500787) (xy 131.171688 -289.549364)
			(xy 131.156104 -289.596045) (xy 131.133233 -289.639622) (xy 131.103668 -289.678966) (xy 131.068175 -289.713058)
			(xy 131.027672 -289.741014) (xy 130.98321 -289.762112) (xy 130.935939 -289.775804) (xy 130.887084 -289.781736)
			(xy 130.837909 -289.779755) (xy 130.78969 -289.769911) (xy 130.743674 -289.752459) (xy 130.701053 -289.727852)
			(xy 130.662932 -289.696727) (xy 130.630297 -289.65989) (xy 130.603994 -289.618294) (xy 130.584703 -289.573018)
			(xy 130.572926 -289.525234) (xy 130.568966 -289.47618) (xy 130.250438 -289.47618) (xy 130.249926 -289.501626)
			(xy 130.241762 -289.55186) (xy 130.225646 -289.600134) (xy 130.201995 -289.645197) (xy 130.171422 -289.685883)
			(xy 130.134718 -289.721138) (xy 130.092834 -289.750048) (xy 130.046855 -289.771865) (xy 129.997971 -289.786025)
			(xy 129.94745 -289.792159) (xy 129.896598 -289.79011) (xy 129.846734 -289.77993) (xy 129.799148 -289.761883)
			(xy 129.755074 -289.736437) (xy 129.715652 -289.70425) (xy 129.681904 -289.666156) (xy 129.654703 -289.623142)
			(xy 129.634755 -289.576322) (xy 129.622576 -289.526908) (xy 129.618481 -289.47618) (xy 129.29997 -289.47618)
			(xy 129.299475 -289.500787) (xy 129.29158 -289.549364) (xy 129.275996 -289.596045) (xy 129.253125 -289.639622)
			(xy 129.22356 -289.678966) (xy 129.188067 -289.713058) (xy 129.147564 -289.741014) (xy 129.103102 -289.762112)
			(xy 129.055831 -289.775804) (xy 129.006976 -289.781736) (xy 128.957801 -289.779755) (xy 128.909582 -289.769911)
			(xy 128.863566 -289.752459) (xy 128.820945 -289.727852) (xy 128.782824 -289.696727) (xy 128.750189 -289.65989)
			(xy 128.723886 -289.618294) (xy 128.704595 -289.573018) (xy 128.692818 -289.525234) (xy 128.688858 -289.47618)
			(xy 128.370067 -289.47618) (xy 128.370067 -289.501353) (xy 128.362087 -289.551028) (xy 128.346328 -289.598809)
			(xy 128.323189 -289.643484) (xy 128.293257 -289.683924) (xy 128.257289 -289.719103) (xy 128.216196 -289.748132)
			(xy 128.171018 -289.770274) (xy 128.1229 -289.78497) (xy 128.098042 -289.788854) (xy 128.091438 -289.78987)
			(xy 128.082489 -289.79147) (xy 128.066484 -289.800067) (xy 128.060196 -289.806634) (xy 128.0541 -289.813746)
			(xy 128.0541 -290.286186) (xy 128.208527 -290.286186) (xy 128.212622 -290.235458) (xy 128.224801 -290.186044)
			(xy 128.244749 -290.139224) (xy 128.27195 -290.09621) (xy 128.305698 -290.058116) (xy 128.34512 -290.025929)
			(xy 128.389194 -290.000483) (xy 128.43678 -289.982436) (xy 128.486644 -289.972256) (xy 128.537496 -289.970207)
			(xy 128.588017 -289.976341) (xy 128.636901 -289.990501) (xy 128.68288 -290.012318) (xy 128.724764 -290.041228)
			(xy 128.761468 -290.076483) (xy 128.792041 -290.117169) (xy 128.815692 -290.162232) (xy 128.831808 -290.210506)
			(xy 128.839972 -290.26074) (xy 128.840484 -290.286186) (xy 129.148581 -290.286186) (xy 129.152676 -290.235458)
			(xy 129.164855 -290.186044) (xy 129.184803 -290.139224) (xy 129.212004 -290.09621) (xy 129.245752 -290.058116)
			(xy 129.285174 -290.025929) (xy 129.329248 -290.000483) (xy 129.376834 -289.982436) (xy 129.426698 -289.972256)
			(xy 129.47755 -289.970207) (xy 129.528071 -289.976341) (xy 129.576955 -289.990501) (xy 129.622934 -290.012318)
			(xy 129.664818 -290.041228) (xy 129.701522 -290.076483) (xy 129.732095 -290.117169) (xy 129.755746 -290.162232)
			(xy 129.771862 -290.210506) (xy 129.780026 -290.26074) (xy 129.780538 -290.286186) (xy 131.028435 -290.286186)
			(xy 131.03253 -290.235458) (xy 131.044709 -290.186044) (xy 131.064657 -290.139224) (xy 131.091858 -290.09621)
			(xy 131.125606 -290.058116) (xy 131.165028 -290.025929) (xy 131.209102 -290.000483) (xy 131.256688 -289.982436)
			(xy 131.306552 -289.972256) (xy 131.357404 -289.970207) (xy 131.407925 -289.976341) (xy 131.456809 -289.990501)
			(xy 131.502788 -290.012318) (xy 131.544672 -290.041228) (xy 131.581376 -290.076483) (xy 131.611949 -290.117169)
			(xy 131.6356 -290.162232) (xy 131.651716 -290.210506) (xy 131.65988 -290.26074) (xy 131.660392 -290.286186)
			(xy 131.97892 -290.286186) (xy 131.98288 -290.237132) (xy 131.994657 -290.189348) (xy 132.013948 -290.144072)
			(xy 132.040251 -290.102476) (xy 132.072886 -290.065639) (xy 132.111007 -290.034514) (xy 132.153628 -290.009907)
			(xy 132.199644 -289.992455) (xy 132.247863 -289.982611) (xy 132.297038 -289.98063) (xy 132.345893 -289.986562)
			(xy 132.393164 -290.000254) (xy 132.437626 -290.021352) (xy 132.478129 -290.049308) (xy 132.513622 -290.0834)
			(xy 132.543187 -290.122744) (xy 132.566058 -290.166321) (xy 132.581642 -290.213002) (xy 132.589537 -290.261579)
			(xy 132.590032 -290.286186) (xy 132.908543 -290.286186) (xy 132.912638 -290.235458) (xy 132.924817 -290.186044)
			(xy 132.944765 -290.139224) (xy 132.971966 -290.09621) (xy 133.005714 -290.058116) (xy 133.045136 -290.025929)
			(xy 133.08921 -290.000483) (xy 133.136796 -289.982436) (xy 133.18666 -289.972256) (xy 133.237512 -289.970207)
			(xy 133.288033 -289.976341) (xy 133.336917 -289.990501) (xy 133.382896 -290.012318) (xy 133.42478 -290.041228)
			(xy 133.461484 -290.076483) (xy 133.492057 -290.117169) (xy 133.515708 -290.162232) (xy 133.531824 -290.210506)
			(xy 133.539988 -290.26074) (xy 133.5405 -290.286186) (xy 133.539988 -290.311632) (xy 133.531824 -290.361866)
			(xy 133.515708 -290.41014) (xy 133.492057 -290.455203) (xy 133.461484 -290.495889) (xy 133.42478 -290.531144)
			(xy 133.382896 -290.560054) (xy 133.336917 -290.581871) (xy 133.288033 -290.596031) (xy 133.237512 -290.602165)
			(xy 133.18666 -290.600116) (xy 133.136796 -290.589936) (xy 133.08921 -290.571889) (xy 133.045136 -290.546443)
			(xy 133.005714 -290.514256) (xy 132.971966 -290.476162) (xy 132.944765 -290.433148) (xy 132.924817 -290.386328)
			(xy 132.912638 -290.336914) (xy 132.908543 -290.286186) (xy 132.590032 -290.286186) (xy 132.589537 -290.310793)
			(xy 132.581642 -290.35937) (xy 132.566058 -290.406051) (xy 132.543187 -290.449628) (xy 132.513622 -290.488972)
			(xy 132.478129 -290.523064) (xy 132.437626 -290.55102) (xy 132.393164 -290.572118) (xy 132.345893 -290.58581)
			(xy 132.297038 -290.591742) (xy 132.247863 -290.589761) (xy 132.199644 -290.579917) (xy 132.153628 -290.562465)
			(xy 132.111007 -290.537858) (xy 132.072886 -290.506733) (xy 132.040251 -290.469896) (xy 132.013948 -290.4283)
			(xy 131.994657 -290.383024) (xy 131.98288 -290.33524) (xy 131.97892 -290.286186) (xy 131.660392 -290.286186)
			(xy 131.65988 -290.311632) (xy 131.651716 -290.361866) (xy 131.6356 -290.41014) (xy 131.611949 -290.455203)
			(xy 131.581376 -290.495889) (xy 131.544672 -290.531144) (xy 131.502788 -290.560054) (xy 131.456809 -290.581871)
			(xy 131.407925 -290.596031) (xy 131.357404 -290.602165) (xy 131.306552 -290.600116) (xy 131.256688 -290.589936)
			(xy 131.209102 -290.571889) (xy 131.165028 -290.546443) (xy 131.125606 -290.514256) (xy 131.091858 -290.476162)
			(xy 131.064657 -290.433148) (xy 131.044709 -290.386328) (xy 131.03253 -290.336914) (xy 131.028435 -290.286186)
			(xy 129.780538 -290.286186) (xy 129.780026 -290.311632) (xy 129.771862 -290.361866) (xy 129.755746 -290.41014)
			(xy 129.732095 -290.455203) (xy 129.701522 -290.495889) (xy 129.664818 -290.531144) (xy 129.622934 -290.560054)
			(xy 129.576955 -290.581871) (xy 129.528071 -290.596031) (xy 129.47755 -290.602165) (xy 129.426698 -290.600116)
			(xy 129.376834 -290.589936) (xy 129.329248 -290.571889) (xy 129.285174 -290.546443) (xy 129.245752 -290.514256)
			(xy 129.212004 -290.476162) (xy 129.184803 -290.433148) (xy 129.164855 -290.386328) (xy 129.152676 -290.336914)
			(xy 129.148581 -290.286186) (xy 128.840484 -290.286186) (xy 128.839972 -290.311632) (xy 128.831808 -290.361866)
			(xy 128.815692 -290.41014) (xy 128.792041 -290.455203) (xy 128.761468 -290.495889) (xy 128.724764 -290.531144)
			(xy 128.68288 -290.560054) (xy 128.636901 -290.581871) (xy 128.588017 -290.596031) (xy 128.537496 -290.602165)
			(xy 128.486644 -290.600116) (xy 128.43678 -290.589936) (xy 128.389194 -290.571889) (xy 128.34512 -290.546443)
			(xy 128.305698 -290.514256) (xy 128.27195 -290.476162) (xy 128.244749 -290.433148) (xy 128.224801 -290.386328)
			(xy 128.212622 -290.336914) (xy 128.208527 -290.286186) (xy 128.0541 -290.286186) (xy 128.0541 -290.739576)
			(xy 128.054476 -290.74868) (xy 128.060859 -290.765731) (xy 128.066546 -290.77285) (xy 128.072642 -290.779962)
			(xy 128.098042 -290.783518) (xy 128.122894 -290.78744) (xy 128.17101 -290.802135) (xy 128.216186 -290.824277)
			(xy 128.257278 -290.853304) (xy 128.293246 -290.888481) (xy 128.323177 -290.928919) (xy 128.346316 -290.973592)
			(xy 128.362075 -291.021371) (xy 128.370055 -291.071044) (xy 128.370055 -291.096192) (xy 128.688858 -291.096192)
			(xy 128.692818 -291.047138) (xy 128.704595 -290.999354) (xy 128.723886 -290.954078) (xy 128.750189 -290.912482)
			(xy 128.782824 -290.875645) (xy 128.820945 -290.84452) (xy 128.863566 -290.819913) (xy 128.909582 -290.802461)
			(xy 128.957801 -290.792617) (xy 129.006976 -290.790636) (xy 129.055831 -290.796568) (xy 129.103102 -290.81026)
			(xy 129.147564 -290.831358) (xy 129.188067 -290.859314) (xy 129.22356 -290.893406) (xy 129.253125 -290.93275)
			(xy 129.275996 -290.976327) (xy 129.29158 -291.023008) (xy 129.299475 -291.071585) (xy 129.29997 -291.096192)
			(xy 129.618481 -291.096192) (xy 129.622576 -291.045464) (xy 129.634755 -290.99605) (xy 129.654703 -290.94923)
			(xy 129.681904 -290.906216) (xy 129.715652 -290.868122) (xy 129.755074 -290.835935) (xy 129.799148 -290.810489)
			(xy 129.846734 -290.792442) (xy 129.896598 -290.782262) (xy 129.94745 -290.780213) (xy 129.997971 -290.786347)
			(xy 130.046855 -290.800507) (xy 130.092834 -290.822324) (xy 130.134718 -290.851234) (xy 130.171422 -290.886489)
			(xy 130.201995 -290.927175) (xy 130.225646 -290.972238) (xy 130.241762 -291.020512) (xy 130.249926 -291.070746)
			(xy 130.250438 -291.096192) (xy 130.568966 -291.096192) (xy 130.572926 -291.047138) (xy 130.584703 -290.999354)
			(xy 130.603994 -290.954078) (xy 130.630297 -290.912482) (xy 130.662932 -290.875645) (xy 130.701053 -290.84452)
			(xy 130.743674 -290.819913) (xy 130.78969 -290.802461) (xy 130.837909 -290.792617) (xy 130.887084 -290.790636)
			(xy 130.935939 -290.796568) (xy 130.98321 -290.81026) (xy 131.027672 -290.831358) (xy 131.068175 -290.859314)
			(xy 131.103668 -290.893406) (xy 131.133233 -290.93275) (xy 131.156104 -290.976327) (xy 131.171688 -291.023008)
			(xy 131.179583 -291.071585) (xy 131.180078 -291.096192) (xy 131.498589 -291.096192) (xy 131.502684 -291.045464)
			(xy 131.514863 -290.99605) (xy 131.534811 -290.94923) (xy 131.562012 -290.906216) (xy 131.59576 -290.868122)
			(xy 131.635182 -290.835935) (xy 131.679256 -290.810489) (xy 131.726842 -290.792442) (xy 131.776706 -290.782262)
			(xy 131.827558 -290.780213) (xy 131.878079 -290.786347) (xy 131.926963 -290.800507) (xy 131.972942 -290.822324)
			(xy 132.014826 -290.851234) (xy 132.05153 -290.886489) (xy 132.082103 -290.927175) (xy 132.105754 -290.972238)
			(xy 132.12187 -291.020512) (xy 132.130034 -291.070746) (xy 132.130546 -291.096192) (xy 132.438643 -291.096192)
			(xy 132.442738 -291.045464) (xy 132.454917 -290.99605) (xy 132.474865 -290.94923) (xy 132.502066 -290.906216)
			(xy 132.535814 -290.868122) (xy 132.575236 -290.835935) (xy 132.61931 -290.810489) (xy 132.666896 -290.792442)
			(xy 132.71676 -290.782262) (xy 132.767612 -290.780213) (xy 132.818133 -290.786347) (xy 132.867017 -290.800507)
			(xy 132.912996 -290.822324) (xy 132.95488 -290.851234) (xy 132.991584 -290.886489) (xy 133.022157 -290.927175)
			(xy 133.045808 -290.972238) (xy 133.061924 -291.020512) (xy 133.070088 -291.070746) (xy 133.0706 -291.096192)
			(xy 133.070088 -291.121638) (xy 133.061924 -291.171872) (xy 133.045808 -291.220146) (xy 133.022157 -291.265209)
			(xy 132.991584 -291.305895) (xy 132.95488 -291.34115) (xy 132.912996 -291.37006) (xy 132.867017 -291.391877)
			(xy 132.818133 -291.406037) (xy 132.767612 -291.412171) (xy 132.71676 -291.410122) (xy 132.666896 -291.399942)
			(xy 132.61931 -291.381895) (xy 132.575236 -291.356449) (xy 132.535814 -291.324262) (xy 132.502066 -291.286168)
			(xy 132.474865 -291.243154) (xy 132.454917 -291.196334) (xy 132.442738 -291.14692) (xy 132.438643 -291.096192)
			(xy 132.130546 -291.096192) (xy 132.130034 -291.121638) (xy 132.12187 -291.171872) (xy 132.105754 -291.220146)
			(xy 132.082103 -291.265209) (xy 132.05153 -291.305895) (xy 132.014826 -291.34115) (xy 131.972942 -291.37006)
			(xy 131.926963 -291.391877) (xy 131.878079 -291.406037) (xy 131.827558 -291.412171) (xy 131.776706 -291.410122)
			(xy 131.726842 -291.399942) (xy 131.679256 -291.381895) (xy 131.635182 -291.356449) (xy 131.59576 -291.324262)
			(xy 131.562012 -291.286168) (xy 131.534811 -291.243154) (xy 131.514863 -291.196334) (xy 131.502684 -291.14692)
			(xy 131.498589 -291.096192) (xy 131.180078 -291.096192) (xy 131.179583 -291.120799) (xy 131.171688 -291.169376)
			(xy 131.156104 -291.216057) (xy 131.133233 -291.259634) (xy 131.103668 -291.298978) (xy 131.068175 -291.33307)
			(xy 131.027672 -291.361026) (xy 130.98321 -291.382124) (xy 130.935939 -291.395816) (xy 130.887084 -291.401748)
			(xy 130.837909 -291.399767) (xy 130.78969 -291.389923) (xy 130.743674 -291.372471) (xy 130.701053 -291.347864)
			(xy 130.662932 -291.316739) (xy 130.630297 -291.279902) (xy 130.603994 -291.238306) (xy 130.584703 -291.19303)
			(xy 130.572926 -291.145246) (xy 130.568966 -291.096192) (xy 130.250438 -291.096192) (xy 130.249926 -291.121638)
			(xy 130.241762 -291.171872) (xy 130.225646 -291.220146) (xy 130.201995 -291.265209) (xy 130.171422 -291.305895)
			(xy 130.134718 -291.34115) (xy 130.092834 -291.37006) (xy 130.046855 -291.391877) (xy 129.997971 -291.406037)
			(xy 129.94745 -291.412171) (xy 129.896598 -291.410122) (xy 129.846734 -291.399942) (xy 129.799148 -291.381895)
			(xy 129.755074 -291.356449) (xy 129.715652 -291.324262) (xy 129.681904 -291.286168) (xy 129.654703 -291.243154)
			(xy 129.634755 -291.196334) (xy 129.622576 -291.14692) (xy 129.618481 -291.096192) (xy 129.29997 -291.096192)
			(xy 129.299475 -291.120799) (xy 129.29158 -291.169376) (xy 129.275996 -291.216057) (xy 129.253125 -291.259634)
			(xy 129.22356 -291.298978) (xy 129.188067 -291.33307) (xy 129.147564 -291.361026) (xy 129.103102 -291.382124)
			(xy 129.055831 -291.395816) (xy 129.006976 -291.401748) (xy 128.957801 -291.399767) (xy 128.909582 -291.389923)
			(xy 128.863566 -291.372471) (xy 128.820945 -291.347864) (xy 128.782824 -291.316739) (xy 128.750189 -291.279902)
			(xy 128.723886 -291.238306) (xy 128.704595 -291.19303) (xy 128.692818 -291.145246) (xy 128.688858 -291.096192)
			(xy 128.370055 -291.096192) (xy 128.370055 -291.121354) (xy 128.362075 -291.171027) (xy 128.346316 -291.218806)
			(xy 128.323178 -291.263479) (xy 128.293247 -291.303917) (xy 128.25728 -291.339095) (xy 128.216188 -291.368122)
			(xy 128.171012 -291.390264) (xy 128.122896 -291.404959) (xy 128.098042 -291.408866) (xy 128.091438 -291.409882)
			(xy 128.082489 -291.411483) (xy 128.066486 -291.420081) (xy 128.060196 -291.426646) (xy 128.0541 -291.433758)
			(xy 128.0541 -291.906198) (xy 128.208527 -291.906198) (xy 128.212622 -291.85547) (xy 128.224801 -291.806056)
			(xy 128.244749 -291.759236) (xy 128.27195 -291.716222) (xy 128.305698 -291.678128) (xy 128.34512 -291.645941)
			(xy 128.389194 -291.620495) (xy 128.43678 -291.602448) (xy 128.486644 -291.592268) (xy 128.537496 -291.590219)
			(xy 128.588017 -291.596353) (xy 128.636901 -291.610513) (xy 128.68288 -291.63233) (xy 128.724764 -291.66124)
			(xy 128.761468 -291.696495) (xy 128.792041 -291.737181) (xy 128.815692 -291.782244) (xy 128.831808 -291.830518)
			(xy 128.839972 -291.880752) (xy 128.840484 -291.906198) (xy 129.148581 -291.906198) (xy 129.152676 -291.85547)
			(xy 129.164855 -291.806056) (xy 129.184803 -291.759236) (xy 129.212004 -291.716222) (xy 129.245752 -291.678128)
			(xy 129.285174 -291.645941) (xy 129.329248 -291.620495) (xy 129.376834 -291.602448) (xy 129.426698 -291.592268)
			(xy 129.47755 -291.590219) (xy 129.528071 -291.596353) (xy 129.576955 -291.610513) (xy 129.622934 -291.63233)
			(xy 129.664818 -291.66124) (xy 129.701522 -291.696495) (xy 129.732095 -291.737181) (xy 129.755746 -291.782244)
			(xy 129.771862 -291.830518) (xy 129.780026 -291.880752) (xy 129.780538 -291.906198) (xy 130.099066 -291.906198)
			(xy 130.103026 -291.857144) (xy 130.114803 -291.80936) (xy 130.134094 -291.764084) (xy 130.160397 -291.722488)
			(xy 130.193032 -291.685651) (xy 130.231153 -291.654526) (xy 130.273774 -291.629919) (xy 130.31979 -291.612467)
			(xy 130.368009 -291.602623) (xy 130.417184 -291.600642) (xy 130.466039 -291.606574) (xy 130.51331 -291.620266)
			(xy 130.557772 -291.641364) (xy 130.598275 -291.66932) (xy 130.633768 -291.703412) (xy 130.663333 -291.742756)
			(xy 130.686204 -291.786333) (xy 130.701788 -291.833014) (xy 130.709683 -291.881591) (xy 130.710178 -291.906198)
			(xy 131.028435 -291.906198) (xy 131.03253 -291.85547) (xy 131.044709 -291.806056) (xy 131.064657 -291.759236)
			(xy 131.091858 -291.716222) (xy 131.125606 -291.678128) (xy 131.165028 -291.645941) (xy 131.209102 -291.620495)
			(xy 131.256688 -291.602448) (xy 131.306552 -291.592268) (xy 131.357404 -291.590219) (xy 131.407925 -291.596353)
			(xy 131.456809 -291.610513) (xy 131.502788 -291.63233) (xy 131.544672 -291.66124) (xy 131.581376 -291.696495)
			(xy 131.611949 -291.737181) (xy 131.6356 -291.782244) (xy 131.651716 -291.830518) (xy 131.65988 -291.880752)
			(xy 131.660392 -291.906198) (xy 131.97892 -291.906198) (xy 131.98288 -291.857144) (xy 131.994657 -291.80936)
			(xy 132.013948 -291.764084) (xy 132.040251 -291.722488) (xy 132.072886 -291.685651) (xy 132.111007 -291.654526)
			(xy 132.153628 -291.629919) (xy 132.199644 -291.612467) (xy 132.247863 -291.602623) (xy 132.297038 -291.600642)
			(xy 132.345893 -291.606574) (xy 132.393164 -291.620266) (xy 132.437626 -291.641364) (xy 132.478129 -291.66932)
			(xy 132.513622 -291.703412) (xy 132.543187 -291.742756) (xy 132.566058 -291.786333) (xy 132.581642 -291.833014)
			(xy 132.589537 -291.881591) (xy 132.590032 -291.906198) (xy 132.908543 -291.906198) (xy 132.912638 -291.85547)
			(xy 132.924817 -291.806056) (xy 132.944765 -291.759236) (xy 132.971966 -291.716222) (xy 133.005714 -291.678128)
			(xy 133.045136 -291.645941) (xy 133.08921 -291.620495) (xy 133.136796 -291.602448) (xy 133.18666 -291.592268)
			(xy 133.237512 -291.590219) (xy 133.288033 -291.596353) (xy 133.336917 -291.610513) (xy 133.382896 -291.63233)
			(xy 133.42478 -291.66124) (xy 133.461484 -291.696495) (xy 133.492057 -291.737181) (xy 133.515708 -291.782244)
			(xy 133.531824 -291.830518) (xy 133.539988 -291.880752) (xy 133.5405 -291.906198) (xy 133.539988 -291.931644)
			(xy 133.531824 -291.981878) (xy 133.515708 -292.030152) (xy 133.492057 -292.075215) (xy 133.461484 -292.115901)
			(xy 133.42478 -292.151156) (xy 133.382896 -292.180066) (xy 133.336917 -292.201883) (xy 133.288033 -292.216043)
			(xy 133.237512 -292.222177) (xy 133.18666 -292.220128) (xy 133.136796 -292.209948) (xy 133.08921 -292.191901)
			(xy 133.045136 -292.166455) (xy 133.005714 -292.134268) (xy 132.971966 -292.096174) (xy 132.944765 -292.05316)
			(xy 132.924817 -292.00634) (xy 132.912638 -291.956926) (xy 132.908543 -291.906198) (xy 132.590032 -291.906198)
			(xy 132.589537 -291.930805) (xy 132.581642 -291.979382) (xy 132.566058 -292.026063) (xy 132.543187 -292.06964)
			(xy 132.513622 -292.108984) (xy 132.478129 -292.143076) (xy 132.437626 -292.171032) (xy 132.393164 -292.19213)
			(xy 132.345893 -292.205822) (xy 132.297038 -292.211754) (xy 132.247863 -292.209773) (xy 132.199644 -292.199929)
			(xy 132.153628 -292.182477) (xy 132.111007 -292.15787) (xy 132.072886 -292.126745) (xy 132.040251 -292.089908)
			(xy 132.013948 -292.048312) (xy 131.994657 -292.003036) (xy 131.98288 -291.955252) (xy 131.97892 -291.906198)
			(xy 131.660392 -291.906198) (xy 131.65988 -291.931644) (xy 131.651716 -291.981878) (xy 131.6356 -292.030152)
			(xy 131.611949 -292.075215) (xy 131.581376 -292.115901) (xy 131.544672 -292.151156) (xy 131.502788 -292.180066)
			(xy 131.456809 -292.201883) (xy 131.407925 -292.216043) (xy 131.357404 -292.222177) (xy 131.306552 -292.220128)
			(xy 131.256688 -292.209948) (xy 131.209102 -292.191901) (xy 131.165028 -292.166455) (xy 131.125606 -292.134268)
			(xy 131.091858 -292.096174) (xy 131.064657 -292.05316) (xy 131.044709 -292.00634) (xy 131.03253 -291.956926)
			(xy 131.028435 -291.906198) (xy 130.710178 -291.906198) (xy 130.709683 -291.930805) (xy 130.701788 -291.979382)
			(xy 130.686204 -292.026063) (xy 130.663333 -292.06964) (xy 130.633768 -292.108984) (xy 130.598275 -292.143076)
			(xy 130.557772 -292.171032) (xy 130.51331 -292.19213) (xy 130.466039 -292.205822) (xy 130.417184 -292.211754)
			(xy 130.368009 -292.209773) (xy 130.31979 -292.199929) (xy 130.273774 -292.182477) (xy 130.231153 -292.15787)
			(xy 130.193032 -292.126745) (xy 130.160397 -292.089908) (xy 130.134094 -292.048312) (xy 130.114803 -292.003036)
			(xy 130.103026 -291.955252) (xy 130.099066 -291.906198) (xy 129.780538 -291.906198) (xy 129.780026 -291.931644)
			(xy 129.771862 -291.981878) (xy 129.755746 -292.030152) (xy 129.732095 -292.075215) (xy 129.701522 -292.115901)
			(xy 129.664818 -292.151156) (xy 129.622934 -292.180066) (xy 129.576955 -292.201883) (xy 129.528071 -292.216043)
			(xy 129.47755 -292.222177) (xy 129.426698 -292.220128) (xy 129.376834 -292.209948) (xy 129.329248 -292.191901)
			(xy 129.285174 -292.166455) (xy 129.245752 -292.134268) (xy 129.212004 -292.096174) (xy 129.184803 -292.05316)
			(xy 129.164855 -292.00634) (xy 129.152676 -291.956926) (xy 129.148581 -291.906198) (xy 128.840484 -291.906198)
			(xy 128.839972 -291.931644) (xy 128.831808 -291.981878) (xy 128.815692 -292.030152) (xy 128.792041 -292.075215)
			(xy 128.761468 -292.115901) (xy 128.724764 -292.151156) (xy 128.68288 -292.180066) (xy 128.636901 -292.201883)
			(xy 128.588017 -292.216043) (xy 128.537496 -292.222177) (xy 128.486644 -292.220128) (xy 128.43678 -292.209948)
			(xy 128.389194 -292.191901) (xy 128.34512 -292.166455) (xy 128.305698 -292.134268) (xy 128.27195 -292.096174)
			(xy 128.244749 -292.05316) (xy 128.224801 -292.00634) (xy 128.212622 -291.956926) (xy 128.208527 -291.906198)
			(xy 128.0541 -291.906198) (xy 128.0541 -292.359588) (xy 128.054478 -292.368691) (xy 128.060864 -292.385739)
			(xy 128.066546 -292.392862) (xy 128.072642 -292.399974) (xy 128.098042 -292.40353) (xy 128.122893 -292.407452)
			(xy 128.171008 -292.422147) (xy 128.216182 -292.444288) (xy 128.257272 -292.473314) (xy 128.293238 -292.50849)
			(xy 128.323168 -292.548927) (xy 128.346305 -292.593599) (xy 128.362063 -292.641375) (xy 128.370044 -292.691046)
			(xy 128.370043 -292.716204) (xy 128.688858 -292.716204) (xy 128.692818 -292.66715) (xy 128.704595 -292.619366)
			(xy 128.723886 -292.57409) (xy 128.750189 -292.532494) (xy 128.782824 -292.495657) (xy 128.820945 -292.464532)
			(xy 128.863566 -292.439925) (xy 128.909582 -292.422473) (xy 128.957801 -292.412629) (xy 129.006976 -292.410648)
			(xy 129.055831 -292.41658) (xy 129.103102 -292.430272) (xy 129.147564 -292.45137) (xy 129.188067 -292.479326)
			(xy 129.22356 -292.513418) (xy 129.253125 -292.552762) (xy 129.275996 -292.596339) (xy 129.29158 -292.64302)
			(xy 129.299475 -292.691597) (xy 129.29997 -292.716204) (xy 129.618481 -292.716204) (xy 129.622576 -292.665476)
			(xy 129.634755 -292.616062) (xy 129.654703 -292.569242) (xy 129.681904 -292.526228) (xy 129.715652 -292.488134)
			(xy 129.755074 -292.455947) (xy 129.799148 -292.430501) (xy 129.846734 -292.412454) (xy 129.896598 -292.402274)
			(xy 129.94745 -292.400225) (xy 129.997971 -292.406359) (xy 130.046855 -292.420519) (xy 130.092834 -292.442336)
			(xy 130.134718 -292.471246) (xy 130.171422 -292.506501) (xy 130.201995 -292.547187) (xy 130.225646 -292.59225)
			(xy 130.241762 -292.640524) (xy 130.249926 -292.690758) (xy 130.250438 -292.716204) (xy 131.498589 -292.716204)
			(xy 131.502684 -292.665476) (xy 131.514863 -292.616062) (xy 131.534811 -292.569242) (xy 131.562012 -292.526228)
			(xy 131.59576 -292.488134) (xy 131.635182 -292.455947) (xy 131.679256 -292.430501) (xy 131.726842 -292.412454)
			(xy 131.776706 -292.402274) (xy 131.827558 -292.400225) (xy 131.878079 -292.406359) (xy 131.926963 -292.420519)
			(xy 131.972942 -292.442336) (xy 132.014826 -292.471246) (xy 132.05153 -292.506501) (xy 132.082103 -292.547187)
			(xy 132.105754 -292.59225) (xy 132.12187 -292.640524) (xy 132.130034 -292.690758) (xy 132.130546 -292.716204)
			(xy 132.438643 -292.716204) (xy 132.442738 -292.665476) (xy 132.454917 -292.616062) (xy 132.474865 -292.569242)
			(xy 132.502066 -292.526228) (xy 132.535814 -292.488134) (xy 132.575236 -292.455947) (xy 132.61931 -292.430501)
			(xy 132.666896 -292.412454) (xy 132.71676 -292.402274) (xy 132.767612 -292.400225) (xy 132.818133 -292.406359)
			(xy 132.867017 -292.420519) (xy 132.912996 -292.442336) (xy 132.95488 -292.471246) (xy 132.991584 -292.506501)
			(xy 133.022157 -292.547187) (xy 133.045808 -292.59225) (xy 133.061924 -292.640524) (xy 133.070088 -292.690758)
			(xy 133.0706 -292.716204) (xy 133.070088 -292.74165) (xy 133.061924 -292.791884) (xy 133.045808 -292.840158)
			(xy 133.022157 -292.885221) (xy 132.991584 -292.925907) (xy 132.95488 -292.961162) (xy 132.912996 -292.990072)
			(xy 132.867017 -293.011889) (xy 132.818133 -293.026049) (xy 132.767612 -293.032183) (xy 132.71676 -293.030134)
			(xy 132.666896 -293.019954) (xy 132.61931 -293.001907) (xy 132.575236 -292.976461) (xy 132.535814 -292.944274)
			(xy 132.502066 -292.90618) (xy 132.474865 -292.863166) (xy 132.454917 -292.816346) (xy 132.442738 -292.766932)
			(xy 132.438643 -292.716204) (xy 132.130546 -292.716204) (xy 132.130034 -292.74165) (xy 132.12187 -292.791884)
			(xy 132.105754 -292.840158) (xy 132.082103 -292.885221) (xy 132.05153 -292.925907) (xy 132.014826 -292.961162)
			(xy 131.972942 -292.990072) (xy 131.926963 -293.011889) (xy 131.878079 -293.026049) (xy 131.827558 -293.032183)
			(xy 131.776706 -293.030134) (xy 131.726842 -293.019954) (xy 131.679256 -293.001907) (xy 131.635182 -292.976461)
			(xy 131.59576 -292.944274) (xy 131.562012 -292.90618) (xy 131.534811 -292.863166) (xy 131.514863 -292.816346)
			(xy 131.502684 -292.766932) (xy 131.498589 -292.716204) (xy 130.250438 -292.716204) (xy 130.249926 -292.74165)
			(xy 130.241762 -292.791884) (xy 130.225646 -292.840158) (xy 130.201995 -292.885221) (xy 130.171422 -292.925907)
			(xy 130.134718 -292.961162) (xy 130.092834 -292.990072) (xy 130.046855 -293.011889) (xy 129.997971 -293.026049)
			(xy 129.94745 -293.032183) (xy 129.896598 -293.030134) (xy 129.846734 -293.019954) (xy 129.799148 -293.001907)
			(xy 129.755074 -292.976461) (xy 129.715652 -292.944274) (xy 129.681904 -292.90618) (xy 129.654703 -292.863166)
			(xy 129.634755 -292.816346) (xy 129.622576 -292.766932) (xy 129.618481 -292.716204) (xy 129.29997 -292.716204)
			(xy 129.299475 -292.740811) (xy 129.29158 -292.789388) (xy 129.275996 -292.836069) (xy 129.253125 -292.879646)
			(xy 129.22356 -292.91899) (xy 129.188067 -292.953082) (xy 129.147564 -292.981038) (xy 129.103102 -293.002136)
			(xy 129.055831 -293.015828) (xy 129.006976 -293.02176) (xy 128.957801 -293.019779) (xy 128.909582 -293.009935)
			(xy 128.863566 -292.992483) (xy 128.820945 -292.967876) (xy 128.782824 -292.936751) (xy 128.750189 -292.899914)
			(xy 128.723886 -292.858318) (xy 128.704595 -292.813042) (xy 128.692818 -292.765258) (xy 128.688858 -292.716204)
			(xy 128.370043 -292.716204) (xy 128.370043 -292.741355) (xy 128.362063 -292.791026) (xy 128.346305 -292.838802)
			(xy 128.323168 -292.883474) (xy 128.293237 -292.923911) (xy 128.257271 -292.959087) (xy 128.216181 -292.988113)
			(xy 128.171007 -293.010253) (xy 128.122892 -293.024948) (xy 128.098042 -293.028878) (xy 128.091438 -293.029894)
			(xy 128.082489 -293.031495) (xy 128.066488 -293.040095) (xy 128.060196 -293.046658) (xy 128.0541 -293.05377)
			(xy 128.0541 -293.52621) (xy 128.208527 -293.52621) (xy 128.212622 -293.475482) (xy 128.224801 -293.426068)
			(xy 128.244749 -293.379248) (xy 128.27195 -293.336234) (xy 128.305698 -293.29814) (xy 128.34512 -293.265953)
			(xy 128.389194 -293.240507) (xy 128.43678 -293.22246) (xy 128.486644 -293.21228) (xy 128.537496 -293.210231)
			(xy 128.588017 -293.216365) (xy 128.636901 -293.230525) (xy 128.68288 -293.252342) (xy 128.724764 -293.281252)
			(xy 128.761468 -293.316507) (xy 128.792041 -293.357193) (xy 128.815692 -293.402256) (xy 128.831808 -293.45053)
			(xy 128.839972 -293.500764) (xy 128.840484 -293.52621) (xy 129.159012 -293.52621) (xy 129.162972 -293.477156)
			(xy 129.174749 -293.429372) (xy 129.19404 -293.384096) (xy 129.220343 -293.3425) (xy 129.252978 -293.305663)
			(xy 129.291099 -293.274538) (xy 129.33372 -293.249931) (xy 129.379736 -293.232479) (xy 129.427955 -293.222635)
			(xy 129.47713 -293.220654) (xy 129.525985 -293.226586) (xy 129.573256 -293.240278) (xy 129.617718 -293.261376)
			(xy 129.658221 -293.289332) (xy 129.693714 -293.323424) (xy 129.723279 -293.362768) (xy 129.74615 -293.406345)
			(xy 129.761734 -293.453026) (xy 129.769629 -293.501603) (xy 129.770124 -293.52621) (xy 130.099066 -293.52621)
			(xy 130.103026 -293.477156) (xy 130.114803 -293.429372) (xy 130.134094 -293.384096) (xy 130.160397 -293.3425)
			(xy 130.193032 -293.305663) (xy 130.231153 -293.274538) (xy 130.273774 -293.249931) (xy 130.31979 -293.232479)
			(xy 130.368009 -293.222635) (xy 130.417184 -293.220654) (xy 130.466039 -293.226586) (xy 130.51331 -293.240278)
			(xy 130.557772 -293.261376) (xy 130.598275 -293.289332) (xy 130.633768 -293.323424) (xy 130.663333 -293.362768)
			(xy 130.686204 -293.406345) (xy 130.701788 -293.453026) (xy 130.709683 -293.501603) (xy 130.710178 -293.52621)
			(xy 131.038866 -293.52621) (xy 131.042826 -293.477156) (xy 131.054603 -293.429372) (xy 131.073894 -293.384096)
			(xy 131.100197 -293.3425) (xy 131.132832 -293.305663) (xy 131.170953 -293.274538) (xy 131.213574 -293.249931)
			(xy 131.25959 -293.232479) (xy 131.307809 -293.222635) (xy 131.356984 -293.220654) (xy 131.405839 -293.226586)
			(xy 131.45311 -293.240278) (xy 131.497572 -293.261376) (xy 131.538075 -293.289332) (xy 131.573568 -293.323424)
			(xy 131.603133 -293.362768) (xy 131.626004 -293.406345) (xy 131.641588 -293.453026) (xy 131.649483 -293.501603)
			(xy 131.649978 -293.52621) (xy 131.97892 -293.52621) (xy 131.98288 -293.477156) (xy 131.994657 -293.429372)
			(xy 132.013948 -293.384096) (xy 132.040251 -293.3425) (xy 132.072886 -293.305663) (xy 132.111007 -293.274538)
			(xy 132.153628 -293.249931) (xy 132.199644 -293.232479) (xy 132.247863 -293.222635) (xy 132.297038 -293.220654)
			(xy 132.345893 -293.226586) (xy 132.393164 -293.240278) (xy 132.437626 -293.261376) (xy 132.478129 -293.289332)
			(xy 132.513622 -293.323424) (xy 132.543187 -293.362768) (xy 132.566058 -293.406345) (xy 132.581642 -293.453026)
			(xy 132.589537 -293.501603) (xy 132.590032 -293.52621) (xy 132.908543 -293.52621) (xy 132.912638 -293.475482)
			(xy 132.924817 -293.426068) (xy 132.944765 -293.379248) (xy 132.971966 -293.336234) (xy 133.005714 -293.29814)
			(xy 133.045136 -293.265953) (xy 133.08921 -293.240507) (xy 133.136796 -293.22246) (xy 133.18666 -293.21228)
			(xy 133.237512 -293.210231) (xy 133.288033 -293.216365) (xy 133.336917 -293.230525) (xy 133.382896 -293.252342)
			(xy 133.42478 -293.281252) (xy 133.461484 -293.316507) (xy 133.492057 -293.357193) (xy 133.515708 -293.402256)
			(xy 133.531824 -293.45053) (xy 133.539988 -293.500764) (xy 133.5405 -293.52621) (xy 133.539988 -293.551656)
			(xy 133.531824 -293.60189) (xy 133.515708 -293.650164) (xy 133.492057 -293.695227) (xy 133.461484 -293.735913)
			(xy 133.42478 -293.771168) (xy 133.382896 -293.800078) (xy 133.336917 -293.821895) (xy 133.288033 -293.836055)
			(xy 133.237512 -293.842189) (xy 133.18666 -293.84014) (xy 133.136796 -293.82996) (xy 133.08921 -293.811913)
			(xy 133.045136 -293.786467) (xy 133.005714 -293.75428) (xy 132.971966 -293.716186) (xy 132.944765 -293.673172)
			(xy 132.924817 -293.626352) (xy 132.912638 -293.576938) (xy 132.908543 -293.52621) (xy 132.590032 -293.52621)
			(xy 132.589537 -293.550817) (xy 132.581642 -293.599394) (xy 132.566058 -293.646075) (xy 132.543187 -293.689652)
			(xy 132.513622 -293.728996) (xy 132.478129 -293.763088) (xy 132.437626 -293.791044) (xy 132.393164 -293.812142)
			(xy 132.345893 -293.825834) (xy 132.297038 -293.831766) (xy 132.247863 -293.829785) (xy 132.199644 -293.819941)
			(xy 132.153628 -293.802489) (xy 132.111007 -293.777882) (xy 132.072886 -293.746757) (xy 132.040251 -293.70992)
			(xy 132.013948 -293.668324) (xy 131.994657 -293.623048) (xy 131.98288 -293.575264) (xy 131.97892 -293.52621)
			(xy 131.649978 -293.52621) (xy 131.649483 -293.550817) (xy 131.641588 -293.599394) (xy 131.626004 -293.646075)
			(xy 131.603133 -293.689652) (xy 131.573568 -293.728996) (xy 131.538075 -293.763088) (xy 131.497572 -293.791044)
			(xy 131.45311 -293.812142) (xy 131.405839 -293.825834) (xy 131.356984 -293.831766) (xy 131.307809 -293.829785)
			(xy 131.25959 -293.819941) (xy 131.213574 -293.802489) (xy 131.170953 -293.777882) (xy 131.132832 -293.746757)
			(xy 131.100197 -293.70992) (xy 131.073894 -293.668324) (xy 131.054603 -293.623048) (xy 131.042826 -293.575264)
			(xy 131.038866 -293.52621) (xy 130.710178 -293.52621) (xy 130.709683 -293.550817) (xy 130.701788 -293.599394)
			(xy 130.686204 -293.646075) (xy 130.663333 -293.689652) (xy 130.633768 -293.728996) (xy 130.598275 -293.763088)
			(xy 130.557772 -293.791044) (xy 130.51331 -293.812142) (xy 130.466039 -293.825834) (xy 130.417184 -293.831766)
			(xy 130.368009 -293.829785) (xy 130.31979 -293.819941) (xy 130.273774 -293.802489) (xy 130.231153 -293.777882)
			(xy 130.193032 -293.746757) (xy 130.160397 -293.70992) (xy 130.134094 -293.668324) (xy 130.114803 -293.623048)
			(xy 130.103026 -293.575264) (xy 130.099066 -293.52621) (xy 129.770124 -293.52621) (xy 129.769629 -293.550817)
			(xy 129.761734 -293.599394) (xy 129.74615 -293.646075) (xy 129.723279 -293.689652) (xy 129.693714 -293.728996)
			(xy 129.658221 -293.763088) (xy 129.617718 -293.791044) (xy 129.573256 -293.812142) (xy 129.525985 -293.825834)
			(xy 129.47713 -293.831766) (xy 129.427955 -293.829785) (xy 129.379736 -293.819941) (xy 129.33372 -293.802489)
			(xy 129.291099 -293.777882) (xy 129.252978 -293.746757) (xy 129.220343 -293.70992) (xy 129.19404 -293.668324)
			(xy 129.174749 -293.623048) (xy 129.162972 -293.575264) (xy 129.159012 -293.52621) (xy 128.840484 -293.52621)
			(xy 128.839972 -293.551656) (xy 128.831808 -293.60189) (xy 128.815692 -293.650164) (xy 128.792041 -293.695227)
			(xy 128.761468 -293.735913) (xy 128.724764 -293.771168) (xy 128.68288 -293.800078) (xy 128.636901 -293.821895)
			(xy 128.588017 -293.836055) (xy 128.537496 -293.842189) (xy 128.486644 -293.84014) (xy 128.43678 -293.82996)
			(xy 128.389194 -293.811913) (xy 128.34512 -293.786467) (xy 128.305698 -293.75428) (xy 128.27195 -293.716186)
			(xy 128.244749 -293.673172) (xy 128.224801 -293.626352) (xy 128.212622 -293.576938) (xy 128.208527 -293.52621)
			(xy 128.0541 -293.52621) (xy 128.0541 -293.983918) (xy 128.054441 -293.993087) (xy 128.060824 -294.010274)
			(xy 128.066546 -294.017446) (xy 128.072388 -294.023796) (xy 128.08839 -294.032686) (xy 128.097788 -294.033956)
			(xy 128.121745 -294.037828) (xy 128.168107 -294.052161) (xy 128.211618 -294.073648) (xy 128.251181 -294.101747)
			(xy 128.2858 -294.135753) (xy 128.314604 -294.174806) (xy 128.336867 -294.217925) (xy 128.352027 -294.264023)
			(xy 128.359704 -294.311939) (xy 128.359704 -294.336216) (xy 128.688858 -294.336216) (xy 128.692818 -294.287162)
			(xy 128.704595 -294.239378) (xy 128.723886 -294.194102) (xy 128.750189 -294.152506) (xy 128.782824 -294.115669)
			(xy 128.820945 -294.084544) (xy 128.863566 -294.059937) (xy 128.909582 -294.042485) (xy 128.957801 -294.032641)
			(xy 129.006976 -294.03066) (xy 129.055831 -294.036592) (xy 129.103102 -294.050284) (xy 129.147564 -294.071382)
			(xy 129.188067 -294.099338) (xy 129.22356 -294.13343) (xy 129.253125 -294.172774) (xy 129.275996 -294.216351)
			(xy 129.29158 -294.263032) (xy 129.299475 -294.311609) (xy 129.29997 -294.336216) (xy 129.628912 -294.336216)
			(xy 129.632872 -294.287162) (xy 129.644649 -294.239378) (xy 129.66394 -294.194102) (xy 129.690243 -294.152506)
			(xy 129.722878 -294.115669) (xy 129.760999 -294.084544) (xy 129.80362 -294.059937) (xy 129.849636 -294.042485)
			(xy 129.897855 -294.032641) (xy 129.94703 -294.03066) (xy 129.995885 -294.036592) (xy 130.043156 -294.050284)
			(xy 130.087618 -294.071382) (xy 130.128121 -294.099338) (xy 130.163614 -294.13343) (xy 130.193179 -294.172774)
			(xy 130.21605 -294.216351) (xy 130.231634 -294.263032) (xy 130.239529 -294.311609) (xy 130.240024 -294.336216)
			(xy 130.568966 -294.336216) (xy 130.572926 -294.287162) (xy 130.584703 -294.239378) (xy 130.603994 -294.194102)
			(xy 130.630297 -294.152506) (xy 130.662932 -294.115669) (xy 130.701053 -294.084544) (xy 130.743674 -294.059937)
			(xy 130.78969 -294.042485) (xy 130.837909 -294.032641) (xy 130.887084 -294.03066) (xy 130.935939 -294.036592)
			(xy 130.98321 -294.050284) (xy 131.027672 -294.071382) (xy 131.068175 -294.099338) (xy 131.103668 -294.13343)
			(xy 131.133233 -294.172774) (xy 131.156104 -294.216351) (xy 131.171688 -294.263032) (xy 131.179583 -294.311609)
			(xy 131.180078 -294.336216) (xy 131.50902 -294.336216) (xy 131.51298 -294.287162) (xy 131.524757 -294.239378)
			(xy 131.544048 -294.194102) (xy 131.570351 -294.152506) (xy 131.602986 -294.115669) (xy 131.641107 -294.084544)
			(xy 131.683728 -294.059937) (xy 131.729744 -294.042485) (xy 131.777963 -294.032641) (xy 131.827138 -294.03066)
			(xy 131.875993 -294.036592) (xy 131.923264 -294.050284) (xy 131.967726 -294.071382) (xy 132.008229 -294.099338)
			(xy 132.043722 -294.13343) (xy 132.073287 -294.172774) (xy 132.096158 -294.216351) (xy 132.111742 -294.263032)
			(xy 132.119637 -294.311609) (xy 132.120132 -294.336216) (xy 132.449074 -294.336216) (xy 132.453034 -294.287162)
			(xy 132.464811 -294.239378) (xy 132.484102 -294.194102) (xy 132.510405 -294.152506) (xy 132.54304 -294.115669)
			(xy 132.581161 -294.084544) (xy 132.623782 -294.059937) (xy 132.669798 -294.042485) (xy 132.718017 -294.032641)
			(xy 132.767192 -294.03066) (xy 132.816047 -294.036592) (xy 132.863318 -294.050284) (xy 132.90778 -294.071382)
			(xy 132.948283 -294.099338) (xy 132.983776 -294.13343) (xy 133.013341 -294.172774) (xy 133.036212 -294.216351)
			(xy 133.051796 -294.263032) (xy 133.059691 -294.311609) (xy 133.060186 -294.336216) (xy 133.388874 -294.336216)
			(xy 133.392834 -294.287162) (xy 133.404611 -294.239378) (xy 133.423902 -294.194102) (xy 133.450205 -294.152506)
			(xy 133.48284 -294.115669) (xy 133.520961 -294.084544) (xy 133.563582 -294.059937) (xy 133.609598 -294.042485)
			(xy 133.657817 -294.032641) (xy 133.706992 -294.03066) (xy 133.755847 -294.036592) (xy 133.803118 -294.050284)
			(xy 133.84758 -294.071382) (xy 133.888083 -294.099338) (xy 133.923576 -294.13343) (xy 133.953141 -294.172774)
			(xy 133.976012 -294.216351) (xy 133.991596 -294.263032) (xy 133.999491 -294.311609) (xy 133.999986 -294.336216)
			(xy 133.999491 -294.360823) (xy 133.991596 -294.4094) (xy 133.976012 -294.456081) (xy 133.953141 -294.499658)
			(xy 133.923576 -294.539002) (xy 133.888083 -294.573094) (xy 133.84758 -294.60105) (xy 133.803118 -294.622148)
			(xy 133.755847 -294.63584) (xy 133.706992 -294.641772) (xy 133.657817 -294.639791) (xy 133.609598 -294.629947)
			(xy 133.563582 -294.612495) (xy 133.520961 -294.587888) (xy 133.48284 -294.556763) (xy 133.450205 -294.519926)
			(xy 133.423902 -294.47833) (xy 133.404611 -294.433054) (xy 133.392834 -294.38527) (xy 133.388874 -294.336216)
			(xy 133.060186 -294.336216) (xy 133.059691 -294.360823) (xy 133.051796 -294.4094) (xy 133.036212 -294.456081)
			(xy 133.013341 -294.499658) (xy 132.983776 -294.539002) (xy 132.948283 -294.573094) (xy 132.90778 -294.60105)
			(xy 132.863318 -294.622148) (xy 132.816047 -294.63584) (xy 132.767192 -294.641772) (xy 132.718017 -294.639791)
			(xy 132.669798 -294.629947) (xy 132.623782 -294.612495) (xy 132.581161 -294.587888) (xy 132.54304 -294.556763)
			(xy 132.510405 -294.519926) (xy 132.484102 -294.47833) (xy 132.464811 -294.433054) (xy 132.453034 -294.38527)
			(xy 132.449074 -294.336216) (xy 132.120132 -294.336216) (xy 132.119637 -294.360823) (xy 132.111742 -294.4094)
			(xy 132.096158 -294.456081) (xy 132.073287 -294.499658) (xy 132.043722 -294.539002) (xy 132.008229 -294.573094)
			(xy 131.967726 -294.60105) (xy 131.923264 -294.622148) (xy 131.875993 -294.63584) (xy 131.827138 -294.641772)
			(xy 131.777963 -294.639791) (xy 131.729744 -294.629947) (xy 131.683728 -294.612495) (xy 131.641107 -294.587888)
			(xy 131.602986 -294.556763) (xy 131.570351 -294.519926) (xy 131.544048 -294.47833) (xy 131.524757 -294.433054)
			(xy 131.51298 -294.38527) (xy 131.50902 -294.336216) (xy 131.180078 -294.336216) (xy 131.179583 -294.360823)
			(xy 131.171688 -294.4094) (xy 131.156104 -294.456081) (xy 131.133233 -294.499658) (xy 131.103668 -294.539002)
			(xy 131.068175 -294.573094) (xy 131.027672 -294.60105) (xy 130.98321 -294.622148) (xy 130.935939 -294.63584)
			(xy 130.887084 -294.641772) (xy 130.837909 -294.639791) (xy 130.78969 -294.629947) (xy 130.743674 -294.612495)
			(xy 130.701053 -294.587888) (xy 130.662932 -294.556763) (xy 130.630297 -294.519926) (xy 130.603994 -294.47833)
			(xy 130.584703 -294.433054) (xy 130.572926 -294.38527) (xy 130.568966 -294.336216) (xy 130.240024 -294.336216)
			(xy 130.239529 -294.360823) (xy 130.231634 -294.4094) (xy 130.21605 -294.456081) (xy 130.193179 -294.499658)
			(xy 130.163614 -294.539002) (xy 130.128121 -294.573094) (xy 130.087618 -294.60105) (xy 130.043156 -294.622148)
			(xy 129.995885 -294.63584) (xy 129.94703 -294.641772) (xy 129.897855 -294.639791) (xy 129.849636 -294.629947)
			(xy 129.80362 -294.612495) (xy 129.760999 -294.587888) (xy 129.722878 -294.556763) (xy 129.690243 -294.519926)
			(xy 129.66394 -294.47833) (xy 129.644649 -294.433054) (xy 129.632872 -294.38527) (xy 129.628912 -294.336216)
			(xy 129.29997 -294.336216) (xy 129.299475 -294.360823) (xy 129.29158 -294.4094) (xy 129.275996 -294.456081)
			(xy 129.253125 -294.499658) (xy 129.22356 -294.539002) (xy 129.188067 -294.573094) (xy 129.147564 -294.60105)
			(xy 129.103102 -294.622148) (xy 129.055831 -294.63584) (xy 129.006976 -294.641772) (xy 128.957801 -294.639791)
			(xy 128.909582 -294.629947) (xy 128.863566 -294.612495) (xy 128.820945 -294.587888) (xy 128.782824 -294.556763)
			(xy 128.750189 -294.519926) (xy 128.723886 -294.47833) (xy 128.704595 -294.433054) (xy 128.692818 -294.38527)
			(xy 128.688858 -294.336216) (xy 128.359704 -294.336216) (xy 128.359704 -294.360466) (xy 128.352026 -294.408381)
			(xy 128.336865 -294.454479) (xy 128.314602 -294.497598) (xy 128.285797 -294.536651) (xy 128.251177 -294.570655)
			(xy 128.211614 -294.598755) (xy 128.168103 -294.620241) (xy 128.121741 -294.634573) (xy 128.097788 -294.638476)
			(xy 128.09728 -294.638476) (xy 128.088366 -294.640145) (xy 128.072476 -294.648861) (xy 128.066292 -294.655494)
			(xy 128.06045 -294.662098) (xy 128.0541 -294.679116) (xy 128.0541 -295.053258) (xy 128.055116 -295.06291)
			(xy 128.056738 -295.070157) (xy 128.06357 -295.083335) (xy 128.068578 -295.088818) (xy 128.133856 -295.154096)
			(xy 128.141048 -295.160621) (xy 128.158911 -295.168195) (xy 128.178309 -295.168614) (xy 128.196483 -295.161817)
			(xy 128.20396 -295.15562) (xy 128.20523 -295.15435) (xy 128.208585 -295.151028) (xy 128.214085 -295.143355)
			(xy 128.216152 -295.13911) (xy 128.219708 -295.131236) (xy 128.22047 -295.122092) (xy 128.222972 -295.096898)
			(xy 128.235253 -295.047784) (xy 128.255464 -295.001367) (xy 128.283054 -294.958919) (xy 128.317266 -294.921602)
			(xy 128.357164 -294.890437) (xy 128.401654 -294.866279) (xy 128.44952 -294.849789) (xy 128.499449 -294.841417)
			(xy 128.524762 -294.840914) (xy 128.548756 -294.841357) (xy 128.596155 -294.84886) (xy 128.641797 -294.863685)
			(xy 128.684556 -294.885469) (xy 128.723381 -294.913674) (xy 128.757316 -294.947606) (xy 128.785523 -294.98643)
			(xy 128.807309 -295.029189) (xy 128.822137 -295.074829) (xy 128.829641 -295.122228) (xy 128.83007 -295.146222)
			(xy 129.159012 -295.146222) (xy 129.162972 -295.097168) (xy 129.174749 -295.049384) (xy 129.19404 -295.004108)
			(xy 129.220343 -294.962512) (xy 129.252978 -294.925675) (xy 129.291099 -294.89455) (xy 129.33372 -294.869943)
			(xy 129.379736 -294.852491) (xy 129.427955 -294.842647) (xy 129.47713 -294.840666) (xy 129.525985 -294.846598)
			(xy 129.573256 -294.86029) (xy 129.617718 -294.881388) (xy 129.658221 -294.909344) (xy 129.693714 -294.943436)
			(xy 129.723279 -294.98278) (xy 129.74615 -295.026357) (xy 129.761734 -295.073038) (xy 129.769629 -295.121615)
			(xy 129.770124 -295.146222) (xy 130.099066 -295.146222) (xy 130.103026 -295.097168) (xy 130.114803 -295.049384)
			(xy 130.134094 -295.004108) (xy 130.160397 -294.962512) (xy 130.193032 -294.925675) (xy 130.231153 -294.89455)
			(xy 130.273774 -294.869943) (xy 130.31979 -294.852491) (xy 130.368009 -294.842647) (xy 130.417184 -294.840666)
			(xy 130.466039 -294.846598) (xy 130.51331 -294.86029) (xy 130.557772 -294.881388) (xy 130.598275 -294.909344)
			(xy 130.633768 -294.943436) (xy 130.663333 -294.98278) (xy 130.686204 -295.026357) (xy 130.701788 -295.073038)
			(xy 130.709683 -295.121615) (xy 130.710178 -295.146222) (xy 131.038866 -295.146222) (xy 131.042826 -295.097168)
			(xy 131.054603 -295.049384) (xy 131.073894 -295.004108) (xy 131.100197 -294.962512) (xy 131.132832 -294.925675)
			(xy 131.170953 -294.89455) (xy 131.213574 -294.869943) (xy 131.25959 -294.852491) (xy 131.307809 -294.842647)
			(xy 131.356984 -294.840666) (xy 131.405839 -294.846598) (xy 131.45311 -294.86029) (xy 131.497572 -294.881388)
			(xy 131.538075 -294.909344) (xy 131.573568 -294.943436) (xy 131.603133 -294.98278) (xy 131.626004 -295.026357)
			(xy 131.641588 -295.073038) (xy 131.649483 -295.121615) (xy 131.649978 -295.146222) (xy 131.97892 -295.146222)
			(xy 131.98288 -295.097168) (xy 131.994657 -295.049384) (xy 132.013948 -295.004108) (xy 132.040251 -294.962512)
			(xy 132.072886 -294.925675) (xy 132.111007 -294.89455) (xy 132.153628 -294.869943) (xy 132.199644 -294.852491)
			(xy 132.247863 -294.842647) (xy 132.297038 -294.840666) (xy 132.345893 -294.846598) (xy 132.393164 -294.86029)
			(xy 132.437626 -294.881388) (xy 132.478129 -294.909344) (xy 132.513622 -294.943436) (xy 132.543187 -294.98278)
			(xy 132.566058 -295.026357) (xy 132.581642 -295.073038) (xy 132.589537 -295.121615) (xy 132.590032 -295.146222)
			(xy 132.918974 -295.146222) (xy 132.922934 -295.097168) (xy 132.934711 -295.049384) (xy 132.954002 -295.004108)
			(xy 132.980305 -294.962512) (xy 133.01294 -294.925675) (xy 133.051061 -294.89455) (xy 133.093682 -294.869943)
			(xy 133.139698 -294.852491) (xy 133.187917 -294.842647) (xy 133.237092 -294.840666) (xy 133.285947 -294.846598)
			(xy 133.333218 -294.86029) (xy 133.37768 -294.881388) (xy 133.418183 -294.909344) (xy 133.453676 -294.943436)
			(xy 133.483241 -294.98278) (xy 133.506112 -295.026357) (xy 133.521696 -295.073038) (xy 133.529591 -295.121615)
			(xy 133.530086 -295.146222) (xy 133.859028 -295.146222) (xy 133.862988 -295.097168) (xy 133.874765 -295.049384)
			(xy 133.894056 -295.004108) (xy 133.920359 -294.962512) (xy 133.952994 -294.925675) (xy 133.991115 -294.89455)
			(xy 134.033736 -294.869943) (xy 134.079752 -294.852491) (xy 134.127971 -294.842647) (xy 134.177146 -294.840666)
			(xy 134.226001 -294.846598) (xy 134.273272 -294.86029) (xy 134.317734 -294.881388) (xy 134.358237 -294.909344)
			(xy 134.39373 -294.943436) (xy 134.423295 -294.98278) (xy 134.446166 -295.026357) (xy 134.46175 -295.073038)
			(xy 134.469645 -295.121615) (xy 134.47014 -295.146222) (xy 134.469645 -295.170829) (xy 134.46175 -295.219406)
			(xy 134.446166 -295.266087) (xy 134.423295 -295.309664) (xy 134.39373 -295.349008) (xy 134.358237 -295.3831)
			(xy 134.317734 -295.411056) (xy 134.273272 -295.432154) (xy 134.226001 -295.445846) (xy 134.177146 -295.451778)
			(xy 134.127971 -295.449797) (xy 134.079752 -295.439953) (xy 134.033736 -295.422501) (xy 133.991115 -295.397894)
			(xy 133.952994 -295.366769) (xy 133.920359 -295.329932) (xy 133.894056 -295.288336) (xy 133.874765 -295.24306)
			(xy 133.862988 -295.195276) (xy 133.859028 -295.146222) (xy 133.530086 -295.146222) (xy 133.529591 -295.170829)
			(xy 133.521696 -295.219406) (xy 133.506112 -295.266087) (xy 133.483241 -295.309664) (xy 133.453676 -295.349008)
			(xy 133.418183 -295.3831) (xy 133.37768 -295.411056) (xy 133.333218 -295.432154) (xy 133.285947 -295.445846)
			(xy 133.237092 -295.451778) (xy 133.187917 -295.449797) (xy 133.139698 -295.439953) (xy 133.093682 -295.422501)
			(xy 133.051061 -295.397894) (xy 133.01294 -295.366769) (xy 132.980305 -295.329932) (xy 132.954002 -295.288336)
			(xy 132.934711 -295.24306) (xy 132.922934 -295.195276) (xy 132.918974 -295.146222) (xy 132.590032 -295.146222)
			(xy 132.589537 -295.170829) (xy 132.581642 -295.219406) (xy 132.566058 -295.266087) (xy 132.543187 -295.309664)
			(xy 132.513622 -295.349008) (xy 132.478129 -295.3831) (xy 132.437626 -295.411056) (xy 132.393164 -295.432154)
			(xy 132.345893 -295.445846) (xy 132.297038 -295.451778) (xy 132.247863 -295.449797) (xy 132.199644 -295.439953)
			(xy 132.153628 -295.422501) (xy 132.111007 -295.397894) (xy 132.072886 -295.366769) (xy 132.040251 -295.329932)
			(xy 132.013948 -295.288336) (xy 131.994657 -295.24306) (xy 131.98288 -295.195276) (xy 131.97892 -295.146222)
			(xy 131.649978 -295.146222) (xy 131.649483 -295.170829) (xy 131.641588 -295.219406) (xy 131.626004 -295.266087)
			(xy 131.603133 -295.309664) (xy 131.573568 -295.349008) (xy 131.538075 -295.3831) (xy 131.497572 -295.411056)
			(xy 131.45311 -295.432154) (xy 131.405839 -295.445846) (xy 131.356984 -295.451778) (xy 131.307809 -295.449797)
			(xy 131.25959 -295.439953) (xy 131.213574 -295.422501) (xy 131.170953 -295.397894) (xy 131.132832 -295.366769)
			(xy 131.100197 -295.329932) (xy 131.073894 -295.288336) (xy 131.054603 -295.24306) (xy 131.042826 -295.195276)
			(xy 131.038866 -295.146222) (xy 130.710178 -295.146222) (xy 130.709683 -295.170829) (xy 130.701788 -295.219406)
			(xy 130.686204 -295.266087) (xy 130.663333 -295.309664) (xy 130.633768 -295.349008) (xy 130.598275 -295.3831)
			(xy 130.557772 -295.411056) (xy 130.51331 -295.432154) (xy 130.466039 -295.445846) (xy 130.417184 -295.451778)
			(xy 130.368009 -295.449797) (xy 130.31979 -295.439953) (xy 130.273774 -295.422501) (xy 130.231153 -295.397894)
			(xy 130.193032 -295.366769) (xy 130.160397 -295.329932) (xy 130.134094 -295.288336) (xy 130.114803 -295.24306)
			(xy 130.103026 -295.195276) (xy 130.099066 -295.146222) (xy 129.770124 -295.146222) (xy 129.769629 -295.170829)
			(xy 129.761734 -295.219406) (xy 129.74615 -295.266087) (xy 129.723279 -295.309664) (xy 129.693714 -295.349008)
			(xy 129.658221 -295.3831) (xy 129.617718 -295.411056) (xy 129.573256 -295.432154) (xy 129.525985 -295.445846)
			(xy 129.47713 -295.451778) (xy 129.427955 -295.449797) (xy 129.379736 -295.439953) (xy 129.33372 -295.422501)
			(xy 129.291099 -295.397894) (xy 129.252978 -295.366769) (xy 129.220343 -295.329932) (xy 129.19404 -295.288336)
			(xy 129.174749 -295.24306) (xy 129.162972 -295.195276) (xy 129.159012 -295.146222) (xy 128.83007 -295.146222)
			(xy 128.829616 -295.16999) (xy 128.822249 -295.216953) (xy 128.807695 -295.262208) (xy 128.786307 -295.304661)
			(xy 128.758601 -295.34329) (xy 128.725245 -295.377159) (xy 128.687046 -295.405453) (xy 128.644924 -295.427488)
			(xy 128.622552 -295.435528) (xy 128.622298 -295.435528) (xy 128.616241 -295.437769) (xy 128.605443 -295.444847)
			(xy 128.600962 -295.449498) (xy 128.596644 -295.454324) (xy 128.590802 -295.4655) (xy 128.571752 -295.547288)
			(xy 128.569466 -295.55694) (xy 128.568704 -295.561004) (xy 128.56845 -295.564814) (xy 128.568367 -295.573575)
			(xy 128.573429 -295.590336) (xy 128.578356 -295.59758) (xy 128.583182 -295.603422) (xy 128.699006 -295.719246)
			(xy 128.706258 -295.725818) (xy 128.724288 -295.733383) (xy 128.734058 -295.733978) (xy 128.764792 -295.734486)
			(xy 128.773914 -295.73424) (xy 128.791089 -295.728115) (xy 128.79832 -295.722548) (xy 128.819086 -295.705775)
			(xy 128.865272 -295.679019) (xy 128.915412 -295.660717) (xy 128.967974 -295.651429) (xy 128.994662 -295.65092)
			(xy 129.018656 -295.651363) (xy 129.066055 -295.658866) (xy 129.111696 -295.673691) (xy 129.154455 -295.695475)
			(xy 129.19328 -295.72368) (xy 129.227213 -295.757613) (xy 129.25542 -295.796436) (xy 129.277205 -295.839195)
			(xy 129.292032 -295.884836) (xy 129.299536 -295.932234) (xy 129.29997 -295.956228) (xy 129.628912 -295.956228)
			(xy 129.632872 -295.907174) (xy 129.644649 -295.85939) (xy 129.66394 -295.814114) (xy 129.690243 -295.772518)
			(xy 129.722878 -295.735681) (xy 129.760999 -295.704556) (xy 129.80362 -295.679949) (xy 129.849636 -295.662497)
			(xy 129.897855 -295.652653) (xy 129.94703 -295.650672) (xy 129.995885 -295.656604) (xy 130.043156 -295.670296)
			(xy 130.087618 -295.691394) (xy 130.128121 -295.71935) (xy 130.163614 -295.753442) (xy 130.193179 -295.792786)
			(xy 130.21605 -295.836363) (xy 130.231634 -295.883044) (xy 130.239529 -295.931621) (xy 130.240024 -295.956228)
			(xy 130.239529 -295.980835) (xy 130.237718 -295.991975) (xy 130.572409 -295.991975) (xy 130.575097 -295.942413)
			(xy 130.585767 -295.893939) (xy 130.604139 -295.847829) (xy 130.629728 -295.805299) (xy 130.66186 -295.767469)
			(xy 130.699689 -295.735335) (xy 130.742219 -295.709744) (xy 130.788327 -295.691371) (xy 130.836801 -295.680699)
			(xy 130.886363 -295.678009) (xy 130.935707 -295.683372) (xy 130.983534 -295.696647) (xy 131.028583 -295.717485)
			(xy 131.069667 -295.745336) (xy 131.105705 -295.779467) (xy 131.135747 -295.818977) (xy 131.159001 -295.862828)
			(xy 131.174855 -295.909863) (xy 131.182891 -295.958843) (xy 131.18338 -295.98366) (xy 131.183198 -295.997843)
			(xy 131.18053 -296.026083) (xy 131.178046 -296.040048) (xy 131.17576 -296.05224) (xy 131.182872 -296.075608)
			(xy 131.249166 -296.144188) (xy 131.258167 -296.152402) (xy 131.281238 -296.160114) (xy 131.293362 -296.15892)
			(xy 131.293616 -296.15892) (xy 131.307122 -296.156993) (xy 131.33433 -296.154955) (xy 131.347972 -296.154856)
			(xy 131.361682 -296.155013) (xy 131.389018 -296.157171) (xy 131.402582 -296.159174) (xy 131.402836 -296.159174)
			(xy 131.414835 -296.160272) (xy 131.437636 -296.152579) (xy 131.446524 -296.144442) (xy 131.513326 -296.075608)
			(xy 131.520438 -296.05224) (xy 131.518152 -296.040048) (xy 131.515673 -296.026083) (xy 131.513003 -295.997843)
			(xy 131.512818 -295.98366) (xy 131.51334 -295.958405) (xy 131.521653 -295.908583) (xy 131.538054 -295.860809)
			(xy 131.562095 -295.816386) (xy 131.593119 -295.776526) (xy 131.630281 -295.742316) (xy 131.672567 -295.71469)
			(xy 131.718823 -295.6944) (xy 131.767788 -295.682) (xy 131.818126 -295.677829) (xy 131.868464 -295.682)
			(xy 131.917429 -295.6944) (xy 131.963685 -295.71469) (xy 132.005971 -295.742316) (xy 132.043133 -295.776526)
			(xy 132.074157 -295.816386) (xy 132.098198 -295.860809) (xy 132.114599 -295.908583) (xy 132.122912 -295.958405)
			(xy 132.123434 -295.98366) (xy 132.123249 -295.997779) (xy 132.120576 -296.025892) (xy 132.1181 -296.039794)
			(xy 132.116558 -296.051904) (xy 132.123597 -296.075245) (xy 132.131562 -296.084498) (xy 132.197856 -296.153078)
			(xy 132.22097 -296.160952) (xy 132.233416 -296.15892) (xy 132.246922 -296.156993) (xy 132.27413 -296.154955)
			(xy 132.287772 -296.154856) (xy 132.301546 -296.154995) (xy 132.329009 -296.157158) (xy 132.342636 -296.159174)
			(xy 132.355082 -296.161206) (xy 132.378196 -296.153332) (xy 132.45338 -296.075862) (xy 132.460492 -296.052494)
			(xy 132.458206 -296.040048) (xy 132.455726 -296.026083) (xy 132.453057 -295.997843) (xy 132.452872 -295.98366)
			(xy 132.453421 -295.958843) (xy 132.461457 -295.909863) (xy 132.477312 -295.862829) (xy 132.500566 -295.818979)
			(xy 132.530609 -295.779469) (xy 132.566647 -295.74534) (xy 132.607732 -295.71749) (xy 132.652782 -295.696654)
			(xy 132.700609 -295.683381) (xy 132.749953 -295.67802) (xy 132.799514 -295.680713) (xy 132.847987 -295.691388)
			(xy 132.894095 -295.709764) (xy 132.936622 -295.735358) (xy 132.974448 -295.767494) (xy 133.006577 -295.805327)
			(xy 133.032162 -295.847859) (xy 133.05053 -295.89397) (xy 133.061195 -295.942445) (xy 133.063877 -295.991981)
			(xy 133.392301 -295.991981) (xy 133.394988 -295.942417) (xy 133.405658 -295.893941) (xy 133.42403 -295.84783)
			(xy 133.449619 -295.805298) (xy 133.481752 -295.767466) (xy 133.519582 -295.735331) (xy 133.562112 -295.709739)
			(xy 133.608222 -295.691364) (xy 133.656697 -295.680691) (xy 133.706261 -295.678001) (xy 133.755607 -295.683364)
			(xy 133.803435 -295.696639) (xy 133.848485 -295.717477) (xy 133.889571 -295.745329) (xy 133.92561 -295.77946)
			(xy 133.955653 -295.818972) (xy 133.978908 -295.862824) (xy 133.994763 -295.90986) (xy 134.002799 -295.958842)
			(xy 134.003288 -295.98366) (xy 134.003106 -295.997843) (xy 134.000438 -296.026083) (xy 133.997954 -296.040048)
			(xy 133.995668 -296.05224) (xy 134.00278 -296.075608) (xy 134.069074 -296.144188) (xy 134.078072 -296.152406)
			(xy 134.101145 -296.160116) (xy 134.11327 -296.15892) (xy 134.113524 -296.15892) (xy 134.12703 -296.156992)
			(xy 134.154238 -296.154955) (xy 134.16788 -296.154856) (xy 134.18159 -296.155012) (xy 134.208926 -296.157171)
			(xy 134.22249 -296.159174) (xy 134.222744 -296.159174) (xy 134.234743 -296.160277) (xy 134.257544 -296.15258)
			(xy 134.266432 -296.144442) (xy 134.333234 -296.075608) (xy 134.340346 -296.05224) (xy 134.33806 -296.040048)
			(xy 134.335581 -296.026083) (xy 134.332911 -295.997843) (xy 134.332726 -295.98366) (xy 134.333248 -295.958405)
			(xy 134.341561 -295.908583) (xy 134.357962 -295.860809) (xy 134.382003 -295.816386) (xy 134.413027 -295.776526)
			(xy 134.450189 -295.742316) (xy 134.492475 -295.71469) (xy 134.538731 -295.6944) (xy 134.587696 -295.682)
			(xy 134.638034 -295.677829) (xy 134.688372 -295.682) (xy 134.737337 -295.6944) (xy 134.783593 -295.71469)
			(xy 134.825879 -295.742316) (xy 134.863041 -295.776526) (xy 134.894065 -295.816386) (xy 134.918106 -295.860809)
			(xy 134.934507 -295.908583) (xy 134.94282 -295.958405) (xy 134.943342 -295.98366) (xy 134.943159 -295.997843)
			(xy 134.940491 -296.026083) (xy 134.938008 -296.040048) (xy 134.935722 -296.05224) (xy 134.942834 -296.075608)
			(xy 135.009128 -296.144188) (xy 135.018103 -296.152436) (xy 135.041194 -296.160129) (xy 135.053324 -296.15892)
			(xy 135.053578 -296.15892) (xy 135.067083 -296.156986) (xy 135.094292 -296.154953) (xy 135.107934 -296.154856)
			(xy 135.121644 -296.155006) (xy 135.14898 -296.157169) (xy 135.162544 -296.159174) (xy 135.162798 -296.159174)
			(xy 135.174798 -296.160247) (xy 135.197596 -296.152571) (xy 135.206486 -296.144442) (xy 135.273288 -296.075608)
			(xy 135.2804 -296.05224) (xy 135.278114 -296.040048) (xy 135.275634 -296.026083) (xy 135.272965 -295.997843)
			(xy 135.27278 -295.98366) (xy 135.273321 -295.958843) (xy 135.281357 -295.909864) (xy 135.297211 -295.862829)
			(xy 135.320466 -295.81898) (xy 135.350508 -295.77947) (xy 135.386546 -295.745341) (xy 135.427631 -295.717491)
			(xy 135.47268 -295.696655) (xy 135.520506 -295.683382) (xy 135.56985 -295.67802) (xy 135.619411 -295.680712)
			(xy 135.667884 -295.691387) (xy 135.713992 -295.709763) (xy 135.756519 -295.735356) (xy 135.794345 -295.767492)
			(xy 135.826475 -295.805324) (xy 135.85206 -295.847855) (xy 135.870428 -295.893966) (xy 135.881095 -295.94244)
			(xy 135.883778 -295.992002) (xy 135.878409 -296.041345) (xy 135.865127 -296.089169) (xy 135.844283 -296.134215)
			(xy 135.816427 -296.175295) (xy 135.782291 -296.211327) (xy 135.742776 -296.241362) (xy 135.698923 -296.264609)
			(xy 135.651886 -296.280455) (xy 135.602905 -296.288483) (xy 135.578088 -296.288968) (xy 135.556498 -296.288206)
			(xy 135.544365 -296.288067) (xy 135.522094 -296.297613) (xy 135.513826 -296.306494) (xy 135.45312 -296.380408)
			(xy 135.44804 -296.404538) (xy 135.451342 -296.416476) (xy 135.457257 -296.439521) (xy 135.463629 -296.486668)
			(xy 135.464042 -296.510456) (xy 135.464042 -296.510964) (xy 135.463544 -296.537613) (xy 135.455601 -296.590317)
			(xy 135.439891 -296.641247) (xy 135.416765 -296.689268) (xy 135.386741 -296.733305) (xy 135.350489 -296.772376)
			(xy 135.308818 -296.805607) (xy 135.26266 -296.832256) (xy 135.213046 -296.851728) (xy 135.161084 -296.863588)
			(xy 135.107934 -296.867572) (xy 135.054784 -296.863588) (xy 135.002822 -296.851728) (xy 134.953208 -296.832256)
			(xy 134.90705 -296.805607) (xy 134.865379 -296.772376) (xy 134.829127 -296.733305) (xy 134.799103 -296.689268)
			(xy 134.775977 -296.641247) (xy 134.760267 -296.590317) (xy 134.752324 -296.537613) (xy 134.751826 -296.510964)
			(xy 134.751826 -296.510456) (xy 134.752235 -296.486668) (xy 134.758611 -296.439521) (xy 134.764526 -296.416476)
			(xy 134.767828 -296.404538) (xy 134.762748 -296.380154) (xy 134.702296 -296.306748) (xy 134.694076 -296.29778)
			(xy 134.67179 -296.288107) (xy 134.659624 -296.288206) (xy 134.65937 -296.288206) (xy 134.638034 -296.288968)
			(xy 134.616444 -296.288206) (xy 134.604309 -296.288034) (xy 134.582036 -296.297603) (xy 134.573772 -296.306494)
			(xy 134.513066 -296.380408) (xy 134.507986 -296.404538) (xy 134.511288 -296.416476) (xy 134.517202 -296.439521)
			(xy 134.523574 -296.486668) (xy 134.523988 -296.510456) (xy 134.523988 -296.510964) (xy 134.52349 -296.537613)
			(xy 134.515547 -296.590317) (xy 134.499837 -296.641247) (xy 134.476711 -296.689268) (xy 134.446687 -296.733305)
			(xy 134.410435 -296.772376) (xy 134.368764 -296.805607) (xy 134.322606 -296.832256) (xy 134.272992 -296.851728)
			(xy 134.22103 -296.863588) (xy 134.16788 -296.867572) (xy 134.11473 -296.863588) (xy 134.062768 -296.851728)
			(xy 134.013154 -296.832256) (xy 133.966996 -296.805607) (xy 133.925325 -296.772376) (xy 133.889073 -296.733305)
			(xy 133.859049 -296.689268) (xy 133.835923 -296.641247) (xy 133.820213 -296.590317) (xy 133.81227 -296.537613)
			(xy 133.811772 -296.510964) (xy 133.811772 -296.510456) (xy 133.812183 -296.486668) (xy 133.818558 -296.439521)
			(xy 133.824472 -296.416476) (xy 133.827774 -296.404538) (xy 133.822694 -296.380154) (xy 133.762242 -296.306748)
			(xy 133.754002 -296.297802) (xy 133.731731 -296.288117) (xy 133.71957 -296.288206) (xy 133.719316 -296.288206)
			(xy 133.69798 -296.288968) (xy 133.673162 -296.288501) (xy 133.62418 -296.280467) (xy 133.577143 -296.264616)
			(xy 133.533289 -296.241364) (xy 133.493775 -296.211324) (xy 133.459641 -296.175287) (xy 133.431787 -296.134203)
			(xy 133.410946 -296.089154) (xy 133.397668 -296.041326) (xy 133.392301 -295.991981) (xy 133.063877 -295.991981)
			(xy 133.063878 -295.992007) (xy 133.058507 -296.04135) (xy 133.045225 -296.089175) (xy 133.02438 -296.13422)
			(xy 132.996523 -296.1753) (xy 132.962386 -296.211332) (xy 132.92287 -296.241366) (xy 132.879016 -296.264612)
			(xy 132.831979 -296.280457) (xy 132.782997 -296.288484) (xy 132.75818 -296.288968) (xy 132.736336 -296.288206)
			(xy 132.7242 -296.288029) (xy 132.701928 -296.297601) (xy 132.693664 -296.306494) (xy 132.632958 -296.380408)
			(xy 132.627878 -296.404538) (xy 132.63118 -296.416476) (xy 132.637093 -296.439521) (xy 132.643466 -296.486668)
			(xy 132.64388 -296.510456) (xy 132.64388 -296.510964) (xy 132.643382 -296.537613) (xy 132.635439 -296.590317)
			(xy 132.619729 -296.641247) (xy 132.596603 -296.689268) (xy 132.566579 -296.733305) (xy 132.530327 -296.772376)
			(xy 132.488656 -296.805607) (xy 132.442498 -296.832256) (xy 132.392884 -296.851728) (xy 132.340922 -296.863588)
			(xy 132.287772 -296.867572) (xy 132.234622 -296.863588) (xy 132.18266 -296.851728) (xy 132.133046 -296.832256)
			(xy 132.086888 -296.805607) (xy 132.045217 -296.772376) (xy 132.008965 -296.733305) (xy 131.978941 -296.689268)
			(xy 131.955815 -296.641247) (xy 131.940105 -296.590317) (xy 131.932162 -296.537613) (xy 131.931664 -296.510964)
			(xy 131.931664 -296.510456) (xy 131.932075 -296.486668) (xy 131.93845 -296.439521) (xy 131.944364 -296.416476)
			(xy 131.947666 -296.404538) (xy 131.942586 -296.380154) (xy 131.87426 -296.297096) (xy 131.851908 -296.287444)
			(xy 131.839462 -296.288206) (xy 131.818126 -296.288968) (xy 131.796536 -296.288206) (xy 131.7844 -296.288029)
			(xy 131.762128 -296.297601) (xy 131.753864 -296.306494) (xy 131.693158 -296.380408) (xy 131.688078 -296.404538)
			(xy 131.69138 -296.416476) (xy 131.697293 -296.439521) (xy 131.703666 -296.486668) (xy 131.70408 -296.510456)
			(xy 131.70408 -296.510964) (xy 131.703582 -296.537613) (xy 131.695639 -296.590317) (xy 131.679929 -296.641247)
			(xy 131.656803 -296.689268) (xy 131.626779 -296.733305) (xy 131.590527 -296.772376) (xy 131.548856 -296.805607)
			(xy 131.502698 -296.832256) (xy 131.453084 -296.851728) (xy 131.401122 -296.863588) (xy 131.347972 -296.867572)
			(xy 131.294822 -296.863588) (xy 131.24286 -296.851728) (xy 131.193246 -296.832256) (xy 131.147088 -296.805607)
			(xy 131.105417 -296.772376) (xy 131.069165 -296.733305) (xy 131.039141 -296.689268) (xy 131.016015 -296.641247)
			(xy 131.000305 -296.590317) (xy 130.992362 -296.537613) (xy 130.991864 -296.510964) (xy 130.991864 -296.510456)
			(xy 130.992275 -296.486668) (xy 130.99865 -296.439521) (xy 131.004564 -296.416476) (xy 131.007866 -296.404538)
			(xy 131.002786 -296.380154) (xy 130.942334 -296.306748) (xy 130.934097 -296.297798) (xy 130.911824 -296.288115)
			(xy 130.899662 -296.288206) (xy 130.899408 -296.288206) (xy 130.878072 -296.288968) (xy 130.853255 -296.288492)
			(xy 130.804274 -296.280458) (xy 130.757239 -296.264606) (xy 130.713388 -296.241353) (xy 130.673875 -296.211313)
			(xy 130.639744 -296.175277) (xy 130.611891 -296.134193) (xy 130.591052 -296.089145) (xy 130.577774 -296.041319)
			(xy 130.572409 -295.991975) (xy 130.237718 -295.991975) (xy 130.231634 -296.029412) (xy 130.21605 -296.076093)
			(xy 130.193179 -296.11967) (xy 130.163614 -296.159014) (xy 130.128121 -296.193106) (xy 130.087618 -296.221062)
			(xy 130.043156 -296.24216) (xy 129.995885 -296.255852) (xy 129.94703 -296.261784) (xy 129.897855 -296.259803)
			(xy 129.849636 -296.249959) (xy 129.80362 -296.232507) (xy 129.760999 -296.2079) (xy 129.722878 -296.176775)
			(xy 129.690243 -296.139938) (xy 129.66394 -296.098342) (xy 129.644649 -296.053066) (xy 129.632872 -296.005282)
			(xy 129.628912 -295.956228) (xy 129.29997 -295.956228) (xy 129.299417 -295.982914) (xy 129.290129 -296.03547)
			(xy 129.271842 -296.085611) (xy 129.245113 -296.131806) (xy 129.228342 -296.15257) (xy 129.222753 -296.159787)
			(xy 129.216642 -296.176972) (xy 129.216404 -296.186098) (xy 129.216912 -296.216832) (xy 129.217508 -296.226598)
			(xy 129.22509 -296.244618) (xy 129.231644 -296.251884) (xy 129.831338 -296.851578) (xy 129.835148 -296.855896)
			(xy 135.786876 -304.378868) (xy 135.789924 -304.383186) (xy 139.053717 -309.521352) (xy 146.640802 -309.521352)
			(xy 146.644873 -309.46573) (xy 146.656999 -309.411293) (xy 146.676922 -309.359202) (xy 146.704218 -309.310567)
			(xy 146.738304 -309.266424) (xy 146.778453 -309.227715) (xy 146.823811 -309.195264) (xy 146.873411 -309.169763)
			(xy 146.926195 -309.151756) (xy 146.981038 -309.141626) (xy 147.036772 -309.139589) (xy 147.092209 -309.145689)
			(xy 147.146166 -309.159795) (xy 147.197495 -309.181607) (xy 147.245101 -309.210661) (xy 147.287969 -309.246336)
			(xy 147.325186 -309.287873) (xy 147.355959 -309.334386) (xy 147.379631 -309.384883) (xy 147.395699 -309.43829)
			(xy 147.403819 -309.493466) (xy 147.404328 -309.521352) (xy 147.403819 -309.549238) (xy 147.395699 -309.604414)
			(xy 147.379631 -309.657821) (xy 147.355959 -309.708318) (xy 147.325186 -309.754831) (xy 147.287969 -309.796368)
			(xy 147.245101 -309.832043) (xy 147.197495 -309.861097) (xy 147.146166 -309.882909) (xy 147.092209 -309.897015)
			(xy 147.036772 -309.903115) (xy 146.981038 -309.901078) (xy 146.926195 -309.890948) (xy 146.873411 -309.872941)
			(xy 146.823811 -309.84744) (xy 146.778453 -309.814989) (xy 146.738304 -309.77628) (xy 146.704218 -309.732137)
			(xy 146.676922 -309.683502) (xy 146.656999 -309.631411) (xy 146.644873 -309.576974) (xy 146.640802 -309.521352)
			(xy 139.053717 -309.521352) (xy 140.046456 -311.084214) (xy 140.04925 -311.08904) (xy 140.227335 -311.452277)
			(xy 141.398437 -311.452277) (xy 141.401049 -311.389254) (xy 141.411437 -311.327038) (xy 141.42944 -311.266584)
			(xy 141.454783 -311.208822) (xy 141.487075 -311.154638) (xy 141.525822 -311.104864) (xy 141.570429 -311.060265)
			(xy 141.620209 -311.021527) (xy 141.674398 -310.989243) (xy 141.732165 -310.96391) (xy 141.792621 -310.945917)
			(xy 141.854839 -310.93554) (xy 141.917863 -310.932939) (xy 141.980724 -310.938153) (xy 142.042458 -310.951103)
			(xy 142.102116 -310.97159) (xy 142.158781 -310.999298) (xy 142.211584 -311.033803) (xy 142.259714 -311.074574)
			(xy 142.302431 -311.120985) (xy 142.339079 -311.172323) (xy 142.369096 -311.227801) (xy 142.39202 -311.286565)
			(xy 142.407499 -311.347714) (xy 142.415295 -311.410307) (xy 142.415768 -311.441846) (xy 142.415768 -311.443878)
			(xy 142.416312 -311.454573) (xy 142.424982 -311.474128) (xy 142.432532 -311.481724) (xy 142.49654 -311.539636)
			(xy 142.517368 -311.546494) (xy 142.528036 -311.545224) (xy 142.541459 -311.543907) (xy 142.568397 -311.542508)
			(xy 142.581884 -311.54243) (xy 142.612617 -311.542853) (xy 142.673636 -311.55026) (xy 142.733316 -311.564969)
			(xy 142.790789 -311.586765) (xy 142.845214 -311.61533) (xy 142.8958 -311.650248) (xy 142.941807 -311.691008)
			(xy 142.982566 -311.737017) (xy 143.017481 -311.787605) (xy 143.046044 -311.842032) (xy 143.067837 -311.899505)
			(xy 143.082544 -311.959186) (xy 143.089949 -312.020205) (xy 143.090392 -312.050938) (xy 143.090227 -312.067305)
			(xy 143.088067 -312.09997) (xy 143.086074 -312.116216) (xy 143.085124 -312.128559) (xy 143.093766 -312.151725)
			(xy 143.102584 -312.160412) (xy 143.16456 -312.216292) (xy 143.174222 -312.223986) (xy 143.198112 -312.230093)
			(xy 143.21028 -312.227976) (xy 143.210534 -312.227976) (xy 143.239447 -312.221567) (xy 143.29827 -312.214691)
			(xy 143.327882 -312.21426) (xy 143.359425 -312.214749) (xy 143.422026 -312.22255) (xy 143.483182 -312.238035)
			(xy 143.541953 -312.260965) (xy 143.597435 -312.290989) (xy 143.648778 -312.327646) (xy 143.695193 -312.370371)
			(xy 143.735966 -312.41851) (xy 143.770471 -312.471323) (xy 143.798179 -312.527998) (xy 143.818663 -312.587665)
			(xy 143.83161 -312.649408) (xy 143.83682 -312.712278) (xy 143.834213 -312.77531) (xy 143.823829 -312.837535)
			(xy 143.805828 -312.897998) (xy 143.780487 -312.95577) (xy 143.748194 -313.009964) (xy 143.709445 -313.059747)
			(xy 143.664836 -313.104355) (xy 143.615052 -313.143102) (xy 143.560858 -313.175393) (xy 143.503085 -313.200733)
			(xy 143.442622 -313.218732) (xy 143.380396 -313.229114) (xy 143.317364 -313.231719) (xy 143.254494 -313.226508)
			(xy 143.192752 -313.21356) (xy 143.133085 -313.193074) (xy 143.076411 -313.165364) (xy 143.023599 -313.130858)
			(xy 142.975461 -313.090083) (xy 142.932737 -313.043668) (xy 142.896082 -312.992324) (xy 142.866059 -312.93684)
			(xy 142.84313 -312.878069) (xy 142.827647 -312.816912) (xy 142.819848 -312.754311) (xy 142.819374 -312.722768)
			(xy 142.819539 -312.706401) (xy 142.821699 -312.673736) (xy 142.823692 -312.65749) (xy 142.824617 -312.645148)
			(xy 142.81599 -312.621985) (xy 142.807182 -312.613294) (xy 142.745206 -312.557414) (xy 142.735557 -312.5497)
			(xy 142.711656 -312.543605) (xy 142.699486 -312.54573) (xy 142.699232 -312.54573) (xy 142.67032 -312.552145)
			(xy 142.611496 -312.559017) (xy 142.581884 -312.559446) (xy 142.551154 -312.558959) (xy 142.490143 -312.551549)
			(xy 142.430469 -312.53684) (xy 142.373003 -312.515046) (xy 142.318583 -312.486484) (xy 142.268003 -312.451572)
			(xy 142.221999 -312.410817) (xy 142.181242 -312.364815) (xy 142.146327 -312.314236) (xy 142.117763 -312.259817)
			(xy 142.095966 -312.202352) (xy 142.081255 -312.142679) (xy 142.073842 -312.081668) (xy 142.073376 -312.050938)
			(xy 142.073376 -312.048906) (xy 142.072827 -312.038212) (xy 142.064159 -312.018657) (xy 142.056612 -312.01106)
			(xy 141.992604 -311.953148) (xy 141.971776 -311.94629) (xy 141.961108 -311.94756) (xy 141.947685 -311.948881)
			(xy 141.920747 -311.950278) (xy 141.90726 -311.950354) (xy 141.875721 -311.94979) (xy 141.813129 -311.941983)
			(xy 141.751983 -311.926493) (xy 141.693223 -311.90356) (xy 141.63775 -311.873534) (xy 141.586418 -311.836877)
			(xy 141.540014 -311.794152) (xy 141.499251 -311.746015) (xy 141.464755 -311.693207) (xy 141.437057 -311.636536)
			(xy 141.41658 -311.576875) (xy 141.403641 -311.515139) (xy 141.398437 -311.452277) (xy 140.227335 -311.452277)
			(xy 141.810959 -314.682378) (xy 142.917418 -314.682378) (xy 142.917838 -314.651847) (xy 142.925153 -314.591226)
			(xy 142.939675 -314.531916) (xy 142.961194 -314.474773) (xy 142.989402 -314.420617) (xy 143.023892 -314.37023)
			(xy 143.064168 -314.324335) (xy 143.109651 -314.283593) (xy 143.159684 -314.248592) (xy 143.186404 -314.233814)
			(xy 143.195666 -314.228393) (xy 143.208963 -314.211576) (xy 143.212058 -314.201302) (xy 143.230346 -314.128404)
			(xy 143.232516 -314.11793) (xy 143.228829 -314.09688) (xy 143.223234 -314.087764) (xy 143.207009 -314.062652)
			(xy 143.179919 -314.009351) (xy 143.159267 -313.953241) (xy 143.145337 -313.895096) (xy 143.138323 -313.835719)
			(xy 143.13789 -313.805824) (xy 143.138392 -313.773863) (xy 143.146403 -313.710445) (xy 143.1623 -313.648531)
			(xy 143.185832 -313.589098) (xy 143.216626 -313.533083) (xy 143.254199 -313.481368) (xy 143.297956 -313.434771)
			(xy 143.347209 -313.394026) (xy 143.40118 -313.359775) (xy 143.459019 -313.332558) (xy 143.519812 -313.312805)
			(xy 143.582602 -313.300827) (xy 143.646398 -313.296814) (xy 143.710194 -313.300827) (xy 143.772984 -313.312805)
			(xy 143.833777 -313.332558) (xy 143.891616 -313.359775) (xy 143.945587 -313.394026) (xy 143.99484 -313.434771)
			(xy 144.038597 -313.481368) (xy 144.07617 -313.533083) (xy 144.106964 -313.589098) (xy 144.130496 -313.648531)
			(xy 144.146393 -313.710445) (xy 144.154404 -313.773863) (xy 144.154906 -313.805824) (xy 144.154475 -313.836354)
			(xy 144.14716 -313.896975) (xy 144.132639 -313.956284) (xy 144.11112 -314.013427) (xy 144.082914 -314.067582)
			(xy 144.048425 -314.117969) (xy 144.008151 -314.163864) (xy 143.962671 -314.204607) (xy 143.912639 -314.239609)
			(xy 143.88592 -314.254388) (xy 143.876643 -314.259787) (xy 143.863356 -314.276621) (xy 143.860266 -314.2869)
			(xy 143.841978 -314.359798) (xy 143.839803 -314.370271) (xy 143.843492 -314.391322) (xy 143.84909 -314.400438)
			(xy 143.865319 -314.425548) (xy 143.892408 -314.47885) (xy 143.913059 -314.53496) (xy 143.926987 -314.593106)
			(xy 143.934002 -314.652483) (xy 143.934434 -314.682378) (xy 143.933932 -314.714339) (xy 143.925921 -314.777757)
			(xy 143.910024 -314.839671) (xy 143.886492 -314.899104) (xy 143.855698 -314.955119) (xy 143.818125 -315.006834)
			(xy 143.774368 -315.053431) (xy 143.725115 -315.094176) (xy 143.671144 -315.128427) (xy 143.613305 -315.155644)
			(xy 143.552512 -315.175397) (xy 143.489722 -315.187375) (xy 143.425926 -315.191389) (xy 143.36213 -315.187375)
			(xy 143.29934 -315.175397) (xy 143.238547 -315.155644) (xy 143.180708 -315.128427) (xy 143.126737 -315.094176)
			(xy 143.077484 -315.053431) (xy 143.033727 -315.006834) (xy 142.996154 -314.955119) (xy 142.96536 -314.899104)
			(xy 142.941828 -314.839671) (xy 142.925931 -314.777757) (xy 142.91792 -314.714339) (xy 142.917418 -314.682378)
			(xy 141.810959 -314.682378) (xy 142.16761 -315.409834) (xy 142.171678 -315.417417) (xy 142.183916 -315.429499)
			(xy 142.199475 -315.436825) (xy 142.207996 -315.438028) (xy 142.293848 -315.446918) (xy 142.300346 -315.447331)
			(xy 142.313198 -315.445263) (xy 142.319248 -315.442854) (xy 142.327122 -315.439552) (xy 142.342452 -315.418077)
			(xy 142.37808 -315.37916) (xy 142.418731 -315.345525) (xy 142.46363 -315.317813) (xy 142.51192 -315.296553)
			(xy 142.562679 -315.282151) (xy 142.614939 -315.274882) (xy 142.64132 -315.274452) (xy 142.668571 -315.274939)
			(xy 142.722519 -315.282698) (xy 142.774814 -315.298054) (xy 142.824391 -315.320696) (xy 142.870242 -315.350162)
			(xy 142.911433 -315.385853) (xy 142.947126 -315.427042) (xy 142.976594 -315.472891) (xy 142.999239 -315.522468)
			(xy 143.014598 -315.574761) (xy 143.022359 -315.628709) (xy 143.022828 -315.65596) (xy 143.022828 -315.657992)
			(xy 143.022521 -315.685388) (xy 143.015013 -315.739657) (xy 142.999819 -315.792295) (xy 142.977253 -315.842218)
			(xy 142.947778 -315.888401) (xy 142.912001 -315.929892) (xy 142.870656 -315.965839) (xy 142.824596 -315.995504)
			(xy 142.774765 -316.018275) (xy 142.72219 -316.033684) (xy 142.667952 -316.041415) (xy 142.640558 -316.041786)
			(xy 142.62735 -316.041786) (xy 142.61592 -316.048136) (xy 142.610439 -316.05146) (xy 142.601188 -316.060328)
			(xy 142.597632 -316.065662) (xy 142.551658 -316.138814) (xy 142.547438 -316.146168) (xy 142.543667 -316.162689)
			(xy 142.54549 -316.1792) (xy 145.262092 -316.1792) (xy 145.262092 -312.4708) (xy 145.262692 -312.437517)
			(xy 145.271425 -312.371524) (xy 145.288691 -312.307234) (xy 145.314194 -312.245745) (xy 145.347498 -312.188108)
			(xy 145.388035 -312.135306) (xy 145.41119 -312.11139) (xy 145.48739 -312.03519) (xy 145.511284 -312.012007)
			(xy 145.564077 -311.971443) (xy 145.621714 -311.93812) (xy 145.683209 -311.912609) (xy 145.747509 -311.895346)
			(xy 145.813512 -311.886627) (xy 145.8468 -311.886092) (xy 145.877531 -311.886556) (xy 145.938545 -311.893965)
			(xy 145.998221 -311.908673) (xy 146.055689 -311.930468) (xy 146.110111 -311.959031) (xy 146.160693 -311.993945)
			(xy 146.206698 -312.034702) (xy 146.247455 -312.080707) (xy 146.282369 -312.131289) (xy 146.310932 -312.185711)
			(xy 146.332727 -312.243179) (xy 146.34726 -312.302144) (xy 148.335236 -312.302144) (xy 148.339307 -312.246522)
			(xy 148.351433 -312.192085) (xy 148.371356 -312.139994) (xy 148.398652 -312.091359) (xy 148.432738 -312.047216)
			(xy 148.472887 -312.008507) (xy 148.518245 -311.976056) (xy 148.567845 -311.950555) (xy 148.620629 -311.932548)
			(xy 148.675472 -311.922418) (xy 148.731206 -311.920381) (xy 148.786643 -311.926481) (xy 148.8406 -311.940587)
			(xy 148.891929 -311.962399) (xy 148.939535 -311.991453) (xy 148.982403 -312.027128) (xy 149.01962 -312.068665)
			(xy 149.050393 -312.115178) (xy 149.074065 -312.165675) (xy 149.090133 -312.219082) (xy 149.098253 -312.274258)
			(xy 149.098762 -312.302144) (xy 149.098253 -312.33003) (xy 149.090133 -312.385206) (xy 149.074065 -312.438613)
			(xy 149.050393 -312.48911) (xy 149.01962 -312.535623) (xy 148.982403 -312.57716) (xy 148.939535 -312.612835)
			(xy 148.891929 -312.641889) (xy 148.8406 -312.663701) (xy 148.786643 -312.677807) (xy 148.731206 -312.683907)
			(xy 148.675472 -312.68187) (xy 148.620629 -312.67174) (xy 148.567845 -312.653733) (xy 148.518245 -312.628232)
			(xy 148.472887 -312.595781) (xy 148.432738 -312.557072) (xy 148.398652 -312.512929) (xy 148.371356 -312.464294)
			(xy 148.351433 -312.412203) (xy 148.339307 -312.357766) (xy 148.335236 -312.302144) (xy 146.34726 -312.302144)
			(xy 146.347435 -312.302855) (xy 146.354844 -312.363869) (xy 146.355308 -312.3946) (xy 146.354777 -312.428191)
			(xy 146.345925 -312.494786) (xy 146.328377 -312.559635) (xy 146.302438 -312.621606) (xy 146.285966 -312.650886)
			(xy 146.282784 -312.656748) (xy 146.279305 -312.669619) (xy 146.279108 -312.676286) (xy 146.279108 -314.47105)
			(xy 146.640802 -314.47105) (xy 146.644873 -314.415428) (xy 146.656999 -314.360991) (xy 146.676922 -314.3089)
			(xy 146.704218 -314.260265) (xy 146.738304 -314.216122) (xy 146.778453 -314.177413) (xy 146.823811 -314.144962)
			(xy 146.873411 -314.119461) (xy 146.926195 -314.101454) (xy 146.981038 -314.091324) (xy 147.036772 -314.089287)
			(xy 147.092209 -314.095387) (xy 147.146166 -314.109493) (xy 147.197495 -314.131305) (xy 147.245101 -314.160359)
			(xy 147.287969 -314.196034) (xy 147.325186 -314.237571) (xy 147.355959 -314.284084) (xy 147.379631 -314.334581)
			(xy 147.395699 -314.387988) (xy 147.403819 -314.443164) (xy 147.404328 -314.47105) (xy 147.403819 -314.498936)
			(xy 147.395699 -314.554112) (xy 147.379631 -314.607519) (xy 147.355959 -314.658016) (xy 147.325186 -314.704529)
			(xy 147.287969 -314.746066) (xy 147.245101 -314.781741) (xy 147.197495 -314.810795) (xy 147.146166 -314.832607)
			(xy 147.092209 -314.846713) (xy 147.036772 -314.852813) (xy 146.981038 -314.850776) (xy 146.926195 -314.840646)
			(xy 146.873411 -314.822639) (xy 146.823811 -314.797138) (xy 146.778453 -314.764687) (xy 146.738304 -314.725978)
			(xy 146.704218 -314.681835) (xy 146.676922 -314.6332) (xy 146.656999 -314.581109) (xy 146.644873 -314.526672)
			(xy 146.640802 -314.47105) (xy 146.279108 -314.47105) (xy 146.279108 -315.947552) (xy 146.279557 -315.957619)
			(xy 146.287261 -315.976217) (xy 146.294094 -315.98362) (xy 146.37385 -316.063376) (xy 146.403822 -316.069218)
			(xy 146.418046 -316.063376) (xy 146.427073 -316.059052) (xy 146.44116 -316.044863) (xy 146.448794 -316.026383)
			(xy 146.449288 -316.016386) (xy 146.449288 -315.578998) (xy 146.449689 -315.568926) (xy 146.457424 -315.550327)
			(xy 146.464274 -315.54293) (xy 147.028408 -314.97905) (xy 147.035817 -314.972221) (xy 147.054409 -314.964493)
			(xy 147.064476 -314.964064) (xy 149.462998 -314.964064) (xy 149.472591 -314.963742) (xy 149.490456 -314.956754)
			(xy 149.504497 -314.943683) (xy 149.512743 -314.926362) (xy 149.513798 -314.91682) (xy 149.513798 -314.916566)
			(xy 149.51851 -314.853063) (xy 149.534997 -314.726782) (xy 149.559359 -314.601781) (xy 149.591499 -314.478551)
			(xy 149.631292 -314.357575) (xy 149.678581 -314.239328) (xy 149.733181 -314.124274) (xy 149.794877 -314.012863)
			(xy 149.863428 -313.905535) (xy 149.938564 -313.802708) (xy 150.019991 -313.704788) (xy 150.107388 -313.612158)
			(xy 150.200414 -313.525182) (xy 150.298703 -313.444201) (xy 150.40187 -313.369533) (xy 150.509509 -313.301471)
			(xy 150.621198 -313.240281) (xy 150.736499 -313.186204) (xy 150.85496 -313.139453) (xy 150.976116 -313.10021)
			(xy 151.099491 -313.06863) (xy 151.224601 -313.044836) (xy 151.350955 -313.028922) (xy 151.478058 -313.020951)
			(xy 151.541734 -313.020456) (xy 151.605592 -313.020961) (xy 151.733056 -313.028982) (xy 151.859765 -313.044991)
			(xy 151.985218 -313.068924) (xy 152.108922 -313.100687) (xy 152.230386 -313.140155) (xy 152.349133 -313.187171)
			(xy 152.464694 -313.241551) (xy 152.576612 -313.303079) (xy 152.684446 -313.371513) (xy 152.78777 -313.446583)
			(xy 152.886177 -313.527993) (xy 152.979278 -313.61542) (xy 153.066706 -313.708521) (xy 153.148115 -313.806928)
			(xy 153.223186 -313.910252) (xy 153.29162 -314.018086) (xy 153.353148 -314.130004) (xy 153.407528 -314.245565)
			(xy 153.454545 -314.364312) (xy 153.494012 -314.485776) (xy 153.525776 -314.60948) (xy 153.549709 -314.734933)
			(xy 153.565718 -314.861642) (xy 153.573739 -314.989106) (xy 153.573978 -315.019436) (xy 154.344368 -315.019436)
			(xy 154.348439 -314.963814) (xy 154.360565 -314.909377) (xy 154.380488 -314.857286) (xy 154.407784 -314.808651)
			(xy 154.44187 -314.764508) (xy 154.482019 -314.725799) (xy 154.527377 -314.693348) (xy 154.576977 -314.667847)
			(xy 154.629761 -314.64984) (xy 154.684604 -314.63971) (xy 154.740338 -314.637673) (xy 154.795775 -314.643773)
			(xy 154.849732 -314.657879) (xy 154.901061 -314.679691) (xy 154.948667 -314.708745) (xy 154.991535 -314.74442)
			(xy 155.028752 -314.785957) (xy 155.059525 -314.83247) (xy 155.083197 -314.882967) (xy 155.099265 -314.936374)
			(xy 155.107385 -314.99155) (xy 155.107894 -315.019436) (xy 155.107385 -315.047322) (xy 155.099265 -315.102498)
			(xy 155.083197 -315.155905) (xy 155.059525 -315.206402) (xy 155.028752 -315.252915) (xy 154.991535 -315.294452)
			(xy 154.948667 -315.330127) (xy 154.901061 -315.359181) (xy 154.849732 -315.380993) (xy 154.795775 -315.395099)
			(xy 154.740338 -315.401199) (xy 154.684604 -315.399162) (xy 154.629761 -315.389032) (xy 154.576977 -315.371025)
			(xy 154.527377 -315.345524) (xy 154.482019 -315.313073) (xy 154.44187 -315.274364) (xy 154.407784 -315.230221)
			(xy 154.380488 -315.181586) (xy 154.360565 -315.129495) (xy 154.348439 -315.075058) (xy 154.344368 -315.019436)
			(xy 153.573978 -315.019436) (xy 153.574242 -315.052964) (xy 153.573769 -315.115907) (xy 153.565975 -315.241551)
			(xy 153.550421 -315.366472) (xy 153.527167 -315.49019) (xy 153.496301 -315.612233) (xy 153.457943 -315.732132)
			(xy 153.412238 -315.849428) (xy 153.359363 -315.96367) (xy 153.29952 -316.074422) (xy 153.232938 -316.181258)
			(xy 153.196798 -316.232794) (xy 153.196544 -316.233048) (xy 153.191572 -316.240871) (xy 153.186993 -316.258816)
			(xy 153.189094 -316.277215) (xy 153.192988 -316.285626) (xy 153.234136 -316.36589) (xy 153.238743 -316.37401)
			(xy 153.252605 -316.38649) (xy 153.270021 -316.393166) (xy 153.279348 -316.393576) (xy 155.777692 -316.393576)
			(xy 155.787763 -316.393985) (xy 155.806362 -316.401715) (xy 155.81376 -316.408562) (xy 156.192474 -316.787022)
			(xy 156.199312 -316.794424) (xy 156.207034 -316.813022) (xy 156.20746 -316.82309) (xy 156.20746 -319.905126)
			(xy 156.207059 -319.915198) (xy 156.199322 -319.933796) (xy 156.192474 -319.941194) (xy 155.936696 -320.196718)
			(xy 155.929293 -320.203555) (xy 155.910696 -320.211276) (xy 155.900628 -320.211704) (xy 155.449524 -320.211704)
			(xy 155.438914 -320.212229) (xy 155.419473 -320.220716) (xy 155.405152 -320.236365) (xy 155.401264 -320.246248)
			(xy 155.365196 -320.353182) (xy 155.374848 -320.384424) (xy 155.387802 -320.39433) (xy 155.414075 -320.415026)
			(xy 155.461552 -320.462133) (xy 155.50244 -320.515059) (xy 155.536033 -320.572892) (xy 155.561751 -320.63463)
			(xy 155.57915 -320.699209) (xy 155.587928 -320.765511) (xy 155.588462 -320.798952) (xy 155.587936 -320.831536)
			(xy 155.579597 -320.89617) (xy 155.563073 -320.959209) (xy 155.538637 -321.019623) (xy 155.506687 -321.076423)
			(xy 155.467747 -321.128678) (xy 155.422453 -321.175535) (xy 155.371549 -321.216225) (xy 155.315865 -321.250083)
			(xy 155.256315 -321.276554) (xy 155.225242 -321.286378) (xy 155.21559 -321.289172) (xy 155.199588 -321.302126)
			(xy 155.16098 -321.374516) (xy 155.156625 -321.383529) (xy 155.154661 -321.403434) (xy 155.15717 -321.413124)
			(xy 155.15717 -321.413378) (xy 155.167485 -321.449592) (xy 155.178584 -321.524066) (xy 155.179268 -321.561714)
			(xy 155.178705 -321.596273) (xy 155.169359 -321.664756) (xy 155.150829 -321.731343) (xy 155.123454 -321.794809)
			(xy 155.08774 -321.853985) (xy 155.066492 -321.881246) (xy 155.057602 -321.891914) (xy 155.053538 -321.9196)
			(xy 155.093162 -322.015104) (xy 155.096997 -322.023331) (xy 155.109377 -322.03659) (xy 155.12559 -322.044728)
			(xy 155.134564 -322.046092) (xy 155.165339 -322.04993) (xy 155.225736 -322.064016) (xy 155.28397 -322.085346)
			(xy 155.339176 -322.113604) (xy 155.390533 -322.148369) (xy 155.437279 -322.189124) (xy 155.478718 -322.235265)
			(xy 155.514236 -322.286105) (xy 155.543303 -322.340889) (xy 155.565489 -322.398803) (xy 155.580462 -322.458985)
			(xy 155.588002 -322.520543) (xy 155.588462 -322.551552) (xy 155.58796 -322.583513) (xy 155.579949 -322.646931)
			(xy 155.564052 -322.708845) (xy 155.54052 -322.768278) (xy 155.509726 -322.824293) (xy 155.472153 -322.876008)
			(xy 155.428396 -322.922605) (xy 155.379143 -322.96335) (xy 155.325172 -322.997601) (xy 155.267333 -323.024818)
			(xy 155.20654 -323.044571) (xy 155.14375 -323.056549) (xy 155.079954 -323.060563) (xy 155.016158 -323.056549)
			(xy 154.953368 -323.044571) (xy 154.892575 -323.024818) (xy 154.834736 -322.997601) (xy 154.780765 -322.96335)
			(xy 154.731512 -322.922605) (xy 154.687755 -322.876008) (xy 154.650182 -322.824293) (xy 154.619388 -322.768278)
			(xy 154.595856 -322.708845) (xy 154.579959 -322.646931) (xy 154.571948 -322.583513) (xy 154.571446 -322.551552)
			(xy 154.571446 -322.551298) (xy 154.572002 -322.516764) (xy 154.581373 -322.448334) (xy 154.599915 -322.381801)
			(xy 154.627287 -322.318387) (xy 154.662987 -322.25926) (xy 154.684222 -322.23202) (xy 154.693112 -322.221352)
			(xy 154.697176 -322.193666) (xy 154.657552 -322.098162) (xy 154.653722 -322.089932) (xy 154.641338 -322.076676)
			(xy 154.625124 -322.068539) (xy 154.61615 -322.067174) (xy 154.582097 -322.06296) (xy 154.515484 -322.046506)
			(xy 154.451693 -322.021231) (xy 154.391888 -321.987593) (xy 154.364182 -321.967352) (xy 154.354768 -321.961076)
			(xy 154.332622 -321.956592) (xy 154.32151 -321.958716) (xy 154.244802 -321.977512) (xy 154.233949 -321.980731)
			(xy 154.216402 -321.994984) (xy 154.21102 -322.004944) (xy 154.21102 -322.005198) (xy 154.199131 -322.029428)
			(xy 154.169527 -322.074556) (xy 154.133855 -322.115058) (xy 154.092829 -322.150126) (xy 154.047267 -322.179057)
			(xy 153.998081 -322.201275) (xy 153.946253 -322.216335) (xy 153.89282 -322.223937) (xy 153.865834 -322.2244)
			(xy 153.836751 -322.223859) (xy 153.779258 -322.215039) (xy 153.723769 -322.197598) (xy 153.671568 -322.171941)
			(xy 153.623864 -322.138661) (xy 153.602436 -322.11899) (xy 153.591514 -322.108576) (xy 153.561542 -322.102988)
			(xy 153.461466 -322.145914) (xy 153.452563 -322.150274) (xy 153.4387 -322.164417) (xy 153.431204 -322.182748)
			(xy 153.430732 -322.19265) (xy 153.430732 -323.594984) (xy 153.431157 -323.605053) (xy 153.438877 -323.623652)
			(xy 153.445718 -323.631052) (xy 153.980134 -324.165214) (xy 153.987527 -324.172063) (xy 154.006132 -324.179777)
			(xy 154.016202 -324.1802) (xy 154.123644 -324.1802) (xy 154.156929 -324.180769) (xy 154.222922 -324.189508)
			(xy 154.287213 -324.20678) (xy 154.348702 -324.232289) (xy 154.406339 -324.265598) (xy 154.459139 -324.306141)
			(xy 154.483054 -324.329298) (xy 154.678634 -324.524878) (xy 154.686031 -324.531723) (xy 154.704632 -324.539441)
			(xy 154.714702 -324.539864) (xy 155.380944 -324.539864) (xy 155.391017 -324.539471) (xy 155.409615 -324.531729)
			(xy 155.417012 -324.524878) (xy 155.612592 -324.329298) (xy 155.636486 -324.306115) (xy 155.689279 -324.265551)
			(xy 155.746916 -324.232228) (xy 155.808411 -324.206717) (xy 155.872711 -324.189454) (xy 155.938714 -324.180735)
			(xy 155.972002 -324.1802) (xy 156.60624 -324.1802) (xy 156.61625 -324.179745) (xy 156.634743 -324.172072)
			(xy 156.648894 -324.157909) (xy 156.656553 -324.139411) (xy 156.65704 -324.1294) (xy 156.65704 -321.814952)
			(xy 156.657541 -321.783007) (xy 156.665549 -321.719621) (xy 156.681438 -321.657738) (xy 156.704957 -321.598334)
			(xy 156.735737 -321.542347) (xy 156.77329 -321.490658) (xy 156.817026 -321.444084) (xy 156.866254 -321.403359)
			(xy 156.920199 -321.369125) (xy 156.978008 -321.341922) (xy 157.038771 -321.322179) (xy 157.10153 -321.310207)
			(xy 157.165294 -321.306196) (xy 157.229058 -321.310207) (xy 157.291817 -321.322179) (xy 157.35258 -321.341922)
			(xy 157.410389 -321.369125) (xy 157.464334 -321.403359) (xy 157.513562 -321.444084) (xy 157.557298 -321.490658)
			(xy 157.594851 -321.542347) (xy 157.625631 -321.598334) (xy 157.64915 -321.657738) (xy 157.665039 -321.719621)
			(xy 157.673047 -321.783007) (xy 157.673548 -321.814952) (xy 157.673548 -324.415869) (xy 160.805362 -324.415869)
			(xy 160.805362 -324.351947) (xy 160.813373 -324.288529) (xy 160.82927 -324.226615) (xy 160.852802 -324.167182)
			(xy 160.883596 -324.111167) (xy 160.921169 -324.059452) (xy 160.964926 -324.012855) (xy 161.014179 -323.97211)
			(xy 161.06815 -323.937859) (xy 161.125989 -323.910642) (xy 161.186782 -323.890889) (xy 161.249572 -323.878911)
			(xy 161.313368 -323.874898) (xy 161.377164 -323.878911) (xy 161.439954 -323.890889) (xy 161.500747 -323.910642)
			(xy 161.558586 -323.937859) (xy 161.612557 -323.97211) (xy 161.66181 -324.012855) (xy 161.705567 -324.059452)
			(xy 161.74314 -324.111167) (xy 161.773934 -324.167182) (xy 161.797466 -324.226615) (xy 161.813363 -324.288529)
			(xy 161.821374 -324.351947) (xy 161.821876 -324.383908) (xy 161.821374 -324.415869) (xy 161.813363 -324.479287)
			(xy 161.798981 -324.5353) (xy 164.610084 -324.5353) (xy 164.614076 -324.446415) (xy 164.626019 -324.358246)
			(xy 164.645817 -324.271502) (xy 164.673311 -324.186882) (xy 164.708279 -324.105067) (xy 164.75044 -324.026716)
			(xy 164.799454 -323.952459) (xy 164.854928 -323.882895) (xy 164.916413 -323.818583) (xy 164.983415 -323.760042)
			(xy 165.055396 -323.707742) (xy 165.131774 -323.662104) (xy 165.211936 -323.623497) (xy 165.295236 -323.59223)
			(xy 165.381003 -323.568556) (xy 165.468547 -323.552665) (xy 165.557163 -323.544685) (xy 165.60165 -323.544184)
			(xy 167.35425 -323.544184) (xy 167.39874 -323.544682) (xy 167.487362 -323.552654) (xy 167.574913 -323.568538)
			(xy 167.660688 -323.592207) (xy 167.743995 -323.623469) (xy 167.824165 -323.662073) (xy 167.900551 -323.707708)
			(xy 167.972539 -323.760007) (xy 168.039549 -323.818549) (xy 168.101041 -323.882862) (xy 168.156521 -323.952428)
			(xy 168.205541 -324.026687) (xy 168.247707 -324.105042) (xy 168.28268 -324.186861) (xy 168.310177 -324.271486)
			(xy 168.329977 -324.358235) (xy 168.341922 -324.44641) (xy 168.345914 -324.5353) (xy 172.15407 -324.5353)
			(xy 172.158062 -324.446411) (xy 172.170006 -324.358237) (xy 172.189806 -324.271489) (xy 172.217302 -324.186865)
			(xy 172.252273 -324.105047) (xy 172.294437 -324.026693) (xy 172.343455 -323.952433) (xy 172.398933 -323.882867)
			(xy 172.460423 -323.818554) (xy 172.527431 -323.760011) (xy 172.599416 -323.707711) (xy 172.6758 -323.662074)
			(xy 172.755967 -323.623468) (xy 172.839273 -323.592203) (xy 172.925045 -323.568531) (xy 173.012594 -323.552644)
			(xy 173.101215 -323.544668) (xy 173.145704 -323.544184) (xy 174.898304 -323.544184) (xy 174.942792 -323.544699)
			(xy 175.031409 -323.552675) (xy 175.118955 -323.568563) (xy 175.204724 -323.592234) (xy 175.288026 -323.623498)
			(xy 175.36819 -323.662103) (xy 175.444571 -323.707739) (xy 175.516554 -323.760038) (xy 175.583559 -323.818578)
			(xy 175.645046 -323.88289) (xy 175.700522 -323.952454) (xy 175.749538 -324.026711) (xy 175.791701 -324.105062)
			(xy 175.82667 -324.186878) (xy 175.854165 -324.271499) (xy 175.873964 -324.358244) (xy 175.885908 -324.446414)
			(xy 175.8899 -324.5353) (xy 179.698184 -324.5353) (xy 179.702176 -324.446415) (xy 179.714119 -324.358245)
			(xy 179.733918 -324.271501) (xy 179.761412 -324.18688) (xy 179.79638 -324.105065) (xy 179.838541 -324.026713)
			(xy 179.887556 -323.952457) (xy 179.94303 -323.882892) (xy 180.004516 -323.81858) (xy 180.071519 -323.760039)
			(xy 180.1435 -323.707739) (xy 180.219879 -323.662101) (xy 180.300042 -323.623494) (xy 180.383342 -323.592228)
			(xy 180.46911 -323.568554) (xy 180.556654 -323.552664) (xy 180.645271 -323.544685) (xy 180.689758 -323.544184)
			(xy 182.442358 -323.544184) (xy 182.486848 -323.544683) (xy 182.57547 -323.552655) (xy 182.66302 -323.56854)
			(xy 182.748794 -323.592209) (xy 182.8321 -323.623471) (xy 182.912269 -323.662075) (xy 182.988655 -323.707711)
			(xy 183.060642 -323.76001) (xy 183.127652 -323.818552) (xy 183.189144 -323.882864) (xy 183.244623 -323.95243)
			(xy 183.293642 -324.02669) (xy 183.335808 -324.105044) (xy 183.37078 -324.186863) (xy 183.398277 -324.271487)
			(xy 183.418077 -324.358236) (xy 183.430022 -324.44641) (xy 183.434014 -324.5353) (xy 187.24217 -324.5353)
			(xy 187.246162 -324.44641) (xy 187.258106 -324.358236) (xy 187.277906 -324.271488) (xy 187.305402 -324.186864)
			(xy 187.340374 -324.105045) (xy 187.382539 -324.02669) (xy 187.431557 -323.952431) (xy 187.487035 -323.882864)
			(xy 187.548526 -323.818551) (xy 187.615534 -323.760008) (xy 187.68752 -323.707708) (xy 187.763905 -323.662071)
			(xy 187.844073 -323.623465) (xy 187.927379 -323.592201) (xy 188.013152 -323.56853) (xy 188.100701 -323.552643)
			(xy 188.189322 -323.544668) (xy 188.233812 -323.544184) (xy 189.986412 -323.544184) (xy 190.0309 -323.544699)
			(xy 190.119517 -323.552676) (xy 190.207062 -323.568564) (xy 190.29283 -323.592236) (xy 190.376132 -323.6235)
			(xy 190.456295 -323.662106) (xy 190.532675 -323.707742) (xy 190.604658 -323.760041) (xy 190.671662 -323.818581)
			(xy 190.733149 -323.882892) (xy 190.788624 -323.952456) (xy 190.83764 -324.026713) (xy 190.879802 -324.105064)
			(xy 190.914771 -324.186879) (xy 190.942266 -324.2715) (xy 190.962064 -324.358244) (xy 190.974008 -324.446414)
			(xy 190.978 -324.5353) (xy 190.974008 -324.624186) (xy 190.962064 -324.712356) (xy 190.942266 -324.7991)
			(xy 190.914771 -324.883721) (xy 190.879802 -324.965536) (xy 190.83764 -325.043887) (xy 190.788624 -325.118144)
			(xy 190.733149 -325.187708) (xy 190.671662 -325.252019) (xy 190.604658 -325.310559) (xy 190.532675 -325.362858)
			(xy 190.456295 -325.408494) (xy 190.376132 -325.4471) (xy 190.29283 -325.478364) (xy 190.207062 -325.502036)
			(xy 190.119517 -325.517924) (xy 190.0309 -325.525901) (xy 189.986412 -325.5264) (xy 188.233812 -325.5264)
			(xy 188.189322 -325.525932) (xy 188.100701 -325.517957) (xy 188.013152 -325.50207) (xy 187.927379 -325.478399)
			(xy 187.844073 -325.447135) (xy 187.763905 -325.408529) (xy 187.68752 -325.362892) (xy 187.615534 -325.310592)
			(xy 187.548526 -325.252049) (xy 187.487035 -325.187736) (xy 187.431557 -325.118169) (xy 187.382539 -325.04391)
			(xy 187.340374 -324.965555) (xy 187.305402 -324.883736) (xy 187.277906 -324.799112) (xy 187.258106 -324.712364)
			(xy 187.246162 -324.62419) (xy 187.24217 -324.5353) (xy 183.434014 -324.5353) (xy 183.430022 -324.62419)
			(xy 183.418077 -324.712364) (xy 183.398277 -324.799113) (xy 183.37078 -324.883737) (xy 183.335808 -324.965556)
			(xy 183.293642 -325.04391) (xy 183.244623 -325.11817) (xy 183.189144 -325.187736) (xy 183.127652 -325.252048)
			(xy 183.060642 -325.31059) (xy 182.988655 -325.362889) (xy 182.912269 -325.408525) (xy 182.8321 -325.447129)
			(xy 182.748794 -325.478391) (xy 182.66302 -325.50206) (xy 182.57547 -325.517945) (xy 182.486848 -325.525917)
			(xy 182.442358 -325.5264) (xy 180.689758 -325.5264) (xy 180.645271 -325.525915) (xy 180.556654 -325.517936)
			(xy 180.46911 -325.502046) (xy 180.383342 -325.478372) (xy 180.300042 -325.447106) (xy 180.219879 -325.408499)
			(xy 180.1435 -325.362861) (xy 180.071519 -325.310561) (xy 180.004516 -325.25202) (xy 179.94303 -325.187708)
			(xy 179.887556 -325.118143) (xy 179.838541 -325.043887) (xy 179.79638 -324.965535) (xy 179.761412 -324.88372)
			(xy 179.733918 -324.799099) (xy 179.714119 -324.712355) (xy 179.702176 -324.624185) (xy 179.698184 -324.5353)
			(xy 175.8899 -324.5353) (xy 175.885908 -324.624186) (xy 175.873964 -324.712356) (xy 175.854165 -324.799101)
			(xy 175.82667 -324.883722) (xy 175.791701 -324.965538) (xy 175.749538 -325.043889) (xy 175.700522 -325.118146)
			(xy 175.645046 -325.18771) (xy 175.583559 -325.252022) (xy 175.516554 -325.310562) (xy 175.444571 -325.362861)
			(xy 175.36819 -325.408497) (xy 175.288026 -325.447102) (xy 175.204724 -325.478366) (xy 175.118955 -325.502037)
			(xy 175.031409 -325.517925) (xy 174.942792 -325.525901) (xy 174.898304 -325.5264) (xy 173.145704 -325.5264)
			(xy 173.101215 -325.525932) (xy 173.012594 -325.517956) (xy 172.925045 -325.502069) (xy 172.839273 -325.478397)
			(xy 172.755967 -325.447132) (xy 172.6758 -325.408526) (xy 172.599416 -325.362889) (xy 172.527431 -325.310589)
			(xy 172.460423 -325.252046) (xy 172.398933 -325.187733) (xy 172.343455 -325.118167) (xy 172.294437 -325.043907)
			(xy 172.252273 -324.965553) (xy 172.217302 -324.883735) (xy 172.189806 -324.799111) (xy 172.170006 -324.712363)
			(xy 172.158062 -324.624189) (xy 172.15407 -324.5353) (xy 168.345914 -324.5353) (xy 168.341922 -324.62419)
			(xy 168.329977 -324.712365) (xy 168.310177 -324.799114) (xy 168.28268 -324.883739) (xy 168.247707 -324.965558)
			(xy 168.205541 -325.043913) (xy 168.156521 -325.118172) (xy 168.101041 -325.187738) (xy 168.039549 -325.252051)
			(xy 167.972539 -325.310593) (xy 167.900551 -325.362892) (xy 167.824165 -325.408527) (xy 167.743995 -325.447131)
			(xy 167.660688 -325.478393) (xy 167.574913 -325.502062) (xy 167.487362 -325.517946) (xy 167.39874 -325.525918)
			(xy 167.35425 -325.5264) (xy 165.60165 -325.5264) (xy 165.557163 -325.525915) (xy 165.468547 -325.517935)
			(xy 165.381003 -325.502044) (xy 165.295236 -325.47837) (xy 165.211936 -325.447103) (xy 165.131774 -325.408496)
			(xy 165.055396 -325.362858) (xy 164.983415 -325.310558) (xy 164.916413 -325.252017) (xy 164.854928 -325.187705)
			(xy 164.799454 -325.118141) (xy 164.75044 -325.043884) (xy 164.708279 -324.965533) (xy 164.673311 -324.883718)
			(xy 164.645817 -324.799098) (xy 164.626019 -324.712354) (xy 164.614076 -324.624185) (xy 164.610084 -324.5353)
			(xy 161.798981 -324.5353) (xy 161.797466 -324.541201) (xy 161.773934 -324.600634) (xy 161.74314 -324.656649)
			(xy 161.705567 -324.708364) (xy 161.66181 -324.754961) (xy 161.612557 -324.795706) (xy 161.558586 -324.829957)
			(xy 161.500747 -324.857174) (xy 161.439954 -324.876927) (xy 161.377164 -324.888905) (xy 161.313368 -324.892919)
			(xy 161.249572 -324.888905) (xy 161.186782 -324.876927) (xy 161.125989 -324.857174) (xy 161.06815 -324.829957)
			(xy 161.014179 -324.795706) (xy 160.964926 -324.754961) (xy 160.921169 -324.708364) (xy 160.883596 -324.656649)
			(xy 160.852802 -324.600634) (xy 160.82927 -324.541201) (xy 160.813373 -324.479287) (xy 160.805362 -324.415869)
			(xy 157.673548 -324.415869) (xy 157.673548 -324.781672) (xy 157.673018 -324.812391) (xy 157.665619 -324.873382)
			(xy 157.650924 -324.933037) (xy 157.629147 -324.990486) (xy 157.600607 -325.044893) (xy 157.56572 -325.095465)
			(xy 157.524992 -325.141464) (xy 157.479019 -325.182221) (xy 157.428469 -325.217141) (xy 157.37408 -325.245715)
			(xy 157.316645 -325.267528) (xy 157.256999 -325.28226) (xy 157.196013 -325.289699) (xy 157.165294 -325.29018)
			(xy 157.135548 -325.289757) (xy 157.076464 -325.282807) (xy 157.018596 -325.269003) (xy 156.962737 -325.248534)
			(xy 156.909651 -325.22168) (xy 156.884624 -325.205598) (xy 156.878274 -325.201534) (xy 156.864304 -325.197216)
			(xy 156.76118 -325.197216) (xy 156.751169 -325.197672) (xy 156.732674 -325.205341) (xy 156.718521 -325.219504)
			(xy 156.710865 -325.238005) (xy 156.71038 -325.248016) (xy 156.71038 -325.257922) (xy 156.717746 -325.27621)
			(xy 156.724858 -325.283322) (xy 156.747242 -325.307138) (xy 156.786404 -325.359466) (xy 156.818539 -325.416379)
			(xy 156.843118 -325.476941) (xy 156.859734 -325.540153) (xy 156.868114 -325.604972) (xy 156.868622 -325.637652)
			(xy 156.868117 -325.668383) (xy 156.860714 -325.729396) (xy 156.846011 -325.789072) (xy 156.824221 -325.846541)
			(xy 156.795663 -325.900964) (xy 156.760752 -325.951548) (xy 156.719999 -325.997555) (xy 156.673997 -326.038314)
			(xy 156.623418 -326.073231) (xy 156.568998 -326.101796) (xy 156.511532 -326.123592) (xy 156.451857 -326.138303)
			(xy 156.390845 -326.145714) (xy 156.360114 -326.14616) (xy 156.326987 -326.145677) (xy 156.261293 -326.137074)
			(xy 156.197273 -326.120012) (xy 156.136012 -326.09478) (xy 156.078546 -326.061805) (xy 156.02585 -326.021646)
			(xy 155.978816 -325.974983) (xy 155.93824 -325.922606) (xy 155.904811 -325.865404) (xy 155.879094 -325.804344)
			(xy 155.861525 -325.740461) (xy 155.852401 -325.674838) (xy 155.851606 -325.641716) (xy 155.851606 -325.641462)
			(xy 155.850823 -325.630151) (xy 155.840807 -325.609844) (xy 155.832302 -325.602346) (xy 155.760928 -325.545704)
			(xy 155.738576 -325.540624) (xy 155.727146 -325.543418) (xy 155.699151 -325.549464) (xy 155.642245 -325.555953)
			(xy 155.613608 -325.556372) (xy 154.483054 -325.556372) (xy 154.449774 -325.555834) (xy 154.383783 -325.547162)
			(xy 154.319489 -325.529948) (xy 154.257993 -325.504485) (xy 154.200349 -325.47121) (xy 154.147544 -325.430692)
			(xy 154.123644 -325.407528) (xy 153.928064 -325.211948) (xy 153.920587 -325.205249) (xy 153.902024 -325.197662)
			(xy 153.891996 -325.197216) (xy 153.784554 -325.197216) (xy 153.751268 -325.196673) (xy 153.685273 -325.187931)
			(xy 153.620981 -325.170657) (xy 153.559491 -325.145143) (xy 153.501855 -325.111828) (xy 153.449057 -325.071279)
			(xy 153.425144 -325.048118) (xy 152.563068 -324.186042) (xy 152.539918 -324.16213) (xy 152.499413 -324.10932)
			(xy 152.466144 -324.051676) (xy 152.44068 -323.990184) (xy 152.423457 -323.925896) (xy 152.41477 -323.85991)
			(xy 152.414224 -323.826632) (xy 152.414224 -321.61607) (xy 152.413805 -321.606428) (xy 152.406603 -321.588534)
			(xy 152.39333 -321.574538) (xy 152.38476 -321.570096) (xy 152.287986 -321.524884) (xy 152.258522 -321.528948)
			(xy 152.247346 -321.538346) (xy 152.224423 -321.557035) (xy 152.17501 -321.589541) (xy 152.122156 -321.616088)
			(xy 152.066576 -321.636316) (xy 152.009023 -321.649951) (xy 151.950275 -321.65681) (xy 151.920702 -321.657218)
			(xy 151.920448 -321.657218) (xy 151.896099 -321.65691) (xy 151.847628 -321.652199) (xy 151.823674 -321.64782)
			(xy 151.823166 -321.64782) (xy 151.812251 -321.646297) (xy 151.790909 -321.651719) (xy 151.782018 -321.658234)
			(xy 151.721312 -321.707002) (xy 151.713088 -321.714352) (xy 151.703332 -321.734103) (xy 151.702516 -321.745102)
			(xy 151.702516 -321.74561) (xy 151.701472 -321.77399) (xy 151.693882 -321.830274) (xy 151.680053 -321.885358)
			(xy 151.660156 -321.938552) (xy 151.647652 -321.96405) (xy 151.642886 -321.974844) (xy 151.642759 -321.998413)
			(xy 151.647398 -322.009262) (xy 151.683212 -322.082414) (xy 151.688947 -322.09277) (xy 151.70777 -322.107077)
			(xy 151.71928 -322.109846) (xy 151.750578 -322.116289) (xy 151.811352 -322.136042) (xy 151.86917 -322.163257)
			(xy 151.92312 -322.197504) (xy 151.972353 -322.238243) (xy 152.016091 -322.284833) (xy 152.053644 -322.336537)
			(xy 152.08442 -322.39254) (xy 152.107933 -322.45196) (xy 152.123814 -322.513858) (xy 152.13181 -322.577259)
			(xy 152.132284 -322.60921) (xy 152.131782 -322.641171) (xy 152.123771 -322.704589) (xy 152.107874 -322.766503)
			(xy 152.084342 -322.825936) (xy 152.053548 -322.881951) (xy 152.015975 -322.933666) (xy 151.972218 -322.980263)
			(xy 151.922965 -323.021008) (xy 151.868994 -323.055259) (xy 151.811155 -323.082476) (xy 151.750362 -323.102229)
			(xy 151.687572 -323.114207) (xy 151.623776 -323.118221) (xy 151.55998 -323.114207) (xy 151.49719 -323.102229)
			(xy 151.436397 -323.082476) (xy 151.378558 -323.055259) (xy 151.324587 -323.021008) (xy 151.275334 -322.980263)
			(xy 151.231577 -322.933666) (xy 151.194004 -322.881951) (xy 151.16321 -322.825936) (xy 151.139678 -322.766503)
			(xy 151.123781 -322.704589) (xy 151.11577 -322.641171) (xy 151.115268 -322.60921) (xy 151.115268 -322.608956)
			(xy 151.115676 -322.579093) (xy 151.12268 -322.519778) (xy 151.136597 -322.461695) (xy 151.157234 -322.405647)
			(xy 151.170386 -322.378832) (xy 151.175161 -322.368042) (xy 151.175281 -322.34447) (xy 151.17064 -322.33362)
			(xy 151.134826 -322.260468) (xy 151.129078 -322.250122) (xy 151.110264 -322.235811) (xy 151.098758 -322.233036)
			(xy 151.067473 -322.226541) (xy 151.006707 -322.206786) (xy 150.948896 -322.179572) (xy 150.894951 -322.145327)
			(xy 150.845723 -322.104592) (xy 150.801989 -322.058008) (xy 150.764437 -322.006311) (xy 150.73366 -321.950315)
			(xy 150.710144 -321.890903) (xy 150.694258 -321.829013) (xy 150.686254 -321.76562) (xy 150.685754 -321.733672)
			(xy 150.68621 -321.702792) (xy 150.693693 -321.641488) (xy 150.708545 -321.581541) (xy 150.730547 -321.523834)
			(xy 150.759376 -321.469216) (xy 150.794608 -321.418491) (xy 150.835723 -321.372407) (xy 150.882116 -321.331641)
			(xy 150.933105 -321.296793) (xy 150.987939 -321.268377) (xy 151.016716 -321.257168) (xy 151.02572 -321.253438)
			(xy 151.040182 -321.240396) (xy 151.048726 -321.222896) (xy 151.050115 -321.203471) (xy 151.044147 -321.184933)
			(xy 151.031687 -321.169966) (xy 151.02332 -321.164966) (xy 150.997666 -321.14998) (xy 150.991824 -321.14617)
			(xy 150.978108 -321.14236) (xy 150.847298 -321.14236) (xy 150.814017 -321.141861) (xy 150.748024 -321.133182)
			(xy 150.683729 -321.11596) (xy 150.622233 -321.09049) (xy 150.56459 -321.057208) (xy 150.511787 -321.016684)
			(xy 150.487888 -320.993516) (xy 149.815296 -320.321178) (xy 149.807894 -320.31434) (xy 149.789296 -320.30662)
			(xy 149.779228 -320.306192) (xy 146.738086 -320.306192) (xy 146.704802 -320.305606) (xy 146.638809 -320.29687)
			(xy 146.574519 -320.279602) (xy 146.51303 -320.254097) (xy 146.455392 -320.22079) (xy 146.402591 -320.18025)
			(xy 146.378676 -320.157094) (xy 145.870676 -319.649094) (xy 145.847552 -319.625158) (xy 145.807044 -319.572353)
			(xy 145.773771 -319.514714) (xy 145.748303 -319.453227) (xy 145.731075 -319.388943) (xy 145.722381 -319.32296)
			(xy 145.721832 -319.289684) (xy 145.721832 -316.870334) (xy 145.721407 -316.860264) (xy 145.713688 -316.841665)
			(xy 145.706846 -316.834266) (xy 145.41119 -316.53861) (xy 145.388007 -316.514716) (xy 145.347443 -316.461923)
			(xy 145.31412 -316.404286) (xy 145.288609 -316.342791) (xy 145.271346 -316.278491) (xy 145.262627 -316.212488)
			(xy 145.262092 -316.1792) (xy 142.54549 -316.1792) (xy 142.545527 -316.179532) (xy 142.548864 -316.187328)
			(xy 142.73911 -316.57544) (xy 143.134589 -317.382144) (xy 143.66824 -317.382144) (xy 143.672311 -317.326522)
			(xy 143.684437 -317.272085) (xy 143.70436 -317.219994) (xy 143.731656 -317.171359) (xy 143.765742 -317.127216)
			(xy 143.805891 -317.088507) (xy 143.851249 -317.056056) (xy 143.900849 -317.030555) (xy 143.953633 -317.012548)
			(xy 144.008476 -317.002418) (xy 144.06421 -317.000381) (xy 144.119647 -317.006481) (xy 144.173604 -317.020587)
			(xy 144.224933 -317.042399) (xy 144.272539 -317.071453) (xy 144.315407 -317.107128) (xy 144.352624 -317.148665)
			(xy 144.383397 -317.195178) (xy 144.407069 -317.245675) (xy 144.423137 -317.299082) (xy 144.431257 -317.354258)
			(xy 144.431766 -317.382144) (xy 144.431257 -317.41003) (xy 144.423137 -317.465206) (xy 144.407069 -317.518613)
			(xy 144.383397 -317.56911) (xy 144.352624 -317.615623) (xy 144.315407 -317.65716) (xy 144.272539 -317.692835)
			(xy 144.224933 -317.721889) (xy 144.173604 -317.743701) (xy 144.119647 -317.757807) (xy 144.06421 -317.763907)
			(xy 144.008476 -317.76187) (xy 143.953633 -317.75174) (xy 143.900849 -317.733733) (xy 143.851249 -317.708232)
			(xy 143.805891 -317.675781) (xy 143.765742 -317.637072) (xy 143.731656 -317.592929) (xy 143.70436 -317.544294)
			(xy 143.684437 -317.492203) (xy 143.672311 -317.437766) (xy 143.66824 -317.382144) (xy 143.134589 -317.382144)
			(xy 144.576292 -320.322956) (xy 144.581414 -320.332097) (xy 144.597411 -320.345598) (xy 144.60728 -320.349118)
			(xy 144.678654 -320.370708) (xy 144.683734 -320.372113) (xy 144.694236 -320.373001) (xy 144.699482 -320.372486)
			(xy 144.709642 -320.371216) (xy 144.71904 -320.365628) (xy 144.746472 -320.350642) (xy 144.786604 -320.332354)
			(xy 144.786858 -320.3321) (xy 144.792526 -320.329661) (xy 144.802545 -320.322465) (xy 144.80667 -320.317876)
			(xy 144.810226 -320.313812) (xy 144.81556 -320.30289) (xy 144.826228 -320.255646) (xy 144.835372 -320.215006)
			(xy 144.836552 -320.208887) (xy 144.836301 -320.196432) (xy 144.834864 -320.190368) (xy 144.831562 -320.178684)
			(xy 144.822926 -320.169286) (xy 144.803942 -320.147992) (xy 144.771858 -320.100824) (xy 144.747149 -320.049407)
			(xy 144.730367 -319.994886) (xy 144.721885 -319.938475) (xy 144.721326 -319.909952) (xy 144.721812 -319.882701)
			(xy 144.729568 -319.828753) (xy 144.744923 -319.776458) (xy 144.767565 -319.726881) (xy 144.797031 -319.681031)
			(xy 144.832722 -319.63984) (xy 144.873913 -319.604149) (xy 144.919763 -319.574683) (xy 144.96934 -319.552041)
			(xy 145.021635 -319.536686) (xy 145.075583 -319.52893) (xy 145.130085 -319.52893) (xy 145.184033 -319.536686)
			(xy 145.236328 -319.552041) (xy 145.285905 -319.574683) (xy 145.331755 -319.604149) (xy 145.372946 -319.63984)
			(xy 145.408637 -319.681031) (xy 145.438103 -319.726881) (xy 145.460745 -319.776458) (xy 145.4761 -319.828753)
			(xy 145.483856 -319.882701) (xy 145.484342 -319.909952) (xy 145.483846 -319.937961) (xy 145.475651 -319.993378)
			(xy 145.459446 -320.047002) (xy 145.435577 -320.097682) (xy 145.404558 -320.144329) (xy 145.367055 -320.185942)
			(xy 145.323873 -320.221627) (xy 145.300192 -320.236596) (xy 145.294604 -320.239898) (xy 145.285714 -320.248788)
			(xy 145.282666 -320.253868) (xy 145.279794 -320.259103) (xy 145.276322 -320.270525) (xy 145.275808 -320.276474)
			(xy 145.273268 -320.318638) (xy 145.270728 -320.360548) (xy 145.270581 -320.366756) (xy 145.27289 -320.378955)
			(xy 145.2753 -320.384678) (xy 145.277586 -320.390012) (xy 145.284952 -320.39941) (xy 145.290032 -320.403474)
			(xy 145.31569 -320.424178) (xy 145.361965 -320.47114) (xy 145.401776 -320.523692) (xy 145.434456 -320.580953)
			(xy 145.459453 -320.64196) (xy 145.47635 -320.705689) (xy 145.484861 -320.771067) (xy 145.485358 -320.804032)
			(xy 145.485279 -320.816754) (xy 145.484008 -320.842166) (xy 145.482818 -320.854832) (xy 145.479269 -320.885581)
			(xy 145.465656 -320.945964) (xy 145.444815 -321.004249) (xy 145.417056 -321.059574) (xy 145.400211 -321.084913)
			(xy 147.896828 -321.084913) (xy 147.896828 -321.020991) (xy 147.904839 -320.957573) (xy 147.920736 -320.895659)
			(xy 147.944268 -320.836226) (xy 147.975062 -320.780211) (xy 148.012635 -320.728496) (xy 148.056392 -320.681899)
			(xy 148.105645 -320.641154) (xy 148.159616 -320.606903) (xy 148.217455 -320.579686) (xy 148.278248 -320.559933)
			(xy 148.341038 -320.547955) (xy 148.404834 -320.543942) (xy 148.46863 -320.547955) (xy 148.53142 -320.559933)
			(xy 148.592213 -320.579686) (xy 148.650052 -320.606903) (xy 148.704023 -320.641154) (xy 148.753276 -320.681899)
			(xy 148.797033 -320.728496) (xy 148.834606 -320.780211) (xy 148.8654 -320.836226) (xy 148.888932 -320.895659)
			(xy 148.904829 -320.957573) (xy 148.91284 -321.020991) (xy 148.913342 -321.052952) (xy 148.91284 -321.084913)
			(xy 148.904829 -321.148331) (xy 148.888932 -321.210245) (xy 148.8654 -321.269678) (xy 148.834606 -321.325693)
			(xy 148.797033 -321.377408) (xy 148.753276 -321.424005) (xy 148.704023 -321.46475) (xy 148.650052 -321.499001)
			(xy 148.592213 -321.526218) (xy 148.53142 -321.545971) (xy 148.46863 -321.557949) (xy 148.404834 -321.561963)
			(xy 148.341038 -321.557949) (xy 148.278248 -321.545971) (xy 148.217455 -321.526218) (xy 148.159616 -321.499001)
			(xy 148.105645 -321.46475) (xy 148.056392 -321.424005) (xy 148.012635 -321.377408) (xy 147.975062 -321.325693)
			(xy 147.944268 -321.269678) (xy 147.920736 -321.210245) (xy 147.904839 -321.148331) (xy 147.896828 -321.084913)
			(xy 145.400211 -321.084913) (xy 145.382788 -321.111122) (xy 145.342518 -321.158131) (xy 145.296841 -321.199905)
			(xy 145.246433 -321.235828) (xy 145.192038 -321.265369) (xy 145.13446 -321.28809) (xy 145.104612 -321.296284)
			(xy 145.09496 -321.298824) (xy 145.08734 -321.304412) (xy 145.083552 -321.307354) (xy 145.077024 -321.314378)
			(xy 145.074386 -321.318382) (xy 145.037048 -321.377564) (xy 145.034 -321.383406) (xy 145.031112 -321.390259)
			(xy 145.029042 -321.404979) (xy 145.029936 -321.412362) (xy 145.030444 -321.414648) (xy 146.27708 -327.553828)
			(xy 150.365206 -327.553828) (xy 150.365655 -327.517084) (xy 150.372719 -327.443935) (xy 150.386782 -327.371805)
			(xy 150.407716 -327.301361) (xy 150.435326 -327.233256) (xy 150.469357 -327.168121) (xy 150.509492 -327.10656)
			(xy 150.532084 -327.077578) (xy 150.538835 -327.068246) (xy 150.543986 -327.045822) (xy 150.538854 -327.023394)
			(xy 150.532084 -327.014078) (xy 150.509509 -326.985083) (xy 150.46937 -326.923525) (xy 150.435336 -326.858393)
			(xy 150.407722 -326.790291) (xy 150.386783 -326.719848) (xy 150.372714 -326.647719) (xy 150.365646 -326.574572)
			(xy 150.365206 -326.537828) (xy 150.365695 -326.499183) (xy 150.373515 -326.422289) (xy 150.389073 -326.346581)
			(xy 150.412211 -326.272835) (xy 150.442691 -326.201808) (xy 150.4802 -326.13423) (xy 150.524354 -326.070792)
			(xy 150.574699 -326.012148) (xy 150.630718 -325.958897) (xy 150.691837 -325.911587) (xy 150.75743 -325.870703)
			(xy 150.826821 -325.836665) (xy 150.899301 -325.809822) (xy 150.974124 -325.790449) (xy 151.050523 -325.778745)
			(xy 151.127714 -325.77483) (xy 151.204905 -325.778745) (xy 151.281304 -325.790449) (xy 151.356127 -325.809822)
			(xy 151.428607 -325.836665) (xy 151.497998 -325.870703) (xy 151.563591 -325.911587) (xy 151.62471 -325.958897)
			(xy 151.680729 -326.012148) (xy 151.731074 -326.070792) (xy 151.775228 -326.13423) (xy 151.812737 -326.201808)
			(xy 151.843217 -326.272835) (xy 151.866355 -326.346581) (xy 151.881913 -326.422289) (xy 151.889733 -326.499183)
			(xy 151.890222 -326.537828) (xy 151.889799 -326.574573) (xy 151.88273 -326.647722) (xy 151.868662 -326.719853)
			(xy 151.847724 -326.790297) (xy 151.82011 -326.858402) (xy 151.786076 -326.923536) (xy 151.745937 -326.985096)
			(xy 151.723344 -327.014078) (xy 151.716549 -327.023381) (xy 151.711422 -327.045822) (xy 151.716568 -327.068259)
			(xy 151.723344 -327.077578) (xy 151.745949 -327.10655) (xy 151.786084 -327.168113) (xy 151.820114 -327.233249)
			(xy 151.847724 -327.301356) (xy 151.868658 -327.371801) (xy 151.882721 -327.443933) (xy 151.889785 -327.517083)
			(xy 151.890222 -327.553828) (xy 151.889733 -327.592473) (xy 151.881913 -327.669367) (xy 151.866355 -327.745075)
			(xy 151.843217 -327.818821) (xy 151.812737 -327.889848) (xy 151.775228 -327.957426) (xy 151.731074 -328.020864)
			(xy 151.680729 -328.079508) (xy 151.62471 -328.132759) (xy 151.563591 -328.180069) (xy 151.497998 -328.220953)
			(xy 151.428607 -328.254991) (xy 151.356127 -328.281834) (xy 151.281304 -328.301207) (xy 151.204905 -328.312911)
			(xy 151.127714 -328.316826) (xy 151.050523 -328.312911) (xy 150.974124 -328.301207) (xy 150.899301 -328.281834)
			(xy 150.826821 -328.254991) (xy 150.75743 -328.220953) (xy 150.691837 -328.180069) (xy 150.630718 -328.132759)
			(xy 150.574699 -328.079508) (xy 150.524354 -328.020864) (xy 150.4802 -327.957426) (xy 150.442691 -327.889848)
			(xy 150.412211 -327.818821) (xy 150.389073 -327.745075) (xy 150.373515 -327.669367) (xy 150.365695 -327.592473)
			(xy 150.365206 -327.553828) (xy 146.27708 -327.553828) (xy 147.082932 -331.522324) (xy 174.389796 -331.522324)
			(xy 174.390335 -331.493586) (xy 174.398954 -331.436759) (xy 174.416001 -331.381869) (xy 174.441089 -331.330157)
			(xy 174.473651 -331.282793) (xy 174.49292 -331.261466) (xy 174.499524 -331.254608) (xy 174.506636 -331.236574)
			(xy 174.506636 -331.147674) (xy 174.499524 -331.12964) (xy 174.49292 -331.122782) (xy 174.473673 -331.101435)
			(xy 174.441107 -331.054075) (xy 174.416015 -331.002367) (xy 174.398963 -330.94748) (xy 174.390338 -330.890655)
			(xy 174.390336 -330.83318) (xy 174.398955 -330.776355) (xy 174.416002 -330.721466) (xy 174.44109 -330.669755)
			(xy 174.473651 -330.622393) (xy 174.49292 -330.601066) (xy 174.499524 -330.594208) (xy 174.506636 -330.576174)
			(xy 174.506636 -330.487274) (xy 174.499524 -330.46924) (xy 174.49292 -330.462382) (xy 174.473658 -330.441048)
			(xy 174.441091 -330.393687) (xy 174.415997 -330.341978) (xy 174.398944 -330.287088) (xy 174.390319 -330.230262)
			(xy 174.389796 -330.201524) (xy 174.390277 -330.174154) (xy 174.398091 -330.119976) (xy 174.413577 -330.067473)
			(xy 174.436415 -330.017726) (xy 174.466136 -329.971758) (xy 174.483776 -329.950826) (xy 174.48403 -329.950572)
			(xy 174.489596 -329.943471) (xy 174.495854 -329.926565) (xy 174.496222 -329.917552) (xy 174.496222 -329.850496)
			(xy 174.495862 -329.84148) (xy 174.489616 -329.824563) (xy 174.48403 -329.817476) (xy 174.483776 -329.817476)
			(xy 174.483776 -329.817222) (xy 174.46613 -329.796296) (xy 174.43642 -329.750321) (xy 174.413586 -329.700572)
			(xy 174.398096 -329.64807) (xy 174.390269 -329.593893) (xy 174.389796 -329.566524) (xy 174.390282 -329.539273)
			(xy 174.398038 -329.485325) (xy 174.413393 -329.43303) (xy 174.436035 -329.383453) (xy 174.465501 -329.337603)
			(xy 174.501192 -329.296412) (xy 174.542383 -329.260721) (xy 174.588233 -329.231255) (xy 174.63781 -329.208613)
			(xy 174.690105 -329.193258) (xy 174.744053 -329.185502) (xy 174.798555 -329.185502) (xy 174.852503 -329.193258)
			(xy 174.904798 -329.208613) (xy 174.954375 -329.231255) (xy 175.000225 -329.260721) (xy 175.041416 -329.296412)
			(xy 175.077107 -329.337603) (xy 175.106573 -329.383453) (xy 175.129215 -329.43303) (xy 175.14457 -329.485325)
			(xy 175.152326 -329.539273) (xy 175.152812 -329.566524) (xy 175.152357 -329.593895) (xy 175.144536 -329.648074)
			(xy 175.129044 -329.700577) (xy 175.1062 -329.750324) (xy 175.076474 -329.79629) (xy 175.058832 -329.817222)
			(xy 175.058578 -329.817476) (xy 175.052993 -329.824563) (xy 175.046746 -329.84148) (xy 175.046386 -329.850496)
			(xy 175.046386 -329.917552) (xy 175.046769 -329.926566) (xy 175.052999 -329.943483) (xy 175.058578 -329.950572)
			(xy 175.058832 -329.950572) (xy 175.058832 -329.950826) (xy 175.076455 -329.971771) (xy 175.106168 -330.017741)
			(xy 175.129007 -330.067485) (xy 175.144502 -330.119983) (xy 175.152335 -330.174156) (xy 175.152812 -330.201524)
			(xy 175.1523 -330.230263) (xy 175.143674 -330.287091) (xy 175.126621 -330.341982) (xy 175.101527 -330.393693)
			(xy 175.06896 -330.441055) (xy 175.049688 -330.462382) (xy 175.043084 -330.46924) (xy 175.035972 -330.487274)
			(xy 175.035972 -330.576174) (xy 175.043084 -330.594208) (xy 175.049688 -330.601066) (xy 175.068982 -330.622372)
			(xy 175.101546 -330.669739) (xy 175.126635 -330.721454) (xy 175.143683 -330.776348) (xy 175.152303 -330.833178)
			(xy 175.1523 -330.890657) (xy 175.143675 -330.947487) (xy 175.126622 -331.002379) (xy 175.101528 -331.054092)
			(xy 175.06896 -331.101455) (xy 175.049688 -331.122782) (xy 175.043084 -331.12964) (xy 175.035972 -331.147674)
			(xy 175.035972 -331.236574) (xy 175.043084 -331.254608) (xy 175.049688 -331.261466) (xy 175.068974 -331.282779)
			(xy 175.101538 -331.330146) (xy 175.126627 -331.381861) (xy 175.143674 -331.436754) (xy 175.152293 -331.493584)
			(xy 175.152812 -331.522324) (xy 176.779174 -331.522324) (xy 176.779719 -331.493586) (xy 176.788338 -331.43676)
			(xy 176.805383 -331.38187) (xy 176.83047 -331.330158) (xy 176.86303 -331.282794) (xy 176.882298 -331.261466)
			(xy 176.888902 -331.254608) (xy 176.896014 -331.236574) (xy 176.896014 -331.147674) (xy 176.888902 -331.12964)
			(xy 176.882298 -331.122782) (xy 176.863052 -331.101434) (xy 176.830488 -331.054074) (xy 176.805397 -331.002366)
			(xy 176.788347 -330.947479) (xy 176.779722 -330.890655) (xy 176.77972 -330.83318) (xy 176.788339 -330.776355)
			(xy 176.805384 -330.721467) (xy 176.830471 -330.669756) (xy 176.86303 -330.622393) (xy 176.882298 -330.601066)
			(xy 176.888902 -330.594208) (xy 176.896014 -330.576174) (xy 176.896014 -330.487274) (xy 176.888902 -330.46924)
			(xy 176.882298 -330.462382) (xy 176.863049 -330.441036) (xy 176.830478 -330.39368) (xy 176.80538 -330.341974)
			(xy 176.788325 -330.287087) (xy 176.779697 -330.230262) (xy 176.779174 -330.201524) (xy 176.779636 -330.174153)
			(xy 176.787452 -330.119973) (xy 176.802941 -330.06747) (xy 176.825784 -330.017723) (xy 176.855511 -329.971757)
			(xy 176.873154 -329.950826) (xy 176.873408 -329.950572) (xy 176.878971 -329.94347) (xy 176.885232 -329.926565)
			(xy 176.8856 -329.917552) (xy 176.8856 -329.850496) (xy 176.885245 -329.841479) (xy 176.878996 -329.824562)
			(xy 176.873408 -329.817476) (xy 176.873154 -329.817476) (xy 176.873154 -329.817222) (xy 176.85552 -329.796286)
			(xy 176.825806 -329.750315) (xy 176.802968 -329.700568) (xy 176.787476 -329.648068) (xy 176.779648 -329.593893)
			(xy 176.779174 -329.566524) (xy 176.77966 -329.539273) (xy 176.787416 -329.485325) (xy 176.802771 -329.43303)
			(xy 176.825413 -329.383453) (xy 176.854879 -329.337603) (xy 176.89057 -329.296412) (xy 176.931761 -329.260721)
			(xy 176.977611 -329.231255) (xy 177.027188 -329.208613) (xy 177.079483 -329.193258) (xy 177.133431 -329.185502)
			(xy 177.187933 -329.185502) (xy 177.241881 -329.193258) (xy 177.294176 -329.208613) (xy 177.343753 -329.231255)
			(xy 177.389603 -329.260721) (xy 177.430794 -329.296412) (xy 177.466485 -329.337603) (xy 177.495951 -329.383453)
			(xy 177.518593 -329.43303) (xy 177.533948 -329.485325) (xy 177.541704 -329.539273) (xy 177.54219 -329.566524)
			(xy 177.54174 -329.593895) (xy 177.533919 -329.648075) (xy 177.518426 -329.700578) (xy 177.495581 -329.750325)
			(xy 177.465853 -329.796291) (xy 177.44821 -329.817222) (xy 177.447956 -329.817476) (xy 177.442368 -329.824561)
			(xy 177.436123 -329.841479) (xy 177.435764 -329.850496) (xy 177.435764 -329.917552) (xy 177.436152 -329.926566)
			(xy 177.442379 -329.943482) (xy 177.447956 -329.950572) (xy 177.44821 -329.950572) (xy 177.44821 -329.950826)
			(xy 177.465829 -329.971774) (xy 177.495544 -330.017742) (xy 177.518383 -330.067486) (xy 177.533879 -330.119983)
			(xy 177.541713 -330.174156) (xy 177.54219 -330.201524) (xy 177.541684 -330.230264) (xy 177.533057 -330.287092)
			(xy 177.516003 -330.341983) (xy 177.490908 -330.393694) (xy 177.458339 -330.441056) (xy 177.439066 -330.462382)
			(xy 177.432462 -330.46924) (xy 177.42535 -330.487274) (xy 177.42535 -330.576174) (xy 177.432462 -330.594208)
			(xy 177.439066 -330.601066) (xy 177.458361 -330.622372) (xy 177.490926 -330.669738) (xy 177.516017 -330.721453)
			(xy 177.533066 -330.776347) (xy 177.541687 -330.833177) (xy 177.541684 -330.890658) (xy 177.533058 -330.947487)
			(xy 177.516004 -331.00238) (xy 177.490909 -331.054093) (xy 177.458339 -331.101455) (xy 177.439066 -331.122782)
			(xy 177.432462 -331.12964) (xy 177.42535 -331.147674) (xy 177.42535 -331.236574) (xy 177.432462 -331.254608)
			(xy 177.439066 -331.261466) (xy 177.458349 -331.282783) (xy 177.490913 -331.330148) (xy 177.516003 -331.381862)
			(xy 177.533051 -331.436755) (xy 177.541671 -331.493584) (xy 177.54219 -331.522324) (xy 177.542009 -331.532484)
			(xy 180.454808 -331.532484) (xy 180.45532 -331.503745) (xy 180.463945 -331.446917) (xy 180.480998 -331.392026)
			(xy 180.506092 -331.340314) (xy 180.53866 -331.292952) (xy 180.557932 -331.271626) (xy 180.564536 -331.264768)
			(xy 180.571648 -331.246734) (xy 180.571648 -331.157834) (xy 180.564536 -331.1398) (xy 180.557932 -331.132942)
			(xy 180.538645 -331.111629) (xy 180.50608 -331.064265) (xy 180.480988 -331.012551) (xy 180.463939 -330.957658)
			(xy 180.455318 -330.900828) (xy 180.45532 -330.843349) (xy 180.463944 -330.78652) (xy 180.480997 -330.731628)
			(xy 180.506091 -330.679915) (xy 180.53866 -330.632553) (xy 180.557932 -330.611226) (xy 180.564536 -330.604368)
			(xy 180.571648 -330.586334) (xy 180.571648 -330.497434) (xy 180.564536 -330.4794) (xy 180.557932 -330.472542)
			(xy 180.538653 -330.451222) (xy 180.506088 -330.403858) (xy 180.480997 -330.352145) (xy 180.463948 -330.297252)
			(xy 180.455328 -330.240424) (xy 180.454808 -330.211684) (xy 180.455263 -330.184313) (xy 180.463083 -330.130134)
			(xy 180.478575 -330.07763) (xy 180.501419 -330.027884) (xy 180.531146 -329.981917) (xy 180.548788 -329.960986)
			(xy 180.549042 -329.960732) (xy 180.554626 -329.953644) (xy 180.560873 -329.936728) (xy 180.561234 -329.927712)
			(xy 180.561234 -329.860656) (xy 180.560843 -329.851643) (xy 180.554618 -329.834726) (xy 180.549042 -329.827636)
			(xy 180.548788 -329.827636) (xy 180.548788 -329.827382) (xy 180.531172 -329.806431) (xy 180.501457 -329.760463)
			(xy 180.478617 -329.710721) (xy 180.46312 -329.658224) (xy 180.455286 -329.604052) (xy 180.454808 -329.576684)
			(xy 180.455294 -329.549433) (xy 180.46305 -329.495485) (xy 180.478405 -329.44319) (xy 180.501047 -329.393613)
			(xy 180.530513 -329.347763) (xy 180.566204 -329.306572) (xy 180.607395 -329.270881) (xy 180.653245 -329.241415)
			(xy 180.702822 -329.218773) (xy 180.755117 -329.203418) (xy 180.809065 -329.195662) (xy 180.863567 -329.195662)
			(xy 180.917515 -329.203418) (xy 180.96981 -329.218773) (xy 181.019387 -329.241415) (xy 181.065237 -329.270881)
			(xy 181.106428 -329.306572) (xy 181.142119 -329.347763) (xy 181.171585 -329.393613) (xy 181.194227 -329.44319)
			(xy 181.209582 -329.495485) (xy 181.217338 -329.549433) (xy 181.217824 -329.576684) (xy 181.217367 -329.604055)
			(xy 181.20955 -329.658235) (xy 181.19406 -329.710739) (xy 181.171215 -329.760486) (xy 181.141487 -329.806451)
			(xy 181.123844 -329.827382) (xy 181.12359 -329.827636) (xy 181.118023 -329.834736) (xy 181.111765 -329.851642)
			(xy 181.111398 -329.860656) (xy 181.111398 -329.927712) (xy 181.11175 -329.936729) (xy 181.118001 -329.953646)
			(xy 181.12359 -329.960732) (xy 181.123844 -329.960732) (xy 181.123844 -329.960986) (xy 181.141497 -329.981907)
			(xy 181.171206 -330.027883) (xy 181.194038 -330.077634) (xy 181.209526 -330.130137) (xy 181.217352 -330.184314)
			(xy 181.217824 -330.211684) (xy 181.217284 -330.240422) (xy 181.208664 -330.297249) (xy 181.191618 -330.352139)
			(xy 181.16653 -330.403851) (xy 181.133969 -330.451214) (xy 181.1147 -330.472542) (xy 181.108096 -330.4794)
			(xy 181.100984 -330.497434) (xy 181.100984 -330.586334) (xy 181.108096 -330.604368) (xy 181.1147 -330.611226)
			(xy 181.133954 -330.632567) (xy 181.166518 -330.679928) (xy 181.191608 -330.731637) (xy 181.208659 -330.786526)
			(xy 181.217282 -330.843351) (xy 181.217284 -330.900826) (xy 181.208664 -330.957652) (xy 181.191617 -331.012541)
			(xy 181.166529 -331.064252) (xy 181.133969 -331.111615) (xy 181.1147 -331.132942) (xy 181.108096 -331.1398)
			(xy 181.100984 -331.157834) (xy 181.100984 -331.246734) (xy 181.108096 -331.264768) (xy 181.1147 -331.271626)
			(xy 181.133952 -331.292969) (xy 181.166524 -331.340326) (xy 181.19162 -331.392033) (xy 181.208675 -331.446921)
			(xy 181.217301 -331.503746) (xy 181.217824 -331.532484) (xy 182.844186 -331.532484) (xy 182.844704 -331.503745)
			(xy 182.853328 -331.446917) (xy 182.87038 -331.392027) (xy 182.895473 -331.340315) (xy 182.928039 -331.292953)
			(xy 182.94731 -331.271626) (xy 182.953914 -331.264768) (xy 182.961026 -331.246734) (xy 182.961026 -331.157834)
			(xy 182.953914 -331.1398) (xy 182.94731 -331.132942) (xy 182.928024 -331.111629) (xy 182.89546 -331.064264)
			(xy 182.870371 -331.012549) (xy 182.853322 -330.957657) (xy 182.844702 -330.900828) (xy 182.844703 -330.843349)
			(xy 182.853328 -330.78652) (xy 182.870379 -330.731629) (xy 182.895472 -330.679916) (xy 182.928039 -330.632553)
			(xy 182.94731 -330.611226) (xy 182.953914 -330.604368) (xy 182.961026 -330.586334) (xy 182.961026 -330.497434)
			(xy 182.953914 -330.4794) (xy 182.94731 -330.472542) (xy 182.928027 -330.451226) (xy 182.895464 -330.40386)
			(xy 182.870374 -330.352146) (xy 182.853326 -330.297253) (xy 182.844706 -330.240424) (xy 182.844186 -330.211684)
			(xy 182.844646 -330.184314) (xy 182.852466 -330.130134) (xy 182.867957 -330.077631) (xy 182.890799 -330.027885)
			(xy 182.920525 -329.981918) (xy 182.938166 -329.960986) (xy 182.93842 -329.960732) (xy 182.944002 -329.953642)
			(xy 182.950251 -329.936728) (xy 182.950612 -329.927712) (xy 182.950612 -329.860656) (xy 182.950226 -329.851642)
			(xy 182.943998 -329.834725) (xy 182.93842 -329.827636) (xy 182.938166 -329.827636) (xy 182.938166 -329.827382)
			(xy 182.920547 -329.806434) (xy 182.890833 -329.760465) (xy 182.867994 -329.710722) (xy 182.852498 -329.658225)
			(xy 182.844664 -329.604052) (xy 182.844186 -329.576684) (xy 182.844672 -329.549433) (xy 182.852428 -329.495485)
			(xy 182.867783 -329.44319) (xy 182.890425 -329.393613) (xy 182.919891 -329.347763) (xy 182.955582 -329.306572)
			(xy 182.996773 -329.270881) (xy 183.042623 -329.241415) (xy 183.0922 -329.218773) (xy 183.144495 -329.203418)
			(xy 183.198443 -329.195662) (xy 183.252945 -329.195662) (xy 183.306893 -329.203418) (xy 183.359188 -329.218773)
			(xy 183.408765 -329.241415) (xy 183.454615 -329.270881) (xy 183.495806 -329.306572) (xy 183.531497 -329.347763)
			(xy 183.560963 -329.393613) (xy 183.583605 -329.44319) (xy 183.59896 -329.495485) (xy 183.606716 -329.549433)
			(xy 183.607202 -329.576684) (xy 183.606726 -329.604054) (xy 183.598911 -329.658233) (xy 183.583424 -329.710736)
			(xy 183.560584 -329.760483) (xy 183.530862 -329.80645) (xy 183.513222 -329.827382) (xy 183.512968 -329.827636)
			(xy 183.507399 -329.834734) (xy 183.501143 -329.851642) (xy 183.500776 -329.860656) (xy 183.500776 -329.927712)
			(xy 183.501133 -329.936729) (xy 183.507381 -329.953645) (xy 183.512968 -329.960732) (xy 183.513222 -329.960732)
			(xy 183.513222 -329.960986) (xy 183.530871 -329.98191) (xy 183.560581 -330.027885) (xy 183.583415 -330.077635)
			(xy 183.598903 -330.130137) (xy 183.606729 -330.184314) (xy 183.607202 -330.211684) (xy 183.606668 -330.240423)
			(xy 183.598048 -330.297249) (xy 183.581 -330.35214) (xy 183.555911 -330.403852) (xy 183.523348 -330.451215)
			(xy 183.504078 -330.472542) (xy 183.497474 -330.4794) (xy 183.490362 -330.497434) (xy 183.490362 -330.586334)
			(xy 183.497474 -330.604368) (xy 183.504078 -330.611226) (xy 183.523333 -330.632567) (xy 183.555898 -330.679927)
			(xy 183.580991 -330.731636) (xy 183.598042 -330.786525) (xy 183.606666 -330.84335) (xy 183.606668 -330.900826)
			(xy 183.598047 -330.957652) (xy 183.580999 -331.012542) (xy 183.55591 -331.064253) (xy 183.523348 -331.111615)
			(xy 183.504078 -331.132942) (xy 183.497474 -331.1398) (xy 183.490362 -331.157834) (xy 183.490362 -331.246734)
			(xy 183.497474 -331.264768) (xy 183.504078 -331.271626) (xy 183.523344 -331.292957) (xy 183.55591 -331.340318)
			(xy 183.581003 -331.392029) (xy 183.598055 -331.446919) (xy 183.60668 -331.503745) (xy 183.607202 -331.532484)
			(xy 186.550808 -331.532484) (xy 186.55132 -331.503745) (xy 186.559945 -331.446917) (xy 186.576998 -331.392026)
			(xy 186.602092 -331.340314) (xy 186.63466 -331.292952) (xy 186.653932 -331.271626) (xy 186.660536 -331.264768)
			(xy 186.667648 -331.246734) (xy 186.667648 -331.157834) (xy 186.660536 -331.1398) (xy 186.653932 -331.132942)
			(xy 186.634645 -331.111629) (xy 186.60208 -331.064265) (xy 186.576988 -331.012551) (xy 186.559939 -330.957658)
			(xy 186.551318 -330.900828) (xy 186.55132 -330.843349) (xy 186.559944 -330.78652) (xy 186.576997 -330.731628)
			(xy 186.602091 -330.679915) (xy 186.63466 -330.632553) (xy 186.653932 -330.611226) (xy 186.660536 -330.604368)
			(xy 186.667648 -330.586334) (xy 186.667648 -330.497434) (xy 186.660536 -330.4794) (xy 186.653932 -330.472542)
			(xy 186.634653 -330.451222) (xy 186.602088 -330.403858) (xy 186.576997 -330.352145) (xy 186.559948 -330.297252)
			(xy 186.551328 -330.240424) (xy 186.550808 -330.211684) (xy 186.551263 -330.184313) (xy 186.559083 -330.130134)
			(xy 186.574575 -330.07763) (xy 186.597419 -330.027884) (xy 186.627146 -329.981917) (xy 186.644788 -329.960986)
			(xy 186.645042 -329.960732) (xy 186.650626 -329.953644) (xy 186.656873 -329.936728) (xy 186.657234 -329.927712)
			(xy 186.657234 -329.860656) (xy 186.656843 -329.851643) (xy 186.650618 -329.834726) (xy 186.645042 -329.827636)
			(xy 186.644788 -329.827636) (xy 186.644788 -329.827382) (xy 186.627172 -329.806431) (xy 186.597457 -329.760463)
			(xy 186.574617 -329.710721) (xy 186.55912 -329.658224) (xy 186.551286 -329.604052) (xy 186.550808 -329.576684)
			(xy 186.551294 -329.549433) (xy 186.55905 -329.495485) (xy 186.574405 -329.44319) (xy 186.597047 -329.393613)
			(xy 186.626513 -329.347763) (xy 186.662204 -329.306572) (xy 186.703395 -329.270881) (xy 186.749245 -329.241415)
			(xy 186.798822 -329.218773) (xy 186.851117 -329.203418) (xy 186.905065 -329.195662) (xy 186.959567 -329.195662)
			(xy 187.013515 -329.203418) (xy 187.06581 -329.218773) (xy 187.115387 -329.241415) (xy 187.161237 -329.270881)
			(xy 187.202428 -329.306572) (xy 187.238119 -329.347763) (xy 187.267585 -329.393613) (xy 187.290227 -329.44319)
			(xy 187.305582 -329.495485) (xy 187.313338 -329.549433) (xy 187.313824 -329.576684) (xy 187.313367 -329.604055)
			(xy 187.30555 -329.658235) (xy 187.29006 -329.710739) (xy 187.267215 -329.760486) (xy 187.237487 -329.806451)
			(xy 187.219844 -329.827382) (xy 187.21959 -329.827636) (xy 187.214023 -329.834736) (xy 187.207765 -329.851642)
			(xy 187.207398 -329.860656) (xy 187.207398 -329.927712) (xy 187.20775 -329.936729) (xy 187.214001 -329.953646)
			(xy 187.21959 -329.960732) (xy 187.219844 -329.960732) (xy 187.219844 -329.960986) (xy 187.237497 -329.981907)
			(xy 187.267206 -330.027883) (xy 187.290038 -330.077634) (xy 187.305526 -330.130137) (xy 187.313352 -330.184314)
			(xy 187.313824 -330.211684) (xy 187.313284 -330.240422) (xy 187.304664 -330.297249) (xy 187.287618 -330.352139)
			(xy 187.26253 -330.403851) (xy 187.229969 -330.451214) (xy 187.2107 -330.472542) (xy 187.204096 -330.4794)
			(xy 187.196984 -330.497434) (xy 187.196984 -330.586334) (xy 187.204096 -330.604368) (xy 187.2107 -330.611226)
			(xy 187.229954 -330.632567) (xy 187.262518 -330.679928) (xy 187.287608 -330.731637) (xy 187.304659 -330.786526)
			(xy 187.313282 -330.843351) (xy 187.313284 -330.900826) (xy 187.304664 -330.957652) (xy 187.287617 -331.012541)
			(xy 187.262529 -331.064252) (xy 187.229969 -331.111615) (xy 187.2107 -331.132942) (xy 187.204096 -331.1398)
			(xy 187.196984 -331.157834) (xy 187.196984 -331.246734) (xy 187.204096 -331.264768) (xy 187.2107 -331.271626)
			(xy 187.229952 -331.292969) (xy 187.262524 -331.340326) (xy 187.28762 -331.392033) (xy 187.304675 -331.446921)
			(xy 187.306096 -331.456284) (xy 188.969142 -331.456284) (xy 188.969672 -331.427546) (xy 188.978295 -331.370719)
			(xy 188.995345 -331.315829) (xy 189.020434 -331.264117) (xy 189.052997 -331.216754) (xy 189.072266 -331.195426)
			(xy 189.07887 -331.188568) (xy 189.085982 -331.170534) (xy 189.085982 -331.081634) (xy 189.07887 -331.0636)
			(xy 189.072266 -331.056742) (xy 189.052982 -331.035428) (xy 189.020422 -330.988061) (xy 188.995335 -330.936347)
			(xy 188.978289 -330.881455) (xy 188.969669 -330.824627) (xy 188.969671 -330.767149) (xy 188.978294 -330.710322)
			(xy 188.995344 -330.655431) (xy 189.020434 -330.603718) (xy 189.052997 -330.556354) (xy 189.072266 -330.535026)
			(xy 189.07887 -330.528168) (xy 189.085982 -330.510134) (xy 189.085982 -330.421234) (xy 189.07887 -330.4032)
			(xy 189.072266 -330.396342) (xy 189.052992 -330.375017) (xy 189.020425 -330.327655) (xy 188.995333 -330.275943)
			(xy 188.978283 -330.221052) (xy 188.969662 -330.164223) (xy 188.969142 -330.135484) (xy 188.969588 -330.108113)
			(xy 188.977409 -330.053933) (xy 188.992903 -330.001429) (xy 189.015749 -329.951682) (xy 189.045478 -329.905717)
			(xy 189.063122 -329.884786) (xy 189.063376 -329.884532) (xy 189.068964 -329.877447) (xy 189.075208 -329.860529)
			(xy 189.075568 -329.851512) (xy 189.075568 -329.784456) (xy 189.075191 -329.775441) (xy 189.068958 -329.758524)
			(xy 189.063376 -329.751436) (xy 189.063122 -329.751436) (xy 189.063122 -329.751182) (xy 189.045511 -329.730227)
			(xy 189.015794 -329.684261) (xy 188.992953 -329.634519) (xy 188.977455 -329.582023) (xy 188.96962 -329.527852)
			(xy 188.969142 -329.500484) (xy 188.969628 -329.473233) (xy 188.977384 -329.419285) (xy 188.992739 -329.36699)
			(xy 189.015381 -329.317413) (xy 189.044847 -329.271563) (xy 189.080538 -329.230372) (xy 189.121729 -329.194681)
			(xy 189.167579 -329.165215) (xy 189.217156 -329.142573) (xy 189.269451 -329.127218) (xy 189.323399 -329.119462)
			(xy 189.377901 -329.119462) (xy 189.431849 -329.127218) (xy 189.484144 -329.142573) (xy 189.533721 -329.165215)
			(xy 189.579571 -329.194681) (xy 189.620762 -329.230372) (xy 189.656453 -329.271563) (xy 189.685919 -329.317413)
			(xy 189.708561 -329.36699) (xy 189.723916 -329.419285) (xy 189.731672 -329.473233) (xy 189.732158 -329.500484)
			(xy 189.731693 -329.527854) (xy 189.723876 -329.582034) (xy 189.708388 -329.634537) (xy 189.685545 -329.684284)
			(xy 189.65582 -329.730251) (xy 189.638178 -329.751182) (xy 189.637924 -329.751436) (xy 189.632349 -329.75853)
			(xy 189.626097 -329.775441) (xy 189.625732 -329.784456) (xy 189.625732 -329.851512) (xy 189.626076 -329.86053)
			(xy 189.632332 -329.877448) (xy 189.637924 -329.884532) (xy 189.638178 -329.884532) (xy 189.638178 -329.884786)
			(xy 189.655821 -329.905715) (xy 189.685533 -329.951689) (xy 189.708368 -330.001437) (xy 189.723858 -330.053938)
			(xy 189.731685 -330.108115) (xy 189.732158 -330.135484) (xy 189.731609 -330.164222) (xy 189.72299 -330.221047)
			(xy 189.705945 -330.275937) (xy 189.68086 -330.327649) (xy 189.648301 -330.375014) (xy 189.629034 -330.396342)
			(xy 189.62243 -330.4032) (xy 189.615318 -330.421234) (xy 189.615318 -330.510134) (xy 189.62243 -330.528168)
			(xy 189.629034 -330.535026) (xy 189.648286 -330.556368) (xy 189.680847 -330.603729) (xy 189.705936 -330.655439)
			(xy 189.722984 -330.710327) (xy 189.731607 -330.767151) (xy 189.731609 -330.824626) (xy 189.72299 -330.88145)
			(xy 189.705944 -330.936339) (xy 189.680859 -330.98805) (xy 189.648301 -331.035414) (xy 189.629034 -331.056742)
			(xy 189.62243 -331.0636) (xy 189.615318 -331.081634) (xy 189.615318 -331.170534) (xy 189.62243 -331.188568)
			(xy 189.629034 -331.195426) (xy 189.648292 -331.216764) (xy 189.680862 -331.264122) (xy 189.705957 -331.315831)
			(xy 189.72301 -331.37072) (xy 189.731636 -331.427546) (xy 189.732158 -331.456284) (xy 192.621408 -331.456284)
			(xy 192.62192 -331.427545) (xy 192.630545 -331.370717) (xy 192.647598 -331.315826) (xy 192.672692 -331.264114)
			(xy 192.70526 -331.216752) (xy 192.724532 -331.195426) (xy 192.731136 -331.188568) (xy 192.738248 -331.170534)
			(xy 192.738248 -331.081634) (xy 192.731136 -331.0636) (xy 192.724532 -331.056742) (xy 192.705245 -331.035429)
			(xy 192.67268 -330.988065) (xy 192.647588 -330.936351) (xy 192.630539 -330.881458) (xy 192.621918 -330.824628)
			(xy 192.62192 -330.767149) (xy 192.630544 -330.71032) (xy 192.647597 -330.655428) (xy 192.672691 -330.603715)
			(xy 192.70526 -330.556353) (xy 192.724532 -330.535026) (xy 192.731136 -330.528168) (xy 192.738248 -330.510134)
			(xy 192.738248 -330.421234) (xy 192.731136 -330.4032) (xy 192.724532 -330.396342) (xy 192.705253 -330.375022)
			(xy 192.672688 -330.327658) (xy 192.647597 -330.275945) (xy 192.630548 -330.221052) (xy 192.621928 -330.164224)
			(xy 192.621408 -330.135484) (xy 192.621863 -330.108113) (xy 192.629683 -330.053934) (xy 192.645175 -330.00143)
			(xy 192.668019 -329.951684) (xy 192.697746 -329.905717) (xy 192.715388 -329.884786) (xy 192.715642 -329.884532)
			(xy 192.721226 -329.877444) (xy 192.727473 -329.860528) (xy 192.727834 -329.851512) (xy 192.727834 -329.784456)
			(xy 192.727443 -329.775443) (xy 192.721218 -329.758526) (xy 192.715642 -329.751436) (xy 192.715388 -329.751436)
			(xy 192.715388 -329.751182) (xy 192.697772 -329.730231) (xy 192.668057 -329.684263) (xy 192.645217 -329.634521)
			(xy 192.62972 -329.582024) (xy 192.621886 -329.527852) (xy 192.621408 -329.500484) (xy 192.621894 -329.473233)
			(xy 192.62965 -329.419285) (xy 192.645005 -329.36699) (xy 192.667647 -329.317413) (xy 192.697113 -329.271563)
			(xy 192.732804 -329.230372) (xy 192.773995 -329.194681) (xy 192.819845 -329.165215) (xy 192.869422 -329.142573)
			(xy 192.921717 -329.127218) (xy 192.975665 -329.119462) (xy 193.030167 -329.119462) (xy 193.084115 -329.127218)
			(xy 193.13641 -329.142573) (xy 193.185987 -329.165215) (xy 193.231837 -329.194681) (xy 193.273028 -329.230372)
			(xy 193.308719 -329.271563) (xy 193.338185 -329.317413) (xy 193.360827 -329.36699) (xy 193.376182 -329.419285)
			(xy 193.383938 -329.473233) (xy 193.384424 -329.500484) (xy 193.383967 -329.527855) (xy 193.37615 -329.582035)
			(xy 193.36066 -329.634539) (xy 193.337815 -329.684286) (xy 193.308087 -329.730251) (xy 193.290444 -329.751182)
			(xy 193.29019 -329.751436) (xy 193.284623 -329.758536) (xy 193.278365 -329.775442) (xy 193.277998 -329.784456)
			(xy 193.277998 -329.851512) (xy 193.27835 -329.860529) (xy 193.284601 -329.877446) (xy 193.29019 -329.884532)
			(xy 193.290444 -329.884532) (xy 193.290444 -329.884786) (xy 193.308097 -329.905707) (xy 193.337806 -329.951683)
			(xy 193.360638 -330.001434) (xy 193.376126 -330.053937) (xy 193.383952 -330.108114) (xy 193.384424 -330.135484)
			(xy 193.383884 -330.164222) (xy 193.375264 -330.221049) (xy 193.358218 -330.275939) (xy 193.33313 -330.327651)
			(xy 193.300569 -330.375014) (xy 193.2813 -330.396342) (xy 193.274696 -330.4032) (xy 193.267584 -330.421234)
			(xy 193.267584 -330.510134) (xy 193.274696 -330.528168) (xy 193.2813 -330.535026) (xy 193.300554 -330.556367)
			(xy 193.333118 -330.603728) (xy 193.358208 -330.655437) (xy 193.375259 -330.710326) (xy 193.383882 -330.767151)
			(xy 193.383884 -330.824626) (xy 193.375264 -330.881452) (xy 193.358217 -330.936341) (xy 193.333129 -330.988052)
			(xy 193.300569 -331.035415) (xy 193.2813 -331.056742) (xy 193.274696 -331.0636) (xy 193.267584 -331.081634)
			(xy 193.267584 -331.170534) (xy 193.274696 -331.188568) (xy 193.2813 -331.195426) (xy 193.300552 -331.216769)
			(xy 193.333124 -331.264126) (xy 193.35822 -331.315833) (xy 193.375275 -331.370721) (xy 193.383901 -331.427546)
			(xy 193.384207 -331.444346) (xy 195.076826 -331.444346) (xy 195.077337 -331.415607) (xy 195.085965 -331.35878)
			(xy 195.10302 -331.30389) (xy 195.128114 -331.252178) (xy 195.160679 -331.204815) (xy 195.17995 -331.183488)
			(xy 195.186554 -331.17663) (xy 195.193666 -331.158596) (xy 195.193666 -331.069696) (xy 195.186554 -331.051662)
			(xy 195.17995 -331.044804) (xy 195.160724 -331.023438) (xy 195.128155 -330.976083) (xy 195.103059 -330.924378)
			(xy 195.086004 -330.869493) (xy 195.077377 -330.81267) (xy 195.077372 -330.755197) (xy 195.085989 -330.698373)
			(xy 195.103034 -330.643485) (xy 195.128121 -330.591775) (xy 195.160681 -330.544414) (xy 195.17995 -330.523088)
			(xy 195.186554 -330.51623) (xy 195.193666 -330.498196) (xy 195.193666 -330.409296) (xy 195.186554 -330.391262)
			(xy 195.17995 -330.384404) (xy 195.160656 -330.363097) (xy 195.128092 -330.31573) (xy 195.103004 -330.264013)
			(xy 195.085959 -330.209118) (xy 195.077343 -330.152286) (xy 195.076826 -330.123546) (xy 195.077313 -330.096176)
			(xy 195.085125 -330.041998) (xy 195.100608 -329.989495) (xy 195.123446 -329.939748) (xy 195.153166 -329.89378)
			(xy 195.170806 -329.872848) (xy 195.17106 -329.872594) (xy 195.176662 -329.865518) (xy 195.182898 -329.848593)
			(xy 195.183252 -329.839574) (xy 195.183252 -329.772518) (xy 195.182897 -329.763501) (xy 195.176649 -329.746583)
			(xy 195.17106 -329.739498) (xy 195.170806 -329.739498) (xy 195.170806 -329.739244) (xy 195.153175 -329.718305)
			(xy 195.123462 -329.672334) (xy 195.100624 -329.622589) (xy 195.085131 -329.570089) (xy 195.077301 -329.515915)
			(xy 195.076826 -329.488546) (xy 195.077312 -329.461295) (xy 195.085068 -329.407347) (xy 195.100423 -329.355052)
			(xy 195.123065 -329.305475) (xy 195.152531 -329.259625) (xy 195.188222 -329.218434) (xy 195.229413 -329.182743)
			(xy 195.275263 -329.153277) (xy 195.32484 -329.130635) (xy 195.377135 -329.11528) (xy 195.431083 -329.107524)
			(xy 195.485585 -329.107524) (xy 195.539533 -329.11528) (xy 195.591828 -329.130635) (xy 195.641405 -329.153277)
			(xy 195.687255 -329.182743) (xy 195.728446 -329.218434) (xy 195.764137 -329.259625) (xy 195.793603 -329.305475)
			(xy 195.816245 -329.355052) (xy 195.8316 -329.407347) (xy 195.839356 -329.461295) (xy 195.839842 -329.488546)
			(xy 195.839358 -329.515916) (xy 195.831547 -329.570095) (xy 195.816063 -329.622598) (xy 195.793225 -329.672345)
			(xy 195.763502 -329.718312) (xy 195.745862 -329.739244) (xy 195.745608 -329.739498) (xy 195.740017 -329.746582)
			(xy 195.733773 -329.763501) (xy 195.733416 -329.772518) (xy 195.733416 -329.839574) (xy 195.733782 -329.84859)
			(xy 195.740023 -329.865507) (xy 195.745608 -329.872594) (xy 195.745862 -329.872594) (xy 195.745862 -329.872848)
			(xy 195.763484 -329.893794) (xy 195.7932 -329.939762) (xy 195.81604 -329.989506) (xy 195.831535 -330.042004)
			(xy 195.839366 -330.096178) (xy 195.839842 -330.123546) (xy 195.839335 -330.152285) (xy 195.830707 -330.209113)
			(xy 195.813652 -330.264003) (xy 195.788557 -330.315715) (xy 195.75599 -330.363077) (xy 195.736718 -330.384404)
			(xy 195.730114 -330.391262) (xy 195.723002 -330.409296) (xy 195.723002 -330.498196) (xy 195.730114 -330.51623)
			(xy 195.736718 -330.523088) (xy 195.756032 -330.544376) (xy 195.788593 -330.591746) (xy 195.813679 -330.643465)
			(xy 195.830724 -330.698361) (xy 195.839341 -330.755193) (xy 195.839336 -330.812674) (xy 195.830709 -330.869505)
			(xy 195.813654 -330.924398) (xy 195.788559 -330.976112) (xy 195.75599 -331.023476) (xy 195.736718 -331.044804)
			(xy 195.730114 -331.051662) (xy 195.723002 -331.069696) (xy 195.723002 -331.158596) (xy 195.730114 -331.17663)
			(xy 195.736718 -331.183488) (xy 195.756003 -331.204803) (xy 195.788569 -331.252167) (xy 195.81366 -331.303882)
			(xy 195.830707 -331.358776) (xy 195.839324 -331.415606) (xy 195.839842 -331.444346) (xy 195.839356 -331.471597)
			(xy 195.8316 -331.525545) (xy 195.816245 -331.57784) (xy 195.793603 -331.627417) (xy 195.764137 -331.673267)
			(xy 195.728446 -331.714458) (xy 195.687255 -331.750149) (xy 195.641405 -331.779615) (xy 195.591828 -331.802257)
			(xy 195.539533 -331.817612) (xy 195.485585 -331.825368) (xy 195.431083 -331.825368) (xy 195.377135 -331.817612)
			(xy 195.32484 -331.802257) (xy 195.275263 -331.779615) (xy 195.229413 -331.750149) (xy 195.188222 -331.714458)
			(xy 195.152531 -331.673267) (xy 195.123065 -331.627417) (xy 195.100423 -331.57784) (xy 195.085068 -331.525545)
			(xy 195.077312 -331.471597) (xy 195.076826 -331.444346) (xy 193.384207 -331.444346) (xy 193.384424 -331.456284)
			(xy 193.383938 -331.483535) (xy 193.376182 -331.537483) (xy 193.360827 -331.589778) (xy 193.338185 -331.639355)
			(xy 193.308719 -331.685205) (xy 193.273028 -331.726396) (xy 193.231837 -331.762087) (xy 193.185987 -331.791553)
			(xy 193.13641 -331.814195) (xy 193.084115 -331.82955) (xy 193.030167 -331.837306) (xy 192.975665 -331.837306)
			(xy 192.921717 -331.82955) (xy 192.869422 -331.814195) (xy 192.819845 -331.791553) (xy 192.773995 -331.762087)
			(xy 192.732804 -331.726396) (xy 192.697113 -331.685205) (xy 192.667647 -331.639355) (xy 192.645005 -331.589778)
			(xy 192.62965 -331.537483) (xy 192.621894 -331.483535) (xy 192.621408 -331.456284) (xy 189.732158 -331.456284)
			(xy 189.731672 -331.483535) (xy 189.723916 -331.537483) (xy 189.708561 -331.589778) (xy 189.685919 -331.639355)
			(xy 189.656453 -331.685205) (xy 189.620762 -331.726396) (xy 189.579571 -331.762087) (xy 189.533721 -331.791553)
			(xy 189.484144 -331.814195) (xy 189.431849 -331.82955) (xy 189.377901 -331.837306) (xy 189.323399 -331.837306)
			(xy 189.269451 -331.82955) (xy 189.217156 -331.814195) (xy 189.167579 -331.791553) (xy 189.121729 -331.762087)
			(xy 189.080538 -331.726396) (xy 189.044847 -331.685205) (xy 189.015381 -331.639355) (xy 188.992739 -331.589778)
			(xy 188.977384 -331.537483) (xy 188.969628 -331.483535) (xy 188.969142 -331.456284) (xy 187.306096 -331.456284)
			(xy 187.313301 -331.503746) (xy 187.313824 -331.532484) (xy 187.313338 -331.559735) (xy 187.305582 -331.613683)
			(xy 187.290227 -331.665978) (xy 187.267585 -331.715555) (xy 187.238119 -331.761405) (xy 187.202428 -331.802596)
			(xy 187.161237 -331.838287) (xy 187.115387 -331.867753) (xy 187.06581 -331.890395) (xy 187.013515 -331.90575)
			(xy 186.959567 -331.913506) (xy 186.905065 -331.913506) (xy 186.851117 -331.90575) (xy 186.798822 -331.890395)
			(xy 186.749245 -331.867753) (xy 186.703395 -331.838287) (xy 186.662204 -331.802596) (xy 186.626513 -331.761405)
			(xy 186.597047 -331.715555) (xy 186.574405 -331.665978) (xy 186.55905 -331.613683) (xy 186.551294 -331.559735)
			(xy 186.550808 -331.532484) (xy 183.607202 -331.532484) (xy 183.606716 -331.559735) (xy 183.59896 -331.613683)
			(xy 183.583605 -331.665978) (xy 183.560963 -331.715555) (xy 183.531497 -331.761405) (xy 183.495806 -331.802596)
			(xy 183.454615 -331.838287) (xy 183.408765 -331.867753) (xy 183.359188 -331.890395) (xy 183.306893 -331.90575)
			(xy 183.252945 -331.913506) (xy 183.198443 -331.913506) (xy 183.144495 -331.90575) (xy 183.0922 -331.890395)
			(xy 183.042623 -331.867753) (xy 182.996773 -331.838287) (xy 182.955582 -331.802596) (xy 182.919891 -331.761405)
			(xy 182.890425 -331.715555) (xy 182.867783 -331.665978) (xy 182.852428 -331.613683) (xy 182.844672 -331.559735)
			(xy 182.844186 -331.532484) (xy 181.217824 -331.532484) (xy 181.217338 -331.559735) (xy 181.209582 -331.613683)
			(xy 181.194227 -331.665978) (xy 181.171585 -331.715555) (xy 181.142119 -331.761405) (xy 181.106428 -331.802596)
			(xy 181.065237 -331.838287) (xy 181.019387 -331.867753) (xy 180.96981 -331.890395) (xy 180.917515 -331.90575)
			(xy 180.863567 -331.913506) (xy 180.809065 -331.913506) (xy 180.755117 -331.90575) (xy 180.702822 -331.890395)
			(xy 180.653245 -331.867753) (xy 180.607395 -331.838287) (xy 180.566204 -331.802596) (xy 180.530513 -331.761405)
			(xy 180.501047 -331.715555) (xy 180.478405 -331.665978) (xy 180.46305 -331.613683) (xy 180.455294 -331.559735)
			(xy 180.454808 -331.532484) (xy 177.542009 -331.532484) (xy 177.541704 -331.549575) (xy 177.533948 -331.603523)
			(xy 177.518593 -331.655818) (xy 177.495951 -331.705395) (xy 177.466485 -331.751245) (xy 177.430794 -331.792436)
			(xy 177.389603 -331.828127) (xy 177.343753 -331.857593) (xy 177.294176 -331.880235) (xy 177.241881 -331.89559)
			(xy 177.187933 -331.903346) (xy 177.133431 -331.903346) (xy 177.079483 -331.89559) (xy 177.027188 -331.880235)
			(xy 176.977611 -331.857593) (xy 176.931761 -331.828127) (xy 176.89057 -331.792436) (xy 176.854879 -331.751245)
			(xy 176.825413 -331.705395) (xy 176.802771 -331.655818) (xy 176.787416 -331.603523) (xy 176.77966 -331.549575)
			(xy 176.779174 -331.522324) (xy 175.152812 -331.522324) (xy 175.152326 -331.549575) (xy 175.14457 -331.603523)
			(xy 175.129215 -331.655818) (xy 175.106573 -331.705395) (xy 175.077107 -331.751245) (xy 175.041416 -331.792436)
			(xy 175.000225 -331.828127) (xy 174.954375 -331.857593) (xy 174.904798 -331.880235) (xy 174.852503 -331.89559)
			(xy 174.798555 -331.903346) (xy 174.744053 -331.903346) (xy 174.690105 -331.89559) (xy 174.63781 -331.880235)
			(xy 174.588233 -331.857593) (xy 174.542383 -331.828127) (xy 174.501192 -331.792436) (xy 174.465501 -331.751245)
			(xy 174.436035 -331.705395) (xy 174.413393 -331.655818) (xy 174.398038 -331.603523) (xy 174.390282 -331.549575)
			(xy 174.389796 -331.522324) (xy 147.082932 -331.522324) (xy 147.407666 -333.121508) (xy 167.537892 -333.121508)
			(xy 167.53833 -333.08433) (xy 167.545581 -333.010329) (xy 167.560006 -332.937387) (xy 167.581466 -332.866196)
			(xy 167.609759 -332.797433) (xy 167.626792 -332.764384) (xy 167.632093 -332.753025) (xy 167.632097 -332.727989)
			(xy 167.626792 -332.716632) (xy 167.609761 -332.683583) (xy 167.581488 -332.614815) (xy 167.560038 -332.543623)
			(xy 167.545614 -332.470682) (xy 167.538353 -332.396684) (xy 167.537892 -332.359508) (xy 167.538381 -332.320863)
			(xy 167.546201 -332.243969) (xy 167.561759 -332.168261) (xy 167.584897 -332.094515) (xy 167.615377 -332.023488)
			(xy 167.652886 -331.95591) (xy 167.69704 -331.892472) (xy 167.747385 -331.833828) (xy 167.803404 -331.780577)
			(xy 167.864523 -331.733267) (xy 167.930116 -331.692383) (xy 167.999507 -331.658345) (xy 168.071987 -331.631502)
			(xy 168.14681 -331.612129) (xy 168.223209 -331.600425) (xy 168.3004 -331.59651) (xy 168.377591 -331.600425)
			(xy 168.45399 -331.612129) (xy 168.528813 -331.631502) (xy 168.601293 -331.658345) (xy 168.670684 -331.692383)
			(xy 168.736277 -331.733267) (xy 168.797396 -331.780577) (xy 168.853415 -331.833828) (xy 168.90376 -331.892472)
			(xy 168.947914 -331.95591) (xy 168.985423 -332.023488) (xy 169.015903 -332.094515) (xy 169.039041 -332.168261)
			(xy 169.054599 -332.243969) (xy 169.062419 -332.320863) (xy 169.062908 -332.359508) (xy 169.062477 -332.396686)
			(xy 169.055224 -332.470687) (xy 169.040798 -332.54363) (xy 169.019336 -332.614821) (xy 168.991041 -332.683583)
			(xy 168.974008 -332.716632) (xy 168.968696 -332.727987) (xy 168.968699 -332.753027) (xy 168.974008 -332.764384)
			(xy 168.991045 -332.79743) (xy 169.019317 -332.866199) (xy 169.040765 -332.937392) (xy 169.055188 -333.010333)
			(xy 169.062448 -333.084331) (xy 169.062908 -333.121508) (xy 169.062419 -333.160153) (xy 169.054599 -333.237047)
			(xy 169.039041 -333.312755) (xy 169.015903 -333.386501) (xy 168.985423 -333.457528) (xy 168.947914 -333.525106)
			(xy 168.90376 -333.588544) (xy 168.853415 -333.647188) (xy 168.797396 -333.700439) (xy 168.736277 -333.747749)
			(xy 168.670684 -333.788633) (xy 168.601293 -333.822671) (xy 168.528813 -333.849514) (xy 168.45399 -333.868887)
			(xy 168.377591 -333.880591) (xy 168.3004 -333.884506) (xy 168.223209 -333.880591) (xy 168.14681 -333.868887)
			(xy 168.071987 -333.849514) (xy 167.999507 -333.822671) (xy 167.930116 -333.788633) (xy 167.864523 -333.747749)
			(xy 167.803404 -333.700439) (xy 167.747385 -333.647188) (xy 167.69704 -333.588544) (xy 167.652886 -333.525106)
			(xy 167.615377 -333.457528) (xy 167.584897 -333.386501) (xy 167.561759 -333.312755) (xy 167.546201 -333.237047)
			(xy 167.538381 -333.160153) (xy 167.537892 -333.121508) (xy 147.407666 -333.121508) (xy 148.954744 -340.740238)
			(xy 148.956268 -340.746334) (xy 149.098508 -341.16772) (xy 149.164802 -341.364062) (xy 149.166806 -341.369588)
			(xy 149.172962 -341.379597) (xy 149.176994 -341.383874) (xy 149.848062 -342.054942) (xy 149.853565 -342.059922)
			(xy 149.866734 -342.066751) (xy 149.87397 -342.068404) (xy 149.883622 -342.06942)
		)
		(stroke
			(width 0)
			(type solid)
		)
		(fill yes)
		(layer "In13.Cu")
		(net "PVDD11_S3_P1")
	)
	(gr_poly
		(pts
			(xy 347.608398 -256.30124) (xy 347.618277 -256.300785) (xy 347.636585 -256.293351) (xy 347.643958 -256.286762)
			(xy 347.644212 -256.286508) (xy 348.130876 -255.799844) (xy 348.137988 -255.78562) (xy 348.139258 -255.777492)
			(xy 348.143921 -255.751302) (xy 348.161082 -255.700954) (xy 348.186693 -255.654333) (xy 348.219981 -255.612845)
			(xy 348.239588 -255.594866) (xy 348.247421 -255.587277) (xy 348.256363 -255.567407) (xy 348.25686 -255.556512)
			(xy 348.25686 -255.377188) (xy 348.25686 -255.363726) (xy 348.243906 -255.340612) (xy 348.158816 -255.288542)
			(xy 348.151267 -255.284289) (xy 348.134339 -255.280655) (xy 348.117173 -255.282919) (xy 348.109286 -255.28651)
			(xy 348.087753 -255.296914) (xy 348.042256 -255.311637) (xy 347.99502 -255.319091) (xy 347.97111 -255.31953)
			(xy 347.947118 -255.31906) (xy 347.899723 -255.311555) (xy 347.854087 -255.296729) (xy 347.811331 -255.274946)
			(xy 347.772509 -255.246744) (xy 347.738577 -255.212815) (xy 347.71037 -255.173996) (xy 347.688583 -255.131243)
			(xy 347.673752 -255.085608) (xy 347.666242 -255.038214) (xy 347.665802 -255.014222) (xy 347.666273 -254.989987)
			(xy 347.673941 -254.942128) (xy 347.689072 -254.896081) (xy 347.711287 -254.853002) (xy 347.740028 -254.813972)
			(xy 347.774573 -254.779972) (xy 347.814054 -254.751856) (xy 347.857481 -254.730329) (xy 347.903763 -254.715931)
			(xy 347.927676 -254.711962) (xy 347.941138 -254.710184) (xy 347.97111 -254.70866) (xy 347.995062 -254.709103)
			(xy 348.042387 -254.716532) (xy 348.087972 -254.731253) (xy 348.10954 -254.74168) (xy 348.121478 -254.747776)
			(xy 348.14764 -254.74676) (xy 348.23273 -254.69469) (xy 348.23992 -254.689828) (xy 348.250778 -254.676301)
			(xy 348.256509 -254.65993) (xy 348.25686 -254.651256) (xy 348.25686 -254.516382) (xy 348.256731 -254.510594)
			(xy 348.254161 -254.499308) (xy 348.25178 -254.49403) (xy 348.237556 -254.465074) (xy 348.229174 -254.458216)
			(xy 348.209283 -254.440942) (xy 348.174709 -254.401196) (xy 348.146868 -254.356475) (xy 348.126462 -254.307909)
			(xy 348.114009 -254.256723) (xy 348.109821 -254.20421) (xy 348.114005 -254.151698) (xy 348.126456 -254.100511)
			(xy 348.146858 -254.051943) (xy 348.174697 -254.00722) (xy 348.209269 -253.967473) (xy 348.229174 -253.950216)
			(xy 348.237556 -253.943358) (xy 348.25178 -253.914402) (xy 348.254154 -253.909123) (xy 348.256713 -253.897837)
			(xy 348.25686 -253.89205) (xy 348.25686 -253.757176) (xy 348.25686 -253.743714) (xy 348.243906 -253.7206)
			(xy 348.158816 -253.66853) (xy 348.151267 -253.664277) (xy 348.134339 -253.660644) (xy 348.117174 -253.662908)
			(xy 348.109286 -253.666498) (xy 348.087753 -253.676902) (xy 348.042256 -253.691626) (xy 347.99502 -253.699079)
			(xy 347.97111 -253.699518) (xy 347.947118 -253.699048) (xy 347.899724 -253.691543) (xy 347.854088 -253.676717)
			(xy 347.811334 -253.654934) (xy 347.772513 -253.626731) (xy 347.738582 -253.592802) (xy 347.710376 -253.553983)
			(xy 347.688591 -253.51123) (xy 347.673761 -253.465595) (xy 347.666253 -253.418202) (xy 347.665802 -253.39421)
			(xy 347.666274 -253.369976) (xy 347.673943 -253.322118) (xy 347.689076 -253.276072) (xy 347.711292 -253.232995)
			(xy 347.740032 -253.193967) (xy 347.774577 -253.159969) (xy 347.814058 -253.131854) (xy 347.857484 -253.110327)
			(xy 347.903765 -253.095931) (xy 347.927676 -253.09195) (xy 347.941138 -253.090172) (xy 347.97111 -253.088648)
			(xy 347.995062 -253.089091) (xy 348.042387 -253.09652) (xy 348.087973 -253.11124) (xy 348.10954 -253.121668)
			(xy 348.121478 -253.127764) (xy 348.14764 -253.126748) (xy 348.23273 -253.074424) (xy 348.238173 -253.070859)
			(xy 348.247173 -253.061468) (xy 348.25051 -253.055882) (xy 348.269052 -253.022862) (xy 348.277434 -253.011686)
			(xy 349.174054 -252.115066) (xy 349.174562 -252.114558) (xy 349.181145 -252.107177) (xy 349.188598 -252.088878)
			(xy 349.18904 -252.078998) (xy 349.18904 -251.252482) (xy 349.188612 -251.242415) (xy 349.180886 -251.223821)
			(xy 349.174054 -251.216414) (xy 348.32925 -250.37161) (xy 348.322138 -250.364498) (xy 348.303596 -250.356624)
			(xy 348.211648 -250.35637) (xy 348.19336 -250.363736) (xy 348.185994 -250.371102) (xy 348.168728 -250.38756)
			(xy 348.130034 -250.415451) (xy 348.087472 -250.436981) (xy 348.042079 -250.451628) (xy 347.994959 -250.459035)
			(xy 347.97111 -250.459494) (xy 347.947117 -250.459049) (xy 347.899721 -250.451543) (xy 347.854083 -250.436715)
			(xy 347.811326 -250.41493) (xy 347.772504 -250.386724) (xy 347.738573 -250.352793) (xy 347.710368 -250.31397)
			(xy 347.688583 -250.271214) (xy 347.673756 -250.225575) (xy 347.666251 -250.178179) (xy 347.665802 -250.154186)
			(xy 347.666261 -250.130337) (xy 347.673677 -250.083219) (xy 347.688324 -250.037826) (xy 347.709849 -249.995262)
			(xy 347.737728 -249.956559) (xy 347.754194 -249.939302) (xy 347.76156 -249.931936) (xy 347.768926 -249.913648)
			(xy 347.768672 -249.83186) (xy 347.768127 -249.821876) (xy 347.7604 -249.803457) (xy 347.753686 -249.796046)
			(xy 347.613732 -249.656092) (xy 347.607496 -249.650328) (xy 347.592218 -249.642933) (xy 347.575365 -249.640925)
			(xy 347.566996 -249.642376) (xy 347.566742 -249.642376) (xy 347.550563 -249.6457) (xy 347.517725 -249.649261)
			(xy 347.50121 -249.649488) (xy 347.477217 -249.649043) (xy 347.429821 -249.641537) (xy 347.384184 -249.626709)
			(xy 347.341428 -249.604924) (xy 347.302606 -249.576718) (xy 347.268675 -249.542786) (xy 347.240471 -249.503964)
			(xy 347.218687 -249.461207) (xy 347.203861 -249.415569) (xy 347.196357 -249.368173) (xy 347.195902 -249.34418)
			(xy 347.196125 -249.327665) (xy 347.199692 -249.294827) (xy 347.203014 -249.278648) (xy 347.203014 -249.278394)
			(xy 347.204531 -249.27003) (xy 347.202528 -249.253161) (xy 347.195075 -249.237895) (xy 347.189298 -249.231658)
			(xy 347.111066 -249.153426) (xy 347.103954 -249.14606) (xy 347.085158 -249.13844) (xy 346.014294 -249.13844)
			(xy 346.002629 -249.139013) (xy 345.981711 -249.14934) (xy 345.974162 -249.158252) (xy 345.92514 -249.222006)
			(xy 345.918466 -249.231609) (xy 345.913834 -249.254506) (xy 345.91625 -249.265948) (xy 345.91625 -249.266202)
			(xy 345.920995 -249.285282) (xy 345.926094 -249.324267) (xy 345.92641 -249.343926) (xy 345.92641 -249.346974)
			(xy 345.925671 -249.372078) (xy 345.917 -249.421543) (xy 345.900351 -249.468922) (xy 345.876173 -249.512938)
			(xy 345.845118 -249.552404) (xy 345.808024 -249.586256) (xy 345.76589 -249.613581) (xy 345.719852 -249.633643)
			(xy 345.671152 -249.645901) (xy 345.621102 -249.650024) (xy 345.571052 -249.645901) (xy 345.522352 -249.633643)
			(xy 345.476314 -249.613581) (xy 345.43418 -249.586256) (xy 345.397086 -249.552404) (xy 345.366031 -249.512938)
			(xy 345.341853 -249.468922) (xy 345.325204 -249.421543) (xy 345.316533 -249.372078) (xy 345.315794 -249.346974)
			(xy 345.315794 -249.343926) (xy 345.31615 -249.32427) (xy 345.321251 -249.28529) (xy 345.325954 -249.266202)
			(xy 345.325954 -249.265948) (xy 345.328371 -249.254506) (xy 345.32374 -249.231608) (xy 345.317064 -249.222006)
			(xy 345.268042 -249.158252) (xy 345.26046 -249.149383) (xy 345.239561 -249.139062) (xy 345.22791 -249.13844)
			(xy 344.785442 -249.13844) (xy 344.775378 -249.138005) (xy 344.756794 -249.130269) (xy 344.749374 -249.123454)
			(xy 344.417396 -248.791476) (xy 344.382852 -248.787158) (xy 344.367612 -248.796302) (xy 344.343774 -248.809823)
			(xy 344.292466 -248.829069) (xy 344.238547 -248.838844) (xy 344.211148 -248.839482) (xy 344.198702 -248.839228)
			(xy 344.173465 -248.837707) (xy 344.123978 -248.82736) (xy 344.076873 -248.809002) (xy 344.033435 -248.783134)
			(xy 343.994852 -248.750464) (xy 343.962179 -248.711884) (xy 343.936308 -248.668448) (xy 343.917946 -248.621344)
			(xy 343.907595 -248.571858) (xy 343.906094 -248.54662) (xy 343.90584 -248.541286) (xy 343.90584 -248.534174)
			(xy 343.906456 -248.506774) (xy 343.916245 -248.452856) (xy 343.935504 -248.401553) (xy 343.94902 -248.37771)
			(xy 343.958164 -248.36247) (xy 343.953846 -248.327926) (xy 343.877646 -248.251726) (xy 343.870806 -248.244326)
			(xy 343.863091 -248.225727) (xy 343.86266 -248.215658) (xy 343.86266 -248.134632) (xy 343.862172 -248.124299)
			(xy 343.854041 -248.105298) (xy 343.846912 -248.097802) (xy 343.785952 -248.039636) (xy 343.779856 -248.03735)
			(xy 343.770178 -248.038442) (xy 343.750733 -248.039584) (xy 343.740994 -248.039636) (xy 343.716207 -248.039149)
			(xy 343.667244 -248.031393) (xy 343.620097 -248.016074) (xy 343.575927 -247.993567) (xy 343.535822 -247.964428)
			(xy 343.500768 -247.929374) (xy 343.47163 -247.889268) (xy 343.449124 -247.845097) (xy 343.433805 -247.79795)
			(xy 343.42605 -247.748987) (xy 343.42605 -247.699413) (xy 343.433805 -247.65045) (xy 343.449124 -247.603303)
			(xy 343.47163 -247.559132) (xy 343.500768 -247.519026) (xy 343.535822 -247.483972) (xy 343.575927 -247.454833)
			(xy 343.620097 -247.432326) (xy 343.667244 -247.417007) (xy 343.716207 -247.409251) (xy 343.740994 -247.4087)
			(xy 343.750734 -247.40874) (xy 343.770179 -247.409883) (xy 343.779856 -247.410986) (xy 343.785952 -247.4087)
			(xy 343.846912 -247.350534) (xy 343.85403 -247.343109) (xy 343.862146 -247.324232) (xy 343.86266 -247.313958)
			(xy 343.86266 -246.51462) (xy 343.86217 -246.504288) (xy 343.854036 -246.485291) (xy 343.846912 -246.47779)
			(xy 343.785952 -246.419624) (xy 343.779856 -246.417338) (xy 343.770178 -246.41843) (xy 343.750733 -246.419573)
			(xy 343.740994 -246.419624) (xy 343.716208 -246.419137) (xy 343.667247 -246.411382) (xy 343.620102 -246.396062)
			(xy 343.575933 -246.373557) (xy 343.535829 -246.344419) (xy 343.500777 -246.309366) (xy 343.47164 -246.269262)
			(xy 343.449135 -246.225093) (xy 343.433817 -246.177947) (xy 343.426062 -246.128986) (xy 343.426062 -246.079414)
			(xy 343.433817 -246.030453) (xy 343.449135 -245.983307) (xy 343.47164 -245.939138) (xy 343.500777 -245.899034)
			(xy 343.535829 -245.863981) (xy 343.575933 -245.834843) (xy 343.620102 -245.812338) (xy 343.667247 -245.797018)
			(xy 343.716208 -245.789263) (xy 343.740994 -245.788688) (xy 343.750734 -245.788728) (xy 343.770179 -245.789871)
			(xy 343.779856 -245.790974) (xy 343.785952 -245.788688) (xy 343.846912 -245.730522) (xy 343.854044 -245.723102)
			(xy 343.862192 -245.704225) (xy 343.86266 -245.693946) (xy 343.86266 -244.894608) (xy 343.862168 -244.884277)
			(xy 343.854031 -244.865283) (xy 343.846912 -244.857778) (xy 343.785952 -244.799612) (xy 343.779856 -244.797326)
			(xy 343.770178 -244.798418) (xy 343.750733 -244.799561) (xy 343.740994 -244.799612) (xy 343.716201 -244.799125)
			(xy 343.667226 -244.791368) (xy 343.620068 -244.776044) (xy 343.575887 -244.753532) (xy 343.535772 -244.724386)
			(xy 343.50071 -244.689324) (xy 343.471565 -244.649208) (xy 343.449053 -244.605027) (xy 343.433731 -244.557868)
			(xy 343.425974 -244.508893) (xy 343.425974 -244.459307) (xy 343.433731 -244.410332) (xy 343.449053 -244.363173)
			(xy 343.471565 -244.318992) (xy 343.50071 -244.278876) (xy 343.535772 -244.243814) (xy 343.575887 -244.214668)
			(xy 343.620068 -244.192156) (xy 343.667226 -244.176832) (xy 343.716201 -244.169075) (xy 343.740994 -244.168676)
			(xy 343.750734 -244.168716) (xy 343.770179 -244.169859) (xy 343.779856 -244.170962) (xy 343.785952 -244.168676)
			(xy 343.846912 -244.11051) (xy 343.854042 -244.10309) (xy 343.862186 -244.084212) (xy 343.86266 -244.073934)
			(xy 343.86266 -243.274596) (xy 343.862165 -243.264266) (xy 343.854025 -243.245275) (xy 343.846912 -243.237766)
			(xy 343.785952 -243.1796) (xy 343.779856 -243.177314) (xy 343.770178 -243.178406) (xy 343.750733 -243.179549)
			(xy 343.740994 -243.1796) (xy 343.716202 -243.179113) (xy 343.667229 -243.171356) (xy 343.620072 -243.156033)
			(xy 343.575893 -243.133522) (xy 343.53578 -243.104377) (xy 343.500719 -243.069316) (xy 343.471575 -243.029201)
			(xy 343.449065 -242.985022) (xy 343.433743 -242.937865) (xy 343.425986 -242.888892) (xy 343.425986 -242.839308)
			(xy 343.433743 -242.790335) (xy 343.449065 -242.743178) (xy 343.471575 -242.698999) (xy 343.500719 -242.658884)
			(xy 343.53578 -242.623823) (xy 343.575893 -242.594678) (xy 343.620072 -242.572167) (xy 343.667229 -242.556844)
			(xy 343.716202 -242.549087) (xy 343.740994 -242.548664) (xy 343.750734 -242.548704) (xy 343.770179 -242.549847)
			(xy 343.779856 -242.55095) (xy 343.785952 -242.548664) (xy 343.846912 -242.490498) (xy 343.85404 -242.483077)
			(xy 343.862179 -242.4642) (xy 343.86266 -242.453922) (xy 343.86266 -241.654584) (xy 343.862182 -241.644247)
			(xy 343.854064 -241.625232) (xy 343.846912 -241.617754) (xy 343.785952 -241.559588) (xy 343.779856 -241.557302)
			(xy 343.770178 -241.558394) (xy 343.750733 -241.559537) (xy 343.740994 -241.559588) (xy 343.716203 -241.559102)
			(xy 343.667232 -241.551344) (xy 343.620077 -241.536022) (xy 343.5759 -241.513512) (xy 343.535787 -241.484368)
			(xy 343.500728 -241.449308) (xy 343.471585 -241.409195) (xy 343.449076 -241.365017) (xy 343.433754 -241.317862)
			(xy 343.425998 -241.268891) (xy 343.425998 -241.219309) (xy 343.433754 -241.170338) (xy 343.449076 -241.123183)
			(xy 343.471585 -241.079005) (xy 343.500728 -241.038892) (xy 343.535787 -241.003832) (xy 343.5759 -240.974688)
			(xy 343.620077 -240.952178) (xy 343.667232 -240.936856) (xy 343.716203 -240.929098) (xy 343.740994 -240.928652)
			(xy 343.750734 -240.928692) (xy 343.770179 -240.929835) (xy 343.779856 -240.930938) (xy 343.785952 -240.928652)
			(xy 343.846912 -240.870486) (xy 343.854038 -240.863064) (xy 343.862173 -240.844187) (xy 343.86266 -240.83391)
			(xy 343.86266 -240.034572) (xy 343.86218 -240.024236) (xy 343.854059 -240.005224) (xy 343.846912 -239.997742)
			(xy 343.785952 -239.939576) (xy 343.779856 -239.93729) (xy 343.770178 -239.938382) (xy 343.750733 -239.939525)
			(xy 343.740994 -239.939576) (xy 343.716204 -239.93909) (xy 343.667235 -239.931333) (xy 343.620082 -239.916011)
			(xy 343.575906 -239.893502) (xy 343.535795 -239.864359) (xy 343.500737 -239.8293) (xy 343.471595 -239.789189)
			(xy 343.449087 -239.745013) (xy 343.433766 -239.697859) (xy 343.42601 -239.64889) (xy 343.42601 -239.59931)
			(xy 343.433766 -239.550341) (xy 343.449087 -239.503187) (xy 343.471595 -239.459011) (xy 343.500737 -239.4189)
			(xy 343.535795 -239.383841) (xy 343.575906 -239.354698) (xy 343.620082 -239.332189) (xy 343.667235 -239.316867)
			(xy 343.716204 -239.30911) (xy 343.740994 -239.30864) (xy 343.750734 -239.30868) (xy 343.770179 -239.309823)
			(xy 343.779856 -239.310926) (xy 343.785952 -239.30864) (xy 343.846912 -239.250474) (xy 343.854036 -239.243052)
			(xy 343.862167 -239.224174) (xy 343.86266 -239.213898) (xy 343.86266 -238.41456) (xy 343.862177 -238.404225)
			(xy 343.854054 -238.385216) (xy 343.846912 -238.37773) (xy 343.785952 -238.319564) (xy 343.779856 -238.317278)
			(xy 343.770178 -238.31837) (xy 343.750733 -238.319512) (xy 343.740994 -238.319564) (xy 343.716205 -238.319077)
			(xy 343.667238 -238.311321) (xy 343.620086 -238.295999) (xy 343.575912 -238.273491) (xy 343.535803 -238.244349)
			(xy 343.500747 -238.209292) (xy 343.471606 -238.169182) (xy 343.449098 -238.125008) (xy 343.433778 -238.077857)
			(xy 343.426022 -238.028889) (xy 343.426022 -237.979311) (xy 343.433778 -237.930343) (xy 343.449098 -237.883192)
			(xy 343.471606 -237.839018) (xy 343.500747 -237.798908) (xy 343.535803 -237.763851) (xy 343.575912 -237.734709)
			(xy 343.620086 -237.712201) (xy 343.667238 -237.696879) (xy 343.716205 -237.689123) (xy 343.740994 -237.688628)
			(xy 343.750734 -237.688668) (xy 343.770179 -237.689811) (xy 343.779856 -237.690914) (xy 343.785952 -237.688628)
			(xy 343.846912 -237.630462) (xy 343.854034 -237.623039) (xy 343.86216 -237.604161) (xy 343.86266 -237.593886)
			(xy 343.86266 -236.794548) (xy 343.862175 -236.784214) (xy 343.854048 -236.765209) (xy 343.846912 -236.757718)
			(xy 343.785952 -236.699552) (xy 343.779856 -236.697266) (xy 343.770178 -236.698358) (xy 343.750733 -236.6995)
			(xy 343.740994 -236.699552) (xy 343.716206 -236.699065) (xy 343.66724 -236.691309) (xy 343.620091 -236.675988)
			(xy 343.575919 -236.653481) (xy 343.535811 -236.62434) (xy 343.500756 -236.589284) (xy 343.471616 -236.549176)
			(xy 343.449109 -236.505003) (xy 343.43379 -236.457854) (xy 343.426034 -236.408888) (xy 343.426034 -236.359312)
			(xy 343.43379 -236.310346) (xy 343.449109 -236.263197) (xy 343.471616 -236.219024) (xy 343.500756 -236.178916)
			(xy 343.535811 -236.14386) (xy 343.575919 -236.114719) (xy 343.620091 -236.092212) (xy 343.66724 -236.076891)
			(xy 343.716206 -236.069135) (xy 343.740994 -236.068616) (xy 343.750734 -236.068656) (xy 343.770179 -236.069799)
			(xy 343.779856 -236.070902) (xy 343.785952 -236.068616) (xy 343.846912 -236.01045) (xy 343.854032 -236.003026)
			(xy 343.862154 -235.984149) (xy 343.86266 -235.973874) (xy 343.86266 -235.174536) (xy 343.862173 -235.164203)
			(xy 343.854043 -235.145201) (xy 343.846912 -235.137706) (xy 343.785952 -235.07954) (xy 343.779856 -235.077254)
			(xy 343.770178 -235.078346) (xy 343.750733 -235.079488) (xy 343.740994 -235.07954) (xy 343.716207 -235.079053)
			(xy 343.667243 -235.071297) (xy 343.620096 -235.055977) (xy 343.575925 -235.03347) (xy 343.535819 -235.004331)
			(xy 343.500765 -234.969276) (xy 343.471626 -234.92917) (xy 343.44912 -234.884999) (xy 343.433801 -234.837851)
			(xy 343.426046 -234.788887) (xy 343.426046 -234.739313) (xy 343.433801 -234.690349) (xy 343.44912 -234.643201)
			(xy 343.471626 -234.59903) (xy 343.500765 -234.558924) (xy 343.535819 -234.523869) (xy 343.575925 -234.49473)
			(xy 343.620096 -234.472223) (xy 343.667243 -234.456903) (xy 343.716207 -234.449147) (xy 343.740994 -234.448604)
			(xy 343.750734 -234.448644) (xy 343.770179 -234.449787) (xy 343.779856 -234.45089) (xy 343.785952 -234.448604)
			(xy 343.846912 -234.390438) (xy 343.85403 -234.383014) (xy 343.862148 -234.364136) (xy 343.86266 -234.353862)
			(xy 343.86266 -233.554524) (xy 343.862171 -233.544192) (xy 343.854038 -233.525193) (xy 343.846912 -233.517694)
			(xy 343.785952 -233.459528) (xy 343.779856 -233.457242) (xy 343.770178 -233.458334) (xy 343.750733 -233.459477)
			(xy 343.740994 -233.459528) (xy 343.716208 -233.459041) (xy 343.667246 -233.451286) (xy 343.6201 -233.435966)
			(xy 343.575931 -233.41346) (xy 343.535827 -233.384322) (xy 343.500774 -233.349269) (xy 343.471637 -233.309164)
			(xy 343.449132 -233.264994) (xy 343.433813 -233.217848) (xy 343.426058 -233.168886) (xy 343.426058 -233.119314)
			(xy 343.433813 -233.070352) (xy 343.449132 -233.023206) (xy 343.471637 -232.979036) (xy 343.500774 -232.938931)
			(xy 343.535827 -232.903878) (xy 343.575931 -232.87474) (xy 343.6201 -232.852234) (xy 343.667246 -232.836914)
			(xy 343.716208 -232.829159) (xy 343.740994 -232.828592) (xy 343.750734 -232.828632) (xy 343.770179 -232.829775)
			(xy 343.779856 -232.830878) (xy 343.785952 -232.828592) (xy 343.846912 -232.770426) (xy 343.854029 -232.763001)
			(xy 343.862141 -232.744123) (xy 343.86266 -232.73385) (xy 343.86266 -231.934512) (xy 343.862168 -231.924181)
			(xy 343.854032 -231.905186) (xy 343.846912 -231.897682) (xy 343.785952 -231.839516) (xy 343.779856 -231.83723)
			(xy 343.770178 -231.838322) (xy 343.750733 -231.839465) (xy 343.740994 -231.839516) (xy 343.716201 -231.839029)
			(xy 343.667225 -231.831272) (xy 343.620066 -231.815948) (xy 343.575885 -231.793436) (xy 343.535769 -231.764289)
			(xy 343.500707 -231.729226) (xy 343.471561 -231.68911) (xy 343.44905 -231.644928) (xy 343.433727 -231.597769)
			(xy 343.42597 -231.548793) (xy 343.42597 -231.499207) (xy 343.433727 -231.450231) (xy 343.44905 -231.403072)
			(xy 343.471561 -231.35889) (xy 343.500707 -231.318774) (xy 343.535769 -231.283711) (xy 343.575885 -231.254564)
			(xy 343.620066 -231.232052) (xy 343.667225 -231.216728) (xy 343.716201 -231.208971) (xy 343.740994 -231.20858)
			(xy 343.750734 -231.20862) (xy 343.770179 -231.209763) (xy 343.779856 -231.210866) (xy 343.785952 -231.20858)
			(xy 343.846912 -231.150414) (xy 343.854042 -231.142994) (xy 343.862188 -231.124117) (xy 343.86266 -231.113838)
			(xy 343.86266 -230.3145) (xy 343.862166 -230.30417) (xy 343.854027 -230.285178) (xy 343.846912 -230.27767)
			(xy 343.785952 -230.219504) (xy 343.779856 -230.217218) (xy 343.770178 -230.21831) (xy 343.750733 -230.219453)
			(xy 343.740994 -230.219504) (xy 343.716202 -230.219017) (xy 343.667228 -230.21126) (xy 343.620071 -230.195937)
			(xy 343.575891 -230.173425) (xy 343.535777 -230.14428) (xy 343.500716 -230.109218) (xy 343.471571 -230.069104)
			(xy 343.449061 -230.024924) (xy 343.433739 -229.977766) (xy 343.425982 -229.928792) (xy 343.425982 -229.879208)
			(xy 343.433739 -229.830234) (xy 343.449061 -229.783076) (xy 343.471571 -229.738896) (xy 343.500716 -229.698782)
			(xy 343.535777 -229.66372) (xy 343.575891 -229.634575) (xy 343.620071 -229.612063) (xy 343.667228 -229.59674)
			(xy 343.716202 -229.588983) (xy 343.740994 -229.588568) (xy 343.750734 -229.588608) (xy 343.770179 -229.589751)
			(xy 343.779856 -229.590854) (xy 343.785952 -229.588568) (xy 343.846912 -229.530402) (xy 343.854041 -229.522981)
			(xy 343.862181 -229.504104) (xy 343.86266 -229.493826) (xy 343.86266 -228.694742) (xy 343.862174 -228.684408)
			(xy 343.854046 -228.665405) (xy 343.846912 -228.657912) (xy 343.785952 -228.599746) (xy 343.779856 -228.59746)
			(xy 343.770181 -228.598616) (xy 343.750737 -228.59989) (xy 343.740994 -228.6) (xy 343.716186 -228.599513)
			(xy 343.667182 -228.591751) (xy 343.619996 -228.576418) (xy 343.575789 -228.553893) (xy 343.53565 -228.524729)
			(xy 343.500567 -228.489646) (xy 343.471404 -228.449506) (xy 343.44888 -228.405299) (xy 343.433548 -228.358112)
			(xy 343.425787 -228.309108) (xy 343.425787 -228.259492) (xy 343.433548 -228.210488) (xy 343.44888 -228.163301)
			(xy 343.471404 -228.119094) (xy 343.500567 -228.078954) (xy 343.53565 -228.043871) (xy 343.575789 -228.014707)
			(xy 343.619996 -227.992182) (xy 343.667182 -227.976849) (xy 343.716186 -227.969087) (xy 343.740994 -227.968556)
			(xy 343.750737 -227.968659) (xy 343.770182 -227.969929) (xy 343.779856 -227.971096) (xy 343.785952 -227.96881)
			(xy 343.846912 -227.910644) (xy 343.854031 -227.90322) (xy 343.862151 -227.884342) (xy 343.86266 -227.874068)
			(xy 343.86266 -227.07473) (xy 343.862172 -227.064397) (xy 343.85404 -227.045397) (xy 343.846912 -227.0379)
			(xy 343.785952 -226.979734) (xy 343.779856 -226.977448) (xy 343.770181 -226.978604) (xy 343.750737 -226.979878)
			(xy 343.740994 -226.979988) (xy 343.716187 -226.979501) (xy 343.667185 -226.971739) (xy 343.620001 -226.956407)
			(xy 343.575795 -226.933882) (xy 343.535658 -226.90472) (xy 343.500576 -226.869638) (xy 343.471415 -226.8295)
			(xy 343.448891 -226.785294) (xy 343.43356 -226.738109) (xy 343.425799 -226.689107) (xy 343.425799 -226.639493)
			(xy 343.43356 -226.590491) (xy 343.448891 -226.543306) (xy 343.471415 -226.4991) (xy 343.500576 -226.458962)
			(xy 343.535658 -226.42388) (xy 343.575795 -226.394718) (xy 343.620001 -226.372193) (xy 343.667185 -226.356861)
			(xy 343.716187 -226.349099) (xy 343.740994 -226.348544) (xy 343.750737 -226.348647) (xy 343.770182 -226.349917)
			(xy 343.779856 -226.351084) (xy 343.785952 -226.348798) (xy 343.846912 -226.290632) (xy 343.85403 -226.283207)
			(xy 343.862145 -226.264329) (xy 343.86266 -226.254056) (xy 343.86266 -225.450654) (xy 343.862176 -225.440319)
			(xy 343.854051 -225.421312) (xy 343.846912 -225.413824) (xy 343.786206 -225.356166) (xy 343.766902 -225.3488)
			(xy 343.756488 -225.349308) (xy 343.740994 -225.349562) (xy 343.715743 -225.34904) (xy 343.665929 -225.340727)
			(xy 343.618164 -225.324328) (xy 343.573748 -225.300291) (xy 343.533895 -225.269271) (xy 343.499691 -225.232115)
			(xy 343.472069 -225.189836) (xy 343.451783 -225.143587) (xy 343.439385 -225.09463) (xy 343.435215 -225.0443)
			(xy 343.439385 -224.99397) (xy 343.451783 -224.945013) (xy 343.472069 -224.898764) (xy 343.499691 -224.856485)
			(xy 343.533895 -224.819329) (xy 343.573748 -224.788309) (xy 343.618164 -224.764272) (xy 343.665929 -224.747873)
			(xy 343.715743 -224.73956) (xy 343.740994 -224.738946) (xy 343.756488 -224.7392) (xy 343.766902 -224.739708)
			(xy 343.786206 -224.732342) (xy 343.846912 -224.674684) (xy 343.854075 -224.66721) (xy 343.862211 -224.648196)
			(xy 343.86266 -224.637854) (xy 343.86266 -223.830642) (xy 343.862174 -223.820308) (xy 343.854046 -223.801305)
			(xy 343.846912 -223.793812) (xy 343.786206 -223.736154) (xy 343.766902 -223.728788) (xy 343.756488 -223.729296)
			(xy 343.740994 -223.72955) (xy 343.715736 -223.729028) (xy 343.665908 -223.720712) (xy 343.618128 -223.704309)
			(xy 343.5737 -223.680265) (xy 343.533836 -223.649236) (xy 343.499622 -223.612069) (xy 343.471992 -223.569778)
			(xy 343.4517 -223.523516) (xy 343.439299 -223.474544) (xy 343.435127 -223.4242) (xy 343.439299 -223.373856)
			(xy 343.4517 -223.324884) (xy 343.471992 -223.278622) (xy 343.499622 -223.236331) (xy 343.533836 -223.199164)
			(xy 343.5737 -223.168135) (xy 343.618128 -223.144091) (xy 343.665908 -223.127688) (xy 343.715736 -223.119372)
			(xy 343.740994 -223.118934) (xy 343.756488 -223.119188) (xy 343.766902 -223.119696) (xy 343.786206 -223.11233)
			(xy 343.846912 -223.054672) (xy 343.854073 -223.047197) (xy 343.862205 -223.028183) (xy 343.86266 -223.017842)
			(xy 343.86266 -221.316042) (xy 343.862225 -221.305977) (xy 343.854491 -221.287392) (xy 343.847674 -221.279974)
			(xy 343.000076 -220.432376) (xy 342.993987 -220.425873) (xy 342.986406 -220.409764) (xy 342.984843 -220.392028)
			(xy 342.986868 -220.383354) (xy 342.989154 -220.374718) (xy 342.980518 -220.347032) (xy 340.400132 -218.119198)
			(xy 340.370414 -218.115134) (xy 340.356698 -218.121738) (xy 340.331157 -218.133228) (xy 340.277546 -218.149425)
			(xy 340.22214 -218.157592) (xy 340.194138 -218.15806) (xy 340.167942 -218.157622) (xy 340.116045 -218.150441)
			(xy 340.06562 -218.136224) (xy 340.017615 -218.115239) (xy 339.972935 -218.087879) (xy 339.93242 -218.054661)
			(xy 339.896835 -218.016209) (xy 339.881464 -217.994992) (xy 339.87588 -217.987754) (xy 339.860778 -217.977479)
			(xy 339.852 -217.974926) (xy 339.822282 -217.967306) (xy 339.813149 -217.965432) (xy 339.794655 -217.967661)
			(xy 339.786214 -217.971624) (xy 339.758826 -217.985469) (xy 339.701442 -218.007223) (xy 339.641855 -218.021906)
			(xy 339.580933 -218.029304) (xy 339.550248 -218.02979) (xy 339.515294 -218.029208) (xy 339.446046 -218.019631)
			(xy 339.37876 -218.000666) (xy 339.314703 -217.97267) (xy 339.255081 -217.936168) (xy 339.227668 -217.914474)
			(xy 339.22065 -217.909239) (xy 339.204158 -217.903395) (xy 339.19541 -217.903044) (xy 338.889086 -217.903044)
			(xy 338.880328 -217.903352) (xy 338.863818 -217.909189) (xy 338.856828 -217.914474) (xy 338.829431 -217.936192)
			(xy 338.76981 -217.972704) (xy 338.70575 -218.000706) (xy 338.638459 -218.019669) (xy 338.569204 -218.029238)
			(xy 338.534248 -218.02979) (xy 338.503565 -218.029309) (xy 338.442647 -218.021888) (xy 338.383064 -218.007196)
			(xy 338.32568 -217.985447) (xy 338.298282 -217.971624) (xy 338.289843 -217.967668) (xy 338.271351 -217.965464)
			(xy 338.262214 -217.967306) (xy 338.232496 -217.974926) (xy 338.2237 -217.977443) (xy 338.208583 -217.987721)
			(xy 338.203032 -217.994992) (xy 338.187686 -218.01623) (xy 338.152104 -218.054693) (xy 338.111589 -218.08792)
			(xy 338.066905 -218.115284) (xy 338.018894 -218.136271) (xy 337.968461 -218.150483) (xy 337.916557 -218.157654)
			(xy 337.890358 -218.15806) (xy 337.863112 -218.157571) (xy 337.809176 -218.149811) (xy 337.756893 -218.134454)
			(xy 337.707327 -218.111813) (xy 337.661488 -218.082349) (xy 337.620308 -218.046662) (xy 337.584625 -218.005479)
			(xy 337.555167 -217.959636) (xy 337.532532 -217.910068) (xy 337.51718 -217.857783) (xy 337.509426 -217.803846)
			(xy 337.509426 -217.749354) (xy 337.51718 -217.695417) (xy 337.532532 -217.643132) (xy 337.555167 -217.593564)
			(xy 337.584625 -217.547721) (xy 337.620308 -217.506538) (xy 337.661488 -217.470851) (xy 337.707327 -217.441387)
			(xy 337.756893 -217.418746) (xy 337.809176 -217.403389) (xy 337.863112 -217.395629) (xy 337.890358 -217.395044)
			(xy 337.909998 -217.3953) (xy 337.949065 -217.399374) (xy 337.968336 -217.403172) (xy 337.977368 -217.404672)
			(xy 337.995462 -217.40195) (xy 338.003642 -217.397838) (xy 338.030566 -217.382598) (xy 338.038431 -217.377715)
			(xy 338.050301 -217.363529) (xy 338.05368 -217.354912) (xy 338.064422 -217.325321) (xy 338.092201 -217.268829)
			(xy 338.126742 -217.216198) (xy 338.167518 -217.168235) (xy 338.213904 -217.125674) (xy 338.26519 -217.089166)
			(xy 338.320591 -217.059269) (xy 338.379259 -217.036442) (xy 338.440298 -217.021033) (xy 338.502771 -217.013278)
			(xy 338.534248 -217.012774) (xy 338.569202 -217.013356) (xy 338.638451 -217.022931) (xy 338.705738 -217.041895)
			(xy 338.769797 -217.069889) (xy 338.82942 -217.106388) (xy 338.856828 -217.12809) (xy 338.863848 -217.13332)
			(xy 338.880339 -217.139158) (xy 338.889086 -217.13952) (xy 339.128862 -217.13952) (xy 339.139214 -217.139095)
			(xy 339.158267 -217.13101) (xy 339.172549 -217.11603) (xy 339.176614 -217.1065) (xy 339.182202 -217.091768)
			(xy 339.174328 -217.061034) (xy 324.671436 -204.540358) (xy 324.67042 -204.539342) (xy 318.425322 -199.418956)
			(xy 318.415749 -199.411873) (xy 318.392566 -199.406556) (xy 318.380872 -199.408796) (xy 318.290194 -199.431148)
			(xy 318.27216 -199.446642) (xy 318.267334 -199.457818) (xy 318.253962 -199.488093) (xy 318.220507 -199.545201)
			(xy 318.179928 -199.597486) (xy 318.13291 -199.644067) (xy 318.080247 -199.684156) (xy 318.022829 -199.717076)
			(xy 317.961627 -199.742271) (xy 317.897674 -199.759314) (xy 317.83205 -199.767919) (xy 317.798958 -199.76846)
			(xy 317.767884 -199.767992) (xy 317.706201 -199.760415) (xy 317.6459 -199.74538) (xy 317.58788 -199.723109)
			(xy 317.533006 -199.693936) (xy 317.482094 -199.658295) (xy 317.435905 -199.616716) (xy 317.395125 -199.569819)
			(xy 317.360362 -199.518304) (xy 317.345822 -199.490838) (xy 317.341504 -199.482202) (xy 317.32728 -199.469502)
			(xy 317.24473 -199.438768) (xy 317.225934 -199.439276) (xy 317.217044 -199.442832) (xy 317.192193 -199.452609)
			(xy 317.140904 -199.467494) (xy 317.114682 -199.47255) (xy 317.105524 -199.474651) (xy 317.089487 -199.48441)
			(xy 317.08344 -199.4916) (xy 317.064644 -199.516238) (xy 317.059298 -199.523876) (xy 317.053945 -199.541718)
			(xy 317.05423 -199.551036) (xy 317.0555 -199.581008) (xy 317.055043 -199.607945) (xy 317.047479 -199.661285)
			(xy 317.032488 -199.71303) (xy 317.010368 -199.762153) (xy 316.981559 -199.807677) (xy 316.946633 -199.848696)
			(xy 316.906285 -199.884395) (xy 316.861318 -199.914065) (xy 316.812624 -199.937115) (xy 316.787022 -199.945498)
			(xy 316.779183 -199.948266) (xy 316.765705 -199.957982) (xy 316.760606 -199.964548) (xy 316.743588 -199.988678)
			(xy 316.738996 -199.995764) (xy 316.734333 -200.011984) (xy 316.734444 -200.020428) (xy 316.734952 -200.044812)
			(xy 316.734475 -200.076356) (xy 316.72667 -200.13896) (xy 316.711181 -200.200117) (xy 316.688247 -200.258889)
			(xy 316.658218 -200.314373) (xy 316.621557 -200.365716) (xy 316.578827 -200.41213) (xy 316.530684 -200.452903)
			(xy 316.477867 -200.487407) (xy 316.421188 -200.515113) (xy 316.361517 -200.535595) (xy 316.299771 -200.548539)
			(xy 316.236898 -200.553746) (xy 316.173864 -200.551136) (xy 316.111636 -200.540749) (xy 316.051171 -200.522745)
			(xy 315.993398 -200.4974) (xy 315.939203 -200.465103) (xy 315.88942 -200.426351) (xy 315.844812 -200.381738)
			(xy 315.806065 -200.33195) (xy 315.773775 -200.277752) (xy 315.748436 -200.219976) (xy 315.730438 -200.159509)
			(xy 315.720058 -200.097281) (xy 315.717455 -200.034246) (xy 315.722669 -199.971373) (xy 315.73562 -199.909629)
			(xy 315.756109 -199.84996) (xy 315.783821 -199.793284) (xy 315.818331 -199.740471) (xy 315.859109 -199.692332)
			(xy 315.905527 -199.649607) (xy 315.956875 -199.612952) (xy 316.012362 -199.58293) (xy 316.071136 -199.560001)
			(xy 316.132295 -199.544519) (xy 316.1949 -199.536721) (xy 316.226444 -199.536304) (xy 316.232794 -199.536304)
			(xy 316.241273 -199.536114) (xy 316.257363 -199.530785) (xy 316.26429 -199.52589) (xy 316.287658 -199.50811)
			(xy 316.294105 -199.50278) (xy 316.303438 -199.488912) (xy 316.305946 -199.480932) (xy 316.313535 -199.45469)
			(xy 316.335191 -199.404538) (xy 316.363785 -199.357992) (xy 316.398733 -199.316006) (xy 316.439318 -199.27944)
			(xy 316.484707 -199.249044) (xy 316.509146 -199.236838) (xy 316.517401 -199.232515) (xy 316.530314 -199.219101)
			(xy 316.534292 -199.210676) (xy 316.545976 -199.181974) (xy 316.549313 -199.173108) (xy 316.549824 -199.154185)
			(xy 316.546992 -199.145144) (xy 316.537335 -199.117296) (xy 316.523772 -199.059934) (xy 316.516944 -199.001388)
			(xy 316.516512 -198.971916) (xy 316.516994 -198.940255) (xy 316.524855 -198.877422) (xy 316.540456 -198.816051)
			(xy 316.563557 -198.757093) (xy 316.5938 -198.701459) (xy 316.630717 -198.650011) (xy 316.673736 -198.603545)
			(xy 316.722192 -198.56278) (xy 316.775335 -198.528348) (xy 316.832342 -198.50078) (xy 316.89233 -198.480504)
			(xy 316.954372 -198.467833) (xy 316.985904 -198.464932) (xy 317.001652 -198.463662) (xy 317.025782 -198.444612)
			(xy 317.058802 -198.33971) (xy 317.061406 -198.329921) (xy 317.059544 -198.309768) (xy 317.050071 -198.291881)
			(xy 317.042546 -198.2851) (xy 316.440058 -197.79107) (xy 316.431784 -197.784821) (xy 316.411916 -197.778965)
			(xy 316.391355 -197.781475) (xy 316.382146 -197.786244) (xy 316.286134 -197.842378) (xy 316.272672 -197.871334)
			(xy 316.275466 -197.887082) (xy 316.279028 -197.908814) (xy 316.282841 -197.952691) (xy 316.283086 -197.974712)
			(xy 316.282609 -198.006166) (xy 316.274835 -198.068593) (xy 316.259419 -198.129584) (xy 316.236597 -198.188207)
			(xy 316.206718 -198.243567) (xy 316.170238 -198.294819) (xy 316.127714 -198.341179) (xy 316.079796 -198.381939)
			(xy 316.027216 -198.416476) (xy 315.970777 -198.444264) (xy 315.911341 -198.464877) (xy 315.849816 -198.478)
			(xy 315.81852 -198.481188) (xy 315.807852 -198.482204) (xy 315.789056 -198.492618) (xy 315.730382 -198.570342)
			(xy 315.725556 -198.59117) (xy 315.727588 -198.601838) (xy 315.731964 -198.625792) (xy 315.73667 -198.674263)
			(xy 315.736986 -198.698612) (xy 315.736484 -198.730573) (xy 315.728473 -198.793991) (xy 315.712576 -198.855905)
			(xy 315.689044 -198.915338) (xy 315.65825 -198.971353) (xy 315.620677 -199.023068) (xy 315.57692 -199.069665)
			(xy 315.527667 -199.11041) (xy 315.473696 -199.144661) (xy 315.415857 -199.171878) (xy 315.355064 -199.191631)
			(xy 315.292274 -199.203609) (xy 315.228478 -199.207623) (xy 315.164682 -199.203609) (xy 315.101892 -199.191631)
			(xy 315.041099 -199.171878) (xy 314.98326 -199.144661) (xy 314.929289 -199.11041) (xy 314.880036 -199.069665)
			(xy 314.836279 -199.023068) (xy 314.798706 -198.971353) (xy 314.767912 -198.915338) (xy 314.74438 -198.855905)
			(xy 314.728483 -198.793991) (xy 314.720472 -198.730573) (xy 314.71997 -198.698612) (xy 314.720446 -198.667158)
			(xy 314.728218 -198.604731) (xy 314.743632 -198.543741) (xy 314.766453 -198.485118) (xy 314.796332 -198.429758)
			(xy 314.832813 -198.378507) (xy 314.875338 -198.332149) (xy 314.923257 -198.291391) (xy 314.975839 -198.256857)
			(xy 315.03228 -198.229073) (xy 315.091717 -198.208465) (xy 315.153242 -198.195348) (xy 315.184536 -198.192136)
			(xy 315.195204 -198.19112) (xy 315.214 -198.180706) (xy 315.272674 -198.102982) (xy 315.2775 -198.082154)
			(xy 315.275468 -198.071486) (xy 315.271091 -198.047532) (xy 315.266383 -197.999061) (xy 315.26607 -197.974712)
			(xy 315.266538 -197.943286) (xy 315.274284 -197.880912) (xy 315.289659 -197.819969) (xy 315.312429 -197.761386)
			(xy 315.342247 -197.706056) (xy 315.378657 -197.654824) (xy 315.421105 -197.60847) (xy 315.468943 -197.567702)
			(xy 315.521441 -197.533142) (xy 315.577799 -197.505316) (xy 315.637157 -197.48465) (xy 315.69861 -197.471458)
			(xy 315.729874 -197.468236) (xy 315.745876 -197.466712) (xy 315.77026 -197.446138) (xy 315.798962 -197.338442)
			(xy 315.801187 -197.328273) (xy 315.798222 -197.30769) (xy 315.787383 -197.289943) (xy 315.77915 -197.283578)
			(xy 314.63742 -196.486526) (xy 314.629674 -196.481613) (xy 314.611905 -196.477115) (xy 314.593689 -196.479149)
			(xy 314.58535 -196.48297) (xy 314.492894 -196.529706) (xy 314.478162 -196.553328) (xy 314.477908 -196.567552)
			(xy 314.476641 -196.600789) (xy 314.466531 -196.666529) (xy 314.447929 -196.730388) (xy 314.421153 -196.791274)
			(xy 314.386662 -196.848146) (xy 314.345046 -196.900032) (xy 314.297015 -196.946043) (xy 314.243392 -196.985395)
			(xy 314.21451 -197.001892) (xy 314.205112 -197.006972) (xy 314.192412 -197.023228) (xy 314.168282 -197.115176)
			(xy 314.17133 -197.135496) (xy 314.176918 -197.144386) (xy 314.194969 -197.174679) (xy 314.223455 -197.239184)
			(xy 314.24276 -197.307006) (xy 314.252513 -197.376844) (xy 314.253118 -197.412102) (xy 314.252616 -197.444063)
			(xy 314.244605 -197.507481) (xy 314.228708 -197.569395) (xy 314.205176 -197.628828) (xy 314.174382 -197.684843)
			(xy 314.136809 -197.736558) (xy 314.093052 -197.783155) (xy 314.043799 -197.8239) (xy 313.989828 -197.858151)
			(xy 313.931989 -197.885368) (xy 313.871196 -197.905121) (xy 313.808406 -197.917099) (xy 313.74461 -197.921113)
			(xy 313.680814 -197.917099) (xy 313.618024 -197.905121) (xy 313.557231 -197.885368) (xy 313.499392 -197.858151)
			(xy 313.445421 -197.8239) (xy 313.396168 -197.783155) (xy 313.352411 -197.736558) (xy 313.314838 -197.684843)
			(xy 313.284044 -197.628828) (xy 313.260512 -197.569395) (xy 313.244615 -197.507481) (xy 313.236604 -197.444063)
			(xy 313.236102 -197.412102) (xy 313.236533 -197.381927) (xy 313.243677 -197.322001) (xy 313.257866 -197.263342)
			(xy 313.2789 -197.206776) (xy 313.306483 -197.153098) (xy 313.340227 -197.103062) (xy 313.379657 -197.057374)
			(xy 313.424219 -197.016675) (xy 313.473285 -196.981538) (xy 313.4995 -196.966586) (xy 313.508898 -196.961506)
			(xy 313.521598 -196.94525) (xy 313.545728 -196.853302) (xy 313.54268 -196.832982) (xy 313.537092 -196.824092)
			(xy 313.5286 -196.810123) (xy 313.513219 -196.781272) (xy 313.506358 -196.766434) (xy 313.502294 -196.757544)
			(xy 313.488832 -196.744336) (xy 313.40679 -196.710046) (xy 313.387994 -196.709792) (xy 313.37885 -196.713094)
			(xy 313.350662 -196.723003) (xy 313.292552 -196.736912) (xy 313.233212 -196.743911) (xy 313.203336 -196.744336)
			(xy 313.172602 -196.743892) (xy 313.111581 -196.736488) (xy 313.051898 -196.721781) (xy 312.994423 -196.699988)
			(xy 312.939994 -196.671426) (xy 312.889404 -196.636511) (xy 312.843392 -196.595753) (xy 312.802628 -196.549746)
			(xy 312.767707 -196.499161) (xy 312.739138 -196.444735) (xy 312.717338 -196.387263) (xy 312.702624 -196.327582)
			(xy 312.695211 -196.266562) (xy 312.694828 -196.235828) (xy 312.695287 -196.20373) (xy 312.703319 -196.140039)
			(xy 312.71083 -196.108828) (xy 312.71337 -196.099176) (xy 312.71083 -196.079618) (xy 312.664856 -196.00037)
			(xy 312.649362 -195.988178) (xy 312.639456 -195.985638) (xy 312.607685 -195.976319) (xy 312.546685 -195.950572)
			(xy 312.489543 -195.917124) (xy 312.437227 -195.876542) (xy 312.390621 -195.829512) (xy 312.350513 -195.776831)
			(xy 312.317584 -195.719389) (xy 312.29239 -195.658159) (xy 312.275356 -195.594176) (xy 312.266772 -195.528524)
			(xy 312.26633 -195.495418) (xy 312.266809 -195.46412) (xy 312.274491 -195.401996) (xy 312.289741 -195.341286)
			(xy 312.312329 -195.282906) (xy 312.341912 -195.227741) (xy 312.378043 -195.176625) (xy 312.420176 -195.130331)
			(xy 312.443622 -195.109592) (xy 312.452766 -195.101718) (xy 312.46191 -195.080382) (xy 312.457338 -194.98818)
			(xy 312.456196 -194.976584) (xy 312.444956 -194.956202) (xy 312.435748 -194.949064) (xy 309.541418 -192.927986)
			(xy 309.533909 -192.923248) (xy 309.516755 -192.918713) (xy 309.499082 -192.920285) (xy 309.490872 -192.923668)
			(xy 309.39867 -192.966848) (xy 309.383176 -192.988946) (xy 309.38216 -193.002662) (xy 309.378326 -193.042663)
			(xy 309.364259 -193.121785) (xy 309.343007 -193.199287) (xy 309.314749 -193.274518) (xy 309.279721 -193.346846)
			(xy 309.238219 -193.415663) (xy 309.19059 -193.480391) (xy 309.137236 -193.540487) (xy 309.078603 -193.595445)
			(xy 309.015185 -193.644805) (xy 308.981602 -193.666872) (xy 308.974177 -193.672107) (xy 308.963313 -193.68665)
			(xy 308.958193 -193.704067) (xy 308.959459 -193.722177) (xy 308.962806 -193.730626) (xy 308.976763 -193.762888)
			(xy 308.996451 -193.830366) (xy 309.006395 -193.89995) (xy 309.007002 -193.935096) (xy 309.006494 -193.967197)
			(xy 308.998202 -194.030863) (xy 308.981756 -194.092923) (xy 308.957433 -194.15234) (xy 308.925638 -194.208118)
			(xy 308.886906 -194.259321) (xy 308.864762 -194.282568) (xy 308.85765 -194.289934) (xy 308.850284 -194.30873)
			(xy 308.851554 -194.40144) (xy 308.859682 -194.419982) (xy 308.867048 -194.427094) (xy 308.890734 -194.450554)
			(xy 308.932238 -194.502724) (xy 308.966375 -194.559987) (xy 308.992529 -194.621308) (xy 309.010228 -194.685581)
			(xy 309.019152 -194.751647) (xy 309.019702 -194.78498) (xy 309.019213 -194.816143) (xy 309.011401 -194.877977)
			(xy 308.995901 -194.938345) (xy 308.972958 -194.996293) (xy 308.942932 -195.05091) (xy 308.906298 -195.101332)
			(xy 308.863633 -195.146766) (xy 308.815611 -195.186494) (xy 308.762987 -195.219889) (xy 308.706593 -195.246426)
			(xy 308.647318 -195.265686) (xy 308.586097 -195.277365) (xy 308.523894 -195.281278) (xy 308.461691 -195.277365)
			(xy 308.40047 -195.265686) (xy 308.341195 -195.246426) (xy 308.284801 -195.219889) (xy 308.232177 -195.186494)
			(xy 308.184155 -195.146766) (xy 308.14149 -195.101332) (xy 308.104856 -195.05091) (xy 308.07483 -194.996293)
			(xy 308.051887 -194.938345) (xy 308.036387 -194.877977) (xy 308.028575 -194.816143) (xy 308.028086 -194.78498)
			(xy 308.028596 -194.752879) (xy 308.03689 -194.689215) (xy 308.053338 -194.627156) (xy 308.077663 -194.567741)
			(xy 308.109459 -194.511965) (xy 308.148191 -194.460763) (xy 308.170326 -194.437508) (xy 308.177438 -194.430142)
			(xy 308.184804 -194.411346) (xy 308.183534 -194.318636) (xy 308.175406 -194.300094) (xy 308.16804 -194.292982)
			(xy 308.144351 -194.269524) (xy 308.10284 -194.217355) (xy 308.068695 -194.160093) (xy 308.042532 -194.098772)
			(xy 308.024824 -194.034498) (xy 308.01589 -193.96843) (xy 308.015386 -193.935096) (xy 308.015996 -193.900422)
			(xy 308.025651 -193.83175) (xy 308.044759 -193.765087) (xy 308.058312 -193.733166) (xy 308.061703 -193.724716)
			(xy 308.062906 -193.706562) (xy 308.057699 -193.689129) (xy 308.046738 -193.674607) (xy 308.039262 -193.669412)
			(xy 308.005613 -193.64758) (xy 307.942038 -193.598662) (xy 307.8832 -193.544139) (xy 307.829591 -193.484467)
			(xy 307.781659 -193.420145) (xy 307.739805 -193.351713) (xy 307.704381 -193.279742) (xy 307.675682 -193.204835)
			(xy 307.653948 -193.127618) (xy 307.639362 -193.048739) (xy 307.632045 -192.968856) (xy 307.631592 -192.928748)
			(xy 307.632134 -192.885106) (xy 307.64081 -192.798256) (xy 307.658071 -192.712696) (xy 307.683745 -192.629275)
			(xy 307.71758 -192.548816) (xy 307.759239 -192.472117) (xy 307.808312 -192.399935) (xy 307.864313 -192.332985)
			(xy 307.926687 -192.27193) (xy 307.994818 -192.217372) (xy 308.031134 -192.193164) (xy 308.045358 -192.18402)
			(xy 308.057042 -192.152778) (xy 308.02453 -192.042796) (xy 308.020927 -192.032472) (xy 308.00658 -192.015998)
			(xy 307.986686 -192.006975) (xy 307.975762 -192.006474) (xy 306.669694 -192.006474) (xy 306.658158 -192.007017)
			(xy 306.637386 -192.017058) (xy 306.629816 -192.025778) (xy 306.573174 -192.09766) (xy 306.568348 -192.12052)
			(xy 306.571142 -192.13195) (xy 306.575906 -192.153221) (xy 306.581004 -192.196514) (xy 306.581302 -192.21831)
			(xy 306.580786 -192.24591) (xy 306.572559 -192.300493) (xy 306.556289 -192.35324) (xy 306.532339 -192.402973)
			(xy 306.501244 -192.44858) (xy 306.463699 -192.489044) (xy 306.420542 -192.523461) (xy 306.372738 -192.55106)
			(xy 306.321354 -192.571227) (xy 306.267539 -192.58351) (xy 306.212494 -192.587635) (xy 306.157449 -192.58351)
			(xy 306.103634 -192.571227) (xy 306.05225 -192.55106) (xy 306.004446 -192.523461) (xy 305.961289 -192.489044)
			(xy 305.923744 -192.44858) (xy 305.892649 -192.402973) (xy 305.868699 -192.35324) (xy 305.852429 -192.300493)
			(xy 305.844202 -192.24591) (xy 305.843686 -192.21831) (xy 305.843962 -192.196512) (xy 305.849057 -192.153217)
			(xy 305.853846 -192.13195) (xy 305.85664 -192.12052) (xy 305.851814 -192.09766) (xy 305.795172 -192.025778)
			(xy 305.787598 -192.017055) (xy 305.766833 -192.006983) (xy 305.755294 -192.006474) (xy 304.881026 -192.006474)
			(xy 304.869487 -192.007011) (xy 304.848704 -192.017044) (xy 304.841148 -192.025778) (xy 304.784506 -192.09766)
			(xy 304.77968 -192.12052) (xy 304.782474 -192.13195) (xy 304.787237 -192.153221) (xy 304.792335 -192.196514)
			(xy 304.792634 -192.21831) (xy 304.792118 -192.24591) (xy 304.783891 -192.300493) (xy 304.767621 -192.35324)
			(xy 304.743671 -192.402973) (xy 304.712576 -192.44858) (xy 304.675031 -192.489044) (xy 304.631874 -192.523461)
			(xy 304.58407 -192.55106) (xy 304.532686 -192.571227) (xy 304.478871 -192.58351) (xy 304.423826 -192.587635)
			(xy 304.368781 -192.58351) (xy 304.314966 -192.571227) (xy 304.263582 -192.55106) (xy 304.215778 -192.523461)
			(xy 304.172621 -192.489044) (xy 304.135076 -192.44858) (xy 304.103981 -192.402973) (xy 304.080031 -192.35324)
			(xy 304.063761 -192.300493) (xy 304.055534 -192.24591) (xy 304.055018 -192.21831) (xy 304.055294 -192.196512)
			(xy 304.06039 -192.153217) (xy 304.065178 -192.13195) (xy 304.067972 -192.12052) (xy 304.063146 -192.09766)
			(xy 304.006504 -192.025778) (xy 303.998926 -192.017066) (xy 303.97816 -192.007021) (xy 303.966626 -192.006474)
			(xy 303.095152 -192.006474) (xy 303.084314 -192.006974) (xy 303.064573 -192.015926) (xy 303.057052 -192.023746)
			(xy 302.999394 -192.089532) (xy 302.993044 -192.11036) (xy 302.994568 -192.121282) (xy 302.998035 -192.149602)
			(xy 303.001718 -192.206544) (xy 303.001934 -192.235074) (xy 303.001444 -192.276801) (xy 302.993493 -192.359874)
			(xy 302.97768 -192.441815) (xy 302.954147 -192.521882) (xy 302.923109 -192.599349) (xy 302.904398 -192.636648)
			(xy 302.89942 -192.647811) (xy 302.899427 -192.672217) (xy 302.904398 -192.683384) (xy 302.923076 -192.720698)
			(xy 302.954095 -192.798166) (xy 302.977619 -192.878231) (xy 302.993435 -192.960167) (xy 303.0014 -193.043234)
			(xy 303.001934 -193.084958) (xy 303.001419 -193.127344) (xy 302.993233 -193.21172) (xy 302.976943 -193.294912)
			(xy 302.952701 -193.376144) (xy 302.920734 -193.454657) (xy 302.881339 -193.529719) (xy 302.834884 -193.600629)
			(xy 302.781804 -193.666726) (xy 302.722593 -193.727392) (xy 302.657804 -193.78206) (xy 302.62322 -193.806572)
			(xy 302.615583 -193.81233) (xy 302.604919 -193.828191) (xy 302.600796 -193.846853) (xy 302.601884 -193.856356)
			(xy 302.604838 -193.875907) (xy 302.608019 -193.915324) (xy 302.608234 -193.935096) (xy 302.607774 -193.965786)
			(xy 302.603978 -193.996305) (xy 303.927495 -193.996305) (xy 303.931342 -193.934627) (xy 303.942824 -193.873905)
			(xy 303.961763 -193.815081) (xy 303.987865 -193.759067) (xy 304.020726 -193.706731) (xy 304.059837 -193.658884)
			(xy 304.10459 -193.616269) (xy 304.154293 -193.579545) (xy 304.181002 -193.564002) (xy 304.192178 -193.557906)
			(xy 304.20564 -193.53657) (xy 304.214276 -193.427096) (xy 304.20437 -193.403982) (xy 304.19421 -193.396108)
			(xy 304.172876 -193.378506) (xy 304.135213 -193.338004) (xy 304.104025 -193.292329) (xy 304.080012 -193.242507)
			(xy 304.063712 -193.189657) (xy 304.055491 -193.134964) (xy 304.055018 -193.10731) (xy 304.055534 -193.07971)
			(xy 304.063761 -193.025127) (xy 304.080031 -192.97238) (xy 304.103981 -192.922648) (xy 304.135076 -192.87704)
			(xy 304.172621 -192.836576) (xy 304.215778 -192.802159) (xy 304.263582 -192.77456) (xy 304.314966 -192.754393)
			(xy 304.368781 -192.74211) (xy 304.423826 -192.737985) (xy 304.478871 -192.74211) (xy 304.532686 -192.754393)
			(xy 304.58407 -192.77456) (xy 304.631874 -192.802159) (xy 304.675031 -192.836576) (xy 304.712576 -192.87704)
			(xy 304.743671 -192.922648) (xy 304.767621 -192.97238) (xy 304.783891 -193.025127) (xy 304.792118 -193.07971)
			(xy 304.792634 -193.10731) (xy 304.792139 -193.134961) (xy 304.7839 -193.189646) (xy 304.767594 -193.242489)
			(xy 304.743584 -193.292308) (xy 304.71241 -193.337986) (xy 304.674768 -193.3785) (xy 304.653442 -193.396108)
			(xy 304.643282 -193.403982) (xy 304.633376 -193.427096) (xy 304.642012 -193.53657) (xy 304.655474 -193.557906)
			(xy 304.66665 -193.564002) (xy 304.693366 -193.579532) (xy 304.743066 -193.61626) (xy 304.787816 -193.658878)
			(xy 304.826924 -193.706727) (xy 304.859783 -193.759065) (xy 304.885883 -193.815081) (xy 304.90482 -193.873905)
			(xy 304.916301 -193.934627) (xy 304.920148 -193.996305) (xy 304.9163 -194.057983) (xy 304.904818 -194.118704)
			(xy 304.885879 -194.177528) (xy 304.859778 -194.233543) (xy 304.826918 -194.28588) (xy 304.78781 -194.333729)
			(xy 304.743058 -194.376347) (xy 304.693358 -194.413073) (xy 304.66665 -194.428618) (xy 304.655474 -194.434714)
			(xy 304.642012 -194.45605) (xy 304.633376 -194.565524) (xy 304.643282 -194.588638) (xy 304.653442 -194.596512)
			(xy 304.674776 -194.614114) (xy 304.712441 -194.654615) (xy 304.74363 -194.700289) (xy 304.767644 -194.750111)
			(xy 304.783944 -194.802962) (xy 304.792162 -194.857656) (xy 304.792634 -194.88531) (xy 304.792118 -194.91291)
			(xy 304.783891 -194.967493) (xy 304.767621 -195.02024) (xy 304.743671 -195.069973) (xy 304.712576 -195.11558)
			(xy 304.675031 -195.156044) (xy 304.631874 -195.190461) (xy 304.58407 -195.21806) (xy 304.532686 -195.238227)
			(xy 304.478871 -195.25051) (xy 304.423826 -195.254635) (xy 304.368781 -195.25051) (xy 304.314966 -195.238227)
			(xy 304.263582 -195.21806) (xy 304.215778 -195.190461) (xy 304.172621 -195.156044) (xy 304.135076 -195.11558)
			(xy 304.103981 -195.069973) (xy 304.080031 -195.02024) (xy 304.063761 -194.967493) (xy 304.055534 -194.91291)
			(xy 304.055018 -194.88531) (xy 304.055508 -194.857658) (xy 304.063745 -194.802972) (xy 304.080051 -194.750128)
			(xy 304.104062 -194.700309) (xy 304.135238 -194.654632) (xy 304.172883 -194.614118) (xy 304.19421 -194.596512)
			(xy 304.20437 -194.588638) (xy 304.214276 -194.565524) (xy 304.20564 -194.45605) (xy 304.192178 -194.434714)
			(xy 304.181002 -194.428618) (xy 304.154301 -194.41306) (xy 304.104598 -194.376338) (xy 304.059844 -194.333723)
			(xy 304.020732 -194.285877) (xy 303.98787 -194.233542) (xy 303.961766 -194.177528) (xy 303.942826 -194.118704)
			(xy 303.931343 -194.057983) (xy 303.927495 -193.996305) (xy 302.603978 -193.996305) (xy 302.600198 -194.026698)
			(xy 302.585162 -194.086209) (xy 302.562894 -194.143408) (xy 302.533737 -194.197422) (xy 302.498135 -194.247423)
			(xy 302.456634 -194.292648) (xy 302.409868 -194.332404) (xy 302.38446 -194.349624) (xy 302.37557 -194.355466)
			(xy 302.364394 -194.372484) (xy 302.347376 -194.465448) (xy 302.351694 -194.485514) (xy 302.358044 -194.49415)
			(xy 302.375887 -194.519613) (xy 302.405774 -194.574135) (xy 302.428607 -194.631968) (xy 302.444028 -194.692202)
			(xy 302.451794 -194.753892) (xy 302.452278 -194.78498) (xy 302.451771 -194.817444) (xy 302.443299 -194.881816)
			(xy 302.426496 -194.944532) (xy 302.40165 -195.004518) (xy 302.369187 -195.060747) (xy 302.329661 -195.112257)
			(xy 302.28375 -195.158168) (xy 302.232238 -195.197692) (xy 302.176009 -195.230154) (xy 302.116022 -195.254999)
			(xy 302.053306 -195.271801) (xy 301.988934 -195.280272) (xy 301.95647 -195.280788) (xy 301.923364 -195.280236)
			(xy 301.85774 -195.271421) (xy 301.793874 -195.253951) (xy 301.7329 -195.228137) (xy 301.675904 -195.194439)
			(xy 301.6239 -195.153455) (xy 301.577812 -195.105915) (xy 301.55769 -195.07962) (xy 301.550324 -195.069714)
			(xy 301.528988 -195.059046) (xy 301.4218 -195.059808) (xy 301.400718 -195.07073) (xy 301.393352 -195.08089)
			(xy 301.380571 -195.098366) (xy 301.352467 -195.131306) (xy 301.337218 -195.146676) (xy 301.329852 -195.154042)
			(xy 301.322232 -195.172076) (xy 301.321216 -195.264024) (xy 301.328582 -195.282566) (xy 301.335694 -195.289932)
			(xy 301.357518 -195.313114) (xy 301.395651 -195.3641) (xy 301.426938 -195.419552) (xy 301.450862 -195.478555)
			(xy 301.467029 -195.540137) (xy 301.469352 -195.558156) (xy 305.687984 -195.558156) (xy 305.688555 -195.524392)
			(xy 305.697736 -195.457489) (xy 305.715909 -195.392451) (xy 305.742737 -195.33048) (xy 305.777725 -195.272721)
			(xy 305.820225 -195.220243) (xy 305.844448 -195.196714) (xy 305.85156 -195.189856) (xy 305.859942 -195.171822)
			(xy 305.864006 -195.081144) (xy 305.857402 -195.062348) (xy 305.850544 -195.054982) (xy 305.830338 -195.031623)
			(xy 305.795112 -194.980888) (xy 305.766289 -194.926261) (xy 305.744291 -194.868546) (xy 305.729444 -194.808593)
			(xy 305.721966 -194.747282) (xy 305.721512 -194.7164) (xy 305.721967 -194.685796) (xy 305.729321 -194.625032)
			(xy 305.74391 -194.565589) (xy 305.765524 -194.508325) (xy 305.79385 -194.454067) (xy 305.828481 -194.403598)
			(xy 305.868914 -194.357648) (xy 305.891438 -194.336924) (xy 305.89855 -194.330828) (xy 305.906932 -194.314826)
			(xy 305.917346 -194.229482) (xy 305.913028 -194.211956) (xy 305.907694 -194.204082) (xy 305.892591 -194.180979)
			(xy 305.868679 -194.131233) (xy 305.85243 -194.078485) (xy 305.844206 -194.023907) (xy 305.843686 -193.99631)
			(xy 305.844202 -193.96871) (xy 305.852429 -193.914127) (xy 305.868699 -193.86138) (xy 305.892649 -193.811648)
			(xy 305.923744 -193.76604) (xy 305.961289 -193.725576) (xy 306.004446 -193.691159) (xy 306.05225 -193.66356)
			(xy 306.103634 -193.643393) (xy 306.157449 -193.63111) (xy 306.212494 -193.626985) (xy 306.267539 -193.63111)
			(xy 306.321354 -193.643393) (xy 306.372738 -193.66356) (xy 306.420542 -193.691159) (xy 306.463699 -193.725576)
			(xy 306.501244 -193.76604) (xy 306.532339 -193.811648) (xy 306.556289 -193.86138) (xy 306.572559 -193.914127)
			(xy 306.580786 -193.96871) (xy 306.581302 -193.99631) (xy 306.580849 -194.021645) (xy 306.573903 -194.071837)
			(xy 306.560143 -194.120603) (xy 306.539829 -194.167023) (xy 306.526946 -194.188842) (xy 306.52212 -194.19697)
			(xy 306.518564 -194.21475) (xy 306.533296 -194.299332) (xy 306.54244 -194.31508) (xy 306.549806 -194.320922)
			(xy 306.57465 -194.341679) (xy 306.619404 -194.388458) (xy 306.657862 -194.440538) (xy 306.689402 -194.497075)
			(xy 306.713514 -194.557157) (xy 306.729808 -194.619813) (xy 306.738022 -194.68403) (xy 306.738528 -194.7164)
			(xy 306.738104 -194.746865) (xy 306.730828 -194.80736) (xy 306.71638 -194.866552) (xy 306.694967 -194.923596)
			(xy 306.666894 -194.977674) (xy 306.632565 -195.028013) (xy 306.59247 -195.073892) (xy 306.570126 -195.094606)
			(xy 306.562506 -195.10121) (xy 306.55387 -195.11899) (xy 306.548028 -195.209668) (xy 306.554124 -195.228464)
			(xy 306.560728 -195.236084) (xy 306.579409 -195.258561) (xy 306.61189 -195.307151) (xy 306.638432 -195.359224)
			(xy 306.658666 -195.414058) (xy 306.672311 -195.47089) (xy 306.679178 -195.528932) (xy 306.6796 -195.558156)
			(xy 306.679111 -195.589319) (xy 306.671299 -195.651153) (xy 306.655799 -195.711521) (xy 306.632856 -195.769469)
			(xy 306.60283 -195.824086) (xy 306.566196 -195.874508) (xy 306.523531 -195.919942) (xy 306.475509 -195.95967)
			(xy 306.422885 -195.993065) (xy 306.366491 -196.019602) (xy 306.307216 -196.038862) (xy 306.245995 -196.050541)
			(xy 306.183792 -196.054454) (xy 306.121589 -196.050541) (xy 306.060368 -196.038862) (xy 306.001093 -196.019602)
			(xy 305.944699 -195.993065) (xy 305.892075 -195.95967) (xy 305.844053 -195.919942) (xy 305.801388 -195.874508)
			(xy 305.764754 -195.824086) (xy 305.734728 -195.769469) (xy 305.711785 -195.711521) (xy 305.696285 -195.651153)
			(xy 305.688473 -195.589319) (xy 305.687984 -195.558156) (xy 301.469352 -195.558156) (xy 301.475171 -195.603283)
			(xy 301.475648 -195.635118) (xy 301.475159 -195.666281) (xy 301.467347 -195.728115) (xy 301.451847 -195.788483)
			(xy 301.428904 -195.846431) (xy 301.398878 -195.901048) (xy 301.362244 -195.95147) (xy 301.319579 -195.996904)
			(xy 301.271557 -196.036632) (xy 301.218933 -196.070027) (xy 301.162539 -196.096564) (xy 301.103264 -196.115824)
			(xy 301.042043 -196.127503) (xy 300.97984 -196.131416) (xy 300.917637 -196.127503) (xy 300.856416 -196.115824)
			(xy 300.797141 -196.096564) (xy 300.740747 -196.070027) (xy 300.688123 -196.036632) (xy 300.640101 -195.996904)
			(xy 300.597436 -195.95147) (xy 300.560802 -195.901048) (xy 300.530776 -195.846431) (xy 300.507833 -195.788483)
			(xy 300.492333 -195.728115) (xy 300.484521 -195.666281) (xy 300.484032 -195.635118) (xy 300.484527 -195.603286)
			(xy 300.492687 -195.540147) (xy 300.508863 -195.478573) (xy 300.532788 -195.419575) (xy 300.564069 -195.364126)
			(xy 300.60219 -195.313137) (xy 300.623986 -195.289932) (xy 300.631098 -195.282566) (xy 300.638464 -195.264024)
			(xy 300.637448 -195.172076) (xy 300.629828 -195.154042) (xy 300.622462 -195.146676) (xy 300.598974 -195.122715)
			(xy 300.557857 -195.069691) (xy 300.524068 -195.011722) (xy 300.498193 -194.949814) (xy 300.480681 -194.885041)
			(xy 300.471837 -194.818529) (xy 300.471332 -194.78498) (xy 300.471847 -194.752059) (xy 300.480338 -194.686767)
			(xy 300.497186 -194.623117) (xy 300.522112 -194.562176) (xy 300.554697 -194.504962) (xy 300.594395 -194.452435)
			(xy 300.617128 -194.428618) (xy 300.62424 -194.421252) (xy 300.631606 -194.402964) (xy 300.631352 -194.311016)
			(xy 300.623732 -194.292728) (xy 300.616366 -194.285616) (xy 300.593812 -194.26228) (xy 300.554337 -194.210768)
			(xy 300.521915 -194.154548) (xy 300.497102 -194.094581) (xy 300.480321 -194.03189) (xy 300.471858 -193.967545)
			(xy 300.471332 -193.935096) (xy 300.47184 -193.902633) (xy 300.480315 -193.838264) (xy 300.49712 -193.775551)
			(xy 300.521968 -193.715569) (xy 300.554432 -193.659343) (xy 300.593958 -193.607836) (xy 300.639869 -193.561929)
			(xy 300.69138 -193.522408) (xy 300.747608 -193.489948) (xy 300.807593 -193.465106) (xy 300.870307 -193.448307)
			(xy 300.934677 -193.439837) (xy 300.96714 -193.439288) (xy 300.999192 -193.439791) (xy 301.062761 -193.448056)
			(xy 301.124732 -193.464458) (xy 301.154592 -193.476118) (xy 301.168308 -193.481706) (xy 301.197264 -193.476372)
			(xy 301.286672 -193.393822) (xy 301.294292 -193.365374) (xy 301.28972 -193.35115) (xy 301.277224 -193.310269)
			(xy 301.25929 -193.22668) (xy 301.253906 -193.184272) (xy 301.252636 -193.17335) (xy 301.242222 -193.155316)
			(xy 301.164752 -193.09842) (xy 301.144178 -193.093848) (xy 301.133764 -193.09588) (xy 301.092515 -193.103364)
			(xy 301.009059 -193.111376) (xy 300.96714 -193.111882) (xy 300.924089 -193.111373) (xy 300.838403 -193.102937)
			(xy 300.753956 -193.086142) (xy 300.671561 -193.061151) (xy 300.592014 -193.028204) (xy 300.516078 -192.987618)
			(xy 300.444487 -192.939784) (xy 300.37793 -192.885163) (xy 300.317047 -192.824281) (xy 300.262424 -192.757724)
			(xy 300.214589 -192.686134) (xy 300.174002 -192.610199) (xy 300.141054 -192.530652) (xy 300.116061 -192.448258)
			(xy 300.099265 -192.363811) (xy 300.090828 -192.278124) (xy 300.090332 -192.235074) (xy 300.090553 -192.206544)
			(xy 300.094236 -192.149602) (xy 300.097698 -192.121282) (xy 300.099222 -192.11036) (xy 300.092872 -192.089532)
			(xy 300.035214 -192.023746) (xy 300.027682 -192.01594) (xy 300.007949 -192.006976) (xy 299.997114 -192.006474)
			(xy 299.12564 -192.006474) (xy 299.11411 -192.007028) (xy 299.093355 -192.017083) (xy 299.085762 -192.025778)
			(xy 299.02912 -192.09766) (xy 299.024294 -192.12052) (xy 299.027088 -192.13195) (xy 299.031851 -192.153221)
			(xy 299.036949 -192.196514) (xy 299.037248 -192.21831) (xy 299.036732 -192.24591) (xy 299.028505 -192.300493)
			(xy 299.012235 -192.35324) (xy 298.988285 -192.402973) (xy 298.95719 -192.44858) (xy 298.919645 -192.489044)
			(xy 298.876488 -192.523461) (xy 298.828684 -192.55106) (xy 298.7773 -192.571227) (xy 298.723485 -192.58351)
			(xy 298.66844 -192.587635) (xy 298.613395 -192.58351) (xy 298.55958 -192.571227) (xy 298.508196 -192.55106)
			(xy 298.460392 -192.523461) (xy 298.417235 -192.489044) (xy 298.37969 -192.44858) (xy 298.348595 -192.402973)
			(xy 298.324645 -192.35324) (xy 298.308375 -192.300493) (xy 298.300148 -192.24591) (xy 298.299632 -192.21831)
			(xy 298.299908 -192.196512) (xy 298.305004 -192.153217) (xy 298.309792 -192.13195) (xy 298.312586 -192.12052)
			(xy 298.30776 -192.09766) (xy 298.251118 -192.025778) (xy 298.243541 -192.017064) (xy 298.222775 -192.007013)
			(xy 298.21124 -192.006474) (xy 297.336972 -192.006474) (xy 297.325438 -192.007022) (xy 297.304674 -192.017068)
			(xy 297.297094 -192.025778) (xy 297.240452 -192.09766) (xy 297.235626 -192.12052) (xy 297.23842 -192.13195)
			(xy 297.243184 -192.153221) (xy 297.248283 -192.196514) (xy 297.24858 -192.21831) (xy 297.248064 -192.24591)
			(xy 297.239837 -192.300493) (xy 297.223567 -192.35324) (xy 297.199617 -192.402973) (xy 297.168522 -192.44858)
			(xy 297.130977 -192.489044) (xy 297.08782 -192.523461) (xy 297.040016 -192.55106) (xy 296.988632 -192.571227)
			(xy 296.934817 -192.58351) (xy 296.879772 -192.587635) (xy 296.824727 -192.58351) (xy 296.770912 -192.571227)
			(xy 296.719528 -192.55106) (xy 296.671724 -192.523461) (xy 296.628567 -192.489044) (xy 296.591022 -192.44858)
			(xy 296.559927 -192.402973) (xy 296.535977 -192.35324) (xy 296.519707 -192.300493) (xy 296.51148 -192.24591)
			(xy 296.510964 -192.21831) (xy 296.51124 -192.196512) (xy 296.516335 -192.153217) (xy 296.521124 -192.13195)
			(xy 296.523918 -192.12052) (xy 296.519092 -192.09766) (xy 296.46245 -192.025778) (xy 296.454875 -192.017058)
			(xy 296.43411 -192.006995) (xy 296.422572 -192.006474) (xy 295.551098 -192.006474) (xy 295.540255 -192.006965)
			(xy 295.520501 -192.015905) (xy 295.512998 -192.023746) (xy 295.45534 -192.089532) (xy 295.44899 -192.11036)
			(xy 295.450514 -192.121282) (xy 295.453981 -192.149602) (xy 295.457663 -192.206544) (xy 295.45788 -192.235074)
			(xy 295.45739 -192.2768) (xy 295.449439 -192.359874) (xy 295.433624 -192.441815) (xy 295.410091 -192.521881)
			(xy 295.37905 -192.599346) (xy 295.360344 -192.636648) (xy 295.35537 -192.647812) (xy 295.355377 -192.672216)
			(xy 295.360344 -192.683384) (xy 295.379023 -192.720697) (xy 295.410044 -192.798166) (xy 295.433569 -192.87823)
			(xy 295.449386 -192.960166) (xy 295.457352 -193.043234) (xy 295.45788 -193.084958) (xy 295.457365 -193.127344)
			(xy 295.449179 -193.211719) (xy 295.432888 -193.29491) (xy 295.408645 -193.37614) (xy 295.376676 -193.454652)
			(xy 295.33728 -193.529713) (xy 295.290824 -193.600621) (xy 295.237741 -193.666715) (xy 295.178528 -193.727378)
			(xy 295.113737 -193.782043) (xy 295.079166 -193.806572) (xy 295.071524 -193.812327) (xy 295.060849 -193.828187)
			(xy 295.056722 -193.846854) (xy 295.05783 -193.856356) (xy 295.060784 -193.875907) (xy 295.063964 -193.915324)
			(xy 295.06418 -193.935096) (xy 295.06369 -193.96693) (xy 295.059899 -193.996305) (xy 296.383469 -193.996305)
			(xy 296.387315 -193.934629) (xy 296.398795 -193.87391) (xy 296.417732 -193.815087) (xy 296.443831 -193.759074)
			(xy 296.476689 -193.706738) (xy 296.515795 -193.65889) (xy 296.560544 -193.616273) (xy 296.610241 -193.579547)
			(xy 296.636948 -193.564002) (xy 296.648124 -193.557906) (xy 296.661586 -193.53657) (xy 296.670222 -193.427096)
			(xy 296.660316 -193.403982) (xy 296.650156 -193.396108) (xy 296.628831 -193.378495) (xy 296.591166 -193.337997)
			(xy 296.559976 -193.292325) (xy 296.53596 -193.242505) (xy 296.519658 -193.189655) (xy 296.511437 -193.134964)
			(xy 296.510964 -193.10731) (xy 296.51148 -193.07971) (xy 296.519707 -193.025127) (xy 296.535977 -192.97238)
			(xy 296.559927 -192.922648) (xy 296.591022 -192.87704) (xy 296.628567 -192.836576) (xy 296.671724 -192.802159)
			(xy 296.719528 -192.77456) (xy 296.770912 -192.754393) (xy 296.824727 -192.74211) (xy 296.879772 -192.737985)
			(xy 296.934817 -192.74211) (xy 296.988632 -192.754393) (xy 297.040016 -192.77456) (xy 297.08782 -192.802159)
			(xy 297.130977 -192.836576) (xy 297.168522 -192.87704) (xy 297.199617 -192.922648) (xy 297.223567 -192.97238)
			(xy 297.239837 -193.025127) (xy 297.248064 -193.07971) (xy 297.24858 -193.10731) (xy 297.248105 -193.134962)
			(xy 297.239865 -193.189649) (xy 297.223556 -193.242494) (xy 297.199543 -193.292312) (xy 297.168363 -193.33799)
			(xy 297.130717 -193.378502) (xy 297.109388 -193.396108) (xy 297.099228 -193.403982) (xy 297.089322 -193.427096)
			(xy 297.097958 -193.53657) (xy 297.11142 -193.557906) (xy 297.122596 -193.564002) (xy 297.149315 -193.57953)
			(xy 297.199019 -193.616255) (xy 297.243774 -193.658872) (xy 297.282886 -193.70672) (xy 297.315749 -193.759059)
			(xy 297.341852 -193.815075) (xy 297.360792 -193.873901) (xy 297.372274 -193.934625) (xy 297.376121 -193.996305)
			(xy 297.372273 -194.057985) (xy 297.36079 -194.118708) (xy 297.341849 -194.177534) (xy 297.315744 -194.23355)
			(xy 297.282881 -194.285888) (xy 297.243768 -194.333735) (xy 297.199011 -194.376351) (xy 297.149306 -194.413075)
			(xy 297.122596 -194.428618) (xy 297.11142 -194.434714) (xy 297.097958 -194.45605) (xy 297.089322 -194.565524)
			(xy 297.099228 -194.588638) (xy 297.109388 -194.596512) (xy 297.130732 -194.614103) (xy 297.168393 -194.654607)
			(xy 297.19958 -194.700284) (xy 297.223592 -194.750108) (xy 297.23989 -194.802961) (xy 297.248108 -194.857655)
			(xy 297.24858 -194.88531) (xy 297.248064 -194.91291) (xy 297.239837 -194.967493) (xy 297.223567 -195.02024)
			(xy 297.199617 -195.069973) (xy 297.168522 -195.11558) (xy 297.130977 -195.156044) (xy 297.08782 -195.190461)
			(xy 297.040016 -195.21806) (xy 296.988632 -195.238227) (xy 296.934817 -195.25051) (xy 296.879772 -195.254635)
			(xy 296.824727 -195.25051) (xy 296.770912 -195.238227) (xy 296.719528 -195.21806) (xy 296.671724 -195.190461)
			(xy 296.628567 -195.156044) (xy 296.591022 -195.11558) (xy 296.559927 -195.069973) (xy 296.535977 -195.02024)
			(xy 296.519707 -194.967493) (xy 296.51148 -194.91291) (xy 296.510964 -194.88531) (xy 296.511474 -194.857659)
			(xy 296.51971 -194.802975) (xy 296.536013 -194.750132) (xy 296.56002 -194.700314) (xy 296.591192 -194.654635)
			(xy 296.628831 -194.61412) (xy 296.650156 -194.596512) (xy 296.660316 -194.588638) (xy 296.670222 -194.565524)
			(xy 296.661586 -194.45605) (xy 296.648124 -194.434714) (xy 296.636948 -194.428618) (xy 296.61025 -194.413058)
			(xy 296.560551 -194.376333) (xy 296.515802 -194.333717) (xy 296.476695 -194.28587) (xy 296.443836 -194.233535)
			(xy 296.417736 -194.177522) (xy 296.398798 -194.1187) (xy 296.387316 -194.05798) (xy 296.383469 -193.996305)
			(xy 295.059899 -193.996305) (xy 295.05554 -194.030074) (xy 295.039373 -194.091656) (xy 295.015456 -194.150661)
			(xy 294.984182 -194.206119) (xy 294.946065 -194.257116) (xy 294.924226 -194.280282) (xy 294.917114 -194.287648)
			(xy 294.909748 -194.305936) (xy 294.910764 -194.397884) (xy 294.918638 -194.416172) (xy 294.92575 -194.423284)
			(xy 294.949234 -194.447247) (xy 294.990344 -194.500272) (xy 295.024125 -194.558243) (xy 295.049992 -194.620151)
			(xy 295.067496 -194.684922) (xy 295.076332 -194.751433) (xy 295.07688 -194.78498) (xy 295.076378 -194.816941)
			(xy 295.068367 -194.880359) (xy 295.05247 -194.942273) (xy 295.028938 -195.001706) (xy 294.998144 -195.057721)
			(xy 294.960571 -195.109436) (xy 294.916814 -195.156033) (xy 294.867561 -195.196778) (xy 294.81359 -195.231029)
			(xy 294.755751 -195.258246) (xy 294.694958 -195.277999) (xy 294.632168 -195.289977) (xy 294.568372 -195.293991)
			(xy 294.504576 -195.289977) (xy 294.441786 -195.277999) (xy 294.380993 -195.258246) (xy 294.323154 -195.231029)
			(xy 294.269183 -195.196778) (xy 294.21993 -195.156033) (xy 294.176173 -195.109436) (xy 294.1386 -195.057721)
			(xy 294.107806 -195.001706) (xy 294.084274 -194.942273) (xy 294.068377 -194.880359) (xy 294.060366 -194.816941)
			(xy 294.059864 -194.78498) (xy 294.060398 -194.75143) (xy 294.069217 -194.684913) (xy 294.086712 -194.620135)
			(xy 294.112579 -194.558223) (xy 294.146368 -194.500252) (xy 294.187492 -194.447232) (xy 294.210994 -194.423284)
			(xy 294.218106 -194.416172) (xy 294.22598 -194.397884) (xy 294.226996 -194.305936) (xy 294.21963 -194.287648)
			(xy 294.212518 -194.280282) (xy 294.190693 -194.2571) (xy 294.152557 -194.206115) (xy 294.121268 -194.150664)
			(xy 294.097342 -194.091661) (xy 294.081173 -194.030078) (xy 294.073028 -193.966931) (xy 294.072564 -193.935096)
			(xy 294.072852 -193.911647) (xy 294.077308 -193.86496) (xy 294.081454 -193.841878) (xy 294.082883 -193.832389)
			(xy 294.07936 -193.813539) (xy 294.069148 -193.79731) (xy 294.061642 -193.791332) (xy 294.038699 -193.774185)
			(xy 293.994851 -193.737323) (xy 293.974012 -193.717672) (xy 293.966675 -193.71129) (xy 293.948625 -193.704098)
			(xy 293.929195 -193.704133) (xy 293.911172 -193.711389) (xy 293.897138 -193.724826) (xy 293.889106 -193.742518)
			(xy 293.888228 -193.761928) (xy 293.890954 -193.771266) (xy 293.899815 -193.79766) (xy 293.912245 -193.851933)
			(xy 293.918516 -193.907257) (xy 293.918894 -193.935096) (xy 293.91845 -193.965219) (xy 293.911147 -194.025022)
			(xy 293.896648 -194.083498) (xy 293.875168 -194.139785) (xy 293.847022 -194.193053) (xy 293.812627 -194.242517)
			(xy 293.79291 -194.265296) (xy 293.786306 -194.272662) (xy 293.779702 -194.29095) (xy 293.78275 -194.380866)
			(xy 293.79037 -194.398646) (xy 293.797482 -194.405504) (xy 293.821188 -194.429502) (xy 293.862705 -194.482666)
			(xy 293.896831 -194.540853) (xy 293.922966 -194.603039) (xy 293.940652 -194.668135) (xy 293.949578 -194.734996)
			(xy 293.950136 -194.768724) (xy 293.949716 -194.798416) (xy 293.942799 -194.857396) (xy 293.929062 -194.91517)
			(xy 293.908693 -194.970951) (xy 293.881967 -195.023981) (xy 293.849249 -195.07354) (xy 293.810983 -195.118951)
			(xy 293.789608 -195.139564) (xy 293.781988 -195.146676) (xy 293.77386 -195.165472) (xy 293.772082 -195.258944)
			(xy 293.779956 -195.277994) (xy 293.787068 -195.28536) (xy 293.809541 -195.308662) (xy 293.848872 -195.360084)
			(xy 293.881174 -195.416189) (xy 293.905896 -195.476021) (xy 293.922619 -195.538562) (xy 293.931058 -195.602749)
			(xy 293.931594 -195.635118) (xy 293.931105 -195.666281) (xy 293.923293 -195.728115) (xy 293.907793 -195.788483)
			(xy 293.88485 -195.846431) (xy 293.87786 -195.859146) (xy 298.159932 -195.859146) (xy 298.160494 -195.825988)
			(xy 298.169105 -195.760234) (xy 298.186187 -195.696156) (xy 298.211451 -195.63484) (xy 298.244467 -195.577328)
			(xy 298.284676 -195.524593) (xy 298.331397 -195.477529) (xy 298.35729 -195.45681) (xy 298.366205 -195.449263)
			(xy 298.376532 -195.428344) (xy 298.377102 -195.416678) (xy 298.377102 -195.336414) (xy 298.376452 -195.324767)
			(xy 298.366149 -195.303868) (xy 298.35729 -195.296282) (xy 298.331421 -195.275533) (xy 298.284695 -195.228476)
			(xy 298.244479 -195.175747) (xy 298.211456 -195.11824) (xy 298.186184 -195.056929) (xy 298.169092 -194.992855)
			(xy 298.160469 -194.927103) (xy 298.159932 -194.893946) (xy 298.160521 -194.860173) (xy 298.169465 -194.793221)
			(xy 298.187189 -194.728042) (xy 298.21338 -194.66578) (xy 298.247579 -194.607531) (xy 298.289184 -194.554319)
			(xy 298.337464 -194.507079) (xy 298.391569 -194.466643) (xy 298.42079 -194.4497) (xy 298.431966 -194.443604)
			(xy 298.445682 -194.422522) (xy 298.45508 -194.313556) (xy 298.445428 -194.290188) (xy 298.435522 -194.282314)
			(xy 298.414673 -194.264704) (xy 298.377908 -194.224374) (xy 298.347485 -194.179069) (xy 298.324066 -194.129777)
			(xy 298.308164 -194.077573) (xy 298.300124 -194.023596) (xy 298.299632 -193.99631) (xy 298.300148 -193.96871)
			(xy 298.308375 -193.914127) (xy 298.324645 -193.86138) (xy 298.348595 -193.811648) (xy 298.37969 -193.76604)
			(xy 298.417235 -193.725576) (xy 298.460392 -193.691159) (xy 298.508196 -193.66356) (xy 298.55958 -193.643393)
			(xy 298.613395 -193.63111) (xy 298.66844 -193.626985) (xy 298.723485 -193.63111) (xy 298.7773 -193.643393)
			(xy 298.828684 -193.66356) (xy 298.876488 -193.691159) (xy 298.919645 -193.725576) (xy 298.95719 -193.76604)
			(xy 298.988285 -193.811648) (xy 299.012235 -193.86138) (xy 299.028505 -193.914127) (xy 299.036732 -193.96871)
			(xy 299.037248 -193.99631) (xy 299.036791 -194.023599) (xy 299.028759 -194.077581) (xy 299.012855 -194.129789)
			(xy 298.989429 -194.179083) (xy 298.958992 -194.224384) (xy 298.922209 -194.264704) (xy 298.901358 -194.282314)
			(xy 298.891452 -194.290188) (xy 298.8818 -194.313556) (xy 298.891198 -194.422522) (xy 298.904914 -194.443604)
			(xy 298.91609 -194.4497) (xy 298.945322 -194.466629) (xy 298.999441 -194.507057) (xy 299.047732 -194.554293)
			(xy 299.089346 -194.607505) (xy 299.123551 -194.665758) (xy 299.149743 -194.728025) (xy 299.167463 -194.793212)
			(xy 299.176399 -194.86017) (xy 299.176948 -194.893946) (xy 299.176387 -194.927104) (xy 299.167777 -194.992859)
			(xy 299.150695 -195.056937) (xy 299.125432 -195.118253) (xy 299.092415 -195.175765) (xy 299.052205 -195.2285)
			(xy 299.005483 -195.275563) (xy 298.97959 -195.296282) (xy 298.970676 -195.303829) (xy 298.960348 -195.324748)
			(xy 298.959778 -195.336414) (xy 298.959778 -195.416678) (xy 298.960439 -195.428323) (xy 298.970735 -195.449222)
			(xy 298.97959 -195.45681) (xy 299.005472 -195.477543) (xy 299.052194 -195.524605) (xy 299.092406 -195.577338)
			(xy 299.125427 -195.634848) (xy 299.150697 -195.69616) (xy 299.167788 -195.760235) (xy 299.17641 -195.825988)
			(xy 299.176948 -195.859146) (xy 299.176446 -195.891107) (xy 299.168435 -195.954525) (xy 299.152538 -196.016439)
			(xy 299.129006 -196.075872) (xy 299.098212 -196.131887) (xy 299.060639 -196.183602) (xy 299.016882 -196.230199)
			(xy 298.967629 -196.270944) (xy 298.913658 -196.305195) (xy 298.855819 -196.332412) (xy 298.795026 -196.352165)
			(xy 298.732236 -196.364143) (xy 298.66844 -196.368157) (xy 298.604644 -196.364143) (xy 298.541854 -196.352165)
			(xy 298.481061 -196.332412) (xy 298.423222 -196.305195) (xy 298.369251 -196.270944) (xy 298.319998 -196.230199)
			(xy 298.276241 -196.183602) (xy 298.238668 -196.131887) (xy 298.207874 -196.075872) (xy 298.184342 -196.016439)
			(xy 298.168445 -195.954525) (xy 298.160434 -195.891107) (xy 298.159932 -195.859146) (xy 293.87786 -195.859146)
			(xy 293.854824 -195.901048) (xy 293.81819 -195.95147) (xy 293.775525 -195.996904) (xy 293.727503 -196.036632)
			(xy 293.674879 -196.070027) (xy 293.618485 -196.096564) (xy 293.55921 -196.115824) (xy 293.497989 -196.127503)
			(xy 293.435786 -196.131416) (xy 293.373583 -196.127503) (xy 293.312362 -196.115824) (xy 293.253087 -196.096564)
			(xy 293.196693 -196.070027) (xy 293.144069 -196.036632) (xy 293.096047 -195.996904) (xy 293.053382 -195.95147)
			(xy 293.016748 -195.901048) (xy 292.986722 -195.846431) (xy 292.963779 -195.788483) (xy 292.948279 -195.728115)
			(xy 292.940467 -195.666281) (xy 292.939978 -195.635118) (xy 292.940497 -195.602185) (xy 292.949182 -195.536896)
			(xy 292.966443 -195.473333) (xy 292.991973 -195.412617) (xy 293.025323 -195.35582) (xy 293.065905 -195.303943)
			(xy 293.089076 -195.280534) (xy 293.096442 -195.273422) (xy 293.10457 -195.254372) (xy 293.104062 -195.1609)
			(xy 293.096188 -195.14185) (xy 293.088568 -195.134738) (xy 293.064431 -195.110699) (xy 293.022154 -195.057283)
			(xy 292.987391 -194.998699) (xy 292.960764 -194.935997) (xy 292.942752 -194.8703) (xy 292.933676 -194.802785)
			(xy 292.93312 -194.768724) (xy 292.933611 -194.736896) (xy 292.941547 -194.673736) (xy 292.957299 -194.612059)
			(xy 292.980621 -194.552828) (xy 293.011148 -194.496969) (xy 293.048404 -194.445353) (xy 293.069772 -194.42176)
			(xy 293.07663 -194.414394) (xy 293.083742 -194.39636) (xy 293.082726 -194.306444) (xy 293.07536 -194.288664)
			(xy 293.068248 -194.281552) (xy 293.046278 -194.258318) (xy 293.007877 -194.207187) (xy 292.976364 -194.151547)
			(xy 292.95226 -194.092318) (xy 292.935965 -194.030484) (xy 292.92775 -193.967069) (xy 292.927278 -193.935096)
			(xy 292.927809 -193.902634) (xy 292.936284 -193.838264) (xy 292.953088 -193.775552) (xy 292.977933 -193.715569)
			(xy 293.010395 -193.659343) (xy 293.049918 -193.607834) (xy 293.095827 -193.561925) (xy 293.147334 -193.522401)
			(xy 293.20356 -193.489938) (xy 293.263543 -193.465091) (xy 293.326255 -193.448286) (xy 293.390624 -193.43981)
			(xy 293.423086 -193.439288) (xy 293.455139 -193.439787) (xy 293.51871 -193.448046) (xy 293.580684 -193.464442)
			(xy 293.610538 -193.476118) (xy 293.624254 -193.481706) (xy 293.65321 -193.476372) (xy 293.742618 -193.393822)
			(xy 293.750238 -193.365374) (xy 293.745666 -193.35115) (xy 293.733169 -193.310269) (xy 293.715234 -193.22668)
			(xy 293.709852 -193.184272) (xy 293.708582 -193.17335) (xy 293.698168 -193.155316) (xy 293.620698 -193.09842)
			(xy 293.600124 -193.093848) (xy 293.58971 -193.09588) (xy 293.548461 -193.103366) (xy 293.465006 -193.111383)
			(xy 293.423086 -193.111882) (xy 293.380037 -193.11137) (xy 293.294354 -193.10293) (xy 293.209911 -193.086131)
			(xy 293.127522 -193.061137) (xy 293.047978 -193.028187) (xy 292.972048 -192.9876) (xy 292.900461 -192.939765)
			(xy 292.833908 -192.885144) (xy 292.77303 -192.824262) (xy 292.718411 -192.757706) (xy 292.67058 -192.686118)
			(xy 292.629996 -192.610185) (xy 292.59705 -192.530641) (xy 292.572059 -192.44825) (xy 292.555265 -192.363806)
			(xy 292.546828 -192.278123) (xy 292.546278 -192.235074) (xy 292.546499 -192.206544) (xy 292.550182 -192.149602)
			(xy 292.553644 -192.121282) (xy 292.555168 -192.11036) (xy 292.548818 -192.089532) (xy 292.49116 -192.023746)
			(xy 292.483624 -192.015948) (xy 292.463891 -192.007005) (xy 292.45306 -192.006474) (xy 291.581586 -192.006474)
			(xy 291.570051 -192.007019) (xy 291.549282 -192.017062) (xy 291.541708 -192.025778) (xy 291.485066 -192.09766)
			(xy 291.48024 -192.12052) (xy 291.483034 -192.13195) (xy 291.487798 -192.153221) (xy 291.492896 -192.196514)
			(xy 291.493194 -192.21831) (xy 291.492678 -192.24591) (xy 291.484451 -192.300493) (xy 291.468181 -192.35324)
			(xy 291.444231 -192.402973) (xy 291.413136 -192.44858) (xy 291.375591 -192.489044) (xy 291.332434 -192.523461)
			(xy 291.28463 -192.55106) (xy 291.233246 -192.571227) (xy 291.179431 -192.58351) (xy 291.124386 -192.587635)
			(xy 291.069341 -192.58351) (xy 291.015526 -192.571227) (xy 290.964142 -192.55106) (xy 290.916338 -192.523461)
			(xy 290.873181 -192.489044) (xy 290.835636 -192.44858) (xy 290.804541 -192.402973) (xy 290.780591 -192.35324)
			(xy 290.764321 -192.300493) (xy 290.756094 -192.24591) (xy 290.755578 -192.21831) (xy 290.755854 -192.196512)
			(xy 290.760949 -192.153217) (xy 290.765738 -192.13195) (xy 290.768532 -192.12052) (xy 290.763706 -192.09766)
			(xy 290.707064 -192.025778) (xy 290.69949 -192.017056) (xy 290.678725 -192.006987) (xy 290.667186 -192.006474)
			(xy 289.792918 -192.006474) (xy 289.78138 -192.007012) (xy 289.7606 -192.017047) (xy 289.75304 -192.025778)
			(xy 289.696398 -192.09766) (xy 289.691572 -192.12052) (xy 289.694366 -192.13195) (xy 289.699129 -192.153221)
			(xy 289.704228 -192.196514) (xy 289.704526 -192.21831) (xy 289.70401 -192.24591) (xy 289.695783 -192.300493)
			(xy 289.679513 -192.35324) (xy 289.655563 -192.402973) (xy 289.624468 -192.44858) (xy 289.586923 -192.489044)
			(xy 289.543766 -192.523461) (xy 289.495962 -192.55106) (xy 289.444578 -192.571227) (xy 289.390763 -192.58351)
			(xy 289.335718 -192.587635) (xy 289.280673 -192.58351) (xy 289.226858 -192.571227) (xy 289.175474 -192.55106)
			(xy 289.12767 -192.523461) (xy 289.084513 -192.489044) (xy 289.046968 -192.44858) (xy 289.015873 -192.402973)
			(xy 288.991923 -192.35324) (xy 288.975653 -192.300493) (xy 288.967426 -192.24591) (xy 288.96691 -192.21831)
			(xy 288.967186 -192.196512) (xy 288.972282 -192.153217) (xy 288.97707 -192.13195) (xy 288.979864 -192.12052)
			(xy 288.975038 -192.09766) (xy 288.918396 -192.025778) (xy 288.910817 -192.017068) (xy 288.890052 -192.007026)
			(xy 288.878518 -192.006474) (xy 288.007044 -192.006474) (xy 287.996207 -192.006976) (xy 287.976469 -192.01593)
			(xy 287.968944 -192.023746) (xy 287.911286 -192.089532) (xy 287.904936 -192.11036) (xy 287.90646 -192.121282)
			(xy 287.909927 -192.149602) (xy 287.91361 -192.206544) (xy 287.913826 -192.235074) (xy 287.913336 -192.276801)
			(xy 287.905385 -192.359874) (xy 287.889572 -192.441815) (xy 287.866039 -192.521882) (xy 287.835 -192.599348)
			(xy 287.81629 -192.636648) (xy 287.811313 -192.647811) (xy 287.811319 -192.672217) (xy 287.81629 -192.683384)
			(xy 287.834968 -192.720697) (xy 287.865987 -192.798166) (xy 287.889512 -192.878231) (xy 287.905328 -192.960167)
			(xy 287.913293 -193.043234) (xy 287.913826 -193.084958) (xy 287.913311 -193.127344) (xy 287.905125 -193.21172)
			(xy 287.888835 -193.294911) (xy 287.864593 -193.376143) (xy 287.832625 -193.454656) (xy 287.79323 -193.529718)
			(xy 287.746775 -193.600628) (xy 287.693694 -193.666724) (xy 287.634483 -193.72739) (xy 287.569694 -193.782058)
			(xy 287.535112 -193.806572) (xy 287.527476 -193.812331) (xy 287.516813 -193.828191) (xy 287.512691 -193.846853)
			(xy 287.513776 -193.856356) (xy 287.51673 -193.875907) (xy 287.519911 -193.915324) (xy 287.520126 -193.935096)
			(xy 287.519636 -193.96693) (xy 287.515844 -193.996305) (xy 288.839391 -193.996305) (xy 288.843238 -193.934627)
			(xy 288.85472 -193.873906) (xy 288.873658 -193.815082) (xy 288.89976 -193.759068) (xy 288.932621 -193.706732)
			(xy 288.971731 -193.658885) (xy 289.016484 -193.616269) (xy 289.066185 -193.579545) (xy 289.092894 -193.564002)
			(xy 289.10407 -193.557906) (xy 289.117532 -193.53657) (xy 289.126168 -193.427096) (xy 289.116262 -193.403982)
			(xy 289.106102 -193.396108) (xy 289.084766 -193.378508) (xy 289.047104 -193.338006) (xy 289.015916 -193.29233)
			(xy 288.991903 -193.242508) (xy 288.975603 -193.189657) (xy 288.967383 -193.134964) (xy 288.96691 -193.10731)
			(xy 288.967426 -193.07971) (xy 288.975653 -193.025127) (xy 288.991923 -192.97238) (xy 289.015873 -192.922648)
			(xy 289.046968 -192.87704) (xy 289.084513 -192.836576) (xy 289.12767 -192.802159) (xy 289.175474 -192.77456)
			(xy 289.226858 -192.754393) (xy 289.280673 -192.74211) (xy 289.335718 -192.737985) (xy 289.390763 -192.74211)
			(xy 289.444578 -192.754393) (xy 289.495962 -192.77456) (xy 289.543766 -192.802159) (xy 289.586923 -192.836576)
			(xy 289.624468 -192.87704) (xy 289.655563 -192.922648) (xy 289.679513 -192.97238) (xy 289.695783 -193.025127)
			(xy 289.70401 -193.07971) (xy 289.704526 -193.10731) (xy 289.704034 -193.134961) (xy 289.695795 -193.189647)
			(xy 289.679488 -193.24249) (xy 289.655478 -193.292308) (xy 289.624303 -193.337986) (xy 289.58666 -193.378501)
			(xy 289.565334 -193.396108) (xy 289.555174 -193.403982) (xy 289.545268 -193.427096) (xy 289.553904 -193.53657)
			(xy 289.567366 -193.557906) (xy 289.578542 -193.564002) (xy 289.605258 -193.579532) (xy 289.654959 -193.616259)
			(xy 289.69971 -193.658877) (xy 289.738818 -193.706726) (xy 289.771678 -193.759064) (xy 289.797778 -193.81508)
			(xy 289.816716 -193.873905) (xy 289.828197 -193.934627) (xy 289.832044 -193.996305) (xy 289.828196 -194.057983)
			(xy 289.816714 -194.118705) (xy 289.797775 -194.177529) (xy 289.771673 -194.233544) (xy 289.738813 -194.285882)
			(xy 289.699703 -194.33373) (xy 289.654951 -194.376347) (xy 289.60525 -194.413073) (xy 289.578542 -194.428618)
			(xy 289.567366 -194.434714) (xy 289.553904 -194.45605) (xy 289.545268 -194.565524) (xy 289.555174 -194.588638)
			(xy 289.565334 -194.596512) (xy 289.586666 -194.614116) (xy 289.624331 -194.654616) (xy 289.655521 -194.70029)
			(xy 289.679536 -194.750112) (xy 289.695835 -194.802963) (xy 289.704054 -194.857656) (xy 289.704526 -194.88531)
			(xy 289.70401 -194.91291) (xy 289.695783 -194.967493) (xy 289.679513 -195.02024) (xy 289.655563 -195.069973)
			(xy 289.624468 -195.11558) (xy 289.586923 -195.156044) (xy 289.543766 -195.190461) (xy 289.495962 -195.21806)
			(xy 289.444578 -195.238227) (xy 289.390763 -195.25051) (xy 289.335718 -195.254635) (xy 289.280673 -195.25051)
			(xy 289.226858 -195.238227) (xy 289.175474 -195.21806) (xy 289.12767 -195.190461) (xy 289.084513 -195.156044)
			(xy 289.046968 -195.11558) (xy 289.015873 -195.069973) (xy 288.991923 -195.02024) (xy 288.975653 -194.967493)
			(xy 288.967426 -194.91291) (xy 288.96691 -194.88531) (xy 288.967403 -194.857659) (xy 288.97564 -194.802973)
			(xy 288.991946 -194.750129) (xy 289.015955 -194.70031) (xy 289.047131 -194.654632) (xy 289.084775 -194.614119)
			(xy 289.106102 -194.596512) (xy 289.116262 -194.588638) (xy 289.126168 -194.565524) (xy 289.117532 -194.45605)
			(xy 289.10407 -194.434714) (xy 289.092894 -194.428618) (xy 289.066194 -194.41306) (xy 289.016491 -194.376337)
			(xy 288.971737 -194.333722) (xy 288.932627 -194.285876) (xy 288.899765 -194.23354) (xy 288.873662 -194.177527)
			(xy 288.854722 -194.118703) (xy 288.843239 -194.057982) (xy 288.839391 -193.996305) (xy 287.515844 -193.996305)
			(xy 287.511485 -194.030073) (xy 287.495317 -194.091654) (xy 287.471398 -194.150657) (xy 287.440121 -194.206113)
			(xy 287.402002 -194.257107) (xy 287.380172 -194.280282) (xy 287.37306 -194.287648) (xy 287.365694 -194.305936)
			(xy 287.36671 -194.397884) (xy 287.374584 -194.416172) (xy 287.381696 -194.423284) (xy 287.405179 -194.447247)
			(xy 287.446285 -194.500274) (xy 287.480063 -194.558245) (xy 287.505928 -194.620153) (xy 287.52343 -194.684924)
			(xy 287.532265 -194.751433) (xy 287.532826 -194.78498) (xy 287.532324 -194.816941) (xy 287.524313 -194.880359)
			(xy 287.508416 -194.942273) (xy 287.484884 -195.001706) (xy 287.45409 -195.057721) (xy 287.416517 -195.109436)
			(xy 287.37276 -195.156033) (xy 287.323507 -195.196778) (xy 287.269536 -195.231029) (xy 287.211697 -195.258246)
			(xy 287.150904 -195.277999) (xy 287.088114 -195.289977) (xy 287.024318 -195.293991) (xy 286.960522 -195.289977)
			(xy 286.897732 -195.277999) (xy 286.836939 -195.258246) (xy 286.7791 -195.231029) (xy 286.725129 -195.196778)
			(xy 286.675876 -195.156033) (xy 286.632119 -195.109436) (xy 286.594546 -195.057721) (xy 286.563752 -195.001706)
			(xy 286.54022 -194.942273) (xy 286.524323 -194.880359) (xy 286.516312 -194.816941) (xy 286.51581 -194.78498)
			(xy 286.516343 -194.75143) (xy 286.525161 -194.684912) (xy 286.542655 -194.620133) (xy 286.56852 -194.558218)
			(xy 286.602307 -194.500246) (xy 286.643428 -194.447222) (xy 286.66694 -194.423284) (xy 286.674052 -194.416172)
			(xy 286.681926 -194.397884) (xy 286.682942 -194.305936) (xy 286.675576 -194.287648) (xy 286.668464 -194.280282)
			(xy 286.646641 -194.257099) (xy 286.608509 -194.206113) (xy 286.577224 -194.150661) (xy 286.5533 -194.091658)
			(xy 286.537133 -194.030076) (xy 286.528989 -193.96693) (xy 286.52851 -193.935096) (xy 286.528798 -193.911647)
			(xy 286.533253 -193.86496) (xy 286.5374 -193.841878) (xy 286.538829 -193.83239) (xy 286.535304 -193.813543)
			(xy 286.525085 -193.79732) (xy 286.517588 -193.791332) (xy 286.494644 -193.774186) (xy 286.450794 -193.737326)
			(xy 286.429958 -193.717672) (xy 286.422617 -193.71128) (xy 286.404554 -193.704071) (xy 286.385105 -193.704098)
			(xy 286.367062 -193.711357) (xy 286.353013 -193.724806) (xy 286.344974 -193.742515) (xy 286.344098 -193.761944)
			(xy 286.3469 -193.771266) (xy 286.35576 -193.79766) (xy 286.368189 -193.851933) (xy 286.37446 -193.907257)
			(xy 286.37484 -193.935096) (xy 286.374332 -193.967198) (xy 286.366041 -194.030863) (xy 286.349596 -194.092925)
			(xy 286.325274 -194.152343) (xy 286.293481 -194.208122) (xy 286.254751 -194.259328) (xy 286.2326 -194.282568)
			(xy 286.225488 -194.289934) (xy 286.218122 -194.30873) (xy 286.219392 -194.40144) (xy 286.22752 -194.419982)
			(xy 286.234886 -194.427094) (xy 286.25857 -194.450554) (xy 286.300071 -194.502726) (xy 286.334205 -194.559989)
			(xy 286.360357 -194.62131) (xy 286.378055 -194.685583) (xy 286.386979 -194.751648) (xy 286.38754 -194.78498)
			(xy 286.387017 -194.817701) (xy 286.378417 -194.882574) (xy 286.361362 -194.945754) (xy 286.336149 -195.006143)
			(xy 286.303216 -195.062693) (xy 286.263134 -195.114423) (xy 286.24022 -195.137786) (xy 286.232854 -195.144898)
			(xy 286.22498 -195.163694) (xy 286.22498 -195.256404) (xy 286.232854 -195.2752) (xy 286.24022 -195.282312)
			(xy 286.263126 -195.305685) (xy 286.303222 -195.357407) (xy 286.336167 -195.413953) (xy 286.36139 -195.474341)
			(xy 286.378452 -195.537521) (xy 286.387056 -195.602396) (xy 286.38754 -195.635118) (xy 286.387051 -195.666281)
			(xy 286.379239 -195.728115) (xy 286.363739 -195.788483) (xy 286.340796 -195.846431) (xy 286.333806 -195.859146)
			(xy 290.616132 -195.859146) (xy 290.616694 -195.825988) (xy 290.625305 -195.760234) (xy 290.642387 -195.696156)
			(xy 290.667651 -195.63484) (xy 290.700667 -195.577328) (xy 290.740876 -195.524593) (xy 290.787597 -195.477529)
			(xy 290.81349 -195.45681) (xy 290.822405 -195.449263) (xy 290.832732 -195.428344) (xy 290.833302 -195.416678)
			(xy 290.833302 -195.336414) (xy 290.832652 -195.324767) (xy 290.822349 -195.303868) (xy 290.81349 -195.296282)
			(xy 290.787621 -195.275533) (xy 290.740895 -195.228476) (xy 290.700679 -195.175747) (xy 290.667656 -195.11824)
			(xy 290.642384 -195.056929) (xy 290.625292 -194.992855) (xy 290.616669 -194.927103) (xy 290.616132 -194.893946)
			(xy 290.616721 -194.860173) (xy 290.625665 -194.793221) (xy 290.643389 -194.728042) (xy 290.66958 -194.66578)
			(xy 290.703779 -194.607531) (xy 290.745384 -194.554319) (xy 290.793664 -194.507079) (xy 290.847769 -194.466643)
			(xy 290.87699 -194.4497) (xy 290.888166 -194.443604) (xy 290.901882 -194.422522) (xy 290.91128 -194.313556)
			(xy 290.901628 -194.290188) (xy 290.891722 -194.282314) (xy 290.870873 -194.264704) (xy 290.834108 -194.224374)
			(xy 290.803685 -194.179069) (xy 290.780266 -194.129777) (xy 290.764364 -194.077573) (xy 290.756324 -194.023596)
			(xy 290.755832 -193.99631) (xy 290.756348 -193.96871) (xy 290.764575 -193.914127) (xy 290.780845 -193.86138)
			(xy 290.804795 -193.811648) (xy 290.83589 -193.76604) (xy 290.873435 -193.725576) (xy 290.916592 -193.691159)
			(xy 290.964396 -193.66356) (xy 291.01578 -193.643393) (xy 291.069595 -193.63111) (xy 291.12464 -193.626985)
			(xy 291.179685 -193.63111) (xy 291.2335 -193.643393) (xy 291.284884 -193.66356) (xy 291.332688 -193.691159)
			(xy 291.375845 -193.725576) (xy 291.41339 -193.76604) (xy 291.444485 -193.811648) (xy 291.468435 -193.86138)
			(xy 291.484705 -193.914127) (xy 291.492932 -193.96871) (xy 291.493448 -193.99631) (xy 291.492991 -194.023599)
			(xy 291.484959 -194.077581) (xy 291.469055 -194.129789) (xy 291.445629 -194.179083) (xy 291.415192 -194.224384)
			(xy 291.378409 -194.264704) (xy 291.357558 -194.282314) (xy 291.347652 -194.290188) (xy 291.338 -194.313556)
			(xy 291.347398 -194.422522) (xy 291.361114 -194.443604) (xy 291.37229 -194.4497) (xy 291.401522 -194.466629)
			(xy 291.455641 -194.507057) (xy 291.503932 -194.554293) (xy 291.545546 -194.607505) (xy 291.579751 -194.665758)
			(xy 291.605943 -194.728025) (xy 291.623663 -194.793212) (xy 291.632599 -194.86017) (xy 291.633148 -194.893946)
			(xy 291.632587 -194.927104) (xy 291.623977 -194.992859) (xy 291.606895 -195.056937) (xy 291.581632 -195.118253)
			(xy 291.548615 -195.175765) (xy 291.508405 -195.2285) (xy 291.461683 -195.275563) (xy 291.43579 -195.296282)
			(xy 291.426876 -195.303829) (xy 291.416548 -195.324748) (xy 291.415978 -195.336414) (xy 291.415978 -195.416678)
			(xy 291.416639 -195.428323) (xy 291.426935 -195.449222) (xy 291.43579 -195.45681) (xy 291.461672 -195.477543)
			(xy 291.508394 -195.524605) (xy 291.548606 -195.577338) (xy 291.581627 -195.634848) (xy 291.606897 -195.69616)
			(xy 291.623988 -195.760235) (xy 291.63261 -195.825988) (xy 291.633148 -195.859146) (xy 291.632646 -195.891107)
			(xy 291.624635 -195.954525) (xy 291.608738 -196.016439) (xy 291.585206 -196.075872) (xy 291.554412 -196.131887)
			(xy 291.516839 -196.183602) (xy 291.473082 -196.230199) (xy 291.423829 -196.270944) (xy 291.369858 -196.305195)
			(xy 291.312019 -196.332412) (xy 291.251226 -196.352165) (xy 291.188436 -196.364143) (xy 291.12464 -196.368157)
			(xy 291.060844 -196.364143) (xy 290.998054 -196.352165) (xy 290.937261 -196.332412) (xy 290.879422 -196.305195)
			(xy 290.825451 -196.270944) (xy 290.776198 -196.230199) (xy 290.732441 -196.183602) (xy 290.694868 -196.131887)
			(xy 290.664074 -196.075872) (xy 290.640542 -196.016439) (xy 290.624645 -195.954525) (xy 290.616634 -195.891107)
			(xy 290.616132 -195.859146) (xy 286.333806 -195.859146) (xy 286.31077 -195.901048) (xy 286.274136 -195.95147)
			(xy 286.231471 -195.996904) (xy 286.183449 -196.036632) (xy 286.130825 -196.070027) (xy 286.074431 -196.096564)
			(xy 286.015156 -196.115824) (xy 285.953935 -196.127503) (xy 285.891732 -196.131416) (xy 285.829529 -196.127503)
			(xy 285.768308 -196.115824) (xy 285.709033 -196.096564) (xy 285.652639 -196.070027) (xy 285.600015 -196.036632)
			(xy 285.551993 -195.996904) (xy 285.509328 -195.95147) (xy 285.472694 -195.901048) (xy 285.442668 -195.846431)
			(xy 285.419725 -195.788483) (xy 285.404225 -195.728115) (xy 285.396413 -195.666281) (xy 285.395924 -195.635118)
			(xy 285.396446 -195.602397) (xy 285.405047 -195.537523) (xy 285.422101 -195.474343) (xy 285.447312 -195.413953)
			(xy 285.480244 -195.357401) (xy 285.520324 -195.305669) (xy 285.543244 -195.282312) (xy 285.55061 -195.2752)
			(xy 285.558484 -195.256404) (xy 285.558484 -195.163694) (xy 285.55061 -195.144898) (xy 285.543244 -195.137786)
			(xy 285.520339 -195.114412) (xy 285.480247 -195.062689) (xy 285.447304 -195.006143) (xy 285.422083 -194.945755)
			(xy 285.405023 -194.882576) (xy 285.39642 -194.817701) (xy 285.395924 -194.78498) (xy 285.396434 -194.752879)
			(xy 285.404729 -194.689216) (xy 285.421177 -194.627158) (xy 285.445504 -194.567744) (xy 285.477301 -194.511969)
			(xy 285.516036 -194.46077) (xy 285.538164 -194.437508) (xy 285.545276 -194.430142) (xy 285.552642 -194.411346)
			(xy 285.551372 -194.318636) (xy 285.543244 -194.300094) (xy 285.535878 -194.292982) (xy 285.512191 -194.269522)
			(xy 285.470685 -194.217352) (xy 285.436544 -194.16009) (xy 285.410385 -194.098769) (xy 285.392679 -194.034496)
			(xy 285.383746 -193.96843) (xy 285.383224 -193.935096) (xy 285.383732 -193.902633) (xy 285.392207 -193.838263)
			(xy 285.409012 -193.77555) (xy 285.43386 -193.715567) (xy 285.466324 -193.659341) (xy 285.50585 -193.607834)
			(xy 285.551761 -193.561926) (xy 285.603271 -193.522404) (xy 285.6595 -193.489944) (xy 285.719484 -193.465101)
			(xy 285.782199 -193.4483) (xy 285.846569 -193.43983) (xy 285.879032 -193.439288) (xy 285.911084 -193.43979)
			(xy 285.974654 -193.448055) (xy 286.036625 -193.464455) (xy 286.066484 -193.476118) (xy 286.0802 -193.481706)
			(xy 286.109156 -193.476372) (xy 286.198564 -193.393822) (xy 286.206184 -193.365374) (xy 286.201612 -193.35115)
			(xy 286.189115 -193.310269) (xy 286.171179 -193.226681) (xy 286.165798 -193.184272) (xy 286.164528 -193.17335)
			(xy 286.154114 -193.155316) (xy 286.076644 -193.09842) (xy 286.05607 -193.093848) (xy 286.045656 -193.09588)
			(xy 286.004407 -193.103363) (xy 285.920951 -193.111375) (xy 285.879032 -193.111882) (xy 285.835982 -193.111372)
			(xy 285.750296 -193.102936) (xy 285.665849 -193.086141) (xy 285.583455 -193.061149) (xy 285.503908 -193.028201)
			(xy 285.427974 -192.987615) (xy 285.356383 -192.939781) (xy 285.289826 -192.88516) (xy 285.228944 -192.824278)
			(xy 285.174322 -192.757721) (xy 285.126488 -192.686131) (xy 285.085901 -192.610197) (xy 285.052953 -192.53065)
			(xy 285.027961 -192.448257) (xy 285.011165 -192.36381) (xy 285.002728 -192.278124) (xy 285.002224 -192.235074)
			(xy 285.002445 -192.206544) (xy 285.006128 -192.149602) (xy 285.00959 -192.121282) (xy 285.011114 -192.11036)
			(xy 285.004764 -192.089532) (xy 284.947106 -192.023746) (xy 284.939573 -192.015941) (xy 284.91984 -192.00698)
			(xy 284.909006 -192.006474) (xy 284.037532 -192.006474) (xy 284.026003 -192.00703) (xy 284.005251 -192.017086)
			(xy 283.997654 -192.025778) (xy 283.941012 -192.09766) (xy 283.936186 -192.12052) (xy 283.93898 -192.13195)
			(xy 283.943743 -192.153221) (xy 283.948841 -192.196514) (xy 283.94914 -192.21831) (xy 283.948624 -192.24591)
			(xy 283.940397 -192.300493) (xy 283.924127 -192.35324) (xy 283.900177 -192.402973) (xy 283.869082 -192.44858)
			(xy 283.831537 -192.489044) (xy 283.78838 -192.523461) (xy 283.740576 -192.55106) (xy 283.689192 -192.571227)
			(xy 283.635377 -192.58351) (xy 283.580332 -192.587635) (xy 283.525287 -192.58351) (xy 283.471472 -192.571227)
			(xy 283.420088 -192.55106) (xy 283.372284 -192.523461) (xy 283.329127 -192.489044) (xy 283.291582 -192.44858)
			(xy 283.260487 -192.402973) (xy 283.236537 -192.35324) (xy 283.220267 -192.300493) (xy 283.21204 -192.24591)
			(xy 283.211524 -192.21831) (xy 283.2118 -192.196512) (xy 283.216896 -192.153217) (xy 283.221684 -192.13195)
			(xy 283.224478 -192.12052) (xy 283.219652 -192.09766) (xy 283.16301 -192.025778) (xy 283.155432 -192.017065)
			(xy 283.134667 -192.007018) (xy 283.123132 -192.006474) (xy 282.248864 -192.006474) (xy 282.237331 -192.007023)
			(xy 282.216569 -192.017072) (xy 282.208986 -192.025778) (xy 282.152344 -192.09766) (xy 282.147518 -192.12052)
			(xy 282.150312 -192.13195) (xy 282.155076 -192.153221) (xy 282.160175 -192.196514) (xy 282.160472 -192.21831)
			(xy 282.159956 -192.24591) (xy 282.151729 -192.300493) (xy 282.135459 -192.35324) (xy 282.111509 -192.402973)
			(xy 282.080414 -192.44858) (xy 282.042869 -192.489044) (xy 281.999712 -192.523461) (xy 281.951908 -192.55106)
			(xy 281.900524 -192.571227) (xy 281.846709 -192.58351) (xy 281.791664 -192.587635) (xy 281.736619 -192.58351)
			(xy 281.682804 -192.571227) (xy 281.63142 -192.55106) (xy 281.583616 -192.523461) (xy 281.540459 -192.489044)
			(xy 281.502914 -192.44858) (xy 281.471819 -192.402973) (xy 281.447869 -192.35324) (xy 281.431599 -192.300493)
			(xy 281.423372 -192.24591) (xy 281.422856 -192.21831) (xy 281.423132 -192.196512) (xy 281.428227 -192.153217)
			(xy 281.433016 -192.13195) (xy 281.43581 -192.12052) (xy 281.430984 -192.09766) (xy 281.374342 -192.025778)
			(xy 281.366766 -192.01706) (xy 281.346001 -192.006999) (xy 281.334464 -192.006474) (xy 280.46299 -192.006474)
			(xy 280.452148 -192.006967) (xy 280.432396 -192.015909) (xy 280.42489 -192.023746) (xy 280.367232 -192.089532)
			(xy 280.360882 -192.11036) (xy 280.362406 -192.121282) (xy 280.365873 -192.149602) (xy 280.369555 -192.206544)
			(xy 280.369772 -192.235074) (xy 280.369282 -192.2768) (xy 280.361331 -192.359874) (xy 280.345516 -192.441815)
			(xy 280.321982 -192.521881) (xy 280.290942 -192.599346) (xy 280.272236 -192.636648) (xy 280.267255 -192.647811)
			(xy 280.267262 -192.672217) (xy 280.272236 -192.683384) (xy 280.290915 -192.720697) (xy 280.321936 -192.798166)
			(xy 280.345462 -192.87823) (xy 280.361279 -192.960166) (xy 280.369245 -193.043234) (xy 280.369772 -193.084958)
			(xy 280.369257 -193.127344) (xy 280.361071 -193.211718) (xy 280.34478 -193.294909) (xy 280.320537 -193.37614)
			(xy 280.288568 -193.454652) (xy 280.249171 -193.529712) (xy 280.202715 -193.60062) (xy 280.149632 -193.666713)
			(xy 280.090419 -193.727376) (xy 280.025627 -193.782041) (xy 279.991058 -193.806572) (xy 279.983417 -193.812328)
			(xy 279.972744 -193.828188) (xy 279.968618 -193.846853) (xy 279.969722 -193.856356) (xy 279.972676 -193.875907)
			(xy 279.975857 -193.915324) (xy 279.976072 -193.935096) (xy 279.975582 -193.96693) (xy 279.971791 -193.996305)
			(xy 281.295365 -193.996305) (xy 281.299211 -193.93463) (xy 281.310691 -193.87391) (xy 281.329628 -193.815088)
			(xy 281.355726 -193.759075) (xy 281.388583 -193.706739) (xy 281.427689 -193.658891) (xy 281.472437 -193.616274)
			(xy 281.522134 -193.579547) (xy 281.54884 -193.564002) (xy 281.560016 -193.557906) (xy 281.573478 -193.53657)
			(xy 281.582114 -193.427096) (xy 281.572208 -193.403982) (xy 281.562048 -193.396108) (xy 281.540721 -193.378497)
			(xy 281.503057 -193.337998) (xy 281.471867 -193.292325) (xy 281.447852 -193.242505) (xy 281.43155 -193.189656)
			(xy 281.423329 -193.134964) (xy 281.422856 -193.10731) (xy 281.423372 -193.07971) (xy 281.431599 -193.025127)
			(xy 281.447869 -192.97238) (xy 281.471819 -192.922648) (xy 281.502914 -192.87704) (xy 281.540459 -192.836576)
			(xy 281.583616 -192.802159) (xy 281.63142 -192.77456) (xy 281.682804 -192.754393) (xy 281.736619 -192.74211)
			(xy 281.791664 -192.737985) (xy 281.846709 -192.74211) (xy 281.900524 -192.754393) (xy 281.951908 -192.77456)
			(xy 281.999712 -192.802159) (xy 282.042869 -192.836576) (xy 282.080414 -192.87704) (xy 282.111509 -192.922648)
			(xy 282.135459 -192.97238) (xy 282.151729 -193.025127) (xy 282.159956 -193.07971) (xy 282.160472 -193.10731)
			(xy 282.16 -193.134962) (xy 282.15176 -193.189649) (xy 282.13545 -193.242494) (xy 282.111436 -193.292313)
			(xy 282.080257 -193.33799) (xy 282.042609 -193.378502) (xy 282.02128 -193.396108) (xy 282.01112 -193.403982)
			(xy 282.001214 -193.427096) (xy 282.00985 -193.53657) (xy 282.023312 -193.557906) (xy 282.034488 -193.564002)
			(xy 282.061207 -193.57953) (xy 282.110912 -193.616254) (xy 282.155668 -193.658871) (xy 282.194781 -193.706719)
			(xy 282.227644 -193.759058) (xy 282.253748 -193.815074) (xy 282.272688 -193.8739) (xy 282.28417 -193.934625)
			(xy 282.288017 -193.996305) (xy 282.284169 -194.057985) (xy 282.272685 -194.118709) (xy 282.253744 -194.177535)
			(xy 282.227639 -194.233551) (xy 282.194775 -194.285889) (xy 282.155661 -194.333736) (xy 282.110905 -194.376352)
			(xy 282.061199 -194.413075) (xy 282.034488 -194.428618) (xy 282.023312 -194.434714) (xy 282.00985 -194.45605)
			(xy 282.001214 -194.565524) (xy 282.01112 -194.588638) (xy 282.02128 -194.596512) (xy 282.042622 -194.614105)
			(xy 282.080284 -194.654609) (xy 282.111472 -194.700285) (xy 282.135484 -194.750109) (xy 282.151782 -194.802961)
			(xy 282.16 -194.857655) (xy 282.160472 -194.88531) (xy 282.159956 -194.91291) (xy 282.151729 -194.967493)
			(xy 282.135459 -195.02024) (xy 282.111509 -195.069973) (xy 282.080414 -195.11558) (xy 282.042869 -195.156044)
			(xy 281.999712 -195.190461) (xy 281.951908 -195.21806) (xy 281.900524 -195.238227) (xy 281.846709 -195.25051)
			(xy 281.791664 -195.254635) (xy 281.736619 -195.25051) (xy 281.682804 -195.238227) (xy 281.63142 -195.21806)
			(xy 281.583616 -195.190461) (xy 281.540459 -195.156044) (xy 281.502914 -195.11558) (xy 281.471819 -195.069973)
			(xy 281.447869 -195.02024) (xy 281.431599 -194.967493) (xy 281.423372 -194.91291) (xy 281.422856 -194.88531)
			(xy 281.423369 -194.85766) (xy 281.431604 -194.802976) (xy 281.447908 -194.750133) (xy 281.471914 -194.700314)
			(xy 281.503085 -194.654636) (xy 281.540724 -194.61412) (xy 281.562048 -194.596512) (xy 281.572208 -194.588638)
			(xy 281.582114 -194.565524) (xy 281.573478 -194.45605) (xy 281.560016 -194.434714) (xy 281.54884 -194.428618)
			(xy 281.522142 -194.413058) (xy 281.472444 -194.376332) (xy 281.427695 -194.333716) (xy 281.388589 -194.285869)
			(xy 281.355731 -194.233534) (xy 281.329631 -194.177521) (xy 281.310694 -194.118699) (xy 281.299212 -194.05798)
			(xy 281.295365 -193.996305) (xy 279.971791 -193.996305) (xy 279.967432 -194.030074) (xy 279.951265 -194.091655)
			(xy 279.927347 -194.15066) (xy 279.896073 -194.206118) (xy 279.857956 -194.257115) (xy 279.836118 -194.280282)
			(xy 279.829006 -194.287648) (xy 279.82164 -194.305936) (xy 279.822656 -194.397884) (xy 279.83053 -194.416172)
			(xy 279.837642 -194.423284) (xy 279.861127 -194.447246) (xy 279.902237 -194.500272) (xy 279.936019 -194.558242)
			(xy 279.961886 -194.62015) (xy 279.97939 -194.684922) (xy 279.988227 -194.751433) (xy 279.988772 -194.78498)
			(xy 279.98827 -194.816941) (xy 279.980259 -194.880359) (xy 279.964362 -194.942273) (xy 279.94083 -195.001706)
			(xy 279.910036 -195.057721) (xy 279.872463 -195.109436) (xy 279.828706 -195.156033) (xy 279.779453 -195.196778)
			(xy 279.725482 -195.231029) (xy 279.667643 -195.258246) (xy 279.60685 -195.277999) (xy 279.54406 -195.289977)
			(xy 279.480264 -195.293991) (xy 279.416468 -195.289977) (xy 279.353678 -195.277999) (xy 279.292885 -195.258246)
			(xy 279.235046 -195.231029) (xy 279.181075 -195.196778) (xy 279.131822 -195.156033) (xy 279.088065 -195.109436)
			(xy 279.050492 -195.057721) (xy 279.019698 -195.001706) (xy 278.996166 -194.942273) (xy 278.980269 -194.880359)
			(xy 278.972258 -194.816941) (xy 278.971756 -194.78498) (xy 278.972289 -194.75143) (xy 278.981108 -194.684913)
			(xy 278.998603 -194.620135) (xy 279.02447 -194.558222) (xy 279.058259 -194.500251) (xy 279.099382 -194.44723)
			(xy 279.122886 -194.423284) (xy 279.129998 -194.416172) (xy 279.137872 -194.397884) (xy 279.138888 -194.305936)
			(xy 279.131522 -194.287648) (xy 279.12441 -194.280282) (xy 279.102586 -194.2571) (xy 279.06445 -194.206115)
			(xy 279.033161 -194.150663) (xy 279.009236 -194.09166) (xy 278.993067 -194.030078) (xy 278.984923 -193.966931)
			(xy 278.984456 -193.935096) (xy 278.984744 -193.911647) (xy 278.9892 -193.86496) (xy 278.993346 -193.841878)
			(xy 278.994775 -193.832389) (xy 278.991252 -193.81354) (xy 278.981039 -193.797311) (xy 278.973534 -193.791332)
			(xy 278.950736 -193.774291) (xy 278.907144 -193.737683) (xy 278.886412 -193.71818) (xy 278.879092 -193.711777)
			(xy 278.86106 -193.704534) (xy 278.841628 -193.704517) (xy 278.823584 -193.711728) (xy 278.809516 -193.725133)
			(xy 278.801442 -193.742808) (xy 278.800522 -193.762219) (xy 278.803354 -193.77152) (xy 278.812143 -193.797885)
			(xy 278.824474 -193.852077) (xy 278.830673 -193.907307) (xy 278.83104 -193.935096) (xy 278.830532 -193.967198)
			(xy 278.822241 -194.030863) (xy 278.805796 -194.092925) (xy 278.781474 -194.152343) (xy 278.749681 -194.208122)
			(xy 278.710951 -194.259328) (xy 278.6888 -194.282568) (xy 278.681688 -194.289934) (xy 278.674322 -194.30873)
			(xy 278.675592 -194.40144) (xy 278.68372 -194.419982) (xy 278.691086 -194.427094) (xy 278.71477 -194.450554)
			(xy 278.756271 -194.502726) (xy 278.790405 -194.559989) (xy 278.816557 -194.62131) (xy 278.834255 -194.685583)
			(xy 278.843179 -194.751648) (xy 278.84374 -194.78498) (xy 278.843217 -194.817701) (xy 278.834617 -194.882574)
			(xy 278.817562 -194.945754) (xy 278.792349 -195.006143) (xy 278.759416 -195.062693) (xy 278.719334 -195.114423)
			(xy 278.69642 -195.137786) (xy 278.689054 -195.144898) (xy 278.68118 -195.163694) (xy 278.68118 -195.256404)
			(xy 278.689054 -195.2752) (xy 278.69642 -195.282312) (xy 278.719326 -195.305685) (xy 278.759422 -195.357407)
			(xy 278.792367 -195.413953) (xy 278.81759 -195.474341) (xy 278.834652 -195.537521) (xy 278.843256 -195.602396)
			(xy 278.84374 -195.635118) (xy 278.843251 -195.666281) (xy 278.835439 -195.728115) (xy 278.819939 -195.788483)
			(xy 278.796996 -195.846431) (xy 278.790006 -195.859146) (xy 283.072078 -195.859146) (xy 283.072623 -195.825987)
			(xy 283.081235 -195.760231) (xy 283.098318 -195.696152) (xy 283.123584 -195.634837) (xy 283.156603 -195.577324)
			(xy 283.196816 -195.52459) (xy 283.243541 -195.477528) (xy 283.269436 -195.45681) (xy 283.278359 -195.449272)
			(xy 283.28868 -195.428346) (xy 283.289248 -195.416678) (xy 283.289248 -195.336414) (xy 283.288617 -195.324764)
			(xy 283.278303 -195.303864) (xy 283.269436 -195.296282) (xy 283.243555 -195.275547) (xy 283.196832 -195.228486)
			(xy 283.156619 -195.175754) (xy 283.123598 -195.118244) (xy 283.098327 -195.056932) (xy 283.081237 -194.992857)
			(xy 283.072615 -194.927104) (xy 283.072078 -194.893946) (xy 283.072644 -194.860172) (xy 283.081589 -194.793218)
			(xy 283.099314 -194.728037) (xy 283.125508 -194.665774) (xy 283.15971 -194.607525) (xy 283.201319 -194.554313)
			(xy 283.249603 -194.507075) (xy 283.303713 -194.466641) (xy 283.332936 -194.4497) (xy 283.344112 -194.443604)
			(xy 283.357828 -194.422522) (xy 283.367226 -194.313556) (xy 283.357574 -194.290188) (xy 283.347668 -194.282314)
			(xy 283.326808 -194.264717) (xy 283.290047 -194.224383) (xy 283.259626 -194.179075) (xy 283.23621 -194.12978)
			(xy 283.220309 -194.077575) (xy 283.21227 -194.023597) (xy 283.211778 -193.99631) (xy 283.212294 -193.96871)
			(xy 283.220521 -193.914127) (xy 283.236791 -193.86138) (xy 283.260741 -193.811648) (xy 283.291836 -193.76604)
			(xy 283.329381 -193.725576) (xy 283.372538 -193.691159) (xy 283.420342 -193.66356) (xy 283.471726 -193.643393)
			(xy 283.525541 -193.63111) (xy 283.580586 -193.626985) (xy 283.635631 -193.63111) (xy 283.689446 -193.643393)
			(xy 283.74083 -193.66356) (xy 283.788634 -193.691159) (xy 283.831791 -193.725576) (xy 283.869336 -193.76604)
			(xy 283.900431 -193.811648) (xy 283.924381 -193.86138) (xy 283.940651 -193.914127) (xy 283.948878 -193.96871)
			(xy 283.949394 -193.99631) (xy 283.948957 -194.023599) (xy 283.940923 -194.077584) (xy 283.925017 -194.129793)
			(xy 283.901588 -194.179087) (xy 283.871146 -194.224388) (xy 283.834358 -194.264705) (xy 283.813504 -194.282314)
			(xy 283.803598 -194.290188) (xy 283.793946 -194.313556) (xy 283.803344 -194.422522) (xy 283.81706 -194.443604)
			(xy 283.828236 -194.4497) (xy 283.857479 -194.46661) (xy 283.911596 -194.507043) (xy 283.959885 -194.554282)
			(xy 284.001497 -194.607498) (xy 284.0357 -194.665753) (xy 284.061891 -194.728022) (xy 284.07961 -194.79321)
			(xy 284.088545 -194.860169) (xy 284.089094 -194.893946) (xy 284.088554 -194.927105) (xy 284.079942 -194.992861)
			(xy 284.062859 -195.056941) (xy 284.037592 -195.118257) (xy 284.004572 -195.17577) (xy 283.964358 -195.228504)
			(xy 283.917631 -195.275564) (xy 283.891736 -195.296282) (xy 283.882812 -195.303819) (xy 283.872492 -195.324746)
			(xy 283.871924 -195.336414) (xy 283.871924 -195.416678) (xy 283.872569 -195.428326) (xy 283.882875 -195.449225)
			(xy 283.891736 -195.45681) (xy 283.917607 -195.477557) (xy 283.964331 -195.524615) (xy 284.004546 -195.577345)
			(xy 284.037569 -195.634852) (xy 284.062841 -195.696163) (xy 284.079933 -195.760237) (xy 284.088556 -195.825989)
			(xy 284.089094 -195.859146) (xy 284.088592 -195.891107) (xy 284.080581 -195.954525) (xy 284.064684 -196.016439)
			(xy 284.041152 -196.075872) (xy 284.010358 -196.131887) (xy 283.972785 -196.183602) (xy 283.929028 -196.230199)
			(xy 283.879775 -196.270944) (xy 283.825804 -196.305195) (xy 283.767965 -196.332412) (xy 283.707172 -196.352165)
			(xy 283.644382 -196.364143) (xy 283.580586 -196.368157) (xy 283.51679 -196.364143) (xy 283.454 -196.352165)
			(xy 283.393207 -196.332412) (xy 283.335368 -196.305195) (xy 283.281397 -196.270944) (xy 283.232144 -196.230199)
			(xy 283.188387 -196.183602) (xy 283.150814 -196.131887) (xy 283.12002 -196.075872) (xy 283.096488 -196.016439)
			(xy 283.080591 -195.954525) (xy 283.07258 -195.891107) (xy 283.072078 -195.859146) (xy 278.790006 -195.859146)
			(xy 278.76697 -195.901048) (xy 278.730336 -195.95147) (xy 278.687671 -195.996904) (xy 278.639649 -196.036632)
			(xy 278.587025 -196.070027) (xy 278.530631 -196.096564) (xy 278.471356 -196.115824) (xy 278.410135 -196.127503)
			(xy 278.347932 -196.131416) (xy 278.285729 -196.127503) (xy 278.224508 -196.115824) (xy 278.165233 -196.096564)
			(xy 278.108839 -196.070027) (xy 278.056215 -196.036632) (xy 278.008193 -195.996904) (xy 277.965528 -195.95147)
			(xy 277.928894 -195.901048) (xy 277.898868 -195.846431) (xy 277.875925 -195.788483) (xy 277.860425 -195.728115)
			(xy 277.852613 -195.666281) (xy 277.852124 -195.635118) (xy 277.852646 -195.602397) (xy 277.861247 -195.537523)
			(xy 277.878301 -195.474343) (xy 277.903512 -195.413953) (xy 277.936444 -195.357401) (xy 277.976524 -195.305669)
			(xy 277.999444 -195.282312) (xy 278.00681 -195.2752) (xy 278.014684 -195.256404) (xy 278.014684 -195.163694)
			(xy 278.00681 -195.144898) (xy 277.999444 -195.137786) (xy 277.976539 -195.114412) (xy 277.936447 -195.062689)
			(xy 277.903504 -195.006143) (xy 277.878283 -194.945755) (xy 277.861223 -194.882576) (xy 277.85262 -194.817701)
			(xy 277.852124 -194.78498) (xy 277.852634 -194.752879) (xy 277.860929 -194.689216) (xy 277.877377 -194.627158)
			(xy 277.901704 -194.567744) (xy 277.933501 -194.511969) (xy 277.972236 -194.46077) (xy 277.994364 -194.437508)
			(xy 278.001476 -194.430142) (xy 278.008842 -194.411346) (xy 278.007572 -194.318636) (xy 277.999444 -194.300094)
			(xy 277.992078 -194.292982) (xy 277.968391 -194.269522) (xy 277.926885 -194.217352) (xy 277.892744 -194.16009)
			(xy 277.866585 -194.098769) (xy 277.848879 -194.034496) (xy 277.839946 -193.96843) (xy 277.839424 -193.935096)
			(xy 277.839932 -193.902633) (xy 277.848407 -193.838263) (xy 277.865212 -193.77555) (xy 277.89006 -193.715567)
			(xy 277.922524 -193.659341) (xy 277.96205 -193.607834) (xy 278.007961 -193.561926) (xy 278.059471 -193.522404)
			(xy 278.1157 -193.489944) (xy 278.175684 -193.465101) (xy 278.238399 -193.4483) (xy 278.302769 -193.43983)
			(xy 278.335232 -193.439288) (xy 278.367232 -193.439776) (xy 278.430704 -193.447984) (xy 278.492594 -193.464283)
			(xy 278.52243 -193.475864) (xy 278.5364 -193.481706) (xy 278.564848 -193.476372) (xy 278.65451 -193.393568)
			(xy 278.66213 -193.365374) (xy 278.657558 -193.35115) (xy 278.645061 -193.310269) (xy 278.627126 -193.22668)
			(xy 278.621744 -193.184272) (xy 278.620474 -193.173604) (xy 278.61006 -193.155316) (xy 278.53259 -193.09842)
			(xy 278.51227 -193.093848) (xy 278.501602 -193.09588) (xy 278.460414 -193.103339) (xy 278.377087 -193.111354)
			(xy 278.335232 -193.111882) (xy 278.292182 -193.111372) (xy 278.206496 -193.102936) (xy 278.122049 -193.086141)
			(xy 278.039655 -193.061149) (xy 277.960108 -193.028201) (xy 277.884174 -192.987615) (xy 277.812583 -192.939781)
			(xy 277.746026 -192.88516) (xy 277.685144 -192.824278) (xy 277.630522 -192.757721) (xy 277.582688 -192.686131)
			(xy 277.542101 -192.610197) (xy 277.509153 -192.53065) (xy 277.484161 -192.448257) (xy 277.467365 -192.36381)
			(xy 277.458928 -192.278124) (xy 277.458424 -192.235074) (xy 277.458645 -192.206544) (xy 277.462328 -192.149602)
			(xy 277.46579 -192.121282) (xy 277.467314 -192.11036) (xy 277.460964 -192.089532) (xy 277.403306 -192.023746)
			(xy 277.395773 -192.015941) (xy 277.37604 -192.00698) (xy 277.365206 -192.006474) (xy 276.493732 -192.006474)
			(xy 276.482203 -192.00703) (xy 276.461451 -192.017086) (xy 276.453854 -192.025778) (xy 276.397212 -192.09766)
			(xy 276.392386 -192.12052) (xy 276.39518 -192.13195) (xy 276.399943 -192.153221) (xy 276.405041 -192.196514)
			(xy 276.40534 -192.21831) (xy 276.404824 -192.24591) (xy 276.396597 -192.300493) (xy 276.380327 -192.35324)
			(xy 276.356377 -192.402973) (xy 276.325282 -192.44858) (xy 276.287737 -192.489044) (xy 276.24458 -192.523461)
			(xy 276.196776 -192.55106) (xy 276.145392 -192.571227) (xy 276.091577 -192.58351) (xy 276.036532 -192.587635)
			(xy 275.981487 -192.58351) (xy 275.927672 -192.571227) (xy 275.876288 -192.55106) (xy 275.828484 -192.523461)
			(xy 275.785327 -192.489044) (xy 275.747782 -192.44858) (xy 275.716687 -192.402973) (xy 275.692737 -192.35324)
			(xy 275.676467 -192.300493) (xy 275.66824 -192.24591) (xy 275.667724 -192.21831) (xy 275.668 -192.196512)
			(xy 275.673096 -192.153217) (xy 275.677884 -192.13195) (xy 275.680678 -192.12052) (xy 275.675852 -192.09766)
			(xy 275.61921 -192.025778) (xy 275.611632 -192.017065) (xy 275.590867 -192.007018) (xy 275.579332 -192.006474)
			(xy 274.705064 -192.006474) (xy 274.693531 -192.007023) (xy 274.672769 -192.017072) (xy 274.665186 -192.025778)
			(xy 274.608544 -192.09766) (xy 274.603718 -192.12052) (xy 274.606512 -192.13195) (xy 274.611276 -192.153221)
			(xy 274.616375 -192.196514) (xy 274.616672 -192.21831) (xy 274.616156 -192.24591) (xy 274.607929 -192.300493)
			(xy 274.591659 -192.35324) (xy 274.567709 -192.402973) (xy 274.536614 -192.44858) (xy 274.499069 -192.489044)
			(xy 274.455912 -192.523461) (xy 274.408108 -192.55106) (xy 274.356724 -192.571227) (xy 274.302909 -192.58351)
			(xy 274.247864 -192.587635) (xy 274.192819 -192.58351) (xy 274.139004 -192.571227) (xy 274.08762 -192.55106)
			(xy 274.039816 -192.523461) (xy 273.996659 -192.489044) (xy 273.959114 -192.44858) (xy 273.928019 -192.402973)
			(xy 273.904069 -192.35324) (xy 273.887799 -192.300493) (xy 273.879572 -192.24591) (xy 273.879056 -192.21831)
			(xy 273.879332 -192.196512) (xy 273.884427 -192.153217) (xy 273.889216 -192.13195) (xy 273.89201 -192.12052)
			(xy 273.887184 -192.09766) (xy 273.830542 -192.025778) (xy 273.822966 -192.01706) (xy 273.802201 -192.006999)
			(xy 273.790664 -192.006474) (xy 272.91919 -192.006474) (xy 272.908348 -192.006967) (xy 272.888596 -192.015909)
			(xy 272.88109 -192.023746) (xy 272.823432 -192.089532) (xy 272.817082 -192.11036) (xy 272.818606 -192.121282)
			(xy 272.822073 -192.149602) (xy 272.825755 -192.206544) (xy 272.825972 -192.235074) (xy 272.825482 -192.2768)
			(xy 272.817531 -192.359874) (xy 272.801716 -192.441815) (xy 272.778182 -192.521881) (xy 272.747142 -192.599346)
			(xy 272.728436 -192.636648) (xy 272.723455 -192.647811) (xy 272.723462 -192.672217) (xy 272.728436 -192.683384)
			(xy 272.747115 -192.720697) (xy 272.778136 -192.798166) (xy 272.801662 -192.87823) (xy 272.817479 -192.960166)
			(xy 272.825445 -193.043234) (xy 272.825972 -193.084958) (xy 272.825457 -193.127344) (xy 272.817271 -193.211718)
			(xy 272.80098 -193.294909) (xy 272.776737 -193.37614) (xy 272.744768 -193.454652) (xy 272.705371 -193.529712)
			(xy 272.658915 -193.60062) (xy 272.605832 -193.666713) (xy 272.546619 -193.727376) (xy 272.481827 -193.782041)
			(xy 272.447258 -193.806572) (xy 272.439617 -193.812328) (xy 272.428944 -193.828188) (xy 272.424818 -193.846853)
			(xy 272.425922 -193.856356) (xy 272.428876 -193.875907) (xy 272.432057 -193.915324) (xy 272.432272 -193.935096)
			(xy 272.431782 -193.96693) (xy 272.427991 -193.996305) (xy 273.751565 -193.996305) (xy 273.755411 -193.93463)
			(xy 273.766891 -193.87391) (xy 273.785828 -193.815088) (xy 273.811926 -193.759075) (xy 273.844783 -193.706739)
			(xy 273.883889 -193.658891) (xy 273.928637 -193.616274) (xy 273.978334 -193.579547) (xy 274.00504 -193.564002)
			(xy 274.016216 -193.557906) (xy 274.029678 -193.53657) (xy 274.038314 -193.427096) (xy 274.028408 -193.403982)
			(xy 274.018248 -193.396108) (xy 273.996921 -193.378497) (xy 273.959257 -193.337998) (xy 273.928067 -193.292325)
			(xy 273.904052 -193.242505) (xy 273.88775 -193.189656) (xy 273.879529 -193.134964) (xy 273.879056 -193.10731)
			(xy 273.879572 -193.07971) (xy 273.887799 -193.025127) (xy 273.904069 -192.97238) (xy 273.928019 -192.922648)
			(xy 273.959114 -192.87704) (xy 273.996659 -192.836576) (xy 274.039816 -192.802159) (xy 274.08762 -192.77456)
			(xy 274.139004 -192.754393) (xy 274.192819 -192.74211) (xy 274.247864 -192.737985) (xy 274.302909 -192.74211)
			(xy 274.356724 -192.754393) (xy 274.408108 -192.77456) (xy 274.455912 -192.802159) (xy 274.499069 -192.836576)
			(xy 274.536614 -192.87704) (xy 274.567709 -192.922648) (xy 274.591659 -192.97238) (xy 274.607929 -193.025127)
			(xy 274.616156 -193.07971) (xy 274.616672 -193.10731) (xy 274.6162 -193.134962) (xy 274.60796 -193.189649)
			(xy 274.59165 -193.242494) (xy 274.567636 -193.292313) (xy 274.536457 -193.33799) (xy 274.498809 -193.378502)
			(xy 274.47748 -193.396108) (xy 274.46732 -193.403982) (xy 274.457414 -193.427096) (xy 274.46605 -193.53657)
			(xy 274.479512 -193.557906) (xy 274.490688 -193.564002) (xy 274.517407 -193.57953) (xy 274.567112 -193.616254)
			(xy 274.611868 -193.658871) (xy 274.650981 -193.706719) (xy 274.683844 -193.759058) (xy 274.709948 -193.815074)
			(xy 274.728888 -193.8739) (xy 274.74037 -193.934625) (xy 274.744217 -193.996305) (xy 274.740369 -194.057985)
			(xy 274.728885 -194.118709) (xy 274.709944 -194.177535) (xy 274.683839 -194.233551) (xy 274.650975 -194.285889)
			(xy 274.611861 -194.333736) (xy 274.567105 -194.376352) (xy 274.517399 -194.413075) (xy 274.490688 -194.428618)
			(xy 274.479512 -194.434714) (xy 274.46605 -194.45605) (xy 274.457414 -194.565524) (xy 274.46732 -194.588638)
			(xy 274.47748 -194.596512) (xy 274.498822 -194.614105) (xy 274.536484 -194.654609) (xy 274.567672 -194.700285)
			(xy 274.591684 -194.750109) (xy 274.607982 -194.802961) (xy 274.6162 -194.857655) (xy 274.616672 -194.88531)
			(xy 274.616156 -194.91291) (xy 274.607929 -194.967493) (xy 274.591659 -195.02024) (xy 274.567709 -195.069973)
			(xy 274.536614 -195.11558) (xy 274.499069 -195.156044) (xy 274.455912 -195.190461) (xy 274.408108 -195.21806)
			(xy 274.356724 -195.238227) (xy 274.302909 -195.25051) (xy 274.247864 -195.254635) (xy 274.192819 -195.25051)
			(xy 274.139004 -195.238227) (xy 274.08762 -195.21806) (xy 274.039816 -195.190461) (xy 273.996659 -195.156044)
			(xy 273.959114 -195.11558) (xy 273.928019 -195.069973) (xy 273.904069 -195.02024) (xy 273.887799 -194.967493)
			(xy 273.879572 -194.91291) (xy 273.879056 -194.88531) (xy 273.879569 -194.85766) (xy 273.887804 -194.802976)
			(xy 273.904108 -194.750133) (xy 273.928114 -194.700314) (xy 273.959285 -194.654636) (xy 273.996924 -194.61412)
			(xy 274.018248 -194.596512) (xy 274.028408 -194.588638) (xy 274.038314 -194.565524) (xy 274.029678 -194.45605)
			(xy 274.016216 -194.434714) (xy 274.00504 -194.428618) (xy 273.978342 -194.413058) (xy 273.928644 -194.376332)
			(xy 273.883895 -194.333716) (xy 273.844789 -194.285869) (xy 273.811931 -194.233534) (xy 273.785831 -194.177521)
			(xy 273.766894 -194.118699) (xy 273.755412 -194.05798) (xy 273.751565 -193.996305) (xy 272.427991 -193.996305)
			(xy 272.423632 -194.030074) (xy 272.407465 -194.091655) (xy 272.383547 -194.15066) (xy 272.352273 -194.206118)
			(xy 272.314156 -194.257115) (xy 272.292318 -194.280282) (xy 272.285206 -194.287648) (xy 272.27784 -194.305936)
			(xy 272.278856 -194.397884) (xy 272.28673 -194.416172) (xy 272.293842 -194.423284) (xy 272.317327 -194.447246)
			(xy 272.358437 -194.500272) (xy 272.392219 -194.558242) (xy 272.418086 -194.62015) (xy 272.43559 -194.684922)
			(xy 272.444427 -194.751433) (xy 272.444972 -194.78498) (xy 272.44447 -194.816941) (xy 272.436459 -194.880359)
			(xy 272.420562 -194.942273) (xy 272.39703 -195.001706) (xy 272.366236 -195.057721) (xy 272.328663 -195.109436)
			(xy 272.284906 -195.156033) (xy 272.235653 -195.196778) (xy 272.181682 -195.231029) (xy 272.123843 -195.258246)
			(xy 272.06305 -195.277999) (xy 272.00026 -195.289977) (xy 271.936464 -195.293991) (xy 271.872668 -195.289977)
			(xy 271.809878 -195.277999) (xy 271.749085 -195.258246) (xy 271.691246 -195.231029) (xy 271.637275 -195.196778)
			(xy 271.588022 -195.156033) (xy 271.544265 -195.109436) (xy 271.506692 -195.057721) (xy 271.475898 -195.001706)
			(xy 271.452366 -194.942273) (xy 271.436469 -194.880359) (xy 271.428458 -194.816941) (xy 271.427956 -194.78498)
			(xy 271.428489 -194.75143) (xy 271.437308 -194.684913) (xy 271.454803 -194.620135) (xy 271.48067 -194.558222)
			(xy 271.514459 -194.500251) (xy 271.555582 -194.44723) (xy 271.579086 -194.423284) (xy 271.586198 -194.416172)
			(xy 271.594072 -194.397884) (xy 271.595088 -194.305936) (xy 271.587722 -194.287648) (xy 271.58061 -194.280282)
			(xy 271.558786 -194.2571) (xy 271.52065 -194.206115) (xy 271.489361 -194.150663) (xy 271.465436 -194.09166)
			(xy 271.449267 -194.030078) (xy 271.441123 -193.966931) (xy 271.440656 -193.935096) (xy 271.440944 -193.911647)
			(xy 271.4454 -193.86496) (xy 271.449546 -193.841878) (xy 271.450975 -193.832389) (xy 271.447452 -193.81354)
			(xy 271.437239 -193.797311) (xy 271.429734 -193.791332) (xy 271.406791 -193.774184) (xy 271.362943 -193.737323)
			(xy 271.342104 -193.717672) (xy 271.334767 -193.711292) (xy 271.31672 -193.704103) (xy 271.297294 -193.704139)
			(xy 271.279273 -193.711395) (xy 271.265242 -193.72483) (xy 271.257212 -193.742519) (xy 271.256333 -193.761925)
			(xy 271.259046 -193.771266) (xy 271.267907 -193.79766) (xy 271.280337 -193.851933) (xy 271.286609 -193.907257)
			(xy 271.286986 -193.935096) (xy 271.286478 -193.967197) (xy 271.278186 -194.030862) (xy 271.26174 -194.092923)
			(xy 271.237415 -194.152339) (xy 271.20562 -194.208116) (xy 271.166887 -194.259319) (xy 271.144746 -194.282568)
			(xy 271.137634 -194.289934) (xy 271.130268 -194.30873) (xy 271.131538 -194.40144) (xy 271.139666 -194.419982)
			(xy 271.147032 -194.427094) (xy 271.170714 -194.450555) (xy 271.212212 -194.502728) (xy 271.246343 -194.559992)
			(xy 271.272492 -194.621313) (xy 271.290188 -194.685585) (xy 271.29911 -194.751648) (xy 271.299686 -194.78498)
			(xy 271.299164 -194.817701) (xy 271.290564 -194.882575) (xy 271.27351 -194.945756) (xy 271.248299 -195.006146)
			(xy 271.215368 -195.062699) (xy 271.175289 -195.114431) (xy 271.152366 -195.137786) (xy 271.145 -195.144898)
			(xy 271.137126 -195.163694) (xy 271.137126 -195.256404) (xy 271.145 -195.2752) (xy 271.152366 -195.282312)
			(xy 271.17527 -195.305686) (xy 271.215363 -195.357409) (xy 271.248305 -195.413956) (xy 271.273525 -195.474343)
			(xy 271.290585 -195.537523) (xy 271.299188 -195.602397) (xy 271.299686 -195.635118) (xy 271.299197 -195.666281)
			(xy 271.291385 -195.728115) (xy 271.275885 -195.788483) (xy 271.252942 -195.846431) (xy 271.245952 -195.859146)
			(xy 275.528024 -195.859146) (xy 275.52859 -195.825988) (xy 275.5372 -195.760234) (xy 275.554282 -195.696156)
			(xy 275.579545 -195.634841) (xy 275.612561 -195.577328) (xy 275.652769 -195.524593) (xy 275.69949 -195.47753)
			(xy 275.725382 -195.45681) (xy 275.734295 -195.449262) (xy 275.744624 -195.428344) (xy 275.745194 -195.416678)
			(xy 275.745194 -195.336414) (xy 275.744547 -195.324767) (xy 275.734242 -195.303868) (xy 275.725382 -195.296282)
			(xy 275.699511 -195.275535) (xy 275.652786 -195.228477) (xy 275.612571 -195.175748) (xy 275.579547 -195.11824)
			(xy 275.554275 -195.05693) (xy 275.537183 -194.992855) (xy 275.528561 -194.927103) (xy 275.528024 -194.893946)
			(xy 275.528618 -194.860173) (xy 275.537561 -194.793222) (xy 275.555285 -194.728043) (xy 275.581476 -194.665781)
			(xy 275.615674 -194.607532) (xy 275.657278 -194.55432) (xy 275.705557 -194.50708) (xy 275.759661 -194.466643)
			(xy 275.788882 -194.4497) (xy 275.800058 -194.443604) (xy 275.813774 -194.422522) (xy 275.823172 -194.313556)
			(xy 275.81352 -194.290188) (xy 275.803614 -194.282314) (xy 275.782764 -194.264706) (xy 275.745999 -194.224376)
			(xy 275.715576 -194.17907) (xy 275.692158 -194.129778) (xy 275.676256 -194.077573) (xy 275.668216 -194.023596)
			(xy 275.667724 -193.99631) (xy 275.66824 -193.96871) (xy 275.676467 -193.914127) (xy 275.692737 -193.86138)
			(xy 275.716687 -193.811648) (xy 275.747782 -193.76604) (xy 275.785327 -193.725576) (xy 275.828484 -193.691159)
			(xy 275.876288 -193.66356) (xy 275.927672 -193.643393) (xy 275.981487 -193.63111) (xy 276.036532 -193.626985)
			(xy 276.091577 -193.63111) (xy 276.145392 -193.643393) (xy 276.196776 -193.66356) (xy 276.24458 -193.691159)
			(xy 276.287737 -193.725576) (xy 276.325282 -193.76604) (xy 276.356377 -193.811648) (xy 276.380327 -193.86138)
			(xy 276.396597 -193.914127) (xy 276.404824 -193.96871) (xy 276.40534 -193.99631) (xy 276.404886 -194.023599)
			(xy 276.396853 -194.077581) (xy 276.38095 -194.12979) (xy 276.357523 -194.179084) (xy 276.327085 -194.224385)
			(xy 276.290302 -194.264704) (xy 276.26945 -194.282314) (xy 276.259544 -194.290188) (xy 276.249892 -194.313556)
			(xy 276.25929 -194.422522) (xy 276.273006 -194.443604) (xy 276.284182 -194.4497) (xy 276.313412 -194.466632)
			(xy 276.367532 -194.507059) (xy 276.415823 -194.554295) (xy 276.457437 -194.607506) (xy 276.491642 -194.665759)
			(xy 276.517835 -194.728026) (xy 276.535555 -194.793212) (xy 276.544491 -194.86017) (xy 276.54504 -194.893946)
			(xy 276.544483 -194.927104) (xy 276.535872 -194.992859) (xy 276.51879 -195.056938) (xy 276.493526 -195.118253)
			(xy 276.460509 -195.175766) (xy 276.420298 -195.228501) (xy 276.373576 -195.275563) (xy 276.347682 -195.296282)
			(xy 276.338766 -195.303827) (xy 276.32844 -195.324748) (xy 276.32787 -195.336414) (xy 276.32787 -195.416678)
			(xy 276.328499 -195.428328) (xy 276.338814 -195.449228) (xy 276.347682 -195.45681) (xy 276.373563 -195.477545)
			(xy 276.420285 -195.524606) (xy 276.460497 -195.577339) (xy 276.493519 -195.634848) (xy 276.518789 -195.69616)
			(xy 276.53588 -195.760236) (xy 276.544502 -195.825988) (xy 276.54504 -195.859146) (xy 276.544538 -195.891107)
			(xy 276.536527 -195.954525) (xy 276.52063 -196.016439) (xy 276.497098 -196.075872) (xy 276.466304 -196.131887)
			(xy 276.428731 -196.183602) (xy 276.384974 -196.230199) (xy 276.335721 -196.270944) (xy 276.28175 -196.305195)
			(xy 276.223911 -196.332412) (xy 276.163118 -196.352165) (xy 276.100328 -196.364143) (xy 276.036532 -196.368157)
			(xy 275.972736 -196.364143) (xy 275.909946 -196.352165) (xy 275.849153 -196.332412) (xy 275.791314 -196.305195)
			(xy 275.737343 -196.270944) (xy 275.68809 -196.230199) (xy 275.644333 -196.183602) (xy 275.60676 -196.131887)
			(xy 275.575966 -196.075872) (xy 275.552434 -196.016439) (xy 275.536537 -195.954525) (xy 275.528526 -195.891107)
			(xy 275.528024 -195.859146) (xy 271.245952 -195.859146) (xy 271.222916 -195.901048) (xy 271.186282 -195.95147)
			(xy 271.143617 -195.996904) (xy 271.095595 -196.036632) (xy 271.042971 -196.070027) (xy 270.986577 -196.096564)
			(xy 270.927302 -196.115824) (xy 270.866081 -196.127503) (xy 270.803878 -196.131416) (xy 270.741675 -196.127503)
			(xy 270.680454 -196.115824) (xy 270.621179 -196.096564) (xy 270.564785 -196.070027) (xy 270.512161 -196.036632)
			(xy 270.464139 -195.996904) (xy 270.421474 -195.95147) (xy 270.38484 -195.901048) (xy 270.354814 -195.846431)
			(xy 270.331871 -195.788483) (xy 270.316371 -195.728115) (xy 270.308559 -195.666281) (xy 270.30807 -195.635118)
			(xy 270.308593 -195.602398) (xy 270.317194 -195.537524) (xy 270.334249 -195.474345) (xy 270.359462 -195.413956)
			(xy 270.392396 -195.357407) (xy 270.432479 -195.305678) (xy 270.45539 -195.282312) (xy 270.462756 -195.2752)
			(xy 270.47063 -195.256404) (xy 270.47063 -195.163694) (xy 270.462756 -195.144898) (xy 270.45539 -195.137786)
			(xy 270.432488 -195.114411) (xy 270.392399 -195.062687) (xy 270.35946 -195.00614) (xy 270.334242 -194.945752)
			(xy 270.317184 -194.882574) (xy 270.308582 -194.817701) (xy 270.30807 -194.78498) (xy 270.30858 -194.752879)
			(xy 270.316874 -194.689215) (xy 270.333321 -194.627155) (xy 270.357646 -194.56774) (xy 270.389441 -194.511963)
			(xy 270.428173 -194.460761) (xy 270.45031 -194.437508) (xy 270.457422 -194.430142) (xy 270.464788 -194.411346)
			(xy 270.463518 -194.318636) (xy 270.45539 -194.300094) (xy 270.448024 -194.292982) (xy 270.424335 -194.269523)
			(xy 270.382826 -194.217354) (xy 270.348682 -194.160092) (xy 270.32252 -194.098771) (xy 270.304813 -194.034497)
			(xy 270.295879 -193.96843) (xy 270.29537 -193.935096) (xy 270.295901 -193.902633) (xy 270.304376 -193.838264)
			(xy 270.321179 -193.775551) (xy 270.346025 -193.715568) (xy 270.378487 -193.659341) (xy 270.41801 -193.607832)
			(xy 270.463918 -193.561922) (xy 270.515426 -193.522397) (xy 270.571652 -193.489933) (xy 270.631634 -193.465085)
			(xy 270.694346 -193.448279) (xy 270.758715 -193.439802) (xy 270.791178 -193.439288) (xy 270.823231 -193.439787)
			(xy 270.886803 -193.448045) (xy 270.948777 -193.464439) (xy 270.97863 -193.476118) (xy 270.992346 -193.481706)
			(xy 271.021302 -193.476372) (xy 271.11071 -193.393822) (xy 271.11833 -193.365374) (xy 271.113758 -193.35115)
			(xy 271.101261 -193.310269) (xy 271.083326 -193.22668) (xy 271.077944 -193.184272) (xy 271.076674 -193.17335)
			(xy 271.06626 -193.155316) (xy 270.98879 -193.09842) (xy 270.968216 -193.093848) (xy 270.957802 -193.09588)
			(xy 270.916553 -193.103365) (xy 270.833098 -193.111382) (xy 270.791178 -193.111882) (xy 270.748129 -193.11137)
			(xy 270.662447 -193.102928) (xy 270.578005 -193.08613) (xy 270.495616 -193.061135) (xy 270.416073 -193.028185)
			(xy 270.340143 -192.987597) (xy 270.268558 -192.939762) (xy 270.202005 -192.885141) (xy 270.141127 -192.824259)
			(xy 270.086509 -192.757704) (xy 270.038678 -192.686115) (xy 269.998095 -192.610183) (xy 269.965149 -192.530639)
			(xy 269.940159 -192.448249) (xy 269.923364 -192.363805) (xy 269.914928 -192.278123) (xy 269.91437 -192.235074)
			(xy 269.914591 -192.206544) (xy 269.918274 -192.149602) (xy 269.921736 -192.121282) (xy 269.92326 -192.11036)
			(xy 269.91691 -192.089532) (xy 269.859252 -192.023746) (xy 269.851716 -192.01595) (xy 269.831983 -192.007009)
			(xy 269.821152 -192.006474) (xy 268.949678 -192.006474) (xy 268.938144 -192.00702) (xy 268.917377 -192.017065)
			(xy 268.9098 -192.025778) (xy 268.853158 -192.09766) (xy 268.848332 -192.12052) (xy 268.851126 -192.13195)
			(xy 268.85589 -192.153221) (xy 268.860989 -192.196514) (xy 268.861286 -192.21831) (xy 268.86077 -192.24591)
			(xy 268.852543 -192.300493) (xy 268.836273 -192.35324) (xy 268.812323 -192.402973) (xy 268.781228 -192.44858)
			(xy 268.743683 -192.489044) (xy 268.700526 -192.523461) (xy 268.652722 -192.55106) (xy 268.601338 -192.571227)
			(xy 268.547523 -192.58351) (xy 268.492478 -192.587635) (xy 268.437433 -192.58351) (xy 268.383618 -192.571227)
			(xy 268.332234 -192.55106) (xy 268.28443 -192.523461) (xy 268.241273 -192.489044) (xy 268.203728 -192.44858)
			(xy 268.172633 -192.402973) (xy 268.148683 -192.35324) (xy 268.132413 -192.300493) (xy 268.124186 -192.24591)
			(xy 268.12367 -192.21831) (xy 268.123946 -192.196512) (xy 268.129041 -192.153217) (xy 268.13383 -192.13195)
			(xy 268.136624 -192.12052) (xy 268.131798 -192.09766) (xy 268.075156 -192.025778) (xy 268.067581 -192.017057)
			(xy 268.046816 -192.006992) (xy 268.035278 -192.006474) (xy 267.16101 -192.006474) (xy 267.149473 -192.007014)
			(xy 267.128695 -192.017051) (xy 267.121132 -192.025778) (xy 267.06449 -192.09766) (xy 267.059664 -192.12052)
			(xy 267.062458 -192.13195) (xy 267.067222 -192.153221) (xy 267.07232 -192.196514) (xy 267.072618 -192.21831)
			(xy 267.072102 -192.24591) (xy 267.063875 -192.300493) (xy 267.047605 -192.35324) (xy 267.023655 -192.402973)
			(xy 266.99256 -192.44858) (xy 266.955015 -192.489044) (xy 266.911858 -192.523461) (xy 266.864054 -192.55106)
			(xy 266.81267 -192.571227) (xy 266.758855 -192.58351) (xy 266.70381 -192.587635) (xy 266.648765 -192.58351)
			(xy 266.59495 -192.571227) (xy 266.543566 -192.55106) (xy 266.495762 -192.523461) (xy 266.452605 -192.489044)
			(xy 266.41506 -192.44858) (xy 266.383965 -192.402973) (xy 266.360015 -192.35324) (xy 266.343745 -192.300493)
			(xy 266.335518 -192.24591) (xy 266.335002 -192.21831) (xy 266.335278 -192.196512) (xy 266.340374 -192.153217)
			(xy 266.345162 -192.13195) (xy 266.347956 -192.12052) (xy 266.34313 -192.09766) (xy 266.286488 -192.025778)
			(xy 266.278909 -192.017069) (xy 266.258143 -192.007031) (xy 266.24661 -192.006474) (xy 265.375136 -192.006474)
			(xy 265.364299 -192.006977) (xy 265.344564 -192.015933) (xy 265.337036 -192.023746) (xy 265.279378 -192.089532)
			(xy 265.273028 -192.11036) (xy 265.274552 -192.121282) (xy 265.278019 -192.149602) (xy 265.281701 -192.206544)
			(xy 265.281918 -192.235074) (xy 265.281428 -192.276801) (xy 265.273477 -192.359874) (xy 265.257663 -192.441815)
			(xy 265.23413 -192.521882) (xy 265.203091 -192.599348) (xy 265.184382 -192.636648) (xy 265.179405 -192.647812)
			(xy 265.179412 -192.672217) (xy 265.184382 -192.683384) (xy 265.20306 -192.720697) (xy 265.23408 -192.798166)
			(xy 265.257604 -192.87823) (xy 265.27342 -192.960166) (xy 265.281385 -193.043234) (xy 265.281918 -193.084958)
			(xy 265.281403 -193.127344) (xy 265.273217 -193.211719) (xy 265.256927 -193.294911) (xy 265.232685 -193.376143)
			(xy 265.200717 -193.454656) (xy 265.161321 -193.529717) (xy 265.114866 -193.600627) (xy 265.061785 -193.666723)
			(xy 265.002573 -193.727388) (xy 264.937784 -193.782055) (xy 264.903204 -193.806572) (xy 264.895569 -193.812331)
			(xy 264.884908 -193.828192) (xy 264.880787 -193.846853) (xy 264.881868 -193.856356) (xy 264.884822 -193.875907)
			(xy 264.888003 -193.915324) (xy 264.888218 -193.935096) (xy 264.887728 -193.96693) (xy 264.883936 -193.996305)
			(xy 266.207487 -193.996305) (xy 266.211334 -193.934628) (xy 266.222815 -193.873907) (xy 266.241754 -193.815083)
			(xy 266.267855 -193.759069) (xy 266.300715 -193.706733) (xy 266.339825 -193.658886) (xy 266.384577 -193.61627)
			(xy 266.434278 -193.579546) (xy 266.460986 -193.564002) (xy 266.472162 -193.557906) (xy 266.485624 -193.53657)
			(xy 266.49426 -193.427096) (xy 266.484354 -193.403982) (xy 266.474194 -193.396108) (xy 266.452877 -193.378485)
			(xy 266.41521 -193.33799) (xy 266.384018 -193.29232) (xy 266.36 -193.242502) (xy 266.343698 -193.189654)
			(xy 266.335476 -193.134963) (xy 266.335002 -193.10731) (xy 266.335518 -193.07971) (xy 266.343745 -193.025127)
			(xy 266.360015 -192.97238) (xy 266.383965 -192.922648) (xy 266.41506 -192.87704) (xy 266.452605 -192.836576)
			(xy 266.495762 -192.802159) (xy 266.543566 -192.77456) (xy 266.59495 -192.754393) (xy 266.648765 -192.74211)
			(xy 266.70381 -192.737985) (xy 266.758855 -192.74211) (xy 266.81267 -192.754393) (xy 266.864054 -192.77456)
			(xy 266.911858 -192.802159) (xy 266.955015 -192.836576) (xy 266.99256 -192.87704) (xy 267.023655 -192.922648)
			(xy 267.047605 -192.97238) (xy 267.063875 -193.025127) (xy 267.072102 -193.07971) (xy 267.072618 -193.10731)
			(xy 267.072129 -193.134961) (xy 267.06389 -193.189647) (xy 267.047582 -193.242491) (xy 267.023572 -193.292309)
			(xy 266.992396 -193.337987) (xy 266.954753 -193.378501) (xy 266.933426 -193.396108) (xy 266.923266 -193.403982)
			(xy 266.91336 -193.427096) (xy 266.921996 -193.53657) (xy 266.935458 -193.557906) (xy 266.946634 -193.564002)
			(xy 266.973351 -193.579532) (xy 267.023052 -193.616258) (xy 267.067804 -193.658876) (xy 267.106913 -193.706725)
			(xy 267.139773 -193.759063) (xy 267.165874 -193.815079) (xy 267.184812 -193.873904) (xy 267.196293 -193.934626)
			(xy 267.20014 -193.996305) (xy 267.196292 -194.057983) (xy 267.18481 -194.118706) (xy 267.16587 -194.17753)
			(xy 267.139768 -194.233545) (xy 267.106907 -194.285883) (xy 267.067797 -194.333731) (xy 267.023044 -194.376348)
			(xy 266.973343 -194.413074) (xy 266.946634 -194.428618) (xy 266.935458 -194.434714) (xy 266.921996 -194.45605)
			(xy 266.91336 -194.565524) (xy 266.923266 -194.588638) (xy 266.933426 -194.596512) (xy 266.954756 -194.614119)
			(xy 266.992422 -194.654618) (xy 267.023612 -194.700291) (xy 267.047627 -194.750112) (xy 267.063927 -194.802963)
			(xy 267.072146 -194.857656) (xy 267.072618 -194.88531) (xy 267.072102 -194.91291) (xy 267.063875 -194.967493)
			(xy 267.047605 -195.02024) (xy 267.023655 -195.069973) (xy 266.99256 -195.11558) (xy 266.955015 -195.156044)
			(xy 266.911858 -195.190461) (xy 266.864054 -195.21806) (xy 266.81267 -195.238227) (xy 266.758855 -195.25051)
			(xy 266.70381 -195.254635) (xy 266.648765 -195.25051) (xy 266.59495 -195.238227) (xy 266.543566 -195.21806)
			(xy 266.495762 -195.190461) (xy 266.452605 -195.156044) (xy 266.41506 -195.11558) (xy 266.383965 -195.069973)
			(xy 266.360015 -195.02024) (xy 266.343745 -194.967493) (xy 266.335518 -194.91291) (xy 266.335002 -194.88531)
			(xy 266.335498 -194.857659) (xy 266.343734 -194.802973) (xy 266.36004 -194.750129) (xy 266.384049 -194.700311)
			(xy 266.415224 -194.654633) (xy 266.452867 -194.614119) (xy 266.474194 -194.596512) (xy 266.484354 -194.588638)
			(xy 266.49426 -194.565524) (xy 266.485624 -194.45605) (xy 266.472162 -194.434714) (xy 266.460986 -194.428618)
			(xy 266.434286 -194.41306) (xy 266.384584 -194.376336) (xy 266.339831 -194.333721) (xy 266.300721 -194.285875)
			(xy 266.26786 -194.233539) (xy 266.241757 -194.177526) (xy 266.222818 -194.118703) (xy 266.211335 -194.057982)
			(xy 266.207487 -193.996305) (xy 264.883936 -193.996305) (xy 264.879577 -194.030073) (xy 264.863409 -194.091653)
			(xy 264.839489 -194.150657) (xy 264.808212 -194.206112) (xy 264.770093 -194.257106) (xy 264.748264 -194.280282)
			(xy 264.741152 -194.287648) (xy 264.733786 -194.305936) (xy 264.734802 -194.397884) (xy 264.742676 -194.416172)
			(xy 264.749788 -194.423284) (xy 264.773271 -194.447247) (xy 264.814378 -194.500274) (xy 264.848157 -194.558245)
			(xy 264.874022 -194.620153) (xy 264.891524 -194.684924) (xy 264.90036 -194.751433) (xy 264.900918 -194.78498)
			(xy 264.900416 -194.816941) (xy 264.892405 -194.880359) (xy 264.876508 -194.942273) (xy 264.852976 -195.001706)
			(xy 264.822182 -195.057721) (xy 264.784609 -195.109436) (xy 264.740852 -195.156033) (xy 264.691599 -195.196778)
			(xy 264.637628 -195.231029) (xy 264.579789 -195.258246) (xy 264.518996 -195.277999) (xy 264.456206 -195.289977)
			(xy 264.39241 -195.293991) (xy 264.328614 -195.289977) (xy 264.265824 -195.277999) (xy 264.205031 -195.258246)
			(xy 264.147192 -195.231029) (xy 264.093221 -195.196778) (xy 264.043968 -195.156033) (xy 264.000211 -195.109436)
			(xy 263.962638 -195.057721) (xy 263.931844 -195.001706) (xy 263.908312 -194.942273) (xy 263.892415 -194.880359)
			(xy 263.884404 -194.816941) (xy 263.883902 -194.78498) (xy 263.884435 -194.75143) (xy 263.893253 -194.684912)
			(xy 263.910747 -194.620132) (xy 263.936612 -194.558218) (xy 263.970398 -194.500245) (xy 264.011518 -194.447221)
			(xy 264.035032 -194.423284) (xy 264.042144 -194.416172) (xy 264.050018 -194.397884) (xy 264.051034 -194.305936)
			(xy 264.043668 -194.287648) (xy 264.036556 -194.280282) (xy 264.014734 -194.257099) (xy 263.976602 -194.206112)
			(xy 263.945317 -194.150661) (xy 263.921394 -194.091657) (xy 263.905227 -194.030076) (xy 263.897084 -193.96693)
			(xy 263.896602 -193.935096) (xy 263.89689 -193.911647) (xy 263.901345 -193.86496) (xy 263.905492 -193.841878)
			(xy 263.90692 -193.832388) (xy 263.9034 -193.813537) (xy 263.893193 -193.797302) (xy 263.88568 -193.791332)
			(xy 263.852875 -193.766611) (xy 263.791538 -193.711966) (xy 263.735581 -193.651825) (xy 263.685493 -193.586713)
			(xy 263.641715 -193.517202) (xy 263.60463 -193.443901) (xy 263.574563 -193.367454) (xy 263.551778 -193.288529)
			(xy 263.536474 -193.207819) (xy 263.528786 -193.126032) (xy 263.528302 -193.084958) (xy 263.52879 -193.043231)
			(xy 263.536739 -192.960157) (xy 263.55255 -192.878214) (xy 263.576081 -192.798147) (xy 263.607118 -192.720679)
			(xy 263.625838 -192.683384) (xy 263.630821 -192.67222) (xy 263.630828 -192.647808) (xy 263.625838 -192.636648)
			(xy 263.607158 -192.599335) (xy 263.576135 -192.521867) (xy 263.552607 -192.441803) (xy 263.536788 -192.359866)
			(xy 263.528819 -192.276798) (xy 263.528302 -192.235074) (xy 263.528813 -192.192768) (xy 263.536958 -192.108547)
			(xy 263.544558 -192.066926) (xy 263.545574 -192.0621) (xy 263.545574 -192.057274) (xy 263.545081 -192.047272)
			(xy 263.537416 -192.028793) (xy 263.523263 -192.014655) (xy 263.504777 -192.007009) (xy 263.494774 -192.006474)
			(xy 263.434576 -192.006474) (xy 263.405366 -192.03416) (xy 263.40435 -192.05448) (xy 263.402079 -192.086523)
			(xy 263.390468 -192.149704) (xy 263.370992 -192.210919) (xy 263.343962 -192.269194) (xy 263.309808 -192.323601)
			(xy 263.269073 -192.373273) (xy 263.222407 -192.41742) (xy 263.170553 -192.455338) (xy 263.114336 -192.486423)
			(xy 263.054652 -192.510181) (xy 262.992451 -192.526233) (xy 262.928723 -192.534323) (xy 262.864485 -192.534323)
			(xy 262.800757 -192.526233) (xy 262.738556 -192.510181) (xy 262.678872 -192.486423) (xy 262.622655 -192.455338)
			(xy 262.570801 -192.41742) (xy 262.524135 -192.373273) (xy 262.4834 -192.323601) (xy 262.449246 -192.269194)
			(xy 262.422216 -192.210919) (xy 262.40274 -192.149704) (xy 262.391129 -192.086523) (xy 262.388858 -192.05448)
			(xy 262.387842 -192.03416) (xy 262.358632 -192.006474) (xy 260.956044 -192.006474) (xy 260.945978 -192.006907)
			(xy 260.927386 -192.014632) (xy 260.919976 -192.02146) (xy 260.673596 -192.26784) (xy 260.666113 -192.276189)
			(xy 260.658596 -192.297281) (xy 260.659118 -192.30848) (xy 260.6675 -192.398142) (xy 260.679184 -192.417446)
			(xy 260.688582 -192.423796) (xy 260.710403 -192.439083) (xy 260.749988 -192.474741) (xy 260.784228 -192.51556)
			(xy 260.812458 -192.560744) (xy 260.834127 -192.609416) (xy 260.848815 -192.660629) (xy 260.856237 -192.713387)
			(xy 260.85673 -192.740026) (xy 260.856115 -192.770718) (xy 260.846288 -192.831311) (xy 260.826891 -192.88955)
			(xy 260.798423 -192.943935) (xy 260.78053 -192.96888) (xy 260.774434 -192.977008) (xy 260.769354 -192.99555)
			(xy 260.780276 -193.085212) (xy 260.789674 -193.10223) (xy 260.797294 -193.10858) (xy 260.821872 -193.129314)
			(xy 260.866118 -193.175973) (xy 260.904124 -193.227842) (xy 260.935281 -193.284092) (xy 260.959091 -193.343825)
			(xy 260.975174 -193.406084) (xy 260.983272 -193.469874) (xy 260.98373 -193.502026) (xy 260.983149 -193.536981)
			(xy 260.973577 -193.606231) (xy 260.954616 -193.67352) (xy 260.926624 -193.737581) (xy 260.890126 -193.797206)
			(xy 260.868414 -193.824606) (xy 260.863181 -193.831625) (xy 260.857335 -193.848116) (xy 260.856984 -193.856864)
			(xy 260.856984 -194.137788) (xy 260.857305 -194.146541) (xy 260.863164 -194.163033) (xy 260.868414 -194.170046)
			(xy 260.890127 -194.197445) (xy 260.926627 -194.257068) (xy 260.954617 -194.321129) (xy 260.973569 -194.388419)
			(xy 260.983127 -194.457672) (xy 260.98373 -194.492626) (xy 260.983236 -194.524776) (xy 260.975127 -194.588562)
			(xy 260.959042 -194.650816) (xy 260.935238 -194.710547) (xy 260.904093 -194.7668) (xy 260.866107 -194.818679)
			(xy 260.821883 -194.865355) (xy 260.797294 -194.886072) (xy 260.789674 -194.892422) (xy 260.780276 -194.90944)
			(xy 260.769354 -194.999102) (xy 260.774434 -195.017644) (xy 260.78053 -195.025772) (xy 260.798439 -195.050706)
			(xy 260.8269 -195.105095) (xy 260.84629 -195.163338) (xy 260.85611 -195.223933) (xy 260.85673 -195.254626)
			(xy 260.856244 -195.281877) (xy 260.848488 -195.335825) (xy 260.833133 -195.38812) (xy 260.810491 -195.437697)
			(xy 260.781025 -195.483547) (xy 260.745334 -195.524738) (xy 260.704143 -195.560429) (xy 260.658293 -195.589895)
			(xy 260.608716 -195.612537) (xy 260.556421 -195.627892) (xy 260.502473 -195.635648) (xy 260.447971 -195.635648)
			(xy 260.394023 -195.627892) (xy 260.341728 -195.612537) (xy 260.292151 -195.589895) (xy 260.246301 -195.560429)
			(xy 260.20511 -195.524738) (xy 260.169419 -195.483547) (xy 260.139953 -195.437697) (xy 260.117311 -195.38812)
			(xy 260.101956 -195.335825) (xy 260.0942 -195.281877) (xy 260.093714 -195.254626) (xy 260.094325 -195.223932)
			(xy 260.104143 -195.163335) (xy 260.123532 -195.105089) (xy 260.151991 -195.050696) (xy 260.169914 -195.025772)
			(xy 260.17601 -195.017644) (xy 260.18109 -194.999102) (xy 260.170168 -194.90944) (xy 260.16077 -194.892422)
			(xy 260.15315 -194.886072) (xy 260.128577 -194.865336) (xy 260.084339 -194.818674) (xy 260.046342 -194.766802)
			(xy 260.015194 -194.710552) (xy 259.991393 -194.650821) (xy 259.975318 -194.588563) (xy 259.967227 -194.524776)
			(xy 259.966714 -194.492626) (xy 259.967298 -194.457673) (xy 259.976877 -194.388426) (xy 259.995844 -194.321141)
			(xy 260.023843 -194.257087) (xy 260.060346 -194.197467) (xy 260.08203 -194.170046) (xy 260.087261 -194.163027)
			(xy 260.093098 -194.146535) (xy 260.09346 -194.137788) (xy 260.09346 -193.856864) (xy 260.093149 -193.848107)
			(xy 260.087306 -193.831601) (xy 260.08203 -193.824606) (xy 260.060313 -193.797209) (xy 260.023803 -193.737587)
			(xy 259.995804 -193.673527) (xy 259.976843 -193.606236) (xy 259.967278 -193.536982) (xy 259.966714 -193.502026)
			(xy 259.967211 -193.469878) (xy 259.975326 -193.406096) (xy 259.991417 -193.343846) (xy 260.015226 -193.284121)
			(xy 260.046375 -193.227874) (xy 260.084366 -193.176002) (xy 260.128593 -193.129334) (xy 260.15315 -193.10858)
			(xy 260.16077 -193.10223) (xy 260.170168 -193.085212) (xy 260.18109 -192.99555) (xy 260.17601 -192.977008)
			(xy 260.169914 -192.96888) (xy 260.158992 -192.953386) (xy 260.152642 -192.943988) (xy 260.133338 -192.932304)
			(xy 260.043676 -192.923922) (xy 260.032483 -192.923441) (xy 260.011403 -192.93095) (xy 260.003036 -192.9384)
			(xy 256.493264 -196.448172) (xy 256.486422 -196.455571) (xy 256.478703 -196.47417) (xy 256.478278 -196.48424)
			(xy 256.478278 -196.489828) (xy 262.672322 -196.489828) (xy 262.672753 -196.463763) (xy 262.679871 -196.412121)
			(xy 262.693951 -196.361927) (xy 262.714732 -196.314118) (xy 262.741825 -196.269581) (xy 262.774728 -196.229146)
			(xy 262.812828 -196.193565) (xy 262.833866 -196.17817) (xy 262.842502 -196.172074) (xy 262.85317 -196.154548)
			(xy 262.866632 -196.06006) (xy 262.861298 -196.040248) (xy 262.854694 -196.031866) (xy 262.833823 -196.004756)
			(xy 262.798753 -195.94601) (xy 262.77188 -195.883091) (xy 262.753689 -195.817136) (xy 262.744509 -195.749337)
			(xy 262.74395 -195.715128) (xy 262.744452 -195.683167) (xy 262.752463 -195.619749) (xy 262.76836 -195.557835)
			(xy 262.791892 -195.498402) (xy 262.822686 -195.442387) (xy 262.860259 -195.390672) (xy 262.904016 -195.344075)
			(xy 262.953269 -195.30333) (xy 263.00724 -195.269079) (xy 263.065079 -195.241862) (xy 263.125872 -195.222109)
			(xy 263.188662 -195.210131) (xy 263.252458 -195.206118) (xy 263.316254 -195.210131) (xy 263.379044 -195.222109)
			(xy 263.439837 -195.241862) (xy 263.497676 -195.269079) (xy 263.551647 -195.30333) (xy 263.6009 -195.344075)
			(xy 263.644657 -195.390672) (xy 263.68223 -195.442387) (xy 263.713024 -195.498402) (xy 263.736556 -195.557835)
			(xy 263.752453 -195.619749) (xy 263.760464 -195.683167) (xy 263.760966 -195.715128) (xy 263.760427 -195.748321)
			(xy 263.751807 -195.814146) (xy 263.739801 -195.859146) (xy 267.98397 -195.859146) (xy 267.984518 -195.825987)
			(xy 267.99313 -195.760232) (xy 268.010213 -195.696153) (xy 268.035478 -195.634837) (xy 268.068497 -195.577325)
			(xy 268.108709 -195.52459) (xy 268.155434 -195.477528) (xy 268.181328 -195.45681) (xy 268.190249 -195.44927)
			(xy 268.200572 -195.428346) (xy 268.20114 -195.416678) (xy 268.20114 -195.336414) (xy 268.200511 -195.324764)
			(xy 268.190196 -195.303864) (xy 268.181328 -195.296282) (xy 268.155446 -195.275549) (xy 268.108723 -195.228488)
			(xy 268.06851 -195.175755) (xy 268.035489 -195.118245) (xy 268.010219 -195.056933) (xy 267.993129 -194.992857)
			(xy 267.984507 -194.927104) (xy 267.98397 -194.893946) (xy 267.98454 -194.860172) (xy 267.993485 -194.793219)
			(xy 268.01121 -194.728038) (xy 268.037403 -194.665775) (xy 268.071605 -194.607526) (xy 268.113213 -194.554314)
			(xy 268.161496 -194.507076) (xy 268.215605 -194.466641) (xy 268.244828 -194.4497) (xy 268.256004 -194.443604)
			(xy 268.26972 -194.422522) (xy 268.279118 -194.313556) (xy 268.269466 -194.290188) (xy 268.25956 -194.282314)
			(xy 268.238699 -194.264719) (xy 268.201937 -194.224384) (xy 268.171517 -194.179076) (xy 268.148101 -194.129781)
			(xy 268.132201 -194.077575) (xy 268.124162 -194.023597) (xy 268.12367 -193.99631) (xy 268.124186 -193.96871)
			(xy 268.132413 -193.914127) (xy 268.148683 -193.86138) (xy 268.172633 -193.811648) (xy 268.203728 -193.76604)
			(xy 268.241273 -193.725576) (xy 268.28443 -193.691159) (xy 268.332234 -193.66356) (xy 268.383618 -193.643393)
			(xy 268.437433 -193.63111) (xy 268.492478 -193.626985) (xy 268.547523 -193.63111) (xy 268.601338 -193.643393)
			(xy 268.652722 -193.66356) (xy 268.700526 -193.691159) (xy 268.743683 -193.725576) (xy 268.781228 -193.76604)
			(xy 268.812323 -193.811648) (xy 268.836273 -193.86138) (xy 268.852543 -193.914127) (xy 268.86077 -193.96871)
			(xy 268.861286 -193.99631) (xy 268.860815 -194.023598) (xy 268.852784 -194.077579) (xy 268.836882 -194.129787)
			(xy 268.813459 -194.17908) (xy 268.783025 -194.224382) (xy 268.746245 -194.264703) (xy 268.725396 -194.282314)
			(xy 268.71549 -194.290188) (xy 268.705838 -194.313556) (xy 268.715236 -194.422522) (xy 268.728952 -194.443604)
			(xy 268.740128 -194.4497) (xy 268.769369 -194.466614) (xy 268.823486 -194.507046) (xy 268.871776 -194.554285)
			(xy 268.913388 -194.607499) (xy 268.947591 -194.665754) (xy 268.973782 -194.728022) (xy 268.991502 -194.79321)
			(xy 269.000437 -194.860169) (xy 269.000986 -194.893946) (xy 269.000449 -194.927105) (xy 268.991837 -194.992862)
			(xy 268.974753 -195.056942) (xy 268.949487 -195.118258) (xy 268.916466 -195.17577) (xy 268.876251 -195.228504)
			(xy 268.829524 -195.275564) (xy 268.803628 -195.296282) (xy 268.794703 -195.303818) (xy 268.784384 -195.324746)
			(xy 268.783816 -195.336414) (xy 268.783816 -195.416678) (xy 268.784464 -195.428325) (xy 268.794768 -195.449224)
			(xy 268.803628 -195.45681) (xy 268.829497 -195.477559) (xy 268.876222 -195.524617) (xy 268.916437 -195.577346)
			(xy 268.949461 -195.634853) (xy 268.974733 -195.696163) (xy 268.991825 -195.760237) (xy 269.000448 -195.825989)
			(xy 269.000986 -195.859146) (xy 269.000484 -195.891107) (xy 268.992473 -195.954525) (xy 268.976576 -196.016439)
			(xy 268.953044 -196.075872) (xy 268.92225 -196.131887) (xy 268.884677 -196.183602) (xy 268.84092 -196.230199)
			(xy 268.791667 -196.270944) (xy 268.737696 -196.305195) (xy 268.679857 -196.332412) (xy 268.619064 -196.352165)
			(xy 268.556274 -196.364143) (xy 268.492478 -196.368157) (xy 268.428682 -196.364143) (xy 268.365892 -196.352165)
			(xy 268.305099 -196.332412) (xy 268.24726 -196.305195) (xy 268.193289 -196.270944) (xy 268.144036 -196.230199)
			(xy 268.100279 -196.183602) (xy 268.062706 -196.131887) (xy 268.031912 -196.075872) (xy 268.00838 -196.016439)
			(xy 267.992483 -195.954525) (xy 267.984472 -195.891107) (xy 267.98397 -195.859146) (xy 263.739801 -195.859146)
			(xy 263.734693 -195.878289) (xy 263.709374 -195.939657) (xy 263.676282 -195.997208) (xy 263.63598 -196.049962)
			(xy 263.589154 -196.09702) (xy 263.5366 -196.137582) (xy 263.479214 -196.170959) (xy 263.4488 -196.184266)
			(xy 263.438894 -196.18833) (xy 263.42467 -196.203062) (xy 263.390888 -196.29247) (xy 263.391904 -196.31279)
			(xy 263.39673 -196.322442) (xy 263.402862 -196.335421) (xy 263.413416 -196.362117) (xy 263.417812 -196.375782)
			(xy 263.421622 -196.387466) (xy 263.43864 -196.404992) (xy 263.54024 -196.43852) (xy 263.56437 -196.434964)
			(xy 263.574276 -196.427598) (xy 263.60036 -196.409333) (xy 263.656236 -196.37879) (xy 263.71549 -196.355463)
			(xy 263.777192 -196.33972) (xy 263.840378 -196.331807) (xy 263.872218 -196.331332) (xy 263.904181 -196.331755)
			(xy 263.967602 -196.339769) (xy 264.029519 -196.355669) (xy 264.088955 -196.379203) (xy 264.144973 -196.410001)
			(xy 264.196689 -196.447576) (xy 264.243288 -196.491337) (xy 264.284035 -196.540593) (xy 264.318287 -196.594568)
			(xy 264.345505 -196.65241) (xy 264.365258 -196.713207) (xy 264.377237 -196.776) (xy 264.381251 -196.8398)
			(xy 264.377237 -196.9036) (xy 264.365258 -196.966393) (xy 264.345505 -197.02719) (xy 264.318287 -197.085032)
			(xy 264.284035 -197.139007) (xy 264.243288 -197.188263) (xy 264.196689 -197.232024) (xy 264.144973 -197.269599)
			(xy 264.088955 -197.300397) (xy 264.029519 -197.323931) (xy 263.967602 -197.339831) (xy 263.904181 -197.347845)
			(xy 263.872218 -197.348348) (xy 263.839063 -197.347871) (xy 263.773317 -197.33923) (xy 263.709252 -197.322118)
			(xy 263.647954 -197.296825) (xy 263.590463 -197.263781) (xy 263.537755 -197.223545) (xy 263.490722 -197.176801)
			(xy 263.450162 -197.12434) (xy 263.416765 -197.067054) (xy 263.391095 -197.005913) (xy 263.373589 -196.941955)
			(xy 263.368536 -196.909182) (xy 263.366758 -196.89699) (xy 263.352788 -196.876924) (xy 263.2583 -196.826886)
			(xy 263.233916 -196.826378) (xy 263.22274 -196.831966) (xy 263.196324 -196.844361) (xy 263.140673 -196.861896)
			(xy 263.083004 -196.870777) (xy 263.05383 -196.871336) (xy 263.026579 -196.870817) (xy 262.972632 -196.863065)
			(xy 262.920337 -196.847714) (xy 262.870758 -196.825077) (xy 262.824907 -196.795615) (xy 262.783714 -196.759927)
			(xy 262.74802 -196.71874) (xy 262.718551 -196.672893) (xy 262.695906 -196.623318) (xy 262.680548 -196.571025)
			(xy 262.672787 -196.517079) (xy 262.672322 -196.489828) (xy 256.478278 -196.489828) (xy 256.478278 -215.803734)
			(xy 256.477848 -215.813801) (xy 256.470123 -215.832394) (xy 256.463292 -215.839802) (xy 247.734074 -224.56902)
			(xy 247.726678 -224.575871) (xy 247.708079 -224.583609) (xy 247.698006 -224.584006) (xy 244.86108 -224.584006)
			(xy 244.854127 -224.584239) (xy 244.840728 -224.587963) (xy 244.834664 -224.591372) (xy 244.812142 -224.604628)
			(xy 244.764242 -224.625522) (xy 244.713935 -224.63967) (xy 244.662166 -224.646807) (xy 244.636036 -224.647252)
			(xy 244.609909 -224.646801) (xy 244.558148 -224.639631) (xy 244.507847 -224.625476) (xy 244.459944 -224.6046)
			(xy 244.437408 -224.591372) (xy 244.431354 -224.587937) (xy 244.41795 -224.584198) (xy 244.410992 -224.584006)
			(xy 239.987074 -224.584006) (xy 239.975136 -224.587054) (xy 239.969548 -224.589848) (xy 239.94181 -224.603897)
			(xy 239.882909 -224.623804) (xy 239.821564 -224.633921) (xy 239.790478 -224.634552) (xy 239.759389 -224.633941)
			(xy 239.698037 -224.623845) (xy 239.639142 -224.603911) (xy 239.611408 -224.589848) (xy 239.60582 -224.587054)
			(xy 239.593882 -224.584006) (xy 236.369098 -224.584006) (xy 236.359028 -224.58443) (xy 236.340425 -224.592145)
			(xy 236.33303 -224.598992) (xy 235.098799 -225.833223) (xy 235.738214 -225.833223) (xy 235.738218 -225.778727)
			(xy 235.745977 -225.724786) (xy 235.761333 -225.672499) (xy 235.783975 -225.622929) (xy 235.81344 -225.577086)
			(xy 235.849129 -225.535902) (xy 235.890316 -225.500217) (xy 235.936162 -225.470756) (xy 235.985734 -225.44812)
			(xy 236.038023 -225.432769) (xy 236.091965 -225.425015) (xy 236.146461 -225.425017) (xy 236.200402 -225.432774)
			(xy 236.252689 -225.448129) (xy 236.30226 -225.470769) (xy 236.348104 -225.500232) (xy 236.389289 -225.53592)
			(xy 236.424975 -225.577106) (xy 236.454438 -225.622951) (xy 236.477076 -225.672522) (xy 236.492428 -225.724811)
			(xy 236.500184 -225.778752) (xy 236.50067 -225.806) (xy 236.500007 -225.838115) (xy 236.489289 -225.901444)
			(xy 236.479334 -225.931984) (xy 236.474508 -225.9457) (xy 236.480604 -225.97364) (xy 236.563662 -226.06)
			(xy 236.591348 -226.066858) (xy 236.605318 -226.06254) (xy 236.632021 -226.0548) (xy 236.686994 -226.046515)
			(xy 236.714792 -226.04603) (xy 236.74442 -226.046612) (xy 236.802917 -226.056074) (xy 236.859152 -226.074756)
			(xy 236.911682 -226.102178) (xy 236.935772 -226.119436) (xy 236.9439 -226.125532) (xy 236.962442 -226.130612)
			(xy 237.052358 -226.119436) (xy 237.069376 -226.110038) (xy 237.075726 -226.102164) (xy 237.096443 -226.077306)
			(xy 237.143182 -226.032553) (xy 237.195226 -225.994096) (xy 237.25173 -225.962557) (xy 237.311781 -225.938446)
			(xy 237.374407 -225.922155) (xy 237.438595 -225.913946) (xy 237.47095 -225.913442) (xy 237.502918 -225.91382)
			(xy 237.566349 -225.921827) (xy 237.628277 -225.937722) (xy 237.687724 -225.961254) (xy 237.743752 -225.992051)
			(xy 237.795479 -226.029628) (xy 237.842088 -226.073392) (xy 237.882844 -226.122653) (xy 237.917104 -226.176634)
			(xy 237.944328 -226.234483) (xy 237.964086 -226.295289) (xy 237.976067 -226.358091) (xy 237.980082 -226.4219)
			(xy 237.97888 -226.441) (xy 239.540089 -226.441) (xy 239.544103 -226.377208) (xy 239.556079 -226.314422)
			(xy 239.57583 -226.253632) (xy 239.603043 -226.195796) (xy 239.63729 -226.141827) (xy 239.678031 -226.092576)
			(xy 239.724623 -226.048819) (xy 239.776331 -226.011245) (xy 239.832341 -225.980449) (xy 239.891769 -225.956915)
			(xy 239.953678 -225.941014) (xy 240.017091 -225.932997) (xy 240.04905 -225.932492) (xy 240.081431 -225.933)
			(xy 240.145669 -225.941222) (xy 240.208342 -225.957537) (xy 240.268434 -225.981683) (xy 240.324972 -226.013267)
			(xy 240.377039 -226.051778) (xy 240.423792 -226.096592) (xy 240.444528 -226.121468) (xy 240.450878 -226.129088)
			(xy 240.46815 -226.13874) (xy 240.557812 -226.149662) (xy 240.576862 -226.144582) (xy 240.58499 -226.13874)
			(xy 240.609139 -226.121196) (xy 240.661918 -226.093323) (xy 240.718496 -226.074313) (xy 240.777397 -226.06466)
			(xy 240.80724 -226.064064) (xy 240.834836 -226.064638) (xy 240.88941 -226.07287) (xy 240.942148 -226.089142)
			(xy 240.991872 -226.113093) (xy 241.037471 -226.144186) (xy 241.077927 -226.181728) (xy 241.112336 -226.22488)
			(xy 241.13993 -226.272678) (xy 241.160092 -226.324055) (xy 241.172373 -226.377863) (xy 241.176497 -226.4329)
			(xy 241.172373 -226.487937) (xy 241.160092 -226.541745) (xy 241.13993 -226.593122) (xy 241.112336 -226.64092)
			(xy 241.077927 -226.684072) (xy 241.037471 -226.721614) (xy 240.991872 -226.752707) (xy 240.942148 -226.776658)
			(xy 240.88941 -226.79293) (xy 240.834836 -226.801162) (xy 240.80724 -226.80168) (xy 240.778392 -226.801121)
			(xy 240.721399 -226.792134) (xy 240.666504 -226.774375) (xy 240.615048 -226.748276) (xy 240.59134 -226.73183)
			(xy 240.583212 -226.725988) (xy 240.563908 -226.721162) (xy 240.4745 -226.734116) (xy 240.457482 -226.744276)
			(xy 240.451386 -226.751896) (xy 240.430694 -226.777827) (xy 240.383658 -226.82461) (xy 240.330935 -226.864876)
			(xy 240.273421 -226.897941) (xy 240.212095 -226.923242) (xy 240.147998 -226.94035) (xy 240.08222 -226.948974)
			(xy 240.04905 -226.949508) (xy 240.017091 -226.949003) (xy 239.953678 -226.940986) (xy 239.891769 -226.925085)
			(xy 239.832341 -226.901551) (xy 239.776331 -226.870755) (xy 239.724623 -226.833181) (xy 239.678031 -226.789424)
			(xy 239.63729 -226.740173) (xy 239.603043 -226.686204) (xy 239.57583 -226.628368) (xy 239.556079 -226.567578)
			(xy 239.544103 -226.504792) (xy 239.540089 -226.441) (xy 237.97888 -226.441) (xy 237.976067 -226.485709)
			(xy 237.964086 -226.548511) (xy 237.944328 -226.609317) (xy 237.917104 -226.667166) (xy 237.882844 -226.721147)
			(xy 237.842088 -226.770408) (xy 237.795479 -226.814172) (xy 237.743752 -226.851749) (xy 237.687724 -226.882546)
			(xy 237.628277 -226.906078) (xy 237.566349 -226.921973) (xy 237.502918 -226.92998) (xy 237.47095 -226.930458)
			(xy 237.437909 -226.929915) (xy 237.372384 -226.921354) (xy 237.308518 -226.904382) (xy 237.247387 -226.879285)
			(xy 237.190019 -226.846486) (xy 237.137379 -226.806537) (xy 237.090355 -226.760109) (xy 237.06963 -226.73437)
			(xy 237.063534 -226.726242) (xy 237.04677 -226.71659) (xy 236.957108 -226.703636) (xy 236.938312 -226.708462)
			(xy 236.930184 -226.714304) (xy 236.906505 -226.73064) (xy 236.85514 -226.756538) (xy 236.800382 -226.774163)
			(xy 236.743554 -226.783091) (xy 236.714792 -226.783646) (xy 236.688449 -226.783146) (xy 236.636301 -226.775647)
			(xy 236.58575 -226.760804) (xy 236.537825 -226.738919) (xy 236.493503 -226.710436) (xy 236.453685 -226.675936)
			(xy 236.419182 -226.636121) (xy 236.390696 -226.591801) (xy 236.368806 -226.543878) (xy 236.353959 -226.493329)
			(xy 236.346456 -226.44118) (xy 236.345984 -226.414838) (xy 236.346532 -226.38503) (xy 236.35611 -226.32619)
			(xy 236.365034 -226.297744) (xy 236.369606 -226.283774) (xy 236.363256 -226.256088) (xy 236.278928 -226.170998)
			(xy 236.251242 -226.16414) (xy 236.237272 -226.168712) (xy 236.208527 -226.177447) (xy 236.149199 -226.186892)
			(xy 236.119162 -226.187508) (xy 236.091914 -226.186981) (xy 236.037974 -226.17922) (xy 235.985687 -226.163862)
			(xy 235.936118 -226.141219) (xy 235.890275 -226.111753) (xy 235.849093 -226.076062) (xy 235.813409 -226.034874)
			(xy 235.78395 -225.989027) (xy 235.761316 -225.939454) (xy 235.745966 -225.887164) (xy 235.738214 -225.833223)
			(xy 235.098799 -225.833223) (xy 234.007914 -226.924108) (xy 234.000813 -226.93188) (xy 233.993061 -226.951428)
			(xy 233.992928 -226.961954) (xy 233.995976 -227.04679) (xy 234.00512 -227.06584) (xy 234.012994 -227.072698)
			(xy 234.026456 -227.084636) (xy 234.07624 -227.084636) (xy 234.085322 -227.084313) (xy 234.102377 -227.078069)
			(xy 234.109514 -227.072444) (xy 234.132646 -227.053) (xy 234.182709 -227.019152) (xy 234.236431 -226.991478)
			(xy 234.293055 -226.970367) (xy 234.351782 -226.956117) (xy 234.411785 -226.94893) (xy 234.442 -226.948492)
			(xy 234.473961 -226.948994) (xy 234.537379 -226.957005) (xy 234.599293 -226.972902) (xy 234.658726 -226.996434)
			(xy 234.714741 -227.027228) (xy 234.766456 -227.064801) (xy 234.813053 -227.108558) (xy 234.853798 -227.157811)
			(xy 234.888049 -227.211782) (xy 234.915266 -227.269621) (xy 234.935019 -227.330414) (xy 234.946997 -227.393204)
			(xy 234.951011 -227.457) (xy 234.946997 -227.520796) (xy 234.935019 -227.583586) (xy 234.915266 -227.644379)
			(xy 234.888049 -227.702218) (xy 234.853798 -227.756189) (xy 234.813053 -227.805442) (xy 234.766456 -227.849199)
			(xy 234.714741 -227.886772) (xy 234.658726 -227.917566) (xy 234.599293 -227.941098) (xy 234.537379 -227.956995)
			(xy 234.473961 -227.965006) (xy 234.442 -227.965508) (xy 234.411786 -227.965058) (xy 234.351786 -227.957863)
			(xy 234.293061 -227.943611) (xy 234.236439 -227.922502) (xy 234.182716 -227.894833) (xy 234.132649 -227.860995)
			(xy 234.109514 -227.841556) (xy 234.102371 -227.835941) (xy 234.08532 -227.829698) (xy 234.07624 -227.829364)
			(xy 234.04576 -227.829364) (xy 234.036678 -227.829687) (xy 234.019623 -227.835931) (xy 234.012486 -227.841556)
			(xy 233.989354 -227.861) (xy 233.939291 -227.894848) (xy 233.885569 -227.922522) (xy 233.828945 -227.943633)
			(xy 233.770218 -227.957883) (xy 233.710215 -227.96507) (xy 233.68 -227.965508) (xy 233.648869 -227.965038)
			(xy 233.587073 -227.957436) (xy 233.526667 -227.942346) (xy 233.468556 -227.919994) (xy 233.413608 -227.890713)
			(xy 233.362647 -227.854943) (xy 233.316434 -227.813218) (xy 233.295698 -227.789994) (xy 233.28884 -227.78212)
			(xy 233.26979 -227.772976) (xy 233.184954 -227.769928) (xy 233.174432 -227.770084) (xy 233.154893 -227.777833)
			(xy 233.147108 -227.784914) (xy 232.191306 -228.740716) (xy 233.380803 -228.740716) (xy 233.384738 -228.686945)
			(xy 233.396461 -228.634321) (xy 233.415721 -228.583964) (xy 233.442107 -228.536947) (xy 233.475059 -228.494274)
			(xy 233.513872 -228.456853) (xy 233.55772 -228.425483) (xy 233.605668 -228.400831) (xy 233.656695 -228.383423)
			(xy 233.709713 -228.37363) (xy 233.763592 -228.371661) (xy 233.817183 -228.377558) (xy 233.869344 -228.391194)
			(xy 233.918964 -228.412281) (xy 233.964985 -228.440367) (xy 234.006427 -228.474855) (xy 234.042405 -228.515009)
			(xy 234.072153 -228.559973) (xy 234.095038 -228.60879) (xy 234.11057 -228.660419) (xy 234.11842 -228.713759)
			(xy 234.118912 -228.740716) (xy 234.11842 -228.767673) (xy 234.11057 -228.821013) (xy 234.095038 -228.872642)
			(xy 234.072153 -228.921459) (xy 234.042405 -228.966423) (xy 234.006427 -229.006577) (xy 233.964985 -229.041065)
			(xy 233.918964 -229.069151) (xy 233.869344 -229.090238) (xy 233.817183 -229.103874) (xy 233.763592 -229.109771)
			(xy 233.709713 -229.107802) (xy 233.656695 -229.098009) (xy 233.605668 -229.080601) (xy 233.55772 -229.055949)
			(xy 233.513872 -229.024579) (xy 233.475059 -228.987158) (xy 233.442107 -228.944485) (xy 233.415721 -228.897468)
			(xy 233.396461 -228.847111) (xy 233.384738 -228.794487) (xy 233.380803 -228.740716) (xy 232.191306 -228.740716)
			(xy 230.677212 -230.25481) (xy 230.670366 -230.262209) (xy 230.662633 -230.280807) (xy 230.662226 -230.290878)
			(xy 230.662226 -230.41864) (xy 230.662806 -230.430302) (xy 230.673139 -230.45121) (xy 230.682038 -230.458772)
			(xy 230.75519 -230.515414) (xy 230.777796 -230.519986) (xy 230.78948 -230.516938) (xy 230.813182 -230.511104)
			(xy 230.861594 -230.504859) (xy 230.886 -230.504492) (xy 230.913251 -230.504978) (xy 230.967199 -230.512734)
			(xy 231.019494 -230.528089) (xy 231.069071 -230.550731) (xy 231.114921 -230.580197) (xy 231.156112 -230.615888)
			(xy 231.191803 -230.657079) (xy 231.221269 -230.702929) (xy 231.243911 -230.752506) (xy 231.259266 -230.804801)
			(xy 231.267022 -230.858749) (xy 231.267022 -230.886) (xy 232.40899 -230.886) (xy 232.413003 -230.822204)
			(xy 232.424981 -230.759414) (xy 232.444734 -230.698621) (xy 232.471951 -230.640782) (xy 232.506202 -230.586811)
			(xy 232.546947 -230.537558) (xy 232.593544 -230.493801) (xy 232.645259 -230.456228) (xy 232.701274 -230.425434)
			(xy 232.760707 -230.401902) (xy 232.822621 -230.386005) (xy 232.886039 -230.377994) (xy 232.918 -230.377492)
			(xy 232.949131 -230.377969) (xy 233.010926 -230.385571) (xy 233.071331 -230.400661) (xy 233.129441 -230.423013)
			(xy 233.184388 -230.452293) (xy 233.235349 -230.488063) (xy 233.281561 -230.529787) (xy 233.302302 -230.553006)
			(xy 233.308652 -230.560372) (xy 233.325416 -230.569008) (xy 233.4133 -230.578914) (xy 233.431588 -230.573834)
			(xy 233.439462 -230.567992) (xy 233.463424 -230.551028) (xy 233.51558 -230.524078) (xy 233.571344 -230.505723)
			(xy 233.62931 -230.496425) (xy 233.658664 -230.495856) (xy 233.686265 -230.496416) (xy 233.74085 -230.504638)
			(xy 233.7936 -230.520905) (xy 233.826947 -230.536961) (xy 234.568994 -230.536961) (xy 234.568994 -230.473039)
			(xy 234.577005 -230.409621) (xy 234.592902 -230.347707) (xy 234.616434 -230.288274) (xy 234.647228 -230.232259)
			(xy 234.684801 -230.180544) (xy 234.728558 -230.133947) (xy 234.777811 -230.093202) (xy 234.831782 -230.058951)
			(xy 234.889621 -230.031734) (xy 234.950414 -230.011981) (xy 235.013204 -230.000003) (xy 235.077 -229.99599)
			(xy 235.140796 -230.000003) (xy 235.203586 -230.011981) (xy 235.264379 -230.031734) (xy 235.322218 -230.058951)
			(xy 235.376189 -230.093202) (xy 235.425442 -230.133947) (xy 235.469199 -230.180544) (xy 235.506772 -230.232259)
			(xy 235.537566 -230.288274) (xy 235.561098 -230.347707) (xy 235.576995 -230.409621) (xy 235.585006 -230.473039)
			(xy 235.585508 -230.505) (xy 235.585006 -230.536961) (xy 237.870994 -230.536961) (xy 237.870994 -230.473039)
			(xy 237.879005 -230.409621) (xy 237.894902 -230.347707) (xy 237.918434 -230.288274) (xy 237.949228 -230.232259)
			(xy 237.986801 -230.180544) (xy 238.030558 -230.133947) (xy 238.079811 -230.093202) (xy 238.133782 -230.058951)
			(xy 238.191621 -230.031734) (xy 238.252414 -230.011981) (xy 238.315204 -230.000003) (xy 238.379 -229.99599)
			(xy 238.442796 -230.000003) (xy 238.505586 -230.011981) (xy 238.566379 -230.031734) (xy 238.624218 -230.058951)
			(xy 238.678189 -230.093202) (xy 238.727442 -230.133947) (xy 238.771199 -230.180544) (xy 238.808772 -230.232259)
			(xy 238.819075 -230.251) (xy 242.588089 -230.251) (xy 242.592103 -230.187208) (xy 242.604079 -230.124422)
			(xy 242.62383 -230.063632) (xy 242.651043 -230.005796) (xy 242.68529 -229.951827) (xy 242.726031 -229.902576)
			(xy 242.772623 -229.858819) (xy 242.824331 -229.821245) (xy 242.880341 -229.790449) (xy 242.939769 -229.766915)
			(xy 243.001678 -229.751014) (xy 243.065091 -229.742997) (xy 243.09705 -229.742492) (xy 243.130826 -229.743079)
			(xy 243.197782 -229.752034) (xy 243.262961 -229.769779) (xy 243.325216 -229.796001) (xy 243.383449 -229.830239)
			(xy 243.436633 -229.871888) (xy 243.483832 -229.920216) (xy 243.504466 -229.946962) (xy 243.512119 -229.956109)
			(xy 243.533448 -229.966708) (xy 243.54536 -229.967282) (xy 243.62664 -229.967282) (xy 243.638552 -229.96671)
			(xy 243.659883 -229.95611) (xy 243.667534 -229.946962) (xy 243.688184 -229.920231) (xy 243.735394 -229.871919)
			(xy 243.788581 -229.83028) (xy 243.846811 -229.796044) (xy 243.909058 -229.769814) (xy 243.974228 -229.75205)
			(xy 244.041176 -229.743067) (xy 244.07495 -229.742492) (xy 244.106914 -229.74297) (xy 244.17034 -229.750977)
			(xy 244.232261 -229.76687) (xy 244.291702 -229.790399) (xy 244.347726 -229.821193) (xy 244.399447 -229.858767)
			(xy 244.446052 -229.902526) (xy 244.486803 -229.951783) (xy 244.52106 -230.005758) (xy 244.548281 -230.063602)
			(xy 244.568037 -230.124401) (xy 244.580017 -230.187197) (xy 244.584032 -230.251) (xy 244.580017 -230.314803)
			(xy 244.568037 -230.377599) (xy 244.548281 -230.438398) (xy 244.52106 -230.496242) (xy 244.486803 -230.550217)
			(xy 244.446052 -230.599474) (xy 244.399447 -230.643233) (xy 244.347726 -230.680807) (xy 244.291702 -230.711601)
			(xy 244.232261 -230.73513) (xy 244.17034 -230.751023) (xy 244.106914 -230.75903) (xy 244.07495 -230.759508)
			(xy 244.041174 -230.758921) (xy 243.974218 -230.749966) (xy 243.909039 -230.732221) (xy 243.846784 -230.705999)
			(xy 243.788551 -230.671761) (xy 243.735367 -230.630112) (xy 243.688168 -230.581784) (xy 243.667534 -230.555038)
			(xy 243.659881 -230.545891) (xy 243.638552 -230.535292) (xy 243.62664 -230.534718) (xy 243.54536 -230.534718)
			(xy 243.533448 -230.53529) (xy 243.512117 -230.54589) (xy 243.504466 -230.555038) (xy 243.483816 -230.581769)
			(xy 243.436606 -230.630081) (xy 243.383419 -230.67172) (xy 243.325189 -230.705956) (xy 243.262942 -230.732186)
			(xy 243.197772 -230.74995) (xy 243.130824 -230.758933) (xy 243.09705 -230.759508) (xy 243.065091 -230.759003)
			(xy 243.001678 -230.750986) (xy 242.939769 -230.735085) (xy 242.880341 -230.711551) (xy 242.824331 -230.680755)
			(xy 242.772623 -230.643181) (xy 242.726031 -230.599424) (xy 242.68529 -230.550173) (xy 242.651043 -230.496204)
			(xy 242.62383 -230.438368) (xy 242.604079 -230.377578) (xy 242.592103 -230.314792) (xy 242.588089 -230.251)
			(xy 238.819075 -230.251) (xy 238.839566 -230.288274) (xy 238.863098 -230.347707) (xy 238.878995 -230.409621)
			(xy 238.887006 -230.473039) (xy 238.887508 -230.505) (xy 238.887006 -230.536961) (xy 238.878995 -230.600379)
			(xy 238.863098 -230.662293) (xy 238.839566 -230.721726) (xy 238.808772 -230.777741) (xy 238.771199 -230.829456)
			(xy 238.727442 -230.876053) (xy 238.678189 -230.916798) (xy 238.624218 -230.951049) (xy 238.566379 -230.978266)
			(xy 238.505586 -230.998019) (xy 238.442796 -231.009997) (xy 238.379 -231.014011) (xy 238.315204 -231.009997)
			(xy 238.252414 -230.998019) (xy 238.191621 -230.978266) (xy 238.133782 -230.951049) (xy 238.079811 -230.916798)
			(xy 238.030558 -230.876053) (xy 237.986801 -230.829456) (xy 237.949228 -230.777741) (xy 237.918434 -230.721726)
			(xy 237.894902 -230.662293) (xy 237.879005 -230.600379) (xy 237.870994 -230.536961) (xy 235.585006 -230.536961)
			(xy 235.576995 -230.600379) (xy 235.561098 -230.662293) (xy 235.537566 -230.721726) (xy 235.506772 -230.777741)
			(xy 235.469199 -230.829456) (xy 235.425442 -230.876053) (xy 235.376189 -230.916798) (xy 235.322218 -230.951049)
			(xy 235.264379 -230.978266) (xy 235.203586 -230.998019) (xy 235.140796 -231.009997) (xy 235.077 -231.014011)
			(xy 235.013204 -231.009997) (xy 234.950414 -230.998019) (xy 234.889621 -230.978266) (xy 234.831782 -230.951049)
			(xy 234.777811 -230.916798) (xy 234.728558 -230.876053) (xy 234.684801 -230.829456) (xy 234.647228 -230.777741)
			(xy 234.616434 -230.721726) (xy 234.592902 -230.662293) (xy 234.577005 -230.600379) (xy 234.568994 -230.536961)
			(xy 233.826947 -230.536961) (xy 233.843336 -230.544852) (xy 233.888948 -230.575945) (xy 233.929415 -230.61349)
			(xy 233.963834 -230.656646) (xy 233.991436 -230.704451) (xy 234.011605 -230.755836) (xy 234.023889 -230.809653)
			(xy 234.028015 -230.8647) (xy 234.023889 -230.919747) (xy 234.011605 -230.973564) (xy 233.991436 -231.024949)
			(xy 233.963834 -231.072754) (xy 233.929415 -231.11591) (xy 233.888948 -231.153455) (xy 233.843336 -231.184548)
			(xy 233.7936 -231.208495) (xy 233.74085 -231.224762) (xy 233.686265 -231.232984) (xy 233.658664 -231.233472)
			(xy 233.631941 -231.232999) (xy 233.579054 -231.225281) (xy 233.527835 -231.210011) (xy 233.479356 -231.187508)
			(xy 233.456734 -231.173274) (xy 233.448606 -231.16794) (xy 233.430064 -231.16413) (xy 233.342942 -231.178862)
			(xy 233.326686 -231.188768) (xy 233.320844 -231.196388) (xy 233.300159 -231.222392) (xy 233.253082 -231.269284)
			(xy 233.2003 -231.309647) (xy 233.142712 -231.342795) (xy 233.081298 -231.368162) (xy 233.017104 -231.385318)
			(xy 232.951223 -231.393969) (xy 232.918 -231.394508) (xy 232.886039 -231.394006) (xy 232.822621 -231.385995)
			(xy 232.760707 -231.370098) (xy 232.701274 -231.346566) (xy 232.645259 -231.315772) (xy 232.593544 -231.278199)
			(xy 232.546947 -231.234442) (xy 232.506202 -231.185189) (xy 232.471951 -231.131218) (xy 232.444734 -231.073379)
			(xy 232.424981 -231.012586) (xy 232.413003 -230.949796) (xy 232.40899 -230.886) (xy 231.267022 -230.886)
			(xy 231.267022 -230.913251) (xy 231.259266 -230.967199) (xy 231.243911 -231.019494) (xy 231.221269 -231.069071)
			(xy 231.191803 -231.114921) (xy 231.156112 -231.156112) (xy 231.114921 -231.191803) (xy 231.069071 -231.221269)
			(xy 231.019494 -231.243911) (xy 230.967199 -231.259266) (xy 230.913251 -231.267022) (xy 230.886 -231.267508)
			(xy 230.861596 -231.2671) (xy 230.81319 -231.260856) (xy 230.78948 -231.255062) (xy 230.777796 -231.252014)
			(xy 230.75519 -231.256586) (xy 230.682038 -231.313228) (xy 230.673166 -231.320809) (xy 230.662836 -231.341708)
			(xy 230.662226 -231.35336) (xy 230.662226 -233.299) (xy 232.40899 -233.299) (xy 232.413003 -233.235204)
			(xy 232.424981 -233.172414) (xy 232.444734 -233.111621) (xy 232.471951 -233.053782) (xy 232.506202 -232.999811)
			(xy 232.546947 -232.950558) (xy 232.593544 -232.906801) (xy 232.645259 -232.869228) (xy 232.701274 -232.838434)
			(xy 232.760707 -232.814902) (xy 232.822621 -232.799005) (xy 232.886039 -232.790994) (xy 232.918 -232.790492)
			(xy 232.948418 -232.79091) (xy 232.949165 -232.791) (xy 234.56799 -232.791) (xy 234.572003 -232.727204)
			(xy 234.583981 -232.664414) (xy 234.603734 -232.603621) (xy 234.630951 -232.545782) (xy 234.665202 -232.491811)
			(xy 234.705947 -232.442558) (xy 234.752544 -232.398801) (xy 234.804259 -232.361228) (xy 234.860274 -232.330434)
			(xy 234.919707 -232.306902) (xy 234.981621 -232.291005) (xy 235.045039 -232.282994) (xy 235.077 -232.282492)
			(xy 235.10828 -232.282911) (xy 235.170369 -232.290575) (xy 235.231047 -232.305801) (xy 235.289399 -232.328358)
			(xy 235.344542 -232.357904) (xy 235.395642 -232.393995) (xy 235.441928 -232.436083) (xy 235.482699 -232.483532)
			(xy 235.500418 -232.509314) (xy 235.50787 -232.519474) (xy 235.530001 -232.53146) (xy 235.542582 -232.532174)
			(xy 235.627418 -232.532174) (xy 235.640001 -232.531494) (xy 235.66212 -232.519472) (xy 235.669582 -232.509314)
			(xy 235.688378 -232.483152) (xy 235.694982 -232.474262) (xy 235.699808 -232.453434) (xy 235.681266 -232.357422)
			(xy 235.66882 -232.339896) (xy 235.659422 -232.334308) (xy 235.636256 -232.319928) (xy 235.593997 -232.285477)
			(xy 235.557273 -232.245178) (xy 235.526883 -232.199911) (xy 235.50349 -232.150662) (xy 235.487605 -232.098505)
			(xy 235.479574 -232.044577) (xy 235.479082 -232.017316) (xy 235.479598 -231.989716) (xy 235.487825 -231.935133)
			(xy 235.504095 -231.882386) (xy 235.528045 -231.832654) (xy 235.55914 -231.787046) (xy 235.596685 -231.746582)
			(xy 235.639842 -231.712165) (xy 235.687646 -231.684566) (xy 235.73903 -231.664399) (xy 235.792845 -231.652116)
			(xy 235.84789 -231.647991) (xy 235.902935 -231.652116) (xy 235.95675 -231.664399) (xy 236.008134 -231.684566)
			(xy 236.055938 -231.712165) (xy 236.099095 -231.746582) (xy 236.13664 -231.787046) (xy 236.167735 -231.832654)
			(xy 236.191685 -231.882386) (xy 236.207955 -231.935133) (xy 236.216182 -231.989716) (xy 236.216698 -232.017316)
			(xy 236.216236 -232.043191) (xy 236.20898 -232.094429) (xy 236.194625 -232.144148) (xy 236.18444 -232.167938)
			(xy 236.180122 -232.178098) (xy 236.180122 -232.199434) (xy 236.22 -232.288588) (xy 236.236002 -232.302812)
			(xy 236.24667 -232.306368) (xy 236.278494 -232.317004) (xy 236.339241 -232.345507) (xy 236.395709 -232.381755)
			(xy 236.446917 -232.425119) (xy 236.491973 -232.474843) (xy 236.530094 -232.530064) (xy 236.560617 -232.589822)
			(xy 236.583012 -232.653075) (xy 236.596889 -232.718726) (xy 236.599984 -232.752138) (xy 236.600746 -232.761536)
			(xy 236.608874 -232.778808) (xy 236.673136 -232.838752) (xy 236.690662 -232.845864) (xy 236.700314 -232.845864)
			(xy 236.710756 -232.846045) (xy 236.731597 -232.847443) (xy 236.74197 -232.848658) (xy 236.752638 -232.849928)
			(xy 236.772196 -232.84434) (xy 236.845602 -232.783888) (xy 236.855 -232.7656) (xy 236.855762 -232.754932)
			(xy 236.858517 -232.723259) (xy 236.870897 -232.660899) (xy 236.890954 -232.600569) (xy 236.918375 -232.54321)
			(xy 236.952732 -232.489716) (xy 236.99349 -232.440923) (xy 237.040013 -232.397591) (xy 237.091574 -232.360396)
			(xy 237.14737 -232.329919) (xy 237.20653 -232.306636) (xy 237.268131 -232.290909) (xy 237.331212 -232.282983)
			(xy 237.363 -232.282492) (xy 237.39428 -232.282911) (xy 237.456369 -232.290575) (xy 237.517047 -232.305801)
			(xy 237.575399 -232.328358) (xy 237.630542 -232.357904) (xy 237.681642 -232.393995) (xy 237.727928 -232.436083)
			(xy 237.768699 -232.483532) (xy 237.786418 -232.509314) (xy 237.79387 -232.519474) (xy 237.816001 -232.53146)
			(xy 237.828582 -232.532174) (xy 237.913418 -232.532174) (xy 237.926001 -232.531494) (xy 237.94812 -232.519472)
			(xy 237.955582 -232.509314) (xy 237.973344 -232.483567) (xy 238.014124 -232.436139) (xy 238.060411 -232.394068)
			(xy 238.111508 -232.35799) (xy 238.166642 -232.32845) (xy 238.224983 -232.305892) (xy 238.285649 -232.290657)
			(xy 238.347725 -232.282976) (xy 238.379 -232.282492) (xy 238.409054 -232.282917) (xy 238.468742 -232.290014)
			(xy 238.527178 -232.304096) (xy 238.583546 -232.324968) (xy 238.637062 -232.352338) (xy 238.686978 -232.385826)
			(xy 238.732599 -232.424963) (xy 238.773289 -232.469205) (xy 238.791242 -232.493312) (xy 238.798608 -232.503472)
			(xy 238.821722 -232.514648) (xy 238.931704 -232.51033) (xy 238.953802 -232.497376) (xy 238.960406 -232.486454)
			(xy 238.97774 -232.458852) (xy 239.018399 -232.407909) (xy 239.065237 -232.362582) (xy 239.117487 -232.323615)
			(xy 239.174289 -232.291648) (xy 239.234712 -232.267205) (xy 239.297764 -232.250688) (xy 239.36241 -232.242367)
			(xy 239.395 -232.241852) (xy 239.427784 -232.242333) (xy 239.492809 -232.250762) (xy 239.55621 -232.267479)
			(xy 239.616937 -232.292207) (xy 239.673981 -232.324536) (xy 239.726397 -232.36393) (xy 239.773313 -232.409735)
			(xy 239.794034 -232.435146) (xy 239.801908 -232.445306) (xy 239.825276 -232.455212) (xy 239.935766 -232.44556)
			(xy 239.957102 -232.43159) (xy 239.963198 -232.42016) (xy 239.978043 -232.393576) (xy 240.013068 -232.343771)
			(xy 240.053791 -232.298505) (xy 240.099628 -232.258426) (xy 240.149924 -232.224108) (xy 240.203958 -232.196043)
			(xy 240.260957 -232.174631) (xy 240.320105 -232.16018) (xy 240.380556 -232.152897) (xy 240.411 -232.152444)
			(xy 240.443613 -232.152974) (xy 240.508305 -232.161303) (xy 240.5714 -232.177837) (xy 240.631863 -232.202305)
			(xy 240.6887 -232.234304) (xy 240.740978 -232.27331) (xy 240.787838 -232.318681) (xy 240.828511 -232.369672)
			(xy 240.845848 -232.3973) (xy 240.852452 -232.408222) (xy 240.874296 -232.421176) (xy 240.984532 -232.425494)
			(xy 241.007392 -232.414572) (xy 241.015012 -232.404158) (xy 241.03237 -232.380874) (xy 241.071536 -232.33799)
			(xy 241.115326 -232.29984) (xy 241.163172 -232.266919) (xy 241.214452 -232.239654) (xy 241.241326 -232.228644)
			(xy 241.249512 -232.224949) (xy 241.262899 -232.212996) (xy 241.267488 -232.205276) (xy 241.281712 -232.178352)
			(xy 241.285615 -232.17031) (xy 241.288082 -232.152614) (xy 241.286538 -232.143808) (xy 241.282719 -232.124733)
			(xy 241.278647 -232.086044) (xy 241.27841 -232.066592) (xy 241.278926 -232.038992) (xy 241.287153 -231.984409)
			(xy 241.303423 -231.931662) (xy 241.327373 -231.88193) (xy 241.358468 -231.836322) (xy 241.396013 -231.795858)
			(xy 241.43917 -231.761441) (xy 241.486974 -231.733842) (xy 241.538358 -231.713675) (xy 241.592173 -231.701392)
			(xy 241.647218 -231.697267) (xy 241.702263 -231.701392) (xy 241.756078 -231.713675) (xy 241.807462 -231.733842)
			(xy 241.855266 -231.761441) (xy 241.898423 -231.795858) (xy 241.935968 -231.836322) (xy 241.967063 -231.88193)
			(xy 241.991013 -231.931662) (xy 242.007283 -231.984409) (xy 242.01551 -232.038992) (xy 242.016026 -232.066592)
			(xy 242.015572 -232.09359) (xy 242.007682 -232.147007) (xy 241.992084 -232.198701) (xy 241.969112 -232.247568)
			(xy 241.939258 -232.29256) (xy 241.90316 -232.332716) (xy 241.882676 -232.35031) (xy 241.876057 -232.35633)
			(xy 241.867098 -232.371803) (xy 241.86515 -232.380536) (xy 241.859816 -232.410508) (xy 241.858562 -232.419416)
			(xy 241.861671 -232.43712) (xy 241.865912 -232.445052) (xy 241.865912 -232.445306) (xy 241.87091 -232.453042)
			(xy 241.885213 -232.46462) (xy 241.902677 -232.470422) (xy 241.911886 -232.470452) (xy 241.941096 -232.469182)
			(xy 241.950245 -232.468383) (xy 241.967134 -232.46121) (xy 241.980432 -232.448566) (xy 241.984784 -232.44048)
			(xy 241.998989 -232.412117) (xy 242.033384 -232.358818) (xy 242.074142 -232.310212) (xy 242.120629 -232.267053)
			(xy 242.172124 -232.230011) (xy 242.227827 -232.199663) (xy 242.286872 -232.17648) (xy 242.348342 -232.160821)
			(xy 242.411283 -232.152931) (xy 242.443 -232.152444) (xy 242.474958 -232.153042) (xy 242.53837 -232.161053)
			(xy 242.600278 -232.176948) (xy 242.659706 -232.200477) (xy 242.715716 -232.231269) (xy 242.767425 -232.268838)
			(xy 242.814018 -232.312591) (xy 242.854759 -232.361839) (xy 242.889007 -232.415805) (xy 242.916221 -232.473638)
			(xy 242.935973 -232.534426) (xy 242.947949 -232.59721) (xy 242.951963 -232.661) (xy 242.947949 -232.72479)
			(xy 242.935973 -232.787574) (xy 242.916221 -232.848362) (xy 242.889007 -232.906195) (xy 242.854759 -232.960161)
			(xy 242.814018 -233.009409) (xy 242.767425 -233.053162) (xy 242.715716 -233.090731) (xy 242.659706 -233.121523)
			(xy 242.600278 -233.145052) (xy 242.53837 -233.160947) (xy 242.474958 -233.168958) (xy 242.443 -233.16946)
			(xy 242.412968 -233.169013) (xy 242.353323 -233.161944) (xy 242.294927 -233.147893) (xy 242.238594 -233.127055)
			(xy 242.185111 -233.099721) (xy 242.135223 -233.066273) (xy 242.089627 -233.027177) (xy 242.048957 -232.982979)
			(xy 242.031012 -232.958894) (xy 242.023392 -232.94848) (xy 242.000532 -232.937558) (xy 241.890296 -232.941876)
			(xy 241.868452 -232.95483) (xy 241.861848 -232.965752) (xy 241.844493 -232.993369) (xy 241.803822 -233.044362)
			(xy 241.756964 -233.089735) (xy 241.70469 -233.128745) (xy 241.647856 -233.16075) (xy 241.587396 -233.185226)
			(xy 241.524303 -233.201769) (xy 241.459613 -233.21011) (xy 241.394387 -233.21011) (xy 241.329697 -233.201769)
			(xy 241.266604 -233.185226) (xy 241.206144 -233.16075) (xy 241.14931 -233.128745) (xy 241.097036 -233.089735)
			(xy 241.050178 -233.044362) (xy 241.009507 -232.993369) (xy 240.992152 -232.965752) (xy 240.985548 -232.95483)
			(xy 240.963704 -232.941876) (xy 240.853468 -232.937558) (xy 240.830608 -232.94848) (xy 240.822988 -232.958894)
			(xy 240.80505 -232.982983) (xy 240.764374 -233.027176) (xy 240.718773 -233.066267) (xy 240.668884 -233.099712)
			(xy 240.615401 -233.127045) (xy 240.55907 -233.147885) (xy 240.500675 -233.161942) (xy 240.441031 -233.16902)
			(xy 240.411 -233.16946) (xy 240.378216 -233.168974) (xy 240.313192 -233.160546) (xy 240.24979 -233.143829)
			(xy 240.189064 -233.119102) (xy 240.13202 -233.086773) (xy 240.079604 -233.04738) (xy 240.032687 -233.001576)
			(xy 240.011966 -232.976166) (xy 240.004092 -232.966006) (xy 239.980724 -232.9561) (xy 239.870234 -232.965752)
			(xy 239.848898 -232.979722) (xy 239.842802 -232.991152) (xy 239.827962 -233.017739) (xy 239.792935 -233.067544)
			(xy 239.752212 -233.112809) (xy 239.706374 -233.152888) (xy 239.656078 -233.187205) (xy 239.602043 -233.21527)
			(xy 239.545044 -233.236681) (xy 239.485895 -233.251132) (xy 239.425444 -233.258415) (xy 239.395 -233.258868)
			(xy 239.377802 -233.258745) (xy 239.343482 -233.256457) (xy 239.32642 -233.254296) (xy 239.317309 -233.253391)
			(xy 239.299467 -233.257447) (xy 239.291622 -233.26217) (xy 239.265968 -233.279188) (xy 239.25866 -233.284415)
			(xy 239.247992 -233.298861) (xy 239.24514 -233.307382) (xy 239.237442 -233.332736) (xy 239.215744 -233.381078)
			(xy 239.187351 -233.425815) (xy 239.152846 -233.466029) (xy 239.112941 -233.500889) (xy 239.068457 -233.529678)
			(xy 239.02031 -233.551804) (xy 238.969492 -233.56681) (xy 238.91705 -233.574388) (xy 238.890556 -233.574844)
			(xy 238.862848 -233.574324) (xy 238.808056 -233.566027) (xy 238.755121 -233.549626) (xy 238.705237 -233.52549)
			(xy 238.659525 -233.494162) (xy 238.619014 -233.456348) (xy 238.584616 -233.412899) (xy 238.557106 -233.364792)
			(xy 238.54664 -233.339132) (xy 238.543173 -233.331143) (xy 238.531891 -233.317894) (xy 238.524542 -233.313224)
			(xy 238.49838 -233.298238) (xy 238.490595 -233.294166) (xy 238.473316 -233.291052) (xy 238.464598 -233.292142)
			(xy 238.443363 -233.295559) (xy 238.400507 -233.299248) (xy 238.379 -233.299508) (xy 238.34772 -233.299089)
			(xy 238.285631 -233.291425) (xy 238.224953 -233.276199) (xy 238.166601 -233.253642) (xy 238.111458 -233.224096)
			(xy 238.060358 -233.188005) (xy 238.014072 -233.145917) (xy 237.973301 -233.098468) (xy 237.955582 -233.072686)
			(xy 237.94813 -233.062526) (xy 237.925999 -233.05054) (xy 237.913418 -233.049826) (xy 237.828582 -233.049826)
			(xy 237.815999 -233.050506) (xy 237.79388 -233.062528) (xy 237.786418 -233.072686) (xy 237.768656 -233.098433)
			(xy 237.727876 -233.145861) (xy 237.681589 -233.187932) (xy 237.630492 -233.22401) (xy 237.575358 -233.25355)
			(xy 237.517017 -233.276108) (xy 237.456351 -233.291343) (xy 237.394275 -233.299024) (xy 237.363 -233.299508)
			(xy 237.33186 -233.299076) (xy 237.27004 -233.291524) (xy 237.20961 -233.276459) (xy 237.180374 -233.265726)
			(xy 237.170468 -233.261916) (xy 237.149894 -233.262678) (xy 237.064296 -233.303318) (xy 237.050834 -233.318812)
			(xy 237.047532 -233.328972) (xy 237.039097 -233.353299) (xy 237.016482 -233.399555) (xy 236.987655 -233.442215)
			(xy 236.953174 -233.480452) (xy 236.913711 -233.513522) (xy 236.870033 -233.540783) (xy 236.822987 -233.561705)
			(xy 236.77349 -233.575881) (xy 236.722502 -233.583035) (xy 236.696758 -233.58348) (xy 236.668756 -233.582935)
			(xy 236.613399 -233.574454) (xy 236.559957 -233.55771) (xy 236.509658 -233.533085) (xy 236.463655 -233.501145)
			(xy 236.423004 -233.462624) (xy 236.388639 -233.418404) (xy 236.361346 -233.369501) (xy 236.351064 -233.34345)
			(xy 236.347762 -233.33456) (xy 236.335316 -233.320336) (xy 236.25683 -233.280458) (xy 236.238034 -233.278426)
			(xy 236.22889 -233.280966) (xy 236.195586 -233.289622) (xy 236.127406 -233.298922) (xy 236.093 -233.299508)
			(xy 236.06172 -233.299089) (xy 235.999631 -233.291425) (xy 235.938953 -233.276199) (xy 235.880601 -233.253642)
			(xy 235.825458 -233.224096) (xy 235.774358 -233.188005) (xy 235.728072 -233.145917) (xy 235.687301 -233.098468)
			(xy 235.669582 -233.072686) (xy 235.66213 -233.062526) (xy 235.639999 -233.05054) (xy 235.627418 -233.049826)
			(xy 235.542582 -233.049826) (xy 235.529999 -233.050506) (xy 235.50788 -233.062528) (xy 235.500418 -233.072686)
			(xy 235.482656 -233.098433) (xy 235.441876 -233.145861) (xy 235.395589 -233.187932) (xy 235.344492 -233.22401)
			(xy 235.289358 -233.25355) (xy 235.231017 -233.276108) (xy 235.170351 -233.291343) (xy 235.108275 -233.299024)
			(xy 235.077 -233.299508) (xy 235.045039 -233.299006) (xy 234.981621 -233.290995) (xy 234.919707 -233.275098)
			(xy 234.860274 -233.251566) (xy 234.804259 -233.220772) (xy 234.752544 -233.183199) (xy 234.705947 -233.139442)
			(xy 234.665202 -233.090189) (xy 234.630951 -233.036218) (xy 234.603734 -232.978379) (xy 234.583981 -232.917586)
			(xy 234.572003 -232.854796) (xy 234.56799 -232.791) (xy 232.949165 -232.791) (xy 233.008819 -232.798183)
			(xy 233.06792 -232.812613) (xy 233.124876 -232.833994) (xy 233.178873 -232.86202) (xy 233.229139 -232.896291)
			(xy 233.274955 -232.936316) (xy 233.315667 -232.981523) (xy 233.333544 -233.006138) (xy 233.340656 -233.016044)
			(xy 233.361484 -233.02722) (xy 233.466894 -233.030522) (xy 233.488484 -233.020616) (xy 233.496104 -233.010964)
			(xy 233.513737 -232.989822) (xy 233.554158 -232.952452) (xy 233.599686 -232.921507) (xy 233.64931 -232.897675)
			(xy 233.701924 -232.881486) (xy 233.756361 -232.873299) (xy 233.783886 -232.872788) (xy 233.811488 -232.873285)
			(xy 233.866076 -232.881511) (xy 233.918827 -232.897781) (xy 233.968565 -232.921732) (xy 234.014178 -232.952828)
			(xy 234.054646 -232.990376) (xy 234.089065 -233.033535) (xy 234.116668 -233.081343) (xy 234.136837 -233.132731)
			(xy 234.149121 -233.18655) (xy 234.153247 -233.2416) (xy 234.149121 -233.29665) (xy 234.136837 -233.350469)
			(xy 234.116668 -233.401857) (xy 234.089065 -233.449665) (xy 234.054646 -233.492824) (xy 234.014178 -233.530372)
			(xy 233.968565 -233.561468) (xy 233.918827 -233.585419) (xy 233.866076 -233.601689) (xy 233.811488 -233.609915)
			(xy 233.783886 -233.610404) (xy 233.755713 -233.60989) (xy 233.700023 -233.601318) (xy 233.646285 -233.584374)
			(xy 233.595749 -233.559454) (xy 233.549591 -233.527137) (xy 233.52887 -233.508042) (xy 233.520234 -233.49966)
			(xy 233.497628 -233.492802) (xy 233.393488 -233.50982) (xy 233.374438 -233.52379) (xy 233.368596 -233.534458)
			(xy 233.353989 -233.561556) (xy 233.319106 -233.612283) (xy 233.278353 -233.658427) (xy 233.232326 -233.699312)
			(xy 233.181698 -233.734339) (xy 233.127211 -233.762997) (xy 233.069663 -233.784866) (xy 233.009895 -233.799625)
			(xy 232.948782 -233.807059) (xy 232.918 -233.807508) (xy 232.886039 -233.807006) (xy 232.822621 -233.798995)
			(xy 232.760707 -233.783098) (xy 232.701274 -233.759566) (xy 232.645259 -233.728772) (xy 232.593544 -233.691199)
			(xy 232.546947 -233.647442) (xy 232.506202 -233.598189) (xy 232.471951 -233.544218) (xy 232.444734 -233.486379)
			(xy 232.424981 -233.425586) (xy 232.413003 -233.362796) (xy 232.40899 -233.299) (xy 230.662226 -233.299)
			(xy 230.662226 -233.78287) (xy 230.662662 -233.792934) (xy 230.670398 -233.811518) (xy 230.677212 -233.818938)
			(xy 231.646222 -234.787948) (xy 231.653619 -234.794796) (xy 231.672218 -234.802531) (xy 231.68229 -234.802934)
			(xy 253.153672 -234.802934) (xy 253.163735 -234.802496) (xy 253.182314 -234.794756) (xy 253.18974 -234.787948)
			(xy 263.109456 -224.868232) (xy 263.116297 -224.860832) (xy 263.124013 -224.842233) (xy 263.124442 -224.832164)
			(xy 263.124442 -199.672956) (xy 263.124874 -199.66289) (xy 263.132605 -199.644302) (xy 263.139428 -199.636888)
			(xy 265.223498 -197.552818) (xy 265.228578 -197.520052) (xy 265.220958 -197.50532) (xy 265.207854 -197.478885)
			(xy 265.189297 -197.422882) (xy 265.179895 -197.364639) (xy 265.179302 -197.33514) (xy 265.179747 -197.308793)
			(xy 265.187241 -197.256634) (xy 265.202083 -197.206073) (xy 265.223969 -197.158139) (xy 265.252456 -197.113808)
			(xy 265.286961 -197.073982) (xy 265.326784 -197.039474) (xy 265.371112 -197.010984) (xy 265.419045 -196.989093)
			(xy 265.469605 -196.974248) (xy 265.521763 -196.966749) (xy 265.54811 -196.966332) (xy 265.577609 -196.966915)
			(xy 265.635853 -196.97632) (xy 265.691852 -196.994888) (xy 265.71829 -197.007988) (xy 265.733022 -197.015608)
			(xy 265.765788 -197.010528) (xy 265.873738 -196.902578) (xy 265.881135 -196.895729) (xy 265.899734 -196.887996)
			(xy 265.909806 -196.887592) (xy 269.286736 -196.887592) (xy 269.296351 -196.887173) (xy 269.314224 -196.880079)
			(xy 269.328228 -196.8669) (xy 269.33271 -196.858382) (xy 269.378176 -196.761354) (xy 269.374366 -196.732652)
			(xy 269.364714 -196.720968) (xy 269.348662 -196.701002) (xy 269.32165 -196.657473) (xy 269.300926 -196.610623)
			(xy 269.286888 -196.561354) (xy 269.279808 -196.510617) (xy 269.27937 -196.485002) (xy 269.279886 -196.457402)
			(xy 269.288113 -196.402819) (xy 269.304383 -196.350072) (xy 269.328333 -196.30034) (xy 269.359428 -196.254732)
			(xy 269.396973 -196.214268) (xy 269.44013 -196.179851) (xy 269.487934 -196.152252) (xy 269.539318 -196.132085)
			(xy 269.593133 -196.119802) (xy 269.648178 -196.115677) (xy 269.703223 -196.119802) (xy 269.757038 -196.132085)
			(xy 269.808422 -196.152252) (xy 269.856226 -196.179851) (xy 269.899383 -196.214268) (xy 269.936928 -196.254732)
			(xy 269.968023 -196.30034) (xy 269.991973 -196.350072) (xy 270.008243 -196.402819) (xy 270.01647 -196.457402)
			(xy 270.016986 -196.485002) (xy 270.016547 -196.510617) (xy 270.00946 -196.561353) (xy 269.995423 -196.610622)
			(xy 269.974705 -196.657475) (xy 269.947704 -196.701011) (xy 269.931642 -196.720968) (xy 269.92199 -196.732652)
			(xy 269.91818 -196.761354) (xy 269.963646 -196.858382) (xy 269.968107 -196.866911) (xy 269.982122 -196.880081)
			(xy 270.000004 -196.887161) (xy 270.00962 -196.887592) (xy 276.83079 -196.887592) (xy 276.840409 -196.887181)
			(xy 276.858296 -196.880096) (xy 276.872314 -196.86692) (xy 276.876764 -196.858382) (xy 276.92223 -196.761354)
			(xy 276.91842 -196.732652) (xy 276.908768 -196.720968) (xy 276.892718 -196.701001) (xy 276.865709 -196.657471)
			(xy 276.844987 -196.610621) (xy 276.830952 -196.561353) (xy 276.823872 -196.510616) (xy 276.823424 -196.485002)
			(xy 276.82394 -196.457402) (xy 276.832167 -196.402819) (xy 276.848437 -196.350072) (xy 276.872387 -196.30034)
			(xy 276.903482 -196.254732) (xy 276.941027 -196.214268) (xy 276.984184 -196.179851) (xy 277.031988 -196.152252)
			(xy 277.083372 -196.132085) (xy 277.137187 -196.119802) (xy 277.192232 -196.115677) (xy 277.247277 -196.119802)
			(xy 277.301092 -196.132085) (xy 277.352476 -196.152252) (xy 277.40028 -196.179851) (xy 277.443437 -196.214268)
			(xy 277.480982 -196.254732) (xy 277.512077 -196.30034) (xy 277.536027 -196.350072) (xy 277.552297 -196.402819)
			(xy 277.560524 -196.457402) (xy 277.56104 -196.485002) (xy 277.560601 -196.510616) (xy 277.553513 -196.561352)
			(xy 277.539474 -196.61062) (xy 277.518754 -196.657471) (xy 277.491751 -196.701006) (xy 277.475696 -196.720968)
			(xy 277.466044 -196.732652) (xy 277.462234 -196.761354) (xy 277.5077 -196.858382) (xy 277.512159 -196.866916)
			(xy 277.526172 -196.880099) (xy 277.544055 -196.887194) (xy 277.553674 -196.887592) (xy 284.37459 -196.887592)
			(xy 284.384209 -196.887181) (xy 284.402096 -196.880096) (xy 284.416114 -196.86692) (xy 284.420564 -196.858382)
			(xy 284.46603 -196.761354) (xy 284.46222 -196.732652) (xy 284.452568 -196.720968) (xy 284.436518 -196.701001)
			(xy 284.409509 -196.657471) (xy 284.388787 -196.610621) (xy 284.374752 -196.561353) (xy 284.367672 -196.510616)
			(xy 284.367224 -196.485002) (xy 284.36774 -196.457402) (xy 284.375967 -196.402819) (xy 284.392237 -196.350072)
			(xy 284.416187 -196.30034) (xy 284.447282 -196.254732) (xy 284.484827 -196.214268) (xy 284.527984 -196.179851)
			(xy 284.575788 -196.152252) (xy 284.627172 -196.132085) (xy 284.680987 -196.119802) (xy 284.736032 -196.115677)
			(xy 284.791077 -196.119802) (xy 284.844892 -196.132085) (xy 284.896276 -196.152252) (xy 284.94408 -196.179851)
			(xy 284.987237 -196.214268) (xy 285.024782 -196.254732) (xy 285.055877 -196.30034) (xy 285.079827 -196.350072)
			(xy 285.096097 -196.402819) (xy 285.104324 -196.457402) (xy 285.10484 -196.485002) (xy 285.104401 -196.510616)
			(xy 285.097313 -196.561352) (xy 285.083274 -196.61062) (xy 285.062554 -196.657471) (xy 285.035551 -196.701006)
			(xy 285.019496 -196.720968) (xy 285.009844 -196.732652) (xy 285.006034 -196.761354) (xy 285.0515 -196.858382)
			(xy 285.055959 -196.866916) (xy 285.069972 -196.880099) (xy 285.087855 -196.887194) (xy 285.097474 -196.887592)
			(xy 291.918644 -196.887592) (xy 291.928268 -196.887189) (xy 291.946168 -196.880114) (xy 291.9602 -196.866939)
			(xy 291.964618 -196.858382) (xy 292.010084 -196.761354) (xy 292.006274 -196.732652) (xy 291.996622 -196.720968)
			(xy 291.980574 -196.701) (xy 291.953568 -196.657469) (xy 291.932849 -196.610619) (xy 291.918815 -196.561352)
			(xy 291.911737 -196.510616) (xy 291.911278 -196.485002) (xy 291.911794 -196.457402) (xy 291.920021 -196.402819)
			(xy 291.936291 -196.350072) (xy 291.960241 -196.30034) (xy 291.991336 -196.254732) (xy 292.028881 -196.214268)
			(xy 292.072038 -196.179851) (xy 292.119842 -196.152252) (xy 292.171226 -196.132085) (xy 292.225041 -196.119802)
			(xy 292.280086 -196.115677) (xy 292.335131 -196.119802) (xy 292.388946 -196.132085) (xy 292.44033 -196.152252)
			(xy 292.488134 -196.179851) (xy 292.531291 -196.214268) (xy 292.568836 -196.254732) (xy 292.599931 -196.30034)
			(xy 292.623881 -196.350072) (xy 292.640151 -196.402819) (xy 292.648378 -196.457402) (xy 292.648894 -196.485002)
			(xy 292.648455 -196.510617) (xy 292.641368 -196.561353) (xy 292.627331 -196.610622) (xy 292.606613 -196.657475)
			(xy 292.579613 -196.701012) (xy 292.56355 -196.720968) (xy 292.553898 -196.732652) (xy 292.550088 -196.761354)
			(xy 292.595554 -196.858382) (xy 292.600016 -196.86691) (xy 292.614031 -196.880078) (xy 292.631912 -196.887155)
			(xy 292.641528 -196.887592) (xy 299.429424 -196.887592) (xy 299.439409 -196.88705) (xy 299.457834 -196.87933)
			(xy 299.465238 -196.872606) (xy 299.556678 -196.781166) (xy 299.558202 -196.741288) (xy 299.545248 -196.726302)
			(xy 299.528384 -196.706094) (xy 299.499955 -196.6618) (xy 299.478109 -196.613916) (xy 299.463289 -196.563414)
			(xy 299.455796 -196.511318) (xy 299.455332 -196.485002) (xy 299.45578 -196.458657) (xy 299.463279 -196.406504)
			(xy 299.478124 -196.355949) (xy 299.500013 -196.308022) (xy 299.5285 -196.263698) (xy 299.563006 -196.22388)
			(xy 299.602828 -196.189378) (xy 299.647155 -196.160895) (xy 299.695085 -196.13901) (xy 299.745641 -196.12417)
			(xy 299.797795 -196.116677) (xy 299.82414 -196.116194) (xy 299.852173 -196.11672) (xy 299.907591 -196.125214)
			(xy 299.961085 -196.142001) (xy 300.01142 -196.166693) (xy 300.057437 -196.198721) (xy 300.098075 -196.237347)
			(xy 300.132396 -196.28168) (xy 300.146466 -196.305932) (xy 300.151642 -196.314332) (xy 300.166998 -196.326692)
			(xy 300.185887 -196.332329) (xy 300.195742 -196.33184) (xy 300.209046 -196.330666) (xy 300.235727 -196.329397)
			(xy 300.249082 -196.3293) (xy 301.174404 -196.3293) (xy 301.207001 -196.32974) (xy 301.271785 -196.337041)
			(xy 301.335345 -196.351551) (xy 301.396879 -196.373087) (xy 301.455615 -196.401378) (xy 301.510814 -196.436069)
			(xy 301.56178 -196.476722) (xy 301.585122 -196.49948) (xy 301.958248 -196.872606) (xy 301.965596 -196.879408)
			(xy 301.984059 -196.887122) (xy 301.994062 -196.887592) (xy 303.518062 -196.887592) (xy 303.526856 -196.887229)
			(xy 303.543411 -196.881288) (xy 303.556976 -196.870093) (xy 303.56175 -196.8627) (xy 303.580884 -196.831344)
			(xy 303.625848 -196.773255) (xy 303.651412 -196.746876) (xy 303.796192 -196.602096) (xy 303.819545 -196.57935)
			(xy 303.870504 -196.538687) (xy 303.925699 -196.50399) (xy 303.984433 -196.475696) (xy 304.045968 -196.45416)
			(xy 304.109528 -196.439655) (xy 304.174313 -196.432363) (xy 304.20691 -196.431916) (xy 304.46853 -196.431916)
			(xy 304.502282 -196.432423) (xy 304.569327 -196.440282) (xy 304.63501 -196.455855) (xy 304.698447 -196.478933)
			(xy 304.758783 -196.509206) (xy 304.815205 -196.546264) (xy 304.841402 -196.567552) (xy 304.848398 -196.573009)
			(xy 304.865048 -196.579109) (xy 304.873914 -196.57949) (xy 304.903886 -196.57949) (xy 304.912743 -196.579067)
			(xy 304.929377 -196.572967) (xy 304.936398 -196.567552) (xy 304.962582 -196.546245) (xy 305.019 -196.509174)
			(xy 305.079336 -196.478895) (xy 305.142777 -196.455818) (xy 305.208466 -196.440252) (xy 305.275516 -196.432409)
			(xy 305.30927 -196.431916) (xy 305.57089 -196.431916) (xy 305.604643 -196.43242) (xy 305.67169 -196.440275)
			(xy 305.737376 -196.455845) (xy 305.800815 -196.47892) (xy 305.861154 -196.509189) (xy 305.917579 -196.546246)
			(xy 305.943762 -196.567552) (xy 305.950756 -196.573015) (xy 305.967406 -196.579128) (xy 305.976274 -196.57949)
			(xy 306.006246 -196.57949) (xy 306.015099 -196.579057) (xy 306.031721 -196.572942) (xy 306.038758 -196.567552)
			(xy 306.064942 -196.546248) (xy 306.121362 -196.509183) (xy 306.181699 -196.47891) (xy 306.24514 -196.455839)
			(xy 306.310828 -196.44028) (xy 306.377877 -196.432444) (xy 306.41163 -196.431916) (xy 306.67325 -196.431916)
			(xy 306.707727 -196.432459) (xy 306.776191 -196.440676) (xy 306.843203 -196.456931) (xy 306.875688 -196.468492)
			(xy 306.886102 -196.472302) (xy 306.907438 -196.471032) (xy 306.994306 -196.425058) (xy 307.00726 -196.408294)
			(xy 307.010054 -196.397372) (xy 307.016993 -196.370982) (xy 307.03759 -196.320454) (xy 307.065414 -196.273516)
			(xy 307.099856 -196.231196) (xy 307.140164 -196.194418) (xy 307.185455 -196.163987) (xy 307.23474 -196.14057)
			(xy 307.286939 -196.124678) (xy 307.340911 -196.116658) (xy 307.368194 -196.116194) (xy 307.39454 -196.116641)
			(xy 307.446695 -196.124139) (xy 307.497253 -196.138983) (xy 307.539678 -196.158358) (xy 308.073296 -196.158358)
			(xy 308.07737 -196.09489) (xy 308.089528 -196.032465) (xy 308.109568 -195.972106) (xy 308.137162 -195.914806)
			(xy 308.171858 -195.861505) (xy 308.213084 -195.813078) (xy 308.260164 -195.770321) (xy 308.312326 -195.733935)
			(xy 308.368713 -195.704518) (xy 308.428398 -195.682553) (xy 308.490402 -195.668401) (xy 308.553706 -195.662295)
			(xy 308.617272 -195.664333) (xy 308.680055 -195.674483) (xy 308.741025 -195.692579) (xy 308.79918 -195.718322)
			(xy 308.853566 -195.751291) (xy 308.903289 -195.790944) (xy 308.947534 -195.83663) (xy 308.985573 -195.887599)
			(xy 309.016782 -195.943013) (xy 309.040648 -196.001964) (xy 309.05678 -196.063482) (xy 309.064913 -196.126559)
			(xy 309.065422 -196.158358) (xy 309.064913 -196.190157) (xy 309.05678 -196.253234) (xy 309.040648 -196.314752)
			(xy 309.016782 -196.373703) (xy 308.985573 -196.429117) (xy 308.947534 -196.480086) (xy 308.903289 -196.525772)
			(xy 308.853566 -196.565425) (xy 308.79918 -196.598394) (xy 308.741025 -196.624137) (xy 308.680055 -196.642233)
			(xy 308.617272 -196.652383) (xy 308.553706 -196.654421) (xy 308.490402 -196.648315) (xy 308.428398 -196.634163)
			(xy 308.368713 -196.612198) (xy 308.312326 -196.582781) (xy 308.260164 -196.546395) (xy 308.213084 -196.503638)
			(xy 308.171858 -196.455211) (xy 308.137162 -196.40191) (xy 308.109568 -196.34461) (xy 308.089528 -196.284251)
			(xy 308.07737 -196.221826) (xy 308.073296 -196.158358) (xy 307.539678 -196.158358) (xy 307.545183 -196.160872)
			(xy 307.589511 -196.189359) (xy 307.629333 -196.223864) (xy 307.663839 -196.263686) (xy 307.692326 -196.308013)
			(xy 307.714215 -196.355943) (xy 307.72906 -196.406501) (xy 307.736559 -196.458656) (xy 307.737002 -196.485002)
			(xy 307.736563 -196.510616) (xy 307.729475 -196.561352) (xy 307.715435 -196.610618) (xy 307.694713 -196.657469)
			(xy 307.667708 -196.701001) (xy 307.651658 -196.720968) (xy 307.642006 -196.732652) (xy 307.638196 -196.761354)
			(xy 307.683662 -196.858382) (xy 307.688119 -196.86692) (xy 307.70213 -196.880113) (xy 307.720014 -196.887222)
			(xy 307.729636 -196.887592) (xy 308.20741 -196.887592) (xy 308.21748 -196.888016) (xy 308.236082 -196.895733)
			(xy 308.243478 -196.902578) (xy 314.275109 -202.934273) (xy 318.629532 -202.934273) (xy 318.629532 -202.870351)
			(xy 318.637543 -202.806933) (xy 318.65344 -202.745019) (xy 318.676972 -202.685586) (xy 318.707766 -202.629571)
			(xy 318.745339 -202.577856) (xy 318.789096 -202.531259) (xy 318.838349 -202.490514) (xy 318.89232 -202.456263)
			(xy 318.950159 -202.429046) (xy 319.010952 -202.409293) (xy 319.073742 -202.397315) (xy 319.137538 -202.393302)
			(xy 319.201334 -202.397315) (xy 319.264124 -202.409293) (xy 319.324917 -202.429046) (xy 319.382756 -202.456263)
			(xy 319.436727 -202.490514) (xy 319.48598 -202.531259) (xy 319.529737 -202.577856) (xy 319.56731 -202.629571)
			(xy 319.598104 -202.685586) (xy 319.621636 -202.745019) (xy 319.637533 -202.806933) (xy 319.645544 -202.870351)
			(xy 319.646046 -202.902312) (xy 319.6456 -202.930717) (xy 320.156072 -202.930717) (xy 320.156072 -202.866795)
			(xy 320.164083 -202.803377) (xy 320.17998 -202.741463) (xy 320.203512 -202.68203) (xy 320.234306 -202.626015)
			(xy 320.271879 -202.5743) (xy 320.315636 -202.527703) (xy 320.364889 -202.486958) (xy 320.41886 -202.452707)
			(xy 320.476699 -202.42549) (xy 320.537492 -202.405737) (xy 320.600282 -202.393759) (xy 320.664078 -202.389746)
			(xy 320.727874 -202.393759) (xy 320.790664 -202.405737) (xy 320.851457 -202.42549) (xy 320.909296 -202.452707)
			(xy 320.963267 -202.486958) (xy 321.01252 -202.527703) (xy 321.056277 -202.5743) (xy 321.09385 -202.626015)
			(xy 321.124644 -202.68203) (xy 321.148176 -202.741463) (xy 321.164073 -202.803377) (xy 321.172084 -202.866795)
			(xy 321.172586 -202.898756) (xy 321.172084 -202.930717) (xy 321.164073 -202.994135) (xy 321.148176 -203.056049)
			(xy 321.124644 -203.115482) (xy 321.09385 -203.171497) (xy 321.056277 -203.223212) (xy 321.01252 -203.269809)
			(xy 320.963267 -203.310554) (xy 320.909296 -203.344805) (xy 320.851457 -203.372022) (xy 320.790664 -203.391775)
			(xy 320.727874 -203.403753) (xy 320.664078 -203.407767) (xy 320.600282 -203.403753) (xy 320.537492 -203.391775)
			(xy 320.476699 -203.372022) (xy 320.41886 -203.344805) (xy 320.364889 -203.310554) (xy 320.315636 -203.269809)
			(xy 320.271879 -203.223212) (xy 320.234306 -203.171497) (xy 320.203512 -203.115482) (xy 320.17998 -203.056049)
			(xy 320.164083 -202.994135) (xy 320.156072 -202.930717) (xy 319.6456 -202.930717) (xy 319.645544 -202.934273)
			(xy 319.637533 -202.997691) (xy 319.621636 -203.059605) (xy 319.598104 -203.119038) (xy 319.56731 -203.175053)
			(xy 319.529737 -203.226768) (xy 319.48598 -203.273365) (xy 319.436727 -203.31411) (xy 319.382756 -203.348361)
			(xy 319.324917 -203.375578) (xy 319.264124 -203.395331) (xy 319.201334 -203.407309) (xy 319.137538 -203.411323)
			(xy 319.073742 -203.407309) (xy 319.010952 -203.395331) (xy 318.950159 -203.375578) (xy 318.89232 -203.348361)
			(xy 318.838349 -203.31411) (xy 318.789096 -203.273365) (xy 318.745339 -203.226768) (xy 318.707766 -203.175053)
			(xy 318.676972 -203.119038) (xy 318.65344 -203.059605) (xy 318.637543 -202.997691) (xy 318.629532 -202.934273)
			(xy 314.275109 -202.934273) (xy 316.811109 -205.4703) (xy 318.902841 -205.4703) (xy 318.906855 -205.406501)
			(xy 318.918832 -205.343709) (xy 318.938585 -205.282912) (xy 318.965802 -205.225071) (xy 319.000053 -205.171096)
			(xy 319.040798 -205.12184) (xy 319.087395 -205.078078) (xy 319.13911 -205.040502) (xy 319.195126 -205.009703)
			(xy 319.25456 -204.986167) (xy 319.316476 -204.970265) (xy 319.379896 -204.962248) (xy 319.411858 -204.961744)
			(xy 319.441876 -204.962229) (xy 319.501492 -204.969319) (xy 319.559858 -204.98338) (xy 319.616162 -205.004217)
			(xy 319.66962 -205.031541) (xy 319.719488 -205.06497) (xy 319.742566 -205.084172) (xy 319.749459 -205.089584)
			(xy 319.765823 -205.095823) (xy 319.77457 -205.096364) (xy 319.804288 -205.097126) (xy 319.812982 -205.096979)
			(xy 319.829478 -205.091522) (xy 319.836546 -205.086458) (xy 319.863408 -205.066278) (xy 319.921431 -205.032405)
			(xy 319.98341 -205.006469) (xy 320.048264 -204.988921) (xy 320.114865 -204.980067) (xy 320.148458 -204.979524)
			(xy 320.181081 -204.979996) (xy 320.245791 -204.988338) (xy 320.308902 -205.00489) (xy 320.369377 -205.029379)
			(xy 320.426222 -205.061404) (xy 320.478503 -205.100439) (xy 320.50228 -205.12278) (xy 320.509138 -205.129384)
			(xy 320.526156 -205.13675) (xy 320.613532 -205.139544) (xy 320.631058 -205.133702) (xy 320.638424 -205.127352)
			(xy 320.661392 -205.108503) (xy 320.710956 -205.075732) (xy 320.764004 -205.048963) (xy 320.81981 -205.028562)
			(xy 320.877615 -205.014806) (xy 320.936629 -205.007883) (xy 320.966338 -205.007464) (xy 321.000741 -205.008062)
			(xy 321.068916 -205.017374) (xy 321.135214 -205.035783) (xy 321.19843 -205.062954) (xy 321.25741 -205.098392)
			(xy 321.2846 -205.119478) (xy 321.29168 -205.124707) (xy 321.308313 -205.130421) (xy 321.317112 -205.130654)
			(xy 321.347084 -205.130146) (xy 321.355814 -205.129679) (xy 321.372181 -205.123568) (xy 321.379088 -205.118208)
			(xy 321.402112 -205.099213) (xy 321.451824 -205.066174) (xy 321.505062 -205.03918) (xy 321.561093 -205.018602)
			(xy 321.619147 -205.004723) (xy 321.678427 -204.997734) (xy 321.708272 -204.997304) (xy 321.740236 -204.997759)
			(xy 321.803661 -205.005768) (xy 321.865582 -205.021664) (xy 321.925022 -205.045195) (xy 321.981044 -205.075991)
			(xy 322.032764 -205.113565) (xy 322.079368 -205.157326) (xy 322.120118 -205.206583) (xy 322.154374 -205.260559)
			(xy 322.181594 -205.318402) (xy 322.20135 -205.379202) (xy 322.213329 -205.441998) (xy 322.215506 -205.4766)
			(xy 322.369991 -205.4766) (xy 322.374005 -205.412808) (xy 322.385981 -205.350021) (xy 322.405732 -205.289231)
			(xy 322.432946 -205.231395) (xy 322.467194 -205.177426) (xy 322.507935 -205.128174) (xy 322.554528 -205.084417)
			(xy 322.606237 -205.046844) (xy 322.662247 -205.016048) (xy 322.721676 -204.992515) (xy 322.783585 -204.976614)
			(xy 322.846999 -204.968598) (xy 322.878958 -204.968094) (xy 322.910237 -204.968544) (xy 322.972324 -204.976204)
			(xy 323.033003 -204.991425) (xy 323.091354 -205.013977) (xy 323.146497 -205.043519) (xy 323.197598 -205.079605)
			(xy 323.243884 -205.12169) (xy 323.284656 -205.169136) (xy 323.302376 -205.194916) (xy 323.309848 -205.205058)
			(xy 323.331964 -205.217052) (xy 323.34454 -205.217776) (xy 323.429376 -205.217776) (xy 323.441955 -205.21707)
			(xy 323.464075 -205.205067) (xy 323.47154 -205.194916) (xy 323.489265 -205.169143) (xy 323.53005 -205.121715)
			(xy 323.576343 -205.079645) (xy 323.627445 -205.04357) (xy 323.682585 -205.014032) (xy 323.740931 -204.991479)
			(xy 323.801601 -204.97625) (xy 323.863682 -204.968575) (xy 323.894958 -204.968094) (xy 323.927882 -204.968634)
			(xy 323.993178 -204.97714) (xy 324.05683 -204.994002) (xy 324.117773 -205.018937) (xy 324.174989 -205.05153)
			(xy 324.22752 -205.091235) (xy 324.274487 -205.137387) (xy 324.315104 -205.189215) (xy 324.332346 -205.217268)
			(xy 324.338696 -205.227936) (xy 324.35927 -205.24089) (xy 324.465696 -205.250542) (xy 324.488302 -205.241398)
			(xy 324.49643 -205.232254) (xy 324.514613 -205.212082) (xy 324.555742 -205.176617) (xy 324.601486 -205.147346)
			(xy 324.65092 -205.124861) (xy 324.703044 -205.109616) (xy 324.756804 -205.10192) (xy 324.783958 -205.101444)
			(xy 324.811209 -205.102) (xy 324.865158 -205.109751) (xy 324.917454 -205.125102) (xy 324.967034 -205.147739)
			(xy 325.012886 -205.177202) (xy 325.054079 -205.212892) (xy 325.089772 -205.25408) (xy 325.119241 -205.29993)
			(xy 325.141883 -205.349506) (xy 325.15724 -205.401801) (xy 325.164997 -205.455749) (xy 325.164997 -205.510251)
			(xy 325.15724 -205.564199) (xy 325.141883 -205.616494) (xy 325.119241 -205.66607) (xy 325.089772 -205.71192)
			(xy 325.054079 -205.753108) (xy 325.012886 -205.788798) (xy 324.967034 -205.818261) (xy 324.917454 -205.840898)
			(xy 324.865158 -205.856249) (xy 324.811209 -205.864) (xy 324.783958 -205.86446) (xy 324.756353 -205.863961)
			(xy 324.701719 -205.85601) (xy 324.648802 -205.840265) (xy 324.598707 -205.817057) (xy 324.552482 -205.786868)
			(xy 324.511092 -205.750331) (xy 324.492874 -205.729586) (xy 324.485 -205.720188) (xy 324.462394 -205.71079)
			(xy 324.355968 -205.718918) (xy 324.33514 -205.731618) (xy 324.328536 -205.742032) (xy 324.311179 -205.769482)
			(xy 324.270512 -205.82012) (xy 324.223724 -205.865165) (xy 324.171579 -205.903881) (xy 324.114926 -205.935639)
			(xy 324.054689 -205.95992) (xy 323.99185 -205.976329) (xy 323.927431 -205.984598) (xy 323.894958 -205.98511)
			(xy 323.863679 -205.984646) (xy 323.801593 -205.976988) (xy 323.740915 -205.961769) (xy 323.682564 -205.939219)
			(xy 323.62742 -205.909679) (xy 323.576319 -205.873594) (xy 323.530033 -205.831512) (xy 323.48926 -205.784067)
			(xy 323.47154 -205.758288) (xy 323.464059 -205.748154) (xy 323.44195 -205.736155) (xy 323.429376 -205.735428)
			(xy 323.34454 -205.735428) (xy 323.331969 -205.736182) (xy 323.309852 -205.748155) (xy 323.302376 -205.758288)
			(xy 323.284642 -205.784055) (xy 323.243858 -205.831483) (xy 323.197566 -205.873552) (xy 323.146465 -205.909628)
			(xy 323.091327 -205.939166) (xy 323.032983 -205.961721) (xy 322.972313 -205.976952) (xy 322.910234 -205.984628)
			(xy 322.878958 -205.98511) (xy 322.846999 -205.984602) (xy 322.783585 -205.976586) (xy 322.721676 -205.960685)
			(xy 322.662247 -205.937152) (xy 322.606237 -205.906356) (xy 322.554528 -205.868783) (xy 322.507935 -205.825026)
			(xy 322.467194 -205.775774) (xy 322.432946 -205.721805) (xy 322.405732 -205.663969) (xy 322.385981 -205.603179)
			(xy 322.374005 -205.540392) (xy 322.369991 -205.4766) (xy 322.215506 -205.4766) (xy 322.217344 -205.5058)
			(xy 322.213329 -205.569602) (xy 322.20135 -205.632398) (xy 322.181594 -205.693198) (xy 322.154374 -205.751041)
			(xy 322.120118 -205.805017) (xy 322.079368 -205.854274) (xy 322.032764 -205.898035) (xy 321.981044 -205.935609)
			(xy 321.925022 -205.966405) (xy 321.865582 -205.989936) (xy 321.803661 -206.005832) (xy 321.740236 -206.013841)
			(xy 321.708272 -206.01432) (xy 321.673869 -206.01372) (xy 321.605694 -206.004409) (xy 321.539395 -205.986)
			(xy 321.47618 -205.95883) (xy 321.4172 -205.923392) (xy 321.39001 -205.902306) (xy 321.382929 -205.897079)
			(xy 321.366296 -205.891365) (xy 321.357498 -205.89113) (xy 321.327526 -205.891638) (xy 321.318794 -205.892092)
			(xy 321.302427 -205.898211) (xy 321.295522 -205.903576) (xy 321.272493 -205.922564) (xy 321.222782 -205.955605)
			(xy 321.169545 -205.9826) (xy 321.113515 -206.003179) (xy 321.055462 -206.017059) (xy 320.996183 -206.02405)
			(xy 320.966338 -206.02448) (xy 320.933715 -206.024009) (xy 320.869005 -206.015667) (xy 320.805894 -205.999115)
			(xy 320.745419 -205.974625) (xy 320.688574 -205.9426) (xy 320.636293 -205.903565) (xy 320.612516 -205.881224)
			(xy 320.605658 -205.87462) (xy 320.58864 -205.867254) (xy 320.501264 -205.86446) (xy 320.483738 -205.870302)
			(xy 320.476372 -205.876652) (xy 320.453394 -205.895488) (xy 320.403833 -205.928263) (xy 320.350788 -205.955035)
			(xy 320.294983 -205.97544) (xy 320.23718 -205.989197) (xy 320.178167 -205.996121) (xy 320.148458 -205.99654)
			(xy 320.118438 -205.996109) (xy 320.05882 -205.989009) (xy 320.000453 -205.974938) (xy 319.944149 -205.954091)
			(xy 319.890692 -205.926757) (xy 319.840826 -205.893318) (xy 319.81775 -205.874112) (xy 319.810854 -205.868704)
			(xy 319.794492 -205.862463) (xy 319.785746 -205.86192) (xy 319.756028 -205.861158) (xy 319.747335 -205.861316)
			(xy 319.730839 -205.866766) (xy 319.72377 -205.871826) (xy 319.696901 -205.891996) (xy 319.63888 -205.925871)
			(xy 319.576903 -205.95181) (xy 319.51205 -205.96936) (xy 319.445451 -205.978215) (xy 319.411858 -205.97876)
			(xy 319.379896 -205.978352) (xy 319.316476 -205.970335) (xy 319.25456 -205.954433) (xy 319.195126 -205.930897)
			(xy 319.13911 -205.900098) (xy 319.087395 -205.862522) (xy 319.040798 -205.81876) (xy 319.000053 -205.769504)
			(xy 318.965802 -205.715529) (xy 318.938585 -205.657688) (xy 318.918832 -205.596891) (xy 318.906855 -205.534099)
			(xy 318.902841 -205.4703) (xy 316.811109 -205.4703) (xy 324.320746 -212.980016) (xy 326.752462 -212.980016)
			(xy 326.756491 -212.837695) (xy 326.768566 -212.69583) (xy 326.788647 -212.554876) (xy 326.81667 -212.415283)
			(xy 326.852546 -212.277499) (xy 326.89616 -212.141966) (xy 326.947372 -212.009117) (xy 327.006018 -211.879378)
			(xy 327.071909 -211.753165) (xy 327.144836 -211.630882) (xy 327.224564 -211.51292) (xy 327.310838 -211.399658)
			(xy 327.403382 -211.291459) (xy 327.501898 -211.188668) (xy 327.606073 -211.091616) (xy 327.715571 -211.000612)
			(xy 327.830042 -210.91595) (xy 327.94912 -210.837899) (xy 328.072423 -210.76671) (xy 328.199556 -210.702611)
			(xy 328.330112 -210.645807) (xy 328.463672 -210.596481) (xy 328.599809 -210.554789) (xy 328.738087 -210.520866)
			(xy 328.878062 -210.494821) (xy 329.019287 -210.476736) (xy 329.161308 -210.466671) (xy 329.303672 -210.464656)
			(xy 329.445922 -210.470699) (xy 329.587602 -210.484779) (xy 329.728258 -210.506853) (xy 329.86744 -210.536849)
			(xy 330.004702 -210.574671) (xy 330.139605 -210.620199) (xy 330.271716 -210.673285) (xy 330.400612 -210.733761)
			(xy 330.52588 -210.801432) (xy 330.647119 -210.876082) (xy 330.76394 -210.957471) (xy 330.87597 -211.045339)
			(xy 330.982849 -211.139405) (xy 331.084235 -211.239366) (xy 331.179804 -211.344904) (xy 331.269249 -211.455679)
			(xy 331.352283 -211.571337) (xy 331.428641 -211.691507) (xy 331.498078 -211.815805) (xy 331.560371 -211.943832)
			(xy 331.615322 -212.075179) (xy 331.662754 -212.209424) (xy 331.702515 -212.346137) (xy 331.734477 -212.484881)
			(xy 331.758539 -212.625211) (xy 331.774623 -212.766677) (xy 331.782679 -212.908827) (xy 331.783182 -212.980016)
			(xy 331.782679 -213.051205) (xy 331.774623 -213.193355) (xy 331.758539 -213.334821) (xy 331.734477 -213.475151)
			(xy 331.702515 -213.613895) (xy 331.662754 -213.750608) (xy 331.615322 -213.884853) (xy 331.560371 -214.0162)
			(xy 331.498078 -214.144227) (xy 331.428641 -214.268525) (xy 331.352283 -214.388695) (xy 331.269249 -214.504353)
			(xy 331.179804 -214.615128) (xy 331.084235 -214.720666) (xy 330.982849 -214.820627) (xy 330.87597 -214.914693)
			(xy 330.76394 -215.002561) (xy 330.647119 -215.08395) (xy 330.52588 -215.1586) (xy 330.400612 -215.226271)
			(xy 330.271716 -215.286747) (xy 330.139605 -215.339833) (xy 330.004702 -215.385361) (xy 329.86744 -215.423183)
			(xy 329.728258 -215.453179) (xy 329.587602 -215.475253) (xy 329.445922 -215.489333) (xy 329.303672 -215.495376)
			(xy 329.161308 -215.493361) (xy 329.019287 -215.483296) (xy 328.878062 -215.465211) (xy 328.738087 -215.439166)
			(xy 328.599809 -215.405243) (xy 328.463672 -215.363551) (xy 328.330112 -215.314225) (xy 328.199556 -215.257421)
			(xy 328.072423 -215.193322) (xy 327.94912 -215.122133) (xy 327.830042 -215.044082) (xy 327.715571 -214.95942)
			(xy 327.606073 -214.868416) (xy 327.501898 -214.771364) (xy 327.403382 -214.668573) (xy 327.310838 -214.560374)
			(xy 327.224564 -214.447112) (xy 327.144836 -214.32915) (xy 327.071909 -214.206867) (xy 327.006018 -214.080654)
			(xy 326.947372 -213.950915) (xy 326.89616 -213.818066) (xy 326.852546 -213.682533) (xy 326.81667 -213.544749)
			(xy 326.788647 -213.405156) (xy 326.768566 -213.264202) (xy 326.756491 -213.122337) (xy 326.752462 -212.980016)
			(xy 324.320746 -212.980016) (xy 332.227174 -220.886528) (xy 332.234019 -220.893927) (xy 332.241747 -220.912525)
			(xy 332.24216 -220.922596) (xy 332.24216 -221.301543) (xy 336.332312 -221.301543) (xy 336.332312 -221.248245)
			(xy 336.340255 -221.195541) (xy 336.355965 -221.144611) (xy 336.379091 -221.09659) (xy 336.409115 -221.052553)
			(xy 336.445367 -221.013482) (xy 336.487038 -220.980251) (xy 336.533196 -220.953602) (xy 336.58281 -220.93413)
			(xy 336.634772 -220.92227) (xy 336.687922 -220.918287) (xy 336.741072 -220.92227) (xy 336.793034 -220.93413)
			(xy 336.842648 -220.953602) (xy 336.888806 -220.980251) (xy 336.930477 -221.013482) (xy 336.966729 -221.052553)
			(xy 336.996753 -221.09659) (xy 337.019879 -221.144611) (xy 337.035589 -221.195541) (xy 337.043532 -221.248245)
			(xy 337.043861 -221.265852) (xy 337.271507 -221.265852) (xy 337.276988 -221.211975) (xy 337.290564 -221.159548)
			(xy 337.311922 -221.109782) (xy 337.34057 -221.063824) (xy 337.375846 -221.022734) (xy 337.416938 -220.987459)
			(xy 337.462898 -220.958814) (xy 337.512665 -220.937458) (xy 337.565092 -220.923884) (xy 337.61897 -220.918406)
			(xy 337.673057 -220.92115) (xy 337.726104 -220.932052) (xy 337.776888 -220.950861) (xy 337.824239 -220.977143)
			(xy 337.867064 -221.010292) (xy 337.904376 -221.049543) (xy 337.935313 -221.093992) (xy 337.959164 -221.142613)
			(xy 337.975377 -221.194285) (xy 337.983578 -221.247816) (xy 337.984084 -221.274894) (xy 337.983677 -221.299271)
			(xy 337.979739 -221.327959) (xy 340.334844 -221.327959) (xy 340.334844 -221.274661) (xy 340.342787 -221.221957)
			(xy 340.358497 -221.171027) (xy 340.381623 -221.123006) (xy 340.411647 -221.078969) (xy 340.447899 -221.039898)
			(xy 340.48957 -221.006667) (xy 340.535728 -220.980018) (xy 340.585342 -220.960546) (xy 340.637304 -220.948686)
			(xy 340.690454 -220.944703) (xy 340.743604 -220.948686) (xy 340.795566 -220.960546) (xy 340.84518 -220.980018)
			(xy 340.891338 -221.006667) (xy 340.933009 -221.039898) (xy 340.969261 -221.078969) (xy 340.999285 -221.123006)
			(xy 341.022411 -221.171027) (xy 341.038121 -221.221957) (xy 341.046064 -221.274661) (xy 341.046562 -221.30131)
			(xy 341.046064 -221.327959) (xy 341.223844 -221.327959) (xy 341.223844 -221.274661) (xy 341.231787 -221.221957)
			(xy 341.247497 -221.171027) (xy 341.270623 -221.123006) (xy 341.300647 -221.078969) (xy 341.336899 -221.039898)
			(xy 341.37857 -221.006667) (xy 341.424728 -220.980018) (xy 341.474342 -220.960546) (xy 341.526304 -220.948686)
			(xy 341.579454 -220.944703) (xy 341.632604 -220.948686) (xy 341.684566 -220.960546) (xy 341.73418 -220.980018)
			(xy 341.780338 -221.006667) (xy 341.822009 -221.039898) (xy 341.858261 -221.078969) (xy 341.888285 -221.123006)
			(xy 341.911411 -221.171027) (xy 341.927121 -221.221957) (xy 341.935064 -221.274661) (xy 341.935562 -221.30131)
			(xy 341.935064 -221.327959) (xy 342.112844 -221.327959) (xy 342.112844 -221.274661) (xy 342.120787 -221.221957)
			(xy 342.136497 -221.171027) (xy 342.159623 -221.123006) (xy 342.189647 -221.078969) (xy 342.225899 -221.039898)
			(xy 342.26757 -221.006667) (xy 342.313728 -220.980018) (xy 342.363342 -220.960546) (xy 342.415304 -220.948686)
			(xy 342.468454 -220.944703) (xy 342.521604 -220.948686) (xy 342.573566 -220.960546) (xy 342.62318 -220.980018)
			(xy 342.669338 -221.006667) (xy 342.711009 -221.039898) (xy 342.747261 -221.078969) (xy 342.777285 -221.123006)
			(xy 342.800411 -221.171027) (xy 342.816121 -221.221957) (xy 342.824064 -221.274661) (xy 342.824562 -221.30131)
			(xy 342.824064 -221.327959) (xy 342.816121 -221.380663) (xy 342.800411 -221.431593) (xy 342.777285 -221.479614)
			(xy 342.747261 -221.523651) (xy 342.711009 -221.562722) (xy 342.669338 -221.595953) (xy 342.62318 -221.622602)
			(xy 342.573566 -221.642074) (xy 342.521604 -221.653934) (xy 342.468454 -221.657918) (xy 342.415304 -221.653934)
			(xy 342.363342 -221.642074) (xy 342.313728 -221.622602) (xy 342.26757 -221.595953) (xy 342.225899 -221.562722)
			(xy 342.189647 -221.523651) (xy 342.159623 -221.479614) (xy 342.136497 -221.431593) (xy 342.120787 -221.380663)
			(xy 342.112844 -221.327959) (xy 341.935064 -221.327959) (xy 341.927121 -221.380663) (xy 341.911411 -221.431593)
			(xy 341.888285 -221.479614) (xy 341.858261 -221.523651) (xy 341.822009 -221.562722) (xy 341.780338 -221.595953)
			(xy 341.73418 -221.622602) (xy 341.684566 -221.642074) (xy 341.632604 -221.653934) (xy 341.579454 -221.657918)
			(xy 341.526304 -221.653934) (xy 341.474342 -221.642074) (xy 341.424728 -221.622602) (xy 341.37857 -221.595953)
			(xy 341.336899 -221.562722) (xy 341.300647 -221.523651) (xy 341.270623 -221.479614) (xy 341.247497 -221.431593)
			(xy 341.231787 -221.380663) (xy 341.223844 -221.327959) (xy 341.046064 -221.327959) (xy 341.038121 -221.380663)
			(xy 341.022411 -221.431593) (xy 340.999285 -221.479614) (xy 340.969261 -221.523651) (xy 340.933009 -221.562722)
			(xy 340.891338 -221.595953) (xy 340.84518 -221.622602) (xy 340.795566 -221.642074) (xy 340.743604 -221.653934)
			(xy 340.690454 -221.657918) (xy 340.637304 -221.653934) (xy 340.585342 -221.642074) (xy 340.535728 -221.622602)
			(xy 340.48957 -221.595953) (xy 340.447899 -221.562722) (xy 340.411647 -221.523651) (xy 340.381623 -221.479614)
			(xy 340.358497 -221.431593) (xy 340.342787 -221.380663) (xy 340.334844 -221.327959) (xy 337.979739 -221.327959)
			(xy 337.977046 -221.347573) (xy 337.970876 -221.37116) (xy 337.967467 -221.384747) (xy 337.967481 -221.412752)
			(xy 337.975103 -221.439699) (xy 337.989761 -221.463561) (xy 338.010351 -221.482543) (xy 338.035324 -221.495216)
			(xy 338.062802 -221.500626) (xy 338.076794 -221.499938) (xy 338.101178 -221.498922) (xy 338.126001 -221.499354)
			(xy 338.174992 -221.507382) (xy 338.22204 -221.52323) (xy 338.265903 -221.546481) (xy 338.305428 -221.576522)
			(xy 338.339571 -221.612562) (xy 338.367434 -221.65365) (xy 338.388283 -221.698705) (xy 338.401569 -221.746539)
			(xy 338.40694 -221.795893) (xy 338.404256 -221.845465) (xy 338.393588 -221.893951) (xy 338.375217 -221.940071)
			(xy 338.349625 -221.982612) (xy 338.317489 -222.020452) (xy 338.279654 -222.052595) (xy 338.237118 -222.078193)
			(xy 338.191 -222.096573) (xy 338.142517 -222.107249) (xy 338.092945 -222.109942) (xy 338.043591 -222.104578)
			(xy 337.995754 -222.091301) (xy 337.950695 -222.07046) (xy 337.909602 -222.042604) (xy 337.873557 -222.008466)
			(xy 337.843509 -221.968947) (xy 337.820251 -221.925087) (xy 337.804395 -221.878043) (xy 337.796358 -221.829052)
			(xy 337.79587 -221.80423) (xy 337.79605 -221.789596) (xy 337.798844 -221.760463) (xy 337.801458 -221.746064)
			(xy 337.803696 -221.732232) (xy 337.80144 -221.704316) (xy 337.791668 -221.67807) (xy 337.775116 -221.655477)
			(xy 337.753038 -221.638245) (xy 337.727101 -221.627678) (xy 337.699267 -221.624574) (xy 337.68538 -221.62643)
			(xy 337.671128 -221.628594) (xy 337.642391 -221.63088) (xy 337.627976 -221.631002) (xy 337.600898 -221.630477)
			(xy 337.547367 -221.622273) (xy 337.495696 -221.606057) (xy 337.447076 -221.582204) (xy 337.402629 -221.551264)
			(xy 337.363379 -221.513951) (xy 337.330233 -221.471124) (xy 337.303953 -221.423772) (xy 337.285147 -221.372986)
			(xy 337.274248 -221.319939) (xy 337.271507 -221.265852) (xy 337.043861 -221.265852) (xy 337.04403 -221.274894)
			(xy 337.043532 -221.301543) (xy 337.035589 -221.354247) (xy 337.019879 -221.405177) (xy 336.996753 -221.453198)
			(xy 336.966729 -221.497235) (xy 336.930477 -221.536306) (xy 336.888806 -221.569537) (xy 336.842648 -221.596186)
			(xy 336.793034 -221.615658) (xy 336.741072 -221.627518) (xy 336.687922 -221.631502) (xy 336.634772 -221.627518)
			(xy 336.58281 -221.615658) (xy 336.533196 -221.596186) (xy 336.487038 -221.569537) (xy 336.445367 -221.536306)
			(xy 336.409115 -221.497235) (xy 336.379091 -221.453198) (xy 336.355965 -221.405177) (xy 336.340255 -221.354247)
			(xy 336.332312 -221.301543) (xy 332.24216 -221.301543) (xy 332.24216 -221.414594) (xy 332.242811 -221.426526)
			(xy 332.25355 -221.44784) (xy 332.262734 -221.455488) (xy 332.338172 -221.511368) (xy 332.36154 -221.515432)
			(xy 332.373224 -221.511876) (xy 332.394695 -221.50585) (xy 332.438812 -221.499352) (xy 332.461108 -221.498922)
			(xy 332.465426 -221.498922) (xy 332.489194 -221.499713) (xy 332.536063 -221.507751) (xy 332.58112 -221.522958)
			(xy 332.623273 -221.544967) (xy 332.661505 -221.573246) (xy 332.69489 -221.607111) (xy 332.72262 -221.645742)
			(xy 332.744026 -221.688205) (xy 332.758589 -221.733474) (xy 332.765957 -221.780453) (xy 332.766416 -221.80423)
			(xy 332.765943 -221.82822) (xy 332.758433 -221.875608) (xy 332.743603 -221.921239) (xy 332.721818 -221.963988)
			(xy 332.693615 -222.002803) (xy 332.659686 -222.036729) (xy 332.620869 -222.06493) (xy 332.578119 -222.086712)
			(xy 332.532487 -222.101539) (xy 332.485098 -222.109045) (xy 332.461108 -222.109538) (xy 332.438808 -222.109154)
			(xy 332.394686 -222.102652) (xy 332.373224 -222.096584) (xy 332.36154 -222.093028) (xy 332.338172 -222.097092)
			(xy 332.262734 -222.152972) (xy 332.253513 -222.160586) (xy 332.242787 -222.181923) (xy 332.24216 -222.193866)
			(xy 332.24216 -222.417894) (xy 332.242222 -222.4215) (xy 332.243241 -222.428639) (xy 332.244192 -222.432118)
			(xy 332.250034 -222.45193) (xy 332.253336 -222.457518) (xy 332.266403 -222.480449) (xy 332.285301 -222.529724)
			(xy 332.295438 -222.581515) (xy 332.296516 -222.607886) (xy 332.296516 -222.612204) (xy 332.296516 -222.614236)
			(xy 333.565258 -222.614236) (xy 333.569218 -222.565182) (xy 333.580995 -222.517398) (xy 333.600286 -222.472122)
			(xy 333.626589 -222.430526) (xy 333.659224 -222.393689) (xy 333.697345 -222.362564) (xy 333.739966 -222.337957)
			(xy 333.785982 -222.320505) (xy 333.834201 -222.310661) (xy 333.883376 -222.30868) (xy 333.932231 -222.314612)
			(xy 333.979502 -222.328304) (xy 334.023964 -222.349402) (xy 334.064467 -222.377358) (xy 334.09996 -222.41145)
			(xy 334.129525 -222.450794) (xy 334.152396 -222.494371) (xy 334.16798 -222.541052) (xy 334.175875 -222.589629)
			(xy 334.17637 -222.614236) (xy 334.505312 -222.614236) (xy 334.509272 -222.565182) (xy 334.521049 -222.517398)
			(xy 334.54034 -222.472122) (xy 334.566643 -222.430526) (xy 334.599278 -222.393689) (xy 334.637399 -222.362564)
			(xy 334.68002 -222.337957) (xy 334.726036 -222.320505) (xy 334.774255 -222.310661) (xy 334.82343 -222.30868)
			(xy 334.872285 -222.314612) (xy 334.919556 -222.328304) (xy 334.964018 -222.349402) (xy 335.004521 -222.377358)
			(xy 335.040014 -222.41145) (xy 335.069579 -222.450794) (xy 335.09245 -222.494371) (xy 335.108034 -222.541052)
			(xy 335.115929 -222.589629) (xy 335.116424 -222.614236) (xy 335.445366 -222.614236) (xy 335.449326 -222.565182)
			(xy 335.461103 -222.517398) (xy 335.480394 -222.472122) (xy 335.506697 -222.430526) (xy 335.539332 -222.393689)
			(xy 335.577453 -222.362564) (xy 335.620074 -222.337957) (xy 335.66609 -222.320505) (xy 335.714309 -222.310661)
			(xy 335.763484 -222.30868) (xy 335.812339 -222.314612) (xy 335.85961 -222.328304) (xy 335.904072 -222.349402)
			(xy 335.944575 -222.377358) (xy 335.980068 -222.41145) (xy 336.009633 -222.450794) (xy 336.032504 -222.494371)
			(xy 336.048088 -222.541052) (xy 336.055983 -222.589629) (xy 336.056478 -222.614236) (xy 336.38542 -222.614236)
			(xy 336.38938 -222.565182) (xy 336.401157 -222.517398) (xy 336.420448 -222.472122) (xy 336.446751 -222.430526)
			(xy 336.479386 -222.393689) (xy 336.517507 -222.362564) (xy 336.560128 -222.337957) (xy 336.606144 -222.320505)
			(xy 336.654363 -222.310661) (xy 336.703538 -222.30868) (xy 336.752393 -222.314612) (xy 336.799664 -222.328304)
			(xy 336.844126 -222.349402) (xy 336.884629 -222.377358) (xy 336.920122 -222.41145) (xy 336.949687 -222.450794)
			(xy 336.972558 -222.494371) (xy 336.988142 -222.541052) (xy 336.996037 -222.589629) (xy 336.996532 -222.614236)
			(xy 337.32522 -222.614236) (xy 337.32918 -222.565182) (xy 337.340957 -222.517398) (xy 337.360248 -222.472122)
			(xy 337.386551 -222.430526) (xy 337.419186 -222.393689) (xy 337.457307 -222.362564) (xy 337.499928 -222.337957)
			(xy 337.545944 -222.320505) (xy 337.594163 -222.310661) (xy 337.643338 -222.30868) (xy 337.692193 -222.314612)
			(xy 337.739464 -222.328304) (xy 337.783926 -222.349402) (xy 337.824429 -222.377358) (xy 337.859922 -222.41145)
			(xy 337.889487 -222.450794) (xy 337.912358 -222.494371) (xy 337.927942 -222.541052) (xy 337.935837 -222.589629)
			(xy 337.936332 -222.614236) (xy 338.265274 -222.614236) (xy 338.269234 -222.565182) (xy 338.281011 -222.517398)
			(xy 338.300302 -222.472122) (xy 338.326605 -222.430526) (xy 338.35924 -222.393689) (xy 338.397361 -222.362564)
			(xy 338.439982 -222.337957) (xy 338.485998 -222.320505) (xy 338.534217 -222.310661) (xy 338.583392 -222.30868)
			(xy 338.632247 -222.314612) (xy 338.679518 -222.328304) (xy 338.72398 -222.349402) (xy 338.764483 -222.377358)
			(xy 338.799976 -222.41145) (xy 338.829541 -222.450794) (xy 338.852412 -222.494371) (xy 338.867996 -222.541052)
			(xy 338.875891 -222.589629) (xy 338.876386 -222.614236) (xy 339.205328 -222.614236) (xy 339.209288 -222.565182)
			(xy 339.221065 -222.517398) (xy 339.240356 -222.472122) (xy 339.266659 -222.430526) (xy 339.299294 -222.393689)
			(xy 339.337415 -222.362564) (xy 339.380036 -222.337957) (xy 339.426052 -222.320505) (xy 339.474271 -222.310661)
			(xy 339.523446 -222.30868) (xy 339.572301 -222.314612) (xy 339.619572 -222.328304) (xy 339.664034 -222.349402)
			(xy 339.704537 -222.377358) (xy 339.74003 -222.41145) (xy 339.769595 -222.450794) (xy 339.792466 -222.494371)
			(xy 339.80805 -222.541052) (xy 339.815945 -222.589629) (xy 339.81644 -222.614236) (xy 340.145382 -222.614236)
			(xy 340.149342 -222.565182) (xy 340.161119 -222.517398) (xy 340.18041 -222.472122) (xy 340.206713 -222.430526)
			(xy 340.239348 -222.393689) (xy 340.277469 -222.362564) (xy 340.32009 -222.337957) (xy 340.366106 -222.320505)
			(xy 340.414325 -222.310661) (xy 340.4635 -222.30868) (xy 340.512355 -222.314612) (xy 340.559626 -222.328304)
			(xy 340.604088 -222.349402) (xy 340.644591 -222.377358) (xy 340.680084 -222.41145) (xy 340.709649 -222.450794)
			(xy 340.73252 -222.494371) (xy 340.748104 -222.541052) (xy 340.755999 -222.589629) (xy 340.756494 -222.614236)
			(xy 341.085182 -222.614236) (xy 341.089142 -222.565182) (xy 341.100919 -222.517398) (xy 341.12021 -222.472122)
			(xy 341.146513 -222.430526) (xy 341.179148 -222.393689) (xy 341.217269 -222.362564) (xy 341.25989 -222.337957)
			(xy 341.305906 -222.320505) (xy 341.354125 -222.310661) (xy 341.4033 -222.30868) (xy 341.452155 -222.314612)
			(xy 341.499426 -222.328304) (xy 341.543888 -222.349402) (xy 341.584391 -222.377358) (xy 341.619884 -222.41145)
			(xy 341.649449 -222.450794) (xy 341.67232 -222.494371) (xy 341.687904 -222.541052) (xy 341.695799 -222.589629)
			(xy 341.696294 -222.614236) (xy 342.025236 -222.614236) (xy 342.029196 -222.565182) (xy 342.040973 -222.517398)
			(xy 342.060264 -222.472122) (xy 342.086567 -222.430526) (xy 342.119202 -222.393689) (xy 342.157323 -222.362564)
			(xy 342.199944 -222.337957) (xy 342.24596 -222.320505) (xy 342.294179 -222.310661) (xy 342.343354 -222.30868)
			(xy 342.392209 -222.314612) (xy 342.43948 -222.328304) (xy 342.483942 -222.349402) (xy 342.524445 -222.377358)
			(xy 342.559938 -222.41145) (xy 342.589503 -222.450794) (xy 342.612374 -222.494371) (xy 342.627958 -222.541052)
			(xy 342.635853 -222.589629) (xy 342.636348 -222.614236) (xy 342.96529 -222.614236) (xy 342.96925 -222.565182)
			(xy 342.981027 -222.517398) (xy 343.000318 -222.472122) (xy 343.026621 -222.430526) (xy 343.059256 -222.393689)
			(xy 343.097377 -222.362564) (xy 343.139998 -222.337957) (xy 343.186014 -222.320505) (xy 343.234233 -222.310661)
			(xy 343.283408 -222.30868) (xy 343.332263 -222.314612) (xy 343.379534 -222.328304) (xy 343.423996 -222.349402)
			(xy 343.464499 -222.377358) (xy 343.499992 -222.41145) (xy 343.529557 -222.450794) (xy 343.552428 -222.494371)
			(xy 343.568012 -222.541052) (xy 343.575907 -222.589629) (xy 343.576402 -222.614236) (xy 343.575907 -222.638843)
			(xy 343.568012 -222.68742) (xy 343.552428 -222.734101) (xy 343.529557 -222.777678) (xy 343.499992 -222.817022)
			(xy 343.464499 -222.851114) (xy 343.423996 -222.87907) (xy 343.379534 -222.900168) (xy 343.332263 -222.91386)
			(xy 343.283408 -222.919792) (xy 343.234233 -222.917811) (xy 343.186014 -222.907967) (xy 343.139998 -222.890515)
			(xy 343.097377 -222.865908) (xy 343.059256 -222.834783) (xy 343.026621 -222.797946) (xy 343.000318 -222.75635)
			(xy 342.981027 -222.711074) (xy 342.96925 -222.66329) (xy 342.96529 -222.614236) (xy 342.636348 -222.614236)
			(xy 342.635853 -222.638843) (xy 342.627958 -222.68742) (xy 342.612374 -222.734101) (xy 342.589503 -222.777678)
			(xy 342.559938 -222.817022) (xy 342.524445 -222.851114) (xy 342.483942 -222.87907) (xy 342.43948 -222.900168)
			(xy 342.392209 -222.91386) (xy 342.343354 -222.919792) (xy 342.294179 -222.917811) (xy 342.24596 -222.907967)
			(xy 342.199944 -222.890515) (xy 342.157323 -222.865908) (xy 342.119202 -222.834783) (xy 342.086567 -222.797946)
			(xy 342.060264 -222.75635) (xy 342.040973 -222.711074) (xy 342.029196 -222.66329) (xy 342.025236 -222.614236)
			(xy 341.696294 -222.614236) (xy 341.695799 -222.638843) (xy 341.687904 -222.68742) (xy 341.67232 -222.734101)
			(xy 341.649449 -222.777678) (xy 341.619884 -222.817022) (xy 341.584391 -222.851114) (xy 341.543888 -222.87907)
			(xy 341.499426 -222.900168) (xy 341.452155 -222.91386) (xy 341.4033 -222.919792) (xy 341.354125 -222.917811)
			(xy 341.305906 -222.907967) (xy 341.25989 -222.890515) (xy 341.217269 -222.865908) (xy 341.179148 -222.834783)
			(xy 341.146513 -222.797946) (xy 341.12021 -222.75635) (xy 341.100919 -222.711074) (xy 341.089142 -222.66329)
			(xy 341.085182 -222.614236) (xy 340.756494 -222.614236) (xy 340.755999 -222.638843) (xy 340.748104 -222.68742)
			(xy 340.73252 -222.734101) (xy 340.709649 -222.777678) (xy 340.680084 -222.817022) (xy 340.644591 -222.851114)
			(xy 340.604088 -222.87907) (xy 340.559626 -222.900168) (xy 340.512355 -222.91386) (xy 340.4635 -222.919792)
			(xy 340.414325 -222.917811) (xy 340.366106 -222.907967) (xy 340.32009 -222.890515) (xy 340.277469 -222.865908)
			(xy 340.239348 -222.834783) (xy 340.206713 -222.797946) (xy 340.18041 -222.75635) (xy 340.161119 -222.711074)
			(xy 340.149342 -222.66329) (xy 340.145382 -222.614236) (xy 339.81644 -222.614236) (xy 339.815945 -222.638843)
			(xy 339.80805 -222.68742) (xy 339.792466 -222.734101) (xy 339.769595 -222.777678) (xy 339.74003 -222.817022)
			(xy 339.704537 -222.851114) (xy 339.664034 -222.87907) (xy 339.619572 -222.900168) (xy 339.572301 -222.91386)
			(xy 339.523446 -222.919792) (xy 339.474271 -222.917811) (xy 339.426052 -222.907967) (xy 339.380036 -222.890515)
			(xy 339.337415 -222.865908) (xy 339.299294 -222.834783) (xy 339.266659 -222.797946) (xy 339.240356 -222.75635)
			(xy 339.221065 -222.711074) (xy 339.209288 -222.66329) (xy 339.205328 -222.614236) (xy 338.876386 -222.614236)
			(xy 338.875891 -222.638843) (xy 338.867996 -222.68742) (xy 338.852412 -222.734101) (xy 338.829541 -222.777678)
			(xy 338.799976 -222.817022) (xy 338.764483 -222.851114) (xy 338.72398 -222.87907) (xy 338.679518 -222.900168)
			(xy 338.632247 -222.91386) (xy 338.583392 -222.919792) (xy 338.534217 -222.917811) (xy 338.485998 -222.907967)
			(xy 338.439982 -222.890515) (xy 338.397361 -222.865908) (xy 338.35924 -222.834783) (xy 338.326605 -222.797946)
			(xy 338.300302 -222.75635) (xy 338.281011 -222.711074) (xy 338.269234 -222.66329) (xy 338.265274 -222.614236)
			(xy 337.936332 -222.614236) (xy 337.935837 -222.638843) (xy 337.927942 -222.68742) (xy 337.912358 -222.734101)
			(xy 337.889487 -222.777678) (xy 337.859922 -222.817022) (xy 337.824429 -222.851114) (xy 337.783926 -222.87907)
			(xy 337.739464 -222.900168) (xy 337.692193 -222.91386) (xy 337.643338 -222.919792) (xy 337.594163 -222.917811)
			(xy 337.545944 -222.907967) (xy 337.499928 -222.890515) (xy 337.457307 -222.865908) (xy 337.419186 -222.834783)
			(xy 337.386551 -222.797946) (xy 337.360248 -222.75635) (xy 337.340957 -222.711074) (xy 337.32918 -222.66329)
			(xy 337.32522 -222.614236) (xy 336.996532 -222.614236) (xy 336.996037 -222.638843) (xy 336.988142 -222.68742)
			(xy 336.972558 -222.734101) (xy 336.949687 -222.777678) (xy 336.920122 -222.817022) (xy 336.884629 -222.851114)
			(xy 336.844126 -222.87907) (xy 336.799664 -222.900168) (xy 336.752393 -222.91386) (xy 336.703538 -222.919792)
			(xy 336.654363 -222.917811) (xy 336.606144 -222.907967) (xy 336.560128 -222.890515) (xy 336.517507 -222.865908)
			(xy 336.479386 -222.834783) (xy 336.446751 -222.797946) (xy 336.420448 -222.75635) (xy 336.401157 -222.711074)
			(xy 336.38938 -222.66329) (xy 336.38542 -222.614236) (xy 336.056478 -222.614236) (xy 336.055983 -222.638843)
			(xy 336.048088 -222.68742) (xy 336.032504 -222.734101) (xy 336.009633 -222.777678) (xy 335.980068 -222.817022)
			(xy 335.944575 -222.851114) (xy 335.904072 -222.87907) (xy 335.85961 -222.900168) (xy 335.812339 -222.91386)
			(xy 335.763484 -222.919792) (xy 335.714309 -222.917811) (xy 335.66609 -222.907967) (xy 335.620074 -222.890515)
			(xy 335.577453 -222.865908) (xy 335.539332 -222.834783) (xy 335.506697 -222.797946) (xy 335.480394 -222.75635)
			(xy 335.461103 -222.711074) (xy 335.449326 -222.66329) (xy 335.445366 -222.614236) (xy 335.116424 -222.614236)
			(xy 335.115929 -222.638843) (xy 335.108034 -222.68742) (xy 335.09245 -222.734101) (xy 335.069579 -222.777678)
			(xy 335.040014 -222.817022) (xy 335.004521 -222.851114) (xy 334.964018 -222.87907) (xy 334.919556 -222.900168)
			(xy 334.872285 -222.91386) (xy 334.82343 -222.919792) (xy 334.774255 -222.917811) (xy 334.726036 -222.907967)
			(xy 334.68002 -222.890515) (xy 334.637399 -222.865908) (xy 334.599278 -222.834783) (xy 334.566643 -222.797946)
			(xy 334.54034 -222.75635) (xy 334.521049 -222.711074) (xy 334.509272 -222.66329) (xy 334.505312 -222.614236)
			(xy 334.17637 -222.614236) (xy 334.175875 -222.638843) (xy 334.16798 -222.68742) (xy 334.152396 -222.734101)
			(xy 334.129525 -222.777678) (xy 334.09996 -222.817022) (xy 334.064467 -222.851114) (xy 334.023964 -222.87907)
			(xy 333.979502 -222.900168) (xy 333.932231 -222.91386) (xy 333.883376 -222.919792) (xy 333.834201 -222.917811)
			(xy 333.785982 -222.907967) (xy 333.739966 -222.890515) (xy 333.697345 -222.865908) (xy 333.659224 -222.834783)
			(xy 333.626589 -222.797946) (xy 333.600286 -222.75635) (xy 333.580995 -222.711074) (xy 333.569218 -222.66329)
			(xy 333.565258 -222.614236) (xy 332.296516 -222.614236) (xy 332.295966 -222.641684) (xy 332.286206 -222.695704)
			(xy 332.266934 -222.747105) (xy 332.253336 -222.770954) (xy 332.250034 -222.776542) (xy 332.244192 -222.796354)
			(xy 332.243242 -222.799833) (xy 332.24222 -222.806972) (xy 332.24216 -222.810578) (xy 332.24216 -223.034606)
			(xy 332.242814 -223.046537) (xy 332.253556 -223.067846) (xy 332.262734 -223.0755) (xy 332.338172 -223.13138)
			(xy 332.36154 -223.135444) (xy 332.373224 -223.131888) (xy 332.394695 -223.125862) (xy 332.438812 -223.119363)
			(xy 332.461108 -223.118934) (xy 332.465426 -223.118934) (xy 332.489194 -223.119725) (xy 332.536062 -223.127763)
			(xy 332.581118 -223.14297) (xy 332.623271 -223.16498) (xy 332.661501 -223.193259) (xy 332.694885 -223.227123)
			(xy 332.722614 -223.265755) (xy 332.744018 -223.308218) (xy 332.75858 -223.353487) (xy 332.765946 -223.400465)
			(xy 332.766416 -223.424242) (xy 333.095358 -223.424242) (xy 333.099318 -223.375188) (xy 333.111095 -223.327404)
			(xy 333.130386 -223.282128) (xy 333.156689 -223.240532) (xy 333.189324 -223.203695) (xy 333.227445 -223.17257)
			(xy 333.270066 -223.147963) (xy 333.316082 -223.130511) (xy 333.364301 -223.120667) (xy 333.413476 -223.118686)
			(xy 333.462331 -223.124618) (xy 333.509602 -223.13831) (xy 333.554064 -223.159408) (xy 333.594567 -223.187364)
			(xy 333.63006 -223.221456) (xy 333.659625 -223.2608) (xy 333.682496 -223.304377) (xy 333.69808 -223.351058)
			(xy 333.705975 -223.399635) (xy 333.70647 -223.424242) (xy 334.035412 -223.424242) (xy 334.039372 -223.375188)
			(xy 334.051149 -223.327404) (xy 334.07044 -223.282128) (xy 334.096743 -223.240532) (xy 334.129378 -223.203695)
			(xy 334.167499 -223.17257) (xy 334.21012 -223.147963) (xy 334.256136 -223.130511) (xy 334.304355 -223.120667)
			(xy 334.35353 -223.118686) (xy 334.402385 -223.124618) (xy 334.449656 -223.13831) (xy 334.494118 -223.159408)
			(xy 334.534621 -223.187364) (xy 334.570114 -223.221456) (xy 334.599679 -223.2608) (xy 334.62255 -223.304377)
			(xy 334.638134 -223.351058) (xy 334.646029 -223.399635) (xy 334.646524 -223.424242) (xy 334.975212 -223.424242)
			(xy 334.979172 -223.375188) (xy 334.990949 -223.327404) (xy 335.01024 -223.282128) (xy 335.036543 -223.240532)
			(xy 335.069178 -223.203695) (xy 335.107299 -223.17257) (xy 335.14992 -223.147963) (xy 335.195936 -223.130511)
			(xy 335.244155 -223.120667) (xy 335.29333 -223.118686) (xy 335.342185 -223.124618) (xy 335.389456 -223.13831)
			(xy 335.433918 -223.159408) (xy 335.474421 -223.187364) (xy 335.509914 -223.221456) (xy 335.539479 -223.2608)
			(xy 335.56235 -223.304377) (xy 335.577934 -223.351058) (xy 335.585829 -223.399635) (xy 335.586324 -223.424242)
			(xy 335.915266 -223.424242) (xy 335.919226 -223.375188) (xy 335.931003 -223.327404) (xy 335.950294 -223.282128)
			(xy 335.976597 -223.240532) (xy 336.009232 -223.203695) (xy 336.047353 -223.17257) (xy 336.089974 -223.147963)
			(xy 336.13599 -223.130511) (xy 336.184209 -223.120667) (xy 336.233384 -223.118686) (xy 336.282239 -223.124618)
			(xy 336.32951 -223.13831) (xy 336.373972 -223.159408) (xy 336.414475 -223.187364) (xy 336.449968 -223.221456)
			(xy 336.479533 -223.2608) (xy 336.502404 -223.304377) (xy 336.517988 -223.351058) (xy 336.525883 -223.399635)
			(xy 336.526378 -223.424242) (xy 336.85532 -223.424242) (xy 336.85928 -223.375188) (xy 336.871057 -223.327404)
			(xy 336.890348 -223.282128) (xy 336.916651 -223.240532) (xy 336.949286 -223.203695) (xy 336.987407 -223.17257)
			(xy 337.030028 -223.147963) (xy 337.076044 -223.130511) (xy 337.124263 -223.120667) (xy 337.173438 -223.118686)
			(xy 337.222293 -223.124618) (xy 337.269564 -223.13831) (xy 337.314026 -223.159408) (xy 337.354529 -223.187364)
			(xy 337.390022 -223.221456) (xy 337.419587 -223.2608) (xy 337.442458 -223.304377) (xy 337.458042 -223.351058)
			(xy 337.465937 -223.399635) (xy 337.466432 -223.424242) (xy 337.795374 -223.424242) (xy 337.799334 -223.375188)
			(xy 337.811111 -223.327404) (xy 337.830402 -223.282128) (xy 337.856705 -223.240532) (xy 337.88934 -223.203695)
			(xy 337.927461 -223.17257) (xy 337.970082 -223.147963) (xy 338.016098 -223.130511) (xy 338.064317 -223.120667)
			(xy 338.113492 -223.118686) (xy 338.162347 -223.124618) (xy 338.209618 -223.13831) (xy 338.25408 -223.159408)
			(xy 338.294583 -223.187364) (xy 338.330076 -223.221456) (xy 338.359641 -223.2608) (xy 338.382512 -223.304377)
			(xy 338.398096 -223.351058) (xy 338.405991 -223.399635) (xy 338.406486 -223.424242) (xy 338.735174 -223.424242)
			(xy 338.739134 -223.375188) (xy 338.750911 -223.327404) (xy 338.770202 -223.282128) (xy 338.796505 -223.240532)
			(xy 338.82914 -223.203695) (xy 338.867261 -223.17257) (xy 338.909882 -223.147963) (xy 338.955898 -223.130511)
			(xy 339.004117 -223.120667) (xy 339.053292 -223.118686) (xy 339.102147 -223.124618) (xy 339.149418 -223.13831)
			(xy 339.19388 -223.159408) (xy 339.234383 -223.187364) (xy 339.269876 -223.221456) (xy 339.299441 -223.2608)
			(xy 339.322312 -223.304377) (xy 339.337896 -223.351058) (xy 339.345791 -223.399635) (xy 339.346286 -223.424242)
			(xy 341.555336 -223.424242) (xy 341.559296 -223.375188) (xy 341.571073 -223.327404) (xy 341.590364 -223.282128)
			(xy 341.616667 -223.240532) (xy 341.649302 -223.203695) (xy 341.687423 -223.17257) (xy 341.730044 -223.147963)
			(xy 341.77606 -223.130511) (xy 341.824279 -223.120667) (xy 341.873454 -223.118686) (xy 341.922309 -223.124618)
			(xy 341.96958 -223.13831) (xy 342.014042 -223.159408) (xy 342.054545 -223.187364) (xy 342.090038 -223.221456)
			(xy 342.119603 -223.2608) (xy 342.142474 -223.304377) (xy 342.158058 -223.351058) (xy 342.165953 -223.399635)
			(xy 342.166448 -223.424242) (xy 342.49539 -223.424242) (xy 342.49935 -223.375188) (xy 342.511127 -223.327404)
			(xy 342.530418 -223.282128) (xy 342.556721 -223.240532) (xy 342.589356 -223.203695) (xy 342.627477 -223.17257)
			(xy 342.670098 -223.147963) (xy 342.716114 -223.130511) (xy 342.764333 -223.120667) (xy 342.813508 -223.118686)
			(xy 342.862363 -223.124618) (xy 342.909634 -223.13831) (xy 342.954096 -223.159408) (xy 342.994599 -223.187364)
			(xy 343.030092 -223.221456) (xy 343.059657 -223.2608) (xy 343.082528 -223.304377) (xy 343.098112 -223.351058)
			(xy 343.106007 -223.399635) (xy 343.106502 -223.424242) (xy 343.106007 -223.448849) (xy 343.098112 -223.497426)
			(xy 343.082528 -223.544107) (xy 343.059657 -223.587684) (xy 343.030092 -223.627028) (xy 342.994599 -223.66112)
			(xy 342.954096 -223.689076) (xy 342.909634 -223.710174) (xy 342.862363 -223.723866) (xy 342.813508 -223.729798)
			(xy 342.764333 -223.727817) (xy 342.716114 -223.717973) (xy 342.670098 -223.700521) (xy 342.627477 -223.675914)
			(xy 342.589356 -223.644789) (xy 342.556721 -223.607952) (xy 342.530418 -223.566356) (xy 342.511127 -223.52108)
			(xy 342.49935 -223.473296) (xy 342.49539 -223.424242) (xy 342.166448 -223.424242) (xy 342.165953 -223.448849)
			(xy 342.158058 -223.497426) (xy 342.142474 -223.544107) (xy 342.119603 -223.587684) (xy 342.090038 -223.627028)
			(xy 342.054545 -223.66112) (xy 342.014042 -223.689076) (xy 341.96958 -223.710174) (xy 341.922309 -223.723866)
			(xy 341.873454 -223.729798) (xy 341.824279 -223.727817) (xy 341.77606 -223.717973) (xy 341.730044 -223.700521)
			(xy 341.687423 -223.675914) (xy 341.649302 -223.644789) (xy 341.616667 -223.607952) (xy 341.590364 -223.566356)
			(xy 341.571073 -223.52108) (xy 341.559296 -223.473296) (xy 341.555336 -223.424242) (xy 339.346286 -223.424242)
			(xy 339.345791 -223.448849) (xy 339.337896 -223.497426) (xy 339.322312 -223.544107) (xy 339.299441 -223.587684)
			(xy 339.269876 -223.627028) (xy 339.234383 -223.66112) (xy 339.19388 -223.689076) (xy 339.149418 -223.710174)
			(xy 339.102147 -223.723866) (xy 339.053292 -223.729798) (xy 339.004117 -223.727817) (xy 338.955898 -223.717973)
			(xy 338.909882 -223.700521) (xy 338.867261 -223.675914) (xy 338.82914 -223.644789) (xy 338.796505 -223.607952)
			(xy 338.770202 -223.566356) (xy 338.750911 -223.52108) (xy 338.739134 -223.473296) (xy 338.735174 -223.424242)
			(xy 338.406486 -223.424242) (xy 338.405991 -223.448849) (xy 338.398096 -223.497426) (xy 338.382512 -223.544107)
			(xy 338.359641 -223.587684) (xy 338.330076 -223.627028) (xy 338.294583 -223.66112) (xy 338.25408 -223.689076)
			(xy 338.209618 -223.710174) (xy 338.162347 -223.723866) (xy 338.113492 -223.729798) (xy 338.064317 -223.727817)
			(xy 338.016098 -223.717973) (xy 337.970082 -223.700521) (xy 337.927461 -223.675914) (xy 337.88934 -223.644789)
			(xy 337.856705 -223.607952) (xy 337.830402 -223.566356) (xy 337.811111 -223.52108) (xy 337.799334 -223.473296)
			(xy 337.795374 -223.424242) (xy 337.466432 -223.424242) (xy 337.465937 -223.448849) (xy 337.458042 -223.497426)
			(xy 337.442458 -223.544107) (xy 337.419587 -223.587684) (xy 337.390022 -223.627028) (xy 337.354529 -223.66112)
			(xy 337.314026 -223.689076) (xy 337.269564 -223.710174) (xy 337.222293 -223.723866) (xy 337.173438 -223.729798)
			(xy 337.124263 -223.727817) (xy 337.076044 -223.717973) (xy 337.030028 -223.700521) (xy 336.987407 -223.675914)
			(xy 336.949286 -223.644789) (xy 336.916651 -223.607952) (xy 336.890348 -223.566356) (xy 336.871057 -223.52108)
			(xy 336.85928 -223.473296) (xy 336.85532 -223.424242) (xy 336.526378 -223.424242) (xy 336.525883 -223.448849)
			(xy 336.517988 -223.497426) (xy 336.502404 -223.544107) (xy 336.479533 -223.587684) (xy 336.449968 -223.627028)
			(xy 336.414475 -223.66112) (xy 336.373972 -223.689076) (xy 336.32951 -223.710174) (xy 336.282239 -223.723866)
			(xy 336.233384 -223.729798) (xy 336.184209 -223.727817) (xy 336.13599 -223.717973) (xy 336.089974 -223.700521)
			(xy 336.047353 -223.675914) (xy 336.009232 -223.644789) (xy 335.976597 -223.607952) (xy 335.950294 -223.566356)
			(xy 335.931003 -223.52108) (xy 335.919226 -223.473296) (xy 335.915266 -223.424242) (xy 335.586324 -223.424242)
			(xy 335.585829 -223.448849) (xy 335.577934 -223.497426) (xy 335.56235 -223.544107) (xy 335.539479 -223.587684)
			(xy 335.509914 -223.627028) (xy 335.474421 -223.66112) (xy 335.433918 -223.689076) (xy 335.389456 -223.710174)
			(xy 335.342185 -223.723866) (xy 335.29333 -223.729798) (xy 335.244155 -223.727817) (xy 335.195936 -223.717973)
			(xy 335.14992 -223.700521) (xy 335.107299 -223.675914) (xy 335.069178 -223.644789) (xy 335.036543 -223.607952)
			(xy 335.01024 -223.566356) (xy 334.990949 -223.52108) (xy 334.979172 -223.473296) (xy 334.975212 -223.424242)
			(xy 334.646524 -223.424242) (xy 334.646029 -223.448849) (xy 334.638134 -223.497426) (xy 334.62255 -223.544107)
			(xy 334.599679 -223.587684) (xy 334.570114 -223.627028) (xy 334.534621 -223.66112) (xy 334.494118 -223.689076)
			(xy 334.449656 -223.710174) (xy 334.402385 -223.723866) (xy 334.35353 -223.729798) (xy 334.304355 -223.727817)
			(xy 334.256136 -223.717973) (xy 334.21012 -223.700521) (xy 334.167499 -223.675914) (xy 334.129378 -223.644789)
			(xy 334.096743 -223.607952) (xy 334.07044 -223.566356) (xy 334.051149 -223.52108) (xy 334.039372 -223.473296)
			(xy 334.035412 -223.424242) (xy 333.70647 -223.424242) (xy 333.705975 -223.448849) (xy 333.69808 -223.497426)
			(xy 333.682496 -223.544107) (xy 333.659625 -223.587684) (xy 333.63006 -223.627028) (xy 333.594567 -223.66112)
			(xy 333.554064 -223.689076) (xy 333.509602 -223.710174) (xy 333.462331 -223.723866) (xy 333.413476 -223.729798)
			(xy 333.364301 -223.727817) (xy 333.316082 -223.717973) (xy 333.270066 -223.700521) (xy 333.227445 -223.675914)
			(xy 333.189324 -223.644789) (xy 333.156689 -223.607952) (xy 333.130386 -223.566356) (xy 333.111095 -223.52108)
			(xy 333.099318 -223.473296) (xy 333.095358 -223.424242) (xy 332.766416 -223.424242) (xy 332.765942 -223.448231)
			(xy 332.758431 -223.495618) (xy 332.7436 -223.541247) (xy 332.721814 -223.583995) (xy 332.69361 -223.622808)
			(xy 332.659682 -223.656732) (xy 332.620866 -223.684932) (xy 332.578116 -223.706713) (xy 332.532485 -223.721539)
			(xy 332.485097 -223.729045) (xy 332.461108 -223.72955) (xy 332.438808 -223.729166) (xy 332.394686 -223.722664)
			(xy 332.373224 -223.716596) (xy 332.36154 -223.71304) (xy 332.338172 -223.717104) (xy 332.262734 -223.772984)
			(xy 332.253515 -223.780599) (xy 332.242794 -223.801936) (xy 332.24216 -223.813878) (xy 332.24216 -223.816418)
			(xy 332.242408 -223.823599) (xy 332.246409 -223.837392) (xy 332.250034 -223.843596) (xy 332.253082 -223.848422)
			(xy 332.506828 -224.102168) (xy 332.515502 -224.109993) (xy 332.537594 -224.117512) (xy 332.549246 -224.116646)
			(xy 332.641194 -224.104708) (xy 332.660752 -224.0915) (xy 332.666848 -224.08134) (xy 332.680645 -224.058552)
			(xy 332.714897 -224.017758) (xy 332.755713 -223.983532) (xy 332.801853 -223.956914) (xy 332.851913 -223.938713)
			(xy 332.904374 -223.929481) (xy 332.931008 -223.92894) (xy 332.954999 -223.929387) (xy 333.002391 -223.936895)
			(xy 333.048025 -223.951725) (xy 333.090776 -223.973511) (xy 333.129593 -224.001718) (xy 333.163519 -224.03565)
			(xy 333.191718 -224.074472) (xy 333.213497 -224.117227) (xy 333.228318 -224.162863) (xy 333.235818 -224.210257)
			(xy 333.236316 -224.234248) (xy 333.23587 -224.257877) (xy 333.228581 -224.30457) (xy 333.214184 -224.349582)
			(xy 333.193024 -224.391838) (xy 333.165605 -224.430329) (xy 333.132583 -224.464136) (xy 333.094746 -224.492451)
			(xy 333.052998 -224.514597) (xy 333.03083 -224.522792) (xy 333.019654 -224.526602) (xy 333.011526 -224.534984)
			(xy 333.004687 -224.542348) (xy 332.996948 -224.560877) (xy 332.996955 -224.580958) (xy 333.004707 -224.599482)
			(xy 333.011526 -224.606866) (xy 333.029814 -224.625154) (xy 333.030322 -224.625662) (xy 333.037702 -224.632248)
			(xy 333.056001 -224.639708) (xy 333.065882 -224.64014) (xy 334.54086 -224.64014) (xy 334.551138 -224.639678)
			(xy 334.570057 -224.63164) (xy 334.584314 -224.616832) (xy 334.588358 -224.607374) (xy 334.62214 -224.518728)
			(xy 334.625327 -224.50901) (xy 334.624559 -224.488589) (xy 334.615924 -224.470068) (xy 334.608678 -224.462848)
			(xy 334.608424 -224.462594) (xy 334.589475 -224.445059) (xy 334.557176 -224.404787) (xy 334.532112 -224.359655)
			(xy 334.514998 -224.31095) (xy 334.506322 -224.26006) (xy 334.505808 -224.234248) (xy 334.506251 -224.210253)
			(xy 334.513751 -224.162852) (xy 334.528576 -224.117209) (xy 334.550359 -224.074448) (xy 334.578564 -224.035621)
			(xy 334.612497 -224.001685) (xy 334.65132 -223.973476) (xy 334.69408 -223.951688) (xy 334.739721 -223.936859)
			(xy 334.787121 -223.929353) (xy 334.811116 -223.92894) (xy 334.834892 -223.929395) (xy 334.88187 -223.936769)
			(xy 334.927136 -223.951336) (xy 334.969597 -223.972744) (xy 335.008227 -224.000475) (xy 335.042091 -224.033859)
			(xy 335.07037 -224.072089) (xy 335.092381 -224.114241) (xy 335.107592 -224.159295) (xy 335.115635 -224.206163)
			(xy 335.116424 -224.22993) (xy 335.116424 -224.234502) (xy 335.11607 -224.255372) (xy 335.110356 -224.296721)
			(xy 335.099063 -224.336905) (xy 335.091024 -224.356168) (xy 335.091024 -224.356422) (xy 335.087737 -224.36483)
			(xy 335.086677 -224.382838) (xy 335.09192 -224.4001) (xy 335.09712 -224.407476) (xy 335.159604 -224.489264)
			(xy 335.185258 -224.499678) (xy 335.198974 -224.497646) (xy 335.235042 -224.493328) (xy 335.280762 -224.491296)
			(xy 335.28127 -224.491296) (xy 335.32699 -224.493328) (xy 335.363058 -224.497646) (xy 335.376774 -224.499678)
			(xy 335.402428 -224.489264) (xy 335.465166 -224.40773) (xy 335.470351 -224.400293) (xy 335.475616 -224.382958)
			(xy 335.474548 -224.364872) (xy 335.471262 -224.356422) (xy 335.471262 -224.356168) (xy 335.463312 -224.337053)
			(xy 335.452059 -224.297212) (xy 335.44629 -224.256216) (xy 335.445862 -224.235518) (xy 335.445862 -224.22993)
			(xy 335.446649 -224.20616) (xy 335.45468 -224.159287) (xy 335.469883 -224.114225) (xy 335.49189 -224.072067)
			(xy 335.520169 -224.033831) (xy 335.554035 -224.000443) (xy 335.592669 -223.972711) (xy 335.635136 -223.951306)
			(xy 335.680408 -223.936745) (xy 335.727392 -223.929381) (xy 335.75117 -223.92894) (xy 335.775163 -223.929384)
			(xy 335.82256 -223.936887) (xy 335.868198 -223.951714) (xy 335.910955 -223.973498) (xy 335.949777 -224.001704)
			(xy 335.983707 -224.035637) (xy 336.011911 -224.07446) (xy 336.033693 -224.117218) (xy 336.048517 -224.162858)
			(xy 336.056017 -224.210255) (xy 336.056478 -224.234248) (xy 337.32522 -224.234248) (xy 337.32918 -224.185194)
			(xy 337.340957 -224.13741) (xy 337.360248 -224.092134) (xy 337.386551 -224.050538) (xy 337.419186 -224.013701)
			(xy 337.457307 -223.982576) (xy 337.499928 -223.957969) (xy 337.545944 -223.940517) (xy 337.594163 -223.930673)
			(xy 337.643338 -223.928692) (xy 337.692193 -223.934624) (xy 337.739464 -223.948316) (xy 337.783926 -223.969414)
			(xy 337.824429 -223.99737) (xy 337.859922 -224.031462) (xy 337.889487 -224.070806) (xy 337.912358 -224.114383)
			(xy 337.927942 -224.161064) (xy 337.935837 -224.209641) (xy 337.936332 -224.234248) (xy 338.265274 -224.234248)
			(xy 338.269234 -224.185194) (xy 338.281011 -224.13741) (xy 338.300302 -224.092134) (xy 338.326605 -224.050538)
			(xy 338.35924 -224.013701) (xy 338.397361 -223.982576) (xy 338.439982 -223.957969) (xy 338.485998 -223.940517)
			(xy 338.534217 -223.930673) (xy 338.583392 -223.928692) (xy 338.632247 -223.934624) (xy 338.679518 -223.948316)
			(xy 338.72398 -223.969414) (xy 338.764483 -223.99737) (xy 338.799976 -224.031462) (xy 338.829541 -224.070806)
			(xy 338.852412 -224.114383) (xy 338.867996 -224.161064) (xy 338.875891 -224.209641) (xy 338.876386 -224.234248)
			(xy 339.205328 -224.234248) (xy 339.209288 -224.185194) (xy 339.221065 -224.13741) (xy 339.240356 -224.092134)
			(xy 339.266659 -224.050538) (xy 339.299294 -224.013701) (xy 339.337415 -223.982576) (xy 339.380036 -223.957969)
			(xy 339.426052 -223.940517) (xy 339.474271 -223.930673) (xy 339.523446 -223.928692) (xy 339.572301 -223.934624)
			(xy 339.619572 -223.948316) (xy 339.664034 -223.969414) (xy 339.704537 -223.99737) (xy 339.74003 -224.031462)
			(xy 339.769595 -224.070806) (xy 339.792466 -224.114383) (xy 339.80805 -224.161064) (xy 339.815945 -224.209641)
			(xy 339.81644 -224.234248) (xy 341.085182 -224.234248) (xy 341.089142 -224.185194) (xy 341.100919 -224.13741)
			(xy 341.12021 -224.092134) (xy 341.146513 -224.050538) (xy 341.179148 -224.013701) (xy 341.217269 -223.982576)
			(xy 341.25989 -223.957969) (xy 341.305906 -223.940517) (xy 341.354125 -223.930673) (xy 341.4033 -223.928692)
			(xy 341.452155 -223.934624) (xy 341.499426 -223.948316) (xy 341.543888 -223.969414) (xy 341.584391 -223.99737)
			(xy 341.619884 -224.031462) (xy 341.649449 -224.070806) (xy 341.67232 -224.114383) (xy 341.687904 -224.161064)
			(xy 341.695799 -224.209641) (xy 341.696294 -224.234248) (xy 342.025236 -224.234248) (xy 342.029196 -224.185194)
			(xy 342.040973 -224.13741) (xy 342.060264 -224.092134) (xy 342.086567 -224.050538) (xy 342.119202 -224.013701)
			(xy 342.157323 -223.982576) (xy 342.199944 -223.957969) (xy 342.24596 -223.940517) (xy 342.294179 -223.930673)
			(xy 342.343354 -223.928692) (xy 342.392209 -223.934624) (xy 342.43948 -223.948316) (xy 342.483942 -223.969414)
			(xy 342.524445 -223.99737) (xy 342.559938 -224.031462) (xy 342.589503 -224.070806) (xy 342.612374 -224.114383)
			(xy 342.627958 -224.161064) (xy 342.635853 -224.209641) (xy 342.636348 -224.234248) (xy 342.96529 -224.234248)
			(xy 342.96925 -224.185194) (xy 342.981027 -224.13741) (xy 343.000318 -224.092134) (xy 343.026621 -224.050538)
			(xy 343.059256 -224.013701) (xy 343.097377 -223.982576) (xy 343.139998 -223.957969) (xy 343.186014 -223.940517)
			(xy 343.234233 -223.930673) (xy 343.283408 -223.928692) (xy 343.332263 -223.934624) (xy 343.379534 -223.948316)
			(xy 343.423996 -223.969414) (xy 343.464499 -223.99737) (xy 343.499992 -224.031462) (xy 343.529557 -224.070806)
			(xy 343.552428 -224.114383) (xy 343.568012 -224.161064) (xy 343.575907 -224.209641) (xy 343.576402 -224.234248)
			(xy 343.575907 -224.258855) (xy 343.568012 -224.307432) (xy 343.552428 -224.354113) (xy 343.529557 -224.39769)
			(xy 343.499992 -224.437034) (xy 343.464499 -224.471126) (xy 343.423996 -224.499082) (xy 343.379534 -224.52018)
			(xy 343.332263 -224.533872) (xy 343.283408 -224.539804) (xy 343.234233 -224.537823) (xy 343.186014 -224.527979)
			(xy 343.139998 -224.510527) (xy 343.097377 -224.48592) (xy 343.059256 -224.454795) (xy 343.026621 -224.417958)
			(xy 343.000318 -224.376362) (xy 342.981027 -224.331086) (xy 342.96925 -224.283302) (xy 342.96529 -224.234248)
			(xy 342.636348 -224.234248) (xy 342.635853 -224.258855) (xy 342.627958 -224.307432) (xy 342.612374 -224.354113)
			(xy 342.589503 -224.39769) (xy 342.559938 -224.437034) (xy 342.524445 -224.471126) (xy 342.483942 -224.499082)
			(xy 342.43948 -224.52018) (xy 342.392209 -224.533872) (xy 342.343354 -224.539804) (xy 342.294179 -224.537823)
			(xy 342.24596 -224.527979) (xy 342.199944 -224.510527) (xy 342.157323 -224.48592) (xy 342.119202 -224.454795)
			(xy 342.086567 -224.417958) (xy 342.060264 -224.376362) (xy 342.040973 -224.331086) (xy 342.029196 -224.283302)
			(xy 342.025236 -224.234248) (xy 341.696294 -224.234248) (xy 341.695799 -224.258855) (xy 341.687904 -224.307432)
			(xy 341.67232 -224.354113) (xy 341.649449 -224.39769) (xy 341.619884 -224.437034) (xy 341.584391 -224.471126)
			(xy 341.543888 -224.499082) (xy 341.499426 -224.52018) (xy 341.452155 -224.533872) (xy 341.4033 -224.539804)
			(xy 341.354125 -224.537823) (xy 341.305906 -224.527979) (xy 341.25989 -224.510527) (xy 341.217269 -224.48592)
			(xy 341.179148 -224.454795) (xy 341.146513 -224.417958) (xy 341.12021 -224.376362) (xy 341.100919 -224.331086)
			(xy 341.089142 -224.283302) (xy 341.085182 -224.234248) (xy 339.81644 -224.234248) (xy 339.815945 -224.258855)
			(xy 339.80805 -224.307432) (xy 339.792466 -224.354113) (xy 339.769595 -224.39769) (xy 339.74003 -224.437034)
			(xy 339.704537 -224.471126) (xy 339.664034 -224.499082) (xy 339.619572 -224.52018) (xy 339.572301 -224.533872)
			(xy 339.523446 -224.539804) (xy 339.474271 -224.537823) (xy 339.426052 -224.527979) (xy 339.380036 -224.510527)
			(xy 339.337415 -224.48592) (xy 339.299294 -224.454795) (xy 339.266659 -224.417958) (xy 339.240356 -224.376362)
			(xy 339.221065 -224.331086) (xy 339.209288 -224.283302) (xy 339.205328 -224.234248) (xy 338.876386 -224.234248)
			(xy 338.875891 -224.258855) (xy 338.867996 -224.307432) (xy 338.852412 -224.354113) (xy 338.829541 -224.39769)
			(xy 338.799976 -224.437034) (xy 338.764483 -224.471126) (xy 338.72398 -224.499082) (xy 338.679518 -224.52018)
			(xy 338.632247 -224.533872) (xy 338.583392 -224.539804) (xy 338.534217 -224.537823) (xy 338.485998 -224.527979)
			(xy 338.439982 -224.510527) (xy 338.397361 -224.48592) (xy 338.35924 -224.454795) (xy 338.326605 -224.417958)
			(xy 338.300302 -224.376362) (xy 338.281011 -224.331086) (xy 338.269234 -224.283302) (xy 338.265274 -224.234248)
			(xy 337.936332 -224.234248) (xy 337.935837 -224.258855) (xy 337.927942 -224.307432) (xy 337.912358 -224.354113)
			(xy 337.889487 -224.39769) (xy 337.859922 -224.437034) (xy 337.824429 -224.471126) (xy 337.783926 -224.499082)
			(xy 337.739464 -224.52018) (xy 337.692193 -224.533872) (xy 337.643338 -224.539804) (xy 337.594163 -224.537823)
			(xy 337.545944 -224.527979) (xy 337.499928 -224.510527) (xy 337.457307 -224.48592) (xy 337.419186 -224.454795)
			(xy 337.386551 -224.417958) (xy 337.360248 -224.376362) (xy 337.340957 -224.331086) (xy 337.32918 -224.283302)
			(xy 337.32522 -224.234248) (xy 336.056478 -224.234248) (xy 336.055936 -224.260058) (xy 336.047252 -224.310941)
			(xy 336.030139 -224.359642) (xy 336.005085 -224.404773) (xy 335.972801 -224.445052) (xy 335.953862 -224.462594)
			(xy 335.953608 -224.462848) (xy 335.946292 -224.470024) (xy 335.937602 -224.488562) (xy 335.936864 -224.509022)
			(xy 335.940146 -224.518728) (xy 335.973928 -224.607374) (xy 335.97802 -224.616803) (xy 335.99226 -224.631598)
			(xy 336.011158 -224.639632) (xy 336.021426 -224.64014) (xy 336.564478 -224.64014) (xy 336.574541 -224.640579)
			(xy 336.593121 -224.648317) (xy 336.600546 -224.655126) (xy 336.787998 -224.842578) (xy 336.791046 -224.845372)
			(xy 336.7913 -224.845626) (xy 336.798627 -224.851284) (xy 336.81608 -224.857407) (xy 336.825336 -224.857564)
			(xy 336.898488 -224.855786) (xy 336.908851 -224.855029) (xy 336.927722 -224.846376) (xy 336.935064 -224.839022)
			(xy 336.952561 -224.820506) (xy 336.992585 -224.788994) (xy 337.037284 -224.764562) (xy 337.085419 -224.747889)
			(xy 337.135654 -224.739438) (xy 337.161124 -224.738946) (xy 337.185115 -224.739418) (xy 337.232507 -224.746927)
			(xy 337.278141 -224.761756) (xy 337.320893 -224.78354) (xy 337.359712 -224.811743) (xy 337.393642 -224.845671)
			(xy 337.421848 -224.884488) (xy 337.443635 -224.927239) (xy 337.458468 -224.972872) (xy 337.46598 -225.020263)
			(xy 337.466432 -225.044254) (xy 337.795374 -225.044254) (xy 337.799334 -224.9952) (xy 337.811111 -224.947416)
			(xy 337.830402 -224.90214) (xy 337.856705 -224.860544) (xy 337.88934 -224.823707) (xy 337.927461 -224.792582)
			(xy 337.970082 -224.767975) (xy 338.016098 -224.750523) (xy 338.064317 -224.740679) (xy 338.113492 -224.738698)
			(xy 338.162347 -224.74463) (xy 338.209618 -224.758322) (xy 338.25408 -224.77942) (xy 338.294583 -224.807376)
			(xy 338.330076 -224.841468) (xy 338.359641 -224.880812) (xy 338.382512 -224.924389) (xy 338.398096 -224.97107)
			(xy 338.405991 -225.019647) (xy 338.406486 -225.044254) (xy 338.724743 -225.044254) (xy 338.728838 -224.993526)
			(xy 338.741017 -224.944112) (xy 338.760965 -224.897292) (xy 338.788166 -224.854278) (xy 338.821914 -224.816184)
			(xy 338.861336 -224.783997) (xy 338.90541 -224.758551) (xy 338.952996 -224.740504) (xy 339.00286 -224.730324)
			(xy 339.053712 -224.728275) (xy 339.104233 -224.734409) (xy 339.153117 -224.748569) (xy 339.199096 -224.770386)
			(xy 339.24098 -224.799296) (xy 339.277684 -224.834551) (xy 339.308257 -224.875237) (xy 339.331908 -224.9203)
			(xy 339.348024 -224.968574) (xy 339.356188 -225.018808) (xy 339.3567 -225.044254) (xy 339.675228 -225.044254)
			(xy 339.679188 -224.9952) (xy 339.690965 -224.947416) (xy 339.710256 -224.90214) (xy 339.736559 -224.860544)
			(xy 339.769194 -224.823707) (xy 339.807315 -224.792582) (xy 339.849936 -224.767975) (xy 339.895952 -224.750523)
			(xy 339.944171 -224.740679) (xy 339.993346 -224.738698) (xy 340.042201 -224.74463) (xy 340.089472 -224.758322)
			(xy 340.133934 -224.77942) (xy 340.174437 -224.807376) (xy 340.20993 -224.841468) (xy 340.239495 -224.880812)
			(xy 340.262366 -224.924389) (xy 340.27795 -224.97107) (xy 340.285845 -225.019647) (xy 340.28634 -225.044254)
			(xy 340.615282 -225.044254) (xy 340.619242 -224.9952) (xy 340.631019 -224.947416) (xy 340.65031 -224.90214)
			(xy 340.676613 -224.860544) (xy 340.709248 -224.823707) (xy 340.747369 -224.792582) (xy 340.78999 -224.767975)
			(xy 340.836006 -224.750523) (xy 340.884225 -224.740679) (xy 340.9334 -224.738698) (xy 340.982255 -224.74463)
			(xy 341.029526 -224.758322) (xy 341.073988 -224.77942) (xy 341.114491 -224.807376) (xy 341.149984 -224.841468)
			(xy 341.179549 -224.880812) (xy 341.20242 -224.924389) (xy 341.218004 -224.97107) (xy 341.225899 -225.019647)
			(xy 341.226394 -225.044254) (xy 341.544905 -225.044254) (xy 341.549 -224.993526) (xy 341.561179 -224.944112)
			(xy 341.581127 -224.897292) (xy 341.608328 -224.854278) (xy 341.642076 -224.816184) (xy 341.681498 -224.783997)
			(xy 341.725572 -224.758551) (xy 341.773158 -224.740504) (xy 341.823022 -224.730324) (xy 341.873874 -224.728275)
			(xy 341.924395 -224.734409) (xy 341.973279 -224.748569) (xy 342.019258 -224.770386) (xy 342.061142 -224.799296)
			(xy 342.097846 -224.834551) (xy 342.128419 -224.875237) (xy 342.15207 -224.9203) (xy 342.168186 -224.968574)
			(xy 342.17635 -225.018808) (xy 342.176862 -225.044254) (xy 342.49539 -225.044254) (xy 342.49935 -224.9952)
			(xy 342.511127 -224.947416) (xy 342.530418 -224.90214) (xy 342.556721 -224.860544) (xy 342.589356 -224.823707)
			(xy 342.627477 -224.792582) (xy 342.670098 -224.767975) (xy 342.716114 -224.750523) (xy 342.764333 -224.740679)
			(xy 342.813508 -224.738698) (xy 342.862363 -224.74463) (xy 342.909634 -224.758322) (xy 342.954096 -224.77942)
			(xy 342.994599 -224.807376) (xy 343.030092 -224.841468) (xy 343.059657 -224.880812) (xy 343.082528 -224.924389)
			(xy 343.098112 -224.97107) (xy 343.106007 -225.019647) (xy 343.106502 -225.044254) (xy 343.106007 -225.068861)
			(xy 343.098112 -225.117438) (xy 343.082528 -225.164119) (xy 343.059657 -225.207696) (xy 343.030092 -225.24704)
			(xy 342.994599 -225.281132) (xy 342.954096 -225.309088) (xy 342.909634 -225.330186) (xy 342.862363 -225.343878)
			(xy 342.813508 -225.34981) (xy 342.764333 -225.347829) (xy 342.716114 -225.337985) (xy 342.670098 -225.320533)
			(xy 342.627477 -225.295926) (xy 342.589356 -225.264801) (xy 342.556721 -225.227964) (xy 342.530418 -225.186368)
			(xy 342.511127 -225.141092) (xy 342.49935 -225.093308) (xy 342.49539 -225.044254) (xy 342.176862 -225.044254)
			(xy 342.17635 -225.0697) (xy 342.168186 -225.119934) (xy 342.15207 -225.168208) (xy 342.128419 -225.213271)
			(xy 342.097846 -225.253957) (xy 342.061142 -225.289212) (xy 342.019258 -225.318122) (xy 341.973279 -225.339939)
			(xy 341.924395 -225.354099) (xy 341.873874 -225.360233) (xy 341.823022 -225.358184) (xy 341.773158 -225.348004)
			(xy 341.725572 -225.329957) (xy 341.681498 -225.304511) (xy 341.642076 -225.272324) (xy 341.608328 -225.23423)
			(xy 341.581127 -225.191216) (xy 341.561179 -225.144396) (xy 341.549 -225.094982) (xy 341.544905 -225.044254)
			(xy 341.226394 -225.044254) (xy 341.225899 -225.068861) (xy 341.218004 -225.117438) (xy 341.20242 -225.164119)
			(xy 341.179549 -225.207696) (xy 341.149984 -225.24704) (xy 341.114491 -225.281132) (xy 341.073988 -225.309088)
			(xy 341.029526 -225.330186) (xy 340.982255 -225.343878) (xy 340.9334 -225.34981) (xy 340.884225 -225.347829)
			(xy 340.836006 -225.337985) (xy 340.78999 -225.320533) (xy 340.747369 -225.295926) (xy 340.709248 -225.264801)
			(xy 340.676613 -225.227964) (xy 340.65031 -225.186368) (xy 340.631019 -225.141092) (xy 340.619242 -225.093308)
			(xy 340.615282 -225.044254) (xy 340.28634 -225.044254) (xy 340.285845 -225.068861) (xy 340.27795 -225.117438)
			(xy 340.262366 -225.164119) (xy 340.239495 -225.207696) (xy 340.20993 -225.24704) (xy 340.174437 -225.281132)
			(xy 340.133934 -225.309088) (xy 340.089472 -225.330186) (xy 340.042201 -225.343878) (xy 339.993346 -225.34981)
			(xy 339.944171 -225.347829) (xy 339.895952 -225.337985) (xy 339.849936 -225.320533) (xy 339.807315 -225.295926)
			(xy 339.769194 -225.264801) (xy 339.736559 -225.227964) (xy 339.710256 -225.186368) (xy 339.690965 -225.141092)
			(xy 339.679188 -225.093308) (xy 339.675228 -225.044254) (xy 339.3567 -225.044254) (xy 339.356188 -225.0697)
			(xy 339.348024 -225.119934) (xy 339.331908 -225.168208) (xy 339.308257 -225.213271) (xy 339.277684 -225.253957)
			(xy 339.24098 -225.289212) (xy 339.199096 -225.318122) (xy 339.153117 -225.339939) (xy 339.104233 -225.354099)
			(xy 339.053712 -225.360233) (xy 339.00286 -225.358184) (xy 338.952996 -225.348004) (xy 338.90541 -225.329957)
			(xy 338.861336 -225.304511) (xy 338.821914 -225.272324) (xy 338.788166 -225.23423) (xy 338.760965 -225.191216)
			(xy 338.741017 -225.144396) (xy 338.728838 -225.094982) (xy 338.724743 -225.044254) (xy 338.406486 -225.044254)
			(xy 338.405991 -225.068861) (xy 338.398096 -225.117438) (xy 338.382512 -225.164119) (xy 338.359641 -225.207696)
			(xy 338.330076 -225.24704) (xy 338.294583 -225.281132) (xy 338.25408 -225.309088) (xy 338.209618 -225.330186)
			(xy 338.162347 -225.343878) (xy 338.113492 -225.34981) (xy 338.064317 -225.347829) (xy 338.016098 -225.337985)
			(xy 337.970082 -225.320533) (xy 337.927461 -225.295926) (xy 337.88934 -225.264801) (xy 337.856705 -225.227964)
			(xy 337.830402 -225.186368) (xy 337.811111 -225.141092) (xy 337.799334 -225.093308) (xy 337.795374 -225.044254)
			(xy 337.466432 -225.044254) (xy 337.465918 -225.069722) (xy 337.457459 -225.119951) (xy 337.440785 -225.16808)
			(xy 337.416359 -225.212777) (xy 337.384856 -225.252802) (xy 337.366356 -225.270314) (xy 337.358951 -225.277622)
			(xy 337.35028 -225.29651) (xy 337.349592 -225.30689) (xy 337.347814 -225.380042) (xy 337.347984 -225.389295)
			(xy 337.354106 -225.406745) (xy 337.359752 -225.414078) (xy 337.361276 -225.415856) (xy 337.494118 -225.548698)
			(xy 337.500841 -225.554841) (xy 337.51742 -225.562347) (xy 337.535575 -225.563607) (xy 337.54441 -225.561398)
			(xy 337.565396 -225.555589) (xy 337.60849 -225.549335) (xy 337.630262 -225.548952) (xy 337.631024 -225.548952)
			(xy 337.655015 -225.549424) (xy 337.702406 -225.556933) (xy 337.74804 -225.571762) (xy 337.790792 -225.593546)
			(xy 337.829611 -225.62175) (xy 337.86354 -225.655677) (xy 337.891745 -225.694494) (xy 337.913532 -225.737246)
			(xy 337.928363 -225.782878) (xy 337.935874 -225.830269) (xy 337.936332 -225.85426) (xy 338.254843 -225.85426)
			(xy 338.258938 -225.803532) (xy 338.271117 -225.754118) (xy 338.291065 -225.707298) (xy 338.318266 -225.664284)
			(xy 338.352014 -225.62619) (xy 338.391436 -225.594003) (xy 338.43551 -225.568557) (xy 338.483096 -225.55051)
			(xy 338.53296 -225.54033) (xy 338.583812 -225.538281) (xy 338.634333 -225.544415) (xy 338.683217 -225.558575)
			(xy 338.729196 -225.580392) (xy 338.77108 -225.609302) (xy 338.807784 -225.644557) (xy 338.838357 -225.685243)
			(xy 338.862008 -225.730306) (xy 338.878124 -225.77858) (xy 338.886288 -225.828814) (xy 338.8868 -225.85426)
			(xy 339.205328 -225.85426) (xy 339.209288 -225.805206) (xy 339.221065 -225.757422) (xy 339.240356 -225.712146)
			(xy 339.266659 -225.67055) (xy 339.299294 -225.633713) (xy 339.337415 -225.602588) (xy 339.380036 -225.577981)
			(xy 339.426052 -225.560529) (xy 339.474271 -225.550685) (xy 339.523446 -225.548704) (xy 339.572301 -225.554636)
			(xy 339.619572 -225.568328) (xy 339.664034 -225.589426) (xy 339.704537 -225.617382) (xy 339.74003 -225.651474)
			(xy 339.769595 -225.690818) (xy 339.792466 -225.734395) (xy 339.80805 -225.781076) (xy 339.815945 -225.829653)
			(xy 339.81644 -225.85426) (xy 340.134951 -225.85426) (xy 340.139046 -225.803532) (xy 340.151225 -225.754118)
			(xy 340.171173 -225.707298) (xy 340.198374 -225.664284) (xy 340.232122 -225.62619) (xy 340.271544 -225.594003)
			(xy 340.315618 -225.568557) (xy 340.363204 -225.55051) (xy 340.413068 -225.54033) (xy 340.46392 -225.538281)
			(xy 340.514441 -225.544415) (xy 340.563325 -225.558575) (xy 340.609304 -225.580392) (xy 340.651188 -225.609302)
			(xy 340.687892 -225.644557) (xy 340.718465 -225.685243) (xy 340.742116 -225.730306) (xy 340.758232 -225.77858)
			(xy 340.766396 -225.828814) (xy 340.766908 -225.85426) (xy 341.085182 -225.85426) (xy 341.089142 -225.805206)
			(xy 341.100919 -225.757422) (xy 341.12021 -225.712146) (xy 341.146513 -225.67055) (xy 341.179148 -225.633713)
			(xy 341.217269 -225.602588) (xy 341.25989 -225.577981) (xy 341.305906 -225.560529) (xy 341.354125 -225.550685)
			(xy 341.4033 -225.548704) (xy 341.452155 -225.554636) (xy 341.499426 -225.568328) (xy 341.543888 -225.589426)
			(xy 341.584391 -225.617382) (xy 341.619884 -225.651474) (xy 341.649449 -225.690818) (xy 341.67232 -225.734395)
			(xy 341.687904 -225.781076) (xy 341.695799 -225.829653) (xy 341.696294 -225.85426) (xy 342.014805 -225.85426)
			(xy 342.0189 -225.803532) (xy 342.031079 -225.754118) (xy 342.051027 -225.707298) (xy 342.078228 -225.664284)
			(xy 342.111976 -225.62619) (xy 342.151398 -225.594003) (xy 342.195472 -225.568557) (xy 342.243058 -225.55051)
			(xy 342.292922 -225.54033) (xy 342.343774 -225.538281) (xy 342.394295 -225.544415) (xy 342.443179 -225.558575)
			(xy 342.489158 -225.580392) (xy 342.531042 -225.609302) (xy 342.567746 -225.644557) (xy 342.598319 -225.685243)
			(xy 342.62197 -225.730306) (xy 342.638086 -225.77858) (xy 342.64625 -225.828814) (xy 342.646762 -225.85426)
			(xy 342.954859 -225.85426) (xy 342.958954 -225.803532) (xy 342.971133 -225.754118) (xy 342.991081 -225.707298)
			(xy 343.018282 -225.664284) (xy 343.05203 -225.62619) (xy 343.091452 -225.594003) (xy 343.135526 -225.568557)
			(xy 343.183112 -225.55051) (xy 343.232976 -225.54033) (xy 343.283828 -225.538281) (xy 343.334349 -225.544415)
			(xy 343.383233 -225.558575) (xy 343.429212 -225.580392) (xy 343.471096 -225.609302) (xy 343.5078 -225.644557)
			(xy 343.538373 -225.685243) (xy 343.562024 -225.730306) (xy 343.57814 -225.77858) (xy 343.586304 -225.828814)
			(xy 343.586816 -225.85426) (xy 343.586304 -225.879706) (xy 343.57814 -225.92994) (xy 343.562024 -225.978214)
			(xy 343.538373 -226.023277) (xy 343.5078 -226.063963) (xy 343.471096 -226.099218) (xy 343.429212 -226.128128)
			(xy 343.383233 -226.149945) (xy 343.334349 -226.164105) (xy 343.283828 -226.170239) (xy 343.232976 -226.16819)
			(xy 343.183112 -226.15801) (xy 343.135526 -226.139963) (xy 343.091452 -226.114517) (xy 343.05203 -226.08233)
			(xy 343.018282 -226.044236) (xy 342.991081 -226.001222) (xy 342.971133 -225.954402) (xy 342.958954 -225.904988)
			(xy 342.954859 -225.85426) (xy 342.646762 -225.85426) (xy 342.64625 -225.879706) (xy 342.638086 -225.92994)
			(xy 342.62197 -225.978214) (xy 342.598319 -226.023277) (xy 342.567746 -226.063963) (xy 342.531042 -226.099218)
			(xy 342.489158 -226.128128) (xy 342.443179 -226.149945) (xy 342.394295 -226.164105) (xy 342.343774 -226.170239)
			(xy 342.292922 -226.16819) (xy 342.243058 -226.15801) (xy 342.195472 -226.139963) (xy 342.151398 -226.114517)
			(xy 342.111976 -226.08233) (xy 342.078228 -226.044236) (xy 342.051027 -226.001222) (xy 342.031079 -225.954402)
			(xy 342.0189 -225.904988) (xy 342.014805 -225.85426) (xy 341.696294 -225.85426) (xy 341.695799 -225.878867)
			(xy 341.687904 -225.927444) (xy 341.67232 -225.974125) (xy 341.649449 -226.017702) (xy 341.619884 -226.057046)
			(xy 341.584391 -226.091138) (xy 341.543888 -226.119094) (xy 341.499426 -226.140192) (xy 341.452155 -226.153884)
			(xy 341.4033 -226.159816) (xy 341.354125 -226.157835) (xy 341.305906 -226.147991) (xy 341.25989 -226.130539)
			(xy 341.217269 -226.105932) (xy 341.179148 -226.074807) (xy 341.146513 -226.03797) (xy 341.12021 -225.996374)
			(xy 341.100919 -225.951098) (xy 341.089142 -225.903314) (xy 341.085182 -225.85426) (xy 340.766908 -225.85426)
			(xy 340.766396 -225.879706) (xy 340.758232 -225.92994) (xy 340.742116 -225.978214) (xy 340.718465 -226.023277)
			(xy 340.687892 -226.063963) (xy 340.651188 -226.099218) (xy 340.609304 -226.128128) (xy 340.563325 -226.149945)
			(xy 340.514441 -226.164105) (xy 340.46392 -226.170239) (xy 340.413068 -226.16819) (xy 340.363204 -226.15801)
			(xy 340.315618 -226.139963) (xy 340.271544 -226.114517) (xy 340.232122 -226.08233) (xy 340.198374 -226.044236)
			(xy 340.171173 -226.001222) (xy 340.151225 -225.954402) (xy 340.139046 -225.904988) (xy 340.134951 -225.85426)
			(xy 339.81644 -225.85426) (xy 339.815945 -225.878867) (xy 339.80805 -225.927444) (xy 339.792466 -225.974125)
			(xy 339.769595 -226.017702) (xy 339.74003 -226.057046) (xy 339.704537 -226.091138) (xy 339.664034 -226.119094)
			(xy 339.619572 -226.140192) (xy 339.572301 -226.153884) (xy 339.523446 -226.159816) (xy 339.474271 -226.157835)
			(xy 339.426052 -226.147991) (xy 339.380036 -226.130539) (xy 339.337415 -226.105932) (xy 339.299294 -226.074807)
			(xy 339.266659 -226.03797) (xy 339.240356 -225.996374) (xy 339.221065 -225.951098) (xy 339.209288 -225.903314)
			(xy 339.205328 -225.85426) (xy 338.8868 -225.85426) (xy 338.886288 -225.879706) (xy 338.878124 -225.92994)
			(xy 338.862008 -225.978214) (xy 338.838357 -226.023277) (xy 338.807784 -226.063963) (xy 338.77108 -226.099218)
			(xy 338.729196 -226.128128) (xy 338.683217 -226.149945) (xy 338.634333 -226.164105) (xy 338.583812 -226.170239)
			(xy 338.53296 -226.16819) (xy 338.483096 -226.15801) (xy 338.43551 -226.139963) (xy 338.391436 -226.114517)
			(xy 338.352014 -226.08233) (xy 338.318266 -226.044236) (xy 338.291065 -226.001222) (xy 338.271117 -225.954402)
			(xy 338.258938 -225.904988) (xy 338.254843 -225.85426) (xy 337.936332 -225.85426) (xy 337.936332 -225.855022)
			(xy 337.935906 -225.876791) (xy 337.929656 -225.919879) (xy 337.923886 -225.940874) (xy 337.921659 -225.949705)
			(xy 337.922918 -225.967862) (xy 337.930456 -225.984427) (xy 337.936586 -225.991166) (xy 338.051394 -226.105974)
			(xy 338.058229 -226.113376) (xy 338.065938 -226.131975) (xy 338.06638 -226.142042) (xy 338.06638 -226.288092)
			(xy 338.066815 -226.297788) (xy 338.074004 -226.3158) (xy 338.08035 -226.323144) (xy 338.095082 -226.338638)
			(xy 338.098323 -226.341868) (xy 338.105734 -226.347234) (xy 338.109814 -226.349306) (xy 338.132674 -226.360228)
			(xy 338.140802 -226.361498) (xy 338.165001 -226.365134) (xy 338.211895 -226.379105) (xy 338.255961 -226.400376)
			(xy 338.296071 -226.428401) (xy 338.331198 -226.462464) (xy 338.360444 -226.501693) (xy 338.38306 -226.545084)
			(xy 338.398467 -226.591526) (xy 338.406271 -226.63983) (xy 338.406271 -226.664266) (xy 338.724743 -226.664266)
			(xy 338.728838 -226.613538) (xy 338.741017 -226.564124) (xy 338.760965 -226.517304) (xy 338.788166 -226.47429)
			(xy 338.821914 -226.436196) (xy 338.861336 -226.404009) (xy 338.90541 -226.378563) (xy 338.952996 -226.360516)
			(xy 339.00286 -226.350336) (xy 339.053712 -226.348287) (xy 339.104233 -226.354421) (xy 339.153117 -226.368581)
			(xy 339.199096 -226.390398) (xy 339.24098 -226.419308) (xy 339.277684 -226.454563) (xy 339.308257 -226.495249)
			(xy 339.331908 -226.540312) (xy 339.348024 -226.588586) (xy 339.356188 -226.63882) (xy 339.3567 -226.664266)
			(xy 339.664797 -226.664266) (xy 339.668892 -226.613538) (xy 339.681071 -226.564124) (xy 339.701019 -226.517304)
			(xy 339.72822 -226.47429) (xy 339.761968 -226.436196) (xy 339.80139 -226.404009) (xy 339.845464 -226.378563)
			(xy 339.89305 -226.360516) (xy 339.942914 -226.350336) (xy 339.993766 -226.348287) (xy 340.044287 -226.354421)
			(xy 340.093171 -226.368581) (xy 340.13915 -226.390398) (xy 340.181034 -226.419308) (xy 340.217738 -226.454563)
			(xy 340.248311 -226.495249) (xy 340.271962 -226.540312) (xy 340.288078 -226.588586) (xy 340.296242 -226.63882)
			(xy 340.296754 -226.664266) (xy 340.615282 -226.664266) (xy 340.619242 -226.615212) (xy 340.631019 -226.567428)
			(xy 340.65031 -226.522152) (xy 340.676613 -226.480556) (xy 340.709248 -226.443719) (xy 340.747369 -226.412594)
			(xy 340.78999 -226.387987) (xy 340.836006 -226.370535) (xy 340.884225 -226.360691) (xy 340.9334 -226.35871)
			(xy 340.982255 -226.364642) (xy 341.029526 -226.378334) (xy 341.073988 -226.399432) (xy 341.114491 -226.427388)
			(xy 341.149984 -226.46148) (xy 341.179549 -226.500824) (xy 341.20242 -226.544401) (xy 341.218004 -226.591082)
			(xy 341.225899 -226.639659) (xy 341.226394 -226.664266) (xy 341.544905 -226.664266) (xy 341.549 -226.613538)
			(xy 341.561179 -226.564124) (xy 341.581127 -226.517304) (xy 341.608328 -226.47429) (xy 341.642076 -226.436196)
			(xy 341.681498 -226.404009) (xy 341.725572 -226.378563) (xy 341.773158 -226.360516) (xy 341.823022 -226.350336)
			(xy 341.873874 -226.348287) (xy 341.924395 -226.354421) (xy 341.973279 -226.368581) (xy 342.019258 -226.390398)
			(xy 342.061142 -226.419308) (xy 342.097846 -226.454563) (xy 342.128419 -226.495249) (xy 342.15207 -226.540312)
			(xy 342.168186 -226.588586) (xy 342.17635 -226.63882) (xy 342.176862 -226.664266) (xy 342.49539 -226.664266)
			(xy 342.49935 -226.615212) (xy 342.511127 -226.567428) (xy 342.530418 -226.522152) (xy 342.556721 -226.480556)
			(xy 342.589356 -226.443719) (xy 342.627477 -226.412594) (xy 342.670098 -226.387987) (xy 342.716114 -226.370535)
			(xy 342.764333 -226.360691) (xy 342.813508 -226.35871) (xy 342.862363 -226.364642) (xy 342.909634 -226.378334)
			(xy 342.954096 -226.399432) (xy 342.994599 -226.427388) (xy 343.030092 -226.46148) (xy 343.059657 -226.500824)
			(xy 343.082528 -226.544401) (xy 343.098112 -226.591082) (xy 343.106007 -226.639659) (xy 343.106502 -226.664266)
			(xy 343.106007 -226.688873) (xy 343.098112 -226.73745) (xy 343.082528 -226.784131) (xy 343.059657 -226.827708)
			(xy 343.030092 -226.867052) (xy 342.994599 -226.901144) (xy 342.954096 -226.9291) (xy 342.909634 -226.950198)
			(xy 342.862363 -226.96389) (xy 342.813508 -226.969822) (xy 342.764333 -226.967841) (xy 342.716114 -226.957997)
			(xy 342.670098 -226.940545) (xy 342.627477 -226.915938) (xy 342.589356 -226.884813) (xy 342.556721 -226.847976)
			(xy 342.530418 -226.80638) (xy 342.511127 -226.761104) (xy 342.49935 -226.71332) (xy 342.49539 -226.664266)
			(xy 342.176862 -226.664266) (xy 342.17635 -226.689712) (xy 342.168186 -226.739946) (xy 342.15207 -226.78822)
			(xy 342.128419 -226.833283) (xy 342.097846 -226.873969) (xy 342.061142 -226.909224) (xy 342.019258 -226.938134)
			(xy 341.973279 -226.959951) (xy 341.924395 -226.974111) (xy 341.873874 -226.980245) (xy 341.823022 -226.978196)
			(xy 341.773158 -226.968016) (xy 341.725572 -226.949969) (xy 341.681498 -226.924523) (xy 341.642076 -226.892336)
			(xy 341.608328 -226.854242) (xy 341.581127 -226.811228) (xy 341.561179 -226.764408) (xy 341.549 -226.714994)
			(xy 341.544905 -226.664266) (xy 341.226394 -226.664266) (xy 341.225899 -226.688873) (xy 341.218004 -226.73745)
			(xy 341.20242 -226.784131) (xy 341.179549 -226.827708) (xy 341.149984 -226.867052) (xy 341.114491 -226.901144)
			(xy 341.073988 -226.9291) (xy 341.029526 -226.950198) (xy 340.982255 -226.96389) (xy 340.9334 -226.969822)
			(xy 340.884225 -226.967841) (xy 340.836006 -226.957997) (xy 340.78999 -226.940545) (xy 340.747369 -226.915938)
			(xy 340.709248 -226.884813) (xy 340.676613 -226.847976) (xy 340.65031 -226.80638) (xy 340.631019 -226.761104)
			(xy 340.619242 -226.71332) (xy 340.615282 -226.664266) (xy 340.296754 -226.664266) (xy 340.296242 -226.689712)
			(xy 340.288078 -226.739946) (xy 340.271962 -226.78822) (xy 340.248311 -226.833283) (xy 340.217738 -226.873969)
			(xy 340.181034 -226.909224) (xy 340.13915 -226.938134) (xy 340.093171 -226.959951) (xy 340.044287 -226.974111)
			(xy 339.993766 -226.980245) (xy 339.942914 -226.978196) (xy 339.89305 -226.968016) (xy 339.845464 -226.949969)
			(xy 339.80139 -226.924523) (xy 339.761968 -226.892336) (xy 339.72822 -226.854242) (xy 339.701019 -226.811228)
			(xy 339.681071 -226.764408) (xy 339.668892 -226.714994) (xy 339.664797 -226.664266) (xy 339.3567 -226.664266)
			(xy 339.356188 -226.689712) (xy 339.348024 -226.739946) (xy 339.331908 -226.78822) (xy 339.308257 -226.833283)
			(xy 339.277684 -226.873969) (xy 339.24098 -226.909224) (xy 339.199096 -226.938134) (xy 339.153117 -226.959951)
			(xy 339.104233 -226.974111) (xy 339.053712 -226.980245) (xy 339.00286 -226.978196) (xy 338.952996 -226.968016)
			(xy 338.90541 -226.949969) (xy 338.861336 -226.924523) (xy 338.821914 -226.892336) (xy 338.788166 -226.854242)
			(xy 338.760965 -226.811228) (xy 338.741017 -226.764408) (xy 338.728838 -226.714994) (xy 338.724743 -226.664266)
			(xy 338.406271 -226.664266) (xy 338.406272 -226.688761) (xy 338.398469 -226.737066) (xy 338.383064 -226.783508)
			(xy 338.360449 -226.8269) (xy 338.331204 -226.866129) (xy 338.296077 -226.900193) (xy 338.255968 -226.92822)
			(xy 338.211903 -226.949491) (xy 338.165009 -226.963464) (xy 338.140802 -226.967034) (xy 338.132674 -226.968304)
			(xy 338.109814 -226.979226) (xy 338.105727 -226.981286) (xy 338.098313 -226.986652) (xy 338.095082 -226.989894)
			(xy 338.08035 -227.005388) (xy 338.073962 -227.012707) (xy 338.066765 -227.030734) (xy 338.06638 -227.04044)
			(xy 338.06638 -227.474272) (xy 338.254843 -227.474272) (xy 338.258938 -227.423544) (xy 338.271117 -227.37413)
			(xy 338.291065 -227.32731) (xy 338.318266 -227.284296) (xy 338.352014 -227.246202) (xy 338.391436 -227.214015)
			(xy 338.43551 -227.188569) (xy 338.483096 -227.170522) (xy 338.53296 -227.160342) (xy 338.583812 -227.158293)
			(xy 338.634333 -227.164427) (xy 338.683217 -227.178587) (xy 338.729196 -227.200404) (xy 338.77108 -227.229314)
			(xy 338.807784 -227.264569) (xy 338.838357 -227.305255) (xy 338.862008 -227.350318) (xy 338.878124 -227.398592)
			(xy 338.886288 -227.448826) (xy 338.8868 -227.474272) (xy 339.205328 -227.474272) (xy 339.209288 -227.425218)
			(xy 339.221065 -227.377434) (xy 339.240356 -227.332158) (xy 339.266659 -227.290562) (xy 339.299294 -227.253725)
			(xy 339.337415 -227.2226) (xy 339.380036 -227.197993) (xy 339.426052 -227.180541) (xy 339.474271 -227.170697)
			(xy 339.523446 -227.168716) (xy 339.572301 -227.174648) (xy 339.619572 -227.18834) (xy 339.664034 -227.209438)
			(xy 339.704537 -227.237394) (xy 339.74003 -227.271486) (xy 339.769595 -227.31083) (xy 339.792466 -227.354407)
			(xy 339.80805 -227.401088) (xy 339.815945 -227.449665) (xy 339.81644 -227.474272) (xy 340.134951 -227.474272)
			(xy 340.139046 -227.423544) (xy 340.151225 -227.37413) (xy 340.171173 -227.32731) (xy 340.198374 -227.284296)
			(xy 340.232122 -227.246202) (xy 340.271544 -227.214015) (xy 340.315618 -227.188569) (xy 340.363204 -227.170522)
			(xy 340.413068 -227.160342) (xy 340.46392 -227.158293) (xy 340.514441 -227.164427) (xy 340.563325 -227.178587)
			(xy 340.609304 -227.200404) (xy 340.651188 -227.229314) (xy 340.687892 -227.264569) (xy 340.718465 -227.305255)
			(xy 340.742116 -227.350318) (xy 340.758232 -227.398592) (xy 340.766396 -227.448826) (xy 340.766908 -227.474272)
			(xy 341.085182 -227.474272) (xy 341.089142 -227.425218) (xy 341.100919 -227.377434) (xy 341.12021 -227.332158)
			(xy 341.146513 -227.290562) (xy 341.179148 -227.253725) (xy 341.217269 -227.2226) (xy 341.25989 -227.197993)
			(xy 341.305906 -227.180541) (xy 341.354125 -227.170697) (xy 341.4033 -227.168716) (xy 341.452155 -227.174648)
			(xy 341.499426 -227.18834) (xy 341.543888 -227.209438) (xy 341.584391 -227.237394) (xy 341.619884 -227.271486)
			(xy 341.649449 -227.31083) (xy 341.67232 -227.354407) (xy 341.687904 -227.401088) (xy 341.695799 -227.449665)
			(xy 341.696294 -227.474272) (xy 342.014805 -227.474272) (xy 342.0189 -227.423544) (xy 342.031079 -227.37413)
			(xy 342.051027 -227.32731) (xy 342.078228 -227.284296) (xy 342.111976 -227.246202) (xy 342.151398 -227.214015)
			(xy 342.195472 -227.188569) (xy 342.243058 -227.170522) (xy 342.292922 -227.160342) (xy 342.343774 -227.158293)
			(xy 342.394295 -227.164427) (xy 342.443179 -227.178587) (xy 342.489158 -227.200404) (xy 342.531042 -227.229314)
			(xy 342.567746 -227.264569) (xy 342.598319 -227.305255) (xy 342.62197 -227.350318) (xy 342.638086 -227.398592)
			(xy 342.64625 -227.448826) (xy 342.646762 -227.474272) (xy 342.954859 -227.474272) (xy 342.958954 -227.423544)
			(xy 342.971133 -227.37413) (xy 342.991081 -227.32731) (xy 343.018282 -227.284296) (xy 343.05203 -227.246202)
			(xy 343.091452 -227.214015) (xy 343.135526 -227.188569) (xy 343.183112 -227.170522) (xy 343.232976 -227.160342)
			(xy 343.283828 -227.158293) (xy 343.334349 -227.164427) (xy 343.383233 -227.178587) (xy 343.429212 -227.200404)
			(xy 343.471096 -227.229314) (xy 343.5078 -227.264569) (xy 343.538373 -227.305255) (xy 343.562024 -227.350318)
			(xy 343.57814 -227.398592) (xy 343.586304 -227.448826) (xy 343.586816 -227.474272) (xy 343.586304 -227.499718)
			(xy 343.57814 -227.549952) (xy 343.562024 -227.598226) (xy 343.538373 -227.643289) (xy 343.5078 -227.683975)
			(xy 343.471096 -227.71923) (xy 343.429212 -227.74814) (xy 343.383233 -227.769957) (xy 343.334349 -227.784117)
			(xy 343.283828 -227.790251) (xy 343.232976 -227.788202) (xy 343.183112 -227.778022) (xy 343.135526 -227.759975)
			(xy 343.091452 -227.734529) (xy 343.05203 -227.702342) (xy 343.018282 -227.664248) (xy 342.991081 -227.621234)
			(xy 342.971133 -227.574414) (xy 342.958954 -227.525) (xy 342.954859 -227.474272) (xy 342.646762 -227.474272)
			(xy 342.64625 -227.499718) (xy 342.638086 -227.549952) (xy 342.62197 -227.598226) (xy 342.598319 -227.643289)
			(xy 342.567746 -227.683975) (xy 342.531042 -227.71923) (xy 342.489158 -227.74814) (xy 342.443179 -227.769957)
			(xy 342.394295 -227.784117) (xy 342.343774 -227.790251) (xy 342.292922 -227.788202) (xy 342.243058 -227.778022)
			(xy 342.195472 -227.759975) (xy 342.151398 -227.734529) (xy 342.111976 -227.702342) (xy 342.078228 -227.664248)
			(xy 342.051027 -227.621234) (xy 342.031079 -227.574414) (xy 342.0189 -227.525) (xy 342.014805 -227.474272)
			(xy 341.696294 -227.474272) (xy 341.695799 -227.498879) (xy 341.687904 -227.547456) (xy 341.67232 -227.594137)
			(xy 341.649449 -227.637714) (xy 341.619884 -227.677058) (xy 341.584391 -227.71115) (xy 341.543888 -227.739106)
			(xy 341.499426 -227.760204) (xy 341.452155 -227.773896) (xy 341.4033 -227.779828) (xy 341.354125 -227.777847)
			(xy 341.305906 -227.768003) (xy 341.25989 -227.750551) (xy 341.217269 -227.725944) (xy 341.179148 -227.694819)
			(xy 341.146513 -227.657982) (xy 341.12021 -227.616386) (xy 341.100919 -227.57111) (xy 341.089142 -227.523326)
			(xy 341.085182 -227.474272) (xy 340.766908 -227.474272) (xy 340.766396 -227.499718) (xy 340.758232 -227.549952)
			(xy 340.742116 -227.598226) (xy 340.718465 -227.643289) (xy 340.687892 -227.683975) (xy 340.651188 -227.71923)
			(xy 340.609304 -227.74814) (xy 340.563325 -227.769957) (xy 340.514441 -227.784117) (xy 340.46392 -227.790251)
			(xy 340.413068 -227.788202) (xy 340.363204 -227.778022) (xy 340.315618 -227.759975) (xy 340.271544 -227.734529)
			(xy 340.232122 -227.702342) (xy 340.198374 -227.664248) (xy 340.171173 -227.621234) (xy 340.151225 -227.574414)
			(xy 340.139046 -227.525) (xy 340.134951 -227.474272) (xy 339.81644 -227.474272) (xy 339.815945 -227.498879)
			(xy 339.80805 -227.547456) (xy 339.792466 -227.594137) (xy 339.769595 -227.637714) (xy 339.74003 -227.677058)
			(xy 339.704537 -227.71115) (xy 339.664034 -227.739106) (xy 339.619572 -227.760204) (xy 339.572301 -227.773896)
			(xy 339.523446 -227.779828) (xy 339.474271 -227.777847) (xy 339.426052 -227.768003) (xy 339.380036 -227.750551)
			(xy 339.337415 -227.725944) (xy 339.299294 -227.694819) (xy 339.266659 -227.657982) (xy 339.240356 -227.616386)
			(xy 339.221065 -227.57111) (xy 339.209288 -227.523326) (xy 339.205328 -227.474272) (xy 338.8868 -227.474272)
			(xy 338.886288 -227.499718) (xy 338.878124 -227.549952) (xy 338.862008 -227.598226) (xy 338.838357 -227.643289)
			(xy 338.807784 -227.683975) (xy 338.77108 -227.71923) (xy 338.729196 -227.74814) (xy 338.683217 -227.769957)
			(xy 338.634333 -227.784117) (xy 338.583812 -227.790251) (xy 338.53296 -227.788202) (xy 338.483096 -227.778022)
			(xy 338.43551 -227.759975) (xy 338.391436 -227.734529) (xy 338.352014 -227.702342) (xy 338.318266 -227.664248)
			(xy 338.291065 -227.621234) (xy 338.271117 -227.574414) (xy 338.258938 -227.525) (xy 338.254843 -227.474272)
			(xy 338.06638 -227.474272) (xy 338.06638 -227.908104) (xy 338.066817 -227.917799) (xy 338.074009 -227.935808)
			(xy 338.08035 -227.943156) (xy 338.095082 -227.95865) (xy 338.09832 -227.961884) (xy 338.105727 -227.967259)
			(xy 338.109814 -227.969318) (xy 338.132674 -227.98024) (xy 338.140802 -227.98151) (xy 338.165 -227.985146)
			(xy 338.211892 -227.999117) (xy 338.255956 -228.020387) (xy 338.296064 -228.048411) (xy 338.33119 -228.082473)
			(xy 338.360435 -228.1217) (xy 338.38305 -228.16509) (xy 338.398456 -228.21153) (xy 338.406259 -228.259833)
			(xy 338.406259 -228.284278) (xy 338.724743 -228.284278) (xy 338.728838 -228.23355) (xy 338.741017 -228.184136)
			(xy 338.760965 -228.137316) (xy 338.788166 -228.094302) (xy 338.821914 -228.056208) (xy 338.861336 -228.024021)
			(xy 338.90541 -227.998575) (xy 338.952996 -227.980528) (xy 339.00286 -227.970348) (xy 339.053712 -227.968299)
			(xy 339.104233 -227.974433) (xy 339.153117 -227.988593) (xy 339.199096 -228.01041) (xy 339.24098 -228.03932)
			(xy 339.277684 -228.074575) (xy 339.308257 -228.115261) (xy 339.331908 -228.160324) (xy 339.348024 -228.208598)
			(xy 339.356188 -228.258832) (xy 339.3567 -228.284278) (xy 339.664797 -228.284278) (xy 339.668892 -228.23355)
			(xy 339.681071 -228.184136) (xy 339.701019 -228.137316) (xy 339.72822 -228.094302) (xy 339.761968 -228.056208)
			(xy 339.80139 -228.024021) (xy 339.845464 -227.998575) (xy 339.89305 -227.980528) (xy 339.942914 -227.970348)
			(xy 339.993766 -227.968299) (xy 340.044287 -227.974433) (xy 340.093171 -227.988593) (xy 340.13915 -228.01041)
			(xy 340.181034 -228.03932) (xy 340.217738 -228.074575) (xy 340.248311 -228.115261) (xy 340.271962 -228.160324)
			(xy 340.288078 -228.208598) (xy 340.296242 -228.258832) (xy 340.296754 -228.284278) (xy 340.615282 -228.284278)
			(xy 340.619242 -228.235224) (xy 340.631019 -228.18744) (xy 340.65031 -228.142164) (xy 340.676613 -228.100568)
			(xy 340.709248 -228.063731) (xy 340.747369 -228.032606) (xy 340.78999 -228.007999) (xy 340.836006 -227.990547)
			(xy 340.884225 -227.980703) (xy 340.9334 -227.978722) (xy 340.982255 -227.984654) (xy 341.029526 -227.998346)
			(xy 341.073988 -228.019444) (xy 341.114491 -228.0474) (xy 341.149984 -228.081492) (xy 341.179549 -228.120836)
			(xy 341.20242 -228.164413) (xy 341.218004 -228.211094) (xy 341.225899 -228.259671) (xy 341.226394 -228.284278)
			(xy 341.544905 -228.284278) (xy 341.549 -228.23355) (xy 341.561179 -228.184136) (xy 341.581127 -228.137316)
			(xy 341.608328 -228.094302) (xy 341.642076 -228.056208) (xy 341.681498 -228.024021) (xy 341.725572 -227.998575)
			(xy 341.773158 -227.980528) (xy 341.823022 -227.970348) (xy 341.873874 -227.968299) (xy 341.924395 -227.974433)
			(xy 341.973279 -227.988593) (xy 342.019258 -228.01041) (xy 342.061142 -228.03932) (xy 342.097846 -228.074575)
			(xy 342.128419 -228.115261) (xy 342.15207 -228.160324) (xy 342.168186 -228.208598) (xy 342.17635 -228.258832)
			(xy 342.176862 -228.284278) (xy 342.49539 -228.284278) (xy 342.49935 -228.235224) (xy 342.511127 -228.18744)
			(xy 342.530418 -228.142164) (xy 342.556721 -228.100568) (xy 342.589356 -228.063731) (xy 342.627477 -228.032606)
			(xy 342.670098 -228.007999) (xy 342.716114 -227.990547) (xy 342.764333 -227.980703) (xy 342.813508 -227.978722)
			(xy 342.862363 -227.984654) (xy 342.909634 -227.998346) (xy 342.954096 -228.019444) (xy 342.994599 -228.0474)
			(xy 343.030092 -228.081492) (xy 343.059657 -228.120836) (xy 343.082528 -228.164413) (xy 343.098112 -228.211094)
			(xy 343.106007 -228.259671) (xy 343.106502 -228.284278) (xy 343.106007 -228.308885) (xy 343.098112 -228.357462)
			(xy 343.082528 -228.404143) (xy 343.059657 -228.44772) (xy 343.030092 -228.487064) (xy 342.994599 -228.521156)
			(xy 342.954096 -228.549112) (xy 342.909634 -228.57021) (xy 342.862363 -228.583902) (xy 342.813508 -228.589834)
			(xy 342.764333 -228.587853) (xy 342.716114 -228.578009) (xy 342.670098 -228.560557) (xy 342.627477 -228.53595)
			(xy 342.589356 -228.504825) (xy 342.556721 -228.467988) (xy 342.530418 -228.426392) (xy 342.511127 -228.381116)
			(xy 342.49935 -228.333332) (xy 342.49539 -228.284278) (xy 342.176862 -228.284278) (xy 342.17635 -228.309724)
			(xy 342.168186 -228.359958) (xy 342.15207 -228.408232) (xy 342.128419 -228.453295) (xy 342.097846 -228.493981)
			(xy 342.061142 -228.529236) (xy 342.019258 -228.558146) (xy 341.973279 -228.579963) (xy 341.924395 -228.594123)
			(xy 341.873874 -228.600257) (xy 341.823022 -228.598208) (xy 341.773158 -228.588028) (xy 341.725572 -228.569981)
			(xy 341.681498 -228.544535) (xy 341.642076 -228.512348) (xy 341.608328 -228.474254) (xy 341.581127 -228.43124)
			(xy 341.561179 -228.38442) (xy 341.549 -228.335006) (xy 341.544905 -228.284278) (xy 341.226394 -228.284278)
			(xy 341.225899 -228.308885) (xy 341.218004 -228.357462) (xy 341.20242 -228.404143) (xy 341.179549 -228.44772)
			(xy 341.149984 -228.487064) (xy 341.114491 -228.521156) (xy 341.073988 -228.549112) (xy 341.029526 -228.57021)
			(xy 340.982255 -228.583902) (xy 340.9334 -228.589834) (xy 340.884225 -228.587853) (xy 340.836006 -228.578009)
			(xy 340.78999 -228.560557) (xy 340.747369 -228.53595) (xy 340.709248 -228.504825) (xy 340.676613 -228.467988)
			(xy 340.65031 -228.426392) (xy 340.631019 -228.381116) (xy 340.619242 -228.333332) (xy 340.615282 -228.284278)
			(xy 340.296754 -228.284278) (xy 340.296242 -228.309724) (xy 340.288078 -228.359958) (xy 340.271962 -228.408232)
			(xy 340.248311 -228.453295) (xy 340.217738 -228.493981) (xy 340.181034 -228.529236) (xy 340.13915 -228.558146)
			(xy 340.093171 -228.579963) (xy 340.044287 -228.594123) (xy 339.993766 -228.600257) (xy 339.942914 -228.598208)
			(xy 339.89305 -228.588028) (xy 339.845464 -228.569981) (xy 339.80139 -228.544535) (xy 339.761968 -228.512348)
			(xy 339.72822 -228.474254) (xy 339.701019 -228.43124) (xy 339.681071 -228.38442) (xy 339.668892 -228.335006)
			(xy 339.664797 -228.284278) (xy 339.3567 -228.284278) (xy 339.356188 -228.309724) (xy 339.348024 -228.359958)
			(xy 339.331908 -228.408232) (xy 339.308257 -228.453295) (xy 339.277684 -228.493981) (xy 339.24098 -228.529236)
			(xy 339.199096 -228.558146) (xy 339.153117 -228.579963) (xy 339.104233 -228.594123) (xy 339.053712 -228.600257)
			(xy 339.00286 -228.598208) (xy 338.952996 -228.588028) (xy 338.90541 -228.569981) (xy 338.861336 -228.544535)
			(xy 338.821914 -228.512348) (xy 338.788166 -228.474254) (xy 338.760965 -228.43124) (xy 338.741017 -228.38442)
			(xy 338.728838 -228.335006) (xy 338.724743 -228.284278) (xy 338.406259 -228.284278) (xy 338.40626 -228.308762)
			(xy 338.398457 -228.357065) (xy 338.383052 -228.403505) (xy 338.360438 -228.446895) (xy 338.331194 -228.486123)
			(xy 338.296069 -228.520185) (xy 338.255961 -228.54821) (xy 338.211897 -228.569481) (xy 338.165005 -228.583452)
			(xy 338.140802 -228.587046) (xy 338.132674 -228.588316) (xy 338.109814 -228.599238) (xy 338.105727 -228.601298)
			(xy 338.098314 -228.606665) (xy 338.095082 -228.609906) (xy 338.08035 -228.6254) (xy 338.073964 -228.63272)
			(xy 338.066771 -228.650746) (xy 338.06638 -228.660452) (xy 338.06638 -229.094284) (xy 338.254843 -229.094284)
			(xy 338.258938 -229.043556) (xy 338.271117 -228.994142) (xy 338.291065 -228.947322) (xy 338.318266 -228.904308)
			(xy 338.352014 -228.866214) (xy 338.391436 -228.834027) (xy 338.43551 -228.808581) (xy 338.483096 -228.790534)
			(xy 338.53296 -228.780354) (xy 338.583812 -228.778305) (xy 338.634333 -228.784439) (xy 338.683217 -228.798599)
			(xy 338.729196 -228.820416) (xy 338.77108 -228.849326) (xy 338.807784 -228.884581) (xy 338.838357 -228.925267)
			(xy 338.862008 -228.97033) (xy 338.878124 -229.018604) (xy 338.886288 -229.068838) (xy 338.8868 -229.094284)
			(xy 339.205328 -229.094284) (xy 339.209288 -229.04523) (xy 339.221065 -228.997446) (xy 339.240356 -228.95217)
			(xy 339.266659 -228.910574) (xy 339.299294 -228.873737) (xy 339.337415 -228.842612) (xy 339.380036 -228.818005)
			(xy 339.426052 -228.800553) (xy 339.474271 -228.790709) (xy 339.523446 -228.788728) (xy 339.572301 -228.79466)
			(xy 339.619572 -228.808352) (xy 339.664034 -228.82945) (xy 339.704537 -228.857406) (xy 339.74003 -228.891498)
			(xy 339.769595 -228.930842) (xy 339.792466 -228.974419) (xy 339.80805 -229.0211) (xy 339.815945 -229.069677)
			(xy 339.81644 -229.094284) (xy 340.134951 -229.094284) (xy 340.139046 -229.043556) (xy 340.151225 -228.994142)
			(xy 340.171173 -228.947322) (xy 340.198374 -228.904308) (xy 340.232122 -228.866214) (xy 340.271544 -228.834027)
			(xy 340.315618 -228.808581) (xy 340.363204 -228.790534) (xy 340.413068 -228.780354) (xy 340.46392 -228.778305)
			(xy 340.514441 -228.784439) (xy 340.563325 -228.798599) (xy 340.609304 -228.820416) (xy 340.651188 -228.849326)
			(xy 340.687892 -228.884581) (xy 340.718465 -228.925267) (xy 340.742116 -228.97033) (xy 340.758232 -229.018604)
			(xy 340.766396 -229.068838) (xy 340.766908 -229.094284) (xy 341.085182 -229.094284) (xy 341.089142 -229.04523)
			(xy 341.100919 -228.997446) (xy 341.12021 -228.95217) (xy 341.146513 -228.910574) (xy 341.179148 -228.873737)
			(xy 341.217269 -228.842612) (xy 341.25989 -228.818005) (xy 341.305906 -228.800553) (xy 341.354125 -228.790709)
			(xy 341.4033 -228.788728) (xy 341.452155 -228.79466) (xy 341.499426 -228.808352) (xy 341.543888 -228.82945)
			(xy 341.584391 -228.857406) (xy 341.619884 -228.891498) (xy 341.649449 -228.930842) (xy 341.67232 -228.974419)
			(xy 341.687904 -229.0211) (xy 341.695799 -229.069677) (xy 341.696294 -229.094284) (xy 342.014805 -229.094284)
			(xy 342.0189 -229.043556) (xy 342.031079 -228.994142) (xy 342.051027 -228.947322) (xy 342.078228 -228.904308)
			(xy 342.111976 -228.866214) (xy 342.151398 -228.834027) (xy 342.195472 -228.808581) (xy 342.243058 -228.790534)
			(xy 342.292922 -228.780354) (xy 342.343774 -228.778305) (xy 342.394295 -228.784439) (xy 342.443179 -228.798599)
			(xy 342.489158 -228.820416) (xy 342.531042 -228.849326) (xy 342.567746 -228.884581) (xy 342.598319 -228.925267)
			(xy 342.62197 -228.97033) (xy 342.638086 -229.018604) (xy 342.64625 -229.068838) (xy 342.646762 -229.094284)
			(xy 342.954859 -229.094284) (xy 342.958954 -229.043556) (xy 342.971133 -228.994142) (xy 342.991081 -228.947322)
			(xy 343.018282 -228.904308) (xy 343.05203 -228.866214) (xy 343.091452 -228.834027) (xy 343.135526 -228.808581)
			(xy 343.183112 -228.790534) (xy 343.232976 -228.780354) (xy 343.283828 -228.778305) (xy 343.334349 -228.784439)
			(xy 343.383233 -228.798599) (xy 343.429212 -228.820416) (xy 343.471096 -228.849326) (xy 343.5078 -228.884581)
			(xy 343.538373 -228.925267) (xy 343.562024 -228.97033) (xy 343.57814 -229.018604) (xy 343.586304 -229.068838)
			(xy 343.586816 -229.094284) (xy 343.586304 -229.11973) (xy 343.57814 -229.169964) (xy 343.562024 -229.218238)
			(xy 343.538373 -229.263301) (xy 343.5078 -229.303987) (xy 343.471096 -229.339242) (xy 343.429212 -229.368152)
			(xy 343.383233 -229.389969) (xy 343.334349 -229.404129) (xy 343.283828 -229.410263) (xy 343.232976 -229.408214)
			(xy 343.183112 -229.398034) (xy 343.135526 -229.379987) (xy 343.091452 -229.354541) (xy 343.05203 -229.322354)
			(xy 343.018282 -229.28426) (xy 342.991081 -229.241246) (xy 342.971133 -229.194426) (xy 342.958954 -229.145012)
			(xy 342.954859 -229.094284) (xy 342.646762 -229.094284) (xy 342.64625 -229.11973) (xy 342.638086 -229.169964)
			(xy 342.62197 -229.218238) (xy 342.598319 -229.263301) (xy 342.567746 -229.303987) (xy 342.531042 -229.339242)
			(xy 342.489158 -229.368152) (xy 342.443179 -229.389969) (xy 342.394295 -229.404129) (xy 342.343774 -229.410263)
			(xy 342.292922 -229.408214) (xy 342.243058 -229.398034) (xy 342.195472 -229.379987) (xy 342.151398 -229.354541)
			(xy 342.111976 -229.322354) (xy 342.078228 -229.28426) (xy 342.051027 -229.241246) (xy 342.031079 -229.194426)
			(xy 342.0189 -229.145012) (xy 342.014805 -229.094284) (xy 341.696294 -229.094284) (xy 341.695799 -229.118891)
			(xy 341.687904 -229.167468) (xy 341.67232 -229.214149) (xy 341.649449 -229.257726) (xy 341.619884 -229.29707)
			(xy 341.584391 -229.331162) (xy 341.543888 -229.359118) (xy 341.499426 -229.380216) (xy 341.452155 -229.393908)
			(xy 341.4033 -229.39984) (xy 341.354125 -229.397859) (xy 341.305906 -229.388015) (xy 341.25989 -229.370563)
			(xy 341.217269 -229.345956) (xy 341.179148 -229.314831) (xy 341.146513 -229.277994) (xy 341.12021 -229.236398)
			(xy 341.100919 -229.191122) (xy 341.089142 -229.143338) (xy 341.085182 -229.094284) (xy 340.766908 -229.094284)
			(xy 340.766396 -229.11973) (xy 340.758232 -229.169964) (xy 340.742116 -229.218238) (xy 340.718465 -229.263301)
			(xy 340.687892 -229.303987) (xy 340.651188 -229.339242) (xy 340.609304 -229.368152) (xy 340.563325 -229.389969)
			(xy 340.514441 -229.404129) (xy 340.46392 -229.410263) (xy 340.413068 -229.408214) (xy 340.363204 -229.398034)
			(xy 340.315618 -229.379987) (xy 340.271544 -229.354541) (xy 340.232122 -229.322354) (xy 340.198374 -229.28426)
			(xy 340.171173 -229.241246) (xy 340.151225 -229.194426) (xy 340.139046 -229.145012) (xy 340.134951 -229.094284)
			(xy 339.81644 -229.094284) (xy 339.815945 -229.118891) (xy 339.80805 -229.167468) (xy 339.792466 -229.214149)
			(xy 339.769595 -229.257726) (xy 339.74003 -229.29707) (xy 339.704537 -229.331162) (xy 339.664034 -229.359118)
			(xy 339.619572 -229.380216) (xy 339.572301 -229.393908) (xy 339.523446 -229.39984) (xy 339.474271 -229.397859)
			(xy 339.426052 -229.388015) (xy 339.380036 -229.370563) (xy 339.337415 -229.345956) (xy 339.299294 -229.314831)
			(xy 339.266659 -229.277994) (xy 339.240356 -229.236398) (xy 339.221065 -229.191122) (xy 339.209288 -229.143338)
			(xy 339.205328 -229.094284) (xy 338.8868 -229.094284) (xy 338.886288 -229.11973) (xy 338.878124 -229.169964)
			(xy 338.862008 -229.218238) (xy 338.838357 -229.263301) (xy 338.807784 -229.303987) (xy 338.77108 -229.339242)
			(xy 338.729196 -229.368152) (xy 338.683217 -229.389969) (xy 338.634333 -229.404129) (xy 338.583812 -229.410263)
			(xy 338.53296 -229.408214) (xy 338.483096 -229.398034) (xy 338.43551 -229.379987) (xy 338.391436 -229.354541)
			(xy 338.352014 -229.322354) (xy 338.318266 -229.28426) (xy 338.291065 -229.241246) (xy 338.271117 -229.194426)
			(xy 338.258938 -229.145012) (xy 338.254843 -229.094284) (xy 338.06638 -229.094284) (xy 338.06638 -229.527862)
			(xy 338.06681 -229.53756) (xy 338.073991 -229.555579) (xy 338.08035 -229.562914) (xy 338.095082 -229.578408)
			(xy 338.098322 -229.581639) (xy 338.105732 -229.587008) (xy 338.109814 -229.589076) (xy 338.132674 -229.599998)
			(xy 338.140802 -229.601268) (xy 338.164995 -229.604904) (xy 338.211878 -229.618873) (xy 338.255933 -229.64014)
			(xy 338.296033 -229.66816) (xy 338.331152 -229.702217) (xy 338.36039 -229.741437) (xy 338.383 -229.784819)
			(xy 338.398402 -229.831251) (xy 338.406202 -229.879545) (xy 338.406202 -229.904036) (xy 338.724743 -229.904036)
			(xy 338.728838 -229.853308) (xy 338.741017 -229.803894) (xy 338.760965 -229.757074) (xy 338.788166 -229.71406)
			(xy 338.821914 -229.675966) (xy 338.861336 -229.643779) (xy 338.90541 -229.618333) (xy 338.952996 -229.600286)
			(xy 339.00286 -229.590106) (xy 339.053712 -229.588057) (xy 339.104233 -229.594191) (xy 339.153117 -229.608351)
			(xy 339.199096 -229.630168) (xy 339.24098 -229.659078) (xy 339.277684 -229.694333) (xy 339.308257 -229.735019)
			(xy 339.331908 -229.780082) (xy 339.348024 -229.828356) (xy 339.356188 -229.87859) (xy 339.3567 -229.904036)
			(xy 339.664797 -229.904036) (xy 339.668892 -229.853308) (xy 339.681071 -229.803894) (xy 339.701019 -229.757074)
			(xy 339.72822 -229.71406) (xy 339.761968 -229.675966) (xy 339.80139 -229.643779) (xy 339.845464 -229.618333)
			(xy 339.89305 -229.600286) (xy 339.942914 -229.590106) (xy 339.993766 -229.588057) (xy 340.044287 -229.594191)
			(xy 340.093171 -229.608351) (xy 340.13915 -229.630168) (xy 340.181034 -229.659078) (xy 340.217738 -229.694333)
			(xy 340.248311 -229.735019) (xy 340.271962 -229.780082) (xy 340.288078 -229.828356) (xy 340.296242 -229.87859)
			(xy 340.296754 -229.904036) (xy 340.615282 -229.904036) (xy 340.619242 -229.854982) (xy 340.631019 -229.807198)
			(xy 340.65031 -229.761922) (xy 340.676613 -229.720326) (xy 340.709248 -229.683489) (xy 340.747369 -229.652364)
			(xy 340.78999 -229.627757) (xy 340.836006 -229.610305) (xy 340.884225 -229.600461) (xy 340.9334 -229.59848)
			(xy 340.982255 -229.604412) (xy 341.029526 -229.618104) (xy 341.073988 -229.639202) (xy 341.114491 -229.667158)
			(xy 341.149984 -229.70125) (xy 341.179549 -229.740594) (xy 341.20242 -229.784171) (xy 341.218004 -229.830852)
			(xy 341.225899 -229.879429) (xy 341.226394 -229.904036) (xy 341.544905 -229.904036) (xy 341.549 -229.853308)
			(xy 341.561179 -229.803894) (xy 341.581127 -229.757074) (xy 341.608328 -229.71406) (xy 341.642076 -229.675966)
			(xy 341.681498 -229.643779) (xy 341.725572 -229.618333) (xy 341.773158 -229.600286) (xy 341.823022 -229.590106)
			(xy 341.873874 -229.588057) (xy 341.924395 -229.594191) (xy 341.973279 -229.608351) (xy 342.019258 -229.630168)
			(xy 342.061142 -229.659078) (xy 342.097846 -229.694333) (xy 342.128419 -229.735019) (xy 342.15207 -229.780082)
			(xy 342.168186 -229.828356) (xy 342.17635 -229.87859) (xy 342.176862 -229.904036) (xy 342.49539 -229.904036)
			(xy 342.49935 -229.854982) (xy 342.511127 -229.807198) (xy 342.530418 -229.761922) (xy 342.556721 -229.720326)
			(xy 342.589356 -229.683489) (xy 342.627477 -229.652364) (xy 342.670098 -229.627757) (xy 342.716114 -229.610305)
			(xy 342.764333 -229.600461) (xy 342.813508 -229.59848) (xy 342.862363 -229.604412) (xy 342.909634 -229.618104)
			(xy 342.954096 -229.639202) (xy 342.994599 -229.667158) (xy 343.030092 -229.70125) (xy 343.059657 -229.740594)
			(xy 343.082528 -229.784171) (xy 343.098112 -229.830852) (xy 343.106007 -229.879429) (xy 343.106502 -229.904036)
			(xy 343.106007 -229.928643) (xy 343.098112 -229.97722) (xy 343.082528 -230.023901) (xy 343.059657 -230.067478)
			(xy 343.030092 -230.106822) (xy 342.994599 -230.140914) (xy 342.954096 -230.16887) (xy 342.909634 -230.189968)
			(xy 342.862363 -230.20366) (xy 342.813508 -230.209592) (xy 342.764333 -230.207611) (xy 342.716114 -230.197767)
			(xy 342.670098 -230.180315) (xy 342.627477 -230.155708) (xy 342.589356 -230.124583) (xy 342.556721 -230.087746)
			(xy 342.530418 -230.04615) (xy 342.511127 -230.000874) (xy 342.49935 -229.95309) (xy 342.49539 -229.904036)
			(xy 342.176862 -229.904036) (xy 342.17635 -229.929482) (xy 342.168186 -229.979716) (xy 342.15207 -230.02799)
			(xy 342.128419 -230.073053) (xy 342.097846 -230.113739) (xy 342.061142 -230.148994) (xy 342.019258 -230.177904)
			(xy 341.973279 -230.199721) (xy 341.924395 -230.213881) (xy 341.873874 -230.220015) (xy 341.823022 -230.217966)
			(xy 341.773158 -230.207786) (xy 341.725572 -230.189739) (xy 341.681498 -230.164293) (xy 341.642076 -230.132106)
			(xy 341.608328 -230.094012) (xy 341.581127 -230.050998) (xy 341.561179 -230.004178) (xy 341.549 -229.954764)
			(xy 341.544905 -229.904036) (xy 341.226394 -229.904036) (xy 341.225899 -229.928643) (xy 341.218004 -229.97722)
			(xy 341.20242 -230.023901) (xy 341.179549 -230.067478) (xy 341.149984 -230.106822) (xy 341.114491 -230.140914)
			(xy 341.073988 -230.16887) (xy 341.029526 -230.189968) (xy 340.982255 -230.20366) (xy 340.9334 -230.209592)
			(xy 340.884225 -230.207611) (xy 340.836006 -230.197767) (xy 340.78999 -230.180315) (xy 340.747369 -230.155708)
			(xy 340.709248 -230.124583) (xy 340.676613 -230.087746) (xy 340.65031 -230.04615) (xy 340.631019 -230.000874)
			(xy 340.619242 -229.95309) (xy 340.615282 -229.904036) (xy 340.296754 -229.904036) (xy 340.296242 -229.929482)
			(xy 340.288078 -229.979716) (xy 340.271962 -230.02799) (xy 340.248311 -230.073053) (xy 340.217738 -230.113739)
			(xy 340.181034 -230.148994) (xy 340.13915 -230.177904) (xy 340.093171 -230.199721) (xy 340.044287 -230.213881)
			(xy 339.993766 -230.220015) (xy 339.942914 -230.217966) (xy 339.89305 -230.207786) (xy 339.845464 -230.189739)
			(xy 339.80139 -230.164293) (xy 339.761968 -230.132106) (xy 339.72822 -230.094012) (xy 339.701019 -230.050998)
			(xy 339.681071 -230.004178) (xy 339.668892 -229.954764) (xy 339.664797 -229.904036) (xy 339.3567 -229.904036)
			(xy 339.356188 -229.929482) (xy 339.348024 -229.979716) (xy 339.331908 -230.02799) (xy 339.308257 -230.073053)
			(xy 339.277684 -230.113739) (xy 339.24098 -230.148994) (xy 339.199096 -230.177904) (xy 339.153117 -230.199721)
			(xy 339.104233 -230.213881) (xy 339.053712 -230.220015) (xy 339.00286 -230.217966) (xy 338.952996 -230.207786)
			(xy 338.90541 -230.189739) (xy 338.861336 -230.164293) (xy 338.821914 -230.132106) (xy 338.788166 -230.094012)
			(xy 338.760965 -230.050998) (xy 338.741017 -230.004178) (xy 338.728838 -229.954764) (xy 338.724743 -229.904036)
			(xy 338.406202 -229.904036) (xy 338.406202 -229.928465) (xy 338.3984 -229.976758) (xy 338.382996 -230.02319)
			(xy 338.360385 -230.066571) (xy 338.331146 -230.10579) (xy 338.296026 -230.139846) (xy 338.255925 -230.167865)
			(xy 338.211869 -230.18913) (xy 338.164986 -230.203098) (xy 338.140802 -230.206804) (xy 338.132674 -230.208074)
			(xy 338.109814 -230.218996) (xy 338.105726 -230.221055) (xy 338.09831 -230.226419) (xy 338.095082 -230.229664)
			(xy 338.08035 -230.245158) (xy 338.073973 -230.252481) (xy 338.066801 -230.270508) (xy 338.06638 -230.28021)
			(xy 338.06638 -230.714296) (xy 338.254843 -230.714296) (xy 338.258938 -230.663568) (xy 338.271117 -230.614154)
			(xy 338.291065 -230.567334) (xy 338.318266 -230.52432) (xy 338.352014 -230.486226) (xy 338.391436 -230.454039)
			(xy 338.43551 -230.428593) (xy 338.483096 -230.410546) (xy 338.53296 -230.400366) (xy 338.583812 -230.398317)
			(xy 338.634333 -230.404451) (xy 338.683217 -230.418611) (xy 338.729196 -230.440428) (xy 338.77108 -230.469338)
			(xy 338.807784 -230.504593) (xy 338.838357 -230.545279) (xy 338.862008 -230.590342) (xy 338.878124 -230.638616)
			(xy 338.886288 -230.68885) (xy 338.8868 -230.714296) (xy 339.205328 -230.714296) (xy 339.209288 -230.665242)
			(xy 339.221065 -230.617458) (xy 339.240356 -230.572182) (xy 339.266659 -230.530586) (xy 339.299294 -230.493749)
			(xy 339.337415 -230.462624) (xy 339.380036 -230.438017) (xy 339.426052 -230.420565) (xy 339.474271 -230.410721)
			(xy 339.523446 -230.40874) (xy 339.572301 -230.414672) (xy 339.619572 -230.428364) (xy 339.664034 -230.449462)
			(xy 339.704537 -230.477418) (xy 339.74003 -230.51151) (xy 339.769595 -230.550854) (xy 339.792466 -230.594431)
			(xy 339.80805 -230.641112) (xy 339.815945 -230.689689) (xy 339.81644 -230.714296) (xy 340.134951 -230.714296)
			(xy 340.139046 -230.663568) (xy 340.151225 -230.614154) (xy 340.171173 -230.567334) (xy 340.198374 -230.52432)
			(xy 340.232122 -230.486226) (xy 340.271544 -230.454039) (xy 340.315618 -230.428593) (xy 340.363204 -230.410546)
			(xy 340.413068 -230.400366) (xy 340.46392 -230.398317) (xy 340.514441 -230.404451) (xy 340.563325 -230.418611)
			(xy 340.609304 -230.440428) (xy 340.651188 -230.469338) (xy 340.687892 -230.504593) (xy 340.718465 -230.545279)
			(xy 340.742116 -230.590342) (xy 340.758232 -230.638616) (xy 340.766396 -230.68885) (xy 340.766903 -230.714042)
			(xy 341.085182 -230.714042) (xy 341.089142 -230.664988) (xy 341.100919 -230.617204) (xy 341.12021 -230.571928)
			(xy 341.146513 -230.530332) (xy 341.179148 -230.493495) (xy 341.217269 -230.46237) (xy 341.25989 -230.437763)
			(xy 341.305906 -230.420311) (xy 341.354125 -230.410467) (xy 341.4033 -230.408486) (xy 341.452155 -230.414418)
			(xy 341.499426 -230.42811) (xy 341.543888 -230.449208) (xy 341.584391 -230.477164) (xy 341.619884 -230.511256)
			(xy 341.649449 -230.5506) (xy 341.67232 -230.594177) (xy 341.687904 -230.640858) (xy 341.695799 -230.689435)
			(xy 341.696294 -230.714042) (xy 341.696289 -230.714296) (xy 342.014805 -230.714296) (xy 342.0189 -230.663568)
			(xy 342.031079 -230.614154) (xy 342.051027 -230.567334) (xy 342.078228 -230.52432) (xy 342.111976 -230.486226)
			(xy 342.151398 -230.454039) (xy 342.195472 -230.428593) (xy 342.243058 -230.410546) (xy 342.292922 -230.400366)
			(xy 342.343774 -230.398317) (xy 342.394295 -230.404451) (xy 342.443179 -230.418611) (xy 342.489158 -230.440428)
			(xy 342.531042 -230.469338) (xy 342.567746 -230.504593) (xy 342.598319 -230.545279) (xy 342.62197 -230.590342)
			(xy 342.638086 -230.638616) (xy 342.64625 -230.68885) (xy 342.646762 -230.714296) (xy 342.954859 -230.714296)
			(xy 342.958954 -230.663568) (xy 342.971133 -230.614154) (xy 342.991081 -230.567334) (xy 343.018282 -230.52432)
			(xy 343.05203 -230.486226) (xy 343.091452 -230.454039) (xy 343.135526 -230.428593) (xy 343.183112 -230.410546)
			(xy 343.232976 -230.400366) (xy 343.283828 -230.398317) (xy 343.334349 -230.404451) (xy 343.383233 -230.418611)
			(xy 343.429212 -230.440428) (xy 343.471096 -230.469338) (xy 343.5078 -230.504593) (xy 343.538373 -230.545279)
			(xy 343.562024 -230.590342) (xy 343.57814 -230.638616) (xy 343.586304 -230.68885) (xy 343.586816 -230.714296)
			(xy 343.586304 -230.739742) (xy 343.57814 -230.789976) (xy 343.562024 -230.83825) (xy 343.538373 -230.883313)
			(xy 343.5078 -230.923999) (xy 343.471096 -230.959254) (xy 343.429212 -230.988164) (xy 343.383233 -231.009981)
			(xy 343.334349 -231.024141) (xy 343.283828 -231.030275) (xy 343.232976 -231.028226) (xy 343.183112 -231.018046)
			(xy 343.135526 -230.999999) (xy 343.091452 -230.974553) (xy 343.05203 -230.942366) (xy 343.018282 -230.904272)
			(xy 342.991081 -230.861258) (xy 342.971133 -230.814438) (xy 342.958954 -230.765024) (xy 342.954859 -230.714296)
			(xy 342.646762 -230.714296) (xy 342.64625 -230.739742) (xy 342.638086 -230.789976) (xy 342.62197 -230.83825)
			(xy 342.598319 -230.883313) (xy 342.567746 -230.923999) (xy 342.531042 -230.959254) (xy 342.489158 -230.988164)
			(xy 342.443179 -231.009981) (xy 342.394295 -231.024141) (xy 342.343774 -231.030275) (xy 342.292922 -231.028226)
			(xy 342.243058 -231.018046) (xy 342.195472 -230.999999) (xy 342.151398 -230.974553) (xy 342.111976 -230.942366)
			(xy 342.078228 -230.904272) (xy 342.051027 -230.861258) (xy 342.031079 -230.814438) (xy 342.0189 -230.765024)
			(xy 342.014805 -230.714296) (xy 341.696289 -230.714296) (xy 341.695799 -230.738649) (xy 341.687904 -230.787226)
			(xy 341.67232 -230.833907) (xy 341.649449 -230.877484) (xy 341.619884 -230.916828) (xy 341.584391 -230.95092)
			(xy 341.543888 -230.978876) (xy 341.499426 -230.999974) (xy 341.452155 -231.013666) (xy 341.4033 -231.019598)
			(xy 341.354125 -231.017617) (xy 341.305906 -231.007773) (xy 341.25989 -230.990321) (xy 341.217269 -230.965714)
			(xy 341.179148 -230.934589) (xy 341.146513 -230.897752) (xy 341.12021 -230.856156) (xy 341.100919 -230.81088)
			(xy 341.089142 -230.763096) (xy 341.085182 -230.714042) (xy 340.766903 -230.714042) (xy 340.766908 -230.714296)
			(xy 340.766396 -230.739742) (xy 340.758232 -230.789976) (xy 340.742116 -230.83825) (xy 340.718465 -230.883313)
			(xy 340.687892 -230.923999) (xy 340.651188 -230.959254) (xy 340.609304 -230.988164) (xy 340.563325 -231.009981)
			(xy 340.514441 -231.024141) (xy 340.46392 -231.030275) (xy 340.413068 -231.028226) (xy 340.363204 -231.018046)
			(xy 340.315618 -230.999999) (xy 340.271544 -230.974553) (xy 340.232122 -230.942366) (xy 340.198374 -230.904272)
			(xy 340.171173 -230.861258) (xy 340.151225 -230.814438) (xy 340.139046 -230.765024) (xy 340.134951 -230.714296)
			(xy 339.81644 -230.714296) (xy 339.815945 -230.738903) (xy 339.80805 -230.78748) (xy 339.792466 -230.834161)
			(xy 339.769595 -230.877738) (xy 339.74003 -230.917082) (xy 339.704537 -230.951174) (xy 339.664034 -230.97913)
			(xy 339.619572 -231.000228) (xy 339.572301 -231.01392) (xy 339.523446 -231.019852) (xy 339.474271 -231.017871)
			(xy 339.426052 -231.008027) (xy 339.380036 -230.990575) (xy 339.337415 -230.965968) (xy 339.299294 -230.934843)
			(xy 339.266659 -230.898006) (xy 339.240356 -230.85641) (xy 339.221065 -230.811134) (xy 339.209288 -230.76335)
			(xy 339.205328 -230.714296) (xy 338.8868 -230.714296) (xy 338.886288 -230.739742) (xy 338.878124 -230.789976)
			(xy 338.862008 -230.83825) (xy 338.838357 -230.883313) (xy 338.807784 -230.923999) (xy 338.77108 -230.959254)
			(xy 338.729196 -230.988164) (xy 338.683217 -231.009981) (xy 338.634333 -231.024141) (xy 338.583812 -231.030275)
			(xy 338.53296 -231.028226) (xy 338.483096 -231.018046) (xy 338.43551 -230.999999) (xy 338.391436 -230.974553)
			(xy 338.352014 -230.942366) (xy 338.318266 -230.904272) (xy 338.291065 -230.861258) (xy 338.271117 -230.814438)
			(xy 338.258938 -230.765024) (xy 338.254843 -230.714296) (xy 338.06638 -230.714296) (xy 338.06638 -231.147874)
			(xy 338.066812 -231.157571) (xy 338.073996 -231.175587) (xy 338.08035 -231.182926) (xy 338.095082 -231.19842)
			(xy 338.098323 -231.201651) (xy 338.105733 -231.207019) (xy 338.109814 -231.209088) (xy 338.132674 -231.22001)
			(xy 338.140802 -231.22128) (xy 338.164994 -231.224916) (xy 338.211875 -231.238885) (xy 338.255929 -231.260151)
			(xy 338.296027 -231.28817) (xy 338.331144 -231.322226) (xy 338.360381 -231.361445) (xy 338.382989 -231.404825)
			(xy 338.398391 -231.451255) (xy 338.406191 -231.499547) (xy 338.40619 -231.524048) (xy 338.724743 -231.524048)
			(xy 338.728838 -231.47332) (xy 338.741017 -231.423906) (xy 338.760965 -231.377086) (xy 338.788166 -231.334072)
			(xy 338.821914 -231.295978) (xy 338.861336 -231.263791) (xy 338.90541 -231.238345) (xy 338.952996 -231.220298)
			(xy 339.00286 -231.210118) (xy 339.053712 -231.208069) (xy 339.104233 -231.214203) (xy 339.153117 -231.228363)
			(xy 339.199096 -231.25018) (xy 339.24098 -231.27909) (xy 339.277684 -231.314345) (xy 339.308257 -231.355031)
			(xy 339.331908 -231.400094) (xy 339.348024 -231.448368) (xy 339.356188 -231.498602) (xy 339.3567 -231.524048)
			(xy 339.664797 -231.524048) (xy 339.668892 -231.47332) (xy 339.681071 -231.423906) (xy 339.701019 -231.377086)
			(xy 339.72822 -231.334072) (xy 339.761968 -231.295978) (xy 339.80139 -231.263791) (xy 339.845464 -231.238345)
			(xy 339.89305 -231.220298) (xy 339.942914 -231.210118) (xy 339.993766 -231.208069) (xy 340.044287 -231.214203)
			(xy 340.093171 -231.228363) (xy 340.13915 -231.25018) (xy 340.181034 -231.27909) (xy 340.217738 -231.314345)
			(xy 340.248311 -231.355031) (xy 340.271962 -231.400094) (xy 340.288078 -231.448368) (xy 340.296242 -231.498602)
			(xy 340.296754 -231.524048) (xy 340.615282 -231.524048) (xy 340.619242 -231.474994) (xy 340.631019 -231.42721)
			(xy 340.65031 -231.381934) (xy 340.676613 -231.340338) (xy 340.709248 -231.303501) (xy 340.747369 -231.272376)
			(xy 340.78999 -231.247769) (xy 340.836006 -231.230317) (xy 340.884225 -231.220473) (xy 340.9334 -231.218492)
			(xy 340.982255 -231.224424) (xy 341.029526 -231.238116) (xy 341.073988 -231.259214) (xy 341.114491 -231.28717)
			(xy 341.149984 -231.321262) (xy 341.179549 -231.360606) (xy 341.20242 -231.404183) (xy 341.218004 -231.450864)
			(xy 341.225899 -231.499441) (xy 341.226394 -231.524048) (xy 341.544905 -231.524048) (xy 341.549 -231.47332)
			(xy 341.561179 -231.423906) (xy 341.581127 -231.377086) (xy 341.608328 -231.334072) (xy 341.642076 -231.295978)
			(xy 341.681498 -231.263791) (xy 341.725572 -231.238345) (xy 341.773158 -231.220298) (xy 341.823022 -231.210118)
			(xy 341.873874 -231.208069) (xy 341.924395 -231.214203) (xy 341.973279 -231.228363) (xy 342.019258 -231.25018)
			(xy 342.061142 -231.27909) (xy 342.097846 -231.314345) (xy 342.128419 -231.355031) (xy 342.15207 -231.400094)
			(xy 342.168186 -231.448368) (xy 342.17635 -231.498602) (xy 342.176862 -231.524048) (xy 342.49539 -231.524048)
			(xy 342.49935 -231.474994) (xy 342.511127 -231.42721) (xy 342.530418 -231.381934) (xy 342.556721 -231.340338)
			(xy 342.589356 -231.303501) (xy 342.627477 -231.272376) (xy 342.670098 -231.247769) (xy 342.716114 -231.230317)
			(xy 342.764333 -231.220473) (xy 342.813508 -231.218492) (xy 342.862363 -231.224424) (xy 342.909634 -231.238116)
			(xy 342.954096 -231.259214) (xy 342.994599 -231.28717) (xy 343.030092 -231.321262) (xy 343.059657 -231.360606)
			(xy 343.082528 -231.404183) (xy 343.098112 -231.450864) (xy 343.106007 -231.499441) (xy 343.106502 -231.524048)
			(xy 343.106007 -231.548655) (xy 343.098112 -231.597232) (xy 343.082528 -231.643913) (xy 343.059657 -231.68749)
			(xy 343.030092 -231.726834) (xy 342.994599 -231.760926) (xy 342.954096 -231.788882) (xy 342.909634 -231.80998)
			(xy 342.862363 -231.823672) (xy 342.813508 -231.829604) (xy 342.764333 -231.827623) (xy 342.716114 -231.817779)
			(xy 342.670098 -231.800327) (xy 342.627477 -231.77572) (xy 342.589356 -231.744595) (xy 342.556721 -231.707758)
			(xy 342.530418 -231.666162) (xy 342.511127 -231.620886) (xy 342.49935 -231.573102) (xy 342.49539 -231.524048)
			(xy 342.176862 -231.524048) (xy 342.17635 -231.549494) (xy 342.168186 -231.599728) (xy 342.15207 -231.648002)
			(xy 342.128419 -231.693065) (xy 342.097846 -231.733751) (xy 342.061142 -231.769006) (xy 342.019258 -231.797916)
			(xy 341.973279 -231.819733) (xy 341.924395 -231.833893) (xy 341.873874 -231.840027) (xy 341.823022 -231.837978)
			(xy 341.773158 -231.827798) (xy 341.725572 -231.809751) (xy 341.681498 -231.784305) (xy 341.642076 -231.752118)
			(xy 341.608328 -231.714024) (xy 341.581127 -231.67101) (xy 341.561179 -231.62419) (xy 341.549 -231.574776)
			(xy 341.544905 -231.524048) (xy 341.226394 -231.524048) (xy 341.225899 -231.548655) (xy 341.218004 -231.597232)
			(xy 341.20242 -231.643913) (xy 341.179549 -231.68749) (xy 341.149984 -231.726834) (xy 341.114491 -231.760926)
			(xy 341.073988 -231.788882) (xy 341.029526 -231.80998) (xy 340.982255 -231.823672) (xy 340.9334 -231.829604)
			(xy 340.884225 -231.827623) (xy 340.836006 -231.817779) (xy 340.78999 -231.800327) (xy 340.747369 -231.77572)
			(xy 340.709248 -231.744595) (xy 340.676613 -231.707758) (xy 340.65031 -231.666162) (xy 340.631019 -231.620886)
			(xy 340.619242 -231.573102) (xy 340.615282 -231.524048) (xy 340.296754 -231.524048) (xy 340.296242 -231.549494)
			(xy 340.288078 -231.599728) (xy 340.271962 -231.648002) (xy 340.248311 -231.693065) (xy 340.217738 -231.733751)
			(xy 340.181034 -231.769006) (xy 340.13915 -231.797916) (xy 340.093171 -231.819733) (xy 340.044287 -231.833893)
			(xy 339.993766 -231.840027) (xy 339.942914 -231.837978) (xy 339.89305 -231.827798) (xy 339.845464 -231.809751)
			(xy 339.80139 -231.784305) (xy 339.761968 -231.752118) (xy 339.72822 -231.714024) (xy 339.701019 -231.67101)
			(xy 339.681071 -231.62419) (xy 339.668892 -231.574776) (xy 339.664797 -231.524048) (xy 339.3567 -231.524048)
			(xy 339.356188 -231.549494) (xy 339.348024 -231.599728) (xy 339.331908 -231.648002) (xy 339.308257 -231.693065)
			(xy 339.277684 -231.733751) (xy 339.24098 -231.769006) (xy 339.199096 -231.797916) (xy 339.153117 -231.819733)
			(xy 339.104233 -231.833893) (xy 339.053712 -231.840027) (xy 339.00286 -231.837978) (xy 338.952996 -231.827798)
			(xy 338.90541 -231.809751) (xy 338.861336 -231.784305) (xy 338.821914 -231.752118) (xy 338.788166 -231.714024)
			(xy 338.760965 -231.67101) (xy 338.741017 -231.62419) (xy 338.728838 -231.574776) (xy 338.724743 -231.524048)
			(xy 338.40619 -231.524048) (xy 338.40619 -231.548465) (xy 338.398388 -231.596757) (xy 338.382985 -231.643186)
			(xy 338.360374 -231.686566) (xy 338.331136 -231.725784) (xy 338.296017 -231.759838) (xy 338.255918 -231.787855)
			(xy 338.211863 -231.809119) (xy 338.164982 -231.823086) (xy 338.140802 -231.826816) (xy 338.132674 -231.828086)
			(xy 338.109814 -231.839008) (xy 338.105726 -231.841067) (xy 338.098311 -231.846432) (xy 338.095082 -231.849676)
			(xy 338.08035 -231.86517) (xy 338.073959 -231.872488) (xy 338.066756 -231.890515) (xy 338.06638 -231.900222)
			(xy 338.06638 -232.334054) (xy 338.254843 -232.334054) (xy 338.258938 -232.283326) (xy 338.271117 -232.233912)
			(xy 338.291065 -232.187092) (xy 338.318266 -232.144078) (xy 338.352014 -232.105984) (xy 338.391436 -232.073797)
			(xy 338.43551 -232.048351) (xy 338.483096 -232.030304) (xy 338.53296 -232.020124) (xy 338.583812 -232.018075)
			(xy 338.634333 -232.024209) (xy 338.683217 -232.038369) (xy 338.729196 -232.060186) (xy 338.77108 -232.089096)
			(xy 338.807784 -232.124351) (xy 338.838357 -232.165037) (xy 338.862008 -232.2101) (xy 338.878124 -232.258374)
			(xy 338.886288 -232.308608) (xy 338.8868 -232.334054) (xy 339.205328 -232.334054) (xy 339.209288 -232.285)
			(xy 339.221065 -232.237216) (xy 339.240356 -232.19194) (xy 339.266659 -232.150344) (xy 339.299294 -232.113507)
			(xy 339.337415 -232.082382) (xy 339.380036 -232.057775) (xy 339.426052 -232.040323) (xy 339.474271 -232.030479)
			(xy 339.523446 -232.028498) (xy 339.572301 -232.03443) (xy 339.619572 -232.048122) (xy 339.664034 -232.06922)
			(xy 339.704537 -232.097176) (xy 339.74003 -232.131268) (xy 339.769595 -232.170612) (xy 339.792466 -232.214189)
			(xy 339.80805 -232.26087) (xy 339.815945 -232.309447) (xy 339.81644 -232.334054) (xy 340.134951 -232.334054)
			(xy 340.139046 -232.283326) (xy 340.151225 -232.233912) (xy 340.171173 -232.187092) (xy 340.198374 -232.144078)
			(xy 340.232122 -232.105984) (xy 340.271544 -232.073797) (xy 340.315618 -232.048351) (xy 340.363204 -232.030304)
			(xy 340.413068 -232.020124) (xy 340.46392 -232.018075) (xy 340.514441 -232.024209) (xy 340.563325 -232.038369)
			(xy 340.609304 -232.060186) (xy 340.651188 -232.089096) (xy 340.687892 -232.124351) (xy 340.718465 -232.165037)
			(xy 340.742116 -232.2101) (xy 340.758232 -232.258374) (xy 340.766396 -232.308608) (xy 340.766908 -232.334054)
			(xy 341.085182 -232.334054) (xy 341.089142 -232.285) (xy 341.100919 -232.237216) (xy 341.12021 -232.19194)
			(xy 341.146513 -232.150344) (xy 341.179148 -232.113507) (xy 341.217269 -232.082382) (xy 341.25989 -232.057775)
			(xy 341.305906 -232.040323) (xy 341.354125 -232.030479) (xy 341.4033 -232.028498) (xy 341.452155 -232.03443)
			(xy 341.499426 -232.048122) (xy 341.543888 -232.06922) (xy 341.584391 -232.097176) (xy 341.619884 -232.131268)
			(xy 341.649449 -232.170612) (xy 341.67232 -232.214189) (xy 341.687904 -232.26087) (xy 341.695799 -232.309447)
			(xy 341.696294 -232.334054) (xy 342.014805 -232.334054) (xy 342.0189 -232.283326) (xy 342.031079 -232.233912)
			(xy 342.051027 -232.187092) (xy 342.078228 -232.144078) (xy 342.111976 -232.105984) (xy 342.151398 -232.073797)
			(xy 342.195472 -232.048351) (xy 342.243058 -232.030304) (xy 342.292922 -232.020124) (xy 342.343774 -232.018075)
			(xy 342.394295 -232.024209) (xy 342.443179 -232.038369) (xy 342.489158 -232.060186) (xy 342.531042 -232.089096)
			(xy 342.567746 -232.124351) (xy 342.598319 -232.165037) (xy 342.62197 -232.2101) (xy 342.638086 -232.258374)
			(xy 342.64625 -232.308608) (xy 342.646762 -232.334054) (xy 342.954859 -232.334054) (xy 342.958954 -232.283326)
			(xy 342.971133 -232.233912) (xy 342.991081 -232.187092) (xy 343.018282 -232.144078) (xy 343.05203 -232.105984)
			(xy 343.091452 -232.073797) (xy 343.135526 -232.048351) (xy 343.183112 -232.030304) (xy 343.232976 -232.020124)
			(xy 343.283828 -232.018075) (xy 343.334349 -232.024209) (xy 343.383233 -232.038369) (xy 343.429212 -232.060186)
			(xy 343.471096 -232.089096) (xy 343.5078 -232.124351) (xy 343.538373 -232.165037) (xy 343.562024 -232.2101)
			(xy 343.57814 -232.258374) (xy 343.586304 -232.308608) (xy 343.586816 -232.334054) (xy 343.586304 -232.3595)
			(xy 343.57814 -232.409734) (xy 343.562024 -232.458008) (xy 343.538373 -232.503071) (xy 343.5078 -232.543757)
			(xy 343.471096 -232.579012) (xy 343.429212 -232.607922) (xy 343.383233 -232.629739) (xy 343.334349 -232.643899)
			(xy 343.283828 -232.650033) (xy 343.232976 -232.647984) (xy 343.183112 -232.637804) (xy 343.135526 -232.619757)
			(xy 343.091452 -232.594311) (xy 343.05203 -232.562124) (xy 343.018282 -232.52403) (xy 342.991081 -232.481016)
			(xy 342.971133 -232.434196) (xy 342.958954 -232.384782) (xy 342.954859 -232.334054) (xy 342.646762 -232.334054)
			(xy 342.64625 -232.3595) (xy 342.638086 -232.409734) (xy 342.62197 -232.458008) (xy 342.598319 -232.503071)
			(xy 342.567746 -232.543757) (xy 342.531042 -232.579012) (xy 342.489158 -232.607922) (xy 342.443179 -232.629739)
			(xy 342.394295 -232.643899) (xy 342.343774 -232.650033) (xy 342.292922 -232.647984) (xy 342.243058 -232.637804)
			(xy 342.195472 -232.619757) (xy 342.151398 -232.594311) (xy 342.111976 -232.562124) (xy 342.078228 -232.52403)
			(xy 342.051027 -232.481016) (xy 342.031079 -232.434196) (xy 342.0189 -232.384782) (xy 342.014805 -232.334054)
			(xy 341.696294 -232.334054) (xy 341.695799 -232.358661) (xy 341.687904 -232.407238) (xy 341.67232 -232.453919)
			(xy 341.649449 -232.497496) (xy 341.619884 -232.53684) (xy 341.584391 -232.570932) (xy 341.543888 -232.598888)
			(xy 341.499426 -232.619986) (xy 341.452155 -232.633678) (xy 341.4033 -232.63961) (xy 341.354125 -232.637629)
			(xy 341.305906 -232.627785) (xy 341.25989 -232.610333) (xy 341.217269 -232.585726) (xy 341.179148 -232.554601)
			(xy 341.146513 -232.517764) (xy 341.12021 -232.476168) (xy 341.100919 -232.430892) (xy 341.089142 -232.383108)
			(xy 341.085182 -232.334054) (xy 340.766908 -232.334054) (xy 340.766396 -232.3595) (xy 340.758232 -232.409734)
			(xy 340.742116 -232.458008) (xy 340.718465 -232.503071) (xy 340.687892 -232.543757) (xy 340.651188 -232.579012)
			(xy 340.609304 -232.607922) (xy 340.563325 -232.629739) (xy 340.514441 -232.643899) (xy 340.46392 -232.650033)
			(xy 340.413068 -232.647984) (xy 340.363204 -232.637804) (xy 340.315618 -232.619757) (xy 340.271544 -232.594311)
			(xy 340.232122 -232.562124) (xy 340.198374 -232.52403) (xy 340.171173 -232.481016) (xy 340.151225 -232.434196)
			(xy 340.139046 -232.384782) (xy 340.134951 -232.334054) (xy 339.81644 -232.334054) (xy 339.815945 -232.358661)
			(xy 339.80805 -232.407238) (xy 339.792466 -232.453919) (xy 339.769595 -232.497496) (xy 339.74003 -232.53684)
			(xy 339.704537 -232.570932) (xy 339.664034 -232.598888) (xy 339.619572 -232.619986) (xy 339.572301 -232.633678)
			(xy 339.523446 -232.63961) (xy 339.474271 -232.637629) (xy 339.426052 -232.627785) (xy 339.380036 -232.610333)
			(xy 339.337415 -232.585726) (xy 339.299294 -232.554601) (xy 339.266659 -232.517764) (xy 339.240356 -232.476168)
			(xy 339.221065 -232.430892) (xy 339.209288 -232.383108) (xy 339.205328 -232.334054) (xy 338.8868 -232.334054)
			(xy 338.886288 -232.3595) (xy 338.878124 -232.409734) (xy 338.862008 -232.458008) (xy 338.838357 -232.503071)
			(xy 338.807784 -232.543757) (xy 338.77108 -232.579012) (xy 338.729196 -232.607922) (xy 338.683217 -232.629739)
			(xy 338.634333 -232.643899) (xy 338.583812 -232.650033) (xy 338.53296 -232.647984) (xy 338.483096 -232.637804)
			(xy 338.43551 -232.619757) (xy 338.391436 -232.594311) (xy 338.352014 -232.562124) (xy 338.318266 -232.52403)
			(xy 338.291065 -232.481016) (xy 338.271117 -232.434196) (xy 338.258938 -232.384782) (xy 338.254843 -232.334054)
			(xy 338.06638 -232.334054) (xy 338.06638 -232.767886) (xy 338.066814 -232.777582) (xy 338.074001 -232.795596)
			(xy 338.08035 -232.802938) (xy 338.095082 -232.818432) (xy 338.098323 -232.821662) (xy 338.105734 -232.827029)
			(xy 338.109814 -232.8291) (xy 338.132674 -232.840022) (xy 338.140802 -232.841292) (xy 338.165001 -232.844929)
			(xy 338.211896 -232.8589) (xy 338.255963 -232.88017) (xy 338.296074 -232.908196) (xy 338.331202 -232.942259)
			(xy 338.360449 -232.981489) (xy 338.383065 -233.02488) (xy 338.398473 -233.071323) (xy 338.406277 -233.119629)
			(xy 338.406277 -233.14406) (xy 338.724743 -233.14406) (xy 338.728838 -233.093332) (xy 338.741017 -233.043918)
			(xy 338.760965 -232.997098) (xy 338.788166 -232.954084) (xy 338.821914 -232.91599) (xy 338.861336 -232.883803)
			(xy 338.90541 -232.858357) (xy 338.952996 -232.84031) (xy 339.00286 -232.83013) (xy 339.053712 -232.828081)
			(xy 339.104233 -232.834215) (xy 339.153117 -232.848375) (xy 339.199096 -232.870192) (xy 339.24098 -232.899102)
			(xy 339.277684 -232.934357) (xy 339.308257 -232.975043) (xy 339.331908 -233.020106) (xy 339.348024 -233.06838)
			(xy 339.356188 -233.118614) (xy 339.3567 -233.14406) (xy 339.664797 -233.14406) (xy 339.668892 -233.093332)
			(xy 339.681071 -233.043918) (xy 339.701019 -232.997098) (xy 339.72822 -232.954084) (xy 339.761968 -232.91599)
			(xy 339.80139 -232.883803) (xy 339.845464 -232.858357) (xy 339.89305 -232.84031) (xy 339.942914 -232.83013)
			(xy 339.993766 -232.828081) (xy 340.044287 -232.834215) (xy 340.093171 -232.848375) (xy 340.13915 -232.870192)
			(xy 340.181034 -232.899102) (xy 340.217738 -232.934357) (xy 340.248311 -232.975043) (xy 340.271962 -233.020106)
			(xy 340.288078 -233.06838) (xy 340.296242 -233.118614) (xy 340.296754 -233.14406) (xy 340.615282 -233.14406)
			(xy 340.619242 -233.095006) (xy 340.631019 -233.047222) (xy 340.65031 -233.001946) (xy 340.676613 -232.96035)
			(xy 340.709248 -232.923513) (xy 340.747369 -232.892388) (xy 340.78999 -232.867781) (xy 340.836006 -232.850329)
			(xy 340.884225 -232.840485) (xy 340.9334 -232.838504) (xy 340.982255 -232.844436) (xy 341.029526 -232.858128)
			(xy 341.073988 -232.879226) (xy 341.114491 -232.907182) (xy 341.149984 -232.941274) (xy 341.179549 -232.980618)
			(xy 341.20242 -233.024195) (xy 341.218004 -233.070876) (xy 341.225899 -233.119453) (xy 341.226394 -233.14406)
			(xy 341.544905 -233.14406) (xy 341.549 -233.093332) (xy 341.561179 -233.043918) (xy 341.581127 -232.997098)
			(xy 341.608328 -232.954084) (xy 341.642076 -232.91599) (xy 341.681498 -232.883803) (xy 341.725572 -232.858357)
			(xy 341.773158 -232.84031) (xy 341.823022 -232.83013) (xy 341.873874 -232.828081) (xy 341.924395 -232.834215)
			(xy 341.973279 -232.848375) (xy 342.019258 -232.870192) (xy 342.061142 -232.899102) (xy 342.097846 -232.934357)
			(xy 342.128419 -232.975043) (xy 342.15207 -233.020106) (xy 342.168186 -233.06838) (xy 342.17635 -233.118614)
			(xy 342.176862 -233.14406) (xy 342.49539 -233.14406) (xy 342.49935 -233.095006) (xy 342.511127 -233.047222)
			(xy 342.530418 -233.001946) (xy 342.556721 -232.96035) (xy 342.589356 -232.923513) (xy 342.627477 -232.892388)
			(xy 342.670098 -232.867781) (xy 342.716114 -232.850329) (xy 342.764333 -232.840485) (xy 342.813508 -232.838504)
			(xy 342.862363 -232.844436) (xy 342.909634 -232.858128) (xy 342.954096 -232.879226) (xy 342.994599 -232.907182)
			(xy 343.030092 -232.941274) (xy 343.059657 -232.980618) (xy 343.082528 -233.024195) (xy 343.098112 -233.070876)
			(xy 343.106007 -233.119453) (xy 343.106502 -233.14406) (xy 343.106007 -233.168667) (xy 343.098112 -233.217244)
			(xy 343.082528 -233.263925) (xy 343.059657 -233.307502) (xy 343.030092 -233.346846) (xy 342.994599 -233.380938)
			(xy 342.954096 -233.408894) (xy 342.909634 -233.429992) (xy 342.862363 -233.443684) (xy 342.813508 -233.449616)
			(xy 342.764333 -233.447635) (xy 342.716114 -233.437791) (xy 342.670098 -233.420339) (xy 342.627477 -233.395732)
			(xy 342.589356 -233.364607) (xy 342.556721 -233.32777) (xy 342.530418 -233.286174) (xy 342.511127 -233.240898)
			(xy 342.49935 -233.193114) (xy 342.49539 -233.14406) (xy 342.176862 -233.14406) (xy 342.17635 -233.169506)
			(xy 342.168186 -233.21974) (xy 342.15207 -233.268014) (xy 342.128419 -233.313077) (xy 342.097846 -233.353763)
			(xy 342.061142 -233.389018) (xy 342.019258 -233.417928) (xy 341.973279 -233.439745) (xy 341.924395 -233.453905)
			(xy 341.873874 -233.460039) (xy 341.823022 -233.45799) (xy 341.773158 -233.44781) (xy 341.725572 -233.429763)
			(xy 341.681498 -233.404317) (xy 341.642076 -233.37213) (xy 341.608328 -233.334036) (xy 341.581127 -233.291022)
			(xy 341.561179 -233.244202) (xy 341.549 -233.194788) (xy 341.544905 -233.14406) (xy 341.226394 -233.14406)
			(xy 341.225899 -233.168667) (xy 341.218004 -233.217244) (xy 341.20242 -233.263925) (xy 341.179549 -233.307502)
			(xy 341.149984 -233.346846) (xy 341.114491 -233.380938) (xy 341.073988 -233.408894) (xy 341.029526 -233.429992)
			(xy 340.982255 -233.443684) (xy 340.9334 -233.449616) (xy 340.884225 -233.447635) (xy 340.836006 -233.437791)
			(xy 340.78999 -233.420339) (xy 340.747369 -233.395732) (xy 340.709248 -233.364607) (xy 340.676613 -233.32777)
			(xy 340.65031 -233.286174) (xy 340.631019 -233.240898) (xy 340.619242 -233.193114) (xy 340.615282 -233.14406)
			(xy 340.296754 -233.14406) (xy 340.296242 -233.169506) (xy 340.288078 -233.21974) (xy 340.271962 -233.268014)
			(xy 340.248311 -233.313077) (xy 340.217738 -233.353763) (xy 340.181034 -233.389018) (xy 340.13915 -233.417928)
			(xy 340.093171 -233.439745) (xy 340.044287 -233.453905) (xy 339.993766 -233.460039) (xy 339.942914 -233.45799)
			(xy 339.89305 -233.44781) (xy 339.845464 -233.429763) (xy 339.80139 -233.404317) (xy 339.761968 -233.37213)
			(xy 339.72822 -233.334036) (xy 339.701019 -233.291022) (xy 339.681071 -233.244202) (xy 339.668892 -233.194788)
			(xy 339.664797 -233.14406) (xy 339.3567 -233.14406) (xy 339.356188 -233.169506) (xy 339.348024 -233.21974)
			(xy 339.331908 -233.268014) (xy 339.308257 -233.313077) (xy 339.277684 -233.353763) (xy 339.24098 -233.389018)
			(xy 339.199096 -233.417928) (xy 339.153117 -233.439745) (xy 339.104233 -233.453905) (xy 339.053712 -233.460039)
			(xy 339.00286 -233.45799) (xy 338.952996 -233.44781) (xy 338.90541 -233.429763) (xy 338.861336 -233.404317)
			(xy 338.821914 -233.37213) (xy 338.788166 -233.334036) (xy 338.760965 -233.291022) (xy 338.741017 -233.244202)
			(xy 338.728838 -233.194788) (xy 338.724743 -233.14406) (xy 338.406277 -233.14406) (xy 338.406278 -233.168561)
			(xy 338.398475 -233.216867) (xy 338.383069 -233.26331) (xy 338.360454 -233.306702) (xy 338.331209 -233.345933)
			(xy 338.296082 -233.379998) (xy 338.255972 -233.408025) (xy 338.211906 -233.429297) (xy 338.165011 -233.443269)
			(xy 338.140802 -233.446828) (xy 338.132674 -233.448098) (xy 338.109814 -233.45902) (xy 338.105726 -233.46108)
			(xy 338.098312 -233.466445) (xy 338.095082 -233.469688) (xy 338.08035 -233.485182) (xy 338.073961 -233.492501)
			(xy 338.066762 -233.510528) (xy 338.06638 -233.520234) (xy 338.06638 -233.954066) (xy 338.254843 -233.954066)
			(xy 338.258938 -233.903338) (xy 338.271117 -233.853924) (xy 338.291065 -233.807104) (xy 338.318266 -233.76409)
			(xy 338.352014 -233.725996) (xy 338.391436 -233.693809) (xy 338.43551 -233.668363) (xy 338.483096 -233.650316)
			(xy 338.53296 -233.640136) (xy 338.583812 -233.638087) (xy 338.634333 -233.644221) (xy 338.683217 -233.658381)
			(xy 338.729196 -233.680198) (xy 338.77108 -233.709108) (xy 338.807784 -233.744363) (xy 338.838357 -233.785049)
			(xy 338.862008 -233.830112) (xy 338.878124 -233.878386) (xy 338.886288 -233.92862) (xy 338.8868 -233.954066)
			(xy 339.205328 -233.954066) (xy 339.209288 -233.905012) (xy 339.221065 -233.857228) (xy 339.240356 -233.811952)
			(xy 339.266659 -233.770356) (xy 339.299294 -233.733519) (xy 339.337415 -233.702394) (xy 339.380036 -233.677787)
			(xy 339.426052 -233.660335) (xy 339.474271 -233.650491) (xy 339.523446 -233.64851) (xy 339.572301 -233.654442)
			(xy 339.619572 -233.668134) (xy 339.664034 -233.689232) (xy 339.704537 -233.717188) (xy 339.74003 -233.75128)
			(xy 339.769595 -233.790624) (xy 339.792466 -233.834201) (xy 339.80805 -233.880882) (xy 339.815945 -233.929459)
			(xy 339.81644 -233.954066) (xy 340.134951 -233.954066) (xy 340.139046 -233.903338) (xy 340.151225 -233.853924)
			(xy 340.171173 -233.807104) (xy 340.198374 -233.76409) (xy 340.232122 -233.725996) (xy 340.271544 -233.693809)
			(xy 340.315618 -233.668363) (xy 340.363204 -233.650316) (xy 340.413068 -233.640136) (xy 340.46392 -233.638087)
			(xy 340.514441 -233.644221) (xy 340.563325 -233.658381) (xy 340.609304 -233.680198) (xy 340.651188 -233.709108)
			(xy 340.687892 -233.744363) (xy 340.718465 -233.785049) (xy 340.742116 -233.830112) (xy 340.758232 -233.878386)
			(xy 340.766396 -233.92862) (xy 340.766908 -233.954066) (xy 341.085182 -233.954066) (xy 341.089142 -233.905012)
			(xy 341.100919 -233.857228) (xy 341.12021 -233.811952) (xy 341.146513 -233.770356) (xy 341.179148 -233.733519)
			(xy 341.217269 -233.702394) (xy 341.25989 -233.677787) (xy 341.305906 -233.660335) (xy 341.354125 -233.650491)
			(xy 341.4033 -233.64851) (xy 341.452155 -233.654442) (xy 341.499426 -233.668134) (xy 341.543888 -233.689232)
			(xy 341.584391 -233.717188) (xy 341.619884 -233.75128) (xy 341.649449 -233.790624) (xy 341.67232 -233.834201)
			(xy 341.687904 -233.880882) (xy 341.695799 -233.929459) (xy 341.696294 -233.954066) (xy 342.014805 -233.954066)
			(xy 342.0189 -233.903338) (xy 342.031079 -233.853924) (xy 342.051027 -233.807104) (xy 342.078228 -233.76409)
			(xy 342.111976 -233.725996) (xy 342.151398 -233.693809) (xy 342.195472 -233.668363) (xy 342.243058 -233.650316)
			(xy 342.292922 -233.640136) (xy 342.343774 -233.638087) (xy 342.394295 -233.644221) (xy 342.443179 -233.658381)
			(xy 342.489158 -233.680198) (xy 342.531042 -233.709108) (xy 342.567746 -233.744363) (xy 342.598319 -233.785049)
			(xy 342.62197 -233.830112) (xy 342.638086 -233.878386) (xy 342.64625 -233.92862) (xy 342.646762 -233.954066)
			(xy 342.954859 -233.954066) (xy 342.958954 -233.903338) (xy 342.971133 -233.853924) (xy 342.991081 -233.807104)
			(xy 343.018282 -233.76409) (xy 343.05203 -233.725996) (xy 343.091452 -233.693809) (xy 343.135526 -233.668363)
			(xy 343.183112 -233.650316) (xy 343.232976 -233.640136) (xy 343.283828 -233.638087) (xy 343.334349 -233.644221)
			(xy 343.383233 -233.658381) (xy 343.429212 -233.680198) (xy 343.471096 -233.709108) (xy 343.5078 -233.744363)
			(xy 343.538373 -233.785049) (xy 343.562024 -233.830112) (xy 343.57814 -233.878386) (xy 343.586304 -233.92862)
			(xy 343.586816 -233.954066) (xy 343.586304 -233.979512) (xy 343.57814 -234.029746) (xy 343.562024 -234.07802)
			(xy 343.538373 -234.123083) (xy 343.5078 -234.163769) (xy 343.471096 -234.199024) (xy 343.429212 -234.227934)
			(xy 343.383233 -234.249751) (xy 343.334349 -234.263911) (xy 343.283828 -234.270045) (xy 343.232976 -234.267996)
			(xy 343.183112 -234.257816) (xy 343.135526 -234.239769) (xy 343.091452 -234.214323) (xy 343.05203 -234.182136)
			(xy 343.018282 -234.144042) (xy 342.991081 -234.101028) (xy 342.971133 -234.054208) (xy 342.958954 -234.004794)
			(xy 342.954859 -233.954066) (xy 342.646762 -233.954066) (xy 342.64625 -233.979512) (xy 342.638086 -234.029746)
			(xy 342.62197 -234.07802) (xy 342.598319 -234.123083) (xy 342.567746 -234.163769) (xy 342.531042 -234.199024)
			(xy 342.489158 -234.227934) (xy 342.443179 -234.249751) (xy 342.394295 -234.263911) (xy 342.343774 -234.270045)
			(xy 342.292922 -234.267996) (xy 342.243058 -234.257816) (xy 342.195472 -234.239769) (xy 342.151398 -234.214323)
			(xy 342.111976 -234.182136) (xy 342.078228 -234.144042) (xy 342.051027 -234.101028) (xy 342.031079 -234.054208)
			(xy 342.0189 -234.004794) (xy 342.014805 -233.954066) (xy 341.696294 -233.954066) (xy 341.695799 -233.978673)
			(xy 341.687904 -234.02725) (xy 341.67232 -234.073931) (xy 341.649449 -234.117508) (xy 341.619884 -234.156852)
			(xy 341.584391 -234.190944) (xy 341.543888 -234.2189) (xy 341.499426 -234.239998) (xy 341.452155 -234.25369)
			(xy 341.4033 -234.259622) (xy 341.354125 -234.257641) (xy 341.305906 -234.247797) (xy 341.25989 -234.230345)
			(xy 341.217269 -234.205738) (xy 341.179148 -234.174613) (xy 341.146513 -234.137776) (xy 341.12021 -234.09618)
			(xy 341.100919 -234.050904) (xy 341.089142 -234.00312) (xy 341.085182 -233.954066) (xy 340.766908 -233.954066)
			(xy 340.766396 -233.979512) (xy 340.758232 -234.029746) (xy 340.742116 -234.07802) (xy 340.718465 -234.123083)
			(xy 340.687892 -234.163769) (xy 340.651188 -234.199024) (xy 340.609304 -234.227934) (xy 340.563325 -234.249751)
			(xy 340.514441 -234.263911) (xy 340.46392 -234.270045) (xy 340.413068 -234.267996) (xy 340.363204 -234.257816)
			(xy 340.315618 -234.239769) (xy 340.271544 -234.214323) (xy 340.232122 -234.182136) (xy 340.198374 -234.144042)
			(xy 340.171173 -234.101028) (xy 340.151225 -234.054208) (xy 340.139046 -234.004794) (xy 340.134951 -233.954066)
			(xy 339.81644 -233.954066) (xy 339.815945 -233.978673) (xy 339.80805 -234.02725) (xy 339.792466 -234.073931)
			(xy 339.769595 -234.117508) (xy 339.74003 -234.156852) (xy 339.704537 -234.190944) (xy 339.664034 -234.2189)
			(xy 339.619572 -234.239998) (xy 339.572301 -234.25369) (xy 339.523446 -234.259622) (xy 339.474271 -234.257641)
			(xy 339.426052 -234.247797) (xy 339.380036 -234.230345) (xy 339.337415 -234.205738) (xy 339.299294 -234.174613)
			(xy 339.266659 -234.137776) (xy 339.240356 -234.09618) (xy 339.221065 -234.050904) (xy 339.209288 -234.00312)
			(xy 339.205328 -233.954066) (xy 338.8868 -233.954066) (xy 338.886288 -233.979512) (xy 338.878124 -234.029746)
			(xy 338.862008 -234.07802) (xy 338.838357 -234.123083) (xy 338.807784 -234.163769) (xy 338.77108 -234.199024)
			(xy 338.729196 -234.227934) (xy 338.683217 -234.249751) (xy 338.634333 -234.263911) (xy 338.583812 -234.270045)
			(xy 338.53296 -234.267996) (xy 338.483096 -234.257816) (xy 338.43551 -234.239769) (xy 338.391436 -234.214323)
			(xy 338.352014 -234.182136) (xy 338.318266 -234.144042) (xy 338.291065 -234.101028) (xy 338.271117 -234.054208)
			(xy 338.258938 -234.004794) (xy 338.254843 -233.954066) (xy 338.06638 -233.954066) (xy 338.06638 -234.387898)
			(xy 338.066816 -234.397593) (xy 338.074006 -234.415604) (xy 338.08035 -234.42295) (xy 338.095082 -234.438444)
			(xy 338.098324 -234.441674) (xy 338.105735 -234.447039) (xy 338.109814 -234.449112) (xy 338.132674 -234.460034)
			(xy 338.140802 -234.461304) (xy 338.165 -234.46494) (xy 338.211893 -234.478911) (xy 338.255958 -234.500181)
			(xy 338.296067 -234.528206) (xy 338.331194 -234.562268) (xy 338.36044 -234.601497) (xy 338.383055 -234.644887)
			(xy 338.398462 -234.691328) (xy 338.406265 -234.739631) (xy 338.406265 -234.764072) (xy 338.724743 -234.764072)
			(xy 338.728838 -234.713344) (xy 338.741017 -234.66393) (xy 338.760965 -234.61711) (xy 338.788166 -234.574096)
			(xy 338.821914 -234.536002) (xy 338.861336 -234.503815) (xy 338.90541 -234.478369) (xy 338.952996 -234.460322)
			(xy 339.00286 -234.450142) (xy 339.053712 -234.448093) (xy 339.104233 -234.454227) (xy 339.153117 -234.468387)
			(xy 339.199096 -234.490204) (xy 339.24098 -234.519114) (xy 339.277684 -234.554369) (xy 339.308257 -234.595055)
			(xy 339.331908 -234.640118) (xy 339.348024 -234.688392) (xy 339.356188 -234.738626) (xy 339.3567 -234.764072)
			(xy 339.664797 -234.764072) (xy 339.668892 -234.713344) (xy 339.681071 -234.66393) (xy 339.701019 -234.61711)
			(xy 339.72822 -234.574096) (xy 339.761968 -234.536002) (xy 339.80139 -234.503815) (xy 339.845464 -234.478369)
			(xy 339.89305 -234.460322) (xy 339.942914 -234.450142) (xy 339.993766 -234.448093) (xy 340.044287 -234.454227)
			(xy 340.093171 -234.468387) (xy 340.13915 -234.490204) (xy 340.181034 -234.519114) (xy 340.217738 -234.554369)
			(xy 340.248311 -234.595055) (xy 340.271962 -234.640118) (xy 340.288078 -234.688392) (xy 340.296242 -234.738626)
			(xy 340.296754 -234.764072) (xy 340.615282 -234.764072) (xy 340.619242 -234.715018) (xy 340.631019 -234.667234)
			(xy 340.65031 -234.621958) (xy 340.676613 -234.580362) (xy 340.709248 -234.543525) (xy 340.747369 -234.5124)
			(xy 340.78999 -234.487793) (xy 340.836006 -234.470341) (xy 340.884225 -234.460497) (xy 340.9334 -234.458516)
			(xy 340.982255 -234.464448) (xy 341.029526 -234.47814) (xy 341.073988 -234.499238) (xy 341.114491 -234.527194)
			(xy 341.149984 -234.561286) (xy 341.179549 -234.60063) (xy 341.20242 -234.644207) (xy 341.218004 -234.690888)
			(xy 341.225899 -234.739465) (xy 341.226394 -234.764072) (xy 341.544905 -234.764072) (xy 341.549 -234.713344)
			(xy 341.561179 -234.66393) (xy 341.581127 -234.61711) (xy 341.608328 -234.574096) (xy 341.642076 -234.536002)
			(xy 341.681498 -234.503815) (xy 341.725572 -234.478369) (xy 341.773158 -234.460322) (xy 341.823022 -234.450142)
			(xy 341.873874 -234.448093) (xy 341.924395 -234.454227) (xy 341.973279 -234.468387) (xy 342.019258 -234.490204)
			(xy 342.061142 -234.519114) (xy 342.097846 -234.554369) (xy 342.128419 -234.595055) (xy 342.15207 -234.640118)
			(xy 342.168186 -234.688392) (xy 342.17635 -234.738626) (xy 342.176862 -234.764072) (xy 342.49539 -234.764072)
			(xy 342.49935 -234.715018) (xy 342.511127 -234.667234) (xy 342.530418 -234.621958) (xy 342.556721 -234.580362)
			(xy 342.589356 -234.543525) (xy 342.627477 -234.5124) (xy 342.670098 -234.487793) (xy 342.716114 -234.470341)
			(xy 342.764333 -234.460497) (xy 342.813508 -234.458516) (xy 342.862363 -234.464448) (xy 342.909634 -234.47814)
			(xy 342.954096 -234.499238) (xy 342.994599 -234.527194) (xy 343.030092 -234.561286) (xy 343.059657 -234.60063)
			(xy 343.082528 -234.644207) (xy 343.098112 -234.690888) (xy 343.106007 -234.739465) (xy 343.106502 -234.764072)
			(xy 343.106007 -234.788679) (xy 343.098112 -234.837256) (xy 343.082528 -234.883937) (xy 343.059657 -234.927514)
			(xy 343.030092 -234.966858) (xy 342.994599 -235.00095) (xy 342.954096 -235.028906) (xy 342.909634 -235.050004)
			(xy 342.862363 -235.063696) (xy 342.813508 -235.069628) (xy 342.764333 -235.067647) (xy 342.716114 -235.057803)
			(xy 342.670098 -235.040351) (xy 342.627477 -235.015744) (xy 342.589356 -234.984619) (xy 342.556721 -234.947782)
			(xy 342.530418 -234.906186) (xy 342.511127 -234.86091) (xy 342.49935 -234.813126) (xy 342.49539 -234.764072)
			(xy 342.176862 -234.764072) (xy 342.17635 -234.789518) (xy 342.168186 -234.839752) (xy 342.15207 -234.888026)
			(xy 342.128419 -234.933089) (xy 342.097846 -234.973775) (xy 342.061142 -235.00903) (xy 342.019258 -235.03794)
			(xy 341.973279 -235.059757) (xy 341.924395 -235.073917) (xy 341.873874 -235.080051) (xy 341.823022 -235.078002)
			(xy 341.773158 -235.067822) (xy 341.725572 -235.049775) (xy 341.681498 -235.024329) (xy 341.642076 -234.992142)
			(xy 341.608328 -234.954048) (xy 341.581127 -234.911034) (xy 341.561179 -234.864214) (xy 341.549 -234.8148)
			(xy 341.544905 -234.764072) (xy 341.226394 -234.764072) (xy 341.225899 -234.788679) (xy 341.218004 -234.837256)
			(xy 341.20242 -234.883937) (xy 341.179549 -234.927514) (xy 341.149984 -234.966858) (xy 341.114491 -235.00095)
			(xy 341.073988 -235.028906) (xy 341.029526 -235.050004) (xy 340.982255 -235.063696) (xy 340.9334 -235.069628)
			(xy 340.884225 -235.067647) (xy 340.836006 -235.057803) (xy 340.78999 -235.040351) (xy 340.747369 -235.015744)
			(xy 340.709248 -234.984619) (xy 340.676613 -234.947782) (xy 340.65031 -234.906186) (xy 340.631019 -234.86091)
			(xy 340.619242 -234.813126) (xy 340.615282 -234.764072) (xy 340.296754 -234.764072) (xy 340.296242 -234.789518)
			(xy 340.288078 -234.839752) (xy 340.271962 -234.888026) (xy 340.248311 -234.933089) (xy 340.217738 -234.973775)
			(xy 340.181034 -235.00903) (xy 340.13915 -235.03794) (xy 340.093171 -235.059757) (xy 340.044287 -235.073917)
			(xy 339.993766 -235.080051) (xy 339.942914 -235.078002) (xy 339.89305 -235.067822) (xy 339.845464 -235.049775)
			(xy 339.80139 -235.024329) (xy 339.761968 -234.992142) (xy 339.72822 -234.954048) (xy 339.701019 -234.911034)
			(xy 339.681071 -234.864214) (xy 339.668892 -234.8148) (xy 339.664797 -234.764072) (xy 339.3567 -234.764072)
			(xy 339.356188 -234.789518) (xy 339.348024 -234.839752) (xy 339.331908 -234.888026) (xy 339.308257 -234.933089)
			(xy 339.277684 -234.973775) (xy 339.24098 -235.00903) (xy 339.199096 -235.03794) (xy 339.153117 -235.059757)
			(xy 339.104233 -235.073917) (xy 339.053712 -235.080051) (xy 339.00286 -235.078002) (xy 338.952996 -235.067822)
			(xy 338.90541 -235.049775) (xy 338.861336 -235.024329) (xy 338.821914 -234.992142) (xy 338.788166 -234.954048)
			(xy 338.760965 -234.911034) (xy 338.741017 -234.864214) (xy 338.728838 -234.8148) (xy 338.724743 -234.764072)
			(xy 338.406265 -234.764072) (xy 338.406266 -234.788561) (xy 338.398463 -234.836865) (xy 338.383058 -234.883307)
			(xy 338.360443 -234.926697) (xy 338.331199 -234.965926) (xy 338.296073 -234.999989) (xy 338.255964 -235.028015)
			(xy 338.2119 -235.049286) (xy 338.165007 -235.063258) (xy 338.140802 -235.06684) (xy 338.132674 -235.06811)
			(xy 338.109814 -235.079032) (xy 338.105727 -235.081092) (xy 338.098313 -235.086458) (xy 338.095082 -235.0897)
			(xy 338.08035 -235.105194) (xy 338.073963 -235.112514) (xy 338.066768 -235.13054) (xy 338.06638 -235.140246)
			(xy 338.06638 -235.574078) (xy 338.254843 -235.574078) (xy 338.258938 -235.52335) (xy 338.271117 -235.473936)
			(xy 338.291065 -235.427116) (xy 338.318266 -235.384102) (xy 338.352014 -235.346008) (xy 338.391436 -235.313821)
			(xy 338.43551 -235.288375) (xy 338.483096 -235.270328) (xy 338.53296 -235.260148) (xy 338.583812 -235.258099)
			(xy 338.634333 -235.264233) (xy 338.683217 -235.278393) (xy 338.729196 -235.30021) (xy 338.77108 -235.32912)
			(xy 338.807784 -235.364375) (xy 338.838357 -235.405061) (xy 338.862008 -235.450124) (xy 338.878124 -235.498398)
			(xy 338.886288 -235.548632) (xy 338.8868 -235.574078) (xy 339.205328 -235.574078) (xy 339.209288 -235.525024)
			(xy 339.221065 -235.47724) (xy 339.240356 -235.431964) (xy 339.266659 -235.390368) (xy 339.299294 -235.353531)
			(xy 339.337415 -235.322406) (xy 339.380036 -235.297799) (xy 339.426052 -235.280347) (xy 339.474271 -235.270503)
			(xy 339.523446 -235.268522) (xy 339.572301 -235.274454) (xy 339.619572 -235.288146) (xy 339.664034 -235.309244)
			(xy 339.704537 -235.3372) (xy 339.74003 -235.371292) (xy 339.769595 -235.410636) (xy 339.792466 -235.454213)
			(xy 339.80805 -235.500894) (xy 339.815945 -235.549471) (xy 339.81644 -235.574078) (xy 340.134951 -235.574078)
			(xy 340.139046 -235.52335) (xy 340.151225 -235.473936) (xy 340.171173 -235.427116) (xy 340.198374 -235.384102)
			(xy 340.232122 -235.346008) (xy 340.271544 -235.313821) (xy 340.315618 -235.288375) (xy 340.363204 -235.270328)
			(xy 340.413068 -235.260148) (xy 340.46392 -235.258099) (xy 340.514441 -235.264233) (xy 340.563325 -235.278393)
			(xy 340.609304 -235.30021) (xy 340.651188 -235.32912) (xy 340.687892 -235.364375) (xy 340.718465 -235.405061)
			(xy 340.742116 -235.450124) (xy 340.758232 -235.498398) (xy 340.766396 -235.548632) (xy 340.766908 -235.574078)
			(xy 341.085182 -235.574078) (xy 341.089142 -235.525024) (xy 341.100919 -235.47724) (xy 341.12021 -235.431964)
			(xy 341.146513 -235.390368) (xy 341.179148 -235.353531) (xy 341.217269 -235.322406) (xy 341.25989 -235.297799)
			(xy 341.305906 -235.280347) (xy 341.354125 -235.270503) (xy 341.4033 -235.268522) (xy 341.452155 -235.274454)
			(xy 341.499426 -235.288146) (xy 341.543888 -235.309244) (xy 341.584391 -235.3372) (xy 341.619884 -235.371292)
			(xy 341.649449 -235.410636) (xy 341.67232 -235.454213) (xy 341.687904 -235.500894) (xy 341.695799 -235.549471)
			(xy 341.696294 -235.574078) (xy 342.014805 -235.574078) (xy 342.0189 -235.52335) (xy 342.031079 -235.473936)
			(xy 342.051027 -235.427116) (xy 342.078228 -235.384102) (xy 342.111976 -235.346008) (xy 342.151398 -235.313821)
			(xy 342.195472 -235.288375) (xy 342.243058 -235.270328) (xy 342.292922 -235.260148) (xy 342.343774 -235.258099)
			(xy 342.394295 -235.264233) (xy 342.443179 -235.278393) (xy 342.489158 -235.30021) (xy 342.531042 -235.32912)
			(xy 342.567746 -235.364375) (xy 342.598319 -235.405061) (xy 342.62197 -235.450124) (xy 342.638086 -235.498398)
			(xy 342.64625 -235.548632) (xy 342.646762 -235.574078) (xy 342.954859 -235.574078) (xy 342.958954 -235.52335)
			(xy 342.971133 -235.473936) (xy 342.991081 -235.427116) (xy 343.018282 -235.384102) (xy 343.05203 -235.346008)
			(xy 343.091452 -235.313821) (xy 343.135526 -235.288375) (xy 343.183112 -235.270328) (xy 343.232976 -235.260148)
			(xy 343.283828 -235.258099) (xy 343.334349 -235.264233) (xy 343.383233 -235.278393) (xy 343.429212 -235.30021)
			(xy 343.471096 -235.32912) (xy 343.5078 -235.364375) (xy 343.538373 -235.405061) (xy 343.562024 -235.450124)
			(xy 343.57814 -235.498398) (xy 343.586304 -235.548632) (xy 343.586816 -235.574078) (xy 343.586304 -235.599524)
			(xy 343.57814 -235.649758) (xy 343.562024 -235.698032) (xy 343.538373 -235.743095) (xy 343.5078 -235.783781)
			(xy 343.471096 -235.819036) (xy 343.429212 -235.847946) (xy 343.383233 -235.869763) (xy 343.334349 -235.883923)
			(xy 343.283828 -235.890057) (xy 343.232976 -235.888008) (xy 343.183112 -235.877828) (xy 343.135526 -235.859781)
			(xy 343.091452 -235.834335) (xy 343.05203 -235.802148) (xy 343.018282 -235.764054) (xy 342.991081 -235.72104)
			(xy 342.971133 -235.67422) (xy 342.958954 -235.624806) (xy 342.954859 -235.574078) (xy 342.646762 -235.574078)
			(xy 342.64625 -235.599524) (xy 342.638086 -235.649758) (xy 342.62197 -235.698032) (xy 342.598319 -235.743095)
			(xy 342.567746 -235.783781) (xy 342.531042 -235.819036) (xy 342.489158 -235.847946) (xy 342.443179 -235.869763)
			(xy 342.394295 -235.883923) (xy 342.343774 -235.890057) (xy 342.292922 -235.888008) (xy 342.243058 -235.877828)
			(xy 342.195472 -235.859781) (xy 342.151398 -235.834335) (xy 342.111976 -235.802148) (xy 342.078228 -235.764054)
			(xy 342.051027 -235.72104) (xy 342.031079 -235.67422) (xy 342.0189 -235.624806) (xy 342.014805 -235.574078)
			(xy 341.696294 -235.574078) (xy 341.695799 -235.598685) (xy 341.687904 -235.647262) (xy 341.67232 -235.693943)
			(xy 341.649449 -235.73752) (xy 341.619884 -235.776864) (xy 341.584391 -235.810956) (xy 341.543888 -235.838912)
			(xy 341.499426 -235.86001) (xy 341.452155 -235.873702) (xy 341.4033 -235.879634) (xy 341.354125 -235.877653)
			(xy 341.305906 -235.867809) (xy 341.25989 -235.850357) (xy 341.217269 -235.82575) (xy 341.179148 -235.794625)
			(xy 341.146513 -235.757788) (xy 341.12021 -235.716192) (xy 341.100919 -235.670916) (xy 341.089142 -235.623132)
			(xy 341.085182 -235.574078) (xy 340.766908 -235.574078) (xy 340.766396 -235.599524) (xy 340.758232 -235.649758)
			(xy 340.742116 -235.698032) (xy 340.718465 -235.743095) (xy 340.687892 -235.783781) (xy 340.651188 -235.819036)
			(xy 340.609304 -235.847946) (xy 340.563325 -235.869763) (xy 340.514441 -235.883923) (xy 340.46392 -235.890057)
			(xy 340.413068 -235.888008) (xy 340.363204 -235.877828) (xy 340.315618 -235.859781) (xy 340.271544 -235.834335)
			(xy 340.232122 -235.802148) (xy 340.198374 -235.764054) (xy 340.171173 -235.72104) (xy 340.151225 -235.67422)
			(xy 340.139046 -235.624806) (xy 340.134951 -235.574078) (xy 339.81644 -235.574078) (xy 339.815945 -235.598685)
			(xy 339.80805 -235.647262) (xy 339.792466 -235.693943) (xy 339.769595 -235.73752) (xy 339.74003 -235.776864)
			(xy 339.704537 -235.810956) (xy 339.664034 -235.838912) (xy 339.619572 -235.86001) (xy 339.572301 -235.873702)
			(xy 339.523446 -235.879634) (xy 339.474271 -235.877653) (xy 339.426052 -235.867809) (xy 339.380036 -235.850357)
			(xy 339.337415 -235.82575) (xy 339.299294 -235.794625) (xy 339.266659 -235.757788) (xy 339.240356 -235.716192)
			(xy 339.221065 -235.670916) (xy 339.209288 -235.623132) (xy 339.205328 -235.574078) (xy 338.8868 -235.574078)
			(xy 338.886288 -235.599524) (xy 338.878124 -235.649758) (xy 338.862008 -235.698032) (xy 338.838357 -235.743095)
			(xy 338.807784 -235.783781) (xy 338.77108 -235.819036) (xy 338.729196 -235.847946) (xy 338.683217 -235.869763)
			(xy 338.634333 -235.883923) (xy 338.583812 -235.890057) (xy 338.53296 -235.888008) (xy 338.483096 -235.877828)
			(xy 338.43551 -235.859781) (xy 338.391436 -235.834335) (xy 338.352014 -235.802148) (xy 338.318266 -235.764054)
			(xy 338.291065 -235.72104) (xy 338.271117 -235.67422) (xy 338.258938 -235.624806) (xy 338.254843 -235.574078)
			(xy 338.06638 -235.574078) (xy 338.06638 -236.00791) (xy 338.066801 -236.017612) (xy 338.073968 -236.035644)
			(xy 338.08035 -236.042962) (xy 338.095082 -236.058456) (xy 338.09832 -236.06169) (xy 338.105727 -236.067064)
			(xy 338.109814 -236.069124) (xy 338.132674 -236.080046) (xy 338.140802 -236.081316) (xy 338.164999 -236.084952)
			(xy 338.21189 -236.098923) (xy 338.255954 -236.120192) (xy 338.296061 -236.148216) (xy 338.331186 -236.182277)
			(xy 338.36043 -236.221504) (xy 338.383045 -236.264893) (xy 338.39845 -236.311332) (xy 338.406253 -236.359634)
			(xy 338.406253 -236.384084) (xy 338.724743 -236.384084) (xy 338.728838 -236.333356) (xy 338.741017 -236.283942)
			(xy 338.760965 -236.237122) (xy 338.788166 -236.194108) (xy 338.821914 -236.156014) (xy 338.861336 -236.123827)
			(xy 338.90541 -236.098381) (xy 338.952996 -236.080334) (xy 339.00286 -236.070154) (xy 339.053712 -236.068105)
			(xy 339.104233 -236.074239) (xy 339.153117 -236.088399) (xy 339.199096 -236.110216) (xy 339.24098 -236.139126)
			(xy 339.277684 -236.174381) (xy 339.308257 -236.215067) (xy 339.331908 -236.26013) (xy 339.348024 -236.308404)
			(xy 339.356188 -236.358638) (xy 339.3567 -236.384084) (xy 339.664797 -236.384084) (xy 339.668892 -236.333356)
			(xy 339.681071 -236.283942) (xy 339.701019 -236.237122) (xy 339.72822 -236.194108) (xy 339.761968 -236.156014)
			(xy 339.80139 -236.123827) (xy 339.845464 -236.098381) (xy 339.89305 -236.080334) (xy 339.942914 -236.070154)
			(xy 339.993766 -236.068105) (xy 340.044287 -236.074239) (xy 340.093171 -236.088399) (xy 340.13915 -236.110216)
			(xy 340.181034 -236.139126) (xy 340.217738 -236.174381) (xy 340.248311 -236.215067) (xy 340.271962 -236.26013)
			(xy 340.288078 -236.308404) (xy 340.296242 -236.358638) (xy 340.296754 -236.384084) (xy 340.615282 -236.384084)
			(xy 340.619242 -236.33503) (xy 340.631019 -236.287246) (xy 340.65031 -236.24197) (xy 340.676613 -236.200374)
			(xy 340.709248 -236.163537) (xy 340.747369 -236.132412) (xy 340.78999 -236.107805) (xy 340.836006 -236.090353)
			(xy 340.884225 -236.080509) (xy 340.9334 -236.078528) (xy 340.982255 -236.08446) (xy 341.029526 -236.098152)
			(xy 341.073988 -236.11925) (xy 341.114491 -236.147206) (xy 341.149984 -236.181298) (xy 341.179549 -236.220642)
			(xy 341.20242 -236.264219) (xy 341.218004 -236.3109) (xy 341.225899 -236.359477) (xy 341.226394 -236.384084)
			(xy 341.544905 -236.384084) (xy 341.549 -236.333356) (xy 341.561179 -236.283942) (xy 341.581127 -236.237122)
			(xy 341.608328 -236.194108) (xy 341.642076 -236.156014) (xy 341.681498 -236.123827) (xy 341.725572 -236.098381)
			(xy 341.773158 -236.080334) (xy 341.823022 -236.070154) (xy 341.873874 -236.068105) (xy 341.924395 -236.074239)
			(xy 341.973279 -236.088399) (xy 342.019258 -236.110216) (xy 342.061142 -236.139126) (xy 342.097846 -236.174381)
			(xy 342.128419 -236.215067) (xy 342.15207 -236.26013) (xy 342.168186 -236.308404) (xy 342.17635 -236.358638)
			(xy 342.176862 -236.384084) (xy 342.49539 -236.384084) (xy 342.49935 -236.33503) (xy 342.511127 -236.287246)
			(xy 342.530418 -236.24197) (xy 342.556721 -236.200374) (xy 342.589356 -236.163537) (xy 342.627477 -236.132412)
			(xy 342.670098 -236.107805) (xy 342.716114 -236.090353) (xy 342.764333 -236.080509) (xy 342.813508 -236.078528)
			(xy 342.862363 -236.08446) (xy 342.909634 -236.098152) (xy 342.954096 -236.11925) (xy 342.994599 -236.147206)
			(xy 343.030092 -236.181298) (xy 343.059657 -236.220642) (xy 343.082528 -236.264219) (xy 343.098112 -236.3109)
			(xy 343.106007 -236.359477) (xy 343.106502 -236.384084) (xy 343.106007 -236.408691) (xy 343.098112 -236.457268)
			(xy 343.082528 -236.503949) (xy 343.059657 -236.547526) (xy 343.030092 -236.58687) (xy 342.994599 -236.620962)
			(xy 342.954096 -236.648918) (xy 342.909634 -236.670016) (xy 342.862363 -236.683708) (xy 342.813508 -236.68964)
			(xy 342.764333 -236.687659) (xy 342.716114 -236.677815) (xy 342.670098 -236.660363) (xy 342.627477 -236.635756)
			(xy 342.589356 -236.604631) (xy 342.556721 -236.567794) (xy 342.530418 -236.526198) (xy 342.511127 -236.480922)
			(xy 342.49935 -236.433138) (xy 342.49539 -236.384084) (xy 342.176862 -236.384084) (xy 342.17635 -236.40953)
			(xy 342.168186 -236.459764) (xy 342.15207 -236.508038) (xy 342.128419 -236.553101) (xy 342.097846 -236.593787)
			(xy 342.061142 -236.629042) (xy 342.019258 -236.657952) (xy 341.973279 -236.679769) (xy 341.924395 -236.693929)
			(xy 341.873874 -236.700063) (xy 341.823022 -236.698014) (xy 341.773158 -236.687834) (xy 341.725572 -236.669787)
			(xy 341.681498 -236.644341) (xy 341.642076 -236.612154) (xy 341.608328 -236.57406) (xy 341.581127 -236.531046)
			(xy 341.561179 -236.484226) (xy 341.549 -236.434812) (xy 341.544905 -236.384084) (xy 341.226394 -236.384084)
			(xy 341.225899 -236.408691) (xy 341.218004 -236.457268) (xy 341.20242 -236.503949) (xy 341.179549 -236.547526)
			(xy 341.149984 -236.58687) (xy 341.114491 -236.620962) (xy 341.073988 -236.648918) (xy 341.029526 -236.670016)
			(xy 340.982255 -236.683708) (xy 340.9334 -236.68964) (xy 340.884225 -236.687659) (xy 340.836006 -236.677815)
			(xy 340.78999 -236.660363) (xy 340.747369 -236.635756) (xy 340.709248 -236.604631) (xy 340.676613 -236.567794)
			(xy 340.65031 -236.526198) (xy 340.631019 -236.480922) (xy 340.619242 -236.433138) (xy 340.615282 -236.384084)
			(xy 340.296754 -236.384084) (xy 340.296242 -236.40953) (xy 340.288078 -236.459764) (xy 340.271962 -236.508038)
			(xy 340.248311 -236.553101) (xy 340.217738 -236.593787) (xy 340.181034 -236.629042) (xy 340.13915 -236.657952)
			(xy 340.093171 -236.679769) (xy 340.044287 -236.693929) (xy 339.993766 -236.700063) (xy 339.942914 -236.698014)
			(xy 339.89305 -236.687834) (xy 339.845464 -236.669787) (xy 339.80139 -236.644341) (xy 339.761968 -236.612154)
			(xy 339.72822 -236.57406) (xy 339.701019 -236.531046) (xy 339.681071 -236.484226) (xy 339.668892 -236.434812)
			(xy 339.664797 -236.384084) (xy 339.3567 -236.384084) (xy 339.356188 -236.40953) (xy 339.348024 -236.459764)
			(xy 339.331908 -236.508038) (xy 339.308257 -236.553101) (xy 339.277684 -236.593787) (xy 339.24098 -236.629042)
			(xy 339.199096 -236.657952) (xy 339.153117 -236.679769) (xy 339.104233 -236.693929) (xy 339.053712 -236.700063)
			(xy 339.00286 -236.698014) (xy 338.952996 -236.687834) (xy 338.90541 -236.669787) (xy 338.861336 -236.644341)
			(xy 338.821914 -236.612154) (xy 338.788166 -236.57406) (xy 338.760965 -236.531046) (xy 338.741017 -236.484226)
			(xy 338.728838 -236.434812) (xy 338.724743 -236.384084) (xy 338.406253 -236.384084) (xy 338.406254 -236.408562)
			(xy 338.398451 -236.456864) (xy 338.383046 -236.503304) (xy 338.360433 -236.546692) (xy 338.331189 -236.585919)
			(xy 338.296064 -236.619981) (xy 338.255957 -236.648006) (xy 338.211894 -236.669276) (xy 338.165003 -236.683247)
			(xy 338.140802 -236.686852) (xy 338.132674 -236.688122) (xy 338.109814 -236.699044) (xy 338.105727 -236.701104)
			(xy 338.098315 -236.706472) (xy 338.095082 -236.709712) (xy 338.08035 -236.725206) (xy 338.073965 -236.732526)
			(xy 338.066774 -236.750553) (xy 338.06638 -236.760258) (xy 338.06638 -237.19409) (xy 338.254843 -237.19409)
			(xy 338.258938 -237.143362) (xy 338.271117 -237.093948) (xy 338.291065 -237.047128) (xy 338.318266 -237.004114)
			(xy 338.352014 -236.96602) (xy 338.391436 -236.933833) (xy 338.43551 -236.908387) (xy 338.483096 -236.89034)
			(xy 338.53296 -236.88016) (xy 338.583812 -236.878111) (xy 338.634333 -236.884245) (xy 338.683217 -236.898405)
			(xy 338.729196 -236.920222) (xy 338.77108 -236.949132) (xy 338.807784 -236.984387) (xy 338.838357 -237.025073)
			(xy 338.862008 -237.070136) (xy 338.878124 -237.11841) (xy 338.886288 -237.168644) (xy 338.8868 -237.19409)
			(xy 339.205328 -237.19409) (xy 339.209288 -237.145036) (xy 339.221065 -237.097252) (xy 339.240356 -237.051976)
			(xy 339.266659 -237.01038) (xy 339.299294 -236.973543) (xy 339.337415 -236.942418) (xy 339.380036 -236.917811)
			(xy 339.426052 -236.900359) (xy 339.474271 -236.890515) (xy 339.523446 -236.888534) (xy 339.572301 -236.894466)
			(xy 339.619572 -236.908158) (xy 339.664034 -236.929256) (xy 339.704537 -236.957212) (xy 339.74003 -236.991304)
			(xy 339.769595 -237.030648) (xy 339.792466 -237.074225) (xy 339.80805 -237.120906) (xy 339.815945 -237.169483)
			(xy 339.81644 -237.19409) (xy 340.134951 -237.19409) (xy 340.139046 -237.143362) (xy 340.151225 -237.093948)
			(xy 340.171173 -237.047128) (xy 340.198374 -237.004114) (xy 340.232122 -236.96602) (xy 340.271544 -236.933833)
			(xy 340.315618 -236.908387) (xy 340.363204 -236.89034) (xy 340.413068 -236.88016) (xy 340.46392 -236.878111)
			(xy 340.514441 -236.884245) (xy 340.563325 -236.898405) (xy 340.609304 -236.920222) (xy 340.651188 -236.949132)
			(xy 340.687892 -236.984387) (xy 340.718465 -237.025073) (xy 340.742116 -237.070136) (xy 340.758232 -237.11841)
			(xy 340.766396 -237.168644) (xy 340.766908 -237.19409) (xy 341.085182 -237.19409) (xy 341.089142 -237.145036)
			(xy 341.100919 -237.097252) (xy 341.12021 -237.051976) (xy 341.146513 -237.01038) (xy 341.179148 -236.973543)
			(xy 341.217269 -236.942418) (xy 341.25989 -236.917811) (xy 341.305906 -236.900359) (xy 341.354125 -236.890515)
			(xy 341.4033 -236.888534) (xy 341.452155 -236.894466) (xy 341.499426 -236.908158) (xy 341.543888 -236.929256)
			(xy 341.584391 -236.957212) (xy 341.619884 -236.991304) (xy 341.649449 -237.030648) (xy 341.67232 -237.074225)
			(xy 341.687904 -237.120906) (xy 341.695799 -237.169483) (xy 341.696294 -237.19409) (xy 342.014805 -237.19409)
			(xy 342.0189 -237.143362) (xy 342.031079 -237.093948) (xy 342.051027 -237.047128) (xy 342.078228 -237.004114)
			(xy 342.111976 -236.96602) (xy 342.151398 -236.933833) (xy 342.195472 -236.908387) (xy 342.243058 -236.89034)
			(xy 342.292922 -236.88016) (xy 342.343774 -236.878111) (xy 342.394295 -236.884245) (xy 342.443179 -236.898405)
			(xy 342.489158 -236.920222) (xy 342.531042 -236.949132) (xy 342.567746 -236.984387) (xy 342.598319 -237.025073)
			(xy 342.62197 -237.070136) (xy 342.638086 -237.11841) (xy 342.64625 -237.168644) (xy 342.646762 -237.19409)
			(xy 342.954859 -237.19409) (xy 342.958954 -237.143362) (xy 342.971133 -237.093948) (xy 342.991081 -237.047128)
			(xy 343.018282 -237.004114) (xy 343.05203 -236.96602) (xy 343.091452 -236.933833) (xy 343.135526 -236.908387)
			(xy 343.183112 -236.89034) (xy 343.232976 -236.88016) (xy 343.283828 -236.878111) (xy 343.334349 -236.884245)
			(xy 343.383233 -236.898405) (xy 343.429212 -236.920222) (xy 343.471096 -236.949132) (xy 343.5078 -236.984387)
			(xy 343.538373 -237.025073) (xy 343.562024 -237.070136) (xy 343.57814 -237.11841) (xy 343.586304 -237.168644)
			(xy 343.586816 -237.19409) (xy 343.586304 -237.219536) (xy 343.57814 -237.26977) (xy 343.562024 -237.318044)
			(xy 343.538373 -237.363107) (xy 343.5078 -237.403793) (xy 343.471096 -237.439048) (xy 343.429212 -237.467958)
			(xy 343.383233 -237.489775) (xy 343.334349 -237.503935) (xy 343.283828 -237.510069) (xy 343.232976 -237.50802)
			(xy 343.183112 -237.49784) (xy 343.135526 -237.479793) (xy 343.091452 -237.454347) (xy 343.05203 -237.42216)
			(xy 343.018282 -237.384066) (xy 342.991081 -237.341052) (xy 342.971133 -237.294232) (xy 342.958954 -237.244818)
			(xy 342.954859 -237.19409) (xy 342.646762 -237.19409) (xy 342.64625 -237.219536) (xy 342.638086 -237.26977)
			(xy 342.62197 -237.318044) (xy 342.598319 -237.363107) (xy 342.567746 -237.403793) (xy 342.531042 -237.439048)
			(xy 342.489158 -237.467958) (xy 342.443179 -237.489775) (xy 342.394295 -237.503935) (xy 342.343774 -237.510069)
			(xy 342.292922 -237.50802) (xy 342.243058 -237.49784) (xy 342.195472 -237.479793) (xy 342.151398 -237.454347)
			(xy 342.111976 -237.42216) (xy 342.078228 -237.384066) (xy 342.051027 -237.341052) (xy 342.031079 -237.294232)
			(xy 342.0189 -237.244818) (xy 342.014805 -237.19409) (xy 341.696294 -237.19409) (xy 341.695799 -237.218697)
			(xy 341.687904 -237.267274) (xy 341.67232 -237.313955) (xy 341.649449 -237.357532) (xy 341.619884 -237.396876)
			(xy 341.584391 -237.430968) (xy 341.543888 -237.458924) (xy 341.499426 -237.480022) (xy 341.452155 -237.493714)
			(xy 341.4033 -237.499646) (xy 341.354125 -237.497665) (xy 341.305906 -237.487821) (xy 341.25989 -237.470369)
			(xy 341.217269 -237.445762) (xy 341.179148 -237.414637) (xy 341.146513 -237.3778) (xy 341.12021 -237.336204)
			(xy 341.100919 -237.290928) (xy 341.089142 -237.243144) (xy 341.085182 -237.19409) (xy 340.766908 -237.19409)
			(xy 340.766396 -237.219536) (xy 340.758232 -237.26977) (xy 340.742116 -237.318044) (xy 340.718465 -237.363107)
			(xy 340.687892 -237.403793) (xy 340.651188 -237.439048) (xy 340.609304 -237.467958) (xy 340.563325 -237.489775)
			(xy 340.514441 -237.503935) (xy 340.46392 -237.510069) (xy 340.413068 -237.50802) (xy 340.363204 -237.49784)
			(xy 340.315618 -237.479793) (xy 340.271544 -237.454347) (xy 340.232122 -237.42216) (xy 340.198374 -237.384066)
			(xy 340.171173 -237.341052) (xy 340.151225 -237.294232) (xy 340.139046 -237.244818) (xy 340.134951 -237.19409)
			(xy 339.81644 -237.19409) (xy 339.815945 -237.218697) (xy 339.80805 -237.267274) (xy 339.792466 -237.313955)
			(xy 339.769595 -237.357532) (xy 339.74003 -237.396876) (xy 339.704537 -237.430968) (xy 339.664034 -237.458924)
			(xy 339.619572 -237.480022) (xy 339.572301 -237.493714) (xy 339.523446 -237.499646) (xy 339.474271 -237.497665)
			(xy 339.426052 -237.487821) (xy 339.380036 -237.470369) (xy 339.337415 -237.445762) (xy 339.299294 -237.414637)
			(xy 339.266659 -237.3778) (xy 339.240356 -237.336204) (xy 339.221065 -237.290928) (xy 339.209288 -237.243144)
			(xy 339.205328 -237.19409) (xy 338.8868 -237.19409) (xy 338.886288 -237.219536) (xy 338.878124 -237.26977)
			(xy 338.862008 -237.318044) (xy 338.838357 -237.363107) (xy 338.807784 -237.403793) (xy 338.77108 -237.439048)
			(xy 338.729196 -237.467958) (xy 338.683217 -237.489775) (xy 338.634333 -237.503935) (xy 338.583812 -237.510069)
			(xy 338.53296 -237.50802) (xy 338.483096 -237.49784) (xy 338.43551 -237.479793) (xy 338.391436 -237.454347)
			(xy 338.352014 -237.42216) (xy 338.318266 -237.384066) (xy 338.291065 -237.341052) (xy 338.271117 -237.294232)
			(xy 338.258938 -237.244818) (xy 338.254843 -237.19409) (xy 338.06638 -237.19409) (xy 338.06638 -237.627922)
			(xy 338.066803 -237.637623) (xy 338.073974 -237.655652) (xy 338.08035 -237.662974) (xy 338.095082 -237.678468)
			(xy 338.098321 -237.681701) (xy 338.105728 -237.687074) (xy 338.109814 -237.689136) (xy 338.132674 -237.700058)
			(xy 338.140802 -237.701328) (xy 338.164998 -237.704964) (xy 338.211887 -237.718934) (xy 338.255949 -237.740203)
			(xy 338.296055 -237.768226) (xy 338.331178 -237.802286) (xy 338.360421 -237.841512) (xy 338.383034 -237.884899)
			(xy 338.398439 -237.931336) (xy 338.406242 -237.979636) (xy 338.406242 -238.004096) (xy 338.724743 -238.004096)
			(xy 338.728838 -237.953368) (xy 338.741017 -237.903954) (xy 338.760965 -237.857134) (xy 338.788166 -237.81412)
			(xy 338.821914 -237.776026) (xy 338.861336 -237.743839) (xy 338.90541 -237.718393) (xy 338.952996 -237.700346)
			(xy 339.00286 -237.690166) (xy 339.053712 -237.688117) (xy 339.104233 -237.694251) (xy 339.153117 -237.708411)
			(xy 339.199096 -237.730228) (xy 339.24098 -237.759138) (xy 339.277684 -237.794393) (xy 339.308257 -237.835079)
			(xy 339.331908 -237.880142) (xy 339.348024 -237.928416) (xy 339.356188 -237.97865) (xy 339.3567 -238.004096)
			(xy 339.664797 -238.004096) (xy 339.668892 -237.953368) (xy 339.681071 -237.903954) (xy 339.701019 -237.857134)
			(xy 339.72822 -237.81412) (xy 339.761968 -237.776026) (xy 339.80139 -237.743839) (xy 339.845464 -237.718393)
			(xy 339.89305 -237.700346) (xy 339.942914 -237.690166) (xy 339.993766 -237.688117) (xy 340.044287 -237.694251)
			(xy 340.093171 -237.708411) (xy 340.13915 -237.730228) (xy 340.181034 -237.759138) (xy 340.217738 -237.794393)
			(xy 340.248311 -237.835079) (xy 340.271962 -237.880142) (xy 340.288078 -237.928416) (xy 340.296242 -237.97865)
			(xy 340.296754 -238.004096) (xy 340.615282 -238.004096) (xy 340.619242 -237.955042) (xy 340.631019 -237.907258)
			(xy 340.65031 -237.861982) (xy 340.676613 -237.820386) (xy 340.709248 -237.783549) (xy 340.747369 -237.752424)
			(xy 340.78999 -237.727817) (xy 340.836006 -237.710365) (xy 340.884225 -237.700521) (xy 340.9334 -237.69854)
			(xy 340.982255 -237.704472) (xy 341.029526 -237.718164) (xy 341.073988 -237.739262) (xy 341.114491 -237.767218)
			(xy 341.149984 -237.80131) (xy 341.179549 -237.840654) (xy 341.20242 -237.884231) (xy 341.218004 -237.930912)
			(xy 341.225899 -237.979489) (xy 341.226394 -238.004096) (xy 341.544905 -238.004096) (xy 341.549 -237.953368)
			(xy 341.561179 -237.903954) (xy 341.581127 -237.857134) (xy 341.608328 -237.81412) (xy 341.642076 -237.776026)
			(xy 341.681498 -237.743839) (xy 341.725572 -237.718393) (xy 341.773158 -237.700346) (xy 341.823022 -237.690166)
			(xy 341.873874 -237.688117) (xy 341.924395 -237.694251) (xy 341.973279 -237.708411) (xy 342.019258 -237.730228)
			(xy 342.061142 -237.759138) (xy 342.097846 -237.794393) (xy 342.128419 -237.835079) (xy 342.15207 -237.880142)
			(xy 342.168186 -237.928416) (xy 342.17635 -237.97865) (xy 342.176862 -238.004096) (xy 342.49539 -238.004096)
			(xy 342.49935 -237.955042) (xy 342.511127 -237.907258) (xy 342.530418 -237.861982) (xy 342.556721 -237.820386)
			(xy 342.589356 -237.783549) (xy 342.627477 -237.752424) (xy 342.670098 -237.727817) (xy 342.716114 -237.710365)
			(xy 342.764333 -237.700521) (xy 342.813508 -237.69854) (xy 342.862363 -237.704472) (xy 342.909634 -237.718164)
			(xy 342.954096 -237.739262) (xy 342.994599 -237.767218) (xy 343.030092 -237.80131) (xy 343.059657 -237.840654)
			(xy 343.082528 -237.884231) (xy 343.098112 -237.930912) (xy 343.106007 -237.979489) (xy 343.106502 -238.004096)
			(xy 343.106007 -238.028703) (xy 343.098112 -238.07728) (xy 343.082528 -238.123961) (xy 343.059657 -238.167538)
			(xy 343.030092 -238.206882) (xy 342.994599 -238.240974) (xy 342.954096 -238.26893) (xy 342.909634 -238.290028)
			(xy 342.862363 -238.30372) (xy 342.813508 -238.309652) (xy 342.764333 -238.307671) (xy 342.716114 -238.297827)
			(xy 342.670098 -238.280375) (xy 342.627477 -238.255768) (xy 342.589356 -238.224643) (xy 342.556721 -238.187806)
			(xy 342.530418 -238.14621) (xy 342.511127 -238.100934) (xy 342.49935 -238.05315) (xy 342.49539 -238.004096)
			(xy 342.176862 -238.004096) (xy 342.17635 -238.029542) (xy 342.168186 -238.079776) (xy 342.15207 -238.12805)
			(xy 342.128419 -238.173113) (xy 342.097846 -238.213799) (xy 342.061142 -238.249054) (xy 342.019258 -238.277964)
			(xy 341.973279 -238.299781) (xy 341.924395 -238.313941) (xy 341.873874 -238.320075) (xy 341.823022 -238.318026)
			(xy 341.773158 -238.307846) (xy 341.725572 -238.289799) (xy 341.681498 -238.264353) (xy 341.642076 -238.232166)
			(xy 341.608328 -238.194072) (xy 341.581127 -238.151058) (xy 341.561179 -238.104238) (xy 341.549 -238.054824)
			(xy 341.544905 -238.004096) (xy 341.226394 -238.004096) (xy 341.225899 -238.028703) (xy 341.218004 -238.07728)
			(xy 341.20242 -238.123961) (xy 341.179549 -238.167538) (xy 341.149984 -238.206882) (xy 341.114491 -238.240974)
			(xy 341.073988 -238.26893) (xy 341.029526 -238.290028) (xy 340.982255 -238.30372) (xy 340.9334 -238.309652)
			(xy 340.884225 -238.307671) (xy 340.836006 -238.297827) (xy 340.78999 -238.280375) (xy 340.747369 -238.255768)
			(xy 340.709248 -238.224643) (xy 340.676613 -238.187806) (xy 340.65031 -238.14621) (xy 340.631019 -238.100934)
			(xy 340.619242 -238.05315) (xy 340.615282 -238.004096) (xy 340.296754 -238.004096) (xy 340.296242 -238.029542)
			(xy 340.288078 -238.079776) (xy 340.271962 -238.12805) (xy 340.248311 -238.173113) (xy 340.217738 -238.213799)
			(xy 340.181034 -238.249054) (xy 340.13915 -238.277964) (xy 340.093171 -238.299781) (xy 340.044287 -238.313941)
			(xy 339.993766 -238.320075) (xy 339.942914 -238.318026) (xy 339.89305 -238.307846) (xy 339.845464 -238.289799)
			(xy 339.80139 -238.264353) (xy 339.761968 -238.232166) (xy 339.72822 -238.194072) (xy 339.701019 -238.151058)
			(xy 339.681071 -238.104238) (xy 339.668892 -238.054824) (xy 339.664797 -238.004096) (xy 339.3567 -238.004096)
			(xy 339.356188 -238.029542) (xy 339.348024 -238.079776) (xy 339.331908 -238.12805) (xy 339.308257 -238.173113)
			(xy 339.277684 -238.213799) (xy 339.24098 -238.249054) (xy 339.199096 -238.277964) (xy 339.153117 -238.299781)
			(xy 339.104233 -238.313941) (xy 339.053712 -238.320075) (xy 339.00286 -238.318026) (xy 338.952996 -238.307846)
			(xy 338.90541 -238.289799) (xy 338.861336 -238.264353) (xy 338.821914 -238.232166) (xy 338.788166 -238.194072)
			(xy 338.760965 -238.151058) (xy 338.741017 -238.104238) (xy 338.728838 -238.054824) (xy 338.724743 -238.004096)
			(xy 338.406242 -238.004096) (xy 338.406242 -238.028563) (xy 338.398439 -238.076863) (xy 338.383035 -238.1233)
			(xy 338.360422 -238.166687) (xy 338.331179 -238.205913) (xy 338.296055 -238.239973) (xy 338.25595 -238.267996)
			(xy 338.211888 -238.289265) (xy 338.164999 -238.303235) (xy 338.140802 -238.306864) (xy 338.132674 -238.308134)
			(xy 338.109814 -238.319056) (xy 338.105727 -238.321117) (xy 338.098316 -238.326485) (xy 338.095082 -238.329724)
			(xy 338.08035 -238.345218) (xy 338.073966 -238.352539) (xy 338.06678 -238.370565) (xy 338.06638 -238.38027)
			(xy 338.06638 -238.814102) (xy 338.254843 -238.814102) (xy 338.258938 -238.763374) (xy 338.271117 -238.71396)
			(xy 338.291065 -238.66714) (xy 338.318266 -238.624126) (xy 338.352014 -238.586032) (xy 338.391436 -238.553845)
			(xy 338.43551 -238.528399) (xy 338.483096 -238.510352) (xy 338.53296 -238.500172) (xy 338.583812 -238.498123)
			(xy 338.634333 -238.504257) (xy 338.683217 -238.518417) (xy 338.729196 -238.540234) (xy 338.77108 -238.569144)
			(xy 338.807784 -238.604399) (xy 338.838357 -238.645085) (xy 338.862008 -238.690148) (xy 338.878124 -238.738422)
			(xy 338.886288 -238.788656) (xy 338.8868 -238.814102) (xy 339.205328 -238.814102) (xy 339.209288 -238.765048)
			(xy 339.221065 -238.717264) (xy 339.240356 -238.671988) (xy 339.266659 -238.630392) (xy 339.299294 -238.593555)
			(xy 339.337415 -238.56243) (xy 339.380036 -238.537823) (xy 339.426052 -238.520371) (xy 339.474271 -238.510527)
			(xy 339.523446 -238.508546) (xy 339.572301 -238.514478) (xy 339.619572 -238.52817) (xy 339.664034 -238.549268)
			(xy 339.704537 -238.577224) (xy 339.74003 -238.611316) (xy 339.769595 -238.65066) (xy 339.792466 -238.694237)
			(xy 339.80805 -238.740918) (xy 339.815945 -238.789495) (xy 339.81644 -238.814102) (xy 340.134951 -238.814102)
			(xy 340.139046 -238.763374) (xy 340.151225 -238.71396) (xy 340.171173 -238.66714) (xy 340.198374 -238.624126)
			(xy 340.232122 -238.586032) (xy 340.271544 -238.553845) (xy 340.315618 -238.528399) (xy 340.363204 -238.510352)
			(xy 340.413068 -238.500172) (xy 340.46392 -238.498123) (xy 340.514441 -238.504257) (xy 340.563325 -238.518417)
			(xy 340.609304 -238.540234) (xy 340.651188 -238.569144) (xy 340.687892 -238.604399) (xy 340.718465 -238.645085)
			(xy 340.742116 -238.690148) (xy 340.758232 -238.738422) (xy 340.766396 -238.788656) (xy 340.766908 -238.814102)
			(xy 341.085182 -238.814102) (xy 341.089142 -238.765048) (xy 341.100919 -238.717264) (xy 341.12021 -238.671988)
			(xy 341.146513 -238.630392) (xy 341.179148 -238.593555) (xy 341.217269 -238.56243) (xy 341.25989 -238.537823)
			(xy 341.305906 -238.520371) (xy 341.354125 -238.510527) (xy 341.4033 -238.508546) (xy 341.452155 -238.514478)
			(xy 341.499426 -238.52817) (xy 341.543888 -238.549268) (xy 341.584391 -238.577224) (xy 341.619884 -238.611316)
			(xy 341.649449 -238.65066) (xy 341.67232 -238.694237) (xy 341.687904 -238.740918) (xy 341.695799 -238.789495)
			(xy 341.696294 -238.814102) (xy 342.014805 -238.814102) (xy 342.0189 -238.763374) (xy 342.031079 -238.71396)
			(xy 342.051027 -238.66714) (xy 342.078228 -238.624126) (xy 342.111976 -238.586032) (xy 342.151398 -238.553845)
			(xy 342.195472 -238.528399) (xy 342.243058 -238.510352) (xy 342.292922 -238.500172) (xy 342.343774 -238.498123)
			(xy 342.394295 -238.504257) (xy 342.443179 -238.518417) (xy 342.489158 -238.540234) (xy 342.531042 -238.569144)
			(xy 342.567746 -238.604399) (xy 342.598319 -238.645085) (xy 342.62197 -238.690148) (xy 342.638086 -238.738422)
			(xy 342.64625 -238.788656) (xy 342.646762 -238.814102) (xy 342.954859 -238.814102) (xy 342.958954 -238.763374)
			(xy 342.971133 -238.71396) (xy 342.991081 -238.66714) (xy 343.018282 -238.624126) (xy 343.05203 -238.586032)
			(xy 343.091452 -238.553845) (xy 343.135526 -238.528399) (xy 343.183112 -238.510352) (xy 343.232976 -238.500172)
			(xy 343.283828 -238.498123) (xy 343.334349 -238.504257) (xy 343.383233 -238.518417) (xy 343.429212 -238.540234)
			(xy 343.471096 -238.569144) (xy 343.5078 -238.604399) (xy 343.538373 -238.645085) (xy 343.562024 -238.690148)
			(xy 343.57814 -238.738422) (xy 343.586304 -238.788656) (xy 343.586816 -238.814102) (xy 343.586304 -238.839548)
			(xy 343.57814 -238.889782) (xy 343.562024 -238.938056) (xy 343.538373 -238.983119) (xy 343.5078 -239.023805)
			(xy 343.471096 -239.05906) (xy 343.429212 -239.08797) (xy 343.383233 -239.109787) (xy 343.334349 -239.123947)
			(xy 343.283828 -239.130081) (xy 343.232976 -239.128032) (xy 343.183112 -239.117852) (xy 343.135526 -239.099805)
			(xy 343.091452 -239.074359) (xy 343.05203 -239.042172) (xy 343.018282 -239.004078) (xy 342.991081 -238.961064)
			(xy 342.971133 -238.914244) (xy 342.958954 -238.86483) (xy 342.954859 -238.814102) (xy 342.646762 -238.814102)
			(xy 342.64625 -238.839548) (xy 342.638086 -238.889782) (xy 342.62197 -238.938056) (xy 342.598319 -238.983119)
			(xy 342.567746 -239.023805) (xy 342.531042 -239.05906) (xy 342.489158 -239.08797) (xy 342.443179 -239.109787)
			(xy 342.394295 -239.123947) (xy 342.343774 -239.130081) (xy 342.292922 -239.128032) (xy 342.243058 -239.117852)
			(xy 342.195472 -239.099805) (xy 342.151398 -239.074359) (xy 342.111976 -239.042172) (xy 342.078228 -239.004078)
			(xy 342.051027 -238.961064) (xy 342.031079 -238.914244) (xy 342.0189 -238.86483) (xy 342.014805 -238.814102)
			(xy 341.696294 -238.814102) (xy 341.695799 -238.838709) (xy 341.687904 -238.887286) (xy 341.67232 -238.933967)
			(xy 341.649449 -238.977544) (xy 341.619884 -239.016888) (xy 341.584391 -239.05098) (xy 341.543888 -239.078936)
			(xy 341.499426 -239.100034) (xy 341.452155 -239.113726) (xy 341.4033 -239.119658) (xy 341.354125 -239.117677)
			(xy 341.305906 -239.107833) (xy 341.25989 -239.090381) (xy 341.217269 -239.065774) (xy 341.179148 -239.034649)
			(xy 341.146513 -238.997812) (xy 341.12021 -238.956216) (xy 341.100919 -238.91094) (xy 341.089142 -238.863156)
			(xy 341.085182 -238.814102) (xy 340.766908 -238.814102) (xy 340.766396 -238.839548) (xy 340.758232 -238.889782)
			(xy 340.742116 -238.938056) (xy 340.718465 -238.983119) (xy 340.687892 -239.023805) (xy 340.651188 -239.05906)
			(xy 340.609304 -239.08797) (xy 340.563325 -239.109787) (xy 340.514441 -239.123947) (xy 340.46392 -239.130081)
			(xy 340.413068 -239.128032) (xy 340.363204 -239.117852) (xy 340.315618 -239.099805) (xy 340.271544 -239.074359)
			(xy 340.232122 -239.042172) (xy 340.198374 -239.004078) (xy 340.171173 -238.961064) (xy 340.151225 -238.914244)
			(xy 340.139046 -238.86483) (xy 340.134951 -238.814102) (xy 339.81644 -238.814102) (xy 339.815945 -238.838709)
			(xy 339.80805 -238.887286) (xy 339.792466 -238.933967) (xy 339.769595 -238.977544) (xy 339.74003 -239.016888)
			(xy 339.704537 -239.05098) (xy 339.664034 -239.078936) (xy 339.619572 -239.100034) (xy 339.572301 -239.113726)
			(xy 339.523446 -239.119658) (xy 339.474271 -239.117677) (xy 339.426052 -239.107833) (xy 339.380036 -239.090381)
			(xy 339.337415 -239.065774) (xy 339.299294 -239.034649) (xy 339.266659 -238.997812) (xy 339.240356 -238.956216)
			(xy 339.221065 -238.91094) (xy 339.209288 -238.863156) (xy 339.205328 -238.814102) (xy 338.8868 -238.814102)
			(xy 338.886288 -238.839548) (xy 338.878124 -238.889782) (xy 338.862008 -238.938056) (xy 338.838357 -238.983119)
			(xy 338.807784 -239.023805) (xy 338.77108 -239.05906) (xy 338.729196 -239.08797) (xy 338.683217 -239.109787)
			(xy 338.634333 -239.123947) (xy 338.583812 -239.130081) (xy 338.53296 -239.128032) (xy 338.483096 -239.117852)
			(xy 338.43551 -239.099805) (xy 338.391436 -239.074359) (xy 338.352014 -239.042172) (xy 338.318266 -239.004078)
			(xy 338.291065 -238.961064) (xy 338.271117 -238.914244) (xy 338.258938 -238.86483) (xy 338.254843 -238.814102)
			(xy 338.06638 -238.814102) (xy 338.06638 -239.247934) (xy 338.066805 -239.257634) (xy 338.073979 -239.27566)
			(xy 338.08035 -239.282986) (xy 338.095082 -239.29848) (xy 338.098321 -239.301713) (xy 338.105729 -239.307085)
			(xy 338.109814 -239.309148) (xy 338.132674 -239.32007) (xy 338.140802 -239.32134) (xy 338.164997 -239.324976)
			(xy 338.211885 -239.338946) (xy 338.255944 -239.360214) (xy 338.296048 -239.388236) (xy 338.331171 -239.422295)
			(xy 338.360412 -239.46152) (xy 338.383024 -239.504905) (xy 338.398428 -239.551341) (xy 338.40623 -239.599639)
			(xy 338.40623 -239.624108) (xy 338.724743 -239.624108) (xy 338.728838 -239.57338) (xy 338.741017 -239.523966)
			(xy 338.760965 -239.477146) (xy 338.788166 -239.434132) (xy 338.821914 -239.396038) (xy 338.861336 -239.363851)
			(xy 338.90541 -239.338405) (xy 338.952996 -239.320358) (xy 339.00286 -239.310178) (xy 339.053712 -239.308129)
			(xy 339.104233 -239.314263) (xy 339.153117 -239.328423) (xy 339.199096 -239.35024) (xy 339.24098 -239.37915)
			(xy 339.277684 -239.414405) (xy 339.308257 -239.455091) (xy 339.331908 -239.500154) (xy 339.348024 -239.548428)
			(xy 339.356188 -239.598662) (xy 339.3567 -239.624108) (xy 339.664797 -239.624108) (xy 339.668892 -239.57338)
			(xy 339.681071 -239.523966) (xy 339.701019 -239.477146) (xy 339.72822 -239.434132) (xy 339.761968 -239.396038)
			(xy 339.80139 -239.363851) (xy 339.845464 -239.338405) (xy 339.89305 -239.320358) (xy 339.942914 -239.310178)
			(xy 339.993766 -239.308129) (xy 340.044287 -239.314263) (xy 340.093171 -239.328423) (xy 340.13915 -239.35024)
			(xy 340.181034 -239.37915) (xy 340.217738 -239.414405) (xy 340.248311 -239.455091) (xy 340.271962 -239.500154)
			(xy 340.288078 -239.548428) (xy 340.296242 -239.598662) (xy 340.296754 -239.624108) (xy 340.615282 -239.624108)
			(xy 340.619242 -239.575054) (xy 340.631019 -239.52727) (xy 340.65031 -239.481994) (xy 340.676613 -239.440398)
			(xy 340.709248 -239.403561) (xy 340.747369 -239.372436) (xy 340.78999 -239.347829) (xy 340.836006 -239.330377)
			(xy 340.884225 -239.320533) (xy 340.9334 -239.318552) (xy 340.982255 -239.324484) (xy 341.029526 -239.338176)
			(xy 341.073988 -239.359274) (xy 341.114491 -239.38723) (xy 341.149984 -239.421322) (xy 341.179549 -239.460666)
			(xy 341.20242 -239.504243) (xy 341.218004 -239.550924) (xy 341.225899 -239.599501) (xy 341.226394 -239.624108)
			(xy 341.544905 -239.624108) (xy 341.549 -239.57338) (xy 341.561179 -239.523966) (xy 341.581127 -239.477146)
			(xy 341.608328 -239.434132) (xy 341.642076 -239.396038) (xy 341.681498 -239.363851) (xy 341.725572 -239.338405)
			(xy 341.773158 -239.320358) (xy 341.823022 -239.310178) (xy 341.873874 -239.308129) (xy 341.924395 -239.314263)
			(xy 341.973279 -239.328423) (xy 342.019258 -239.35024) (xy 342.061142 -239.37915) (xy 342.097846 -239.414405)
			(xy 342.128419 -239.455091) (xy 342.15207 -239.500154) (xy 342.168186 -239.548428) (xy 342.17635 -239.598662)
			(xy 342.176862 -239.624108) (xy 342.49539 -239.624108) (xy 342.49935 -239.575054) (xy 342.511127 -239.52727)
			(xy 342.530418 -239.481994) (xy 342.556721 -239.440398) (xy 342.589356 -239.403561) (xy 342.627477 -239.372436)
			(xy 342.670098 -239.347829) (xy 342.716114 -239.330377) (xy 342.764333 -239.320533) (xy 342.813508 -239.318552)
			(xy 342.862363 -239.324484) (xy 342.909634 -239.338176) (xy 342.954096 -239.359274) (xy 342.994599 -239.38723)
			(xy 343.030092 -239.421322) (xy 343.059657 -239.460666) (xy 343.082528 -239.504243) (xy 343.098112 -239.550924)
			(xy 343.106007 -239.599501) (xy 343.106502 -239.624108) (xy 343.106007 -239.648715) (xy 343.098112 -239.697292)
			(xy 343.082528 -239.743973) (xy 343.059657 -239.78755) (xy 343.030092 -239.826894) (xy 342.994599 -239.860986)
			(xy 342.954096 -239.888942) (xy 342.909634 -239.91004) (xy 342.862363 -239.923732) (xy 342.813508 -239.929664)
			(xy 342.764333 -239.927683) (xy 342.716114 -239.917839) (xy 342.670098 -239.900387) (xy 342.627477 -239.87578)
			(xy 342.589356 -239.844655) (xy 342.556721 -239.807818) (xy 342.530418 -239.766222) (xy 342.511127 -239.720946)
			(xy 342.49935 -239.673162) (xy 342.49539 -239.624108) (xy 342.176862 -239.624108) (xy 342.17635 -239.649554)
			(xy 342.168186 -239.699788) (xy 342.15207 -239.748062) (xy 342.128419 -239.793125) (xy 342.097846 -239.833811)
			(xy 342.061142 -239.869066) (xy 342.019258 -239.897976) (xy 341.973279 -239.919793) (xy 341.924395 -239.933953)
			(xy 341.873874 -239.940087) (xy 341.823022 -239.938038) (xy 341.773158 -239.927858) (xy 341.725572 -239.909811)
			(xy 341.681498 -239.884365) (xy 341.642076 -239.852178) (xy 341.608328 -239.814084) (xy 341.581127 -239.77107)
			(xy 341.561179 -239.72425) (xy 341.549 -239.674836) (xy 341.544905 -239.624108) (xy 341.226394 -239.624108)
			(xy 341.225899 -239.648715) (xy 341.218004 -239.697292) (xy 341.20242 -239.743973) (xy 341.179549 -239.78755)
			(xy 341.149984 -239.826894) (xy 341.114491 -239.860986) (xy 341.073988 -239.888942) (xy 341.029526 -239.91004)
			(xy 340.982255 -239.923732) (xy 340.9334 -239.929664) (xy 340.884225 -239.927683) (xy 340.836006 -239.917839)
			(xy 340.78999 -239.900387) (xy 340.747369 -239.87578) (xy 340.709248 -239.844655) (xy 340.676613 -239.807818)
			(xy 340.65031 -239.766222) (xy 340.631019 -239.720946) (xy 340.619242 -239.673162) (xy 340.615282 -239.624108)
			(xy 340.296754 -239.624108) (xy 340.296242 -239.649554) (xy 340.288078 -239.699788) (xy 340.271962 -239.748062)
			(xy 340.248311 -239.793125) (xy 340.217738 -239.833811) (xy 340.181034 -239.869066) (xy 340.13915 -239.897976)
			(xy 340.093171 -239.919793) (xy 340.044287 -239.933953) (xy 339.993766 -239.940087) (xy 339.942914 -239.938038)
			(xy 339.89305 -239.927858) (xy 339.845464 -239.909811) (xy 339.80139 -239.884365) (xy 339.761968 -239.852178)
			(xy 339.72822 -239.814084) (xy 339.701019 -239.77107) (xy 339.681071 -239.72425) (xy 339.668892 -239.674836)
			(xy 339.664797 -239.624108) (xy 339.3567 -239.624108) (xy 339.356188 -239.649554) (xy 339.348024 -239.699788)
			(xy 339.331908 -239.748062) (xy 339.308257 -239.793125) (xy 339.277684 -239.833811) (xy 339.24098 -239.869066)
			(xy 339.199096 -239.897976) (xy 339.153117 -239.919793) (xy 339.104233 -239.933953) (xy 339.053712 -239.940087)
			(xy 339.00286 -239.938038) (xy 338.952996 -239.927858) (xy 338.90541 -239.909811) (xy 338.861336 -239.884365)
			(xy 338.821914 -239.852178) (xy 338.788166 -239.814084) (xy 338.760965 -239.77107) (xy 338.741017 -239.72425)
			(xy 338.728838 -239.674836) (xy 338.724743 -239.624108) (xy 338.40623 -239.624108) (xy 338.40623 -239.648563)
			(xy 338.398428 -239.696861) (xy 338.383023 -239.743297) (xy 338.360411 -239.786682) (xy 338.331169 -239.825906)
			(xy 338.296047 -239.859965) (xy 338.255942 -239.887987) (xy 338.211883 -239.909255) (xy 338.164995 -239.923224)
			(xy 338.140802 -239.926876) (xy 338.132674 -239.928146) (xy 338.109814 -239.939068) (xy 338.105728 -239.941129)
			(xy 338.098317 -239.946498) (xy 338.095082 -239.949736) (xy 338.08035 -239.96523) (xy 338.073968 -239.972551)
			(xy 338.066786 -239.990578) (xy 338.06638 -240.000282) (xy 338.06638 -240.434114) (xy 338.254843 -240.434114)
			(xy 338.258938 -240.383386) (xy 338.271117 -240.333972) (xy 338.291065 -240.287152) (xy 338.318266 -240.244138)
			(xy 338.352014 -240.206044) (xy 338.391436 -240.173857) (xy 338.43551 -240.148411) (xy 338.483096 -240.130364)
			(xy 338.53296 -240.120184) (xy 338.583812 -240.118135) (xy 338.634333 -240.124269) (xy 338.683217 -240.138429)
			(xy 338.729196 -240.160246) (xy 338.77108 -240.189156) (xy 338.807784 -240.224411) (xy 338.838357 -240.265097)
			(xy 338.862008 -240.31016) (xy 338.878124 -240.358434) (xy 338.886288 -240.408668) (xy 338.8868 -240.434114)
			(xy 339.205328 -240.434114) (xy 339.209288 -240.38506) (xy 339.221065 -240.337276) (xy 339.240356 -240.292)
			(xy 339.266659 -240.250404) (xy 339.299294 -240.213567) (xy 339.337415 -240.182442) (xy 339.380036 -240.157835)
			(xy 339.426052 -240.140383) (xy 339.474271 -240.130539) (xy 339.523446 -240.128558) (xy 339.572301 -240.13449)
			(xy 339.619572 -240.148182) (xy 339.664034 -240.16928) (xy 339.704537 -240.197236) (xy 339.74003 -240.231328)
			(xy 339.769595 -240.270672) (xy 339.792466 -240.314249) (xy 339.80805 -240.36093) (xy 339.815945 -240.409507)
			(xy 339.81644 -240.434114) (xy 340.134951 -240.434114) (xy 340.139046 -240.383386) (xy 340.151225 -240.333972)
			(xy 340.171173 -240.287152) (xy 340.198374 -240.244138) (xy 340.232122 -240.206044) (xy 340.271544 -240.173857)
			(xy 340.315618 -240.148411) (xy 340.363204 -240.130364) (xy 340.413068 -240.120184) (xy 340.46392 -240.118135)
			(xy 340.514441 -240.124269) (xy 340.563325 -240.138429) (xy 340.609304 -240.160246) (xy 340.651188 -240.189156)
			(xy 340.687892 -240.224411) (xy 340.718465 -240.265097) (xy 340.742116 -240.31016) (xy 340.758232 -240.358434)
			(xy 340.766396 -240.408668) (xy 340.766908 -240.434114) (xy 341.085182 -240.434114) (xy 341.089142 -240.38506)
			(xy 341.100919 -240.337276) (xy 341.12021 -240.292) (xy 341.146513 -240.250404) (xy 341.179148 -240.213567)
			(xy 341.217269 -240.182442) (xy 341.25989 -240.157835) (xy 341.305906 -240.140383) (xy 341.354125 -240.130539)
			(xy 341.4033 -240.128558) (xy 341.452155 -240.13449) (xy 341.499426 -240.148182) (xy 341.543888 -240.16928)
			(xy 341.584391 -240.197236) (xy 341.619884 -240.231328) (xy 341.649449 -240.270672) (xy 341.67232 -240.314249)
			(xy 341.687904 -240.36093) (xy 341.695799 -240.409507) (xy 341.696294 -240.434114) (xy 342.014805 -240.434114)
			(xy 342.0189 -240.383386) (xy 342.031079 -240.333972) (xy 342.051027 -240.287152) (xy 342.078228 -240.244138)
			(xy 342.111976 -240.206044) (xy 342.151398 -240.173857) (xy 342.195472 -240.148411) (xy 342.243058 -240.130364)
			(xy 342.292922 -240.120184) (xy 342.343774 -240.118135) (xy 342.394295 -240.124269) (xy 342.443179 -240.138429)
			(xy 342.489158 -240.160246) (xy 342.531042 -240.189156) (xy 342.567746 -240.224411) (xy 342.598319 -240.265097)
			(xy 342.62197 -240.31016) (xy 342.638086 -240.358434) (xy 342.64625 -240.408668) (xy 342.646762 -240.434114)
			(xy 342.954859 -240.434114) (xy 342.958954 -240.383386) (xy 342.971133 -240.333972) (xy 342.991081 -240.287152)
			(xy 343.018282 -240.244138) (xy 343.05203 -240.206044) (xy 343.091452 -240.173857) (xy 343.135526 -240.148411)
			(xy 343.183112 -240.130364) (xy 343.232976 -240.120184) (xy 343.283828 -240.118135) (xy 343.334349 -240.124269)
			(xy 343.383233 -240.138429) (xy 343.429212 -240.160246) (xy 343.471096 -240.189156) (xy 343.5078 -240.224411)
			(xy 343.538373 -240.265097) (xy 343.562024 -240.31016) (xy 343.57814 -240.358434) (xy 343.586304 -240.408668)
			(xy 343.586816 -240.434114) (xy 343.586304 -240.45956) (xy 343.57814 -240.509794) (xy 343.562024 -240.558068)
			(xy 343.538373 -240.603131) (xy 343.5078 -240.643817) (xy 343.471096 -240.679072) (xy 343.429212 -240.707982)
			(xy 343.383233 -240.729799) (xy 343.334349 -240.743959) (xy 343.283828 -240.750093) (xy 343.232976 -240.748044)
			(xy 343.183112 -240.737864) (xy 343.135526 -240.719817) (xy 343.091452 -240.694371) (xy 343.05203 -240.662184)
			(xy 343.018282 -240.62409) (xy 342.991081 -240.581076) (xy 342.971133 -240.534256) (xy 342.958954 -240.484842)
			(xy 342.954859 -240.434114) (xy 342.646762 -240.434114) (xy 342.64625 -240.45956) (xy 342.638086 -240.509794)
			(xy 342.62197 -240.558068) (xy 342.598319 -240.603131) (xy 342.567746 -240.643817) (xy 342.531042 -240.679072)
			(xy 342.489158 -240.707982) (xy 342.443179 -240.729799) (xy 342.394295 -240.743959) (xy 342.343774 -240.750093)
			(xy 342.292922 -240.748044) (xy 342.243058 -240.737864) (xy 342.195472 -240.719817) (xy 342.151398 -240.694371)
			(xy 342.111976 -240.662184) (xy 342.078228 -240.62409) (xy 342.051027 -240.581076) (xy 342.031079 -240.534256)
			(xy 342.0189 -240.484842) (xy 342.014805 -240.434114) (xy 341.696294 -240.434114) (xy 341.695799 -240.458721)
			(xy 341.687904 -240.507298) (xy 341.67232 -240.553979) (xy 341.649449 -240.597556) (xy 341.619884 -240.6369)
			(xy 341.584391 -240.670992) (xy 341.543888 -240.698948) (xy 341.499426 -240.720046) (xy 341.452155 -240.733738)
			(xy 341.4033 -240.73967) (xy 341.354125 -240.737689) (xy 341.305906 -240.727845) (xy 341.25989 -240.710393)
			(xy 341.217269 -240.685786) (xy 341.179148 -240.654661) (xy 341.146513 -240.617824) (xy 341.12021 -240.576228)
			(xy 341.100919 -240.530952) (xy 341.089142 -240.483168) (xy 341.085182 -240.434114) (xy 340.766908 -240.434114)
			(xy 340.766396 -240.45956) (xy 340.758232 -240.509794) (xy 340.742116 -240.558068) (xy 340.718465 -240.603131)
			(xy 340.687892 -240.643817) (xy 340.651188 -240.679072) (xy 340.609304 -240.707982) (xy 340.563325 -240.729799)
			(xy 340.514441 -240.743959) (xy 340.46392 -240.750093) (xy 340.413068 -240.748044) (xy 340.363204 -240.737864)
			(xy 340.315618 -240.719817) (xy 340.271544 -240.694371) (xy 340.232122 -240.662184) (xy 340.198374 -240.62409)
			(xy 340.171173 -240.581076) (xy 340.151225 -240.534256) (xy 340.139046 -240.484842) (xy 340.134951 -240.434114)
			(xy 339.81644 -240.434114) (xy 339.815945 -240.458721) (xy 339.80805 -240.507298) (xy 339.792466 -240.553979)
			(xy 339.769595 -240.597556) (xy 339.74003 -240.6369) (xy 339.704537 -240.670992) (xy 339.664034 -240.698948)
			(xy 339.619572 -240.720046) (xy 339.572301 -240.733738) (xy 339.523446 -240.73967) (xy 339.474271 -240.737689)
			(xy 339.426052 -240.727845) (xy 339.380036 -240.710393) (xy 339.337415 -240.685786) (xy 339.299294 -240.654661)
			(xy 339.266659 -240.617824) (xy 339.240356 -240.576228) (xy 339.221065 -240.530952) (xy 339.209288 -240.483168)
			(xy 339.205328 -240.434114) (xy 338.8868 -240.434114) (xy 338.886288 -240.45956) (xy 338.878124 -240.509794)
			(xy 338.862008 -240.558068) (xy 338.838357 -240.603131) (xy 338.807784 -240.643817) (xy 338.77108 -240.679072)
			(xy 338.729196 -240.707982) (xy 338.683217 -240.729799) (xy 338.634333 -240.743959) (xy 338.583812 -240.750093)
			(xy 338.53296 -240.748044) (xy 338.483096 -240.737864) (xy 338.43551 -240.719817) (xy 338.391436 -240.694371)
			(xy 338.352014 -240.662184) (xy 338.318266 -240.62409) (xy 338.291065 -240.581076) (xy 338.271117 -240.534256)
			(xy 338.258938 -240.484842) (xy 338.254843 -240.434114) (xy 338.06638 -240.434114) (xy 338.06638 -240.867946)
			(xy 338.066807 -240.877645) (xy 338.073984 -240.895668) (xy 338.08035 -240.902998) (xy 338.095082 -240.918492)
			(xy 338.098322 -240.921724) (xy 338.10573 -240.927095) (xy 338.109814 -240.92916) (xy 338.132674 -240.940082)
			(xy 338.140802 -240.941352) (xy 338.164996 -240.944988) (xy 338.211882 -240.958958) (xy 338.25594 -240.980225)
			(xy 338.296042 -241.008247) (xy 338.331163 -241.042304) (xy 338.360403 -241.081527) (xy 338.383014 -241.124911)
			(xy 338.398417 -241.171345) (xy 338.406218 -241.219641) (xy 338.406218 -241.24412) (xy 338.724743 -241.24412)
			(xy 338.728838 -241.193392) (xy 338.741017 -241.143978) (xy 338.760965 -241.097158) (xy 338.788166 -241.054144)
			(xy 338.821914 -241.01605) (xy 338.861336 -240.983863) (xy 338.90541 -240.958417) (xy 338.952996 -240.94037)
			(xy 339.00286 -240.93019) (xy 339.053712 -240.928141) (xy 339.104233 -240.934275) (xy 339.153117 -240.948435)
			(xy 339.199096 -240.970252) (xy 339.24098 -240.999162) (xy 339.277684 -241.034417) (xy 339.308257 -241.075103)
			(xy 339.331908 -241.120166) (xy 339.348024 -241.16844) (xy 339.356188 -241.218674) (xy 339.3567 -241.24412)
			(xy 339.664797 -241.24412) (xy 339.668892 -241.193392) (xy 339.681071 -241.143978) (xy 339.701019 -241.097158)
			(xy 339.72822 -241.054144) (xy 339.761968 -241.01605) (xy 339.80139 -240.983863) (xy 339.845464 -240.958417)
			(xy 339.89305 -240.94037) (xy 339.942914 -240.93019) (xy 339.993766 -240.928141) (xy 340.044287 -240.934275)
			(xy 340.093171 -240.948435) (xy 340.13915 -240.970252) (xy 340.181034 -240.999162) (xy 340.217738 -241.034417)
			(xy 340.248311 -241.075103) (xy 340.271962 -241.120166) (xy 340.288078 -241.16844) (xy 340.296242 -241.218674)
			(xy 340.296754 -241.24412) (xy 340.615282 -241.24412) (xy 340.619242 -241.195066) (xy 340.631019 -241.147282)
			(xy 340.65031 -241.102006) (xy 340.676613 -241.06041) (xy 340.709248 -241.023573) (xy 340.747369 -240.992448)
			(xy 340.78999 -240.967841) (xy 340.836006 -240.950389) (xy 340.884225 -240.940545) (xy 340.9334 -240.938564)
			(xy 340.982255 -240.944496) (xy 341.029526 -240.958188) (xy 341.073988 -240.979286) (xy 341.114491 -241.007242)
			(xy 341.149984 -241.041334) (xy 341.179549 -241.080678) (xy 341.20242 -241.124255) (xy 341.218004 -241.170936)
			(xy 341.225899 -241.219513) (xy 341.226394 -241.24412) (xy 341.544905 -241.24412) (xy 341.549 -241.193392)
			(xy 341.561179 -241.143978) (xy 341.581127 -241.097158) (xy 341.608328 -241.054144) (xy 341.642076 -241.01605)
			(xy 341.681498 -240.983863) (xy 341.725572 -240.958417) (xy 341.773158 -240.94037) (xy 341.823022 -240.93019)
			(xy 341.873874 -240.928141) (xy 341.924395 -240.934275) (xy 341.973279 -240.948435) (xy 342.019258 -240.970252)
			(xy 342.061142 -240.999162) (xy 342.097846 -241.034417) (xy 342.128419 -241.075103) (xy 342.15207 -241.120166)
			(xy 342.168186 -241.16844) (xy 342.17635 -241.218674) (xy 342.176862 -241.24412) (xy 342.49539 -241.24412)
			(xy 342.49935 -241.195066) (xy 342.511127 -241.147282) (xy 342.530418 -241.102006) (xy 342.556721 -241.06041)
			(xy 342.589356 -241.023573) (xy 342.627477 -240.992448) (xy 342.670098 -240.967841) (xy 342.716114 -240.950389)
			(xy 342.764333 -240.940545) (xy 342.813508 -240.938564) (xy 342.862363 -240.944496) (xy 342.909634 -240.958188)
			(xy 342.954096 -240.979286) (xy 342.994599 -241.007242) (xy 343.030092 -241.041334) (xy 343.059657 -241.080678)
			(xy 343.082528 -241.124255) (xy 343.098112 -241.170936) (xy 343.106007 -241.219513) (xy 343.106502 -241.24412)
			(xy 343.106007 -241.268727) (xy 343.098112 -241.317304) (xy 343.082528 -241.363985) (xy 343.059657 -241.407562)
			(xy 343.030092 -241.446906) (xy 342.994599 -241.480998) (xy 342.954096 -241.508954) (xy 342.909634 -241.530052)
			(xy 342.862363 -241.543744) (xy 342.813508 -241.549676) (xy 342.764333 -241.547695) (xy 342.716114 -241.537851)
			(xy 342.670098 -241.520399) (xy 342.627477 -241.495792) (xy 342.589356 -241.464667) (xy 342.556721 -241.42783)
			(xy 342.530418 -241.386234) (xy 342.511127 -241.340958) (xy 342.49935 -241.293174) (xy 342.49539 -241.24412)
			(xy 342.176862 -241.24412) (xy 342.17635 -241.269566) (xy 342.168186 -241.3198) (xy 342.15207 -241.368074)
			(xy 342.128419 -241.413137) (xy 342.097846 -241.453823) (xy 342.061142 -241.489078) (xy 342.019258 -241.517988)
			(xy 341.973279 -241.539805) (xy 341.924395 -241.553965) (xy 341.873874 -241.560099) (xy 341.823022 -241.55805)
			(xy 341.773158 -241.54787) (xy 341.725572 -241.529823) (xy 341.681498 -241.504377) (xy 341.642076 -241.47219)
			(xy 341.608328 -241.434096) (xy 341.581127 -241.391082) (xy 341.561179 -241.344262) (xy 341.549 -241.294848)
			(xy 341.544905 -241.24412) (xy 341.226394 -241.24412) (xy 341.225899 -241.268727) (xy 341.218004 -241.317304)
			(xy 341.20242 -241.363985) (xy 341.179549 -241.407562) (xy 341.149984 -241.446906) (xy 341.114491 -241.480998)
			(xy 341.073988 -241.508954) (xy 341.029526 -241.530052) (xy 340.982255 -241.543744) (xy 340.9334 -241.549676)
			(xy 340.884225 -241.547695) (xy 340.836006 -241.537851) (xy 340.78999 -241.520399) (xy 340.747369 -241.495792)
			(xy 340.709248 -241.464667) (xy 340.676613 -241.42783) (xy 340.65031 -241.386234) (xy 340.631019 -241.340958)
			(xy 340.619242 -241.293174) (xy 340.615282 -241.24412) (xy 340.296754 -241.24412) (xy 340.296242 -241.269566)
			(xy 340.288078 -241.3198) (xy 340.271962 -241.368074) (xy 340.248311 -241.413137) (xy 340.217738 -241.453823)
			(xy 340.181034 -241.489078) (xy 340.13915 -241.517988) (xy 340.093171 -241.539805) (xy 340.044287 -241.553965)
			(xy 339.993766 -241.560099) (xy 339.942914 -241.55805) (xy 339.89305 -241.54787) (xy 339.845464 -241.529823)
			(xy 339.80139 -241.504377) (xy 339.761968 -241.47219) (xy 339.72822 -241.434096) (xy 339.701019 -241.391082)
			(xy 339.681071 -241.344262) (xy 339.668892 -241.294848) (xy 339.664797 -241.24412) (xy 339.3567 -241.24412)
			(xy 339.356188 -241.269566) (xy 339.348024 -241.3198) (xy 339.331908 -241.368074) (xy 339.308257 -241.413137)
			(xy 339.277684 -241.453823) (xy 339.24098 -241.489078) (xy 339.199096 -241.517988) (xy 339.153117 -241.539805)
			(xy 339.104233 -241.553965) (xy 339.053712 -241.560099) (xy 339.00286 -241.55805) (xy 338.952996 -241.54787)
			(xy 338.90541 -241.529823) (xy 338.861336 -241.504377) (xy 338.821914 -241.47219) (xy 338.788166 -241.434096)
			(xy 338.760965 -241.391082) (xy 338.741017 -241.344262) (xy 338.728838 -241.294848) (xy 338.724743 -241.24412)
			(xy 338.406218 -241.24412) (xy 338.406218 -241.268564) (xy 338.398416 -241.31686) (xy 338.383012 -241.363294)
			(xy 338.3604 -241.406677) (xy 338.331159 -241.445899) (xy 338.296038 -241.479957) (xy 338.255935 -241.507977)
			(xy 338.211877 -241.529244) (xy 338.164991 -241.543213) (xy 338.140802 -241.546888) (xy 338.132674 -241.548158)
			(xy 338.109814 -241.55908) (xy 338.105728 -241.561142) (xy 338.098318 -241.566512) (xy 338.095082 -241.569748)
			(xy 338.08035 -241.585242) (xy 338.07397 -241.592564) (xy 338.066793 -241.610591) (xy 338.06638 -241.620294)
			(xy 338.06638 -242.054126) (xy 338.254843 -242.054126) (xy 338.258938 -242.003398) (xy 338.271117 -241.953984)
			(xy 338.291065 -241.907164) (xy 338.318266 -241.86415) (xy 338.352014 -241.826056) (xy 338.391436 -241.793869)
			(xy 338.43551 -241.768423) (xy 338.483096 -241.750376) (xy 338.53296 -241.740196) (xy 338.583812 -241.738147)
			(xy 338.634333 -241.744281) (xy 338.683217 -241.758441) (xy 338.729196 -241.780258) (xy 338.77108 -241.809168)
			(xy 338.807784 -241.844423) (xy 338.838357 -241.885109) (xy 338.862008 -241.930172) (xy 338.878124 -241.978446)
			(xy 338.886288 -242.02868) (xy 338.8868 -242.054126) (xy 339.205328 -242.054126) (xy 339.209288 -242.005072)
			(xy 339.221065 -241.957288) (xy 339.240356 -241.912012) (xy 339.266659 -241.870416) (xy 339.299294 -241.833579)
			(xy 339.337415 -241.802454) (xy 339.380036 -241.777847) (xy 339.426052 -241.760395) (xy 339.474271 -241.750551)
			(xy 339.523446 -241.74857) (xy 339.572301 -241.754502) (xy 339.619572 -241.768194) (xy 339.664034 -241.789292)
			(xy 339.704537 -241.817248) (xy 339.74003 -241.85134) (xy 339.769595 -241.890684) (xy 339.792466 -241.934261)
			(xy 339.80805 -241.980942) (xy 339.815945 -242.029519) (xy 339.81644 -242.054126) (xy 340.134951 -242.054126)
			(xy 340.139046 -242.003398) (xy 340.151225 -241.953984) (xy 340.171173 -241.907164) (xy 340.198374 -241.86415)
			(xy 340.232122 -241.826056) (xy 340.271544 -241.793869) (xy 340.315618 -241.768423) (xy 340.363204 -241.750376)
			(xy 340.413068 -241.740196) (xy 340.46392 -241.738147) (xy 340.514441 -241.744281) (xy 340.563325 -241.758441)
			(xy 340.609304 -241.780258) (xy 340.651188 -241.809168) (xy 340.687892 -241.844423) (xy 340.718465 -241.885109)
			(xy 340.742116 -241.930172) (xy 340.758232 -241.978446) (xy 340.766396 -242.02868) (xy 340.766908 -242.054126)
			(xy 341.085182 -242.054126) (xy 341.089142 -242.005072) (xy 341.100919 -241.957288) (xy 341.12021 -241.912012)
			(xy 341.146513 -241.870416) (xy 341.179148 -241.833579) (xy 341.217269 -241.802454) (xy 341.25989 -241.777847)
			(xy 341.305906 -241.760395) (xy 341.354125 -241.750551) (xy 341.4033 -241.74857) (xy 341.452155 -241.754502)
			(xy 341.499426 -241.768194) (xy 341.543888 -241.789292) (xy 341.584391 -241.817248) (xy 341.619884 -241.85134)
			(xy 341.649449 -241.890684) (xy 341.67232 -241.934261) (xy 341.687904 -241.980942) (xy 341.695799 -242.029519)
			(xy 341.696294 -242.054126) (xy 342.014805 -242.054126) (xy 342.0189 -242.003398) (xy 342.031079 -241.953984)
			(xy 342.051027 -241.907164) (xy 342.078228 -241.86415) (xy 342.111976 -241.826056) (xy 342.151398 -241.793869)
			(xy 342.195472 -241.768423) (xy 342.243058 -241.750376) (xy 342.292922 -241.740196) (xy 342.343774 -241.738147)
			(xy 342.394295 -241.744281) (xy 342.443179 -241.758441) (xy 342.489158 -241.780258) (xy 342.531042 -241.809168)
			(xy 342.567746 -241.844423) (xy 342.598319 -241.885109) (xy 342.62197 -241.930172) (xy 342.638086 -241.978446)
			(xy 342.64625 -242.02868) (xy 342.646762 -242.054126) (xy 342.954859 -242.054126) (xy 342.958954 -242.003398)
			(xy 342.971133 -241.953984) (xy 342.991081 -241.907164) (xy 343.018282 -241.86415) (xy 343.05203 -241.826056)
			(xy 343.091452 -241.793869) (xy 343.135526 -241.768423) (xy 343.183112 -241.750376) (xy 343.232976 -241.740196)
			(xy 343.283828 -241.738147) (xy 343.334349 -241.744281) (xy 343.383233 -241.758441) (xy 343.429212 -241.780258)
			(xy 343.471096 -241.809168) (xy 343.5078 -241.844423) (xy 343.538373 -241.885109) (xy 343.562024 -241.930172)
			(xy 343.57814 -241.978446) (xy 343.586304 -242.02868) (xy 343.586816 -242.054126) (xy 343.586304 -242.079572)
			(xy 343.57814 -242.129806) (xy 343.562024 -242.17808) (xy 343.538373 -242.223143) (xy 343.5078 -242.263829)
			(xy 343.471096 -242.299084) (xy 343.429212 -242.327994) (xy 343.383233 -242.349811) (xy 343.334349 -242.363971)
			(xy 343.283828 -242.370105) (xy 343.232976 -242.368056) (xy 343.183112 -242.357876) (xy 343.135526 -242.339829)
			(xy 343.091452 -242.314383) (xy 343.05203 -242.282196) (xy 343.018282 -242.244102) (xy 342.991081 -242.201088)
			(xy 342.971133 -242.154268) (xy 342.958954 -242.104854) (xy 342.954859 -242.054126) (xy 342.646762 -242.054126)
			(xy 342.64625 -242.079572) (xy 342.638086 -242.129806) (xy 342.62197 -242.17808) (xy 342.598319 -242.223143)
			(xy 342.567746 -242.263829) (xy 342.531042 -242.299084) (xy 342.489158 -242.327994) (xy 342.443179 -242.349811)
			(xy 342.394295 -242.363971) (xy 342.343774 -242.370105) (xy 342.292922 -242.368056) (xy 342.243058 -242.357876)
			(xy 342.195472 -242.339829) (xy 342.151398 -242.314383) (xy 342.111976 -242.282196) (xy 342.078228 -242.244102)
			(xy 342.051027 -242.201088) (xy 342.031079 -242.154268) (xy 342.0189 -242.104854) (xy 342.014805 -242.054126)
			(xy 341.696294 -242.054126) (xy 341.695799 -242.078733) (xy 341.687904 -242.12731) (xy 341.67232 -242.173991)
			(xy 341.649449 -242.217568) (xy 341.619884 -242.256912) (xy 341.584391 -242.291004) (xy 341.543888 -242.31896)
			(xy 341.499426 -242.340058) (xy 341.452155 -242.35375) (xy 341.4033 -242.359682) (xy 341.354125 -242.357701)
			(xy 341.305906 -242.347857) (xy 341.25989 -242.330405) (xy 341.217269 -242.305798) (xy 341.179148 -242.274673)
			(xy 341.146513 -242.237836) (xy 341.12021 -242.19624) (xy 341.100919 -242.150964) (xy 341.089142 -242.10318)
			(xy 341.085182 -242.054126) (xy 340.766908 -242.054126) (xy 340.766396 -242.079572) (xy 340.758232 -242.129806)
			(xy 340.742116 -242.17808) (xy 340.718465 -242.223143) (xy 340.687892 -242.263829) (xy 340.651188 -242.299084)
			(xy 340.609304 -242.327994) (xy 340.563325 -242.349811) (xy 340.514441 -242.363971) (xy 340.46392 -242.370105)
			(xy 340.413068 -242.368056) (xy 340.363204 -242.357876) (xy 340.315618 -242.339829) (xy 340.271544 -242.314383)
			(xy 340.232122 -242.282196) (xy 340.198374 -242.244102) (xy 340.171173 -242.201088) (xy 340.151225 -242.154268)
			(xy 340.139046 -242.104854) (xy 340.134951 -242.054126) (xy 339.81644 -242.054126) (xy 339.815945 -242.078733)
			(xy 339.80805 -242.12731) (xy 339.792466 -242.173991) (xy 339.769595 -242.217568) (xy 339.74003 -242.256912)
			(xy 339.704537 -242.291004) (xy 339.664034 -242.31896) (xy 339.619572 -242.340058) (xy 339.572301 -242.35375)
			(xy 339.523446 -242.359682) (xy 339.474271 -242.357701) (xy 339.426052 -242.347857) (xy 339.380036 -242.330405)
			(xy 339.337415 -242.305798) (xy 339.299294 -242.274673) (xy 339.266659 -242.237836) (xy 339.240356 -242.19624)
			(xy 339.221065 -242.150964) (xy 339.209288 -242.10318) (xy 339.205328 -242.054126) (xy 338.8868 -242.054126)
			(xy 338.886288 -242.079572) (xy 338.878124 -242.129806) (xy 338.862008 -242.17808) (xy 338.838357 -242.223143)
			(xy 338.807784 -242.263829) (xy 338.77108 -242.299084) (xy 338.729196 -242.327994) (xy 338.683217 -242.349811)
			(xy 338.634333 -242.363971) (xy 338.583812 -242.370105) (xy 338.53296 -242.368056) (xy 338.483096 -242.357876)
			(xy 338.43551 -242.339829) (xy 338.391436 -242.314383) (xy 338.352014 -242.282196) (xy 338.318266 -242.244102)
			(xy 338.291065 -242.201088) (xy 338.271117 -242.154268) (xy 338.258938 -242.104854) (xy 338.254843 -242.054126)
			(xy 338.06638 -242.054126) (xy 338.06638 -242.487958) (xy 338.066809 -242.497656) (xy 338.073989 -242.515677)
			(xy 338.08035 -242.52301) (xy 338.095082 -242.538504) (xy 338.098322 -242.541736) (xy 338.105731 -242.547105)
			(xy 338.109814 -242.549172) (xy 338.132674 -242.560094) (xy 338.140802 -242.561364) (xy 338.164995 -242.565)
			(xy 338.211879 -242.578969) (xy 338.255935 -242.600236) (xy 338.296036 -242.628257) (xy 338.331155 -242.662314)
			(xy 338.360393 -242.701535) (xy 338.383003 -242.744917) (xy 338.398406 -242.791349) (xy 338.406206 -242.839644)
			(xy 338.406206 -242.864132) (xy 338.724743 -242.864132) (xy 338.728838 -242.813404) (xy 338.741017 -242.76399)
			(xy 338.760965 -242.71717) (xy 338.788166 -242.674156) (xy 338.821914 -242.636062) (xy 338.861336 -242.603875)
			(xy 338.90541 -242.578429) (xy 338.952996 -242.560382) (xy 339.00286 -242.550202) (xy 339.053712 -242.548153)
			(xy 339.104233 -242.554287) (xy 339.153117 -242.568447) (xy 339.199096 -242.590264) (xy 339.24098 -242.619174)
			(xy 339.277684 -242.654429) (xy 339.308257 -242.695115) (xy 339.331908 -242.740178) (xy 339.348024 -242.788452)
			(xy 339.356188 -242.838686) (xy 339.3567 -242.864132) (xy 339.664797 -242.864132) (xy 339.668892 -242.813404)
			(xy 339.681071 -242.76399) (xy 339.701019 -242.71717) (xy 339.72822 -242.674156) (xy 339.761968 -242.636062)
			(xy 339.80139 -242.603875) (xy 339.845464 -242.578429) (xy 339.89305 -242.560382) (xy 339.942914 -242.550202)
			(xy 339.993766 -242.548153) (xy 340.044287 -242.554287) (xy 340.093171 -242.568447) (xy 340.13915 -242.590264)
			(xy 340.181034 -242.619174) (xy 340.217738 -242.654429) (xy 340.248311 -242.695115) (xy 340.271962 -242.740178)
			(xy 340.288078 -242.788452) (xy 340.296242 -242.838686) (xy 340.296754 -242.864132) (xy 340.615282 -242.864132)
			(xy 340.619242 -242.815078) (xy 340.631019 -242.767294) (xy 340.65031 -242.722018) (xy 340.676613 -242.680422)
			(xy 340.709248 -242.643585) (xy 340.747369 -242.61246) (xy 340.78999 -242.587853) (xy 340.836006 -242.570401)
			(xy 340.884225 -242.560557) (xy 340.9334 -242.558576) (xy 340.982255 -242.564508) (xy 341.029526 -242.5782)
			(xy 341.073988 -242.599298) (xy 341.114491 -242.627254) (xy 341.149984 -242.661346) (xy 341.179549 -242.70069)
			(xy 341.20242 -242.744267) (xy 341.218004 -242.790948) (xy 341.225899 -242.839525) (xy 341.226394 -242.864132)
			(xy 341.544905 -242.864132) (xy 341.549 -242.813404) (xy 341.561179 -242.76399) (xy 341.581127 -242.71717)
			(xy 341.608328 -242.674156) (xy 341.642076 -242.636062) (xy 341.681498 -242.603875) (xy 341.725572 -242.578429)
			(xy 341.773158 -242.560382) (xy 341.823022 -242.550202) (xy 341.873874 -242.548153) (xy 341.924395 -242.554287)
			(xy 341.973279 -242.568447) (xy 342.019258 -242.590264) (xy 342.061142 -242.619174) (xy 342.097846 -242.654429)
			(xy 342.128419 -242.695115) (xy 342.15207 -242.740178) (xy 342.168186 -242.788452) (xy 342.17635 -242.838686)
			(xy 342.176862 -242.864132) (xy 342.49539 -242.864132) (xy 342.49935 -242.815078) (xy 342.511127 -242.767294)
			(xy 342.530418 -242.722018) (xy 342.556721 -242.680422) (xy 342.589356 -242.643585) (xy 342.627477 -242.61246)
			(xy 342.670098 -242.587853) (xy 342.716114 -242.570401) (xy 342.764333 -242.560557) (xy 342.813508 -242.558576)
			(xy 342.862363 -242.564508) (xy 342.909634 -242.5782) (xy 342.954096 -242.599298) (xy 342.994599 -242.627254)
			(xy 343.030092 -242.661346) (xy 343.059657 -242.70069) (xy 343.082528 -242.744267) (xy 343.098112 -242.790948)
			(xy 343.106007 -242.839525) (xy 343.106502 -242.864132) (xy 343.106007 -242.888739) (xy 343.098112 -242.937316)
			(xy 343.082528 -242.983997) (xy 343.059657 -243.027574) (xy 343.030092 -243.066918) (xy 342.994599 -243.10101)
			(xy 342.954096 -243.128966) (xy 342.909634 -243.150064) (xy 342.862363 -243.163756) (xy 342.813508 -243.169688)
			(xy 342.764333 -243.167707) (xy 342.716114 -243.157863) (xy 342.670098 -243.140411) (xy 342.627477 -243.115804)
			(xy 342.589356 -243.084679) (xy 342.556721 -243.047842) (xy 342.530418 -243.006246) (xy 342.511127 -242.96097)
			(xy 342.49935 -242.913186) (xy 342.49539 -242.864132) (xy 342.176862 -242.864132) (xy 342.17635 -242.889578)
			(xy 342.168186 -242.939812) (xy 342.15207 -242.988086) (xy 342.128419 -243.033149) (xy 342.097846 -243.073835)
			(xy 342.061142 -243.10909) (xy 342.019258 -243.138) (xy 341.973279 -243.159817) (xy 341.924395 -243.173977)
			(xy 341.873874 -243.180111) (xy 341.823022 -243.178062) (xy 341.773158 -243.167882) (xy 341.725572 -243.149835)
			(xy 341.681498 -243.124389) (xy 341.642076 -243.092202) (xy 341.608328 -243.054108) (xy 341.581127 -243.011094)
			(xy 341.561179 -242.964274) (xy 341.549 -242.91486) (xy 341.544905 -242.864132) (xy 341.226394 -242.864132)
			(xy 341.225899 -242.888739) (xy 341.218004 -242.937316) (xy 341.20242 -242.983997) (xy 341.179549 -243.027574)
			(xy 341.149984 -243.066918) (xy 341.114491 -243.10101) (xy 341.073988 -243.128966) (xy 341.029526 -243.150064)
			(xy 340.982255 -243.163756) (xy 340.9334 -243.169688) (xy 340.884225 -243.167707) (xy 340.836006 -243.157863)
			(xy 340.78999 -243.140411) (xy 340.747369 -243.115804) (xy 340.709248 -243.084679) (xy 340.676613 -243.047842)
			(xy 340.65031 -243.006246) (xy 340.631019 -242.96097) (xy 340.619242 -242.913186) (xy 340.615282 -242.864132)
			(xy 340.296754 -242.864132) (xy 340.296242 -242.889578) (xy 340.288078 -242.939812) (xy 340.271962 -242.988086)
			(xy 340.248311 -243.033149) (xy 340.217738 -243.073835) (xy 340.181034 -243.10909) (xy 340.13915 -243.138)
			(xy 340.093171 -243.159817) (xy 340.044287 -243.173977) (xy 339.993766 -243.180111) (xy 339.942914 -243.178062)
			(xy 339.89305 -243.167882) (xy 339.845464 -243.149835) (xy 339.80139 -243.124389) (xy 339.761968 -243.092202)
			(xy 339.72822 -243.054108) (xy 339.701019 -243.011094) (xy 339.681071 -242.964274) (xy 339.668892 -242.91486)
			(xy 339.664797 -242.864132) (xy 339.3567 -242.864132) (xy 339.356188 -242.889578) (xy 339.348024 -242.939812)
			(xy 339.331908 -242.988086) (xy 339.308257 -243.033149) (xy 339.277684 -243.073835) (xy 339.24098 -243.10909)
			(xy 339.199096 -243.138) (xy 339.153117 -243.159817) (xy 339.104233 -243.173977) (xy 339.053712 -243.180111)
			(xy 339.00286 -243.178062) (xy 338.952996 -243.167882) (xy 338.90541 -243.149835) (xy 338.861336 -243.124389)
			(xy 338.821914 -243.092202) (xy 338.788166 -243.054108) (xy 338.760965 -243.011094) (xy 338.741017 -242.964274)
			(xy 338.728838 -242.91486) (xy 338.724743 -242.864132) (xy 338.406206 -242.864132) (xy 338.406206 -242.888564)
			(xy 338.398404 -242.936859) (xy 338.383 -242.983291) (xy 338.360389 -243.026672) (xy 338.331149 -243.065893)
			(xy 338.296029 -243.099948) (xy 338.255928 -243.127968) (xy 338.211871 -243.149234) (xy 338.164987 -243.163201)
			(xy 338.140802 -243.1669) (xy 338.132674 -243.16817) (xy 338.109814 -243.179092) (xy 338.105726 -243.181151)
			(xy 338.098309 -243.186514) (xy 338.095082 -243.18976) (xy 338.08035 -243.205254) (xy 338.073972 -243.212577)
			(xy 338.066799 -243.230603) (xy 338.06638 -243.240306) (xy 338.06638 -243.674138) (xy 338.254843 -243.674138)
			(xy 338.258938 -243.62341) (xy 338.271117 -243.573996) (xy 338.291065 -243.527176) (xy 338.318266 -243.484162)
			(xy 338.352014 -243.446068) (xy 338.391436 -243.413881) (xy 338.43551 -243.388435) (xy 338.483096 -243.370388)
			(xy 338.53296 -243.360208) (xy 338.583812 -243.358159) (xy 338.634333 -243.364293) (xy 338.683217 -243.378453)
			(xy 338.729196 -243.40027) (xy 338.77108 -243.42918) (xy 338.807784 -243.464435) (xy 338.838357 -243.505121)
			(xy 338.862008 -243.550184) (xy 338.878124 -243.598458) (xy 338.886288 -243.648692) (xy 338.8868 -243.674138)
			(xy 339.205328 -243.674138) (xy 339.209288 -243.625084) (xy 339.221065 -243.5773) (xy 339.240356 -243.532024)
			(xy 339.266659 -243.490428) (xy 339.299294 -243.453591) (xy 339.337415 -243.422466) (xy 339.380036 -243.397859)
			(xy 339.426052 -243.380407) (xy 339.474271 -243.370563) (xy 339.523446 -243.368582) (xy 339.572301 -243.374514)
			(xy 339.619572 -243.388206) (xy 339.664034 -243.409304) (xy 339.704537 -243.43726) (xy 339.74003 -243.471352)
			(xy 339.769595 -243.510696) (xy 339.792466 -243.554273) (xy 339.80805 -243.600954) (xy 339.815945 -243.649531)
			(xy 339.81644 -243.674138) (xy 340.134951 -243.674138) (xy 340.139046 -243.62341) (xy 340.151225 -243.573996)
			(xy 340.171173 -243.527176) (xy 340.198374 -243.484162) (xy 340.232122 -243.446068) (xy 340.271544 -243.413881)
			(xy 340.315618 -243.388435) (xy 340.363204 -243.370388) (xy 340.413068 -243.360208) (xy 340.46392 -243.358159)
			(xy 340.514441 -243.364293) (xy 340.563325 -243.378453) (xy 340.609304 -243.40027) (xy 340.651188 -243.42918)
			(xy 340.687892 -243.464435) (xy 340.718465 -243.505121) (xy 340.742116 -243.550184) (xy 340.758232 -243.598458)
			(xy 340.766396 -243.648692) (xy 340.766908 -243.674138) (xy 341.085182 -243.674138) (xy 341.089142 -243.625084)
			(xy 341.100919 -243.5773) (xy 341.12021 -243.532024) (xy 341.146513 -243.490428) (xy 341.179148 -243.453591)
			(xy 341.217269 -243.422466) (xy 341.25989 -243.397859) (xy 341.305906 -243.380407) (xy 341.354125 -243.370563)
			(xy 341.4033 -243.368582) (xy 341.452155 -243.374514) (xy 341.499426 -243.388206) (xy 341.543888 -243.409304)
			(xy 341.584391 -243.43726) (xy 341.619884 -243.471352) (xy 341.649449 -243.510696) (xy 341.67232 -243.554273)
			(xy 341.687904 -243.600954) (xy 341.695799 -243.649531) (xy 341.696294 -243.674138) (xy 342.014805 -243.674138)
			(xy 342.0189 -243.62341) (xy 342.031079 -243.573996) (xy 342.051027 -243.527176) (xy 342.078228 -243.484162)
			(xy 342.111976 -243.446068) (xy 342.151398 -243.413881) (xy 342.195472 -243.388435) (xy 342.243058 -243.370388)
			(xy 342.292922 -243.360208) (xy 342.343774 -243.358159) (xy 342.394295 -243.364293) (xy 342.443179 -243.378453)
			(xy 342.489158 -243.40027) (xy 342.531042 -243.42918) (xy 342.567746 -243.464435) (xy 342.598319 -243.505121)
			(xy 342.62197 -243.550184) (xy 342.638086 -243.598458) (xy 342.64625 -243.648692) (xy 342.646762 -243.674138)
			(xy 342.954859 -243.674138) (xy 342.958954 -243.62341) (xy 342.971133 -243.573996) (xy 342.991081 -243.527176)
			(xy 343.018282 -243.484162) (xy 343.05203 -243.446068) (xy 343.091452 -243.413881) (xy 343.135526 -243.388435)
			(xy 343.183112 -243.370388) (xy 343.232976 -243.360208) (xy 343.283828 -243.358159) (xy 343.334349 -243.364293)
			(xy 343.383233 -243.378453) (xy 343.429212 -243.40027) (xy 343.471096 -243.42918) (xy 343.5078 -243.464435)
			(xy 343.538373 -243.505121) (xy 343.562024 -243.550184) (xy 343.57814 -243.598458) (xy 343.586304 -243.648692)
			(xy 343.586816 -243.674138) (xy 343.586304 -243.699584) (xy 343.57814 -243.749818) (xy 343.562024 -243.798092)
			(xy 343.538373 -243.843155) (xy 343.5078 -243.883841) (xy 343.471096 -243.919096) (xy 343.429212 -243.948006)
			(xy 343.383233 -243.969823) (xy 343.334349 -243.983983) (xy 343.283828 -243.990117) (xy 343.232976 -243.988068)
			(xy 343.183112 -243.977888) (xy 343.135526 -243.959841) (xy 343.091452 -243.934395) (xy 343.05203 -243.902208)
			(xy 343.018282 -243.864114) (xy 342.991081 -243.8211) (xy 342.971133 -243.77428) (xy 342.958954 -243.724866)
			(xy 342.954859 -243.674138) (xy 342.646762 -243.674138) (xy 342.64625 -243.699584) (xy 342.638086 -243.749818)
			(xy 342.62197 -243.798092) (xy 342.598319 -243.843155) (xy 342.567746 -243.883841) (xy 342.531042 -243.919096)
			(xy 342.489158 -243.948006) (xy 342.443179 -243.969823) (xy 342.394295 -243.983983) (xy 342.343774 -243.990117)
			(xy 342.292922 -243.988068) (xy 342.243058 -243.977888) (xy 342.195472 -243.959841) (xy 342.151398 -243.934395)
			(xy 342.111976 -243.902208) (xy 342.078228 -243.864114) (xy 342.051027 -243.8211) (xy 342.031079 -243.77428)
			(xy 342.0189 -243.724866) (xy 342.014805 -243.674138) (xy 341.696294 -243.674138) (xy 341.695799 -243.698745)
			(xy 341.687904 -243.747322) (xy 341.67232 -243.794003) (xy 341.649449 -243.83758) (xy 341.619884 -243.876924)
			(xy 341.584391 -243.911016) (xy 341.543888 -243.938972) (xy 341.499426 -243.96007) (xy 341.452155 -243.973762)
			(xy 341.4033 -243.979694) (xy 341.354125 -243.977713) (xy 341.305906 -243.967869) (xy 341.25989 -243.950417)
			(xy 341.217269 -243.92581) (xy 341.179148 -243.894685) (xy 341.146513 -243.857848) (xy 341.12021 -243.816252)
			(xy 341.100919 -243.770976) (xy 341.089142 -243.723192) (xy 341.085182 -243.674138) (xy 340.766908 -243.674138)
			(xy 340.766396 -243.699584) (xy 340.758232 -243.749818) (xy 340.742116 -243.798092) (xy 340.718465 -243.843155)
			(xy 340.687892 -243.883841) (xy 340.651188 -243.919096) (xy 340.609304 -243.948006) (xy 340.563325 -243.969823)
			(xy 340.514441 -243.983983) (xy 340.46392 -243.990117) (xy 340.413068 -243.988068) (xy 340.363204 -243.977888)
			(xy 340.315618 -243.959841) (xy 340.271544 -243.934395) (xy 340.232122 -243.902208) (xy 340.198374 -243.864114)
			(xy 340.171173 -243.8211) (xy 340.151225 -243.77428) (xy 340.139046 -243.724866) (xy 340.134951 -243.674138)
			(xy 339.81644 -243.674138) (xy 339.815945 -243.698745) (xy 339.80805 -243.747322) (xy 339.792466 -243.794003)
			(xy 339.769595 -243.83758) (xy 339.74003 -243.876924) (xy 339.704537 -243.911016) (xy 339.664034 -243.938972)
			(xy 339.619572 -243.96007) (xy 339.572301 -243.973762) (xy 339.523446 -243.979694) (xy 339.474271 -243.977713)
			(xy 339.426052 -243.967869) (xy 339.380036 -243.950417) (xy 339.337415 -243.92581) (xy 339.299294 -243.894685)
			(xy 339.266659 -243.857848) (xy 339.240356 -243.816252) (xy 339.221065 -243.770976) (xy 339.209288 -243.723192)
			(xy 339.205328 -243.674138) (xy 338.8868 -243.674138) (xy 338.886288 -243.699584) (xy 338.878124 -243.749818)
			(xy 338.862008 -243.798092) (xy 338.838357 -243.843155) (xy 338.807784 -243.883841) (xy 338.77108 -243.919096)
			(xy 338.729196 -243.948006) (xy 338.683217 -243.969823) (xy 338.634333 -243.983983) (xy 338.583812 -243.990117)
			(xy 338.53296 -243.988068) (xy 338.483096 -243.977888) (xy 338.43551 -243.959841) (xy 338.391436 -243.934395)
			(xy 338.352014 -243.902208) (xy 338.318266 -243.864114) (xy 338.291065 -243.8211) (xy 338.271117 -243.77428)
			(xy 338.258938 -243.724866) (xy 338.254843 -243.674138) (xy 338.06638 -243.674138) (xy 338.06638 -244.10797)
			(xy 338.066811 -244.117668) (xy 338.073994 -244.135685) (xy 338.08035 -244.143022) (xy 338.095082 -244.158516)
			(xy 338.098323 -244.161747) (xy 338.105732 -244.167115) (xy 338.109814 -244.169184) (xy 338.132674 -244.180106)
			(xy 338.140802 -244.181376) (xy 338.164994 -244.185012) (xy 338.211876 -244.198981) (xy 338.25593 -244.220247)
			(xy 338.296029 -244.248267) (xy 338.331147 -244.282323) (xy 338.360384 -244.321542) (xy 338.382993 -244.364923)
			(xy 338.398394 -244.411354) (xy 338.406195 -244.459646) (xy 338.406194 -244.484144) (xy 338.724743 -244.484144)
			(xy 338.728838 -244.433416) (xy 338.741017 -244.384002) (xy 338.760965 -244.337182) (xy 338.788166 -244.294168)
			(xy 338.821914 -244.256074) (xy 338.861336 -244.223887) (xy 338.90541 -244.198441) (xy 338.952996 -244.180394)
			(xy 339.00286 -244.170214) (xy 339.053712 -244.168165) (xy 339.104233 -244.174299) (xy 339.153117 -244.188459)
			(xy 339.199096 -244.210276) (xy 339.24098 -244.239186) (xy 339.277684 -244.274441) (xy 339.308257 -244.315127)
			(xy 339.331908 -244.36019) (xy 339.348024 -244.408464) (xy 339.356188 -244.458698) (xy 339.3567 -244.484144)
			(xy 339.664797 -244.484144) (xy 339.668892 -244.433416) (xy 339.681071 -244.384002) (xy 339.701019 -244.337182)
			(xy 339.72822 -244.294168) (xy 339.761968 -244.256074) (xy 339.80139 -244.223887) (xy 339.845464 -244.198441)
			(xy 339.89305 -244.180394) (xy 339.942914 -244.170214) (xy 339.993766 -244.168165) (xy 340.044287 -244.174299)
			(xy 340.093171 -244.188459) (xy 340.13915 -244.210276) (xy 340.181034 -244.239186) (xy 340.217738 -244.274441)
			(xy 340.248311 -244.315127) (xy 340.271962 -244.36019) (xy 340.288078 -244.408464) (xy 340.296242 -244.458698)
			(xy 340.296754 -244.484144) (xy 340.615282 -244.484144) (xy 340.619242 -244.43509) (xy 340.631019 -244.387306)
			(xy 340.65031 -244.34203) (xy 340.676613 -244.300434) (xy 340.709248 -244.263597) (xy 340.747369 -244.232472)
			(xy 340.78999 -244.207865) (xy 340.836006 -244.190413) (xy 340.884225 -244.180569) (xy 340.9334 -244.178588)
			(xy 340.982255 -244.18452) (xy 341.029526 -244.198212) (xy 341.073988 -244.21931) (xy 341.114491 -244.247266)
			(xy 341.149984 -244.281358) (xy 341.179549 -244.320702) (xy 341.20242 -244.364279) (xy 341.218004 -244.41096)
			(xy 341.225899 -244.459537) (xy 341.226394 -244.484144) (xy 341.544905 -244.484144) (xy 341.549 -244.433416)
			(xy 341.561179 -244.384002) (xy 341.581127 -244.337182) (xy 341.608328 -244.294168) (xy 341.642076 -244.256074)
			(xy 341.681498 -244.223887) (xy 341.725572 -244.198441) (xy 341.773158 -244.180394) (xy 341.823022 -244.170214)
			(xy 341.873874 -244.168165) (xy 341.924395 -244.174299) (xy 341.973279 -244.188459) (xy 342.019258 -244.210276)
			(xy 342.061142 -244.239186) (xy 342.097846 -244.274441) (xy 342.128419 -244.315127) (xy 342.15207 -244.36019)
			(xy 342.168186 -244.408464) (xy 342.17635 -244.458698) (xy 342.176862 -244.484144) (xy 342.49539 -244.484144)
			(xy 342.49935 -244.43509) (xy 342.511127 -244.387306) (xy 342.530418 -244.34203) (xy 342.556721 -244.300434)
			(xy 342.589356 -244.263597) (xy 342.627477 -244.232472) (xy 342.670098 -244.207865) (xy 342.716114 -244.190413)
			(xy 342.764333 -244.180569) (xy 342.813508 -244.178588) (xy 342.862363 -244.18452) (xy 342.909634 -244.198212)
			(xy 342.954096 -244.21931) (xy 342.994599 -244.247266) (xy 343.030092 -244.281358) (xy 343.059657 -244.320702)
			(xy 343.082528 -244.364279) (xy 343.098112 -244.41096) (xy 343.106007 -244.459537) (xy 343.106502 -244.484144)
			(xy 343.106007 -244.508751) (xy 343.098112 -244.557328) (xy 343.082528 -244.604009) (xy 343.059657 -244.647586)
			(xy 343.030092 -244.68693) (xy 342.994599 -244.721022) (xy 342.954096 -244.748978) (xy 342.909634 -244.770076)
			(xy 342.862363 -244.783768) (xy 342.813508 -244.7897) (xy 342.764333 -244.787719) (xy 342.716114 -244.777875)
			(xy 342.670098 -244.760423) (xy 342.627477 -244.735816) (xy 342.589356 -244.704691) (xy 342.556721 -244.667854)
			(xy 342.530418 -244.626258) (xy 342.511127 -244.580982) (xy 342.49935 -244.533198) (xy 342.49539 -244.484144)
			(xy 342.176862 -244.484144) (xy 342.17635 -244.50959) (xy 342.168186 -244.559824) (xy 342.15207 -244.608098)
			(xy 342.128419 -244.653161) (xy 342.097846 -244.693847) (xy 342.061142 -244.729102) (xy 342.019258 -244.758012)
			(xy 341.973279 -244.779829) (xy 341.924395 -244.793989) (xy 341.873874 -244.800123) (xy 341.823022 -244.798074)
			(xy 341.773158 -244.787894) (xy 341.725572 -244.769847) (xy 341.681498 -244.744401) (xy 341.642076 -244.712214)
			(xy 341.608328 -244.67412) (xy 341.581127 -244.631106) (xy 341.561179 -244.584286) (xy 341.549 -244.534872)
			(xy 341.544905 -244.484144) (xy 341.226394 -244.484144) (xy 341.225899 -244.508751) (xy 341.218004 -244.557328)
			(xy 341.20242 -244.604009) (xy 341.179549 -244.647586) (xy 341.149984 -244.68693) (xy 341.114491 -244.721022)
			(xy 341.073988 -244.748978) (xy 341.029526 -244.770076) (xy 340.982255 -244.783768) (xy 340.9334 -244.7897)
			(xy 340.884225 -244.787719) (xy 340.836006 -244.777875) (xy 340.78999 -244.760423) (xy 340.747369 -244.735816)
			(xy 340.709248 -244.704691) (xy 340.676613 -244.667854) (xy 340.65031 -244.626258) (xy 340.631019 -244.580982)
			(xy 340.619242 -244.533198) (xy 340.615282 -244.484144) (xy 340.296754 -244.484144) (xy 340.296242 -244.50959)
			(xy 340.288078 -244.559824) (xy 340.271962 -244.608098) (xy 340.248311 -244.653161) (xy 340.217738 -244.693847)
			(xy 340.181034 -244.729102) (xy 340.13915 -244.758012) (xy 340.093171 -244.779829) (xy 340.044287 -244.793989)
			(xy 339.993766 -244.800123) (xy 339.942914 -244.798074) (xy 339.89305 -244.787894) (xy 339.845464 -244.769847)
			(xy 339.80139 -244.744401) (xy 339.761968 -244.712214) (xy 339.72822 -244.67412) (xy 339.701019 -244.631106)
			(xy 339.681071 -244.584286) (xy 339.668892 -244.534872) (xy 339.664797 -244.484144) (xy 339.3567 -244.484144)
			(xy 339.356188 -244.50959) (xy 339.348024 -244.559824) (xy 339.331908 -244.608098) (xy 339.308257 -244.653161)
			(xy 339.277684 -244.693847) (xy 339.24098 -244.729102) (xy 339.199096 -244.758012) (xy 339.153117 -244.779829)
			(xy 339.104233 -244.793989) (xy 339.053712 -244.800123) (xy 339.00286 -244.798074) (xy 338.952996 -244.787894)
			(xy 338.90541 -244.769847) (xy 338.861336 -244.744401) (xy 338.821914 -244.712214) (xy 338.788166 -244.67412)
			(xy 338.760965 -244.631106) (xy 338.741017 -244.584286) (xy 338.728838 -244.534872) (xy 338.724743 -244.484144)
			(xy 338.406194 -244.484144) (xy 338.406194 -244.508565) (xy 338.398392 -244.556857) (xy 338.382988 -244.603288)
			(xy 338.360378 -244.646667) (xy 338.331139 -244.685886) (xy 338.29602 -244.71994) (xy 338.25592 -244.747958)
			(xy 338.211865 -244.769223) (xy 338.164983 -244.78319) (xy 338.140802 -244.786912) (xy 338.132674 -244.788182)
			(xy 338.109814 -244.799104) (xy 338.105726 -244.801163) (xy 338.09831 -244.806527) (xy 338.095082 -244.809772)
			(xy 338.08035 -244.825266) (xy 338.073974 -244.832589) (xy 338.066805 -244.850616) (xy 338.06638 -244.860318)
			(xy 338.06638 -245.29415) (xy 338.254843 -245.29415) (xy 338.258938 -245.243422) (xy 338.271117 -245.194008)
			(xy 338.291065 -245.147188) (xy 338.318266 -245.104174) (xy 338.352014 -245.06608) (xy 338.391436 -245.033893)
			(xy 338.43551 -245.008447) (xy 338.483096 -244.9904) (xy 338.53296 -244.98022) (xy 338.583812 -244.978171)
			(xy 338.634333 -244.984305) (xy 338.683217 -244.998465) (xy 338.729196 -245.020282) (xy 338.77108 -245.049192)
			(xy 338.807784 -245.084447) (xy 338.838357 -245.125133) (xy 338.862008 -245.170196) (xy 338.878124 -245.21847)
			(xy 338.886288 -245.268704) (xy 338.8868 -245.29415) (xy 339.205328 -245.29415) (xy 339.209288 -245.245096)
			(xy 339.221065 -245.197312) (xy 339.240356 -245.152036) (xy 339.266659 -245.11044) (xy 339.299294 -245.073603)
			(xy 339.337415 -245.042478) (xy 339.380036 -245.017871) (xy 339.426052 -245.000419) (xy 339.474271 -244.990575)
			(xy 339.523446 -244.988594) (xy 339.572301 -244.994526) (xy 339.619572 -245.008218) (xy 339.664034 -245.029316)
			(xy 339.704537 -245.057272) (xy 339.74003 -245.091364) (xy 339.769595 -245.130708) (xy 339.792466 -245.174285)
			(xy 339.80805 -245.220966) (xy 339.815945 -245.269543) (xy 339.81644 -245.29415) (xy 340.134951 -245.29415)
			(xy 340.139046 -245.243422) (xy 340.151225 -245.194008) (xy 340.171173 -245.147188) (xy 340.198374 -245.104174)
			(xy 340.232122 -245.06608) (xy 340.271544 -245.033893) (xy 340.315618 -245.008447) (xy 340.363204 -244.9904)
			(xy 340.413068 -244.98022) (xy 340.46392 -244.978171) (xy 340.514441 -244.984305) (xy 340.563325 -244.998465)
			(xy 340.609304 -245.020282) (xy 340.651188 -245.049192) (xy 340.687892 -245.084447) (xy 340.718465 -245.125133)
			(xy 340.742116 -245.170196) (xy 340.758232 -245.21847) (xy 340.766396 -245.268704) (xy 340.766908 -245.29415)
			(xy 341.085182 -245.29415) (xy 341.089142 -245.245096) (xy 341.100919 -245.197312) (xy 341.12021 -245.152036)
			(xy 341.146513 -245.11044) (xy 341.179148 -245.073603) (xy 341.217269 -245.042478) (xy 341.25989 -245.017871)
			(xy 341.305906 -245.000419) (xy 341.354125 -244.990575) (xy 341.4033 -244.988594) (xy 341.452155 -244.994526)
			(xy 341.499426 -245.008218) (xy 341.543888 -245.029316) (xy 341.584391 -245.057272) (xy 341.619884 -245.091364)
			(xy 341.649449 -245.130708) (xy 341.67232 -245.174285) (xy 341.687904 -245.220966) (xy 341.695799 -245.269543)
			(xy 341.696294 -245.29415) (xy 342.014805 -245.29415) (xy 342.0189 -245.243422) (xy 342.031079 -245.194008)
			(xy 342.051027 -245.147188) (xy 342.078228 -245.104174) (xy 342.111976 -245.06608) (xy 342.151398 -245.033893)
			(xy 342.195472 -245.008447) (xy 342.243058 -244.9904) (xy 342.292922 -244.98022) (xy 342.343774 -244.978171)
			(xy 342.394295 -244.984305) (xy 342.443179 -244.998465) (xy 342.489158 -245.020282) (xy 342.531042 -245.049192)
			(xy 342.567746 -245.084447) (xy 342.598319 -245.125133) (xy 342.62197 -245.170196) (xy 342.638086 -245.21847)
			(xy 342.64625 -245.268704) (xy 342.646762 -245.29415) (xy 342.954859 -245.29415) (xy 342.958954 -245.243422)
			(xy 342.971133 -245.194008) (xy 342.991081 -245.147188) (xy 343.018282 -245.104174) (xy 343.05203 -245.06608)
			(xy 343.091452 -245.033893) (xy 343.135526 -245.008447) (xy 343.183112 -244.9904) (xy 343.232976 -244.98022)
			(xy 343.283828 -244.978171) (xy 343.334349 -244.984305) (xy 343.383233 -244.998465) (xy 343.429212 -245.020282)
			(xy 343.471096 -245.049192) (xy 343.5078 -245.084447) (xy 343.538373 -245.125133) (xy 343.562024 -245.170196)
			(xy 343.57814 -245.21847) (xy 343.586304 -245.268704) (xy 343.586816 -245.29415) (xy 343.586304 -245.319596)
			(xy 343.57814 -245.36983) (xy 343.562024 -245.418104) (xy 343.538373 -245.463167) (xy 343.5078 -245.503853)
			(xy 343.471096 -245.539108) (xy 343.429212 -245.568018) (xy 343.383233 -245.589835) (xy 343.334349 -245.603995)
			(xy 343.283828 -245.610129) (xy 343.232976 -245.60808) (xy 343.183112 -245.5979) (xy 343.135526 -245.579853)
			(xy 343.091452 -245.554407) (xy 343.05203 -245.52222) (xy 343.018282 -245.484126) (xy 342.991081 -245.441112)
			(xy 342.971133 -245.394292) (xy 342.958954 -245.344878) (xy 342.954859 -245.29415) (xy 342.646762 -245.29415)
			(xy 342.64625 -245.319596) (xy 342.638086 -245.36983) (xy 342.62197 -245.418104) (xy 342.598319 -245.463167)
			(xy 342.567746 -245.503853) (xy 342.531042 -245.539108) (xy 342.489158 -245.568018) (xy 342.443179 -245.589835)
			(xy 342.394295 -245.603995) (xy 342.343774 -245.610129) (xy 342.292922 -245.60808) (xy 342.243058 -245.5979)
			(xy 342.195472 -245.579853) (xy 342.151398 -245.554407) (xy 342.111976 -245.52222) (xy 342.078228 -245.484126)
			(xy 342.051027 -245.441112) (xy 342.031079 -245.394292) (xy 342.0189 -245.344878) (xy 342.014805 -245.29415)
			(xy 341.696294 -245.29415) (xy 341.695799 -245.318757) (xy 341.687904 -245.367334) (xy 341.67232 -245.414015)
			(xy 341.649449 -245.457592) (xy 341.619884 -245.496936) (xy 341.584391 -245.531028) (xy 341.543888 -245.558984)
			(xy 341.499426 -245.580082) (xy 341.452155 -245.593774) (xy 341.4033 -245.599706) (xy 341.354125 -245.597725)
			(xy 341.305906 -245.587881) (xy 341.25989 -245.570429) (xy 341.217269 -245.545822) (xy 341.179148 -245.514697)
			(xy 341.146513 -245.47786) (xy 341.12021 -245.436264) (xy 341.100919 -245.390988) (xy 341.089142 -245.343204)
			(xy 341.085182 -245.29415) (xy 340.766908 -245.29415) (xy 340.766396 -245.319596) (xy 340.758232 -245.36983)
			(xy 340.742116 -245.418104) (xy 340.718465 -245.463167) (xy 340.687892 -245.503853) (xy 340.651188 -245.539108)
			(xy 340.609304 -245.568018) (xy 340.563325 -245.589835) (xy 340.514441 -245.603995) (xy 340.46392 -245.610129)
			(xy 340.413068 -245.60808) (xy 340.363204 -245.5979) (xy 340.315618 -245.579853) (xy 340.271544 -245.554407)
			(xy 340.232122 -245.52222) (xy 340.198374 -245.484126) (xy 340.171173 -245.441112) (xy 340.151225 -245.394292)
			(xy 340.139046 -245.344878) (xy 340.134951 -245.29415) (xy 339.81644 -245.29415) (xy 339.815945 -245.318757)
			(xy 339.80805 -245.367334) (xy 339.792466 -245.414015) (xy 339.769595 -245.457592) (xy 339.74003 -245.496936)
			(xy 339.704537 -245.531028) (xy 339.664034 -245.558984) (xy 339.619572 -245.580082) (xy 339.572301 -245.593774)
			(xy 339.523446 -245.599706) (xy 339.474271 -245.597725) (xy 339.426052 -245.587881) (xy 339.380036 -245.570429)
			(xy 339.337415 -245.545822) (xy 339.299294 -245.514697) (xy 339.266659 -245.47786) (xy 339.240356 -245.436264)
			(xy 339.221065 -245.390988) (xy 339.209288 -245.343204) (xy 339.205328 -245.29415) (xy 338.8868 -245.29415)
			(xy 338.886288 -245.319596) (xy 338.878124 -245.36983) (xy 338.862008 -245.418104) (xy 338.838357 -245.463167)
			(xy 338.807784 -245.503853) (xy 338.77108 -245.539108) (xy 338.729196 -245.568018) (xy 338.683217 -245.589835)
			(xy 338.634333 -245.603995) (xy 338.583812 -245.610129) (xy 338.53296 -245.60808) (xy 338.483096 -245.5979)
			(xy 338.43551 -245.579853) (xy 338.391436 -245.554407) (xy 338.352014 -245.52222) (xy 338.318266 -245.484126)
			(xy 338.291065 -245.441112) (xy 338.271117 -245.394292) (xy 338.258938 -245.344878) (xy 338.254843 -245.29415)
			(xy 338.06638 -245.29415) (xy 338.06638 -245.727982) (xy 338.066814 -245.737679) (xy 338.073999 -245.755693)
			(xy 338.08035 -245.763034) (xy 338.095082 -245.778528) (xy 338.098323 -245.781758) (xy 338.105733 -245.787126)
			(xy 338.109814 -245.789196) (xy 338.132674 -245.800118) (xy 338.140802 -245.801388) (xy 338.165001 -245.805025)
			(xy 338.211897 -245.818996) (xy 338.255964 -245.840266) (xy 338.296076 -245.868292) (xy 338.331205 -245.902356)
			(xy 338.360452 -245.941586) (xy 338.383069 -245.984978) (xy 338.398477 -246.031422) (xy 338.406281 -246.079728)
			(xy 338.406281 -246.104156) (xy 338.724743 -246.104156) (xy 338.728838 -246.053428) (xy 338.741017 -246.004014)
			(xy 338.760965 -245.957194) (xy 338.788166 -245.91418) (xy 338.821914 -245.876086) (xy 338.861336 -245.843899)
			(xy 338.90541 -245.818453) (xy 338.952996 -245.800406) (xy 339.00286 -245.790226) (xy 339.053712 -245.788177)
			(xy 339.104233 -245.794311) (xy 339.153117 -245.808471) (xy 339.199096 -245.830288) (xy 339.24098 -245.859198)
			(xy 339.277684 -245.894453) (xy 339.308257 -245.935139) (xy 339.331908 -245.980202) (xy 339.348024 -246.028476)
			(xy 339.356188 -246.07871) (xy 339.3567 -246.104156) (xy 339.664797 -246.104156) (xy 339.668892 -246.053428)
			(xy 339.681071 -246.004014) (xy 339.701019 -245.957194) (xy 339.72822 -245.91418) (xy 339.761968 -245.876086)
			(xy 339.80139 -245.843899) (xy 339.845464 -245.818453) (xy 339.89305 -245.800406) (xy 339.942914 -245.790226)
			(xy 339.993766 -245.788177) (xy 340.044287 -245.794311) (xy 340.093171 -245.808471) (xy 340.13915 -245.830288)
			(xy 340.181034 -245.859198) (xy 340.217738 -245.894453) (xy 340.248311 -245.935139) (xy 340.271962 -245.980202)
			(xy 340.288078 -246.028476) (xy 340.296242 -246.07871) (xy 340.296754 -246.104156) (xy 340.615282 -246.104156)
			(xy 340.619242 -246.055102) (xy 340.631019 -246.007318) (xy 340.65031 -245.962042) (xy 340.676613 -245.920446)
			(xy 340.709248 -245.883609) (xy 340.747369 -245.852484) (xy 340.78999 -245.827877) (xy 340.836006 -245.810425)
			(xy 340.884225 -245.800581) (xy 340.9334 -245.7986) (xy 340.982255 -245.804532) (xy 341.029526 -245.818224)
			(xy 341.073988 -245.839322) (xy 341.114491 -245.867278) (xy 341.149984 -245.90137) (xy 341.179549 -245.940714)
			(xy 341.20242 -245.984291) (xy 341.218004 -246.030972) (xy 341.225899 -246.079549) (xy 341.226394 -246.104156)
			(xy 341.544905 -246.104156) (xy 341.549 -246.053428) (xy 341.561179 -246.004014) (xy 341.581127 -245.957194)
			(xy 341.608328 -245.91418) (xy 341.642076 -245.876086) (xy 341.681498 -245.843899) (xy 341.725572 -245.818453)
			(xy 341.773158 -245.800406) (xy 341.823022 -245.790226) (xy 341.873874 -245.788177) (xy 341.924395 -245.794311)
			(xy 341.973279 -245.808471) (xy 342.019258 -245.830288) (xy 342.061142 -245.859198) (xy 342.097846 -245.894453)
			(xy 342.128419 -245.935139) (xy 342.15207 -245.980202) (xy 342.168186 -246.028476) (xy 342.17635 -246.07871)
			(xy 342.176862 -246.104156) (xy 342.49539 -246.104156) (xy 342.49935 -246.055102) (xy 342.511127 -246.007318)
			(xy 342.530418 -245.962042) (xy 342.556721 -245.920446) (xy 342.589356 -245.883609) (xy 342.627477 -245.852484)
			(xy 342.670098 -245.827877) (xy 342.716114 -245.810425) (xy 342.764333 -245.800581) (xy 342.813508 -245.7986)
			(xy 342.862363 -245.804532) (xy 342.909634 -245.818224) (xy 342.954096 -245.839322) (xy 342.994599 -245.867278)
			(xy 343.030092 -245.90137) (xy 343.059657 -245.940714) (xy 343.082528 -245.984291) (xy 343.098112 -246.030972)
			(xy 343.106007 -246.079549) (xy 343.106502 -246.104156) (xy 343.106007 -246.128763) (xy 343.098112 -246.17734)
			(xy 343.082528 -246.224021) (xy 343.059657 -246.267598) (xy 343.030092 -246.306942) (xy 342.994599 -246.341034)
			(xy 342.954096 -246.36899) (xy 342.909634 -246.390088) (xy 342.862363 -246.40378) (xy 342.813508 -246.409712)
			(xy 342.764333 -246.407731) (xy 342.716114 -246.397887) (xy 342.670098 -246.380435) (xy 342.627477 -246.355828)
			(xy 342.589356 -246.324703) (xy 342.556721 -246.287866) (xy 342.530418 -246.24627) (xy 342.511127 -246.200994)
			(xy 342.49935 -246.15321) (xy 342.49539 -246.104156) (xy 342.176862 -246.104156) (xy 342.17635 -246.129602)
			(xy 342.168186 -246.179836) (xy 342.15207 -246.22811) (xy 342.128419 -246.273173) (xy 342.097846 -246.313859)
			(xy 342.061142 -246.349114) (xy 342.019258 -246.378024) (xy 341.973279 -246.399841) (xy 341.924395 -246.414001)
			(xy 341.873874 -246.420135) (xy 341.823022 -246.418086) (xy 341.773158 -246.407906) (xy 341.725572 -246.389859)
			(xy 341.681498 -246.364413) (xy 341.642076 -246.332226) (xy 341.608328 -246.294132) (xy 341.581127 -246.251118)
			(xy 341.561179 -246.204298) (xy 341.549 -246.154884) (xy 341.544905 -246.104156) (xy 341.226394 -246.104156)
			(xy 341.225899 -246.128763) (xy 341.218004 -246.17734) (xy 341.20242 -246.224021) (xy 341.179549 -246.267598)
			(xy 341.149984 -246.306942) (xy 341.114491 -246.341034) (xy 341.073988 -246.36899) (xy 341.029526 -246.390088)
			(xy 340.982255 -246.40378) (xy 340.9334 -246.409712) (xy 340.884225 -246.407731) (xy 340.836006 -246.397887)
			(xy 340.78999 -246.380435) (xy 340.747369 -246.355828) (xy 340.709248 -246.324703) (xy 340.676613 -246.287866)
			(xy 340.65031 -246.24627) (xy 340.631019 -246.200994) (xy 340.619242 -246.15321) (xy 340.615282 -246.104156)
			(xy 340.296754 -246.104156) (xy 340.296242 -246.129602) (xy 340.288078 -246.179836) (xy 340.271962 -246.22811)
			(xy 340.248311 -246.273173) (xy 340.217738 -246.313859) (xy 340.181034 -246.349114) (xy 340.13915 -246.378024)
			(xy 340.093171 -246.399841) (xy 340.044287 -246.414001) (xy 339.993766 -246.420135) (xy 339.942914 -246.418086)
			(xy 339.89305 -246.407906) (xy 339.845464 -246.389859) (xy 339.80139 -246.364413) (xy 339.761968 -246.332226)
			(xy 339.72822 -246.294132) (xy 339.701019 -246.251118) (xy 339.681071 -246.204298) (xy 339.668892 -246.154884)
			(xy 339.664797 -246.104156) (xy 339.3567 -246.104156) (xy 339.356188 -246.129602) (xy 339.348024 -246.179836)
			(xy 339.331908 -246.22811) (xy 339.308257 -246.273173) (xy 339.277684 -246.313859) (xy 339.24098 -246.349114)
			(xy 339.199096 -246.378024) (xy 339.153117 -246.399841) (xy 339.104233 -246.414001) (xy 339.053712 -246.420135)
			(xy 339.00286 -246.418086) (xy 338.952996 -246.407906) (xy 338.90541 -246.389859) (xy 338.861336 -246.364413)
			(xy 338.821914 -246.332226) (xy 338.788166 -246.294132) (xy 338.760965 -246.251118) (xy 338.741017 -246.204298)
			(xy 338.728838 -246.154884) (xy 338.724743 -246.104156) (xy 338.406281 -246.104156) (xy 338.406282 -246.128661)
			(xy 338.398479 -246.176967) (xy 338.383073 -246.223411) (xy 338.360458 -246.266804) (xy 338.331212 -246.306035)
			(xy 338.296085 -246.3401) (xy 338.255974 -246.368128) (xy 338.211908 -246.3894) (xy 338.165012 -246.403373)
			(xy 338.140802 -246.406924) (xy 338.132674 -246.408194) (xy 338.109814 -246.419116) (xy 338.105726 -246.421175)
			(xy 338.098312 -246.426541) (xy 338.095082 -246.429784) (xy 338.08035 -246.445278) (xy 338.07396 -246.452597)
			(xy 338.06676 -246.470623) (xy 338.06638 -246.48033) (xy 338.06638 -246.914162) (xy 338.254843 -246.914162)
			(xy 338.258938 -246.863434) (xy 338.271117 -246.81402) (xy 338.291065 -246.7672) (xy 338.318266 -246.724186)
			(xy 338.352014 -246.686092) (xy 338.391436 -246.653905) (xy 338.43551 -246.628459) (xy 338.483096 -246.610412)
			(xy 338.53296 -246.600232) (xy 338.583812 -246.598183) (xy 338.634333 -246.604317) (xy 338.683217 -246.618477)
			(xy 338.729196 -246.640294) (xy 338.77108 -246.669204) (xy 338.807784 -246.704459) (xy 338.838357 -246.745145)
			(xy 338.862008 -246.790208) (xy 338.878124 -246.838482) (xy 338.886288 -246.888716) (xy 338.8868 -246.914162)
			(xy 339.205328 -246.914162) (xy 339.209288 -246.865108) (xy 339.221065 -246.817324) (xy 339.240356 -246.772048)
			(xy 339.266659 -246.730452) (xy 339.299294 -246.693615) (xy 339.337415 -246.66249) (xy 339.380036 -246.637883)
			(xy 339.426052 -246.620431) (xy 339.474271 -246.610587) (xy 339.523446 -246.608606) (xy 339.572301 -246.614538)
			(xy 339.619572 -246.62823) (xy 339.664034 -246.649328) (xy 339.704537 -246.677284) (xy 339.74003 -246.711376)
			(xy 339.769595 -246.75072) (xy 339.792466 -246.794297) (xy 339.80805 -246.840978) (xy 339.815945 -246.889555)
			(xy 339.81644 -246.914162) (xy 340.134951 -246.914162) (xy 340.139046 -246.863434) (xy 340.151225 -246.81402)
			(xy 340.171173 -246.7672) (xy 340.198374 -246.724186) (xy 340.232122 -246.686092) (xy 340.271544 -246.653905)
			(xy 340.315618 -246.628459) (xy 340.363204 -246.610412) (xy 340.413068 -246.600232) (xy 340.46392 -246.598183)
			(xy 340.514441 -246.604317) (xy 340.563325 -246.618477) (xy 340.609304 -246.640294) (xy 340.651188 -246.669204)
			(xy 340.687892 -246.704459) (xy 340.718465 -246.745145) (xy 340.742116 -246.790208) (xy 340.758232 -246.838482)
			(xy 340.766396 -246.888716) (xy 340.766908 -246.914162) (xy 341.085182 -246.914162) (xy 341.089142 -246.865108)
			(xy 341.100919 -246.817324) (xy 341.12021 -246.772048) (xy 341.146513 -246.730452) (xy 341.179148 -246.693615)
			(xy 341.217269 -246.66249) (xy 341.25989 -246.637883) (xy 341.305906 -246.620431) (xy 341.354125 -246.610587)
			(xy 341.4033 -246.608606) (xy 341.452155 -246.614538) (xy 341.499426 -246.62823) (xy 341.543888 -246.649328)
			(xy 341.584391 -246.677284) (xy 341.619884 -246.711376) (xy 341.649449 -246.75072) (xy 341.67232 -246.794297)
			(xy 341.687904 -246.840978) (xy 341.695799 -246.889555) (xy 341.696294 -246.914162) (xy 342.014805 -246.914162)
			(xy 342.0189 -246.863434) (xy 342.031079 -246.81402) (xy 342.051027 -246.7672) (xy 342.078228 -246.724186)
			(xy 342.111976 -246.686092) (xy 342.151398 -246.653905) (xy 342.195472 -246.628459) (xy 342.243058 -246.610412)
			(xy 342.292922 -246.600232) (xy 342.343774 -246.598183) (xy 342.394295 -246.604317) (xy 342.443179 -246.618477)
			(xy 342.489158 -246.640294) (xy 342.531042 -246.669204) (xy 342.567746 -246.704459) (xy 342.598319 -246.745145)
			(xy 342.62197 -246.790208) (xy 342.638086 -246.838482) (xy 342.64625 -246.888716) (xy 342.646762 -246.914162)
			(xy 342.954859 -246.914162) (xy 342.958954 -246.863434) (xy 342.971133 -246.81402) (xy 342.991081 -246.7672)
			(xy 343.018282 -246.724186) (xy 343.05203 -246.686092) (xy 343.091452 -246.653905) (xy 343.135526 -246.628459)
			(xy 343.183112 -246.610412) (xy 343.232976 -246.600232) (xy 343.283828 -246.598183) (xy 343.334349 -246.604317)
			(xy 343.383233 -246.618477) (xy 343.429212 -246.640294) (xy 343.471096 -246.669204) (xy 343.5078 -246.704459)
			(xy 343.538373 -246.745145) (xy 343.562024 -246.790208) (xy 343.57814 -246.838482) (xy 343.586304 -246.888716)
			(xy 343.586816 -246.914162) (xy 343.586304 -246.939608) (xy 343.57814 -246.989842) (xy 343.562024 -247.038116)
			(xy 343.538373 -247.083179) (xy 343.5078 -247.123865) (xy 343.471096 -247.15912) (xy 343.429212 -247.18803)
			(xy 343.383233 -247.209847) (xy 343.334349 -247.224007) (xy 343.283828 -247.230141) (xy 343.232976 -247.228092)
			(xy 343.183112 -247.217912) (xy 343.135526 -247.199865) (xy 343.091452 -247.174419) (xy 343.05203 -247.142232)
			(xy 343.018282 -247.104138) (xy 342.991081 -247.061124) (xy 342.971133 -247.014304) (xy 342.958954 -246.96489)
			(xy 342.954859 -246.914162) (xy 342.646762 -246.914162) (xy 342.64625 -246.939608) (xy 342.638086 -246.989842)
			(xy 342.62197 -247.038116) (xy 342.598319 -247.083179) (xy 342.567746 -247.123865) (xy 342.531042 -247.15912)
			(xy 342.489158 -247.18803) (xy 342.443179 -247.209847) (xy 342.394295 -247.224007) (xy 342.343774 -247.230141)
			(xy 342.292922 -247.228092) (xy 342.243058 -247.217912) (xy 342.195472 -247.199865) (xy 342.151398 -247.174419)
			(xy 342.111976 -247.142232) (xy 342.078228 -247.104138) (xy 342.051027 -247.061124) (xy 342.031079 -247.014304)
			(xy 342.0189 -246.96489) (xy 342.014805 -246.914162) (xy 341.696294 -246.914162) (xy 341.695799 -246.938769)
			(xy 341.687904 -246.987346) (xy 341.67232 -247.034027) (xy 341.649449 -247.077604) (xy 341.619884 -247.116948)
			(xy 341.584391 -247.15104) (xy 341.543888 -247.178996) (xy 341.499426 -247.200094) (xy 341.452155 -247.213786)
			(xy 341.4033 -247.219718) (xy 341.354125 -247.217737) (xy 341.305906 -247.207893) (xy 341.25989 -247.190441)
			(xy 341.217269 -247.165834) (xy 341.179148 -247.134709) (xy 341.146513 -247.097872) (xy 341.12021 -247.056276)
			(xy 341.100919 -247.011) (xy 341.089142 -246.963216) (xy 341.085182 -246.914162) (xy 340.766908 -246.914162)
			(xy 340.766396 -246.939608) (xy 340.758232 -246.989842) (xy 340.742116 -247.038116) (xy 340.718465 -247.083179)
			(xy 340.687892 -247.123865) (xy 340.651188 -247.15912) (xy 340.609304 -247.18803) (xy 340.563325 -247.209847)
			(xy 340.514441 -247.224007) (xy 340.46392 -247.230141) (xy 340.413068 -247.228092) (xy 340.363204 -247.217912)
			(xy 340.315618 -247.199865) (xy 340.271544 -247.174419) (xy 340.232122 -247.142232) (xy 340.198374 -247.104138)
			(xy 340.171173 -247.061124) (xy 340.151225 -247.014304) (xy 340.139046 -246.96489) (xy 340.134951 -246.914162)
			(xy 339.81644 -246.914162) (xy 339.815945 -246.938769) (xy 339.80805 -246.987346) (xy 339.792466 -247.034027)
			(xy 339.769595 -247.077604) (xy 339.74003 -247.116948) (xy 339.704537 -247.15104) (xy 339.664034 -247.178996)
			(xy 339.619572 -247.200094) (xy 339.572301 -247.213786) (xy 339.523446 -247.219718) (xy 339.474271 -247.217737)
			(xy 339.426052 -247.207893) (xy 339.380036 -247.190441) (xy 339.337415 -247.165834) (xy 339.299294 -247.134709)
			(xy 339.266659 -247.097872) (xy 339.240356 -247.056276) (xy 339.221065 -247.011) (xy 339.209288 -246.963216)
			(xy 339.205328 -246.914162) (xy 338.8868 -246.914162) (xy 338.886288 -246.939608) (xy 338.878124 -246.989842)
			(xy 338.862008 -247.038116) (xy 338.838357 -247.083179) (xy 338.807784 -247.123865) (xy 338.77108 -247.15912)
			(xy 338.729196 -247.18803) (xy 338.683217 -247.209847) (xy 338.634333 -247.224007) (xy 338.583812 -247.230141)
			(xy 338.53296 -247.228092) (xy 338.483096 -247.217912) (xy 338.43551 -247.199865) (xy 338.391436 -247.174419)
			(xy 338.352014 -247.142232) (xy 338.318266 -247.104138) (xy 338.291065 -247.061124) (xy 338.271117 -247.014304)
			(xy 338.258938 -246.96489) (xy 338.254843 -246.914162) (xy 338.06638 -246.914162) (xy 338.06638 -247.347994)
			(xy 338.066816 -247.35769) (xy 338.074005 -247.375701) (xy 338.08035 -247.383046) (xy 338.095082 -247.39854)
			(xy 338.098324 -247.40177) (xy 338.105734 -247.407136) (xy 338.109814 -247.409208) (xy 338.132674 -247.42013)
			(xy 338.140802 -247.4214) (xy 338.165 -247.425036) (xy 338.211894 -247.439007) (xy 338.25596 -247.460277)
			(xy 338.29607 -247.488303) (xy 338.331197 -247.522365) (xy 338.360443 -247.561594) (xy 338.383058 -247.604985)
			(xy 338.398465 -247.651426) (xy 338.406269 -247.699731) (xy 338.406269 -247.724168) (xy 338.724743 -247.724168)
			(xy 338.728838 -247.67344) (xy 338.741017 -247.624026) (xy 338.760965 -247.577206) (xy 338.788166 -247.534192)
			(xy 338.821914 -247.496098) (xy 338.861336 -247.463911) (xy 338.90541 -247.438465) (xy 338.952996 -247.420418)
			(xy 339.00286 -247.410238) (xy 339.053712 -247.408189) (xy 339.104233 -247.414323) (xy 339.153117 -247.428483)
			(xy 339.199096 -247.4503) (xy 339.24098 -247.47921) (xy 339.277684 -247.514465) (xy 339.308257 -247.555151)
			(xy 339.331908 -247.600214) (xy 339.348024 -247.648488) (xy 339.356188 -247.698722) (xy 339.3567 -247.724168)
			(xy 339.664797 -247.724168) (xy 339.668892 -247.67344) (xy 339.681071 -247.624026) (xy 339.701019 -247.577206)
			(xy 339.72822 -247.534192) (xy 339.761968 -247.496098) (xy 339.80139 -247.463911) (xy 339.845464 -247.438465)
			(xy 339.89305 -247.420418) (xy 339.942914 -247.410238) (xy 339.993766 -247.408189) (xy 340.044287 -247.414323)
			(xy 340.093171 -247.428483) (xy 340.13915 -247.4503) (xy 340.181034 -247.47921) (xy 340.217738 -247.514465)
			(xy 340.248311 -247.555151) (xy 340.271962 -247.600214) (xy 340.288078 -247.648488) (xy 340.296242 -247.698722)
			(xy 340.296754 -247.724168) (xy 340.615282 -247.724168) (xy 340.619242 -247.675114) (xy 340.631019 -247.62733)
			(xy 340.65031 -247.582054) (xy 340.676613 -247.540458) (xy 340.709248 -247.503621) (xy 340.747369 -247.472496)
			(xy 340.78999 -247.447889) (xy 340.836006 -247.430437) (xy 340.884225 -247.420593) (xy 340.9334 -247.418612)
			(xy 340.982255 -247.424544) (xy 341.029526 -247.438236) (xy 341.073988 -247.459334) (xy 341.114491 -247.48729)
			(xy 341.149984 -247.521382) (xy 341.179549 -247.560726) (xy 341.20242 -247.604303) (xy 341.218004 -247.650984)
			(xy 341.225899 -247.699561) (xy 341.226394 -247.724168) (xy 341.544905 -247.724168) (xy 341.549 -247.67344)
			(xy 341.561179 -247.624026) (xy 341.581127 -247.577206) (xy 341.608328 -247.534192) (xy 341.642076 -247.496098)
			(xy 341.681498 -247.463911) (xy 341.725572 -247.438465) (xy 341.773158 -247.420418) (xy 341.823022 -247.410238)
			(xy 341.873874 -247.408189) (xy 341.924395 -247.414323) (xy 341.973279 -247.428483) (xy 342.019258 -247.4503)
			(xy 342.061142 -247.47921) (xy 342.097846 -247.514465) (xy 342.128419 -247.555151) (xy 342.15207 -247.600214)
			(xy 342.168186 -247.648488) (xy 342.17635 -247.698722) (xy 342.176862 -247.724168) (xy 342.49539 -247.724168)
			(xy 342.49935 -247.675114) (xy 342.511127 -247.62733) (xy 342.530418 -247.582054) (xy 342.556721 -247.540458)
			(xy 342.589356 -247.503621) (xy 342.627477 -247.472496) (xy 342.670098 -247.447889) (xy 342.716114 -247.430437)
			(xy 342.764333 -247.420593) (xy 342.813508 -247.418612) (xy 342.862363 -247.424544) (xy 342.909634 -247.438236)
			(xy 342.954096 -247.459334) (xy 342.994599 -247.48729) (xy 343.030092 -247.521382) (xy 343.059657 -247.560726)
			(xy 343.082528 -247.604303) (xy 343.098112 -247.650984) (xy 343.106007 -247.699561) (xy 343.106502 -247.724168)
			(xy 343.106007 -247.748775) (xy 343.098112 -247.797352) (xy 343.082528 -247.844033) (xy 343.059657 -247.88761)
			(xy 343.030092 -247.926954) (xy 342.994599 -247.961046) (xy 342.954096 -247.989002) (xy 342.909634 -248.0101)
			(xy 342.862363 -248.023792) (xy 342.813508 -248.029724) (xy 342.764333 -248.027743) (xy 342.716114 -248.017899)
			(xy 342.670098 -248.000447) (xy 342.627477 -247.97584) (xy 342.589356 -247.944715) (xy 342.556721 -247.907878)
			(xy 342.530418 -247.866282) (xy 342.511127 -247.821006) (xy 342.49935 -247.773222) (xy 342.49539 -247.724168)
			(xy 342.176862 -247.724168) (xy 342.17635 -247.749614) (xy 342.168186 -247.799848) (xy 342.15207 -247.848122)
			(xy 342.128419 -247.893185) (xy 342.097846 -247.933871) (xy 342.061142 -247.969126) (xy 342.019258 -247.998036)
			(xy 341.973279 -248.019853) (xy 341.924395 -248.034013) (xy 341.873874 -248.040147) (xy 341.823022 -248.038098)
			(xy 341.773158 -248.027918) (xy 341.725572 -248.009871) (xy 341.681498 -247.984425) (xy 341.642076 -247.952238)
			(xy 341.608328 -247.914144) (xy 341.581127 -247.87113) (xy 341.561179 -247.82431) (xy 341.549 -247.774896)
			(xy 341.544905 -247.724168) (xy 341.226394 -247.724168) (xy 341.225899 -247.748775) (xy 341.218004 -247.797352)
			(xy 341.20242 -247.844033) (xy 341.179549 -247.88761) (xy 341.149984 -247.926954) (xy 341.114491 -247.961046)
			(xy 341.073988 -247.989002) (xy 341.029526 -248.0101) (xy 340.982255 -248.023792) (xy 340.9334 -248.029724)
			(xy 340.884225 -248.027743) (xy 340.836006 -248.017899) (xy 340.78999 -248.000447) (xy 340.747369 -247.97584)
			(xy 340.709248 -247.944715) (xy 340.676613 -247.907878) (xy 340.65031 -247.866282) (xy 340.631019 -247.821006)
			(xy 340.619242 -247.773222) (xy 340.615282 -247.724168) (xy 340.296754 -247.724168) (xy 340.296242 -247.749614)
			(xy 340.288078 -247.799848) (xy 340.271962 -247.848122) (xy 340.248311 -247.893185) (xy 340.217738 -247.933871)
			(xy 340.181034 -247.969126) (xy 340.13915 -247.998036) (xy 340.093171 -248.019853) (xy 340.044287 -248.034013)
			(xy 339.993766 -248.040147) (xy 339.942914 -248.038098) (xy 339.89305 -248.027918) (xy 339.845464 -248.009871)
			(xy 339.80139 -247.984425) (xy 339.761968 -247.952238) (xy 339.72822 -247.914144) (xy 339.701019 -247.87113)
			(xy 339.681071 -247.82431) (xy 339.668892 -247.774896) (xy 339.664797 -247.724168) (xy 339.3567 -247.724168)
			(xy 339.356188 -247.749614) (xy 339.348024 -247.799848) (xy 339.331908 -247.848122) (xy 339.308257 -247.893185)
			(xy 339.277684 -247.933871) (xy 339.24098 -247.969126) (xy 339.199096 -247.998036) (xy 339.153117 -248.019853)
			(xy 339.104233 -248.034013) (xy 339.053712 -248.040147) (xy 339.00286 -248.038098) (xy 338.952996 -248.027918)
			(xy 338.90541 -248.009871) (xy 338.861336 -247.984425) (xy 338.821914 -247.952238) (xy 338.788166 -247.914144)
			(xy 338.760965 -247.87113) (xy 338.741017 -247.82431) (xy 338.728838 -247.774896) (xy 338.724743 -247.724168)
			(xy 338.406269 -247.724168) (xy 338.40627 -247.748661) (xy 338.398467 -247.796966) (xy 338.383062 -247.843408)
			(xy 338.360447 -247.886799) (xy 338.331202 -247.926028) (xy 338.296076 -247.960092) (xy 338.255967 -247.988118)
			(xy 338.211902 -248.00939) (xy 338.165008 -248.023362) (xy 338.140802 -248.026936) (xy 338.132674 -248.028206)
			(xy 338.109814 -248.039128) (xy 338.105727 -248.041188) (xy 338.098313 -248.046554) (xy 338.095082 -248.049796)
			(xy 338.08035 -248.06529) (xy 338.073962 -248.072609) (xy 338.066766 -248.090636) (xy 338.06638 -248.100342)
			(xy 338.06638 -248.534174) (xy 338.254843 -248.534174) (xy 338.258938 -248.483446) (xy 338.271117 -248.434032)
			(xy 338.291065 -248.387212) (xy 338.318266 -248.344198) (xy 338.352014 -248.306104) (xy 338.391436 -248.273917)
			(xy 338.43551 -248.248471) (xy 338.483096 -248.230424) (xy 338.53296 -248.220244) (xy 338.583812 -248.218195)
			(xy 338.634333 -248.224329) (xy 338.683217 -248.238489) (xy 338.729196 -248.260306) (xy 338.77108 -248.289216)
			(xy 338.807784 -248.324471) (xy 338.838357 -248.365157) (xy 338.862008 -248.41022) (xy 338.878124 -248.458494)
			(xy 338.886288 -248.508728) (xy 338.8868 -248.534174) (xy 339.205328 -248.534174) (xy 339.209288 -248.48512)
			(xy 339.221065 -248.437336) (xy 339.240356 -248.39206) (xy 339.266659 -248.350464) (xy 339.299294 -248.313627)
			(xy 339.337415 -248.282502) (xy 339.380036 -248.257895) (xy 339.426052 -248.240443) (xy 339.474271 -248.230599)
			(xy 339.523446 -248.228618) (xy 339.572301 -248.23455) (xy 339.619572 -248.248242) (xy 339.664034 -248.26934)
			(xy 339.704537 -248.297296) (xy 339.74003 -248.331388) (xy 339.769595 -248.370732) (xy 339.792466 -248.414309)
			(xy 339.80805 -248.46099) (xy 339.815945 -248.509567) (xy 339.81644 -248.534174) (xy 340.134951 -248.534174)
			(xy 340.139046 -248.483446) (xy 340.151225 -248.434032) (xy 340.171173 -248.387212) (xy 340.198374 -248.344198)
			(xy 340.232122 -248.306104) (xy 340.271544 -248.273917) (xy 340.315618 -248.248471) (xy 340.363204 -248.230424)
			(xy 340.413068 -248.220244) (xy 340.46392 -248.218195) (xy 340.514441 -248.224329) (xy 340.563325 -248.238489)
			(xy 340.609304 -248.260306) (xy 340.651188 -248.289216) (xy 340.687892 -248.324471) (xy 340.718465 -248.365157)
			(xy 340.742116 -248.41022) (xy 340.758232 -248.458494) (xy 340.766396 -248.508728) (xy 340.766908 -248.534174)
			(xy 341.085182 -248.534174) (xy 341.089142 -248.48512) (xy 341.100919 -248.437336) (xy 341.12021 -248.39206)
			(xy 341.146513 -248.350464) (xy 341.179148 -248.313627) (xy 341.217269 -248.282502) (xy 341.25989 -248.257895)
			(xy 341.305906 -248.240443) (xy 341.354125 -248.230599) (xy 341.4033 -248.228618) (xy 341.452155 -248.23455)
			(xy 341.499426 -248.248242) (xy 341.543888 -248.26934) (xy 341.584391 -248.297296) (xy 341.619884 -248.331388)
			(xy 341.649449 -248.370732) (xy 341.67232 -248.414309) (xy 341.687904 -248.46099) (xy 341.695799 -248.509567)
			(xy 341.696294 -248.534174) (xy 342.014805 -248.534174) (xy 342.0189 -248.483446) (xy 342.031079 -248.434032)
			(xy 342.051027 -248.387212) (xy 342.078228 -248.344198) (xy 342.111976 -248.306104) (xy 342.151398 -248.273917)
			(xy 342.195472 -248.248471) (xy 342.243058 -248.230424) (xy 342.292922 -248.220244) (xy 342.343774 -248.218195)
			(xy 342.394295 -248.224329) (xy 342.443179 -248.238489) (xy 342.489158 -248.260306) (xy 342.531042 -248.289216)
			(xy 342.567746 -248.324471) (xy 342.598319 -248.365157) (xy 342.62197 -248.41022) (xy 342.638086 -248.458494)
			(xy 342.64625 -248.508728) (xy 342.646762 -248.534174) (xy 342.954859 -248.534174) (xy 342.958954 -248.483446)
			(xy 342.971133 -248.434032) (xy 342.991081 -248.387212) (xy 343.018282 -248.344198) (xy 343.05203 -248.306104)
			(xy 343.091452 -248.273917) (xy 343.135526 -248.248471) (xy 343.183112 -248.230424) (xy 343.232976 -248.220244)
			(xy 343.283828 -248.218195) (xy 343.334349 -248.224329) (xy 343.383233 -248.238489) (xy 343.429212 -248.260306)
			(xy 343.471096 -248.289216) (xy 343.5078 -248.324471) (xy 343.538373 -248.365157) (xy 343.562024 -248.41022)
			(xy 343.57814 -248.458494) (xy 343.586304 -248.508728) (xy 343.586816 -248.534174) (xy 343.586304 -248.55962)
			(xy 343.57814 -248.609854) (xy 343.562024 -248.658128) (xy 343.538373 -248.703191) (xy 343.5078 -248.743877)
			(xy 343.471096 -248.779132) (xy 343.429212 -248.808042) (xy 343.383233 -248.829859) (xy 343.334349 -248.844019)
			(xy 343.283828 -248.850153) (xy 343.232976 -248.848104) (xy 343.183112 -248.837924) (xy 343.135526 -248.819877)
			(xy 343.091452 -248.794431) (xy 343.05203 -248.762244) (xy 343.018282 -248.72415) (xy 342.991081 -248.681136)
			(xy 342.971133 -248.634316) (xy 342.958954 -248.584902) (xy 342.954859 -248.534174) (xy 342.646762 -248.534174)
			(xy 342.64625 -248.55962) (xy 342.638086 -248.609854) (xy 342.62197 -248.658128) (xy 342.598319 -248.703191)
			(xy 342.567746 -248.743877) (xy 342.531042 -248.779132) (xy 342.489158 -248.808042) (xy 342.443179 -248.829859)
			(xy 342.394295 -248.844019) (xy 342.343774 -248.850153) (xy 342.292922 -248.848104) (xy 342.243058 -248.837924)
			(xy 342.195472 -248.819877) (xy 342.151398 -248.794431) (xy 342.111976 -248.762244) (xy 342.078228 -248.72415)
			(xy 342.051027 -248.681136) (xy 342.031079 -248.634316) (xy 342.0189 -248.584902) (xy 342.014805 -248.534174)
			(xy 341.696294 -248.534174) (xy 341.695799 -248.558781) (xy 341.687904 -248.607358) (xy 341.67232 -248.654039)
			(xy 341.649449 -248.697616) (xy 341.619884 -248.73696) (xy 341.584391 -248.771052) (xy 341.543888 -248.799008)
			(xy 341.499426 -248.820106) (xy 341.452155 -248.833798) (xy 341.4033 -248.83973) (xy 341.354125 -248.837749)
			(xy 341.305906 -248.827905) (xy 341.25989 -248.810453) (xy 341.217269 -248.785846) (xy 341.179148 -248.754721)
			(xy 341.146513 -248.717884) (xy 341.12021 -248.676288) (xy 341.100919 -248.631012) (xy 341.089142 -248.583228)
			(xy 341.085182 -248.534174) (xy 340.766908 -248.534174) (xy 340.766396 -248.55962) (xy 340.758232 -248.609854)
			(xy 340.742116 -248.658128) (xy 340.718465 -248.703191) (xy 340.687892 -248.743877) (xy 340.651188 -248.779132)
			(xy 340.609304 -248.808042) (xy 340.563325 -248.829859) (xy 340.514441 -248.844019) (xy 340.46392 -248.850153)
			(xy 340.413068 -248.848104) (xy 340.363204 -248.837924) (xy 340.315618 -248.819877) (xy 340.271544 -248.794431)
			(xy 340.232122 -248.762244) (xy 340.198374 -248.72415) (xy 340.171173 -248.681136) (xy 340.151225 -248.634316)
			(xy 340.139046 -248.584902) (xy 340.134951 -248.534174) (xy 339.81644 -248.534174) (xy 339.815945 -248.558781)
			(xy 339.80805 -248.607358) (xy 339.792466 -248.654039) (xy 339.769595 -248.697616) (xy 339.74003 -248.73696)
			(xy 339.704537 -248.771052) (xy 339.664034 -248.799008) (xy 339.619572 -248.820106) (xy 339.572301 -248.833798)
			(xy 339.523446 -248.83973) (xy 339.474271 -248.837749) (xy 339.426052 -248.827905) (xy 339.380036 -248.810453)
			(xy 339.337415 -248.785846) (xy 339.299294 -248.754721) (xy 339.266659 -248.717884) (xy 339.240356 -248.676288)
			(xy 339.221065 -248.631012) (xy 339.209288 -248.583228) (xy 339.205328 -248.534174) (xy 338.8868 -248.534174)
			(xy 338.886288 -248.55962) (xy 338.878124 -248.609854) (xy 338.862008 -248.658128) (xy 338.838357 -248.703191)
			(xy 338.807784 -248.743877) (xy 338.77108 -248.779132) (xy 338.729196 -248.808042) (xy 338.683217 -248.829859)
			(xy 338.634333 -248.844019) (xy 338.583812 -248.850153) (xy 338.53296 -248.848104) (xy 338.483096 -248.837924)
			(xy 338.43551 -248.819877) (xy 338.391436 -248.794431) (xy 338.352014 -248.762244) (xy 338.318266 -248.72415)
			(xy 338.291065 -248.681136) (xy 338.271117 -248.634316) (xy 338.258938 -248.584902) (xy 338.254843 -248.534174)
			(xy 338.06638 -248.534174) (xy 338.06638 -248.968006) (xy 338.066818 -248.977701) (xy 338.07401 -248.995709)
			(xy 338.08035 -249.003058) (xy 338.095082 -249.018552) (xy 338.09832 -249.021786) (xy 338.105727 -249.027161)
			(xy 338.109814 -249.02922) (xy 338.132674 -249.040142) (xy 338.140802 -249.041412) (xy 338.164999 -249.045048)
			(xy 338.211891 -249.059019) (xy 338.255955 -249.080289) (xy 338.296063 -249.108313) (xy 338.331189 -249.142374)
			(xy 338.360433 -249.181602) (xy 338.383048 -249.224991) (xy 338.398454 -249.271431) (xy 338.406257 -249.319733)
			(xy 338.406257 -249.34418) (xy 338.735174 -249.34418) (xy 338.739134 -249.295126) (xy 338.750911 -249.247342)
			(xy 338.770202 -249.202066) (xy 338.796505 -249.16047) (xy 338.82914 -249.123633) (xy 338.867261 -249.092508)
			(xy 338.909882 -249.067901) (xy 338.955898 -249.050449) (xy 339.004117 -249.040605) (xy 339.053292 -249.038624)
			(xy 339.102147 -249.044556) (xy 339.149418 -249.058248) (xy 339.19388 -249.079346) (xy 339.234383 -249.107302)
			(xy 339.269876 -249.141394) (xy 339.299441 -249.180738) (xy 339.322312 -249.224315) (xy 339.337896 -249.270996)
			(xy 339.345791 -249.319573) (xy 339.346286 -249.34418) (xy 339.664797 -249.34418) (xy 339.668892 -249.293452)
			(xy 339.681071 -249.244038) (xy 339.701019 -249.197218) (xy 339.72822 -249.154204) (xy 339.761968 -249.11611)
			(xy 339.80139 -249.083923) (xy 339.845464 -249.058477) (xy 339.89305 -249.04043) (xy 339.942914 -249.03025)
			(xy 339.993766 -249.028201) (xy 340.044287 -249.034335) (xy 340.093171 -249.048495) (xy 340.13915 -249.070312)
			(xy 340.181034 -249.099222) (xy 340.217738 -249.134477) (xy 340.248311 -249.175163) (xy 340.271962 -249.220226)
			(xy 340.288078 -249.2685) (xy 340.296242 -249.318734) (xy 340.296754 -249.34418) (xy 340.615282 -249.34418)
			(xy 340.619242 -249.295126) (xy 340.631019 -249.247342) (xy 340.65031 -249.202066) (xy 340.676613 -249.16047)
			(xy 340.709248 -249.123633) (xy 340.747369 -249.092508) (xy 340.78999 -249.067901) (xy 340.836006 -249.050449)
			(xy 340.884225 -249.040605) (xy 340.9334 -249.038624) (xy 340.982255 -249.044556) (xy 341.029526 -249.058248)
			(xy 341.073988 -249.079346) (xy 341.114491 -249.107302) (xy 341.149984 -249.141394) (xy 341.179549 -249.180738)
			(xy 341.20242 -249.224315) (xy 341.218004 -249.270996) (xy 341.225899 -249.319573) (xy 341.226394 -249.34418)
			(xy 341.555336 -249.34418) (xy 341.559296 -249.295126) (xy 341.571073 -249.247342) (xy 341.590364 -249.202066)
			(xy 341.616667 -249.16047) (xy 341.649302 -249.123633) (xy 341.687423 -249.092508) (xy 341.730044 -249.067901)
			(xy 341.77606 -249.050449) (xy 341.824279 -249.040605) (xy 341.873454 -249.038624) (xy 341.922309 -249.044556)
			(xy 341.96958 -249.058248) (xy 342.014042 -249.079346) (xy 342.054545 -249.107302) (xy 342.090038 -249.141394)
			(xy 342.119603 -249.180738) (xy 342.142474 -249.224315) (xy 342.158058 -249.270996) (xy 342.165953 -249.319573)
			(xy 342.166448 -249.34418) (xy 342.49539 -249.34418) (xy 342.49935 -249.295126) (xy 342.511127 -249.247342)
			(xy 342.530418 -249.202066) (xy 342.556721 -249.16047) (xy 342.589356 -249.123633) (xy 342.627477 -249.092508)
			(xy 342.670098 -249.067901) (xy 342.716114 -249.050449) (xy 342.764333 -249.040605) (xy 342.813508 -249.038624)
			(xy 342.862363 -249.044556) (xy 342.909634 -249.058248) (xy 342.954096 -249.079346) (xy 342.994599 -249.107302)
			(xy 343.030092 -249.141394) (xy 343.059657 -249.180738) (xy 343.082528 -249.224315) (xy 343.098112 -249.270996)
			(xy 343.106007 -249.319573) (xy 343.106502 -249.34418) (xy 343.424759 -249.34418) (xy 343.428854 -249.293452)
			(xy 343.441033 -249.244038) (xy 343.460981 -249.197218) (xy 343.488182 -249.154204) (xy 343.52193 -249.11611)
			(xy 343.561352 -249.083923) (xy 343.605426 -249.058477) (xy 343.653012 -249.04043) (xy 343.702876 -249.03025)
			(xy 343.753728 -249.028201) (xy 343.804249 -249.034335) (xy 343.853133 -249.048495) (xy 343.899112 -249.070312)
			(xy 343.940996 -249.099222) (xy 343.9777 -249.134477) (xy 344.008273 -249.175163) (xy 344.031924 -249.220226)
			(xy 344.04804 -249.2685) (xy 344.056204 -249.318734) (xy 344.056716 -249.34418) (xy 344.056204 -249.369626)
			(xy 344.04804 -249.41986) (xy 344.031924 -249.468134) (xy 344.008273 -249.513197) (xy 343.9777 -249.553883)
			(xy 343.940996 -249.589138) (xy 343.899112 -249.618048) (xy 343.853133 -249.639865) (xy 343.804249 -249.654025)
			(xy 343.753728 -249.660159) (xy 343.702876 -249.65811) (xy 343.653012 -249.64793) (xy 343.605426 -249.629883)
			(xy 343.561352 -249.604437) (xy 343.52193 -249.57225) (xy 343.488182 -249.534156) (xy 343.460981 -249.491142)
			(xy 343.441033 -249.444322) (xy 343.428854 -249.394908) (xy 343.424759 -249.34418) (xy 343.106502 -249.34418)
			(xy 343.106007 -249.368787) (xy 343.098112 -249.417364) (xy 343.082528 -249.464045) (xy 343.059657 -249.507622)
			(xy 343.030092 -249.546966) (xy 342.994599 -249.581058) (xy 342.954096 -249.609014) (xy 342.909634 -249.630112)
			(xy 342.862363 -249.643804) (xy 342.813508 -249.649736) (xy 342.764333 -249.647755) (xy 342.716114 -249.637911)
			(xy 342.670098 -249.620459) (xy 342.627477 -249.595852) (xy 342.589356 -249.564727) (xy 342.556721 -249.52789)
			(xy 342.530418 -249.486294) (xy 342.511127 -249.441018) (xy 342.49935 -249.393234) (xy 342.49539 -249.34418)
			(xy 342.166448 -249.34418) (xy 342.165953 -249.368787) (xy 342.158058 -249.417364) (xy 342.142474 -249.464045)
			(xy 342.119603 -249.507622) (xy 342.090038 -249.546966) (xy 342.054545 -249.581058) (xy 342.014042 -249.609014)
			(xy 341.96958 -249.630112) (xy 341.922309 -249.643804) (xy 341.873454 -249.649736) (xy 341.824279 -249.647755)
			(xy 341.77606 -249.637911) (xy 341.730044 -249.620459) (xy 341.687423 -249.595852) (xy 341.649302 -249.564727)
			(xy 341.616667 -249.52789) (xy 341.590364 -249.486294) (xy 341.571073 -249.441018) (xy 341.559296 -249.393234)
			(xy 341.555336 -249.34418) (xy 341.226394 -249.34418) (xy 341.225899 -249.368787) (xy 341.218004 -249.417364)
			(xy 341.20242 -249.464045) (xy 341.179549 -249.507622) (xy 341.149984 -249.546966) (xy 341.114491 -249.581058)
			(xy 341.073988 -249.609014) (xy 341.029526 -249.630112) (xy 340.982255 -249.643804) (xy 340.9334 -249.649736)
			(xy 340.884225 -249.647755) (xy 340.836006 -249.637911) (xy 340.78999 -249.620459) (xy 340.747369 -249.595852)
			(xy 340.709248 -249.564727) (xy 340.676613 -249.52789) (xy 340.65031 -249.486294) (xy 340.631019 -249.441018)
			(xy 340.619242 -249.393234) (xy 340.615282 -249.34418) (xy 340.296754 -249.34418) (xy 340.296242 -249.369626)
			(xy 340.288078 -249.41986) (xy 340.271962 -249.468134) (xy 340.248311 -249.513197) (xy 340.217738 -249.553883)
			(xy 340.181034 -249.589138) (xy 340.13915 -249.618048) (xy 340.093171 -249.639865) (xy 340.044287 -249.654025)
			(xy 339.993766 -249.660159) (xy 339.942914 -249.65811) (xy 339.89305 -249.64793) (xy 339.845464 -249.629883)
			(xy 339.80139 -249.604437) (xy 339.761968 -249.57225) (xy 339.72822 -249.534156) (xy 339.701019 -249.491142)
			(xy 339.681071 -249.444322) (xy 339.668892 -249.394908) (xy 339.664797 -249.34418) (xy 339.346286 -249.34418)
			(xy 339.345791 -249.368787) (xy 339.337896 -249.417364) (xy 339.322312 -249.464045) (xy 339.299441 -249.507622)
			(xy 339.269876 -249.546966) (xy 339.234383 -249.581058) (xy 339.19388 -249.609014) (xy 339.149418 -249.630112)
			(xy 339.102147 -249.643804) (xy 339.053292 -249.649736) (xy 339.004117 -249.647755) (xy 338.955898 -249.637911)
			(xy 338.909882 -249.620459) (xy 338.867261 -249.595852) (xy 338.82914 -249.564727) (xy 338.796505 -249.52789)
			(xy 338.770202 -249.486294) (xy 338.750911 -249.441018) (xy 338.739134 -249.393234) (xy 338.735174 -249.34418)
			(xy 338.406257 -249.34418) (xy 338.406258 -249.368662) (xy 338.398455 -249.416964) (xy 338.38305 -249.463405)
			(xy 338.360436 -249.506794) (xy 338.331192 -249.546022) (xy 338.296067 -249.580084) (xy 338.25596 -249.608109)
			(xy 338.211896 -249.629379) (xy 338.165004 -249.64335) (xy 338.140802 -249.646948) (xy 338.132674 -249.648218)
			(xy 338.109814 -249.65914) (xy 338.105727 -249.6612) (xy 338.098314 -249.666567) (xy 338.095082 -249.669808)
			(xy 338.08035 -249.685302) (xy 338.073964 -249.692622) (xy 338.066772 -249.710649) (xy 338.06638 -249.720354)
			(xy 338.06638 -250.154186) (xy 338.265274 -250.154186) (xy 338.269234 -250.105132) (xy 338.281011 -250.057348)
			(xy 338.300302 -250.012072) (xy 338.326605 -249.970476) (xy 338.35924 -249.933639) (xy 338.397361 -249.902514)
			(xy 338.439982 -249.877907) (xy 338.485998 -249.860455) (xy 338.534217 -249.850611) (xy 338.583392 -249.84863)
			(xy 338.632247 -249.854562) (xy 338.679518 -249.868254) (xy 338.72398 -249.889352) (xy 338.764483 -249.917308)
			(xy 338.799976 -249.9514) (xy 338.829541 -249.990744) (xy 338.852412 -250.034321) (xy 338.867996 -250.081002)
			(xy 338.875891 -250.129579) (xy 338.876386 -250.154186) (xy 339.205328 -250.154186) (xy 339.209288 -250.105132)
			(xy 339.221065 -250.057348) (xy 339.240356 -250.012072) (xy 339.266659 -249.970476) (xy 339.299294 -249.933639)
			(xy 339.337415 -249.902514) (xy 339.380036 -249.877907) (xy 339.426052 -249.860455) (xy 339.474271 -249.850611)
			(xy 339.523446 -249.84863) (xy 339.572301 -249.854562) (xy 339.619572 -249.868254) (xy 339.664034 -249.889352)
			(xy 339.704537 -249.917308) (xy 339.74003 -249.9514) (xy 339.769595 -249.990744) (xy 339.792466 -250.034321)
			(xy 339.80805 -250.081002) (xy 339.815945 -250.129579) (xy 339.81644 -250.154186) (xy 340.134951 -250.154186)
			(xy 340.139046 -250.103458) (xy 340.151225 -250.054044) (xy 340.171173 -250.007224) (xy 340.198374 -249.96421)
			(xy 340.232122 -249.926116) (xy 340.271544 -249.893929) (xy 340.315618 -249.868483) (xy 340.363204 -249.850436)
			(xy 340.413068 -249.840256) (xy 340.46392 -249.838207) (xy 340.514441 -249.844341) (xy 340.563325 -249.858501)
			(xy 340.609304 -249.880318) (xy 340.651188 -249.909228) (xy 340.687892 -249.944483) (xy 340.718465 -249.985169)
			(xy 340.742116 -250.030232) (xy 340.758232 -250.078506) (xy 340.766396 -250.12874) (xy 340.766908 -250.154186)
			(xy 341.085182 -250.154186) (xy 341.089142 -250.105132) (xy 341.100919 -250.057348) (xy 341.12021 -250.012072)
			(xy 341.146513 -249.970476) (xy 341.179148 -249.933639) (xy 341.217269 -249.902514) (xy 341.25989 -249.877907)
			(xy 341.305906 -249.860455) (xy 341.354125 -249.850611) (xy 341.4033 -249.84863) (xy 341.452155 -249.854562)
			(xy 341.499426 -249.868254) (xy 341.543888 -249.889352) (xy 341.584391 -249.917308) (xy 341.619884 -249.9514)
			(xy 341.649449 -249.990744) (xy 341.67232 -250.034321) (xy 341.687904 -250.081002) (xy 341.695799 -250.129579)
			(xy 341.696294 -250.154186) (xy 342.025236 -250.154186) (xy 342.029196 -250.105132) (xy 342.040973 -250.057348)
			(xy 342.060264 -250.012072) (xy 342.086567 -249.970476) (xy 342.119202 -249.933639) (xy 342.157323 -249.902514)
			(xy 342.199944 -249.877907) (xy 342.24596 -249.860455) (xy 342.294179 -249.850611) (xy 342.343354 -249.84863)
			(xy 342.392209 -249.854562) (xy 342.43948 -249.868254) (xy 342.483942 -249.889352) (xy 342.524445 -249.917308)
			(xy 342.559938 -249.9514) (xy 342.589503 -249.990744) (xy 342.612374 -250.034321) (xy 342.627958 -250.081002)
			(xy 342.635853 -250.129579) (xy 342.636348 -250.154186) (xy 342.954859 -250.154186) (xy 342.958954 -250.103458)
			(xy 342.971133 -250.054044) (xy 342.991081 -250.007224) (xy 343.018282 -249.96421) (xy 343.05203 -249.926116)
			(xy 343.091452 -249.893929) (xy 343.135526 -249.868483) (xy 343.183112 -249.850436) (xy 343.232976 -249.840256)
			(xy 343.283828 -249.838207) (xy 343.334349 -249.844341) (xy 343.383233 -249.858501) (xy 343.429212 -249.880318)
			(xy 343.471096 -249.909228) (xy 343.5078 -249.944483) (xy 343.538373 -249.985169) (xy 343.562024 -250.030232)
			(xy 343.57814 -250.078506) (xy 343.586304 -250.12874) (xy 343.586816 -250.154186) (xy 343.905344 -250.154186)
			(xy 343.909304 -250.105132) (xy 343.921081 -250.057348) (xy 343.940372 -250.012072) (xy 343.966675 -249.970476)
			(xy 343.99931 -249.933639) (xy 344.037431 -249.902514) (xy 344.080052 -249.877907) (xy 344.126068 -249.860455)
			(xy 344.174287 -249.850611) (xy 344.223462 -249.84863) (xy 344.272317 -249.854562) (xy 344.319588 -249.868254)
			(xy 344.36405 -249.889352) (xy 344.404553 -249.917308) (xy 344.440046 -249.9514) (xy 344.469611 -249.990744)
			(xy 344.492482 -250.034321) (xy 344.508066 -250.081002) (xy 344.515961 -250.129579) (xy 344.516456 -250.154186)
			(xy 345.785198 -250.154186) (xy 345.789158 -250.105132) (xy 345.800935 -250.057348) (xy 345.820226 -250.012072)
			(xy 345.846529 -249.970476) (xy 345.879164 -249.933639) (xy 345.917285 -249.902514) (xy 345.959906 -249.877907)
			(xy 346.005922 -249.860455) (xy 346.054141 -249.850611) (xy 346.103316 -249.84863) (xy 346.152171 -249.854562)
			(xy 346.199442 -249.868254) (xy 346.243904 -249.889352) (xy 346.284407 -249.917308) (xy 346.3199 -249.9514)
			(xy 346.349465 -249.990744) (xy 346.372336 -250.034321) (xy 346.38792 -250.081002) (xy 346.395815 -250.129579)
			(xy 346.39631 -250.154186) (xy 346.395815 -250.178793) (xy 346.38792 -250.22737) (xy 346.372336 -250.274051)
			(xy 346.349465 -250.317628) (xy 346.3199 -250.356972) (xy 346.284407 -250.391064) (xy 346.243904 -250.41902)
			(xy 346.199442 -250.440118) (xy 346.152171 -250.45381) (xy 346.103316 -250.459742) (xy 346.054141 -250.457761)
			(xy 346.005922 -250.447917) (xy 345.959906 -250.430465) (xy 345.917285 -250.405858) (xy 345.879164 -250.374733)
			(xy 345.846529 -250.337896) (xy 345.820226 -250.2963) (xy 345.800935 -250.251024) (xy 345.789158 -250.20324)
			(xy 345.785198 -250.154186) (xy 344.516456 -250.154186) (xy 344.515961 -250.178793) (xy 344.508066 -250.22737)
			(xy 344.492482 -250.274051) (xy 344.469611 -250.317628) (xy 344.440046 -250.356972) (xy 344.404553 -250.391064)
			(xy 344.36405 -250.41902) (xy 344.319588 -250.440118) (xy 344.272317 -250.45381) (xy 344.223462 -250.459742)
			(xy 344.174287 -250.457761) (xy 344.126068 -250.447917) (xy 344.080052 -250.430465) (xy 344.037431 -250.405858)
			(xy 343.99931 -250.374733) (xy 343.966675 -250.337896) (xy 343.940372 -250.2963) (xy 343.921081 -250.251024)
			(xy 343.909304 -250.20324) (xy 343.905344 -250.154186) (xy 343.586816 -250.154186) (xy 343.586304 -250.179632)
			(xy 343.57814 -250.229866) (xy 343.562024 -250.27814) (xy 343.538373 -250.323203) (xy 343.5078 -250.363889)
			(xy 343.471096 -250.399144) (xy 343.429212 -250.428054) (xy 343.383233 -250.449871) (xy 343.334349 -250.464031)
			(xy 343.283828 -250.470165) (xy 343.232976 -250.468116) (xy 343.183112 -250.457936) (xy 343.135526 -250.439889)
			(xy 343.091452 -250.414443) (xy 343.05203 -250.382256) (xy 343.018282 -250.344162) (xy 342.991081 -250.301148)
			(xy 342.971133 -250.254328) (xy 342.958954 -250.204914) (xy 342.954859 -250.154186) (xy 342.636348 -250.154186)
			(xy 342.635853 -250.178793) (xy 342.627958 -250.22737) (xy 342.612374 -250.274051) (xy 342.589503 -250.317628)
			(xy 342.559938 -250.356972) (xy 342.524445 -250.391064) (xy 342.483942 -250.41902) (xy 342.43948 -250.440118)
			(xy 342.392209 -250.45381) (xy 342.343354 -250.459742) (xy 342.294179 -250.457761) (xy 342.24596 -250.447917)
			(xy 342.199944 -250.430465) (xy 342.157323 -250.405858) (xy 342.119202 -250.374733) (xy 342.086567 -250.337896)
			(xy 342.060264 -250.2963) (xy 342.040973 -250.251024) (xy 342.029196 -250.20324) (xy 342.025236 -250.154186)
			(xy 341.696294 -250.154186) (xy 341.695799 -250.178793) (xy 341.687904 -250.22737) (xy 341.67232 -250.274051)
			(xy 341.649449 -250.317628) (xy 341.619884 -250.356972) (xy 341.584391 -250.391064) (xy 341.543888 -250.41902)
			(xy 341.499426 -250.440118) (xy 341.452155 -250.45381) (xy 341.4033 -250.459742) (xy 341.354125 -250.457761)
			(xy 341.305906 -250.447917) (xy 341.25989 -250.430465) (xy 341.217269 -250.405858) (xy 341.179148 -250.374733)
			(xy 341.146513 -250.337896) (xy 341.12021 -250.2963) (xy 341.100919 -250.251024) (xy 341.089142 -250.20324)
			(xy 341.085182 -250.154186) (xy 340.766908 -250.154186) (xy 340.766396 -250.179632) (xy 340.758232 -250.229866)
			(xy 340.742116 -250.27814) (xy 340.718465 -250.323203) (xy 340.687892 -250.363889) (xy 340.651188 -250.399144)
			(xy 340.609304 -250.428054) (xy 340.563325 -250.449871) (xy 340.514441 -250.464031) (xy 340.46392 -250.470165)
			(xy 340.413068 -250.468116) (xy 340.363204 -250.457936) (xy 340.315618 -250.439889) (xy 340.271544 -250.414443)
			(xy 340.232122 -250.382256) (xy 340.198374 -250.344162) (xy 340.171173 -250.301148) (xy 340.151225 -250.254328)
			(xy 340.139046 -250.204914) (xy 340.134951 -250.154186) (xy 339.81644 -250.154186) (xy 339.815945 -250.178793)
			(xy 339.80805 -250.22737) (xy 339.792466 -250.274051) (xy 339.769595 -250.317628) (xy 339.74003 -250.356972)
			(xy 339.704537 -250.391064) (xy 339.664034 -250.41902) (xy 339.619572 -250.440118) (xy 339.572301 -250.45381)
			(xy 339.523446 -250.459742) (xy 339.474271 -250.457761) (xy 339.426052 -250.447917) (xy 339.380036 -250.430465)
			(xy 339.337415 -250.405858) (xy 339.299294 -250.374733) (xy 339.266659 -250.337896) (xy 339.240356 -250.2963)
			(xy 339.221065 -250.251024) (xy 339.209288 -250.20324) (xy 339.205328 -250.154186) (xy 338.876386 -250.154186)
			(xy 338.875891 -250.178793) (xy 338.867996 -250.22737) (xy 338.852412 -250.274051) (xy 338.829541 -250.317628)
			(xy 338.799976 -250.356972) (xy 338.764483 -250.391064) (xy 338.72398 -250.41902) (xy 338.679518 -250.440118)
			(xy 338.632247 -250.45381) (xy 338.583392 -250.459742) (xy 338.534217 -250.457761) (xy 338.485998 -250.447917)
			(xy 338.439982 -250.430465) (xy 338.397361 -250.405858) (xy 338.35924 -250.374733) (xy 338.326605 -250.337896)
			(xy 338.300302 -250.2963) (xy 338.281011 -250.251024) (xy 338.269234 -250.20324) (xy 338.265274 -250.154186)
			(xy 338.06638 -250.154186) (xy 338.06638 -250.588018) (xy 338.066802 -250.597719) (xy 338.073972 -250.615749)
			(xy 338.08035 -250.62307) (xy 338.095082 -250.638564) (xy 338.098321 -250.641798) (xy 338.105728 -250.647171)
			(xy 338.109814 -250.649232) (xy 338.132674 -250.660154) (xy 338.140802 -250.661424) (xy 338.164998 -250.66506)
			(xy 338.211888 -250.679031) (xy 338.25595 -250.7003) (xy 338.296057 -250.728323) (xy 338.331181 -250.762383)
			(xy 338.360424 -250.801609) (xy 338.383038 -250.844997) (xy 338.398443 -250.891435) (xy 338.406245 -250.939736)
			(xy 338.406245 -250.964192) (xy 338.735428 -250.964192) (xy 338.739388 -250.915138) (xy 338.751165 -250.867354)
			(xy 338.770456 -250.822078) (xy 338.796759 -250.780482) (xy 338.829394 -250.743645) (xy 338.867515 -250.71252)
			(xy 338.910136 -250.687913) (xy 338.956152 -250.670461) (xy 339.004371 -250.660617) (xy 339.053546 -250.658636)
			(xy 339.102401 -250.664568) (xy 339.149672 -250.67826) (xy 339.194134 -250.699358) (xy 339.234637 -250.727314)
			(xy 339.27013 -250.761406) (xy 339.299695 -250.80075) (xy 339.322566 -250.844327) (xy 339.33815 -250.891008)
			(xy 339.346045 -250.939585) (xy 339.34654 -250.964192) (xy 339.664797 -250.964192) (xy 339.668892 -250.913464)
			(xy 339.681071 -250.86405) (xy 339.701019 -250.81723) (xy 339.72822 -250.774216) (xy 339.761968 -250.736122)
			(xy 339.80139 -250.703935) (xy 339.845464 -250.678489) (xy 339.89305 -250.660442) (xy 339.942914 -250.650262)
			(xy 339.993766 -250.648213) (xy 340.044287 -250.654347) (xy 340.093171 -250.668507) (xy 340.13915 -250.690324)
			(xy 340.181034 -250.719234) (xy 340.217738 -250.754489) (xy 340.248311 -250.795175) (xy 340.271962 -250.840238)
			(xy 340.288078 -250.888512) (xy 340.296242 -250.938746) (xy 340.296754 -250.964192) (xy 340.615282 -250.964192)
			(xy 340.619242 -250.915138) (xy 340.631019 -250.867354) (xy 340.65031 -250.822078) (xy 340.676613 -250.780482)
			(xy 340.709248 -250.743645) (xy 340.747369 -250.71252) (xy 340.78999 -250.687913) (xy 340.836006 -250.670461)
			(xy 340.884225 -250.660617) (xy 340.9334 -250.658636) (xy 340.982255 -250.664568) (xy 341.029526 -250.67826)
			(xy 341.073988 -250.699358) (xy 341.114491 -250.727314) (xy 341.149984 -250.761406) (xy 341.179549 -250.80075)
			(xy 341.20242 -250.844327) (xy 341.218004 -250.891008) (xy 341.225899 -250.939585) (xy 341.226394 -250.964192)
			(xy 341.555336 -250.964192) (xy 341.559296 -250.915138) (xy 341.571073 -250.867354) (xy 341.590364 -250.822078)
			(xy 341.616667 -250.780482) (xy 341.649302 -250.743645) (xy 341.687423 -250.71252) (xy 341.730044 -250.687913)
			(xy 341.77606 -250.670461) (xy 341.824279 -250.660617) (xy 341.873454 -250.658636) (xy 341.922309 -250.664568)
			(xy 341.96958 -250.67826) (xy 342.014042 -250.699358) (xy 342.054545 -250.727314) (xy 342.090038 -250.761406)
			(xy 342.119603 -250.80075) (xy 342.142474 -250.844327) (xy 342.158058 -250.891008) (xy 342.165953 -250.939585)
			(xy 342.166448 -250.964192) (xy 342.49539 -250.964192) (xy 342.49935 -250.915138) (xy 342.511127 -250.867354)
			(xy 342.530418 -250.822078) (xy 342.556721 -250.780482) (xy 342.589356 -250.743645) (xy 342.627477 -250.71252)
			(xy 342.670098 -250.687913) (xy 342.716114 -250.670461) (xy 342.764333 -250.660617) (xy 342.813508 -250.658636)
			(xy 342.862363 -250.664568) (xy 342.909634 -250.67826) (xy 342.954096 -250.699358) (xy 342.994599 -250.727314)
			(xy 343.030092 -250.761406) (xy 343.059657 -250.80075) (xy 343.082528 -250.844327) (xy 343.098112 -250.891008)
			(xy 343.106007 -250.939585) (xy 343.106502 -250.964192) (xy 343.424759 -250.964192) (xy 343.428854 -250.913464)
			(xy 343.441033 -250.86405) (xy 343.460981 -250.81723) (xy 343.488182 -250.774216) (xy 343.52193 -250.736122)
			(xy 343.561352 -250.703935) (xy 343.605426 -250.678489) (xy 343.653012 -250.660442) (xy 343.702876 -250.650262)
			(xy 343.753728 -250.648213) (xy 343.804249 -250.654347) (xy 343.853133 -250.668507) (xy 343.899112 -250.690324)
			(xy 343.940996 -250.719234) (xy 343.9777 -250.754489) (xy 344.008273 -250.795175) (xy 344.031924 -250.840238)
			(xy 344.04804 -250.888512) (xy 344.056204 -250.938746) (xy 344.056716 -250.964192) (xy 345.315298 -250.964192)
			(xy 345.319258 -250.915138) (xy 345.331035 -250.867354) (xy 345.350326 -250.822078) (xy 345.376629 -250.780482)
			(xy 345.409264 -250.743645) (xy 345.447385 -250.71252) (xy 345.490006 -250.687913) (xy 345.536022 -250.670461)
			(xy 345.584241 -250.660617) (xy 345.633416 -250.658636) (xy 345.682271 -250.664568) (xy 345.729542 -250.67826)
			(xy 345.774004 -250.699358) (xy 345.814507 -250.727314) (xy 345.85 -250.761406) (xy 345.879565 -250.80075)
			(xy 345.902436 -250.844327) (xy 345.91802 -250.891008) (xy 345.925915 -250.939585) (xy 345.92641 -250.964192)
			(xy 347.195406 -250.964192) (xy 347.199366 -250.915138) (xy 347.211143 -250.867354) (xy 347.230434 -250.822078)
			(xy 347.256737 -250.780482) (xy 347.289372 -250.743645) (xy 347.327493 -250.71252) (xy 347.370114 -250.687913)
			(xy 347.41613 -250.670461) (xy 347.464349 -250.660617) (xy 347.513524 -250.658636) (xy 347.562379 -250.664568)
			(xy 347.60965 -250.67826) (xy 347.654112 -250.699358) (xy 347.694615 -250.727314) (xy 347.730108 -250.761406)
			(xy 347.759673 -250.80075) (xy 347.782544 -250.844327) (xy 347.798128 -250.891008) (xy 347.806023 -250.939585)
			(xy 347.806518 -250.964192) (xy 347.806023 -250.988799) (xy 347.798128 -251.037376) (xy 347.782544 -251.084057)
			(xy 347.759673 -251.127634) (xy 347.730108 -251.166978) (xy 347.694615 -251.20107) (xy 347.654112 -251.229026)
			(xy 347.60965 -251.250124) (xy 347.562379 -251.263816) (xy 347.513524 -251.269748) (xy 347.464349 -251.267767)
			(xy 347.41613 -251.257923) (xy 347.370114 -251.240471) (xy 347.327493 -251.215864) (xy 347.289372 -251.184739)
			(xy 347.256737 -251.147902) (xy 347.230434 -251.106306) (xy 347.211143 -251.06103) (xy 347.199366 -251.013246)
			(xy 347.195406 -250.964192) (xy 345.92641 -250.964192) (xy 345.925915 -250.988799) (xy 345.91802 -251.037376)
			(xy 345.902436 -251.084057) (xy 345.879565 -251.127634) (xy 345.85 -251.166978) (xy 345.814507 -251.20107)
			(xy 345.774004 -251.229026) (xy 345.729542 -251.250124) (xy 345.682271 -251.263816) (xy 345.633416 -251.269748)
			(xy 345.584241 -251.267767) (xy 345.536022 -251.257923) (xy 345.490006 -251.240471) (xy 345.447385 -251.215864)
			(xy 345.409264 -251.184739) (xy 345.376629 -251.147902) (xy 345.350326 -251.106306) (xy 345.331035 -251.06103)
			(xy 345.319258 -251.013246) (xy 345.315298 -250.964192) (xy 344.056716 -250.964192) (xy 344.056204 -250.989638)
			(xy 344.04804 -251.039872) (xy 344.031924 -251.088146) (xy 344.008273 -251.133209) (xy 343.9777 -251.173895)
			(xy 343.940996 -251.20915) (xy 343.899112 -251.23806) (xy 343.853133 -251.259877) (xy 343.804249 -251.274037)
			(xy 343.753728 -251.280171) (xy 343.702876 -251.278122) (xy 343.653012 -251.267942) (xy 343.605426 -251.249895)
			(xy 343.561352 -251.224449) (xy 343.52193 -251.192262) (xy 343.488182 -251.154168) (xy 343.460981 -251.111154)
			(xy 343.441033 -251.064334) (xy 343.428854 -251.01492) (xy 343.424759 -250.964192) (xy 343.106502 -250.964192)
			(xy 343.106007 -250.988799) (xy 343.098112 -251.037376) (xy 343.082528 -251.084057) (xy 343.059657 -251.127634)
			(xy 343.030092 -251.166978) (xy 342.994599 -251.20107) (xy 342.954096 -251.229026) (xy 342.909634 -251.250124)
			(xy 342.862363 -251.263816) (xy 342.813508 -251.269748) (xy 342.764333 -251.267767) (xy 342.716114 -251.257923)
			(xy 342.670098 -251.240471) (xy 342.627477 -251.215864) (xy 342.589356 -251.184739) (xy 342.556721 -251.147902)
			(xy 342.530418 -251.106306) (xy 342.511127 -251.06103) (xy 342.49935 -251.013246) (xy 342.49539 -250.964192)
			(xy 342.166448 -250.964192) (xy 342.165953 -250.988799) (xy 342.158058 -251.037376) (xy 342.142474 -251.084057)
			(xy 342.119603 -251.127634) (xy 342.090038 -251.166978) (xy 342.054545 -251.20107) (xy 342.014042 -251.229026)
			(xy 341.96958 -251.250124) (xy 341.922309 -251.263816) (xy 341.873454 -251.269748) (xy 341.824279 -251.267767)
			(xy 341.77606 -251.257923) (xy 341.730044 -251.240471) (xy 341.687423 -251.215864) (xy 341.649302 -251.184739)
			(xy 341.616667 -251.147902) (xy 341.590364 -251.106306) (xy 341.571073 -251.06103) (xy 341.559296 -251.013246)
			(xy 341.555336 -250.964192) (xy 341.226394 -250.964192) (xy 341.225899 -250.988799) (xy 341.218004 -251.037376)
			(xy 341.20242 -251.084057) (xy 341.179549 -251.127634) (xy 341.149984 -251.166978) (xy 341.114491 -251.20107)
			(xy 341.073988 -251.229026) (xy 341.029526 -251.250124) (xy 340.982255 -251.263816) (xy 340.9334 -251.269748)
			(xy 340.884225 -251.267767) (xy 340.836006 -251.257923) (xy 340.78999 -251.240471) (xy 340.747369 -251.215864)
			(xy 340.709248 -251.184739) (xy 340.676613 -251.147902) (xy 340.65031 -251.106306) (xy 340.631019 -251.06103)
			(xy 340.619242 -251.013246) (xy 340.615282 -250.964192) (xy 340.296754 -250.964192) (xy 340.296242 -250.989638)
			(xy 340.288078 -251.039872) (xy 340.271962 -251.088146) (xy 340.248311 -251.133209) (xy 340.217738 -251.173895)
			(xy 340.181034 -251.20915) (xy 340.13915 -251.23806) (xy 340.093171 -251.259877) (xy 340.044287 -251.274037)
			(xy 339.993766 -251.280171) (xy 339.942914 -251.278122) (xy 339.89305 -251.267942) (xy 339.845464 -251.249895)
			(xy 339.80139 -251.224449) (xy 339.761968 -251.192262) (xy 339.72822 -251.154168) (xy 339.701019 -251.111154)
			(xy 339.681071 -251.064334) (xy 339.668892 -251.01492) (xy 339.664797 -250.964192) (xy 339.34654 -250.964192)
			(xy 339.346045 -250.988799) (xy 339.33815 -251.037376) (xy 339.322566 -251.084057) (xy 339.299695 -251.127634)
			(xy 339.27013 -251.166978) (xy 339.234637 -251.20107) (xy 339.194134 -251.229026) (xy 339.149672 -251.250124)
			(xy 339.102401 -251.263816) (xy 339.053546 -251.269748) (xy 339.004371 -251.267767) (xy 338.956152 -251.257923)
			(xy 338.910136 -251.240471) (xy 338.867515 -251.215864) (xy 338.829394 -251.184739) (xy 338.796759 -251.147902)
			(xy 338.770456 -251.106306) (xy 338.751165 -251.06103) (xy 338.739388 -251.013246) (xy 338.735428 -250.964192)
			(xy 338.406245 -250.964192) (xy 338.406246 -250.988662) (xy 338.398443 -251.036963) (xy 338.383039 -251.083401)
			(xy 338.360425 -251.126789) (xy 338.331182 -251.166015) (xy 338.296058 -251.200076) (xy 338.255952 -251.228099)
			(xy 338.21189 -251.249369) (xy 338.165 -251.263339) (xy 338.140802 -251.26696) (xy 338.132674 -251.26823)
			(xy 338.109814 -251.279152) (xy 338.105727 -251.281213) (xy 338.098315 -251.286581) (xy 338.095082 -251.28982)
			(xy 338.08035 -251.305314) (xy 338.073966 -251.312634) (xy 338.066778 -251.330661) (xy 338.06638 -251.340366)
			(xy 338.06638 -251.774198) (xy 338.254843 -251.774198) (xy 338.258938 -251.72347) (xy 338.271117 -251.674056)
			(xy 338.291065 -251.627236) (xy 338.318266 -251.584222) (xy 338.352014 -251.546128) (xy 338.391436 -251.513941)
			(xy 338.43551 -251.488495) (xy 338.483096 -251.470448) (xy 338.53296 -251.460268) (xy 338.583812 -251.458219)
			(xy 338.634333 -251.464353) (xy 338.683217 -251.478513) (xy 338.729196 -251.50033) (xy 338.77108 -251.52924)
			(xy 338.807784 -251.564495) (xy 338.838357 -251.605181) (xy 338.862008 -251.650244) (xy 338.878124 -251.698518)
			(xy 338.886288 -251.748752) (xy 338.8868 -251.774198) (xy 339.205328 -251.774198) (xy 339.209288 -251.725144)
			(xy 339.221065 -251.67736) (xy 339.240356 -251.632084) (xy 339.266659 -251.590488) (xy 339.299294 -251.553651)
			(xy 339.337415 -251.522526) (xy 339.380036 -251.497919) (xy 339.426052 -251.480467) (xy 339.474271 -251.470623)
			(xy 339.523446 -251.468642) (xy 339.572301 -251.474574) (xy 339.619572 -251.488266) (xy 339.664034 -251.509364)
			(xy 339.704537 -251.53732) (xy 339.74003 -251.571412) (xy 339.769595 -251.610756) (xy 339.792466 -251.654333)
			(xy 339.80805 -251.701014) (xy 339.815945 -251.749591) (xy 339.81644 -251.774198) (xy 340.145382 -251.774198)
			(xy 340.149342 -251.725144) (xy 340.161119 -251.67736) (xy 340.18041 -251.632084) (xy 340.206713 -251.590488)
			(xy 340.239348 -251.553651) (xy 340.277469 -251.522526) (xy 340.32009 -251.497919) (xy 340.366106 -251.480467)
			(xy 340.414325 -251.470623) (xy 340.4635 -251.468642) (xy 340.512355 -251.474574) (xy 340.559626 -251.488266)
			(xy 340.604088 -251.509364) (xy 340.644591 -251.53732) (xy 340.680084 -251.571412) (xy 340.709649 -251.610756)
			(xy 340.73252 -251.654333) (xy 340.748104 -251.701014) (xy 340.755999 -251.749591) (xy 340.756494 -251.774198)
			(xy 341.085182 -251.774198) (xy 341.089142 -251.725144) (xy 341.100919 -251.67736) (xy 341.12021 -251.632084)
			(xy 341.146513 -251.590488) (xy 341.179148 -251.553651) (xy 341.217269 -251.522526) (xy 341.25989 -251.497919)
			(xy 341.305906 -251.480467) (xy 341.354125 -251.470623) (xy 341.4033 -251.468642) (xy 341.452155 -251.474574)
			(xy 341.499426 -251.488266) (xy 341.543888 -251.509364) (xy 341.584391 -251.53732) (xy 341.619884 -251.571412)
			(xy 341.649449 -251.610756) (xy 341.67232 -251.654333) (xy 341.687904 -251.701014) (xy 341.695799 -251.749591)
			(xy 341.696294 -251.774198) (xy 342.014805 -251.774198) (xy 342.0189 -251.72347) (xy 342.031079 -251.674056)
			(xy 342.051027 -251.627236) (xy 342.078228 -251.584222) (xy 342.111976 -251.546128) (xy 342.151398 -251.513941)
			(xy 342.195472 -251.488495) (xy 342.243058 -251.470448) (xy 342.292922 -251.460268) (xy 342.343774 -251.458219)
			(xy 342.394295 -251.464353) (xy 342.443179 -251.478513) (xy 342.489158 -251.50033) (xy 342.531042 -251.52924)
			(xy 342.567746 -251.564495) (xy 342.598319 -251.605181) (xy 342.62197 -251.650244) (xy 342.638086 -251.698518)
			(xy 342.64625 -251.748752) (xy 342.646762 -251.774198) (xy 342.96529 -251.774198) (xy 342.96925 -251.725144)
			(xy 342.981027 -251.67736) (xy 343.000318 -251.632084) (xy 343.026621 -251.590488) (xy 343.059256 -251.553651)
			(xy 343.097377 -251.522526) (xy 343.139998 -251.497919) (xy 343.186014 -251.480467) (xy 343.234233 -251.470623)
			(xy 343.283408 -251.468642) (xy 343.332263 -251.474574) (xy 343.379534 -251.488266) (xy 343.423996 -251.509364)
			(xy 343.464499 -251.53732) (xy 343.499992 -251.571412) (xy 343.529557 -251.610756) (xy 343.552428 -251.654333)
			(xy 343.568012 -251.701014) (xy 343.575907 -251.749591) (xy 343.576402 -251.774198) (xy 343.905344 -251.774198)
			(xy 343.909304 -251.725144) (xy 343.921081 -251.67736) (xy 343.940372 -251.632084) (xy 343.966675 -251.590488)
			(xy 343.99931 -251.553651) (xy 344.037431 -251.522526) (xy 344.080052 -251.497919) (xy 344.126068 -251.480467)
			(xy 344.174287 -251.470623) (xy 344.223462 -251.468642) (xy 344.272317 -251.474574) (xy 344.319588 -251.488266)
			(xy 344.36405 -251.509364) (xy 344.404553 -251.53732) (xy 344.440046 -251.571412) (xy 344.469611 -251.610756)
			(xy 344.492482 -251.654333) (xy 344.508066 -251.701014) (xy 344.515961 -251.749591) (xy 344.516456 -251.774198)
			(xy 345.785198 -251.774198) (xy 345.789158 -251.725144) (xy 345.800935 -251.67736) (xy 345.820226 -251.632084)
			(xy 345.846529 -251.590488) (xy 345.879164 -251.553651) (xy 345.917285 -251.522526) (xy 345.959906 -251.497919)
			(xy 346.005922 -251.480467) (xy 346.054141 -251.470623) (xy 346.103316 -251.468642) (xy 346.152171 -251.474574)
			(xy 346.199442 -251.488266) (xy 346.243904 -251.509364) (xy 346.284407 -251.53732) (xy 346.3199 -251.571412)
			(xy 346.349465 -251.610756) (xy 346.372336 -251.654333) (xy 346.38792 -251.701014) (xy 346.395815 -251.749591)
			(xy 346.39631 -251.774198) (xy 347.665306 -251.774198) (xy 347.669266 -251.725144) (xy 347.681043 -251.67736)
			(xy 347.700334 -251.632084) (xy 347.726637 -251.590488) (xy 347.759272 -251.553651) (xy 347.797393 -251.522526)
			(xy 347.840014 -251.497919) (xy 347.88603 -251.480467) (xy 347.934249 -251.470623) (xy 347.983424 -251.468642)
			(xy 348.032279 -251.474574) (xy 348.07955 -251.488266) (xy 348.124012 -251.509364) (xy 348.164515 -251.53732)
			(xy 348.200008 -251.571412) (xy 348.229573 -251.610756) (xy 348.252444 -251.654333) (xy 348.268028 -251.701014)
			(xy 348.275923 -251.749591) (xy 348.276418 -251.774198) (xy 348.275923 -251.798805) (xy 348.268028 -251.847382)
			(xy 348.252444 -251.894063) (xy 348.229573 -251.93764) (xy 348.200008 -251.976984) (xy 348.164515 -252.011076)
			(xy 348.124012 -252.039032) (xy 348.07955 -252.06013) (xy 348.032279 -252.073822) (xy 347.983424 -252.079754)
			(xy 347.934249 -252.077773) (xy 347.88603 -252.067929) (xy 347.840014 -252.050477) (xy 347.797393 -252.02587)
			(xy 347.759272 -251.994745) (xy 347.726637 -251.957908) (xy 347.700334 -251.916312) (xy 347.681043 -251.871036)
			(xy 347.669266 -251.823252) (xy 347.665306 -251.774198) (xy 346.39631 -251.774198) (xy 346.395815 -251.798805)
			(xy 346.38792 -251.847382) (xy 346.372336 -251.894063) (xy 346.349465 -251.93764) (xy 346.3199 -251.976984)
			(xy 346.284407 -252.011076) (xy 346.243904 -252.039032) (xy 346.199442 -252.06013) (xy 346.152171 -252.073822)
			(xy 346.103316 -252.079754) (xy 346.054141 -252.077773) (xy 346.005922 -252.067929) (xy 345.959906 -252.050477)
			(xy 345.917285 -252.02587) (xy 345.879164 -251.994745) (xy 345.846529 -251.957908) (xy 345.820226 -251.916312)
			(xy 345.800935 -251.871036) (xy 345.789158 -251.823252) (xy 345.785198 -251.774198) (xy 344.516456 -251.774198)
			(xy 344.515961 -251.798805) (xy 344.508066 -251.847382) (xy 344.492482 -251.894063) (xy 344.469611 -251.93764)
			(xy 344.440046 -251.976984) (xy 344.404553 -252.011076) (xy 344.36405 -252.039032) (xy 344.319588 -252.06013)
			(xy 344.272317 -252.073822) (xy 344.223462 -252.079754) (xy 344.174287 -252.077773) (xy 344.126068 -252.067929)
			(xy 344.080052 -252.050477) (xy 344.037431 -252.02587) (xy 343.99931 -251.994745) (xy 343.966675 -251.957908)
			(xy 343.940372 -251.916312) (xy 343.921081 -251.871036) (xy 343.909304 -251.823252) (xy 343.905344 -251.774198)
			(xy 343.576402 -251.774198) (xy 343.575907 -251.798805) (xy 343.568012 -251.847382) (xy 343.552428 -251.894063)
			(xy 343.529557 -251.93764) (xy 343.499992 -251.976984) (xy 343.464499 -252.011076) (xy 343.423996 -252.039032)
			(xy 343.379534 -252.06013) (xy 343.332263 -252.073822) (xy 343.283408 -252.079754) (xy 343.234233 -252.077773)
			(xy 343.186014 -252.067929) (xy 343.139998 -252.050477) (xy 343.097377 -252.02587) (xy 343.059256 -251.994745)
			(xy 343.026621 -251.957908) (xy 343.000318 -251.916312) (xy 342.981027 -251.871036) (xy 342.96925 -251.823252)
			(xy 342.96529 -251.774198) (xy 342.646762 -251.774198) (xy 342.64625 -251.799644) (xy 342.638086 -251.849878)
			(xy 342.62197 -251.898152) (xy 342.598319 -251.943215) (xy 342.567746 -251.983901) (xy 342.531042 -252.019156)
			(xy 342.489158 -252.048066) (xy 342.443179 -252.069883) (xy 342.394295 -252.084043) (xy 342.343774 -252.090177)
			(xy 342.292922 -252.088128) (xy 342.243058 -252.077948) (xy 342.195472 -252.059901) (xy 342.151398 -252.034455)
			(xy 342.111976 -252.002268) (xy 342.078228 -251.964174) (xy 342.051027 -251.92116) (xy 342.031079 -251.87434)
			(xy 342.0189 -251.824926) (xy 342.014805 -251.774198) (xy 341.696294 -251.774198) (xy 341.695799 -251.798805)
			(xy 341.687904 -251.847382) (xy 341.67232 -251.894063) (xy 341.649449 -251.93764) (xy 341.619884 -251.976984)
			(xy 341.584391 -252.011076) (xy 341.543888 -252.039032) (xy 341.499426 -252.06013) (xy 341.452155 -252.073822)
			(xy 341.4033 -252.079754) (xy 341.354125 -252.077773) (xy 341.305906 -252.067929) (xy 341.25989 -252.050477)
			(xy 341.217269 -252.02587) (xy 341.179148 -251.994745) (xy 341.146513 -251.957908) (xy 341.12021 -251.916312)
			(xy 341.100919 -251.871036) (xy 341.089142 -251.823252) (xy 341.085182 -251.774198) (xy 340.756494 -251.774198)
			(xy 340.755999 -251.798805) (xy 340.748104 -251.847382) (xy 340.73252 -251.894063) (xy 340.709649 -251.93764)
			(xy 340.680084 -251.976984) (xy 340.644591 -252.011076) (xy 340.604088 -252.039032) (xy 340.559626 -252.06013)
			(xy 340.512355 -252.073822) (xy 340.4635 -252.079754) (xy 340.414325 -252.077773) (xy 340.366106 -252.067929)
			(xy 340.32009 -252.050477) (xy 340.277469 -252.02587) (xy 340.239348 -251.994745) (xy 340.206713 -251.957908)
			(xy 340.18041 -251.916312) (xy 340.161119 -251.871036) (xy 340.149342 -251.823252) (xy 340.145382 -251.774198)
			(xy 339.81644 -251.774198) (xy 339.815945 -251.798805) (xy 339.80805 -251.847382) (xy 339.792466 -251.894063)
			(xy 339.769595 -251.93764) (xy 339.74003 -251.976984) (xy 339.704537 -252.011076) (xy 339.664034 -252.039032)
			(xy 339.619572 -252.06013) (xy 339.572301 -252.073822) (xy 339.523446 -252.079754) (xy 339.474271 -252.077773)
			(xy 339.426052 -252.067929) (xy 339.380036 -252.050477) (xy 339.337415 -252.02587) (xy 339.299294 -251.994745)
			(xy 339.266659 -251.957908) (xy 339.240356 -251.916312) (xy 339.221065 -251.871036) (xy 339.209288 -251.823252)
			(xy 339.205328 -251.774198) (xy 338.8868 -251.774198) (xy 338.886288 -251.799644) (xy 338.878124 -251.849878)
			(xy 338.862008 -251.898152) (xy 338.838357 -251.943215) (xy 338.807784 -251.983901) (xy 338.77108 -252.019156)
			(xy 338.729196 -252.048066) (xy 338.683217 -252.069883) (xy 338.634333 -252.084043) (xy 338.583812 -252.090177)
			(xy 338.53296 -252.088128) (xy 338.483096 -252.077948) (xy 338.43551 -252.059901) (xy 338.391436 -252.034455)
			(xy 338.352014 -252.002268) (xy 338.318266 -251.964174) (xy 338.291065 -251.92116) (xy 338.271117 -251.87434)
			(xy 338.258938 -251.824926) (xy 338.254843 -251.774198) (xy 338.06638 -251.774198) (xy 338.06638 -252.20803)
			(xy 338.066804 -252.217731) (xy 338.073977 -252.235758) (xy 338.08035 -252.243082) (xy 338.095082 -252.258576)
			(xy 338.098321 -252.261809) (xy 338.105729 -252.267181) (xy 338.109814 -252.269244) (xy 338.132674 -252.280166)
			(xy 338.140802 -252.281436) (xy 338.164997 -252.285072) (xy 338.211886 -252.299042) (xy 338.255946 -252.320311)
			(xy 338.29605 -252.348333) (xy 338.331173 -252.382392) (xy 338.360415 -252.421617) (xy 338.383027 -252.465003)
			(xy 338.398432 -252.511439) (xy 338.406234 -252.559738) (xy 338.406234 -252.584204) (xy 338.724743 -252.584204)
			(xy 338.728838 -252.533476) (xy 338.741017 -252.484062) (xy 338.760965 -252.437242) (xy 338.788166 -252.394228)
			(xy 338.821914 -252.356134) (xy 338.861336 -252.323947) (xy 338.90541 -252.298501) (xy 338.952996 -252.280454)
			(xy 339.00286 -252.270274) (xy 339.053712 -252.268225) (xy 339.104233 -252.274359) (xy 339.153117 -252.288519)
			(xy 339.199096 -252.310336) (xy 339.24098 -252.339246) (xy 339.277684 -252.374501) (xy 339.308257 -252.415187)
			(xy 339.331908 -252.46025) (xy 339.348024 -252.508524) (xy 339.356188 -252.558758) (xy 339.3567 -252.584204)
			(xy 339.664797 -252.584204) (xy 339.668892 -252.533476) (xy 339.681071 -252.484062) (xy 339.701019 -252.437242)
			(xy 339.72822 -252.394228) (xy 339.761968 -252.356134) (xy 339.80139 -252.323947) (xy 339.845464 -252.298501)
			(xy 339.89305 -252.280454) (xy 339.942914 -252.270274) (xy 339.993766 -252.268225) (xy 340.044287 -252.274359)
			(xy 340.093171 -252.288519) (xy 340.13915 -252.310336) (xy 340.181034 -252.339246) (xy 340.217738 -252.374501)
			(xy 340.248311 -252.415187) (xy 340.271962 -252.46025) (xy 340.288078 -252.508524) (xy 340.296242 -252.558758)
			(xy 340.296754 -252.584204) (xy 340.615282 -252.584204) (xy 340.619242 -252.53515) (xy 340.631019 -252.487366)
			(xy 340.65031 -252.44209) (xy 340.676613 -252.400494) (xy 340.709248 -252.363657) (xy 340.747369 -252.332532)
			(xy 340.78999 -252.307925) (xy 340.836006 -252.290473) (xy 340.884225 -252.280629) (xy 340.9334 -252.278648)
			(xy 340.982255 -252.28458) (xy 341.029526 -252.298272) (xy 341.073988 -252.31937) (xy 341.114491 -252.347326)
			(xy 341.149984 -252.381418) (xy 341.179549 -252.420762) (xy 341.20242 -252.464339) (xy 341.218004 -252.51102)
			(xy 341.225899 -252.559597) (xy 341.226394 -252.584204) (xy 341.544905 -252.584204) (xy 341.549 -252.533476)
			(xy 341.561179 -252.484062) (xy 341.581127 -252.437242) (xy 341.608328 -252.394228) (xy 341.642076 -252.356134)
			(xy 341.681498 -252.323947) (xy 341.725572 -252.298501) (xy 341.773158 -252.280454) (xy 341.823022 -252.270274)
			(xy 341.873874 -252.268225) (xy 341.924395 -252.274359) (xy 341.973279 -252.288519) (xy 342.019258 -252.310336)
			(xy 342.061142 -252.339246) (xy 342.097846 -252.374501) (xy 342.128419 -252.415187) (xy 342.15207 -252.46025)
			(xy 342.168186 -252.508524) (xy 342.17635 -252.558758) (xy 342.176862 -252.584204) (xy 342.49539 -252.584204)
			(xy 342.49935 -252.53515) (xy 342.511127 -252.487366) (xy 342.530418 -252.44209) (xy 342.556721 -252.400494)
			(xy 342.589356 -252.363657) (xy 342.627477 -252.332532) (xy 342.670098 -252.307925) (xy 342.716114 -252.290473)
			(xy 342.764333 -252.280629) (xy 342.813508 -252.278648) (xy 342.862363 -252.28458) (xy 342.909634 -252.298272)
			(xy 342.954096 -252.31937) (xy 342.994599 -252.347326) (xy 343.030092 -252.381418) (xy 343.059657 -252.420762)
			(xy 343.082528 -252.464339) (xy 343.098112 -252.51102) (xy 343.106007 -252.559597) (xy 343.106502 -252.584204)
			(xy 343.424759 -252.584204) (xy 343.428854 -252.533476) (xy 343.441033 -252.484062) (xy 343.460981 -252.437242)
			(xy 343.488182 -252.394228) (xy 343.52193 -252.356134) (xy 343.561352 -252.323947) (xy 343.605426 -252.298501)
			(xy 343.653012 -252.280454) (xy 343.702876 -252.270274) (xy 343.753728 -252.268225) (xy 343.804249 -252.274359)
			(xy 343.853133 -252.288519) (xy 343.899112 -252.310336) (xy 343.940996 -252.339246) (xy 343.9777 -252.374501)
			(xy 344.008273 -252.415187) (xy 344.031924 -252.46025) (xy 344.04804 -252.508524) (xy 344.056204 -252.558758)
			(xy 344.056716 -252.584204) (xy 345.315298 -252.584204) (xy 345.319258 -252.53515) (xy 345.331035 -252.487366)
			(xy 345.350326 -252.44209) (xy 345.376629 -252.400494) (xy 345.409264 -252.363657) (xy 345.447385 -252.332532)
			(xy 345.490006 -252.307925) (xy 345.536022 -252.290473) (xy 345.584241 -252.280629) (xy 345.633416 -252.278648)
			(xy 345.682271 -252.28458) (xy 345.729542 -252.298272) (xy 345.774004 -252.31937) (xy 345.814507 -252.347326)
			(xy 345.85 -252.381418) (xy 345.879565 -252.420762) (xy 345.902436 -252.464339) (xy 345.91802 -252.51102)
			(xy 345.925915 -252.559597) (xy 345.92641 -252.584204) (xy 347.195406 -252.584204) (xy 347.199366 -252.53515)
			(xy 347.211143 -252.487366) (xy 347.230434 -252.44209) (xy 347.256737 -252.400494) (xy 347.289372 -252.363657)
			(xy 347.327493 -252.332532) (xy 347.370114 -252.307925) (xy 347.41613 -252.290473) (xy 347.464349 -252.280629)
			(xy 347.513524 -252.278648) (xy 347.562379 -252.28458) (xy 347.60965 -252.298272) (xy 347.654112 -252.31937)
			(xy 347.694615 -252.347326) (xy 347.730108 -252.381418) (xy 347.759673 -252.420762) (xy 347.782544 -252.464339)
			(xy 347.798128 -252.51102) (xy 347.806023 -252.559597) (xy 347.806518 -252.584204) (xy 347.806023 -252.608811)
			(xy 347.798128 -252.657388) (xy 347.782544 -252.704069) (xy 347.759673 -252.747646) (xy 347.730108 -252.78699)
			(xy 347.694615 -252.821082) (xy 347.654112 -252.849038) (xy 347.60965 -252.870136) (xy 347.562379 -252.883828)
			(xy 347.513524 -252.88976) (xy 347.464349 -252.887779) (xy 347.41613 -252.877935) (xy 347.370114 -252.860483)
			(xy 347.327493 -252.835876) (xy 347.289372 -252.804751) (xy 347.256737 -252.767914) (xy 347.230434 -252.726318)
			(xy 347.211143 -252.681042) (xy 347.199366 -252.633258) (xy 347.195406 -252.584204) (xy 345.92641 -252.584204)
			(xy 345.925915 -252.608811) (xy 345.91802 -252.657388) (xy 345.902436 -252.704069) (xy 345.879565 -252.747646)
			(xy 345.85 -252.78699) (xy 345.814507 -252.821082) (xy 345.774004 -252.849038) (xy 345.729542 -252.870136)
			(xy 345.682271 -252.883828) (xy 345.633416 -252.88976) (xy 345.584241 -252.887779) (xy 345.536022 -252.877935)
			(xy 345.490006 -252.860483) (xy 345.447385 -252.835876) (xy 345.409264 -252.804751) (xy 345.376629 -252.767914)
			(xy 345.350326 -252.726318) (xy 345.331035 -252.681042) (xy 345.319258 -252.633258) (xy 345.315298 -252.584204)
			(xy 344.056716 -252.584204) (xy 344.056204 -252.60965) (xy 344.04804 -252.659884) (xy 344.031924 -252.708158)
			(xy 344.008273 -252.753221) (xy 343.9777 -252.793907) (xy 343.940996 -252.829162) (xy 343.899112 -252.858072)
			(xy 343.853133 -252.879889) (xy 343.804249 -252.894049) (xy 343.753728 -252.900183) (xy 343.702876 -252.898134)
			(xy 343.653012 -252.887954) (xy 343.605426 -252.869907) (xy 343.561352 -252.844461) (xy 343.52193 -252.812274)
			(xy 343.488182 -252.77418) (xy 343.460981 -252.731166) (xy 343.441033 -252.684346) (xy 343.428854 -252.634932)
			(xy 343.424759 -252.584204) (xy 343.106502 -252.584204) (xy 343.106007 -252.608811) (xy 343.098112 -252.657388)
			(xy 343.082528 -252.704069) (xy 343.059657 -252.747646) (xy 343.030092 -252.78699) (xy 342.994599 -252.821082)
			(xy 342.954096 -252.849038) (xy 342.909634 -252.870136) (xy 342.862363 -252.883828) (xy 342.813508 -252.88976)
			(xy 342.764333 -252.887779) (xy 342.716114 -252.877935) (xy 342.670098 -252.860483) (xy 342.627477 -252.835876)
			(xy 342.589356 -252.804751) (xy 342.556721 -252.767914) (xy 342.530418 -252.726318) (xy 342.511127 -252.681042)
			(xy 342.49935 -252.633258) (xy 342.49539 -252.584204) (xy 342.176862 -252.584204) (xy 342.17635 -252.60965)
			(xy 342.168186 -252.659884) (xy 342.15207 -252.708158) (xy 342.128419 -252.753221) (xy 342.097846 -252.793907)
			(xy 342.061142 -252.829162) (xy 342.019258 -252.858072) (xy 341.973279 -252.879889) (xy 341.924395 -252.894049)
			(xy 341.873874 -252.900183) (xy 341.823022 -252.898134) (xy 341.773158 -252.887954) (xy 341.725572 -252.869907)
			(xy 341.681498 -252.844461) (xy 341.642076 -252.812274) (xy 341.608328 -252.77418) (xy 341.581127 -252.731166)
			(xy 341.561179 -252.684346) (xy 341.549 -252.634932) (xy 341.544905 -252.584204) (xy 341.226394 -252.584204)
			(xy 341.225899 -252.608811) (xy 341.218004 -252.657388) (xy 341.20242 -252.704069) (xy 341.179549 -252.747646)
			(xy 341.149984 -252.78699) (xy 341.114491 -252.821082) (xy 341.073988 -252.849038) (xy 341.029526 -252.870136)
			(xy 340.982255 -252.883828) (xy 340.9334 -252.88976) (xy 340.884225 -252.887779) (xy 340.836006 -252.877935)
			(xy 340.78999 -252.860483) (xy 340.747369 -252.835876) (xy 340.709248 -252.804751) (xy 340.676613 -252.767914)
			(xy 340.65031 -252.726318) (xy 340.631019 -252.681042) (xy 340.619242 -252.633258) (xy 340.615282 -252.584204)
			(xy 340.296754 -252.584204) (xy 340.296242 -252.60965) (xy 340.288078 -252.659884) (xy 340.271962 -252.708158)
			(xy 340.248311 -252.753221) (xy 340.217738 -252.793907) (xy 340.181034 -252.829162) (xy 340.13915 -252.858072)
			(xy 340.093171 -252.879889) (xy 340.044287 -252.894049) (xy 339.993766 -252.900183) (xy 339.942914 -252.898134)
			(xy 339.89305 -252.887954) (xy 339.845464 -252.869907) (xy 339.80139 -252.844461) (xy 339.761968 -252.812274)
			(xy 339.72822 -252.77418) (xy 339.701019 -252.731166) (xy 339.681071 -252.684346) (xy 339.668892 -252.634932)
			(xy 339.664797 -252.584204) (xy 339.3567 -252.584204) (xy 339.356188 -252.60965) (xy 339.348024 -252.659884)
			(xy 339.331908 -252.708158) (xy 339.308257 -252.753221) (xy 339.277684 -252.793907) (xy 339.24098 -252.829162)
			(xy 339.199096 -252.858072) (xy 339.153117 -252.879889) (xy 339.104233 -252.894049) (xy 339.053712 -252.900183)
			(xy 339.00286 -252.898134) (xy 338.952996 -252.887954) (xy 338.90541 -252.869907) (xy 338.861336 -252.844461)
			(xy 338.821914 -252.812274) (xy 338.788166 -252.77418) (xy 338.760965 -252.731166) (xy 338.741017 -252.684346)
			(xy 338.728838 -252.634932) (xy 338.724743 -252.584204) (xy 338.406234 -252.584204) (xy 338.406234 -252.608663)
			(xy 338.398432 -252.656962) (xy 338.383027 -252.703398) (xy 338.360414 -252.746784) (xy 338.331172 -252.786008)
			(xy 338.29605 -252.820068) (xy 338.255945 -252.84809) (xy 338.211885 -252.869358) (xy 338.164996 -252.883328)
			(xy 338.140802 -252.886972) (xy 338.132674 -252.888242) (xy 338.109814 -252.899164) (xy 338.105728 -252.901225)
			(xy 338.098317 -252.906594) (xy 338.095082 -252.909832) (xy 338.08035 -252.925326) (xy 338.073968 -252.932647)
			(xy 338.066784 -252.950674) (xy 338.06638 -252.960378) (xy 338.06638 -253.39421) (xy 338.254843 -253.39421)
			(xy 338.258938 -253.343482) (xy 338.271117 -253.294068) (xy 338.291065 -253.247248) (xy 338.318266 -253.204234)
			(xy 338.352014 -253.16614) (xy 338.391436 -253.133953) (xy 338.43551 -253.108507) (xy 338.483096 -253.09046)
			(xy 338.53296 -253.08028) (xy 338.583812 -253.078231) (xy 338.634333 -253.084365) (xy 338.683217 -253.098525)
			(xy 338.729196 -253.120342) (xy 338.77108 -253.149252) (xy 338.807784 -253.184507) (xy 338.838357 -253.225193)
			(xy 338.862008 -253.270256) (xy 338.878124 -253.31853) (xy 338.886288 -253.368764) (xy 338.8868 -253.39421)
			(xy 339.205328 -253.39421) (xy 339.209288 -253.345156) (xy 339.221065 -253.297372) (xy 339.240356 -253.252096)
			(xy 339.266659 -253.2105) (xy 339.299294 -253.173663) (xy 339.337415 -253.142538) (xy 339.380036 -253.117931)
			(xy 339.426052 -253.100479) (xy 339.474271 -253.090635) (xy 339.523446 -253.088654) (xy 339.572301 -253.094586)
			(xy 339.619572 -253.108278) (xy 339.664034 -253.129376) (xy 339.704537 -253.157332) (xy 339.74003 -253.191424)
			(xy 339.769595 -253.230768) (xy 339.792466 -253.274345) (xy 339.80805 -253.321026) (xy 339.815945 -253.369603)
			(xy 339.81644 -253.39421) (xy 340.134951 -253.39421) (xy 340.139046 -253.343482) (xy 340.151225 -253.294068)
			(xy 340.171173 -253.247248) (xy 340.198374 -253.204234) (xy 340.232122 -253.16614) (xy 340.271544 -253.133953)
			(xy 340.315618 -253.108507) (xy 340.363204 -253.09046) (xy 340.413068 -253.08028) (xy 340.46392 -253.078231)
			(xy 340.514441 -253.084365) (xy 340.563325 -253.098525) (xy 340.609304 -253.120342) (xy 340.651188 -253.149252)
			(xy 340.687892 -253.184507) (xy 340.718465 -253.225193) (xy 340.742116 -253.270256) (xy 340.758232 -253.31853)
			(xy 340.766396 -253.368764) (xy 340.766908 -253.39421) (xy 341.085182 -253.39421) (xy 341.089142 -253.345156)
			(xy 341.100919 -253.297372) (xy 341.12021 -253.252096) (xy 341.146513 -253.2105) (xy 341.179148 -253.173663)
			(xy 341.217269 -253.142538) (xy 341.25989 -253.117931) (xy 341.305906 -253.100479) (xy 341.354125 -253.090635)
			(xy 341.4033 -253.088654) (xy 341.452155 -253.094586) (xy 341.499426 -253.108278) (xy 341.543888 -253.129376)
			(xy 341.584391 -253.157332) (xy 341.619884 -253.191424) (xy 341.649449 -253.230768) (xy 341.67232 -253.274345)
			(xy 341.687904 -253.321026) (xy 341.695799 -253.369603) (xy 341.696294 -253.39421) (xy 342.014805 -253.39421)
			(xy 342.0189 -253.343482) (xy 342.031079 -253.294068) (xy 342.051027 -253.247248) (xy 342.078228 -253.204234)
			(xy 342.111976 -253.16614) (xy 342.151398 -253.133953) (xy 342.195472 -253.108507) (xy 342.243058 -253.09046)
			(xy 342.292922 -253.08028) (xy 342.343774 -253.078231) (xy 342.394295 -253.084365) (xy 342.443179 -253.098525)
			(xy 342.489158 -253.120342) (xy 342.531042 -253.149252) (xy 342.567746 -253.184507) (xy 342.598319 -253.225193)
			(xy 342.62197 -253.270256) (xy 342.638086 -253.31853) (xy 342.64625 -253.368764) (xy 342.646762 -253.39421)
			(xy 342.954859 -253.39421) (xy 342.958954 -253.343482) (xy 342.971133 -253.294068) (xy 342.991081 -253.247248)
			(xy 343.018282 -253.204234) (xy 343.05203 -253.16614) (xy 343.091452 -253.133953) (xy 343.135526 -253.108507)
			(xy 343.183112 -253.09046) (xy 343.232976 -253.08028) (xy 343.283828 -253.078231) (xy 343.334349 -253.084365)
			(xy 343.383233 -253.098525) (xy 343.429212 -253.120342) (xy 343.471096 -253.149252) (xy 343.5078 -253.184507)
			(xy 343.538373 -253.225193) (xy 343.562024 -253.270256) (xy 343.57814 -253.31853) (xy 343.586304 -253.368764)
			(xy 343.586816 -253.39421) (xy 343.905344 -253.39421) (xy 343.909304 -253.345156) (xy 343.921081 -253.297372)
			(xy 343.940372 -253.252096) (xy 343.966675 -253.2105) (xy 343.99931 -253.173663) (xy 344.037431 -253.142538)
			(xy 344.080052 -253.117931) (xy 344.126068 -253.100479) (xy 344.174287 -253.090635) (xy 344.223462 -253.088654)
			(xy 344.272317 -253.094586) (xy 344.319588 -253.108278) (xy 344.36405 -253.129376) (xy 344.404553 -253.157332)
			(xy 344.440046 -253.191424) (xy 344.469611 -253.230768) (xy 344.492482 -253.274345) (xy 344.508066 -253.321026)
			(xy 344.515961 -253.369603) (xy 344.516456 -253.39421) (xy 345.785198 -253.39421) (xy 345.789158 -253.345156)
			(xy 345.800935 -253.297372) (xy 345.820226 -253.252096) (xy 345.846529 -253.2105) (xy 345.879164 -253.173663)
			(xy 345.917285 -253.142538) (xy 345.959906 -253.117931) (xy 346.005922 -253.100479) (xy 346.054141 -253.090635)
			(xy 346.103316 -253.088654) (xy 346.152171 -253.094586) (xy 346.199442 -253.108278) (xy 346.243904 -253.129376)
			(xy 346.284407 -253.157332) (xy 346.3199 -253.191424) (xy 346.349465 -253.230768) (xy 346.372336 -253.274345)
			(xy 346.38792 -253.321026) (xy 346.395815 -253.369603) (xy 346.39631 -253.39421) (xy 346.395815 -253.418817)
			(xy 346.38792 -253.467394) (xy 346.372336 -253.514075) (xy 346.349465 -253.557652) (xy 346.3199 -253.596996)
			(xy 346.284407 -253.631088) (xy 346.243904 -253.659044) (xy 346.199442 -253.680142) (xy 346.152171 -253.693834)
			(xy 346.103316 -253.699766) (xy 346.054141 -253.697785) (xy 346.005922 -253.687941) (xy 345.959906 -253.670489)
			(xy 345.917285 -253.645882) (xy 345.879164 -253.614757) (xy 345.846529 -253.57792) (xy 345.820226 -253.536324)
			(xy 345.800935 -253.491048) (xy 345.789158 -253.443264) (xy 345.785198 -253.39421) (xy 344.516456 -253.39421)
			(xy 344.515961 -253.418817) (xy 344.508066 -253.467394) (xy 344.492482 -253.514075) (xy 344.469611 -253.557652)
			(xy 344.440046 -253.596996) (xy 344.404553 -253.631088) (xy 344.36405 -253.659044) (xy 344.319588 -253.680142)
			(xy 344.272317 -253.693834) (xy 344.223462 -253.699766) (xy 344.174287 -253.697785) (xy 344.126068 -253.687941)
			(xy 344.080052 -253.670489) (xy 344.037431 -253.645882) (xy 343.99931 -253.614757) (xy 343.966675 -253.57792)
			(xy 343.940372 -253.536324) (xy 343.921081 -253.491048) (xy 343.909304 -253.443264) (xy 343.905344 -253.39421)
			(xy 343.586816 -253.39421) (xy 343.586304 -253.419656) (xy 343.57814 -253.46989) (xy 343.562024 -253.518164)
			(xy 343.538373 -253.563227) (xy 343.5078 -253.603913) (xy 343.471096 -253.639168) (xy 343.429212 -253.668078)
			(xy 343.383233 -253.689895) (xy 343.334349 -253.704055) (xy 343.283828 -253.710189) (xy 343.232976 -253.70814)
			(xy 343.183112 -253.69796) (xy 343.135526 -253.679913) (xy 343.091452 -253.654467) (xy 343.05203 -253.62228)
			(xy 343.018282 -253.584186) (xy 342.991081 -253.541172) (xy 342.971133 -253.494352) (xy 342.958954 -253.444938)
			(xy 342.954859 -253.39421) (xy 342.646762 -253.39421) (xy 342.64625 -253.419656) (xy 342.638086 -253.46989)
			(xy 342.62197 -253.518164) (xy 342.598319 -253.563227) (xy 342.567746 -253.603913) (xy 342.531042 -253.639168)
			(xy 342.489158 -253.668078) (xy 342.443179 -253.689895) (xy 342.394295 -253.704055) (xy 342.343774 -253.710189)
			(xy 342.292922 -253.70814) (xy 342.243058 -253.69796) (xy 342.195472 -253.679913) (xy 342.151398 -253.654467)
			(xy 342.111976 -253.62228) (xy 342.078228 -253.584186) (xy 342.051027 -253.541172) (xy 342.031079 -253.494352)
			(xy 342.0189 -253.444938) (xy 342.014805 -253.39421) (xy 341.696294 -253.39421) (xy 341.695799 -253.418817)
			(xy 341.687904 -253.467394) (xy 341.67232 -253.514075) (xy 341.649449 -253.557652) (xy 341.619884 -253.596996)
			(xy 341.584391 -253.631088) (xy 341.543888 -253.659044) (xy 341.499426 -253.680142) (xy 341.452155 -253.693834)
			(xy 341.4033 -253.699766) (xy 341.354125 -253.697785) (xy 341.305906 -253.687941) (xy 341.25989 -253.670489)
			(xy 341.217269 -253.645882) (xy 341.179148 -253.614757) (xy 341.146513 -253.57792) (xy 341.12021 -253.536324)
			(xy 341.100919 -253.491048) (xy 341.089142 -253.443264) (xy 341.085182 -253.39421) (xy 340.766908 -253.39421)
			(xy 340.766396 -253.419656) (xy 340.758232 -253.46989) (xy 340.742116 -253.518164) (xy 340.718465 -253.563227)
			(xy 340.687892 -253.603913) (xy 340.651188 -253.639168) (xy 340.609304 -253.668078) (xy 340.563325 -253.689895)
			(xy 340.514441 -253.704055) (xy 340.46392 -253.710189) (xy 340.413068 -253.70814) (xy 340.363204 -253.69796)
			(xy 340.315618 -253.679913) (xy 340.271544 -253.654467) (xy 340.232122 -253.62228) (xy 340.198374 -253.584186)
			(xy 340.171173 -253.541172) (xy 340.151225 -253.494352) (xy 340.139046 -253.444938) (xy 340.134951 -253.39421)
			(xy 339.81644 -253.39421) (xy 339.815945 -253.418817) (xy 339.80805 -253.467394) (xy 339.792466 -253.514075)
			(xy 339.769595 -253.557652) (xy 339.74003 -253.596996) (xy 339.704537 -253.631088) (xy 339.664034 -253.659044)
			(xy 339.619572 -253.680142) (xy 339.572301 -253.693834) (xy 339.523446 -253.699766) (xy 339.474271 -253.697785)
			(xy 339.426052 -253.687941) (xy 339.380036 -253.670489) (xy 339.337415 -253.645882) (xy 339.299294 -253.614757)
			(xy 339.266659 -253.57792) (xy 339.240356 -253.536324) (xy 339.221065 -253.491048) (xy 339.209288 -253.443264)
			(xy 339.205328 -253.39421) (xy 338.8868 -253.39421) (xy 338.886288 -253.419656) (xy 338.878124 -253.46989)
			(xy 338.862008 -253.518164) (xy 338.838357 -253.563227) (xy 338.807784 -253.603913) (xy 338.77108 -253.639168)
			(xy 338.729196 -253.668078) (xy 338.683217 -253.689895) (xy 338.634333 -253.704055) (xy 338.583812 -253.710189)
			(xy 338.53296 -253.70814) (xy 338.483096 -253.69796) (xy 338.43551 -253.679913) (xy 338.391436 -253.654467)
			(xy 338.352014 -253.62228) (xy 338.318266 -253.584186) (xy 338.291065 -253.541172) (xy 338.271117 -253.494352)
			(xy 338.258938 -253.444938) (xy 338.254843 -253.39421) (xy 338.06638 -253.39421) (xy 338.06638 -253.828042)
			(xy 338.066807 -253.837742) (xy 338.073982 -253.855766) (xy 338.08035 -253.863094) (xy 338.095082 -253.878588)
			(xy 338.098322 -253.88182) (xy 338.10573 -253.887191) (xy 338.109814 -253.889256) (xy 338.132674 -253.900178)
			(xy 338.140802 -253.901448) (xy 338.164997 -253.905084) (xy 338.211883 -253.919054) (xy 338.255941 -253.940322)
			(xy 338.296044 -253.968343) (xy 338.331165 -254.002401) (xy 338.360406 -254.041625) (xy 338.383017 -254.085009)
			(xy 338.398421 -254.131444) (xy 338.406222 -254.179741) (xy 338.406222 -254.204216) (xy 338.724743 -254.204216)
			(xy 338.728838 -254.153488) (xy 338.741017 -254.104074) (xy 338.760965 -254.057254) (xy 338.788166 -254.01424)
			(xy 338.821914 -253.976146) (xy 338.861336 -253.943959) (xy 338.90541 -253.918513) (xy 338.952996 -253.900466)
			(xy 339.00286 -253.890286) (xy 339.053712 -253.888237) (xy 339.104233 -253.894371) (xy 339.153117 -253.908531)
			(xy 339.199096 -253.930348) (xy 339.24098 -253.959258) (xy 339.277684 -253.994513) (xy 339.308257 -254.035199)
			(xy 339.331908 -254.080262) (xy 339.348024 -254.128536) (xy 339.356188 -254.17877) (xy 339.3567 -254.204216)
			(xy 339.664797 -254.204216) (xy 339.668892 -254.153488) (xy 339.681071 -254.104074) (xy 339.701019 -254.057254)
			(xy 339.72822 -254.01424) (xy 339.761968 -253.976146) (xy 339.80139 -253.943959) (xy 339.845464 -253.918513)
			(xy 339.89305 -253.900466) (xy 339.942914 -253.890286) (xy 339.993766 -253.888237) (xy 340.044287 -253.894371)
			(xy 340.093171 -253.908531) (xy 340.13915 -253.930348) (xy 340.181034 -253.959258) (xy 340.217738 -253.994513)
			(xy 340.248311 -254.035199) (xy 340.271962 -254.080262) (xy 340.288078 -254.128536) (xy 340.296242 -254.17877)
			(xy 340.296754 -254.204216) (xy 340.615282 -254.204216) (xy 340.619242 -254.155162) (xy 340.631019 -254.107378)
			(xy 340.65031 -254.062102) (xy 340.676613 -254.020506) (xy 340.709248 -253.983669) (xy 340.747369 -253.952544)
			(xy 340.78999 -253.927937) (xy 340.836006 -253.910485) (xy 340.884225 -253.900641) (xy 340.9334 -253.89866)
			(xy 340.982255 -253.904592) (xy 341.029526 -253.918284) (xy 341.073988 -253.939382) (xy 341.114491 -253.967338)
			(xy 341.149984 -254.00143) (xy 341.179549 -254.040774) (xy 341.20242 -254.084351) (xy 341.218004 -254.131032)
			(xy 341.225899 -254.179609) (xy 341.226394 -254.204216) (xy 341.544905 -254.204216) (xy 341.549 -254.153488)
			(xy 341.561179 -254.104074) (xy 341.581127 -254.057254) (xy 341.608328 -254.01424) (xy 341.642076 -253.976146)
			(xy 341.681498 -253.943959) (xy 341.725572 -253.918513) (xy 341.773158 -253.900466) (xy 341.823022 -253.890286)
			(xy 341.873874 -253.888237) (xy 341.924395 -253.894371) (xy 341.973279 -253.908531) (xy 342.019258 -253.930348)
			(xy 342.061142 -253.959258) (xy 342.097846 -253.994513) (xy 342.128419 -254.035199) (xy 342.15207 -254.080262)
			(xy 342.168186 -254.128536) (xy 342.17635 -254.17877) (xy 342.176862 -254.204216) (xy 342.49539 -254.204216)
			(xy 342.49935 -254.155162) (xy 342.511127 -254.107378) (xy 342.530418 -254.062102) (xy 342.556721 -254.020506)
			(xy 342.589356 -253.983669) (xy 342.627477 -253.952544) (xy 342.670098 -253.927937) (xy 342.716114 -253.910485)
			(xy 342.764333 -253.900641) (xy 342.813508 -253.89866) (xy 342.862363 -253.904592) (xy 342.909634 -253.918284)
			(xy 342.954096 -253.939382) (xy 342.994599 -253.967338) (xy 343.030092 -254.00143) (xy 343.059657 -254.040774)
			(xy 343.082528 -254.084351) (xy 343.098112 -254.131032) (xy 343.106007 -254.179609) (xy 343.106502 -254.204216)
			(xy 343.424759 -254.204216) (xy 343.428854 -254.153488) (xy 343.441033 -254.104074) (xy 343.460981 -254.057254)
			(xy 343.488182 -254.01424) (xy 343.52193 -253.976146) (xy 343.561352 -253.943959) (xy 343.605426 -253.918513)
			(xy 343.653012 -253.900466) (xy 343.702876 -253.890286) (xy 343.753728 -253.888237) (xy 343.804249 -253.894371)
			(xy 343.853133 -253.908531) (xy 343.899112 -253.930348) (xy 343.940996 -253.959258) (xy 343.9777 -253.994513)
			(xy 344.008273 -254.035199) (xy 344.031924 -254.080262) (xy 344.04804 -254.128536) (xy 344.056204 -254.17877)
			(xy 344.056716 -254.204216) (xy 345.315298 -254.204216) (xy 345.319258 -254.155162) (xy 345.331035 -254.107378)
			(xy 345.350326 -254.062102) (xy 345.376629 -254.020506) (xy 345.409264 -253.983669) (xy 345.447385 -253.952544)
			(xy 345.490006 -253.927937) (xy 345.536022 -253.910485) (xy 345.584241 -253.900641) (xy 345.633416 -253.89866)
			(xy 345.682271 -253.904592) (xy 345.729542 -253.918284) (xy 345.774004 -253.939382) (xy 345.814507 -253.967338)
			(xy 345.85 -254.00143) (xy 345.879565 -254.040774) (xy 345.902436 -254.084351) (xy 345.91802 -254.131032)
			(xy 345.925915 -254.179609) (xy 345.92641 -254.204216) (xy 347.195406 -254.204216) (xy 347.199366 -254.155162)
			(xy 347.211143 -254.107378) (xy 347.230434 -254.062102) (xy 347.256737 -254.020506) (xy 347.289372 -253.983669)
			(xy 347.327493 -253.952544) (xy 347.370114 -253.927937) (xy 347.41613 -253.910485) (xy 347.464349 -253.900641)
			(xy 347.513524 -253.89866) (xy 347.562379 -253.904592) (xy 347.60965 -253.918284) (xy 347.654112 -253.939382)
			(xy 347.694615 -253.967338) (xy 347.730108 -254.00143) (xy 347.759673 -254.040774) (xy 347.782544 -254.084351)
			(xy 347.798128 -254.131032) (xy 347.806023 -254.179609) (xy 347.806518 -254.204216) (xy 347.806023 -254.228823)
			(xy 347.798128 -254.2774) (xy 347.782544 -254.324081) (xy 347.759673 -254.367658) (xy 347.730108 -254.407002)
			(xy 347.694615 -254.441094) (xy 347.654112 -254.46905) (xy 347.60965 -254.490148) (xy 347.562379 -254.50384)
			(xy 347.513524 -254.509772) (xy 347.464349 -254.507791) (xy 347.41613 -254.497947) (xy 347.370114 -254.480495)
			(xy 347.327493 -254.455888) (xy 347.289372 -254.424763) (xy 347.256737 -254.387926) (xy 347.230434 -254.34633)
			(xy 347.211143 -254.301054) (xy 347.199366 -254.25327) (xy 347.195406 -254.204216) (xy 345.92641 -254.204216)
			(xy 345.925915 -254.228823) (xy 345.91802 -254.2774) (xy 345.902436 -254.324081) (xy 345.879565 -254.367658)
			(xy 345.85 -254.407002) (xy 345.814507 -254.441094) (xy 345.774004 -254.46905) (xy 345.729542 -254.490148)
			(xy 345.682271 -254.50384) (xy 345.633416 -254.509772) (xy 345.584241 -254.507791) (xy 345.536022 -254.497947)
			(xy 345.490006 -254.480495) (xy 345.447385 -254.455888) (xy 345.409264 -254.424763) (xy 345.376629 -254.387926)
			(xy 345.350326 -254.34633) (xy 345.331035 -254.301054) (xy 345.319258 -254.25327) (xy 345.315298 -254.204216)
			(xy 344.056716 -254.204216) (xy 344.056204 -254.229662) (xy 344.04804 -254.279896) (xy 344.031924 -254.32817)
			(xy 344.008273 -254.373233) (xy 343.9777 -254.413919) (xy 343.940996 -254.449174) (xy 343.899112 -254.478084)
			(xy 343.853133 -254.499901) (xy 343.804249 -254.514061) (xy 343.753728 -254.520195) (xy 343.702876 -254.518146)
			(xy 343.653012 -254.507966) (xy 343.605426 -254.489919) (xy 343.561352 -254.464473) (xy 343.52193 -254.432286)
			(xy 343.488182 -254.394192) (xy 343.460981 -254.351178) (xy 343.441033 -254.304358) (xy 343.428854 -254.254944)
			(xy 343.424759 -254.204216) (xy 343.106502 -254.204216) (xy 343.106007 -254.228823) (xy 343.098112 -254.2774)
			(xy 343.082528 -254.324081) (xy 343.059657 -254.367658) (xy 343.030092 -254.407002) (xy 342.994599 -254.441094)
			(xy 342.954096 -254.46905) (xy 342.909634 -254.490148) (xy 342.862363 -254.50384) (xy 342.813508 -254.509772)
			(xy 342.764333 -254.507791) (xy 342.716114 -254.497947) (xy 342.670098 -254.480495) (xy 342.627477 -254.455888)
			(xy 342.589356 -254.424763) (xy 342.556721 -254.387926) (xy 342.530418 -254.34633) (xy 342.511127 -254.301054)
			(xy 342.49935 -254.25327) (xy 342.49539 -254.204216) (xy 342.176862 -254.204216) (xy 342.17635 -254.229662)
			(xy 342.168186 -254.279896) (xy 342.15207 -254.32817) (xy 342.128419 -254.373233) (xy 342.097846 -254.413919)
			(xy 342.061142 -254.449174) (xy 342.019258 -254.478084) (xy 341.973279 -254.499901) (xy 341.924395 -254.514061)
			(xy 341.873874 -254.520195) (xy 341.823022 -254.518146) (xy 341.773158 -254.507966) (xy 341.725572 -254.489919)
			(xy 341.681498 -254.464473) (xy 341.642076 -254.432286) (xy 341.608328 -254.394192) (xy 341.581127 -254.351178)
			(xy 341.561179 -254.304358) (xy 341.549 -254.254944) (xy 341.544905 -254.204216) (xy 341.226394 -254.204216)
			(xy 341.225899 -254.228823) (xy 341.218004 -254.2774) (xy 341.20242 -254.324081) (xy 341.179549 -254.367658)
			(xy 341.149984 -254.407002) (xy 341.114491 -254.441094) (xy 341.073988 -254.46905) (xy 341.029526 -254.490148)
			(xy 340.982255 -254.50384) (xy 340.9334 -254.509772) (xy 340.884225 -254.507791) (xy 340.836006 -254.497947)
			(xy 340.78999 -254.480495) (xy 340.747369 -254.455888) (xy 340.709248 -254.424763) (xy 340.676613 -254.387926)
			(xy 340.65031 -254.34633) (xy 340.631019 -254.301054) (xy 340.619242 -254.25327) (xy 340.615282 -254.204216)
			(xy 340.296754 -254.204216) (xy 340.296242 -254.229662) (xy 340.288078 -254.279896) (xy 340.271962 -254.32817)
			(xy 340.248311 -254.373233) (xy 340.217738 -254.413919) (xy 340.181034 -254.449174) (xy 340.13915 -254.478084)
			(xy 340.093171 -254.499901) (xy 340.044287 -254.514061) (xy 339.993766 -254.520195) (xy 339.942914 -254.518146)
			(xy 339.89305 -254.507966) (xy 339.845464 -254.489919) (xy 339.80139 -254.464473) (xy 339.761968 -254.432286)
			(xy 339.72822 -254.394192) (xy 339.701019 -254.351178) (xy 339.681071 -254.304358) (xy 339.668892 -254.254944)
			(xy 339.664797 -254.204216) (xy 339.3567 -254.204216) (xy 339.356188 -254.229662) (xy 339.348024 -254.279896)
			(xy 339.331908 -254.32817) (xy 339.308257 -254.373233) (xy 339.277684 -254.413919) (xy 339.24098 -254.449174)
			(xy 339.199096 -254.478084) (xy 339.153117 -254.499901) (xy 339.104233 -254.514061) (xy 339.053712 -254.520195)
			(xy 339.00286 -254.518146) (xy 338.952996 -254.507966) (xy 338.90541 -254.489919) (xy 338.861336 -254.464473)
			(xy 338.821914 -254.432286) (xy 338.788166 -254.394192) (xy 338.760965 -254.351178) (xy 338.741017 -254.304358)
			(xy 338.728838 -254.254944) (xy 338.724743 -254.204216) (xy 338.406222 -254.204216) (xy 338.406222 -254.228664)
			(xy 338.39842 -254.27696) (xy 338.383015 -254.323395) (xy 338.360404 -254.366779) (xy 338.331163 -254.406002)
			(xy 338.296041 -254.440059) (xy 338.255937 -254.46808) (xy 338.211879 -254.489348) (xy 338.164992 -254.503317)
			(xy 338.140802 -254.506984) (xy 338.132674 -254.508254) (xy 338.109814 -254.519176) (xy 338.105728 -254.521238)
			(xy 338.098318 -254.526607) (xy 338.095082 -254.529844) (xy 338.08035 -254.545338) (xy 338.073969 -254.55266)
			(xy 338.06679 -254.570686) (xy 338.06638 -254.58039) (xy 338.06638 -255.014222) (xy 338.254843 -255.014222)
			(xy 338.258938 -254.963494) (xy 338.271117 -254.91408) (xy 338.291065 -254.86726) (xy 338.318266 -254.824246)
			(xy 338.352014 -254.786152) (xy 338.391436 -254.753965) (xy 338.43551 -254.728519) (xy 338.483096 -254.710472)
			(xy 338.53296 -254.700292) (xy 338.583812 -254.698243) (xy 338.634333 -254.704377) (xy 338.683217 -254.718537)
			(xy 338.729196 -254.740354) (xy 338.77108 -254.769264) (xy 338.807784 -254.804519) (xy 338.838357 -254.845205)
			(xy 338.862008 -254.890268) (xy 338.878124 -254.938542) (xy 338.886288 -254.988776) (xy 338.8868 -255.014222)
			(xy 339.205328 -255.014222) (xy 339.209288 -254.965168) (xy 339.221065 -254.917384) (xy 339.240356 -254.872108)
			(xy 339.266659 -254.830512) (xy 339.299294 -254.793675) (xy 339.337415 -254.76255) (xy 339.380036 -254.737943)
			(xy 339.426052 -254.720491) (xy 339.474271 -254.710647) (xy 339.523446 -254.708666) (xy 339.572301 -254.714598)
			(xy 339.619572 -254.72829) (xy 339.664034 -254.749388) (xy 339.704537 -254.777344) (xy 339.74003 -254.811436)
			(xy 339.769595 -254.85078) (xy 339.792466 -254.894357) (xy 339.80805 -254.941038) (xy 339.815945 -254.989615)
			(xy 339.81644 -255.014222) (xy 340.134951 -255.014222) (xy 340.139046 -254.963494) (xy 340.151225 -254.91408)
			(xy 340.171173 -254.86726) (xy 340.198374 -254.824246) (xy 340.232122 -254.786152) (xy 340.271544 -254.753965)
			(xy 340.315618 -254.728519) (xy 340.363204 -254.710472) (xy 340.413068 -254.700292) (xy 340.46392 -254.698243)
			(xy 340.514441 -254.704377) (xy 340.563325 -254.718537) (xy 340.609304 -254.740354) (xy 340.651188 -254.769264)
			(xy 340.687892 -254.804519) (xy 340.718465 -254.845205) (xy 340.742116 -254.890268) (xy 340.758232 -254.938542)
			(xy 340.766396 -254.988776) (xy 340.766908 -255.014222) (xy 341.085182 -255.014222) (xy 341.089142 -254.965168)
			(xy 341.100919 -254.917384) (xy 341.12021 -254.872108) (xy 341.146513 -254.830512) (xy 341.179148 -254.793675)
			(xy 341.217269 -254.76255) (xy 341.25989 -254.737943) (xy 341.305906 -254.720491) (xy 341.354125 -254.710647)
			(xy 341.4033 -254.708666) (xy 341.452155 -254.714598) (xy 341.499426 -254.72829) (xy 341.543888 -254.749388)
			(xy 341.584391 -254.777344) (xy 341.619884 -254.811436) (xy 341.649449 -254.85078) (xy 341.67232 -254.894357)
			(xy 341.687904 -254.941038) (xy 341.695799 -254.989615) (xy 341.696294 -255.014222) (xy 342.014805 -255.014222)
			(xy 342.0189 -254.963494) (xy 342.031079 -254.91408) (xy 342.051027 -254.86726) (xy 342.078228 -254.824246)
			(xy 342.111976 -254.786152) (xy 342.151398 -254.753965) (xy 342.195472 -254.728519) (xy 342.243058 -254.710472)
			(xy 342.292922 -254.700292) (xy 342.343774 -254.698243) (xy 342.394295 -254.704377) (xy 342.443179 -254.718537)
			(xy 342.489158 -254.740354) (xy 342.531042 -254.769264) (xy 342.567746 -254.804519) (xy 342.598319 -254.845205)
			(xy 342.62197 -254.890268) (xy 342.638086 -254.938542) (xy 342.64625 -254.988776) (xy 342.646762 -255.014222)
			(xy 342.954859 -255.014222) (xy 342.958954 -254.963494) (xy 342.971133 -254.91408) (xy 342.991081 -254.86726)
			(xy 343.018282 -254.824246) (xy 343.05203 -254.786152) (xy 343.091452 -254.753965) (xy 343.135526 -254.728519)
			(xy 343.183112 -254.710472) (xy 343.232976 -254.700292) (xy 343.283828 -254.698243) (xy 343.334349 -254.704377)
			(xy 343.383233 -254.718537) (xy 343.429212 -254.740354) (xy 343.471096 -254.769264) (xy 343.5078 -254.804519)
			(xy 343.538373 -254.845205) (xy 343.562024 -254.890268) (xy 343.57814 -254.938542) (xy 343.586304 -254.988776)
			(xy 343.586816 -255.014222) (xy 343.905344 -255.014222) (xy 343.909304 -254.965168) (xy 343.921081 -254.917384)
			(xy 343.940372 -254.872108) (xy 343.966675 -254.830512) (xy 343.99931 -254.793675) (xy 344.037431 -254.76255)
			(xy 344.080052 -254.737943) (xy 344.126068 -254.720491) (xy 344.174287 -254.710647) (xy 344.223462 -254.708666)
			(xy 344.272317 -254.714598) (xy 344.319588 -254.72829) (xy 344.36405 -254.749388) (xy 344.404553 -254.777344)
			(xy 344.440046 -254.811436) (xy 344.469611 -254.85078) (xy 344.492482 -254.894357) (xy 344.508066 -254.941038)
			(xy 344.515961 -254.989615) (xy 344.516456 -255.014222) (xy 345.785198 -255.014222) (xy 345.789158 -254.965168)
			(xy 345.800935 -254.917384) (xy 345.820226 -254.872108) (xy 345.846529 -254.830512) (xy 345.879164 -254.793675)
			(xy 345.917285 -254.76255) (xy 345.959906 -254.737943) (xy 346.005922 -254.720491) (xy 346.054141 -254.710647)
			(xy 346.103316 -254.708666) (xy 346.152171 -254.714598) (xy 346.199442 -254.72829) (xy 346.243904 -254.749388)
			(xy 346.284407 -254.777344) (xy 346.3199 -254.811436) (xy 346.349465 -254.85078) (xy 346.372336 -254.894357)
			(xy 346.38792 -254.941038) (xy 346.395815 -254.989615) (xy 346.39631 -255.014222) (xy 346.395815 -255.038829)
			(xy 346.38792 -255.087406) (xy 346.372336 -255.134087) (xy 346.349465 -255.177664) (xy 346.3199 -255.217008)
			(xy 346.284407 -255.2511) (xy 346.243904 -255.279056) (xy 346.199442 -255.300154) (xy 346.152171 -255.313846)
			(xy 346.103316 -255.319778) (xy 346.054141 -255.317797) (xy 346.005922 -255.307953) (xy 345.959906 -255.290501)
			(xy 345.917285 -255.265894) (xy 345.879164 -255.234769) (xy 345.846529 -255.197932) (xy 345.820226 -255.156336)
			(xy 345.800935 -255.11106) (xy 345.789158 -255.063276) (xy 345.785198 -255.014222) (xy 344.516456 -255.014222)
			(xy 344.515961 -255.038829) (xy 344.508066 -255.087406) (xy 344.492482 -255.134087) (xy 344.469611 -255.177664)
			(xy 344.440046 -255.217008) (xy 344.404553 -255.2511) (xy 344.36405 -255.279056) (xy 344.319588 -255.300154)
			(xy 344.272317 -255.313846) (xy 344.223462 -255.319778) (xy 344.174287 -255.317797) (xy 344.126068 -255.307953)
			(xy 344.080052 -255.290501) (xy 344.037431 -255.265894) (xy 343.99931 -255.234769) (xy 343.966675 -255.197932)
			(xy 343.940372 -255.156336) (xy 343.921081 -255.11106) (xy 343.909304 -255.063276) (xy 343.905344 -255.014222)
			(xy 343.586816 -255.014222) (xy 343.586304 -255.039668) (xy 343.57814 -255.089902) (xy 343.562024 -255.138176)
			(xy 343.538373 -255.183239) (xy 343.5078 -255.223925) (xy 343.471096 -255.25918) (xy 343.429212 -255.28809)
			(xy 343.383233 -255.309907) (xy 343.334349 -255.324067) (xy 343.283828 -255.330201) (xy 343.232976 -255.328152)
			(xy 343.183112 -255.317972) (xy 343.135526 -255.299925) (xy 343.091452 -255.274479) (xy 343.05203 -255.242292)
			(xy 343.018282 -255.204198) (xy 342.991081 -255.161184) (xy 342.971133 -255.114364) (xy 342.958954 -255.06495)
			(xy 342.954859 -255.014222) (xy 342.646762 -255.014222) (xy 342.64625 -255.039668) (xy 342.638086 -255.089902)
			(xy 342.62197 -255.138176) (xy 342.598319 -255.183239) (xy 342.567746 -255.223925) (xy 342.531042 -255.25918)
			(xy 342.489158 -255.28809) (xy 342.443179 -255.309907) (xy 342.394295 -255.324067) (xy 342.343774 -255.330201)
			(xy 342.292922 -255.328152) (xy 342.243058 -255.317972) (xy 342.195472 -255.299925) (xy 342.151398 -255.274479)
			(xy 342.111976 -255.242292) (xy 342.078228 -255.204198) (xy 342.051027 -255.161184) (xy 342.031079 -255.114364)
			(xy 342.0189 -255.06495) (xy 342.014805 -255.014222) (xy 341.696294 -255.014222) (xy 341.695799 -255.038829)
			(xy 341.687904 -255.087406) (xy 341.67232 -255.134087) (xy 341.649449 -255.177664) (xy 341.619884 -255.217008)
			(xy 341.584391 -255.2511) (xy 341.543888 -255.279056) (xy 341.499426 -255.300154) (xy 341.452155 -255.313846)
			(xy 341.4033 -255.319778) (xy 341.354125 -255.317797) (xy 341.305906 -255.307953) (xy 341.25989 -255.290501)
			(xy 341.217269 -255.265894) (xy 341.179148 -255.234769) (xy 341.146513 -255.197932) (xy 341.12021 -255.156336)
			(xy 341.100919 -255.11106) (xy 341.089142 -255.063276) (xy 341.085182 -255.014222) (xy 340.766908 -255.014222)
			(xy 340.766396 -255.039668) (xy 340.758232 -255.089902) (xy 340.742116 -255.138176) (xy 340.718465 -255.183239)
			(xy 340.687892 -255.223925) (xy 340.651188 -255.25918) (xy 340.609304 -255.28809) (xy 340.563325 -255.309907)
			(xy 340.514441 -255.324067) (xy 340.46392 -255.330201) (xy 340.413068 -255.328152) (xy 340.363204 -255.317972)
			(xy 340.315618 -255.299925) (xy 340.271544 -255.274479) (xy 340.232122 -255.242292) (xy 340.198374 -255.204198)
			(xy 340.171173 -255.161184) (xy 340.151225 -255.114364) (xy 340.139046 -255.06495) (xy 340.134951 -255.014222)
			(xy 339.81644 -255.014222) (xy 339.815945 -255.038829) (xy 339.80805 -255.087406) (xy 339.792466 -255.134087)
			(xy 339.769595 -255.177664) (xy 339.74003 -255.217008) (xy 339.704537 -255.2511) (xy 339.664034 -255.279056)
			(xy 339.619572 -255.300154) (xy 339.572301 -255.313846) (xy 339.523446 -255.319778) (xy 339.474271 -255.317797)
			(xy 339.426052 -255.307953) (xy 339.380036 -255.290501) (xy 339.337415 -255.265894) (xy 339.299294 -255.234769)
			(xy 339.266659 -255.197932) (xy 339.240356 -255.156336) (xy 339.221065 -255.11106) (xy 339.209288 -255.063276)
			(xy 339.205328 -255.014222) (xy 338.8868 -255.014222) (xy 338.886288 -255.039668) (xy 338.878124 -255.089902)
			(xy 338.862008 -255.138176) (xy 338.838357 -255.183239) (xy 338.807784 -255.223925) (xy 338.77108 -255.25918)
			(xy 338.729196 -255.28809) (xy 338.683217 -255.309907) (xy 338.634333 -255.324067) (xy 338.583812 -255.330201)
			(xy 338.53296 -255.328152) (xy 338.483096 -255.317972) (xy 338.43551 -255.299925) (xy 338.391436 -255.274479)
			(xy 338.352014 -255.242292) (xy 338.318266 -255.204198) (xy 338.291065 -255.161184) (xy 338.271117 -255.114364)
			(xy 338.258938 -255.06495) (xy 338.254843 -255.014222) (xy 338.06638 -255.014222) (xy 338.06638 -255.448054)
			(xy 338.066809 -255.457753) (xy 338.073987 -255.475774) (xy 338.08035 -255.483106) (xy 338.095082 -255.4986)
			(xy 338.098322 -255.501832) (xy 338.105731 -255.507202) (xy 338.109814 -255.509268) (xy 338.132674 -255.52019)
			(xy 338.140802 -255.52146) (xy 338.164983 -255.525111) (xy 338.211837 -255.539105) (xy 338.255861 -255.560391)
			(xy 338.295928 -255.588423) (xy 338.331013 -255.622485) (xy 338.360219 -255.661705) (xy 338.382797 -255.70508)
			(xy 338.398171 -255.7515) (xy 338.405948 -255.799778) (xy 338.406486 -255.824228) (xy 338.724743 -255.824228)
			(xy 338.728838 -255.7735) (xy 338.741017 -255.724086) (xy 338.760965 -255.677266) (xy 338.788166 -255.634252)
			(xy 338.821914 -255.596158) (xy 338.861336 -255.563971) (xy 338.90541 -255.538525) (xy 338.952996 -255.520478)
			(xy 339.00286 -255.510298) (xy 339.053712 -255.508249) (xy 339.104233 -255.514383) (xy 339.153117 -255.528543)
			(xy 339.199096 -255.55036) (xy 339.24098 -255.57927) (xy 339.277684 -255.614525) (xy 339.308257 -255.655211)
			(xy 339.331908 -255.700274) (xy 339.348024 -255.748548) (xy 339.356188 -255.798782) (xy 339.3567 -255.824228)
			(xy 339.664797 -255.824228) (xy 339.668892 -255.7735) (xy 339.681071 -255.724086) (xy 339.701019 -255.677266)
			(xy 339.72822 -255.634252) (xy 339.761968 -255.596158) (xy 339.80139 -255.563971) (xy 339.845464 -255.538525)
			(xy 339.89305 -255.520478) (xy 339.942914 -255.510298) (xy 339.993766 -255.508249) (xy 340.044287 -255.514383)
			(xy 340.093171 -255.528543) (xy 340.13915 -255.55036) (xy 340.181034 -255.57927) (xy 340.217738 -255.614525)
			(xy 340.248311 -255.655211) (xy 340.271962 -255.700274) (xy 340.288078 -255.748548) (xy 340.296242 -255.798782)
			(xy 340.296754 -255.824228) (xy 340.615282 -255.824228) (xy 340.619242 -255.775174) (xy 340.631019 -255.72739)
			(xy 340.65031 -255.682114) (xy 340.676613 -255.640518) (xy 340.709248 -255.603681) (xy 340.747369 -255.572556)
			(xy 340.78999 -255.547949) (xy 340.836006 -255.530497) (xy 340.884225 -255.520653) (xy 340.9334 -255.518672)
			(xy 340.982255 -255.524604) (xy 341.029526 -255.538296) (xy 341.073988 -255.559394) (xy 341.114491 -255.58735)
			(xy 341.149984 -255.621442) (xy 341.179549 -255.660786) (xy 341.20242 -255.704363) (xy 341.218004 -255.751044)
			(xy 341.225899 -255.799621) (xy 341.226394 -255.824228) (xy 341.544905 -255.824228) (xy 341.549 -255.7735)
			(xy 341.561179 -255.724086) (xy 341.581127 -255.677266) (xy 341.608328 -255.634252) (xy 341.642076 -255.596158)
			(xy 341.681498 -255.563971) (xy 341.725572 -255.538525) (xy 341.773158 -255.520478) (xy 341.823022 -255.510298)
			(xy 341.873874 -255.508249) (xy 341.924395 -255.514383) (xy 341.973279 -255.528543) (xy 342.019258 -255.55036)
			(xy 342.061142 -255.57927) (xy 342.097846 -255.614525) (xy 342.128419 -255.655211) (xy 342.15207 -255.700274)
			(xy 342.168186 -255.748548) (xy 342.17635 -255.798782) (xy 342.176862 -255.824228) (xy 342.49539 -255.824228)
			(xy 342.49935 -255.775174) (xy 342.511127 -255.72739) (xy 342.530418 -255.682114) (xy 342.556721 -255.640518)
			(xy 342.589356 -255.603681) (xy 342.627477 -255.572556) (xy 342.670098 -255.547949) (xy 342.716114 -255.530497)
			(xy 342.764333 -255.520653) (xy 342.813508 -255.518672) (xy 342.862363 -255.524604) (xy 342.909634 -255.538296)
			(xy 342.954096 -255.559394) (xy 342.994599 -255.58735) (xy 343.030092 -255.621442) (xy 343.059657 -255.660786)
			(xy 343.082528 -255.704363) (xy 343.098112 -255.751044) (xy 343.106007 -255.799621) (xy 343.106502 -255.824228)
			(xy 343.424759 -255.824228) (xy 343.428854 -255.7735) (xy 343.441033 -255.724086) (xy 343.460981 -255.677266)
			(xy 343.488182 -255.634252) (xy 343.52193 -255.596158) (xy 343.561352 -255.563971) (xy 343.605426 -255.538525)
			(xy 343.653012 -255.520478) (xy 343.702876 -255.510298) (xy 343.753728 -255.508249) (xy 343.804249 -255.514383)
			(xy 343.853133 -255.528543) (xy 343.899112 -255.55036) (xy 343.940996 -255.57927) (xy 343.9777 -255.614525)
			(xy 344.008273 -255.655211) (xy 344.031924 -255.700274) (xy 344.04804 -255.748548) (xy 344.056204 -255.798782)
			(xy 344.056716 -255.824228) (xy 345.315298 -255.824228) (xy 345.319258 -255.775174) (xy 345.331035 -255.72739)
			(xy 345.350326 -255.682114) (xy 345.376629 -255.640518) (xy 345.409264 -255.603681) (xy 345.447385 -255.572556)
			(xy 345.490006 -255.547949) (xy 345.536022 -255.530497) (xy 345.584241 -255.520653) (xy 345.633416 -255.518672)
			(xy 345.682271 -255.524604) (xy 345.729542 -255.538296) (xy 345.774004 -255.559394) (xy 345.814507 -255.58735)
			(xy 345.85 -255.621442) (xy 345.879565 -255.660786) (xy 345.902436 -255.704363) (xy 345.91802 -255.751044)
			(xy 345.925915 -255.799621) (xy 345.92641 -255.824228) (xy 347.195406 -255.824228) (xy 347.199366 -255.775174)
			(xy 347.211143 -255.72739) (xy 347.230434 -255.682114) (xy 347.256737 -255.640518) (xy 347.289372 -255.603681)
			(xy 347.327493 -255.572556) (xy 347.370114 -255.547949) (xy 347.41613 -255.530497) (xy 347.464349 -255.520653)
			(xy 347.513524 -255.518672) (xy 347.562379 -255.524604) (xy 347.60965 -255.538296) (xy 347.654112 -255.559394)
			(xy 347.694615 -255.58735) (xy 347.730108 -255.621442) (xy 347.759673 -255.660786) (xy 347.782544 -255.704363)
			(xy 347.798128 -255.751044) (xy 347.806023 -255.799621) (xy 347.806518 -255.824228) (xy 347.806023 -255.848835)
			(xy 347.798128 -255.897412) (xy 347.782544 -255.944093) (xy 347.759673 -255.98767) (xy 347.730108 -256.027014)
			(xy 347.694615 -256.061106) (xy 347.654112 -256.089062) (xy 347.60965 -256.11016) (xy 347.562379 -256.123852)
			(xy 347.513524 -256.129784) (xy 347.464349 -256.127803) (xy 347.41613 -256.117959) (xy 347.370114 -256.100507)
			(xy 347.327493 -256.0759) (xy 347.289372 -256.044775) (xy 347.256737 -256.007938) (xy 347.230434 -255.966342)
			(xy 347.211143 -255.921066) (xy 347.199366 -255.873282) (xy 347.195406 -255.824228) (xy 345.92641 -255.824228)
			(xy 345.925915 -255.848835) (xy 345.91802 -255.897412) (xy 345.902436 -255.944093) (xy 345.879565 -255.98767)
			(xy 345.85 -256.027014) (xy 345.814507 -256.061106) (xy 345.774004 -256.089062) (xy 345.729542 -256.11016)
			(xy 345.682271 -256.123852) (xy 345.633416 -256.129784) (xy 345.584241 -256.127803) (xy 345.536022 -256.117959)
			(xy 345.490006 -256.100507) (xy 345.447385 -256.0759) (xy 345.409264 -256.044775) (xy 345.376629 -256.007938)
			(xy 345.350326 -255.966342) (xy 345.331035 -255.921066) (xy 345.319258 -255.873282) (xy 345.315298 -255.824228)
			(xy 344.056716 -255.824228) (xy 344.056204 -255.849674) (xy 344.04804 -255.899908) (xy 344.031924 -255.948182)
			(xy 344.008273 -255.993245) (xy 343.9777 -256.033931) (xy 343.940996 -256.069186) (xy 343.899112 -256.098096)
			(xy 343.853133 -256.119913) (xy 343.804249 -256.134073) (xy 343.753728 -256.140207) (xy 343.702876 -256.138158)
			(xy 343.653012 -256.127978) (xy 343.605426 -256.109931) (xy 343.561352 -256.084485) (xy 343.52193 -256.052298)
			(xy 343.488182 -256.014204) (xy 343.460981 -255.97119) (xy 343.441033 -255.92437) (xy 343.428854 -255.874956)
			(xy 343.424759 -255.824228) (xy 343.106502 -255.824228) (xy 343.106007 -255.848835) (xy 343.098112 -255.897412)
			(xy 343.082528 -255.944093) (xy 343.059657 -255.98767) (xy 343.030092 -256.027014) (xy 342.994599 -256.061106)
			(xy 342.954096 -256.089062) (xy 342.909634 -256.11016) (xy 342.862363 -256.123852) (xy 342.813508 -256.129784)
			(xy 342.764333 -256.127803) (xy 342.716114 -256.117959) (xy 342.670098 -256.100507) (xy 342.627477 -256.0759)
			(xy 342.589356 -256.044775) (xy 342.556721 -256.007938) (xy 342.530418 -255.966342) (xy 342.511127 -255.921066)
			(xy 342.49935 -255.873282) (xy 342.49539 -255.824228) (xy 342.176862 -255.824228) (xy 342.17635 -255.849674)
			(xy 342.168186 -255.899908) (xy 342.15207 -255.948182) (xy 342.128419 -255.993245) (xy 342.097846 -256.033931)
			(xy 342.061142 -256.069186) (xy 342.019258 -256.098096) (xy 341.973279 -256.119913) (xy 341.924395 -256.134073)
			(xy 341.873874 -256.140207) (xy 341.823022 -256.138158) (xy 341.773158 -256.127978) (xy 341.725572 -256.109931)
			(xy 341.681498 -256.084485) (xy 341.642076 -256.052298) (xy 341.608328 -256.014204) (xy 341.581127 -255.97119)
			(xy 341.561179 -255.92437) (xy 341.549 -255.874956) (xy 341.544905 -255.824228) (xy 341.226394 -255.824228)
			(xy 341.225899 -255.848835) (xy 341.218004 -255.897412) (xy 341.20242 -255.944093) (xy 341.179549 -255.98767)
			(xy 341.149984 -256.027014) (xy 341.114491 -256.061106) (xy 341.073988 -256.089062) (xy 341.029526 -256.11016)
			(xy 340.982255 -256.123852) (xy 340.9334 -256.129784) (xy 340.884225 -256.127803) (xy 340.836006 -256.117959)
			(xy 340.78999 -256.100507) (xy 340.747369 -256.0759) (xy 340.709248 -256.044775) (xy 340.676613 -256.007938)
			(xy 340.65031 -255.966342) (xy 340.631019 -255.921066) (xy 340.619242 -255.873282) (xy 340.615282 -255.824228)
			(xy 340.296754 -255.824228) (xy 340.296242 -255.849674) (xy 340.288078 -255.899908) (xy 340.271962 -255.948182)
			(xy 340.248311 -255.993245) (xy 340.217738 -256.033931) (xy 340.181034 -256.069186) (xy 340.13915 -256.098096)
			(xy 340.093171 -256.119913) (xy 340.044287 -256.134073) (xy 339.993766 -256.140207) (xy 339.942914 -256.138158)
			(xy 339.89305 -256.127978) (xy 339.845464 -256.109931) (xy 339.80139 -256.084485) (xy 339.761968 -256.052298)
			(xy 339.72822 -256.014204) (xy 339.701019 -255.97119) (xy 339.681071 -255.92437) (xy 339.668892 -255.874956)
			(xy 339.664797 -255.824228) (xy 339.3567 -255.824228) (xy 339.356188 -255.849674) (xy 339.348024 -255.899908)
			(xy 339.331908 -255.948182) (xy 339.308257 -255.993245) (xy 339.277684 -256.033931) (xy 339.24098 -256.069186)
			(xy 339.199096 -256.098096) (xy 339.153117 -256.119913) (xy 339.104233 -256.134073) (xy 339.053712 -256.140207)
			(xy 339.00286 -256.138158) (xy 338.952996 -256.127978) (xy 338.90541 -256.109931) (xy 338.861336 -256.084485)
			(xy 338.821914 -256.052298) (xy 338.788166 -256.014204) (xy 338.760965 -255.97119) (xy 338.741017 -255.92437)
			(xy 338.728838 -255.874956) (xy 338.724743 -255.824228) (xy 338.406486 -255.824228) (xy 338.406192 -255.843488)
			(xy 338.401349 -255.881702) (xy 338.396834 -255.900428) (xy 338.395056 -255.907032) (xy 338.39531 -255.919732)
			(xy 338.397088 -255.92659) (xy 338.399046 -255.932929) (xy 338.405731 -255.944382) (xy 338.410296 -255.949196)
			(xy 338.747354 -256.286254) (xy 338.747862 -256.286762) (xy 338.755244 -256.293342) (xy 338.773543 -256.300788)
			(xy 338.783422 -256.30124)
		)
		(stroke
			(width 0)
			(type solid)
		)
		(fill yes)
		(layer "In13.Cu")
		(net "PVDD18_S5_P0")
	)
	(gr_poly
		(pts
			(xy 440.038998 -341.78494) (xy 440.049067 -341.784516) (xy 440.067666 -341.776795) (xy 440.075066 -341.769954)
			(xy 440.873134 -340.971886) (xy 440.873642 -340.971378) (xy 440.88023 -340.963999) (xy 440.887693 -340.9457)
			(xy 440.88812 -340.935818) (xy 440.88812 -320.988182) (xy 440.887694 -320.978113) (xy 440.879977 -320.959511)
			(xy 440.873134 -320.952114) (xy 440.057286 -320.136266) (xy 440.050174 -320.1289) (xy 440.031378 -320.12128)
			(xy 415.752788 -320.12128) (xy 415.742239 -320.121808) (xy 415.722947 -320.130348) (xy 415.71545 -320.13779)
			(xy 415.657538 -320.200528) (xy 415.65068 -320.22034) (xy 415.651442 -320.231262) (xy 415.65322 -320.272918)
			(xy 415.652755 -320.303649) (xy 415.645345 -320.364661) (xy 415.630634 -320.424336) (xy 415.608839 -320.481803)
			(xy 415.580275 -320.536223) (xy 415.545361 -320.586805) (xy 415.504604 -320.632809) (xy 415.4586 -320.673565)
			(xy 415.408018 -320.708479) (xy 415.353597 -320.737041) (xy 415.29613 -320.758836) (xy 415.236455 -320.773546)
			(xy 415.175443 -320.780955) (xy 415.144712 -320.781426) (xy 415.114016 -320.780948) (xy 415.053075 -320.77353)
			(xy 414.993468 -320.758835) (xy 414.936061 -320.737078) (xy 414.881687 -320.708574) (xy 414.856168 -320.69151)
			(xy 414.847416 -320.686039) (xy 414.827212 -320.681911) (xy 414.807008 -320.686039) (xy 414.798256 -320.69151)
			(xy 414.772728 -320.708562) (xy 414.718364 -320.737084) (xy 414.66096 -320.758848) (xy 414.601352 -320.773536)
			(xy 414.540408 -320.780935) (xy 414.509712 -320.781426) (xy 414.479016 -320.780948) (xy 414.418075 -320.77353)
			(xy 414.358468 -320.758835) (xy 414.301061 -320.737078) (xy 414.246687 -320.708574) (xy 414.221168 -320.69151)
			(xy 414.212416 -320.686039) (xy 414.192212 -320.681911) (xy 414.172008 -320.686039) (xy 414.163256 -320.69151)
			(xy 414.137728 -320.708562) (xy 414.083364 -320.737084) (xy 414.02596 -320.758848) (xy 413.966352 -320.773536)
			(xy 413.905408 -320.780935) (xy 413.874712 -320.781426) (xy 413.844016 -320.780948) (xy 413.783075 -320.77353)
			(xy 413.723468 -320.758835) (xy 413.666061 -320.737078) (xy 413.611687 -320.708574) (xy 413.586168 -320.69151)
			(xy 413.577416 -320.686039) (xy 413.557212 -320.681911) (xy 413.537008 -320.686039) (xy 413.528256 -320.69151)
			(xy 413.502728 -320.708562) (xy 413.448364 -320.737084) (xy 413.39096 -320.758848) (xy 413.331352 -320.773536)
			(xy 413.270408 -320.780935) (xy 413.239712 -320.781426) (xy 413.20898 -320.780963) (xy 413.147964 -320.773555)
			(xy 413.088286 -320.758848) (xy 413.030816 -320.737054) (xy 412.976392 -320.708492) (xy 412.925807 -320.673578)
			(xy 412.8798 -320.632821) (xy 412.839041 -320.586816) (xy 412.804124 -320.536234) (xy 412.775558 -320.481811)
			(xy 412.753761 -320.424342) (xy 412.73905 -320.364665) (xy 412.731639 -320.30365) (xy 412.731204 -320.272918)
			(xy 412.732728 -320.232278) (xy 412.732982 -320.2305) (xy 412.732982 -320.226944) (xy 412.732591 -320.21742)
			(xy 412.725684 -320.199669) (xy 412.71952 -320.1924) (xy 412.66872 -320.137536) (xy 412.6612 -320.130154)
			(xy 412.641908 -320.12174) (xy 412.631382 -320.12128) (xy 408.397202 -320.12128) (xy 408.387132 -320.120857)
			(xy 408.368529 -320.113141) (xy 408.361134 -320.106294) (xy 404.571962 -316.317122) (xy 404.560993 -316.306904)
			(xy 404.53457 -316.292774) (xy 404.505186 -316.286913) (xy 404.475365 -316.289825) (xy 404.447669 -316.301258)
			(xy 404.424479 -316.320232) (xy 404.407787 -316.345115) (xy 404.399028 -316.37377) (xy 404.39848 -316.38875)
			(xy 404.39848 -318.177926) (xy 404.397998 -318.202765) (xy 404.389961 -318.251788) (xy 404.374088 -318.298861)
			(xy 404.350798 -318.34274) (xy 404.320707 -318.382267) (xy 404.302976 -318.399668) (xy 404.30196 -318.400684)
			(xy 403.911816 -318.790828) (xy 403.9108 -318.791844) (xy 403.893374 -318.809547) (xy 403.853844 -318.839621)
			(xy 403.809969 -318.862906) (xy 403.762906 -318.878787) (xy 403.713893 -318.886847) (xy 403.689058 -318.887348)
			(xy 395.69898 -318.887348) (xy 395.673548 -318.886839) (xy 395.623386 -318.878407) (xy 395.575316 -318.86178)
			(xy 395.530665 -318.837418) (xy 395.490668 -318.805993) (xy 395.473174 -318.787526) (xy 395.47165 -318.785748)
			(xy 394.637514 -317.951612) (xy 394.63726 -317.951612) (xy 394.620595 -317.934341) (xy 394.592369 -317.895526)
			(xy 394.570581 -317.852765) (xy 394.55577 -317.807116) (xy 394.548302 -317.759709) (xy 394.547852 -317.735712)
			(xy 394.547852 -315.14669) (xy 394.54833 -315.122699) (xy 394.555844 -315.07531) (xy 394.570671 -315.029677)
			(xy 394.592447 -314.986922) (xy 394.620636 -314.948094) (xy 394.63726 -314.93079) (xy 394.637514 -314.93079)
			(xy 394.734796 -314.833508) (xy 394.73632 -314.83173) (xy 394.753813 -314.813262) (xy 394.793809 -314.781838)
			(xy 394.83846 -314.757477) (xy 394.886532 -314.740853) (xy 394.936694 -314.732427) (xy 394.962126 -314.731908)
			(xy 402.741638 -314.731908) (xy 402.756616 -314.731343) (xy 402.785265 -314.722588) (xy 402.810145 -314.7059)
			(xy 402.829115 -314.682715) (xy 402.840546 -314.655024) (xy 402.843455 -314.625208) (xy 402.837592 -314.595829)
			(xy 402.823461 -314.569414) (xy 402.813266 -314.558426) (xy 393.15009 -304.89525) (xy 393.142926 -304.888715)
			(xy 393.125109 -304.881104) (xy 393.10574 -304.880633) (xy 393.096496 -304.883566) (xy 392.995658 -304.921158)
			(xy 392.977878 -304.94478) (xy 392.976862 -304.959766) (xy 392.971279 -305.030815) (xy 392.95307 -305.172178)
			(xy 392.926884 -305.312284) (xy 392.892806 -305.450682) (xy 392.850945 -305.586928) (xy 392.801436 -305.720585)
			(xy 392.744438 -305.851223) (xy 392.680133 -305.978425) (xy 392.608727 -306.10178) (xy 392.530451 -306.220894)
			(xy 392.445555 -306.335384) (xy 392.354311 -306.444882) (xy 392.257013 -306.549038) (xy 392.153973 -306.647517)
			(xy 392.045522 -306.740002) (xy 391.932007 -306.826198) (xy 391.813793 -306.905826) (xy 391.691259 -306.978633)
			(xy 391.564799 -307.044384) (xy 391.434818 -307.102867) (xy 391.301735 -307.153897) (xy 391.165974 -307.197307)
			(xy 391.027974 -307.23296) (xy 390.888176 -307.260741) (xy 390.747029 -307.28056) (xy 390.604986 -307.292355)
			(xy 390.462503 -307.296087) (xy 390.320037 -307.291744) (xy 390.178046 -307.27934) (xy 390.036986 -307.258915)
			(xy 389.897308 -307.230535) (xy 389.759462 -307.19429) (xy 389.623889 -307.150297) (xy 389.491025 -307.098698)
			(xy 389.361297 -307.039657) (xy 389.23512 -306.973364) (xy 389.1129 -306.900033) (xy 388.995029 -306.819897)
			(xy 388.881884 -306.733216) (xy 388.773831 -306.640266) (xy 388.671214 -306.541346) (xy 388.574364 -306.436774)
			(xy 388.483591 -306.326885) (xy 388.399187 -306.212032) (xy 388.321422 -306.092583) (xy 388.250547 -305.968922)
			(xy 388.186788 -305.841446) (xy 388.130351 -305.710564) (xy 388.081415 -305.576696) (xy 388.04014 -305.440272)
			(xy 388.006656 -305.301729) (xy 387.981071 -305.161512) (xy 387.963469 -305.020072) (xy 387.953904 -304.877861)
			(xy 387.952407 -304.735338) (xy 387.958985 -304.592958) (xy 387.973614 -304.451179) (xy 387.99625 -304.310456)
			(xy 388.026818 -304.17124) (xy 388.06522 -304.03398) (xy 388.111334 -303.899114) (xy 388.165012 -303.767076)
			(xy 388.22608 -303.638289) (xy 388.294344 -303.513168) (xy 388.369584 -303.392113) (xy 388.451558 -303.275514)
			(xy 388.540004 -303.163743) (xy 388.634638 -303.057161) (xy 388.735155 -302.956109) (xy 388.841234 -302.860911)
			(xy 388.952533 -302.771873) (xy 389.068696 -302.689281) (xy 389.18935 -302.613399) (xy 389.314107 -302.544473)
			(xy 389.442567 -302.482721) (xy 389.574319 -302.428344) (xy 389.708938 -302.381515) (xy 389.845993 -302.342384)
			(xy 389.985044 -302.311078) (xy 390.125645 -302.287696) (xy 390.267344 -302.272314) (xy 390.409687 -302.264981)
			(xy 390.552217 -302.265721) (xy 390.694476 -302.274531) (xy 390.836008 -302.291383) (xy 390.976359 -302.316222)
			(xy 391.115077 -302.34897) (xy 391.251719 -302.389522) (xy 391.385845 -302.437746) (xy 391.517024 -302.493488)
			(xy 391.644837 -302.556569) (xy 391.707116 -302.591216) (xy 391.713017 -302.59425) (xy 391.725882 -302.597475)
			(xy 391.732516 -302.597566) (xy 391.745724 -302.597566) (xy 391.833354 -302.546512) (xy 391.840846 -302.541758)
			(xy 391.85219 -302.528128) (xy 391.858184 -302.511438) (xy 391.8585 -302.50257) (xy 391.8585 -295.465246)
			(xy 391.858111 -295.45572) (xy 391.851162 -295.437982) (xy 391.838209 -295.424013) (xy 391.829798 -295.419526)
			(xy 391.734294 -295.373298) (xy 391.705592 -295.376346) (xy 391.693908 -295.38549) (xy 391.67356 -295.40092)
			(xy 391.628792 -295.42548) (xy 391.58056 -295.442243) (xy 391.530209 -295.450741) (xy 391.504678 -295.451276)
			(xy 391.480687 -295.450828) (xy 391.433296 -295.443318) (xy 391.387663 -295.428488) (xy 391.344913 -295.406701)
			(xy 391.306096 -295.378494) (xy 391.272171 -295.344562) (xy 391.243971 -295.305741) (xy 391.222192 -295.262987)
			(xy 391.207369 -295.217351) (xy 391.199868 -295.169959) (xy 391.19937 -295.145968) (xy 391.199842 -295.12199)
			(xy 391.207344 -295.074626) (xy 391.222159 -295.029016) (xy 391.243921 -294.986284) (xy 391.272097 -294.947479)
			(xy 391.305993 -294.913556) (xy 391.344775 -294.885349) (xy 391.387491 -294.863552) (xy 391.433088 -294.848701)
			(xy 391.480447 -294.841161) (xy 391.504424 -294.84066) (xy 391.50544 -294.84066) (xy 391.520172 -294.840914)
			(xy 391.53592 -294.841676) (xy 391.562336 -294.825166) (xy 391.607294 -294.724328) (xy 391.610996 -294.714819)
			(xy 391.611331 -294.694434) (xy 391.603712 -294.675522) (xy 391.59688 -294.66794) (xy 391.116566 -294.187626)
			(xy 391.109454 -294.18026) (xy 391.090658 -294.17264) (xy 390.49706 -294.17264) (xy 390.486129 -294.173153)
			(xy 390.46624 -294.18223) (xy 390.458706 -294.190166) (xy 390.40816 -294.248586) (xy 390.401877 -294.256468)
			(xy 390.395578 -294.275598) (xy 390.395968 -294.28567) (xy 390.396222 -294.287448) (xy 390.396476 -294.28948)
			(xy 390.398143 -294.301028) (xy 390.399927 -294.324295) (xy 390.400032 -294.335962) (xy 390.39951 -294.361217)
			(xy 390.391197 -294.411039) (xy 390.374796 -294.458813) (xy 390.350755 -294.503236) (xy 390.319731 -294.543096)
			(xy 390.282569 -294.577306) (xy 390.240283 -294.604932) (xy 390.194027 -294.625222) (xy 390.145062 -294.637622)
			(xy 390.094724 -294.641793) (xy 390.044386 -294.637622) (xy 389.995421 -294.625222) (xy 389.949165 -294.604932)
			(xy 389.906879 -294.577306) (xy 389.869717 -294.543096) (xy 389.838693 -294.503236) (xy 389.814652 -294.458813)
			(xy 389.798251 -294.411039) (xy 389.789938 -294.361217) (xy 389.789416 -294.335962) (xy 389.789528 -294.324295)
			(xy 389.791312 -294.301029) (xy 389.792972 -294.28948) (xy 389.793226 -294.287448) (xy 389.79348 -294.28567)
			(xy 389.793737 -294.275614) (xy 389.787467 -294.256523) (xy 389.781288 -294.248586) (xy 389.730742 -294.190166)
			(xy 389.723191 -294.182249) (xy 389.703316 -294.173155) (xy 389.692388 -294.17264) (xy 389.55726 -294.17264)
			(xy 389.546329 -294.173153) (xy 389.52644 -294.18223) (xy 389.518906 -294.190166) (xy 389.46836 -294.248586)
			(xy 389.462077 -294.256468) (xy 389.455778 -294.275598) (xy 389.456168 -294.28567) (xy 389.456422 -294.287448)
			(xy 389.456676 -294.28948) (xy 389.458343 -294.301028) (xy 389.460127 -294.324295) (xy 389.460232 -294.335962)
			(xy 389.45971 -294.361217) (xy 389.451397 -294.411039) (xy 389.434996 -294.458813) (xy 389.410955 -294.503236)
			(xy 389.379931 -294.543096) (xy 389.342769 -294.577306) (xy 389.300483 -294.604932) (xy 389.254227 -294.625222)
			(xy 389.205262 -294.637622) (xy 389.154924 -294.641793) (xy 389.104586 -294.637622) (xy 389.055621 -294.625222)
			(xy 389.009365 -294.604932) (xy 388.967079 -294.577306) (xy 388.929917 -294.543096) (xy 388.898893 -294.503236)
			(xy 388.874852 -294.458813) (xy 388.858451 -294.411039) (xy 388.850138 -294.361217) (xy 388.849616 -294.335962)
			(xy 388.849728 -294.324295) (xy 388.851512 -294.301029) (xy 388.853172 -294.28948) (xy 388.853426 -294.287448)
			(xy 388.85368 -294.28567) (xy 388.853937 -294.275614) (xy 388.847667 -294.256523) (xy 388.841488 -294.248586)
			(xy 388.790942 -294.190166) (xy 388.783391 -294.182249) (xy 388.763516 -294.173155) (xy 388.752588 -294.17264)
			(xy 388.617206 -294.17264) (xy 388.60628 -294.173164) (xy 388.586408 -294.182255) (xy 388.578852 -294.190166)
			(xy 388.528306 -294.248586) (xy 388.522028 -294.25647) (xy 388.515736 -294.275599) (xy 388.516114 -294.28567)
			(xy 388.516368 -294.287448) (xy 388.516622 -294.28948) (xy 388.518289 -294.301028) (xy 388.520073 -294.324295)
			(xy 388.520178 -294.335962) (xy 388.519656 -294.361217) (xy 388.511343 -294.411039) (xy 388.494942 -294.458813)
			(xy 388.470901 -294.503236) (xy 388.439877 -294.543096) (xy 388.402715 -294.577306) (xy 388.360429 -294.604932)
			(xy 388.314173 -294.625222) (xy 388.265208 -294.637622) (xy 388.21487 -294.641793) (xy 388.164532 -294.637622)
			(xy 388.115567 -294.625222) (xy 388.069311 -294.604932) (xy 388.027025 -294.577306) (xy 387.989863 -294.543096)
			(xy 387.958839 -294.503236) (xy 387.934798 -294.458813) (xy 387.918397 -294.411039) (xy 387.910084 -294.361217)
			(xy 387.909562 -294.335962) (xy 387.909674 -294.324295) (xy 387.911458 -294.301029) (xy 387.913118 -294.28948)
			(xy 387.913372 -294.287448) (xy 387.913626 -294.28567) (xy 387.913884 -294.275614) (xy 387.907618 -294.256519)
			(xy 387.901434 -294.248586) (xy 387.850888 -294.190166) (xy 387.843334 -294.182258) (xy 387.823458 -294.173185)
			(xy 387.812534 -294.17264) (xy 387.677152 -294.17264) (xy 387.666221 -294.173155) (xy 387.646335 -294.182234)
			(xy 387.638798 -294.190166) (xy 387.588252 -294.248586) (xy 387.58197 -294.256469) (xy 387.575671 -294.275598)
			(xy 387.57606 -294.28567) (xy 387.576314 -294.287448) (xy 387.576568 -294.28948) (xy 387.578235 -294.301028)
			(xy 387.580019 -294.324295) (xy 387.580124 -294.335962) (xy 387.579602 -294.361217) (xy 387.571289 -294.411039)
			(xy 387.554888 -294.458813) (xy 387.530847 -294.503236) (xy 387.499823 -294.543096) (xy 387.462661 -294.577306)
			(xy 387.420375 -294.604932) (xy 387.374119 -294.625222) (xy 387.325154 -294.637622) (xy 387.274816 -294.641793)
			(xy 387.224478 -294.637622) (xy 387.175513 -294.625222) (xy 387.129257 -294.604932) (xy 387.086971 -294.577306)
			(xy 387.049809 -294.543096) (xy 387.018785 -294.503236) (xy 386.994744 -294.458813) (xy 386.978343 -294.411039)
			(xy 386.97003 -294.361217) (xy 386.969508 -294.335962) (xy 386.96962 -294.324295) (xy 386.971404 -294.301029)
			(xy 386.973064 -294.28948) (xy 386.973318 -294.287448) (xy 386.973572 -294.28567) (xy 386.97383 -294.275613)
			(xy 386.967569 -294.256515) (xy 386.96138 -294.248586) (xy 386.910834 -294.190166) (xy 386.903283 -294.18225)
			(xy 386.883407 -294.17316) (xy 386.87248 -294.17264) (xy 386.737098 -294.17264) (xy 386.726172 -294.173166)
			(xy 386.706303 -294.182258) (xy 386.698744 -294.190166) (xy 386.648198 -294.248586) (xy 386.641921 -294.256471)
			(xy 386.63563 -294.275599) (xy 386.636006 -294.28567) (xy 386.63626 -294.287448) (xy 386.636514 -294.28948)
			(xy 386.638181 -294.301028) (xy 386.639965 -294.324295) (xy 386.64007 -294.335962) (xy 386.639548 -294.361217)
			(xy 386.631235 -294.411039) (xy 386.614834 -294.458813) (xy 386.590793 -294.503236) (xy 386.559769 -294.543096)
			(xy 386.522607 -294.577306) (xy 386.480321 -294.604932) (xy 386.434065 -294.625222) (xy 386.3851 -294.637622)
			(xy 386.334762 -294.641793) (xy 386.284424 -294.637622) (xy 386.235459 -294.625222) (xy 386.189203 -294.604932)
			(xy 386.146917 -294.577306) (xy 386.109755 -294.543096) (xy 386.078731 -294.503236) (xy 386.05469 -294.458813)
			(xy 386.038289 -294.411039) (xy 386.029976 -294.361217) (xy 386.029454 -294.335962) (xy 386.029566 -294.324295)
			(xy 386.03135 -294.301029) (xy 386.03301 -294.28948) (xy 386.033264 -294.287448) (xy 386.033518 -294.28567)
			(xy 386.033776 -294.275614) (xy 386.027509 -294.25652) (xy 386.021326 -294.248586) (xy 385.97078 -294.190166)
			(xy 385.963231 -294.182242) (xy 385.943356 -294.173134) (xy 385.932426 -294.17264) (xy 384.857244 -294.17264)
			(xy 384.846314 -294.173157) (xy 384.826431 -294.182238) (xy 384.81889 -294.190166) (xy 384.768344 -294.248586)
			(xy 384.762063 -294.256469) (xy 384.755765 -294.275599) (xy 384.756152 -294.28567) (xy 384.756406 -294.287448)
			(xy 384.75666 -294.28948) (xy 384.758327 -294.301028) (xy 384.76011 -294.324295) (xy 384.760216 -294.335962)
			(xy 384.759694 -294.361217) (xy 384.751381 -294.411039) (xy 384.73498 -294.458813) (xy 384.710939 -294.503236)
			(xy 384.679915 -294.543096) (xy 384.642753 -294.577306) (xy 384.600467 -294.604932) (xy 384.554211 -294.625222)
			(xy 384.505246 -294.637622) (xy 384.454908 -294.641793) (xy 384.40457 -294.637622) (xy 384.355605 -294.625222)
			(xy 384.309349 -294.604932) (xy 384.267063 -294.577306) (xy 384.229901 -294.543096) (xy 384.198877 -294.503236)
			(xy 384.174836 -294.458813) (xy 384.158435 -294.411039) (xy 384.150122 -294.361217) (xy 384.1496 -294.335962)
			(xy 384.149712 -294.324295) (xy 384.151495 -294.301029) (xy 384.153156 -294.28948) (xy 384.15341 -294.287448)
			(xy 384.153664 -294.28567) (xy 384.153922 -294.275613) (xy 384.14766 -294.256516) (xy 384.141472 -294.248586)
			(xy 384.090926 -294.190166) (xy 384.083374 -294.182251) (xy 384.063499 -294.173164) (xy 384.052572 -294.17264)
			(xy 383.91719 -294.17264) (xy 383.906265 -294.173167) (xy 383.886398 -294.182262) (xy 383.878836 -294.190166)
			(xy 383.82829 -294.248586) (xy 383.822014 -294.256471) (xy 383.815724 -294.275599) (xy 383.816098 -294.28567)
			(xy 383.816352 -294.287448) (xy 383.816606 -294.28948) (xy 383.818273 -294.301028) (xy 383.820057 -294.324295)
			(xy 383.820162 -294.335962) (xy 383.81964 -294.361217) (xy 383.811327 -294.411039) (xy 383.794926 -294.458813)
			(xy 383.770885 -294.503236) (xy 383.739861 -294.543096) (xy 383.702699 -294.577306) (xy 383.660413 -294.604932)
			(xy 383.614157 -294.625222) (xy 383.565192 -294.637622) (xy 383.514854 -294.641793) (xy 383.464516 -294.637622)
			(xy 383.415551 -294.625222) (xy 383.369295 -294.604932) (xy 383.327009 -294.577306) (xy 383.289847 -294.543096)
			(xy 383.258823 -294.503236) (xy 383.234782 -294.458813) (xy 383.218381 -294.411039) (xy 383.210068 -294.361217)
			(xy 383.209546 -294.335962) (xy 383.209658 -294.324295) (xy 383.211442 -294.301029) (xy 383.213102 -294.28948)
			(xy 383.213356 -294.287448) (xy 383.21361 -294.28567) (xy 383.213868 -294.275614) (xy 383.2076 -294.25652)
			(xy 383.201418 -294.248586) (xy 383.150872 -294.190166) (xy 383.143323 -294.182244) (xy 383.123448 -294.173139)
			(xy 383.112518 -294.17264) (xy 382.977136 -294.17264) (xy 382.966207 -294.173158) (xy 382.946326 -294.182241)
			(xy 382.938782 -294.190166) (xy 382.888236 -294.248586) (xy 382.881955 -294.256469) (xy 382.875659 -294.275599)
			(xy 382.876044 -294.28567) (xy 382.876298 -294.287448) (xy 382.876552 -294.28948) (xy 382.878219 -294.301028)
			(xy 382.880002 -294.324295) (xy 382.880108 -294.335962) (xy 382.879586 -294.361217) (xy 382.871273 -294.411039)
			(xy 382.854872 -294.458813) (xy 382.830831 -294.503236) (xy 382.799807 -294.543096) (xy 382.762645 -294.577306)
			(xy 382.720359 -294.604932) (xy 382.674103 -294.625222) (xy 382.625138 -294.637622) (xy 382.5748 -294.641793)
			(xy 382.524462 -294.637622) (xy 382.475497 -294.625222) (xy 382.429241 -294.604932) (xy 382.386955 -294.577306)
			(xy 382.349793 -294.543096) (xy 382.318769 -294.503236) (xy 382.294728 -294.458813) (xy 382.278327 -294.411039)
			(xy 382.270014 -294.361217) (xy 382.269492 -294.335962) (xy 382.270059 -294.310143) (xy 382.278797 -294.259249)
			(xy 382.295966 -294.210549) (xy 382.321079 -294.165428) (xy 382.35342 -294.125171) (xy 382.372362 -294.107616)
			(xy 382.377696 -294.10279) (xy 382.387856 -294.086788) (xy 382.39124 -294.081033) (xy 382.395229 -294.068299)
			(xy 382.39573 -294.061642) (xy 382.398524 -293.991538) (xy 382.39843 -293.981039) (xy 382.390819 -293.961494)
			(xy 382.383792 -293.953692) (xy 382.259586 -293.829486) (xy 382.252474 -293.82212) (xy 382.233678 -293.8145)
			(xy 382.204976 -293.8145) (xy 382.197356 -293.816786) (xy 382.174839 -293.82353) (xy 382.128401 -293.8308)
			(xy 382.1049 -293.831264) (xy 382.080908 -293.830818) (xy 382.033515 -293.823311) (xy 381.98788 -293.808482)
			(xy 381.945127 -293.786696) (xy 381.906309 -293.758489) (xy 381.872382 -293.724557) (xy 381.844181 -293.685735)
			(xy 381.822401 -293.642979) (xy 381.807579 -293.597342) (xy 381.800079 -293.549948) (xy 381.799592 -293.525956)
			(xy 381.80012 -293.500582) (xy 381.808551 -293.450538) (xy 381.816356 -293.426388) (xy 381.820928 -293.412672)
			(xy 381.814578 -293.384478) (xy 381.604266 -293.174166) (xy 381.597418 -293.166769) (xy 381.589685 -293.14817)
			(xy 381.58928 -293.138098) (xy 381.58928 -293.059866) (xy 381.588854 -293.05058) (xy 381.582222 -293.03323)
			(xy 381.569869 -293.019359) (xy 381.561848 -293.014654) (xy 381.552704 -293.010082) (xy 381.548132 -293.008812)
			(xy 381.524783 -293.001376) (xy 381.480636 -292.980119) (xy 381.440446 -292.95209) (xy 381.405241 -292.918009)
			(xy 381.375926 -292.878748) (xy 381.353249 -292.835313) (xy 381.337792 -292.788816) (xy 381.329951 -292.740449)
			(xy 381.329438 -292.71595) (xy 381.329916 -292.691187) (xy 381.337905 -292.642311) (xy 381.353682 -292.595366)
			(xy 381.376833 -292.551585) (xy 381.40675 -292.512116) (xy 381.442648 -292.477997) (xy 381.483584 -292.450123)
			(xy 381.528484 -292.429225) (xy 381.552196 -292.422072) (xy 381.568706 -292.417246) (xy 381.58928 -292.390322)
			(xy 381.58928 -291.439854) (xy 381.588869 -291.430559) (xy 381.582256 -291.413185) (xy 381.569907 -291.399289)
			(xy 381.561848 -291.394642) (xy 381.552704 -291.39007) (xy 381.548132 -291.3888) (xy 381.52478 -291.381366)
			(xy 381.480625 -291.360111) (xy 381.440426 -291.332084) (xy 381.405213 -291.298005) (xy 381.375886 -291.258745)
			(xy 381.353197 -291.215309) (xy 381.337728 -291.168811) (xy 381.329873 -291.12044) (xy 381.329438 -291.095938)
			(xy 381.329916 -291.071176) (xy 381.337907 -291.022301) (xy 381.353686 -290.975357) (xy 381.376838 -290.931578)
			(xy 381.406755 -290.892111) (xy 381.442652 -290.857994) (xy 381.483588 -290.830121) (xy 381.528488 -290.809223)
			(xy 381.552196 -290.80206) (xy 381.568706 -290.797234) (xy 381.58928 -290.77031) (xy 381.58928 -289.819842)
			(xy 381.588867 -289.810549) (xy 381.582251 -289.793178) (xy 381.569902 -289.779285) (xy 381.561848 -289.77463)
			(xy 381.552704 -289.770058) (xy 381.548132 -289.768788) (xy 381.52478 -289.761354) (xy 381.480627 -289.740098)
			(xy 381.440429 -289.712072) (xy 381.405216 -289.677992) (xy 381.375891 -289.638731) (xy 381.353204 -289.595296)
			(xy 381.337736 -289.548798) (xy 381.329884 -289.500427) (xy 381.329438 -289.475926) (xy 381.329917 -289.451164)
			(xy 381.33791 -289.402291) (xy 381.35369 -289.355349) (xy 381.376842 -289.311571) (xy 381.40676 -289.272106)
			(xy 381.442657 -289.23799) (xy 381.483592 -289.210118) (xy 381.528491 -289.189222) (xy 381.552196 -289.182048)
			(xy 381.568706 -289.177222) (xy 381.58928 -289.150298) (xy 381.58928 -288.200084) (xy 381.588857 -288.190796)
			(xy 381.582229 -288.173441) (xy 381.569876 -288.159565) (xy 381.561848 -288.154872) (xy 381.552704 -288.1503)
			(xy 381.548132 -288.14903) (xy 381.524783 -288.141594) (xy 381.480634 -288.120337) (xy 381.440442 -288.09231)
			(xy 381.405236 -288.058229) (xy 381.375917 -288.018968) (xy 381.353238 -287.975533) (xy 381.337779 -287.929035)
			(xy 381.329935 -287.880668) (xy 381.329438 -287.856168) (xy 381.329914 -287.831404) (xy 381.337901 -287.782526)
			(xy 381.353677 -287.735578) (xy 381.376827 -287.691795) (xy 381.406743 -287.652324) (xy 381.442641 -287.618203)
			(xy 381.483577 -287.590327) (xy 381.528479 -287.569427) (xy 381.552196 -287.56229) (xy 381.568706 -287.557464)
			(xy 381.58928 -287.53054) (xy 381.58928 -286.580072) (xy 381.588855 -286.570785) (xy 381.582224 -286.553434)
			(xy 381.569871 -286.539561) (xy 381.561848 -286.53486) (xy 381.552704 -286.530288) (xy 381.548132 -286.529018)
			(xy 381.524783 -286.521582) (xy 381.480635 -286.500325) (xy 381.440444 -286.472297) (xy 381.40524 -286.438216)
			(xy 381.375923 -286.398955) (xy 381.353245 -286.355519) (xy 381.337787 -286.309023) (xy 381.329946 -286.260655)
			(xy 381.329438 -286.236156) (xy 381.329915 -286.211393) (xy 381.337904 -286.162516) (xy 381.35368 -286.11557)
			(xy 381.376831 -286.071788) (xy 381.406748 -286.032319) (xy 381.442645 -285.998199) (xy 381.483582 -285.970324)
			(xy 381.528482 -285.949425) (xy 381.552196 -285.942278) (xy 381.568706 -285.937452) (xy 381.58928 -285.910528)
			(xy 381.58928 -284.96006) (xy 381.588853 -284.950774) (xy 381.58222 -284.933426) (xy 381.569866 -284.919557)
			(xy 381.561848 -284.914848) (xy 381.552704 -284.910276) (xy 381.548132 -284.909006) (xy 381.524784 -284.90157)
			(xy 381.480637 -284.880313) (xy 381.440447 -284.852284) (xy 381.405243 -284.818203) (xy 381.375928 -284.778942)
			(xy 381.353252 -284.735506) (xy 381.337796 -284.68901) (xy 381.329956 -284.640643) (xy 381.329438 -284.616144)
			(xy 381.329916 -284.591382) (xy 381.337906 -284.542506) (xy 381.353684 -284.495561) (xy 381.376835 -284.451781)
			(xy 381.406752 -284.412314) (xy 381.44265 -284.378196) (xy 381.483586 -284.350322) (xy 381.528486 -284.329424)
			(xy 381.552196 -284.322266) (xy 381.568706 -284.31744) (xy 381.58928 -284.290516) (xy 381.58928 -283.340048)
			(xy 381.588868 -283.330754) (xy 381.582253 -283.313382) (xy 381.569904 -283.299487) (xy 381.561848 -283.294836)
			(xy 381.552704 -283.290264) (xy 381.548132 -283.288994) (xy 381.52478 -283.28156) (xy 381.480626 -283.260304)
			(xy 381.440428 -283.232278) (xy 381.405215 -283.198198) (xy 381.375889 -283.158938) (xy 381.353201 -283.115503)
			(xy 381.337732 -283.069004) (xy 381.329878 -283.020634) (xy 381.329438 -282.996132) (xy 381.329917 -282.97137)
			(xy 381.337909 -282.922496) (xy 381.353688 -282.875553) (xy 381.37684 -282.831774) (xy 381.406757 -282.792309)
			(xy 381.442655 -282.758192) (xy 381.48359 -282.730319) (xy 381.528489 -282.709423) (xy 381.552196 -282.702254)
			(xy 381.568706 -282.697428) (xy 381.58928 -282.670504) (xy 381.58928 -281.720036) (xy 381.588866 -281.710743)
			(xy 381.582249 -281.693374) (xy 381.569899 -281.679483) (xy 381.561848 -281.674824) (xy 381.552704 -281.670252)
			(xy 381.548132 -281.668982) (xy 381.524781 -281.661548) (xy 381.480627 -281.640292) (xy 381.44043 -281.612265)
			(xy 381.405218 -281.578185) (xy 381.375894 -281.538925) (xy 381.353208 -281.495489) (xy 381.337741 -281.448991)
			(xy 381.329889 -281.400621) (xy 381.329438 -281.37612) (xy 381.329918 -281.351359) (xy 381.337911 -281.302486)
			(xy 381.353691 -281.255544) (xy 381.376844 -281.211767) (xy 381.406762 -281.172303) (xy 381.442659 -281.138188)
			(xy 381.483594 -281.110317) (xy 381.528493 -281.089421) (xy 381.552196 -281.082242) (xy 381.568706 -281.077416)
			(xy 381.58928 -281.050492) (xy 381.58928 -280.100024) (xy 381.588864 -280.090732) (xy 381.582244 -280.073366)
			(xy 381.569894 -280.059479) (xy 381.561848 -280.054812) (xy 381.552704 -280.05024) (xy 381.548132 -280.04897)
			(xy 381.524781 -280.041535) (xy 381.480629 -280.020279) (xy 381.440433 -279.992253) (xy 381.405222 -279.958172)
			(xy 381.375899 -279.918912) (xy 381.353215 -279.875476) (xy 381.337749 -279.828978) (xy 381.329899 -279.780609)
			(xy 381.329438 -279.756108) (xy 381.329919 -279.731347) (xy 381.337914 -279.682475) (xy 381.353695 -279.635536)
			(xy 381.376849 -279.59176) (xy 381.406767 -279.552298) (xy 381.442664 -279.518184) (xy 381.483599 -279.490314)
			(xy 381.528496 -279.46942) (xy 381.552196 -279.46223) (xy 381.568706 -279.457404) (xy 381.58928 -279.43048)
			(xy 381.58928 -278.480012) (xy 381.588862 -278.470721) (xy 381.58224 -278.453359) (xy 381.569889 -278.439475)
			(xy 381.561848 -278.4348) (xy 381.552704 -278.430228) (xy 381.548132 -278.428958) (xy 381.524782 -278.421523)
			(xy 381.48063 -278.400267) (xy 381.440436 -278.372239) (xy 381.405227 -278.338159) (xy 381.375905 -278.298898)
			(xy 381.353222 -278.255463) (xy 381.337758 -278.208965) (xy 381.329911 -278.160596) (xy 381.329438 -278.136096)
			(xy 381.329912 -278.111331) (xy 381.337895 -278.062449) (xy 381.353668 -278.015498) (xy 381.376816 -277.971711)
			(xy 381.406732 -277.932237) (xy 381.44263 -277.898112) (xy 381.483568 -277.870232) (xy 381.52847 -277.84933)
			(xy 381.552196 -277.842218) (xy 381.568706 -277.837392) (xy 381.58928 -277.810468) (xy 381.58928 -276.86)
			(xy 381.58886 -276.850711) (xy 381.582235 -276.833351) (xy 381.569883 -276.819471) (xy 381.561848 -276.814788)
			(xy 381.552704 -276.810216) (xy 381.548132 -276.808946) (xy 381.524782 -276.801511) (xy 381.480632 -276.780254)
			(xy 381.440438 -276.752227) (xy 381.40523 -276.718146) (xy 381.37591 -276.678885) (xy 381.353229 -276.63545)
			(xy 381.337767 -276.588953) (xy 381.329921 -276.540584) (xy 381.329438 -276.516084) (xy 381.329913 -276.49132)
			(xy 381.337898 -276.442439) (xy 381.353672 -276.39549) (xy 381.376821 -276.351704) (xy 381.406737 -276.312231)
			(xy 381.442635 -276.278108) (xy 381.483572 -276.25023) (xy 381.528474 -276.229328) (xy 381.552196 -276.222206)
			(xy 381.568706 -276.21738) (xy 381.58928 -276.190456) (xy 381.58928 -275.239988) (xy 381.588858 -275.2307)
			(xy 381.58223 -275.213344) (xy 381.569878 -275.199467) (xy 381.561848 -275.194776) (xy 381.552704 -275.190204)
			(xy 381.548132 -275.188934) (xy 381.524783 -275.181498) (xy 381.480633 -275.160242) (xy 381.440441 -275.132214)
			(xy 381.405234 -275.098133) (xy 381.375916 -275.058872) (xy 381.353236 -275.015437) (xy 381.337776 -274.96894)
			(xy 381.329932 -274.920572) (xy 381.329438 -274.896072) (xy 381.329914 -274.871308) (xy 381.3379 -274.822429)
			(xy 381.353676 -274.775481) (xy 381.376825 -274.731697) (xy 381.406741 -274.692226) (xy 381.442639 -274.658104)
			(xy 381.483576 -274.630227) (xy 381.528477 -274.609327) (xy 381.552196 -274.602194) (xy 381.568706 -274.597368)
			(xy 381.58928 -274.570444) (xy 381.58928 -273.619976) (xy 381.588856 -273.610689) (xy 381.582226 -273.593336)
			(xy 381.569873 -273.579462) (xy 381.561848 -273.574764) (xy 381.552704 -273.570192) (xy 381.548132 -273.568922)
			(xy 381.524783 -273.561486) (xy 381.480635 -273.540229) (xy 381.440443 -273.512201) (xy 381.405238 -273.47812)
			(xy 381.375921 -273.438859) (xy 381.353243 -273.395424) (xy 381.337785 -273.348927) (xy 381.329942 -273.300559)
			(xy 381.329438 -273.27606) (xy 381.329915 -273.251297) (xy 381.337903 -273.202419) (xy 381.353679 -273.155473)
			(xy 381.376829 -273.11169) (xy 381.406746 -273.072221) (xy 381.442644 -273.038101) (xy 381.48358 -273.010225)
			(xy 381.528481 -272.989326) (xy 381.552196 -272.982182) (xy 381.568706 -272.977356) (xy 381.58928 -272.950432)
			(xy 381.58928 -271.999964) (xy 381.588854 -271.990678) (xy 381.582221 -271.973329) (xy 381.569868 -271.959458)
			(xy 381.561848 -271.954752) (xy 381.552704 -271.95018) (xy 381.548132 -271.94891) (xy 381.524783 -271.941474)
			(xy 381.480636 -271.920217) (xy 381.440446 -271.892188) (xy 381.405242 -271.858107) (xy 381.375926 -271.818846)
			(xy 381.35325 -271.775411) (xy 381.337793 -271.728914) (xy 381.329953 -271.680547) (xy 381.329438 -271.656048)
			(xy 381.329916 -271.631285) (xy 381.337905 -271.582409) (xy 381.353683 -271.535464) (xy 381.376834 -271.491683)
			(xy 381.406751 -271.452216) (xy 381.442649 -271.418097) (xy 381.483585 -271.390223) (xy 381.528485 -271.369325)
			(xy 381.552196 -271.36217) (xy 381.568706 -271.357344) (xy 381.58928 -271.33042) (xy 381.58928 -270.379952)
			(xy 381.588868 -270.370658) (xy 381.582255 -270.353284) (xy 381.569906 -270.339389) (xy 381.561848 -270.33474)
			(xy 381.552704 -270.330168) (xy 381.548132 -270.328898) (xy 381.52478 -270.321464) (xy 381.480625 -270.300209)
			(xy 381.440427 -270.272182) (xy 381.405213 -270.238103) (xy 381.375887 -270.198842) (xy 381.353198 -270.155407)
			(xy 381.337729 -270.108908) (xy 381.329875 -270.060538) (xy 381.329438 -270.036036) (xy 381.329917 -270.011274)
			(xy 381.337908 -269.962399) (xy 381.353686 -269.915456) (xy 381.376838 -269.871677) (xy 381.406756 -269.83221)
			(xy 381.442653 -269.798093) (xy 381.483589 -269.77022) (xy 381.528488 -269.749323) (xy 381.552196 -269.742158)
			(xy 381.568706 -269.737332) (xy 381.58928 -269.710408) (xy 381.58928 -268.75994) (xy 381.588866 -268.750647)
			(xy 381.58225 -268.733277) (xy 381.569901 -268.719384) (xy 381.561848 -268.714728) (xy 381.552704 -268.710156)
			(xy 381.548132 -268.708886) (xy 381.52478 -268.701452) (xy 381.480627 -268.680196) (xy 381.440429 -268.65217)
			(xy 381.405217 -268.61809) (xy 381.375892 -268.578829) (xy 381.353205 -268.535394) (xy 381.337738 -268.488896)
			(xy 381.329885 -268.440525) (xy 381.329438 -268.416024) (xy 381.329918 -268.391263) (xy 381.33791 -268.342389)
			(xy 381.35369 -268.295447) (xy 381.376843 -268.25167) (xy 381.40676 -268.212205) (xy 381.442658 -268.178089)
			(xy 381.483593 -268.150218) (xy 381.528492 -268.129322) (xy 381.552196 -268.122146) (xy 381.568706 -268.11732)
			(xy 381.58928 -268.090396) (xy 381.58928 -267.139928) (xy 381.588864 -267.130636) (xy 381.582246 -267.113269)
			(xy 381.569896 -267.09938) (xy 381.561848 -267.094716) (xy 381.552704 -267.090144) (xy 381.548132 -267.088874)
			(xy 381.524781 -267.081439) (xy 381.480628 -267.060184) (xy 381.440432 -267.032157) (xy 381.405221 -266.998077)
			(xy 381.375897 -266.958816) (xy 381.353212 -266.915381) (xy 381.337746 -266.868883) (xy 381.329896 -266.820513)
			(xy 381.329438 -266.796012) (xy 381.329919 -266.771251) (xy 381.337913 -266.722379) (xy 381.353694 -266.675439)
			(xy 381.376847 -266.631663) (xy 381.406765 -266.5922) (xy 381.442662 -266.558085) (xy 381.483597 -266.530215)
			(xy 381.528495 -266.509321) (xy 381.552196 -266.502134) (xy 381.568706 -266.497308) (xy 381.58928 -266.470384)
			(xy 381.58928 -265.519916) (xy 381.588862 -265.510625) (xy 381.582241 -265.493261) (xy 381.56989 -265.479376)
			(xy 381.561848 -265.474704) (xy 381.552704 -265.470132) (xy 381.548132 -265.468862) (xy 381.524781 -265.461427)
			(xy 381.48063 -265.440171) (xy 381.440435 -265.412144) (xy 381.405225 -265.378063) (xy 381.375903 -265.338803)
			(xy 381.35322 -265.295367) (xy 381.337756 -265.24887) (xy 381.329907 -265.200501) (xy 381.329438 -265.176)
			(xy 381.329919 -265.15124) (xy 381.337915 -265.102369) (xy 381.353697 -265.05543) (xy 381.376851 -265.011656)
			(xy 381.40677 -264.972194) (xy 381.442667 -264.938082) (xy 381.483602 -264.910213) (xy 381.528499 -264.889319)
			(xy 381.552196 -264.882122) (xy 381.568706 -264.877296) (xy 381.58928 -264.850372) (xy 381.58928 -264.546842)
			(xy 381.588846 -264.536777) (xy 381.581114 -264.51819) (xy 381.574294 -264.510774) (xy 381.538988 -264.475468)
			(xy 381.530312 -264.467624) (xy 381.508192 -264.460108) (xy 381.485025 -264.463129) (xy 381.47498 -264.469118)
			(xy 381.46609 -264.47496) (xy 381.456946 -264.485882) (xy 381.453898 -264.49274) (xy 381.442963 -264.516468)
			(xy 381.414427 -264.560229) (xy 381.379069 -264.598689) (xy 381.337855 -264.630795) (xy 381.291914 -264.655669)
			(xy 381.242501 -264.672631) (xy 381.190968 -264.681216) (xy 381.164846 -264.681716) (xy 381.140032 -264.681258)
			(xy 381.091015 -264.673501) (xy 381.043815 -264.658171) (xy 380.999594 -264.635645) (xy 380.959443 -264.606478)
			(xy 380.924349 -264.571388) (xy 380.895176 -264.53124) (xy 380.872645 -264.487022) (xy 380.857308 -264.439824)
			(xy 380.849545 -264.390808) (xy 380.849124 -264.365994) (xy 380.849675 -264.339414) (xy 380.858588 -264.287007)
			(xy 380.876162 -264.236836) (xy 380.901899 -264.190322) (xy 380.93507 -264.148782) (xy 380.974736 -264.11339)
			(xy 380.996952 -264.098786) (xy 381.006858 -264.092436) (xy 381.019304 -264.072624) (xy 381.027686 -263.990836)
			(xy 381.028233 -263.982548) (xy 381.024603 -263.96635) (xy 381.020574 -263.959086) (xy 381.017272 -263.953752)
			(xy 380.90094 -263.83742) (xy 380.894944 -263.831821) (xy 380.880304 -263.82444) (xy 380.872238 -263.822942)
			(xy 380.864872 -263.821926) (xy 380.845746 -263.83366) (xy 380.804881 -263.852192) (xy 380.761803 -263.864751)
			(xy 380.717382 -263.871084) (xy 380.694946 -263.871456) (xy 380.670146 -263.870974) (xy 380.621154 -263.863225)
			(xy 380.573977 -263.847912) (xy 380.529775 -263.825411) (xy 380.489634 -263.796275) (xy 380.454543 -263.76122)
			(xy 380.425364 -263.721111) (xy 380.402816 -263.676932) (xy 380.387453 -263.629771) (xy 380.379653 -263.580788)
			(xy 380.379224 -263.555988) (xy 380.379616 -263.534568) (xy 380.385479 -263.49213) (xy 380.390908 -263.471406)
			(xy 380.39421 -263.459722) (xy 380.389384 -263.4361) (xy 380.337822 -263.369298) (xy 380.330232 -263.360468)
			(xy 380.309322 -263.350285) (xy 380.29769 -263.34974) (xy 380.140464 -263.34974) (xy 380.119128 -263.360154)
			(xy 380.11227 -263.369298) (xy 380.111762 -263.369806) (xy 380.0602 -263.435846) (xy 380.055628 -263.459468)
			(xy 380.05893 -263.471152) (xy 380.0643 -263.491947) (xy 380.070028 -263.534513) (xy 380.07036 -263.555988)
			(xy 380.069874 -263.580778) (xy 380.062118 -263.629746) (xy 380.046797 -263.676899) (xy 380.024288 -263.721074)
			(xy 379.995146 -263.761185) (xy 379.960089 -263.796242) (xy 379.919978 -263.825384) (xy 379.875803 -263.847893)
			(xy 379.82865 -263.863214) (xy 379.779682 -263.87097) (xy 379.730102 -263.87097) (xy 379.681134 -263.863214)
			(xy 379.633981 -263.847893) (xy 379.589806 -263.825384) (xy 379.549695 -263.796242) (xy 379.514638 -263.761185)
			(xy 379.485496 -263.721074) (xy 379.462987 -263.676899) (xy 379.447666 -263.629746) (xy 379.43991 -263.580778)
			(xy 379.439424 -263.555988) (xy 379.439746 -263.534575) (xy 379.44548 -263.492136) (xy 379.450854 -263.471406)
			(xy 379.454156 -263.459722) (xy 379.44933 -263.4361) (xy 379.397768 -263.369298) (xy 379.390181 -263.36046)
			(xy 379.369271 -263.350259) (xy 379.357636 -263.34974) (xy 378.260356 -263.34974) (xy 378.23902 -263.360154)
			(xy 378.232162 -263.369298) (xy 378.231654 -263.369806) (xy 378.180092 -263.435846) (xy 378.17552 -263.459468)
			(xy 378.178822 -263.471152) (xy 378.184192 -263.491947) (xy 378.18992 -263.534513) (xy 378.190252 -263.555988)
			(xy 378.189766 -263.580778) (xy 378.18201 -263.629746) (xy 378.166689 -263.676899) (xy 378.14418 -263.721074)
			(xy 378.115038 -263.761185) (xy 378.079981 -263.796242) (xy 378.03987 -263.825384) (xy 377.995695 -263.847893)
			(xy 377.948542 -263.863214) (xy 377.899574 -263.87097) (xy 377.849994 -263.87097) (xy 377.801026 -263.863214)
			(xy 377.753873 -263.847893) (xy 377.709698 -263.825384) (xy 377.669587 -263.796242) (xy 377.63453 -263.761185)
			(xy 377.605388 -263.721074) (xy 377.582879 -263.676899) (xy 377.567558 -263.629746) (xy 377.559802 -263.580778)
			(xy 377.559316 -263.555988) (xy 377.559638 -263.534575) (xy 377.565371 -263.492136) (xy 377.570746 -263.471406)
			(xy 377.574048 -263.459722) (xy 377.569222 -263.4361) (xy 377.51766 -263.369298) (xy 377.510073 -263.360462)
			(xy 377.489162 -263.350263) (xy 377.477528 -263.34974) (xy 377.327922 -263.34974) (xy 377.316254 -263.350308)
			(xy 377.295326 -263.360628) (xy 377.28779 -263.369552) (xy 377.238768 -263.433052) (xy 377.232063 -263.442716)
			(xy 377.227421 -263.465747) (xy 377.229878 -263.477248) (xy 377.234633 -263.496391) (xy 377.239728 -263.535504)
			(xy 377.240038 -263.555226) (xy 377.240038 -263.555988) (xy 377.239516 -263.581243) (xy 377.231203 -263.631065)
			(xy 377.214802 -263.678839) (xy 377.190761 -263.723262) (xy 377.159737 -263.763122) (xy 377.122575 -263.797332)
			(xy 377.080289 -263.824958) (xy 377.034033 -263.845248) (xy 376.985068 -263.857648) (xy 376.93473 -263.861819)
			(xy 376.884392 -263.857648) (xy 376.835427 -263.845248) (xy 376.789171 -263.824958) (xy 376.746885 -263.797332)
			(xy 376.709723 -263.763122) (xy 376.678699 -263.723262) (xy 376.654658 -263.678839) (xy 376.638257 -263.631065)
			(xy 376.629944 -263.581243) (xy 376.629422 -263.555988) (xy 376.629422 -263.555226) (xy 376.629749 -263.535505)
			(xy 376.634844 -263.496394) (xy 376.639582 -263.477248) (xy 376.642054 -263.465747) (xy 376.6374 -263.442718)
			(xy 376.630692 -263.433052) (xy 376.58167 -263.369552) (xy 376.57409 -263.360678) (xy 376.553191 -263.350346)
			(xy 376.541538 -263.34974) (xy 376.380502 -263.34974) (xy 376.359166 -263.360154) (xy 376.352308 -263.369298)
			(xy 376.3518 -263.369806) (xy 376.300238 -263.435846) (xy 376.295666 -263.459468) (xy 376.298968 -263.471152)
			(xy 376.304413 -263.491938) (xy 376.310282 -263.534504) (xy 376.310652 -263.555988) (xy 376.310165 -263.580798)
			(xy 376.302403 -263.629806) (xy 376.28707 -263.676996) (xy 376.264543 -263.721207) (xy 376.235378 -263.76135)
			(xy 376.200292 -263.796436) (xy 376.160149 -263.825601) (xy 376.115938 -263.848128) (xy 376.068748 -263.863461)
			(xy 376.01974 -263.871223) (xy 375.97012 -263.871223) (xy 375.921112 -263.863461) (xy 375.873922 -263.848128)
			(xy 375.829711 -263.825601) (xy 375.789568 -263.796436) (xy 375.754482 -263.76135) (xy 375.725317 -263.721207)
			(xy 375.70279 -263.676996) (xy 375.687457 -263.629806) (xy 375.679695 -263.580798) (xy 375.679208 -263.555988)
			(xy 375.6796 -263.534568) (xy 375.685463 -263.49213) (xy 375.690892 -263.471406) (xy 375.694194 -263.459722)
			(xy 375.689368 -263.4361) (xy 375.637806 -263.369298) (xy 375.630215 -263.360471) (xy 375.609304 -263.350295)
			(xy 375.597674 -263.34974) (xy 375.448068 -263.34974) (xy 375.436406 -263.350319) (xy 375.415497 -263.360652)
			(xy 375.407936 -263.369552) (xy 375.358914 -263.433052) (xy 375.352204 -263.442714) (xy 375.347558 -263.465747)
			(xy 375.350024 -263.477248) (xy 375.35478 -263.496391) (xy 375.359876 -263.535504) (xy 375.360184 -263.555226)
			(xy 375.360184 -263.555988) (xy 375.359662 -263.581243) (xy 375.351349 -263.631065) (xy 375.334948 -263.678839)
			(xy 375.310907 -263.723262) (xy 375.279883 -263.763122) (xy 375.242721 -263.797332) (xy 375.200435 -263.824958)
			(xy 375.154179 -263.845248) (xy 375.105214 -263.857648) (xy 375.054876 -263.861819) (xy 375.004538 -263.857648)
			(xy 374.955573 -263.845248) (xy 374.909317 -263.824958) (xy 374.867031 -263.797332) (xy 374.829869 -263.763122)
			(xy 374.798845 -263.723262) (xy 374.774804 -263.678839) (xy 374.758403 -263.631065) (xy 374.75009 -263.581243)
			(xy 374.749568 -263.555988) (xy 374.749568 -263.555226) (xy 374.749895 -263.535505) (xy 374.754991 -263.496394)
			(xy 374.759728 -263.477248) (xy 374.762199 -263.465747) (xy 374.757549 -263.442716) (xy 374.750838 -263.433052)
			(xy 374.701816 -263.369552) (xy 374.694233 -263.360687) (xy 374.673333 -263.350376) (xy 374.661684 -263.34974)
			(xy 373.56796 -263.34974) (xy 373.556299 -263.35032) (xy 373.535392 -263.360656) (xy 373.527828 -263.369552)
			(xy 373.478806 -263.433052) (xy 373.472097 -263.442714) (xy 373.467451 -263.465747) (xy 373.469916 -263.477248)
			(xy 373.474672 -263.496391) (xy 373.479768 -263.535504) (xy 373.480076 -263.555226) (xy 373.480076 -263.555988)
			(xy 373.479554 -263.581243) (xy 373.471241 -263.631065) (xy 373.45484 -263.678839) (xy 373.430799 -263.723262)
			(xy 373.399775 -263.763122) (xy 373.362613 -263.797332) (xy 373.320327 -263.824958) (xy 373.274071 -263.845248)
			(xy 373.225106 -263.857648) (xy 373.174768 -263.861819) (xy 373.12443 -263.857648) (xy 373.075465 -263.845248)
			(xy 373.029209 -263.824958) (xy 372.986923 -263.797332) (xy 372.949761 -263.763122) (xy 372.918737 -263.723262)
			(xy 372.894696 -263.678839) (xy 372.878295 -263.631065) (xy 372.869982 -263.581243) (xy 372.86946 -263.555988)
			(xy 372.86946 -263.555226) (xy 372.869787 -263.535505) (xy 372.874883 -263.496394) (xy 372.87962 -263.477248)
			(xy 372.882091 -263.465747) (xy 372.87744 -263.442716) (xy 372.87073 -263.433052) (xy 372.821708 -263.369552)
			(xy 372.814124 -263.360689) (xy 372.793224 -263.350381) (xy 372.781576 -263.34974) (xy 371.688106 -263.34974)
			(xy 371.67644 -263.350311) (xy 371.655518 -263.360635) (xy 371.647974 -263.369552) (xy 371.598952 -263.433052)
			(xy 371.592249 -263.442716) (xy 371.587608 -263.465746) (xy 371.590062 -263.477248) (xy 371.594817 -263.496391)
			(xy 371.599912 -263.535504) (xy 371.600222 -263.555226) (xy 371.600222 -263.555988) (xy 371.5997 -263.581243)
			(xy 371.591387 -263.631065) (xy 371.574986 -263.678839) (xy 371.550945 -263.723262) (xy 371.519921 -263.763122)
			(xy 371.482759 -263.797332) (xy 371.440473 -263.824958) (xy 371.394217 -263.845248) (xy 371.345252 -263.857648)
			(xy 371.294914 -263.861819) (xy 371.244576 -263.857648) (xy 371.195611 -263.845248) (xy 371.149355 -263.824958)
			(xy 371.107069 -263.797332) (xy 371.069907 -263.763122) (xy 371.038883 -263.723262) (xy 371.014842 -263.678839)
			(xy 370.998441 -263.631065) (xy 370.990128 -263.581243) (xy 370.989606 -263.555988) (xy 370.989606 -263.555226)
			(xy 370.989933 -263.535505) (xy 370.995028 -263.496394) (xy 370.999766 -263.477248) (xy 371.002239 -263.465748)
			(xy 370.997584 -263.442719) (xy 370.990876 -263.433052) (xy 370.941854 -263.369552) (xy 370.934273 -263.360681)
			(xy 370.913374 -263.350355) (xy 370.901722 -263.34974) (xy 369.807998 -263.34974) (xy 369.796332 -263.350313)
			(xy 369.775413 -263.360639) (xy 369.767866 -263.369552) (xy 369.718844 -263.433052) (xy 369.712141 -263.442716)
			(xy 369.707501 -263.465746) (xy 369.709954 -263.477248) (xy 369.71471 -263.496391) (xy 369.719805 -263.535504)
			(xy 369.720114 -263.555226) (xy 369.720114 -263.555988) (xy 369.719592 -263.581243) (xy 369.711279 -263.631065)
			(xy 369.694878 -263.678839) (xy 369.670837 -263.723262) (xy 369.639813 -263.763122) (xy 369.602651 -263.797332)
			(xy 369.560365 -263.824958) (xy 369.514109 -263.845248) (xy 369.465144 -263.857648) (xy 369.414806 -263.861819)
			(xy 369.364468 -263.857648) (xy 369.315503 -263.845248) (xy 369.269247 -263.824958) (xy 369.226961 -263.797332)
			(xy 369.189799 -263.763122) (xy 369.158775 -263.723262) (xy 369.134734 -263.678839) (xy 369.118333 -263.631065)
			(xy 369.11002 -263.581243) (xy 369.109498 -263.555988) (xy 369.110043 -263.529764) (xy 369.119007 -263.478089)
			(xy 369.13667 -263.428705) (xy 369.149122 -263.40562) (xy 369.157504 -263.390634) (xy 369.152932 -263.356852)
			(xy 367.776506 -261.980426) (xy 367.769394 -261.97306) (xy 367.750598 -261.96544) (xy 365.811054 -261.96544)
			(xy 365.799382 -261.966001) (xy 365.778444 -261.976313) (xy 365.770922 -261.985252) (xy 365.723424 -262.04672)
			(xy 365.718607 -262.053614) (xy 365.713283 -262.069557) (xy 365.71301 -262.077962) (xy 365.71301 -262.092186)
			(xy 365.714534 -262.098282) (xy 365.719059 -262.118232) (xy 365.723902 -262.158853) (xy 365.724186 -262.179308)
			(xy 365.724186 -262.18007) (xy 365.723686 -262.207058) (xy 365.715246 -262.260371) (xy 365.69857 -262.311706)
			(xy 365.674067 -262.3598) (xy 365.642342 -262.403469) (xy 365.604175 -262.441637) (xy 365.560507 -262.473363)
			(xy 365.512414 -262.497867) (xy 365.461078 -262.514545) (xy 365.407766 -262.522986) (xy 365.380778 -262.523478)
			(xy 365.353909 -262.522956) (xy 365.300827 -262.514581) (xy 365.249698 -262.49804) (xy 365.20177 -262.473736)
			(xy 365.158214 -262.442262) (xy 365.120092 -262.404387) (xy 365.088335 -262.361036) (xy 365.06372 -262.313267)
			(xy 365.046846 -262.262247) (xy 365.038126 -262.209221) (xy 365.03737 -262.182356) (xy 365.03737 -262.179816)
			(xy 365.037728 -262.157916) (xy 365.043327 -262.114474) (xy 365.048546 -262.093202) (xy 365.048546 -262.092694)
			(xy 365.050898 -262.081314) (xy 365.046264 -262.058566) (xy 365.039656 -262.049006) (xy 364.990634 -261.985252)
			(xy 364.983052 -261.976384) (xy 364.962152 -261.966066) (xy 364.950502 -261.96544) (xy 353.990402 -261.96544)
			(xy 353.980333 -261.965864) (xy 353.961731 -261.973582) (xy 353.954334 -261.980426) (xy 353.781868 -262.152892)
			(xy 353.774248 -262.17118) (xy 353.774248 -262.18134) (xy 353.773632 -262.208199) (xy 353.765075 -262.261236)
			(xy 353.748366 -262.312293) (xy 353.72391 -262.360126) (xy 353.692305 -262.403568) (xy 353.654322 -262.44156)
			(xy 353.610886 -262.473173) (xy 353.563058 -262.497639) (xy 353.512004 -262.514359) (xy 353.458969 -262.522926)
			(xy 353.43211 -262.523478) (xy 353.42195 -262.523478) (xy 353.403662 -262.531098) (xy 352.08845 -263.84631)
			(xy 359.174291 -263.84631) (xy 359.178321 -263.793812) (xy 359.190318 -263.742544) (xy 359.210001 -263.693709)
			(xy 359.236907 -263.64845) (xy 359.270407 -263.607829) (xy 359.309715 -263.572798) (xy 359.35391 -263.544178)
			(xy 359.401955 -263.522639) (xy 359.452726 -263.508687) (xy 359.505031 -263.502649) (xy 359.557645 -263.504666)
			(xy 359.609335 -263.51469) (xy 359.658888 -263.532488) (xy 359.705144 -263.557641) (xy 359.747018 -263.58956)
			(xy 359.78353 -263.627498) (xy 359.813822 -263.670564) (xy 359.837185 -263.717749) (xy 359.853071 -263.767948)
			(xy 359.861108 -263.819984) (xy 359.861612 -263.84631) (xy 359.861108 -263.872636) (xy 359.853071 -263.924672)
			(xy 359.837185 -263.974871) (xy 359.813822 -264.022056) (xy 359.78353 -264.065122) (xy 359.747018 -264.10306)
			(xy 359.705144 -264.134979) (xy 359.658888 -264.160132) (xy 359.609335 -264.17793) (xy 359.557645 -264.187954)
			(xy 359.505031 -264.189971) (xy 359.452726 -264.183933) (xy 359.401955 -264.169981) (xy 359.35391 -264.148442)
			(xy 359.309715 -264.119822) (xy 359.270407 -264.084791) (xy 359.236907 -264.04417) (xy 359.210001 -263.998911)
			(xy 359.190318 -263.950076) (xy 359.178321 -263.898808) (xy 359.174291 -263.84631) (xy 352.08845 -263.84631)
			(xy 352.02749 -263.90727) (xy 352.020632 -263.934448) (xy 352.024696 -263.94791) (xy 352.046286 -264.019792)
			(xy 352.048441 -264.026269) (xy 352.055657 -264.037851) (xy 352.06051 -264.042652) (xy 352.083624 -264.063988)
			(xy 352.0948 -264.070084) (xy 352.10115 -264.071608) (xy 352.125663 -264.078175) (xy 352.172242 -264.098314)
			(xy 352.214849 -264.125877) (xy 352.252313 -264.160105) (xy 352.283601 -264.200057) (xy 352.307852 -264.244633)
			(xy 352.324399 -264.292605) (xy 352.332785 -264.342653) (xy 352.333306 -264.368026) (xy 353.602302 -264.368026)
			(xy 353.606262 -264.318972) (xy 353.618039 -264.271188) (xy 353.63733 -264.225912) (xy 353.663633 -264.184316)
			(xy 353.696268 -264.147479) (xy 353.734389 -264.116354) (xy 353.77701 -264.091747) (xy 353.823026 -264.074295)
			(xy 353.871245 -264.064451) (xy 353.92042 -264.06247) (xy 353.969275 -264.068402) (xy 354.016546 -264.082094)
			(xy 354.061008 -264.103192) (xy 354.101511 -264.131148) (xy 354.137004 -264.16524) (xy 354.166569 -264.204584)
			(xy 354.18944 -264.248161) (xy 354.205024 -264.294842) (xy 354.212919 -264.343419) (xy 354.213414 -264.368026)
			(xy 355.482156 -264.368026) (xy 355.486116 -264.318972) (xy 355.497893 -264.271188) (xy 355.517184 -264.225912)
			(xy 355.543487 -264.184316) (xy 355.576122 -264.147479) (xy 355.614243 -264.116354) (xy 355.656864 -264.091747)
			(xy 355.70288 -264.074295) (xy 355.751099 -264.064451) (xy 355.800274 -264.06247) (xy 355.849129 -264.068402)
			(xy 355.8964 -264.082094) (xy 355.940862 -264.103192) (xy 355.981365 -264.131148) (xy 356.016858 -264.16524)
			(xy 356.046423 -264.204584) (xy 356.069294 -264.248161) (xy 356.084878 -264.294842) (xy 356.092773 -264.343419)
			(xy 356.093268 -264.368026) (xy 363.00208 -264.368026) (xy 363.00604 -264.318972) (xy 363.017817 -264.271188)
			(xy 363.037108 -264.225912) (xy 363.063411 -264.184316) (xy 363.096046 -264.147479) (xy 363.134167 -264.116354)
			(xy 363.176788 -264.091747) (xy 363.222804 -264.074295) (xy 363.271023 -264.064451) (xy 363.320198 -264.06247)
			(xy 363.369053 -264.068402) (xy 363.416324 -264.082094) (xy 363.460786 -264.103192) (xy 363.501289 -264.131148)
			(xy 363.536782 -264.16524) (xy 363.566347 -264.204584) (xy 363.589218 -264.248161) (xy 363.604802 -264.294842)
			(xy 363.612697 -264.343419) (xy 363.613192 -264.368026) (xy 364.882188 -264.368026) (xy 364.886148 -264.318972)
			(xy 364.897925 -264.271188) (xy 364.917216 -264.225912) (xy 364.943519 -264.184316) (xy 364.976154 -264.147479)
			(xy 365.014275 -264.116354) (xy 365.056896 -264.091747) (xy 365.102912 -264.074295) (xy 365.151131 -264.064451)
			(xy 365.200306 -264.06247) (xy 365.249161 -264.068402) (xy 365.296432 -264.082094) (xy 365.340894 -264.103192)
			(xy 365.381397 -264.131148) (xy 365.41689 -264.16524) (xy 365.446455 -264.204584) (xy 365.469326 -264.248161)
			(xy 365.48491 -264.294842) (xy 365.492805 -264.343419) (xy 365.4933 -264.368026) (xy 366.762042 -264.368026)
			(xy 366.766002 -264.318972) (xy 366.777779 -264.271188) (xy 366.79707 -264.225912) (xy 366.823373 -264.184316)
			(xy 366.856008 -264.147479) (xy 366.894129 -264.116354) (xy 366.93675 -264.091747) (xy 366.982766 -264.074295)
			(xy 367.030985 -264.064451) (xy 367.08016 -264.06247) (xy 367.129015 -264.068402) (xy 367.176286 -264.082094)
			(xy 367.220748 -264.103192) (xy 367.261251 -264.131148) (xy 367.296744 -264.16524) (xy 367.326309 -264.204584)
			(xy 367.34918 -264.248161) (xy 367.364764 -264.294842) (xy 367.372659 -264.343419) (xy 367.373154 -264.368026)
			(xy 368.639864 -264.368026) (xy 368.643824 -264.318972) (xy 368.655601 -264.271188) (xy 368.674892 -264.225912)
			(xy 368.701195 -264.184316) (xy 368.73383 -264.147479) (xy 368.771951 -264.116354) (xy 368.814572 -264.091747)
			(xy 368.860588 -264.074295) (xy 368.908807 -264.064451) (xy 368.957982 -264.06247) (xy 369.006837 -264.068402)
			(xy 369.054108 -264.082094) (xy 369.09857 -264.103192) (xy 369.139073 -264.131148) (xy 369.174566 -264.16524)
			(xy 369.204131 -264.204584) (xy 369.227002 -264.248161) (xy 369.242586 -264.294842) (xy 369.250481 -264.343419)
			(xy 369.250935 -264.365994) (xy 370.518956 -264.365994) (xy 370.522916 -264.31694) (xy 370.534693 -264.269156)
			(xy 370.553984 -264.22388) (xy 370.580287 -264.182284) (xy 370.612922 -264.145447) (xy 370.651043 -264.114322)
			(xy 370.693664 -264.089715) (xy 370.73968 -264.072263) (xy 370.787899 -264.062419) (xy 370.837074 -264.060438)
			(xy 370.885929 -264.06637) (xy 370.9332 -264.080062) (xy 370.977662 -264.10116) (xy 371.018165 -264.129116)
			(xy 371.053658 -264.163208) (xy 371.083223 -264.202552) (xy 371.106094 -264.246129) (xy 371.121678 -264.29281)
			(xy 371.129573 -264.341387) (xy 371.130068 -264.365994) (xy 372.399064 -264.365994) (xy 372.403024 -264.31694)
			(xy 372.414801 -264.269156) (xy 372.434092 -264.22388) (xy 372.460395 -264.182284) (xy 372.49303 -264.145447)
			(xy 372.531151 -264.114322) (xy 372.573772 -264.089715) (xy 372.619788 -264.072263) (xy 372.668007 -264.062419)
			(xy 372.717182 -264.060438) (xy 372.766037 -264.06637) (xy 372.813308 -264.080062) (xy 372.85777 -264.10116)
			(xy 372.898273 -264.129116) (xy 372.933766 -264.163208) (xy 372.963331 -264.202552) (xy 372.986202 -264.246129)
			(xy 373.001786 -264.29281) (xy 373.009681 -264.341387) (xy 373.010176 -264.365994) (xy 374.278918 -264.365994)
			(xy 374.282878 -264.31694) (xy 374.294655 -264.269156) (xy 374.313946 -264.22388) (xy 374.340249 -264.182284)
			(xy 374.372884 -264.145447) (xy 374.411005 -264.114322) (xy 374.453626 -264.089715) (xy 374.499642 -264.072263)
			(xy 374.547861 -264.062419) (xy 374.597036 -264.060438) (xy 374.645891 -264.06637) (xy 374.693162 -264.080062)
			(xy 374.737624 -264.10116) (xy 374.778127 -264.129116) (xy 374.81362 -264.163208) (xy 374.843185 -264.202552)
			(xy 374.866056 -264.246129) (xy 374.88164 -264.29281) (xy 374.889535 -264.341387) (xy 374.89003 -264.365994)
			(xy 376.148595 -264.365994) (xy 376.15269 -264.315266) (xy 376.164869 -264.265852) (xy 376.184817 -264.219032)
			(xy 376.212018 -264.176018) (xy 376.245766 -264.137924) (xy 376.285188 -264.105737) (xy 376.329262 -264.080291)
			(xy 376.376848 -264.062244) (xy 376.426712 -264.052064) (xy 376.477564 -264.050015) (xy 376.528085 -264.056149)
			(xy 376.576969 -264.070309) (xy 376.622948 -264.092126) (xy 376.664832 -264.121036) (xy 376.701536 -264.156291)
			(xy 376.732109 -264.196977) (xy 376.75576 -264.24204) (xy 376.771876 -264.290314) (xy 376.78004 -264.340548)
			(xy 376.780552 -264.365994) (xy 377.088649 -264.365994) (xy 377.092744 -264.315266) (xy 377.104923 -264.265852)
			(xy 377.124871 -264.219032) (xy 377.152072 -264.176018) (xy 377.18582 -264.137924) (xy 377.225242 -264.105737)
			(xy 377.269316 -264.080291) (xy 377.316902 -264.062244) (xy 377.366766 -264.052064) (xy 377.417618 -264.050015)
			(xy 377.468139 -264.056149) (xy 377.517023 -264.070309) (xy 377.563002 -264.092126) (xy 377.604886 -264.121036)
			(xy 377.64159 -264.156291) (xy 377.672163 -264.196977) (xy 377.695814 -264.24204) (xy 377.71193 -264.290314)
			(xy 377.720094 -264.340548) (xy 377.720606 -264.365994) (xy 378.039134 -264.365994) (xy 378.043094 -264.31694)
			(xy 378.054871 -264.269156) (xy 378.074162 -264.22388) (xy 378.100465 -264.182284) (xy 378.1331 -264.145447)
			(xy 378.171221 -264.114322) (xy 378.213842 -264.089715) (xy 378.259858 -264.072263) (xy 378.308077 -264.062419)
			(xy 378.357252 -264.060438) (xy 378.406107 -264.06637) (xy 378.453378 -264.080062) (xy 378.49784 -264.10116)
			(xy 378.538343 -264.129116) (xy 378.573836 -264.163208) (xy 378.603401 -264.202552) (xy 378.626272 -264.246129)
			(xy 378.641856 -264.29281) (xy 378.649751 -264.341387) (xy 378.650246 -264.365994) (xy 378.968503 -264.365994)
			(xy 378.972598 -264.315266) (xy 378.984777 -264.265852) (xy 379.004725 -264.219032) (xy 379.031926 -264.176018)
			(xy 379.065674 -264.137924) (xy 379.105096 -264.105737) (xy 379.14917 -264.080291) (xy 379.196756 -264.062244)
			(xy 379.24662 -264.052064) (xy 379.297472 -264.050015) (xy 379.347993 -264.056149) (xy 379.396877 -264.070309)
			(xy 379.442856 -264.092126) (xy 379.48474 -264.121036) (xy 379.521444 -264.156291) (xy 379.552017 -264.196977)
			(xy 379.575668 -264.24204) (xy 379.591784 -264.290314) (xy 379.599948 -264.340548) (xy 379.60046 -264.365994)
			(xy 379.918988 -264.365994) (xy 379.922948 -264.31694) (xy 379.934725 -264.269156) (xy 379.954016 -264.22388)
			(xy 379.980319 -264.182284) (xy 380.012954 -264.145447) (xy 380.051075 -264.114322) (xy 380.093696 -264.089715)
			(xy 380.139712 -264.072263) (xy 380.187931 -264.062419) (xy 380.237106 -264.060438) (xy 380.285961 -264.06637)
			(xy 380.333232 -264.080062) (xy 380.377694 -264.10116) (xy 380.418197 -264.129116) (xy 380.45369 -264.163208)
			(xy 380.483255 -264.202552) (xy 380.506126 -264.246129) (xy 380.52171 -264.29281) (xy 380.529605 -264.341387)
			(xy 380.5301 -264.365994) (xy 380.529605 -264.390601) (xy 380.52171 -264.439178) (xy 380.506126 -264.485859)
			(xy 380.483255 -264.529436) (xy 380.45369 -264.56878) (xy 380.418197 -264.602872) (xy 380.377694 -264.630828)
			(xy 380.333232 -264.651926) (xy 380.285961 -264.665618) (xy 380.237106 -264.67155) (xy 380.187931 -264.669569)
			(xy 380.139712 -264.659725) (xy 380.093696 -264.642273) (xy 380.051075 -264.617666) (xy 380.012954 -264.586541)
			(xy 379.980319 -264.549704) (xy 379.954016 -264.508108) (xy 379.934725 -264.462832) (xy 379.922948 -264.415048)
			(xy 379.918988 -264.365994) (xy 379.60046 -264.365994) (xy 379.599948 -264.39144) (xy 379.591784 -264.441674)
			(xy 379.575668 -264.489948) (xy 379.552017 -264.535011) (xy 379.521444 -264.575697) (xy 379.48474 -264.610952)
			(xy 379.442856 -264.639862) (xy 379.396877 -264.661679) (xy 379.347993 -264.675839) (xy 379.297472 -264.681973)
			(xy 379.24662 -264.679924) (xy 379.196756 -264.669744) (xy 379.14917 -264.651697) (xy 379.105096 -264.626251)
			(xy 379.065674 -264.594064) (xy 379.031926 -264.55597) (xy 379.004725 -264.512956) (xy 378.984777 -264.466136)
			(xy 378.972598 -264.416722) (xy 378.968503 -264.365994) (xy 378.650246 -264.365994) (xy 378.649751 -264.390601)
			(xy 378.641856 -264.439178) (xy 378.626272 -264.485859) (xy 378.603401 -264.529436) (xy 378.573836 -264.56878)
			(xy 378.538343 -264.602872) (xy 378.49784 -264.630828) (xy 378.453378 -264.651926) (xy 378.406107 -264.665618)
			(xy 378.357252 -264.67155) (xy 378.308077 -264.669569) (xy 378.259858 -264.659725) (xy 378.213842 -264.642273)
			(xy 378.171221 -264.617666) (xy 378.1331 -264.586541) (xy 378.100465 -264.549704) (xy 378.074162 -264.508108)
			(xy 378.054871 -264.462832) (xy 378.043094 -264.415048) (xy 378.039134 -264.365994) (xy 377.720606 -264.365994)
			(xy 377.720094 -264.39144) (xy 377.71193 -264.441674) (xy 377.695814 -264.489948) (xy 377.672163 -264.535011)
			(xy 377.64159 -264.575697) (xy 377.604886 -264.610952) (xy 377.563002 -264.639862) (xy 377.517023 -264.661679)
			(xy 377.468139 -264.675839) (xy 377.417618 -264.681973) (xy 377.366766 -264.679924) (xy 377.316902 -264.669744)
			(xy 377.269316 -264.651697) (xy 377.225242 -264.626251) (xy 377.18582 -264.594064) (xy 377.152072 -264.55597)
			(xy 377.124871 -264.512956) (xy 377.104923 -264.466136) (xy 377.092744 -264.416722) (xy 377.088649 -264.365994)
			(xy 376.780552 -264.365994) (xy 376.78004 -264.39144) (xy 376.771876 -264.441674) (xy 376.75576 -264.489948)
			(xy 376.732109 -264.535011) (xy 376.701536 -264.575697) (xy 376.664832 -264.610952) (xy 376.622948 -264.639862)
			(xy 376.576969 -264.661679) (xy 376.528085 -264.675839) (xy 376.477564 -264.681973) (xy 376.426712 -264.679924)
			(xy 376.376848 -264.669744) (xy 376.329262 -264.651697) (xy 376.285188 -264.626251) (xy 376.245766 -264.594064)
			(xy 376.212018 -264.55597) (xy 376.184817 -264.512956) (xy 376.164869 -264.466136) (xy 376.15269 -264.416722)
			(xy 376.148595 -264.365994) (xy 374.89003 -264.365994) (xy 374.889535 -264.390601) (xy 374.88164 -264.439178)
			(xy 374.866056 -264.485859) (xy 374.843185 -264.529436) (xy 374.81362 -264.56878) (xy 374.778127 -264.602872)
			(xy 374.737624 -264.630828) (xy 374.693162 -264.651926) (xy 374.645891 -264.665618) (xy 374.597036 -264.67155)
			(xy 374.547861 -264.669569) (xy 374.499642 -264.659725) (xy 374.453626 -264.642273) (xy 374.411005 -264.617666)
			(xy 374.372884 -264.586541) (xy 374.340249 -264.549704) (xy 374.313946 -264.508108) (xy 374.294655 -264.462832)
			(xy 374.282878 -264.415048) (xy 374.278918 -264.365994) (xy 373.010176 -264.365994) (xy 373.009681 -264.390601)
			(xy 373.001786 -264.439178) (xy 372.986202 -264.485859) (xy 372.963331 -264.529436) (xy 372.933766 -264.56878)
			(xy 372.898273 -264.602872) (xy 372.85777 -264.630828) (xy 372.813308 -264.651926) (xy 372.766037 -264.665618)
			(xy 372.717182 -264.67155) (xy 372.668007 -264.669569) (xy 372.619788 -264.659725) (xy 372.573772 -264.642273)
			(xy 372.531151 -264.617666) (xy 372.49303 -264.586541) (xy 372.460395 -264.549704) (xy 372.434092 -264.508108)
			(xy 372.414801 -264.462832) (xy 372.403024 -264.415048) (xy 372.399064 -264.365994) (xy 371.130068 -264.365994)
			(xy 371.129573 -264.390601) (xy 371.121678 -264.439178) (xy 371.106094 -264.485859) (xy 371.083223 -264.529436)
			(xy 371.053658 -264.56878) (xy 371.018165 -264.602872) (xy 370.977662 -264.630828) (xy 370.9332 -264.651926)
			(xy 370.885929 -264.665618) (xy 370.837074 -264.67155) (xy 370.787899 -264.669569) (xy 370.73968 -264.659725)
			(xy 370.693664 -264.642273) (xy 370.651043 -264.617666) (xy 370.612922 -264.586541) (xy 370.580287 -264.549704)
			(xy 370.553984 -264.508108) (xy 370.534693 -264.462832) (xy 370.522916 -264.415048) (xy 370.518956 -264.365994)
			(xy 369.250935 -264.365994) (xy 369.250976 -264.368026) (xy 369.250481 -264.392633) (xy 369.242586 -264.44121)
			(xy 369.227002 -264.487891) (xy 369.204131 -264.531468) (xy 369.174566 -264.570812) (xy 369.139073 -264.604904)
			(xy 369.09857 -264.63286) (xy 369.054108 -264.653958) (xy 369.006837 -264.66765) (xy 368.957982 -264.673582)
			(xy 368.908807 -264.671601) (xy 368.860588 -264.661757) (xy 368.814572 -264.644305) (xy 368.771951 -264.619698)
			(xy 368.73383 -264.588573) (xy 368.701195 -264.551736) (xy 368.674892 -264.51014) (xy 368.655601 -264.464864)
			(xy 368.643824 -264.41708) (xy 368.639864 -264.368026) (xy 367.373154 -264.368026) (xy 367.372659 -264.392633)
			(xy 367.364764 -264.44121) (xy 367.34918 -264.487891) (xy 367.326309 -264.531468) (xy 367.296744 -264.570812)
			(xy 367.261251 -264.604904) (xy 367.220748 -264.63286) (xy 367.176286 -264.653958) (xy 367.129015 -264.66765)
			(xy 367.08016 -264.673582) (xy 367.030985 -264.671601) (xy 366.982766 -264.661757) (xy 366.93675 -264.644305)
			(xy 366.894129 -264.619698) (xy 366.856008 -264.588573) (xy 366.823373 -264.551736) (xy 366.79707 -264.51014)
			(xy 366.777779 -264.464864) (xy 366.766002 -264.41708) (xy 366.762042 -264.368026) (xy 365.4933 -264.368026)
			(xy 365.492805 -264.392633) (xy 365.48491 -264.44121) (xy 365.469326 -264.487891) (xy 365.446455 -264.531468)
			(xy 365.41689 -264.570812) (xy 365.381397 -264.604904) (xy 365.340894 -264.63286) (xy 365.296432 -264.653958)
			(xy 365.249161 -264.66765) (xy 365.200306 -264.673582) (xy 365.151131 -264.671601) (xy 365.102912 -264.661757)
			(xy 365.056896 -264.644305) (xy 365.014275 -264.619698) (xy 364.976154 -264.588573) (xy 364.943519 -264.551736)
			(xy 364.917216 -264.51014) (xy 364.897925 -264.464864) (xy 364.886148 -264.41708) (xy 364.882188 -264.368026)
			(xy 363.613192 -264.368026) (xy 363.612697 -264.392633) (xy 363.604802 -264.44121) (xy 363.589218 -264.487891)
			(xy 363.566347 -264.531468) (xy 363.536782 -264.570812) (xy 363.501289 -264.604904) (xy 363.460786 -264.63286)
			(xy 363.416324 -264.653958) (xy 363.369053 -264.66765) (xy 363.320198 -264.673582) (xy 363.271023 -264.671601)
			(xy 363.222804 -264.661757) (xy 363.176788 -264.644305) (xy 363.134167 -264.619698) (xy 363.096046 -264.588573)
			(xy 363.063411 -264.551736) (xy 363.037108 -264.51014) (xy 363.017817 -264.464864) (xy 363.00604 -264.41708)
			(xy 363.00208 -264.368026) (xy 356.093268 -264.368026) (xy 356.092773 -264.392633) (xy 356.084878 -264.44121)
			(xy 356.069294 -264.487891) (xy 356.046423 -264.531468) (xy 356.016858 -264.570812) (xy 355.981365 -264.604904)
			(xy 355.940862 -264.63286) (xy 355.8964 -264.653958) (xy 355.849129 -264.66765) (xy 355.800274 -264.673582)
			(xy 355.751099 -264.671601) (xy 355.70288 -264.661757) (xy 355.656864 -264.644305) (xy 355.614243 -264.619698)
			(xy 355.576122 -264.588573) (xy 355.543487 -264.551736) (xy 355.517184 -264.51014) (xy 355.497893 -264.464864)
			(xy 355.486116 -264.41708) (xy 355.482156 -264.368026) (xy 354.213414 -264.368026) (xy 354.212919 -264.392633)
			(xy 354.205024 -264.44121) (xy 354.18944 -264.487891) (xy 354.166569 -264.531468) (xy 354.137004 -264.570812)
			(xy 354.101511 -264.604904) (xy 354.061008 -264.63286) (xy 354.016546 -264.653958) (xy 353.969275 -264.66765)
			(xy 353.92042 -264.673582) (xy 353.871245 -264.671601) (xy 353.823026 -264.661757) (xy 353.77701 -264.644305)
			(xy 353.734389 -264.619698) (xy 353.696268 -264.588573) (xy 353.663633 -264.551736) (xy 353.63733 -264.51014)
			(xy 353.618039 -264.464864) (xy 353.606262 -264.41708) (xy 353.602302 -264.368026) (xy 352.333306 -264.368026)
			(xy 352.332833 -264.392016) (xy 352.325324 -264.439404) (xy 352.310494 -264.485035) (xy 352.288709 -264.527784)
			(xy 352.260506 -264.566599) (xy 352.226577 -264.600524) (xy 352.18776 -264.628724) (xy 352.145009 -264.650505)
			(xy 352.099377 -264.665331) (xy 352.051988 -264.672836) (xy 352.027998 -264.673334) (xy 352.004196 -264.672878)
			(xy 351.95717 -264.66549) (xy 351.91186 -264.650894) (xy 351.869364 -264.629442) (xy 351.830712 -264.601655)
			(xy 351.796841 -264.568207) (xy 351.768571 -264.529907) (xy 351.746587 -264.487683) (xy 351.731423 -264.44256)
			(xy 351.723445 -264.39563) (xy 351.72269 -264.371836) (xy 351.72269 -264.368026) (xy 351.723062 -264.346467)
			(xy 351.729117 -264.303777) (xy 351.741097 -264.262358) (xy 351.749614 -264.24255) (xy 351.755202 -264.230358)
			(xy 351.75317 -264.205212) (xy 351.69983 -264.122408) (xy 351.694969 -264.11546) (xy 351.681639 -264.104995)
			(xy 351.66563 -264.099434) (xy 351.657158 -264.09904) (xy 350.523048 -264.09904) (xy 350.510313 -264.099737)
			(xy 350.487914 -264.111866) (xy 350.480376 -264.122154) (xy 350.438212 -264.18667) (xy 350.43491 -264.19302)
			(xy 350.433117 -264.197139) (xy 350.430826 -264.205826) (xy 350.430338 -264.210292) (xy 350.430084 -264.21461)
			(xy 350.430084 -264.24128) (xy 350.433894 -264.250678) (xy 350.444423 -264.278337) (xy 350.455801 -264.336407)
			(xy 350.4565 -264.365994) (xy 350.455978 -264.391249) (xy 350.447665 -264.441071) (xy 350.431264 -264.488845)
			(xy 350.407223 -264.533268) (xy 350.376199 -264.573128) (xy 350.339037 -264.607338) (xy 350.296751 -264.634964)
			(xy 350.250495 -264.655254) (xy 350.20153 -264.667654) (xy 350.151192 -264.671825) (xy 350.100854 -264.667654)
			(xy 350.051889 -264.655254) (xy 350.005633 -264.634964) (xy 349.963347 -264.607338) (xy 349.926185 -264.573128)
			(xy 349.895161 -264.533268) (xy 349.87112 -264.488845) (xy 349.854719 -264.441071) (xy 349.846406 -264.391249)
			(xy 349.845884 -264.365994) (xy 349.846268 -264.344708) (xy 349.852215 -264.302552) (xy 349.863965 -264.261632)
			(xy 349.8723 -264.242042) (xy 349.87738 -264.230104) (xy 349.875348 -264.204704) (xy 349.822008 -264.122154)
			(xy 349.81715 -264.115215) (xy 349.803816 -264.104783) (xy 349.787802 -264.099291) (xy 349.779336 -264.09904)
			(xy 349.009462 -264.09904) (xy 348.999396 -264.099471) (xy 348.980805 -264.1072) (xy 348.973394 -264.114026)
			(xy 348.736666 -264.350754) (xy 348.7293 -264.357866) (xy 348.72168 -264.376662) (xy 348.72168 -264.80135)
			(xy 348.72207 -264.810875) (xy 348.72897 -264.828631) (xy 348.735142 -264.835894) (xy 348.759454 -264.86231)
			(xy 359.174291 -264.86231) (xy 359.178321 -264.809812) (xy 359.190318 -264.758544) (xy 359.210001 -264.709709)
			(xy 359.236907 -264.66445) (xy 359.270407 -264.623829) (xy 359.309715 -264.588798) (xy 359.35391 -264.560178)
			(xy 359.401955 -264.538639) (xy 359.452726 -264.524687) (xy 359.505031 -264.518649) (xy 359.557645 -264.520666)
			(xy 359.609335 -264.53069) (xy 359.658888 -264.548488) (xy 359.705144 -264.573641) (xy 359.747018 -264.60556)
			(xy 359.78353 -264.643498) (xy 359.813822 -264.686564) (xy 359.837185 -264.733749) (xy 359.853071 -264.783948)
			(xy 359.861108 -264.835984) (xy 359.861612 -264.86231) (xy 359.861108 -264.888636) (xy 359.853071 -264.940672)
			(xy 359.837185 -264.990871) (xy 359.813822 -265.038056) (xy 359.78353 -265.081122) (xy 359.747018 -265.11906)
			(xy 359.705144 -265.150979) (xy 359.659131 -265.176) (xy 369.109002 -265.176) (xy 369.112962 -265.126946)
			(xy 369.124739 -265.079162) (xy 369.14403 -265.033886) (xy 369.170333 -264.99229) (xy 369.202968 -264.955453)
			(xy 369.241089 -264.924328) (xy 369.28371 -264.899721) (xy 369.329726 -264.882269) (xy 369.377945 -264.872425)
			(xy 369.42712 -264.870444) (xy 369.475975 -264.876376) (xy 369.523246 -264.890068) (xy 369.567708 -264.911166)
			(xy 369.608211 -264.939122) (xy 369.643704 -264.973214) (xy 369.673269 -265.012558) (xy 369.69614 -265.056135)
			(xy 369.711724 -265.102816) (xy 369.719619 -265.151393) (xy 369.720114 -265.176) (xy 370.98911 -265.176)
			(xy 370.99307 -265.126946) (xy 371.004847 -265.079162) (xy 371.024138 -265.033886) (xy 371.050441 -264.99229)
			(xy 371.083076 -264.955453) (xy 371.121197 -264.924328) (xy 371.163818 -264.899721) (xy 371.209834 -264.882269)
			(xy 371.258053 -264.872425) (xy 371.307228 -264.870444) (xy 371.356083 -264.876376) (xy 371.403354 -264.890068)
			(xy 371.447816 -264.911166) (xy 371.488319 -264.939122) (xy 371.523812 -264.973214) (xy 371.553377 -265.012558)
			(xy 371.576248 -265.056135) (xy 371.591832 -265.102816) (xy 371.599727 -265.151393) (xy 371.600222 -265.176)
			(xy 372.868964 -265.176) (xy 372.872924 -265.126946) (xy 372.884701 -265.079162) (xy 372.903992 -265.033886)
			(xy 372.930295 -264.99229) (xy 372.96293 -264.955453) (xy 373.001051 -264.924328) (xy 373.043672 -264.899721)
			(xy 373.089688 -264.882269) (xy 373.137907 -264.872425) (xy 373.187082 -264.870444) (xy 373.235937 -264.876376)
			(xy 373.283208 -264.890068) (xy 373.32767 -264.911166) (xy 373.368173 -264.939122) (xy 373.403666 -264.973214)
			(xy 373.433231 -265.012558) (xy 373.456102 -265.056135) (xy 373.471686 -265.102816) (xy 373.479581 -265.151393)
			(xy 373.480076 -265.176) (xy 374.749072 -265.176) (xy 374.753032 -265.126946) (xy 374.764809 -265.079162)
			(xy 374.7841 -265.033886) (xy 374.810403 -264.99229) (xy 374.843038 -264.955453) (xy 374.881159 -264.924328)
			(xy 374.92378 -264.899721) (xy 374.969796 -264.882269) (xy 375.018015 -264.872425) (xy 375.06719 -264.870444)
			(xy 375.116045 -264.876376) (xy 375.163316 -264.890068) (xy 375.207778 -264.911166) (xy 375.248281 -264.939122)
			(xy 375.283774 -264.973214) (xy 375.313339 -265.012558) (xy 375.33621 -265.056135) (xy 375.351794 -265.102816)
			(xy 375.359689 -265.151393) (xy 375.360184 -265.176) (xy 375.678695 -265.176) (xy 375.68279 -265.125272)
			(xy 375.694969 -265.075858) (xy 375.714917 -265.029038) (xy 375.742118 -264.986024) (xy 375.775866 -264.94793)
			(xy 375.815288 -264.915743) (xy 375.859362 -264.890297) (xy 375.906948 -264.87225) (xy 375.956812 -264.86207)
			(xy 376.007664 -264.860021) (xy 376.058185 -264.866155) (xy 376.107069 -264.880315) (xy 376.153048 -264.902132)
			(xy 376.194932 -264.931042) (xy 376.231636 -264.966297) (xy 376.262209 -265.006983) (xy 376.28586 -265.052046)
			(xy 376.301976 -265.10032) (xy 376.31014 -265.150554) (xy 376.310652 -265.176) (xy 376.628926 -265.176)
			(xy 376.632886 -265.126946) (xy 376.644663 -265.079162) (xy 376.663954 -265.033886) (xy 376.690257 -264.99229)
			(xy 376.722892 -264.955453) (xy 376.761013 -264.924328) (xy 376.803634 -264.899721) (xy 376.84965 -264.882269)
			(xy 376.897869 -264.872425) (xy 376.947044 -264.870444) (xy 376.995899 -264.876376) (xy 377.04317 -264.890068)
			(xy 377.087632 -264.911166) (xy 377.128135 -264.939122) (xy 377.163628 -264.973214) (xy 377.193193 -265.012558)
			(xy 377.216064 -265.056135) (xy 377.231648 -265.102816) (xy 377.239543 -265.151393) (xy 377.240038 -265.176)
			(xy 377.56898 -265.176) (xy 377.57294 -265.126946) (xy 377.584717 -265.079162) (xy 377.604008 -265.033886)
			(xy 377.630311 -264.99229) (xy 377.662946 -264.955453) (xy 377.701067 -264.924328) (xy 377.743688 -264.899721)
			(xy 377.789704 -264.882269) (xy 377.837923 -264.872425) (xy 377.887098 -264.870444) (xy 377.935953 -264.876376)
			(xy 377.983224 -264.890068) (xy 378.027686 -264.911166) (xy 378.068189 -264.939122) (xy 378.103682 -264.973214)
			(xy 378.133247 -265.012558) (xy 378.156118 -265.056135) (xy 378.171702 -265.102816) (xy 378.179597 -265.151393)
			(xy 378.180092 -265.176) (xy 378.509034 -265.176) (xy 378.512994 -265.126946) (xy 378.524771 -265.079162)
			(xy 378.544062 -265.033886) (xy 378.570365 -264.99229) (xy 378.603 -264.955453) (xy 378.641121 -264.924328)
			(xy 378.683742 -264.899721) (xy 378.729758 -264.882269) (xy 378.777977 -264.872425) (xy 378.827152 -264.870444)
			(xy 378.876007 -264.876376) (xy 378.923278 -264.890068) (xy 378.96774 -264.911166) (xy 379.008243 -264.939122)
			(xy 379.043736 -264.973214) (xy 379.073301 -265.012558) (xy 379.096172 -265.056135) (xy 379.111756 -265.102816)
			(xy 379.119651 -265.151393) (xy 379.120146 -265.176) (xy 379.438657 -265.176) (xy 379.442752 -265.125272)
			(xy 379.454931 -265.075858) (xy 379.474879 -265.029038) (xy 379.50208 -264.986024) (xy 379.535828 -264.94793)
			(xy 379.57525 -264.915743) (xy 379.619324 -264.890297) (xy 379.66691 -264.87225) (xy 379.716774 -264.86207)
			(xy 379.767626 -264.860021) (xy 379.818147 -264.866155) (xy 379.867031 -264.880315) (xy 379.91301 -264.902132)
			(xy 379.954894 -264.931042) (xy 379.991598 -264.966297) (xy 380.022171 -265.006983) (xy 380.045822 -265.052046)
			(xy 380.061938 -265.10032) (xy 380.070102 -265.150554) (xy 380.070614 -265.176) (xy 380.388888 -265.176)
			(xy 380.392848 -265.126946) (xy 380.404625 -265.079162) (xy 380.423916 -265.033886) (xy 380.450219 -264.99229)
			(xy 380.482854 -264.955453) (xy 380.520975 -264.924328) (xy 380.563596 -264.899721) (xy 380.609612 -264.882269)
			(xy 380.657831 -264.872425) (xy 380.707006 -264.870444) (xy 380.755861 -264.876376) (xy 380.803132 -264.890068)
			(xy 380.847594 -264.911166) (xy 380.888097 -264.939122) (xy 380.92359 -264.973214) (xy 380.953155 -265.012558)
			(xy 380.976026 -265.056135) (xy 380.99161 -265.102816) (xy 380.999505 -265.151393) (xy 381 -265.176)
			(xy 380.999505 -265.200607) (xy 380.99161 -265.249184) (xy 380.976026 -265.295865) (xy 380.953155 -265.339442)
			(xy 380.92359 -265.378786) (xy 380.888097 -265.412878) (xy 380.847594 -265.440834) (xy 380.803132 -265.461932)
			(xy 380.755861 -265.475624) (xy 380.707006 -265.481556) (xy 380.657831 -265.479575) (xy 380.609612 -265.469731)
			(xy 380.563596 -265.452279) (xy 380.520975 -265.427672) (xy 380.482854 -265.396547) (xy 380.450219 -265.35971)
			(xy 380.423916 -265.318114) (xy 380.404625 -265.272838) (xy 380.392848 -265.225054) (xy 380.388888 -265.176)
			(xy 380.070614 -265.176) (xy 380.070102 -265.201446) (xy 380.061938 -265.25168) (xy 380.045822 -265.299954)
			(xy 380.022171 -265.345017) (xy 379.991598 -265.385703) (xy 379.954894 -265.420958) (xy 379.91301 -265.449868)
			(xy 379.867031 -265.471685) (xy 379.818147 -265.485845) (xy 379.767626 -265.491979) (xy 379.716774 -265.48993)
			(xy 379.66691 -265.47975) (xy 379.619324 -265.461703) (xy 379.57525 -265.436257) (xy 379.535828 -265.40407)
			(xy 379.50208 -265.365976) (xy 379.474879 -265.322962) (xy 379.454931 -265.276142) (xy 379.442752 -265.226728)
			(xy 379.438657 -265.176) (xy 379.120146 -265.176) (xy 379.119651 -265.200607) (xy 379.111756 -265.249184)
			(xy 379.096172 -265.295865) (xy 379.073301 -265.339442) (xy 379.043736 -265.378786) (xy 379.008243 -265.412878)
			(xy 378.96774 -265.440834) (xy 378.923278 -265.461932) (xy 378.876007 -265.475624) (xy 378.827152 -265.481556)
			(xy 378.777977 -265.479575) (xy 378.729758 -265.469731) (xy 378.683742 -265.452279) (xy 378.641121 -265.427672)
			(xy 378.603 -265.396547) (xy 378.570365 -265.35971) (xy 378.544062 -265.318114) (xy 378.524771 -265.272838)
			(xy 378.512994 -265.225054) (xy 378.509034 -265.176) (xy 378.180092 -265.176) (xy 378.179597 -265.200607)
			(xy 378.171702 -265.249184) (xy 378.156118 -265.295865) (xy 378.133247 -265.339442) (xy 378.103682 -265.378786)
			(xy 378.068189 -265.412878) (xy 378.027686 -265.440834) (xy 377.983224 -265.461932) (xy 377.935953 -265.475624)
			(xy 377.887098 -265.481556) (xy 377.837923 -265.479575) (xy 377.789704 -265.469731) (xy 377.743688 -265.452279)
			(xy 377.701067 -265.427672) (xy 377.662946 -265.396547) (xy 377.630311 -265.35971) (xy 377.604008 -265.318114)
			(xy 377.584717 -265.272838) (xy 377.57294 -265.225054) (xy 377.56898 -265.176) (xy 377.240038 -265.176)
			(xy 377.239543 -265.200607) (xy 377.231648 -265.249184) (xy 377.216064 -265.295865) (xy 377.193193 -265.339442)
			(xy 377.163628 -265.378786) (xy 377.128135 -265.412878) (xy 377.087632 -265.440834) (xy 377.04317 -265.461932)
			(xy 376.995899 -265.475624) (xy 376.947044 -265.481556) (xy 376.897869 -265.479575) (xy 376.84965 -265.469731)
			(xy 376.803634 -265.452279) (xy 376.761013 -265.427672) (xy 376.722892 -265.396547) (xy 376.690257 -265.35971)
			(xy 376.663954 -265.318114) (xy 376.644663 -265.272838) (xy 376.632886 -265.225054) (xy 376.628926 -265.176)
			(xy 376.310652 -265.176) (xy 376.31014 -265.201446) (xy 376.301976 -265.25168) (xy 376.28586 -265.299954)
			(xy 376.262209 -265.345017) (xy 376.231636 -265.385703) (xy 376.194932 -265.420958) (xy 376.153048 -265.449868)
			(xy 376.107069 -265.471685) (xy 376.058185 -265.485845) (xy 376.007664 -265.491979) (xy 375.956812 -265.48993)
			(xy 375.906948 -265.47975) (xy 375.859362 -265.461703) (xy 375.815288 -265.436257) (xy 375.775866 -265.40407)
			(xy 375.742118 -265.365976) (xy 375.714917 -265.322962) (xy 375.694969 -265.276142) (xy 375.68279 -265.226728)
			(xy 375.678695 -265.176) (xy 375.360184 -265.176) (xy 375.359689 -265.200607) (xy 375.351794 -265.249184)
			(xy 375.33621 -265.295865) (xy 375.313339 -265.339442) (xy 375.283774 -265.378786) (xy 375.248281 -265.412878)
			(xy 375.207778 -265.440834) (xy 375.163316 -265.461932) (xy 375.116045 -265.475624) (xy 375.06719 -265.481556)
			(xy 375.018015 -265.479575) (xy 374.969796 -265.469731) (xy 374.92378 -265.452279) (xy 374.881159 -265.427672)
			(xy 374.843038 -265.396547) (xy 374.810403 -265.35971) (xy 374.7841 -265.318114) (xy 374.764809 -265.272838)
			(xy 374.753032 -265.225054) (xy 374.749072 -265.176) (xy 373.480076 -265.176) (xy 373.479581 -265.200607)
			(xy 373.471686 -265.249184) (xy 373.456102 -265.295865) (xy 373.433231 -265.339442) (xy 373.403666 -265.378786)
			(xy 373.368173 -265.412878) (xy 373.32767 -265.440834) (xy 373.283208 -265.461932) (xy 373.235937 -265.475624)
			(xy 373.187082 -265.481556) (xy 373.137907 -265.479575) (xy 373.089688 -265.469731) (xy 373.043672 -265.452279)
			(xy 373.001051 -265.427672) (xy 372.96293 -265.396547) (xy 372.930295 -265.35971) (xy 372.903992 -265.318114)
			(xy 372.884701 -265.272838) (xy 372.872924 -265.225054) (xy 372.868964 -265.176) (xy 371.600222 -265.176)
			(xy 371.599727 -265.200607) (xy 371.591832 -265.249184) (xy 371.576248 -265.295865) (xy 371.553377 -265.339442)
			(xy 371.523812 -265.378786) (xy 371.488319 -265.412878) (xy 371.447816 -265.440834) (xy 371.403354 -265.461932)
			(xy 371.356083 -265.475624) (xy 371.307228 -265.481556) (xy 371.258053 -265.479575) (xy 371.209834 -265.469731)
			(xy 371.163818 -265.452279) (xy 371.121197 -265.427672) (xy 371.083076 -265.396547) (xy 371.050441 -265.35971)
			(xy 371.024138 -265.318114) (xy 371.004847 -265.272838) (xy 370.99307 -265.225054) (xy 370.98911 -265.176)
			(xy 369.720114 -265.176) (xy 369.719619 -265.200607) (xy 369.711724 -265.249184) (xy 369.69614 -265.295865)
			(xy 369.673269 -265.339442) (xy 369.643704 -265.378786) (xy 369.608211 -265.412878) (xy 369.567708 -265.440834)
			(xy 369.523246 -265.461932) (xy 369.475975 -265.475624) (xy 369.42712 -265.481556) (xy 369.377945 -265.479575)
			(xy 369.329726 -265.469731) (xy 369.28371 -265.452279) (xy 369.241089 -265.427672) (xy 369.202968 -265.396547)
			(xy 369.170333 -265.35971) (xy 369.14403 -265.318114) (xy 369.124739 -265.272838) (xy 369.112962 -265.225054)
			(xy 369.109002 -265.176) (xy 359.659131 -265.176) (xy 359.658888 -265.176132) (xy 359.609335 -265.19393)
			(xy 359.557645 -265.203954) (xy 359.505031 -265.205971) (xy 359.452726 -265.199933) (xy 359.401955 -265.185981)
			(xy 359.35391 -265.164442) (xy 359.309715 -265.135822) (xy 359.270407 -265.100791) (xy 359.236907 -265.06017)
			(xy 359.210001 -265.014911) (xy 359.190318 -264.966076) (xy 359.178321 -264.914808) (xy 359.174291 -264.86231)
			(xy 348.759454 -264.86231) (xy 348.761558 -264.864596) (xy 348.776798 -264.872724) (xy 348.785434 -264.873994)
			(xy 348.809296 -264.877955) (xy 348.855449 -264.892425) (xy 348.898743 -264.913992) (xy 348.938093 -264.942118)
			(xy 348.972515 -264.976097) (xy 349.001147 -265.01508) (xy 349.023273 -265.058091) (xy 349.038338 -265.104053)
			(xy 349.045967 -265.151816) (xy 349.045967 -265.176) (xy 349.375234 -265.176) (xy 349.379194 -265.126946)
			(xy 349.390971 -265.079162) (xy 349.410262 -265.033886) (xy 349.436565 -264.99229) (xy 349.4692 -264.955453)
			(xy 349.507321 -264.924328) (xy 349.549942 -264.899721) (xy 349.595958 -264.882269) (xy 349.644177 -264.872425)
			(xy 349.693352 -264.870444) (xy 349.742207 -264.876376) (xy 349.789478 -264.890068) (xy 349.83394 -264.911166)
			(xy 349.874443 -264.939122) (xy 349.909936 -264.973214) (xy 349.939501 -265.012558) (xy 349.962372 -265.056135)
			(xy 349.977956 -265.102816) (xy 349.985851 -265.151393) (xy 349.986346 -265.176) (xy 349.985851 -265.200607)
			(xy 349.977956 -265.249184) (xy 349.962372 -265.295865) (xy 349.939501 -265.339442) (xy 349.909936 -265.378786)
			(xy 349.874443 -265.412878) (xy 349.83394 -265.440834) (xy 349.789478 -265.461932) (xy 349.742207 -265.475624)
			(xy 349.693352 -265.481556) (xy 349.644177 -265.479575) (xy 349.595958 -265.469731) (xy 349.549942 -265.452279)
			(xy 349.507321 -265.427672) (xy 349.4692 -265.396547) (xy 349.436565 -265.35971) (xy 349.410262 -265.318114)
			(xy 349.390971 -265.272838) (xy 349.379194 -265.225054) (xy 349.375234 -265.176) (xy 349.045967 -265.176)
			(xy 349.045967 -265.200184) (xy 349.038338 -265.247947) (xy 349.023273 -265.293909) (xy 349.001147 -265.33692)
			(xy 348.972515 -265.375903) (xy 348.938093 -265.409882) (xy 348.898743 -265.438008) (xy 348.855449 -265.459575)
			(xy 348.809296 -265.474045) (xy 348.785434 -265.478006) (xy 348.776798 -265.479276) (xy 348.761558 -265.487404)
			(xy 348.735142 -265.516106) (xy 348.728959 -265.523366) (xy 348.722041 -265.541121) (xy 348.72168 -265.55065)
			(xy 348.72168 -265.986006) (xy 349.845388 -265.986006) (xy 349.849348 -265.936952) (xy 349.861125 -265.889168)
			(xy 349.880416 -265.843892) (xy 349.906719 -265.802296) (xy 349.939354 -265.765459) (xy 349.977475 -265.734334)
			(xy 350.020096 -265.709727) (xy 350.066112 -265.692275) (xy 350.114331 -265.682431) (xy 350.163506 -265.68045)
			(xy 350.212361 -265.686382) (xy 350.259632 -265.700074) (xy 350.304094 -265.721172) (xy 350.344597 -265.749128)
			(xy 350.38009 -265.78322) (xy 350.409655 -265.822564) (xy 350.432526 -265.866141) (xy 350.44811 -265.912822)
			(xy 350.456005 -265.961399) (xy 350.4565 -265.986006) (xy 351.725242 -265.986006) (xy 351.729202 -265.936952)
			(xy 351.740979 -265.889168) (xy 351.76027 -265.843892) (xy 351.786573 -265.802296) (xy 351.819208 -265.765459)
			(xy 351.857329 -265.734334) (xy 351.89995 -265.709727) (xy 351.945966 -265.692275) (xy 351.994185 -265.682431)
			(xy 352.04336 -265.68045) (xy 352.092215 -265.686382) (xy 352.139486 -265.700074) (xy 352.183948 -265.721172)
			(xy 352.224451 -265.749128) (xy 352.259944 -265.78322) (xy 352.289509 -265.822564) (xy 352.31238 -265.866141)
			(xy 352.327964 -265.912822) (xy 352.335859 -265.961399) (xy 352.336354 -265.986006) (xy 353.60535 -265.986006)
			(xy 353.60931 -265.936952) (xy 353.621087 -265.889168) (xy 353.640378 -265.843892) (xy 353.666681 -265.802296)
			(xy 353.699316 -265.765459) (xy 353.737437 -265.734334) (xy 353.780058 -265.709727) (xy 353.826074 -265.692275)
			(xy 353.874293 -265.682431) (xy 353.923468 -265.68045) (xy 353.972323 -265.686382) (xy 354.019594 -265.700074)
			(xy 354.064056 -265.721172) (xy 354.104559 -265.749128) (xy 354.140052 -265.78322) (xy 354.169617 -265.822564)
			(xy 354.192488 -265.866141) (xy 354.208072 -265.912822) (xy 354.215967 -265.961399) (xy 354.216462 -265.986006)
			(xy 355.485204 -265.986006) (xy 355.489164 -265.936952) (xy 355.500941 -265.889168) (xy 355.520232 -265.843892)
			(xy 355.546535 -265.802296) (xy 355.57917 -265.765459) (xy 355.617291 -265.734334) (xy 355.659912 -265.709727)
			(xy 355.705928 -265.692275) (xy 355.754147 -265.682431) (xy 355.803322 -265.68045) (xy 355.852177 -265.686382)
			(xy 355.899448 -265.700074) (xy 355.94391 -265.721172) (xy 355.984413 -265.749128) (xy 356.019906 -265.78322)
			(xy 356.049471 -265.822564) (xy 356.072342 -265.866141) (xy 356.087926 -265.912822) (xy 356.095821 -265.961399)
			(xy 356.096316 -265.986006) (xy 357.365312 -265.986006) (xy 357.369272 -265.936952) (xy 357.381049 -265.889168)
			(xy 357.40034 -265.843892) (xy 357.426643 -265.802296) (xy 357.459278 -265.765459) (xy 357.497399 -265.734334)
			(xy 357.54002 -265.709727) (xy 357.586036 -265.692275) (xy 357.634255 -265.682431) (xy 357.68343 -265.68045)
			(xy 357.732285 -265.686382) (xy 357.779556 -265.700074) (xy 357.824018 -265.721172) (xy 357.864521 -265.749128)
			(xy 357.900014 -265.78322) (xy 357.929579 -265.822564) (xy 357.95245 -265.866141) (xy 357.968034 -265.912822)
			(xy 357.975929 -265.961399) (xy 357.976424 -265.986006) (xy 361.118924 -265.986006) (xy 361.122884 -265.936952)
			(xy 361.134661 -265.889168) (xy 361.153952 -265.843892) (xy 361.180255 -265.802296) (xy 361.21289 -265.765459)
			(xy 361.251011 -265.734334) (xy 361.293632 -265.709727) (xy 361.339648 -265.692275) (xy 361.387867 -265.682431)
			(xy 361.437042 -265.68045) (xy 361.485897 -265.686382) (xy 361.533168 -265.700074) (xy 361.57763 -265.721172)
			(xy 361.618133 -265.749128) (xy 361.653626 -265.78322) (xy 361.683191 -265.822564) (xy 361.706062 -265.866141)
			(xy 361.721646 -265.912822) (xy 361.729541 -265.961399) (xy 361.730036 -265.986006) (xy 362.999032 -265.986006)
			(xy 363.002992 -265.936952) (xy 363.014769 -265.889168) (xy 363.03406 -265.843892) (xy 363.060363 -265.802296)
			(xy 363.092998 -265.765459) (xy 363.131119 -265.734334) (xy 363.17374 -265.709727) (xy 363.219756 -265.692275)
			(xy 363.267975 -265.682431) (xy 363.31715 -265.68045) (xy 363.366005 -265.686382) (xy 363.413276 -265.700074)
			(xy 363.457738 -265.721172) (xy 363.498241 -265.749128) (xy 363.533734 -265.78322) (xy 363.563299 -265.822564)
			(xy 363.58617 -265.866141) (xy 363.601754 -265.912822) (xy 363.609649 -265.961399) (xy 363.610144 -265.986006)
			(xy 364.878886 -265.986006) (xy 364.882846 -265.936952) (xy 364.894623 -265.889168) (xy 364.913914 -265.843892)
			(xy 364.940217 -265.802296) (xy 364.972852 -265.765459) (xy 365.010973 -265.734334) (xy 365.053594 -265.709727)
			(xy 365.09961 -265.692275) (xy 365.147829 -265.682431) (xy 365.197004 -265.68045) (xy 365.245859 -265.686382)
			(xy 365.29313 -265.700074) (xy 365.337592 -265.721172) (xy 365.378095 -265.749128) (xy 365.413588 -265.78322)
			(xy 365.443153 -265.822564) (xy 365.466024 -265.866141) (xy 365.481608 -265.912822) (xy 365.489503 -265.961399)
			(xy 365.489998 -265.986006) (xy 366.758994 -265.986006) (xy 366.762954 -265.936952) (xy 366.774731 -265.889168)
			(xy 366.794022 -265.843892) (xy 366.820325 -265.802296) (xy 366.85296 -265.765459) (xy 366.891081 -265.734334)
			(xy 366.933702 -265.709727) (xy 366.979718 -265.692275) (xy 367.027937 -265.682431) (xy 367.077112 -265.68045)
			(xy 367.125967 -265.686382) (xy 367.173238 -265.700074) (xy 367.2177 -265.721172) (xy 367.258203 -265.749128)
			(xy 367.293696 -265.78322) (xy 367.323261 -265.822564) (xy 367.346132 -265.866141) (xy 367.361716 -265.912822)
			(xy 367.369611 -265.961399) (xy 367.370106 -265.986006) (xy 368.639102 -265.986006) (xy 368.643062 -265.936952)
			(xy 368.654839 -265.889168) (xy 368.67413 -265.843892) (xy 368.700433 -265.802296) (xy 368.733068 -265.765459)
			(xy 368.771189 -265.734334) (xy 368.81381 -265.709727) (xy 368.859826 -265.692275) (xy 368.908045 -265.682431)
			(xy 368.95722 -265.68045) (xy 369.006075 -265.686382) (xy 369.053346 -265.700074) (xy 369.097808 -265.721172)
			(xy 369.138311 -265.749128) (xy 369.173804 -265.78322) (xy 369.203369 -265.822564) (xy 369.22624 -265.866141)
			(xy 369.241824 -265.912822) (xy 369.249719 -265.961399) (xy 369.250214 -265.986006) (xy 370.518956 -265.986006)
			(xy 370.522916 -265.936952) (xy 370.534693 -265.889168) (xy 370.553984 -265.843892) (xy 370.580287 -265.802296)
			(xy 370.612922 -265.765459) (xy 370.651043 -265.734334) (xy 370.693664 -265.709727) (xy 370.73968 -265.692275)
			(xy 370.787899 -265.682431) (xy 370.837074 -265.68045) (xy 370.885929 -265.686382) (xy 370.9332 -265.700074)
			(xy 370.977662 -265.721172) (xy 371.018165 -265.749128) (xy 371.053658 -265.78322) (xy 371.083223 -265.822564)
			(xy 371.106094 -265.866141) (xy 371.121678 -265.912822) (xy 371.129573 -265.961399) (xy 371.130068 -265.986006)
			(xy 372.399064 -265.986006) (xy 372.403024 -265.936952) (xy 372.414801 -265.889168) (xy 372.434092 -265.843892)
			(xy 372.460395 -265.802296) (xy 372.49303 -265.765459) (xy 372.531151 -265.734334) (xy 372.573772 -265.709727)
			(xy 372.619788 -265.692275) (xy 372.668007 -265.682431) (xy 372.717182 -265.68045) (xy 372.766037 -265.686382)
			(xy 372.813308 -265.700074) (xy 372.85777 -265.721172) (xy 372.898273 -265.749128) (xy 372.933766 -265.78322)
			(xy 372.963331 -265.822564) (xy 372.986202 -265.866141) (xy 373.001786 -265.912822) (xy 373.009681 -265.961399)
			(xy 373.010176 -265.986006) (xy 374.278918 -265.986006) (xy 374.282878 -265.936952) (xy 374.294655 -265.889168)
			(xy 374.313946 -265.843892) (xy 374.340249 -265.802296) (xy 374.372884 -265.765459) (xy 374.411005 -265.734334)
			(xy 374.453626 -265.709727) (xy 374.499642 -265.692275) (xy 374.547861 -265.682431) (xy 374.597036 -265.68045)
			(xy 374.645891 -265.686382) (xy 374.693162 -265.700074) (xy 374.737624 -265.721172) (xy 374.778127 -265.749128)
			(xy 374.81362 -265.78322) (xy 374.843185 -265.822564) (xy 374.866056 -265.866141) (xy 374.88164 -265.912822)
			(xy 374.889535 -265.961399) (xy 374.89003 -265.986006) (xy 376.148595 -265.986006) (xy 376.15269 -265.935278)
			(xy 376.164869 -265.885864) (xy 376.184817 -265.839044) (xy 376.212018 -265.79603) (xy 376.245766 -265.757936)
			(xy 376.285188 -265.725749) (xy 376.329262 -265.700303) (xy 376.376848 -265.682256) (xy 376.426712 -265.672076)
			(xy 376.477564 -265.670027) (xy 376.528085 -265.676161) (xy 376.576969 -265.690321) (xy 376.622948 -265.712138)
			(xy 376.664832 -265.741048) (xy 376.701536 -265.776303) (xy 376.732109 -265.816989) (xy 376.75576 -265.862052)
			(xy 376.771876 -265.910326) (xy 376.78004 -265.96056) (xy 376.780552 -265.986006) (xy 377.09908 -265.986006)
			(xy 377.10304 -265.936952) (xy 377.114817 -265.889168) (xy 377.134108 -265.843892) (xy 377.160411 -265.802296)
			(xy 377.193046 -265.765459) (xy 377.231167 -265.734334) (xy 377.273788 -265.709727) (xy 377.319804 -265.692275)
			(xy 377.368023 -265.682431) (xy 377.417198 -265.68045) (xy 377.466053 -265.686382) (xy 377.513324 -265.700074)
			(xy 377.557786 -265.721172) (xy 377.598289 -265.749128) (xy 377.633782 -265.78322) (xy 377.663347 -265.822564)
			(xy 377.686218 -265.866141) (xy 377.701802 -265.912822) (xy 377.709697 -265.961399) (xy 377.710192 -265.986006)
			(xy 378.968503 -265.986006) (xy 378.972598 -265.935278) (xy 378.984777 -265.885864) (xy 379.004725 -265.839044)
			(xy 379.031926 -265.79603) (xy 379.065674 -265.757936) (xy 379.105096 -265.725749) (xy 379.14917 -265.700303)
			(xy 379.196756 -265.682256) (xy 379.24662 -265.672076) (xy 379.297472 -265.670027) (xy 379.347993 -265.676161)
			(xy 379.396877 -265.690321) (xy 379.442856 -265.712138) (xy 379.48474 -265.741048) (xy 379.521444 -265.776303)
			(xy 379.552017 -265.816989) (xy 379.575668 -265.862052) (xy 379.591784 -265.910326) (xy 379.599948 -265.96056)
			(xy 379.60046 -265.986006) (xy 379.918988 -265.986006) (xy 379.922948 -265.936952) (xy 379.934725 -265.889168)
			(xy 379.954016 -265.843892) (xy 379.980319 -265.802296) (xy 380.012954 -265.765459) (xy 380.051075 -265.734334)
			(xy 380.093696 -265.709727) (xy 380.139712 -265.692275) (xy 380.187931 -265.682431) (xy 380.237106 -265.68045)
			(xy 380.285961 -265.686382) (xy 380.333232 -265.700074) (xy 380.377694 -265.721172) (xy 380.418197 -265.749128)
			(xy 380.45369 -265.78322) (xy 380.483255 -265.822564) (xy 380.506126 -265.866141) (xy 380.52171 -265.912822)
			(xy 380.529605 -265.961399) (xy 380.5301 -265.986006) (xy 380.859042 -265.986006) (xy 380.863002 -265.936952)
			(xy 380.874779 -265.889168) (xy 380.89407 -265.843892) (xy 380.920373 -265.802296) (xy 380.953008 -265.765459)
			(xy 380.991129 -265.734334) (xy 381.03375 -265.709727) (xy 381.079766 -265.692275) (xy 381.127985 -265.682431)
			(xy 381.17716 -265.68045) (xy 381.226015 -265.686382) (xy 381.273286 -265.700074) (xy 381.317748 -265.721172)
			(xy 381.358251 -265.749128) (xy 381.393744 -265.78322) (xy 381.423309 -265.822564) (xy 381.44618 -265.866141)
			(xy 381.461764 -265.912822) (xy 381.469659 -265.961399) (xy 381.470154 -265.986006) (xy 381.469659 -266.010613)
			(xy 381.461764 -266.05919) (xy 381.44618 -266.105871) (xy 381.423309 -266.149448) (xy 381.393744 -266.188792)
			(xy 381.358251 -266.222884) (xy 381.317748 -266.25084) (xy 381.273286 -266.271938) (xy 381.226015 -266.28563)
			(xy 381.17716 -266.291562) (xy 381.127985 -266.289581) (xy 381.079766 -266.279737) (xy 381.03375 -266.262285)
			(xy 380.991129 -266.237678) (xy 380.953008 -266.206553) (xy 380.920373 -266.169716) (xy 380.89407 -266.12812)
			(xy 380.874779 -266.082844) (xy 380.863002 -266.03506) (xy 380.859042 -265.986006) (xy 380.5301 -265.986006)
			(xy 380.529605 -266.010613) (xy 380.52171 -266.05919) (xy 380.506126 -266.105871) (xy 380.483255 -266.149448)
			(xy 380.45369 -266.188792) (xy 380.418197 -266.222884) (xy 380.377694 -266.25084) (xy 380.333232 -266.271938)
			(xy 380.285961 -266.28563) (xy 380.237106 -266.291562) (xy 380.187931 -266.289581) (xy 380.139712 -266.279737)
			(xy 380.093696 -266.262285) (xy 380.051075 -266.237678) (xy 380.012954 -266.206553) (xy 379.980319 -266.169716)
			(xy 379.954016 -266.12812) (xy 379.934725 -266.082844) (xy 379.922948 -266.03506) (xy 379.918988 -265.986006)
			(xy 379.60046 -265.986006) (xy 379.599948 -266.011452) (xy 379.591784 -266.061686) (xy 379.575668 -266.10996)
			(xy 379.552017 -266.155023) (xy 379.521444 -266.195709) (xy 379.48474 -266.230964) (xy 379.442856 -266.259874)
			(xy 379.396877 -266.281691) (xy 379.347993 -266.295851) (xy 379.297472 -266.301985) (xy 379.24662 -266.299936)
			(xy 379.196756 -266.289756) (xy 379.14917 -266.271709) (xy 379.105096 -266.246263) (xy 379.065674 -266.214076)
			(xy 379.031926 -266.175982) (xy 379.004725 -266.132968) (xy 378.984777 -266.086148) (xy 378.972598 -266.036734)
			(xy 378.968503 -265.986006) (xy 377.710192 -265.986006) (xy 377.709697 -266.010613) (xy 377.701802 -266.05919)
			(xy 377.686218 -266.105871) (xy 377.663347 -266.149448) (xy 377.633782 -266.188792) (xy 377.598289 -266.222884)
			(xy 377.557786 -266.25084) (xy 377.513324 -266.271938) (xy 377.466053 -266.28563) (xy 377.417198 -266.291562)
			(xy 377.368023 -266.289581) (xy 377.319804 -266.279737) (xy 377.273788 -266.262285) (xy 377.231167 -266.237678)
			(xy 377.193046 -266.206553) (xy 377.160411 -266.169716) (xy 377.134108 -266.12812) (xy 377.114817 -266.082844)
			(xy 377.10304 -266.03506) (xy 377.09908 -265.986006) (xy 376.780552 -265.986006) (xy 376.78004 -266.011452)
			(xy 376.771876 -266.061686) (xy 376.75576 -266.10996) (xy 376.732109 -266.155023) (xy 376.701536 -266.195709)
			(xy 376.664832 -266.230964) (xy 376.622948 -266.259874) (xy 376.576969 -266.281691) (xy 376.528085 -266.295851)
			(xy 376.477564 -266.301985) (xy 376.426712 -266.299936) (xy 376.376848 -266.289756) (xy 376.329262 -266.271709)
			(xy 376.285188 -266.246263) (xy 376.245766 -266.214076) (xy 376.212018 -266.175982) (xy 376.184817 -266.132968)
			(xy 376.164869 -266.086148) (xy 376.15269 -266.036734) (xy 376.148595 -265.986006) (xy 374.89003 -265.986006)
			(xy 374.889535 -266.010613) (xy 374.88164 -266.05919) (xy 374.866056 -266.105871) (xy 374.843185 -266.149448)
			(xy 374.81362 -266.188792) (xy 374.778127 -266.222884) (xy 374.737624 -266.25084) (xy 374.693162 -266.271938)
			(xy 374.645891 -266.28563) (xy 374.597036 -266.291562) (xy 374.547861 -266.289581) (xy 374.499642 -266.279737)
			(xy 374.453626 -266.262285) (xy 374.411005 -266.237678) (xy 374.372884 -266.206553) (xy 374.340249 -266.169716)
			(xy 374.313946 -266.12812) (xy 374.294655 -266.082844) (xy 374.282878 -266.03506) (xy 374.278918 -265.986006)
			(xy 373.010176 -265.986006) (xy 373.009681 -266.010613) (xy 373.001786 -266.05919) (xy 372.986202 -266.105871)
			(xy 372.963331 -266.149448) (xy 372.933766 -266.188792) (xy 372.898273 -266.222884) (xy 372.85777 -266.25084)
			(xy 372.813308 -266.271938) (xy 372.766037 -266.28563) (xy 372.717182 -266.291562) (xy 372.668007 -266.289581)
			(xy 372.619788 -266.279737) (xy 372.573772 -266.262285) (xy 372.531151 -266.237678) (xy 372.49303 -266.206553)
			(xy 372.460395 -266.169716) (xy 372.434092 -266.12812) (xy 372.414801 -266.082844) (xy 372.403024 -266.03506)
			(xy 372.399064 -265.986006) (xy 371.130068 -265.986006) (xy 371.129573 -266.010613) (xy 371.121678 -266.05919)
			(xy 371.106094 -266.105871) (xy 371.083223 -266.149448) (xy 371.053658 -266.188792) (xy 371.018165 -266.222884)
			(xy 370.977662 -266.25084) (xy 370.9332 -266.271938) (xy 370.885929 -266.28563) (xy 370.837074 -266.291562)
			(xy 370.787899 -266.289581) (xy 370.73968 -266.279737) (xy 370.693664 -266.262285) (xy 370.651043 -266.237678)
			(xy 370.612922 -266.206553) (xy 370.580287 -266.169716) (xy 370.553984 -266.12812) (xy 370.534693 -266.082844)
			(xy 370.522916 -266.03506) (xy 370.518956 -265.986006) (xy 369.250214 -265.986006) (xy 369.249719 -266.010613)
			(xy 369.241824 -266.05919) (xy 369.22624 -266.105871) (xy 369.203369 -266.149448) (xy 369.173804 -266.188792)
			(xy 369.138311 -266.222884) (xy 369.097808 -266.25084) (xy 369.053346 -266.271938) (xy 369.006075 -266.28563)
			(xy 368.95722 -266.291562) (xy 368.908045 -266.289581) (xy 368.859826 -266.279737) (xy 368.81381 -266.262285)
			(xy 368.771189 -266.237678) (xy 368.733068 -266.206553) (xy 368.700433 -266.169716) (xy 368.67413 -266.12812)
			(xy 368.654839 -266.082844) (xy 368.643062 -266.03506) (xy 368.639102 -265.986006) (xy 367.370106 -265.986006)
			(xy 367.369611 -266.010613) (xy 367.361716 -266.05919) (xy 367.346132 -266.105871) (xy 367.323261 -266.149448)
			(xy 367.293696 -266.188792) (xy 367.258203 -266.222884) (xy 367.2177 -266.25084) (xy 367.173238 -266.271938)
			(xy 367.125967 -266.28563) (xy 367.077112 -266.291562) (xy 367.027937 -266.289581) (xy 366.979718 -266.279737)
			(xy 366.933702 -266.262285) (xy 366.891081 -266.237678) (xy 366.85296 -266.206553) (xy 366.820325 -266.169716)
			(xy 366.794022 -266.12812) (xy 366.774731 -266.082844) (xy 366.762954 -266.03506) (xy 366.758994 -265.986006)
			(xy 365.489998 -265.986006) (xy 365.489503 -266.010613) (xy 365.481608 -266.05919) (xy 365.466024 -266.105871)
			(xy 365.443153 -266.149448) (xy 365.413588 -266.188792) (xy 365.378095 -266.222884) (xy 365.337592 -266.25084)
			(xy 365.29313 -266.271938) (xy 365.245859 -266.28563) (xy 365.197004 -266.291562) (xy 365.147829 -266.289581)
			(xy 365.09961 -266.279737) (xy 365.053594 -266.262285) (xy 365.010973 -266.237678) (xy 364.972852 -266.206553)
			(xy 364.940217 -266.169716) (xy 364.913914 -266.12812) (xy 364.894623 -266.082844) (xy 364.882846 -266.03506)
			(xy 364.878886 -265.986006) (xy 363.610144 -265.986006) (xy 363.609649 -266.010613) (xy 363.601754 -266.05919)
			(xy 363.58617 -266.105871) (xy 363.563299 -266.149448) (xy 363.533734 -266.188792) (xy 363.498241 -266.222884)
			(xy 363.457738 -266.25084) (xy 363.413276 -266.271938) (xy 363.366005 -266.28563) (xy 363.31715 -266.291562)
			(xy 363.267975 -266.289581) (xy 363.219756 -266.279737) (xy 363.17374 -266.262285) (xy 363.131119 -266.237678)
			(xy 363.092998 -266.206553) (xy 363.060363 -266.169716) (xy 363.03406 -266.12812) (xy 363.014769 -266.082844)
			(xy 363.002992 -266.03506) (xy 362.999032 -265.986006) (xy 361.730036 -265.986006) (xy 361.729541 -266.010613)
			(xy 361.721646 -266.05919) (xy 361.706062 -266.105871) (xy 361.683191 -266.149448) (xy 361.653626 -266.188792)
			(xy 361.618133 -266.222884) (xy 361.57763 -266.25084) (xy 361.533168 -266.271938) (xy 361.485897 -266.28563)
			(xy 361.437042 -266.291562) (xy 361.387867 -266.289581) (xy 361.339648 -266.279737) (xy 361.293632 -266.262285)
			(xy 361.251011 -266.237678) (xy 361.21289 -266.206553) (xy 361.180255 -266.169716) (xy 361.153952 -266.12812)
			(xy 361.134661 -266.082844) (xy 361.122884 -266.03506) (xy 361.118924 -265.986006) (xy 357.976424 -265.986006)
			(xy 357.975929 -266.010613) (xy 357.968034 -266.05919) (xy 357.95245 -266.105871) (xy 357.929579 -266.149448)
			(xy 357.900014 -266.188792) (xy 357.864521 -266.222884) (xy 357.824018 -266.25084) (xy 357.779556 -266.271938)
			(xy 357.732285 -266.28563) (xy 357.68343 -266.291562) (xy 357.634255 -266.289581) (xy 357.586036 -266.279737)
			(xy 357.54002 -266.262285) (xy 357.497399 -266.237678) (xy 357.459278 -266.206553) (xy 357.426643 -266.169716)
			(xy 357.40034 -266.12812) (xy 357.381049 -266.082844) (xy 357.369272 -266.03506) (xy 357.365312 -265.986006)
			(xy 356.096316 -265.986006) (xy 356.095821 -266.010613) (xy 356.087926 -266.05919) (xy 356.072342 -266.105871)
			(xy 356.049471 -266.149448) (xy 356.019906 -266.188792) (xy 355.984413 -266.222884) (xy 355.94391 -266.25084)
			(xy 355.899448 -266.271938) (xy 355.852177 -266.28563) (xy 355.803322 -266.291562) (xy 355.754147 -266.289581)
			(xy 355.705928 -266.279737) (xy 355.659912 -266.262285) (xy 355.617291 -266.237678) (xy 355.57917 -266.206553)
			(xy 355.546535 -266.169716) (xy 355.520232 -266.12812) (xy 355.500941 -266.082844) (xy 355.489164 -266.03506)
			(xy 355.485204 -265.986006) (xy 354.216462 -265.986006) (xy 354.215967 -266.010613) (xy 354.208072 -266.05919)
			(xy 354.192488 -266.105871) (xy 354.169617 -266.149448) (xy 354.140052 -266.188792) (xy 354.104559 -266.222884)
			(xy 354.064056 -266.25084) (xy 354.019594 -266.271938) (xy 353.972323 -266.28563) (xy 353.923468 -266.291562)
			(xy 353.874293 -266.289581) (xy 353.826074 -266.279737) (xy 353.780058 -266.262285) (xy 353.737437 -266.237678)
			(xy 353.699316 -266.206553) (xy 353.666681 -266.169716) (xy 353.640378 -266.12812) (xy 353.621087 -266.082844)
			(xy 353.60931 -266.03506) (xy 353.60535 -265.986006) (xy 352.336354 -265.986006) (xy 352.335859 -266.010613)
			(xy 352.327964 -266.05919) (xy 352.31238 -266.105871) (xy 352.289509 -266.149448) (xy 352.259944 -266.188792)
			(xy 352.224451 -266.222884) (xy 352.183948 -266.25084) (xy 352.139486 -266.271938) (xy 352.092215 -266.28563)
			(xy 352.04336 -266.291562) (xy 351.994185 -266.289581) (xy 351.945966 -266.279737) (xy 351.89995 -266.262285)
			(xy 351.857329 -266.237678) (xy 351.819208 -266.206553) (xy 351.786573 -266.169716) (xy 351.76027 -266.12812)
			(xy 351.740979 -266.082844) (xy 351.729202 -266.03506) (xy 351.725242 -265.986006) (xy 350.4565 -265.986006)
			(xy 350.456005 -266.010613) (xy 350.44811 -266.05919) (xy 350.432526 -266.105871) (xy 350.409655 -266.149448)
			(xy 350.38009 -266.188792) (xy 350.344597 -266.222884) (xy 350.304094 -266.25084) (xy 350.259632 -266.271938)
			(xy 350.212361 -266.28563) (xy 350.163506 -266.291562) (xy 350.114331 -266.289581) (xy 350.066112 -266.279737)
			(xy 350.020096 -266.262285) (xy 349.977475 -266.237678) (xy 349.939354 -266.206553) (xy 349.906719 -266.169716)
			(xy 349.880416 -266.12812) (xy 349.861125 -266.082844) (xy 349.849348 -266.03506) (xy 349.845388 -265.986006)
			(xy 348.72168 -265.986006) (xy 348.72168 -266.421362) (xy 348.722072 -266.430886) (xy 348.728976 -266.448639)
			(xy 348.735142 -266.455906) (xy 348.761558 -266.484608) (xy 348.776798 -266.492736) (xy 348.785434 -266.494006)
			(xy 348.809324 -266.497979) (xy 348.855529 -266.512481) (xy 348.898867 -266.534093) (xy 348.938251 -266.562273)
			(xy 348.972695 -266.596314) (xy 349.001336 -266.635365) (xy 349.023455 -266.678446) (xy 349.038499 -266.724477)
			(xy 349.046091 -266.772306) (xy 349.046546 -266.79652) (xy 349.046546 -266.799314) (xy 349.045623 -266.827444)
			(xy 349.034758 -266.882659) (xy 349.024956 -266.909042) (xy 349.019114 -266.923266) (xy 349.02521 -266.95273)
			(xy 349.110554 -267.038074) (xy 349.111062 -267.038582) (xy 349.118445 -267.04516) (xy 349.136744 -267.052602)
			(xy 349.146622 -267.05306) (xy 349.304864 -267.05306) (xy 349.316307 -267.052537) (xy 349.336933 -267.042621)
			(xy 349.344488 -267.03401) (xy 349.346012 -267.032232) (xy 349.394018 -266.960604) (xy 349.400492 -266.949866)
			(xy 349.403171 -266.924963) (xy 349.399098 -266.913106) (xy 349.398844 -266.912852) (xy 349.398844 -266.912598)
			(xy 349.388129 -266.884779) (xy 349.376483 -266.826322) (xy 349.37573 -266.79652) (xy 349.37573 -266.796012)
			(xy 349.376252 -266.770757) (xy 349.384565 -266.720935) (xy 349.400966 -266.673161) (xy 349.425007 -266.628738)
			(xy 349.456031 -266.588878) (xy 349.493193 -266.554668) (xy 349.535479 -266.527042) (xy 349.581735 -266.506752)
			(xy 349.6307 -266.494352) (xy 349.681038 -266.490181) (xy 349.731376 -266.494352) (xy 349.780341 -266.506752)
			(xy 349.826597 -266.527042) (xy 349.868883 -266.554668) (xy 349.906045 -266.588878) (xy 349.937069 -266.628738)
			(xy 349.96111 -266.673161) (xy 349.977511 -266.720935) (xy 349.985824 -266.770757) (xy 349.986346 -266.796012)
			(xy 349.986346 -266.79652) (xy 349.985582 -266.826321) (xy 349.973942 -266.884778) (xy 349.963232 -266.912598)
			(xy 349.963232 -266.912852) (xy 349.962978 -266.91336) (xy 349.958947 -266.925164) (xy 349.961596 -266.949937)
			(xy 349.968058 -266.960604) (xy 350.014794 -267.030454) (xy 350.01581 -267.031978) (xy 350.023421 -267.041363)
			(xy 350.044895 -267.052368) (xy 350.056958 -267.05306) (xy 351.184972 -267.05306) (xy 351.196414 -267.052535)
			(xy 351.217038 -267.042617) (xy 351.224596 -267.03401) (xy 351.22612 -267.032232) (xy 351.274126 -266.960604)
			(xy 351.280599 -266.949866) (xy 351.283278 -266.924963) (xy 351.279206 -266.913106) (xy 351.278952 -266.912852)
			(xy 351.278952 -266.912598) (xy 351.268237 -266.884779) (xy 351.25659 -266.826322) (xy 351.255838 -266.79652)
			(xy 351.255838 -266.796012) (xy 351.25636 -266.770757) (xy 351.264673 -266.720935) (xy 351.281074 -266.673161)
			(xy 351.305115 -266.628738) (xy 351.336139 -266.588878) (xy 351.373301 -266.554668) (xy 351.415587 -266.527042)
			(xy 351.461843 -266.506752) (xy 351.510808 -266.494352) (xy 351.561146 -266.490181) (xy 351.611484 -266.494352)
			(xy 351.660449 -266.506752) (xy 351.706705 -266.527042) (xy 351.748991 -266.554668) (xy 351.786153 -266.588878)
			(xy 351.817177 -266.628738) (xy 351.841218 -266.673161) (xy 351.857619 -266.720935) (xy 351.865932 -266.770757)
			(xy 351.866454 -266.796012) (xy 351.866454 -266.79652) (xy 351.86569 -266.826321) (xy 351.85405 -266.884778)
			(xy 351.84334 -266.912598) (xy 351.84334 -266.912852) (xy 351.843086 -266.91336) (xy 351.839054 -266.925163)
			(xy 351.841704 -266.949937) (xy 351.848166 -266.960604) (xy 351.894902 -267.030454) (xy 351.895918 -267.031978)
			(xy 351.903529 -267.041362) (xy 351.925004 -267.052364) (xy 351.937066 -267.05306) (xy 352.125026 -267.05306)
			(xy 352.136473 -267.052544) (xy 352.157111 -267.042638) (xy 352.16465 -267.03401) (xy 352.166174 -267.032232)
			(xy 352.21418 -266.960604) (xy 352.220658 -266.949867) (xy 352.223339 -266.924962) (xy 352.21926 -266.913106)
			(xy 352.219006 -266.912852) (xy 352.219006 -266.912598) (xy 352.208293 -266.884778) (xy 352.196647 -266.826321)
			(xy 352.195892 -266.79652) (xy 352.195892 -266.796012) (xy 352.196414 -266.770757) (xy 352.204727 -266.720935)
			(xy 352.221128 -266.673161) (xy 352.245169 -266.628738) (xy 352.276193 -266.588878) (xy 352.313355 -266.554668)
			(xy 352.355641 -266.527042) (xy 352.401897 -266.506752) (xy 352.450862 -266.494352) (xy 352.5012 -266.490181)
			(xy 352.551538 -266.494352) (xy 352.600503 -266.506752) (xy 352.646759 -266.527042) (xy 352.689045 -266.554668)
			(xy 352.726207 -266.588878) (xy 352.757231 -266.628738) (xy 352.781272 -266.673161) (xy 352.797673 -266.720935)
			(xy 352.805986 -266.770757) (xy 352.806508 -266.796012) (xy 352.806508 -266.79652) (xy 352.805744 -266.826321)
			(xy 352.794102 -266.884777) (xy 352.783394 -266.912598) (xy 352.783394 -266.912852) (xy 352.78314 -266.91336)
			(xy 352.779111 -266.925164) (xy 352.781758 -266.949938) (xy 352.78822 -266.960604) (xy 352.834956 -267.030454)
			(xy 352.835972 -267.031978) (xy 352.843587 -267.041353) (xy 352.865062 -267.052332) (xy 352.87712 -267.05306)
			(xy 353.064826 -267.05306) (xy 353.076273 -267.052544) (xy 353.096911 -267.042638) (xy 353.10445 -267.03401)
			(xy 353.105974 -267.032232) (xy 353.15398 -266.960604) (xy 353.160458 -266.949867) (xy 353.163139 -266.924962)
			(xy 353.15906 -266.913106) (xy 353.158806 -266.912852) (xy 353.158806 -266.912598) (xy 353.148093 -266.884778)
			(xy 353.136447 -266.826321) (xy 353.135692 -266.79652) (xy 353.135692 -266.796012) (xy 353.136214 -266.770757)
			(xy 353.144527 -266.720935) (xy 353.160928 -266.673161) (xy 353.184969 -266.628738) (xy 353.215993 -266.588878)
			(xy 353.253155 -266.554668) (xy 353.295441 -266.527042) (xy 353.341697 -266.506752) (xy 353.390662 -266.494352)
			(xy 353.441 -266.490181) (xy 353.491338 -266.494352) (xy 353.540303 -266.506752) (xy 353.586559 -266.527042)
			(xy 353.628845 -266.554668) (xy 353.666007 -266.588878) (xy 353.697031 -266.628738) (xy 353.721072 -266.673161)
			(xy 353.737473 -266.720935) (xy 353.745786 -266.770757) (xy 353.746308 -266.796012) (xy 353.746308 -266.79652)
			(xy 353.745544 -266.826321) (xy 353.733902 -266.884777) (xy 353.723194 -266.912598) (xy 353.723194 -266.912852)
			(xy 353.72294 -266.91336) (xy 353.718911 -266.925164) (xy 353.721558 -266.949938) (xy 353.72802 -266.960604)
			(xy 353.774756 -267.030454) (xy 353.775772 -267.031978) (xy 353.783387 -267.041353) (xy 353.804862 -267.052332)
			(xy 353.81692 -267.05306) (xy 354.944934 -267.05306) (xy 354.95638 -267.052543) (xy 354.977016 -267.042634)
			(xy 354.984558 -267.03401) (xy 354.986082 -267.032232) (xy 355.034088 -266.960604) (xy 355.040565 -266.949867)
			(xy 355.043246 -266.924962) (xy 355.039168 -266.913106) (xy 355.038914 -266.912852) (xy 355.038914 -266.912598)
			(xy 355.0282 -266.884778) (xy 355.016555 -266.826322) (xy 355.0158 -266.79652) (xy 355.0158 -266.796012)
			(xy 355.016322 -266.770757) (xy 355.024635 -266.720935) (xy 355.041036 -266.673161) (xy 355.065077 -266.628738)
			(xy 355.096101 -266.588878) (xy 355.133263 -266.554668) (xy 355.175549 -266.527042) (xy 355.221805 -266.506752)
			(xy 355.27077 -266.494352) (xy 355.321108 -266.490181) (xy 355.371446 -266.494352) (xy 355.420411 -266.506752)
			(xy 355.466667 -266.527042) (xy 355.508953 -266.554668) (xy 355.546115 -266.588878) (xy 355.577139 -266.628738)
			(xy 355.60118 -266.673161) (xy 355.617581 -266.720935) (xy 355.625894 -266.770757) (xy 355.626416 -266.796012)
			(xy 355.626416 -266.79652) (xy 355.625652 -266.826321) (xy 355.614011 -266.884777) (xy 355.603302 -266.912598)
			(xy 355.603302 -266.912852) (xy 355.603048 -266.91336) (xy 355.599018 -266.925164) (xy 355.601666 -266.949937)
			(xy 355.608128 -266.960604) (xy 355.654864 -267.030454) (xy 355.65588 -267.031978) (xy 355.663489 -267.041368)
			(xy 355.684963 -267.052386) (xy 355.697028 -267.05306) (xy 355.884988 -267.05306) (xy 355.896405 -267.052428)
			(xy 355.91698 -267.042526) (xy 355.924612 -267.03401) (xy 355.926136 -267.032232) (xy 355.974142 -266.960604)
			(xy 355.980623 -266.949868) (xy 355.983306 -266.924961) (xy 355.979222 -266.913106) (xy 355.978968 -266.912852)
			(xy 355.978968 -266.912598) (xy 355.968256 -266.884778) (xy 355.956612 -266.826321) (xy 355.955854 -266.79652)
			(xy 355.955854 -266.796012) (xy 355.956376 -266.770757) (xy 355.964689 -266.720935) (xy 355.98109 -266.673161)
			(xy 356.005131 -266.628738) (xy 356.036155 -266.588878) (xy 356.073317 -266.554668) (xy 356.115603 -266.527042)
			(xy 356.161859 -266.506752) (xy 356.210824 -266.494352) (xy 356.261162 -266.490181) (xy 356.3115 -266.494352)
			(xy 356.360465 -266.506752) (xy 356.406721 -266.527042) (xy 356.449007 -266.554668) (xy 356.486169 -266.588878)
			(xy 356.517193 -266.628738) (xy 356.541234 -266.673161) (xy 356.557635 -266.720935) (xy 356.565948 -266.770757)
			(xy 356.56647 -266.796012) (xy 356.56647 -266.79652) (xy 356.565706 -266.826321) (xy 356.554063 -266.884777)
			(xy 356.543356 -266.912598) (xy 356.543356 -266.912852) (xy 356.543102 -266.91336) (xy 356.53907 -266.925163)
			(xy 356.54172 -266.949937) (xy 356.548182 -266.960604) (xy 356.594918 -267.030454) (xy 356.595934 -267.031978)
			(xy 356.603546 -267.041359) (xy 356.625021 -267.052355) (xy 356.637082 -267.05306) (xy 356.825042 -267.05306)
			(xy 356.836487 -267.052541) (xy 356.85712 -267.042631) (xy 356.864666 -267.03401) (xy 356.86619 -267.032232)
			(xy 356.914196 -266.960604) (xy 356.920672 -266.949866) (xy 356.923352 -266.924963) (xy 356.919276 -266.913106)
			(xy 356.919022 -266.912852) (xy 356.919022 -266.912598) (xy 356.908308 -266.884778) (xy 356.896662 -266.826322)
			(xy 356.895908 -266.79652) (xy 356.895908 -266.796012) (xy 356.89643 -266.770757) (xy 356.904743 -266.720935)
			(xy 356.921144 -266.673161) (xy 356.945185 -266.628738) (xy 356.976209 -266.588878) (xy 357.013371 -266.554668)
			(xy 357.055657 -266.527042) (xy 357.101913 -266.506752) (xy 357.150878 -266.494352) (xy 357.201216 -266.490181)
			(xy 357.251554 -266.494352) (xy 357.300519 -266.506752) (xy 357.346775 -266.527042) (xy 357.389061 -266.554668)
			(xy 357.426223 -266.588878) (xy 357.457247 -266.628738) (xy 357.481288 -266.673161) (xy 357.497689 -266.720935)
			(xy 357.506002 -266.770757) (xy 357.506524 -266.796012) (xy 357.506524 -266.79652) (xy 357.50576 -266.826321)
			(xy 357.494119 -266.884777) (xy 357.48341 -266.912598) (xy 357.48341 -266.912852) (xy 357.483156 -266.91336)
			(xy 357.479126 -266.925164) (xy 357.481775 -266.949937) (xy 357.488236 -266.960604) (xy 357.534972 -267.030454)
			(xy 357.535988 -267.031978) (xy 357.543597 -267.041367) (xy 357.565071 -267.052381) (xy 357.577136 -267.05306)
			(xy 359.610406 -267.05306) (xy 359.619305 -267.052622) (xy 359.636001 -267.046444) (xy 359.649584 -267.034936)
			(xy 359.654348 -267.027406) (xy 359.658158 -267.020802) (xy 359.659936 -267.01369) (xy 359.666185 -266.988823)
			(xy 359.685054 -266.94115) (xy 359.7108 -266.896813) (xy 359.742853 -266.856796) (xy 359.780498 -266.821988)
			(xy 359.8229 -266.793164) (xy 359.869116 -266.770965) (xy 359.918118 -266.755883) (xy 359.968819 -266.748254)
			(xy 359.994454 -266.747752) (xy 360.021541 -266.748265) (xy 360.075044 -266.756773) (xy 360.126549 -266.773571)
			(xy 360.174781 -266.798243) (xy 360.218544 -266.830176) (xy 360.256754 -266.86858) (xy 360.288466 -266.912504)
			(xy 360.312893 -266.96086) (xy 360.321606 -266.986512) (xy 360.32567 -266.999466) (xy 360.32694 -267.003784)
			(xy 360.328972 -267.013182) (xy 360.329935 -267.017254) (xy 360.333004 -267.025036) (xy 360.335068 -267.028676)
			(xy 360.339886 -267.035934) (xy 360.353388 -267.046923) (xy 360.369797 -267.052737) (xy 360.378502 -267.05306)
			(xy 361.518708 -267.05306) (xy 361.530123 -267.052424) (xy 361.550692 -267.042517) (xy 361.558332 -267.03401)
			(xy 361.559856 -267.032232) (xy 361.607862 -266.960604) (xy 361.614341 -266.949867) (xy 361.617023 -266.924962)
			(xy 361.612942 -266.913106) (xy 361.612688 -266.912852) (xy 361.612688 -266.912598) (xy 361.601975 -266.884778)
			(xy 361.590331 -266.826321) (xy 361.589574 -266.79652) (xy 361.589574 -266.796012) (xy 361.590096 -266.770757)
			(xy 361.598409 -266.720935) (xy 361.61481 -266.673161) (xy 361.638851 -266.628738) (xy 361.669875 -266.588878)
			(xy 361.707037 -266.554668) (xy 361.749323 -266.527042) (xy 361.795579 -266.506752) (xy 361.844544 -266.494352)
			(xy 361.894882 -266.490181) (xy 361.94522 -266.494352) (xy 361.994185 -266.506752) (xy 362.040441 -266.527042)
			(xy 362.082727 -266.554668) (xy 362.119889 -266.588878) (xy 362.150913 -266.628738) (xy 362.174954 -266.673161)
			(xy 362.191355 -266.720935) (xy 362.199668 -266.770757) (xy 362.20019 -266.796012) (xy 362.20019 -266.79652)
			(xy 362.199426 -266.826321) (xy 362.187784 -266.884777) (xy 362.177076 -266.912598) (xy 362.177076 -266.912852)
			(xy 362.176822 -266.91336) (xy 362.172789 -266.925163) (xy 362.175441 -266.949937) (xy 362.181902 -266.960604)
			(xy 362.228638 -267.030454) (xy 362.229654 -267.031978) (xy 362.237268 -267.041356) (xy 362.258742 -267.052343)
			(xy 362.270802 -267.05306) (xy 362.458508 -267.05306) (xy 362.469923 -267.052424) (xy 362.490492 -267.042517)
			(xy 362.498132 -267.03401) (xy 362.499656 -267.032232) (xy 362.547662 -266.960604) (xy 362.554141 -266.949867)
			(xy 362.556823 -266.924962) (xy 362.552742 -266.913106) (xy 362.552488 -266.912852) (xy 362.552488 -266.912598)
			(xy 362.541775 -266.884778) (xy 362.530131 -266.826321) (xy 362.529374 -266.79652) (xy 362.529374 -266.796012)
			(xy 362.529896 -266.770757) (xy 362.538209 -266.720935) (xy 362.55461 -266.673161) (xy 362.578651 -266.628738)
			(xy 362.609675 -266.588878) (xy 362.646837 -266.554668) (xy 362.689123 -266.527042) (xy 362.735379 -266.506752)
			(xy 362.784344 -266.494352) (xy 362.834682 -266.490181) (xy 362.88502 -266.494352) (xy 362.933985 -266.506752)
			(xy 362.980241 -266.527042) (xy 363.022527 -266.554668) (xy 363.059689 -266.588878) (xy 363.090713 -266.628738)
			(xy 363.114754 -266.673161) (xy 363.131155 -266.720935) (xy 363.139468 -266.770757) (xy 363.13999 -266.796012)
			(xy 363.13999 -266.79652) (xy 363.139226 -266.826321) (xy 363.127584 -266.884777) (xy 363.116876 -266.912598)
			(xy 363.116876 -266.912852) (xy 363.116622 -266.91336) (xy 363.112589 -266.925163) (xy 363.115241 -266.949937)
			(xy 363.121702 -266.960604) (xy 363.168438 -267.030454) (xy 363.169454 -267.031978) (xy 363.177068 -267.041356)
			(xy 363.198542 -267.052343) (xy 363.210602 -267.05306) (xy 363.398562 -267.05306) (xy 363.410005 -267.052537)
			(xy 363.430632 -267.042622) (xy 363.438186 -267.03401) (xy 363.43971 -267.032232) (xy 363.487716 -266.960604)
			(xy 363.49419 -266.949866) (xy 363.49687 -266.924963) (xy 363.492796 -266.913106) (xy 363.492542 -266.912852)
			(xy 363.492542 -266.912598) (xy 363.481827 -266.884779) (xy 363.470181 -266.826322) (xy 363.469428 -266.79652)
			(xy 363.469428 -266.796012) (xy 363.46995 -266.770757) (xy 363.478263 -266.720935) (xy 363.494664 -266.673161)
			(xy 363.518705 -266.628738) (xy 363.549729 -266.588878) (xy 363.586891 -266.554668) (xy 363.629177 -266.527042)
			(xy 363.675433 -266.506752) (xy 363.724398 -266.494352) (xy 363.774736 -266.490181) (xy 363.825074 -266.494352)
			(xy 363.874039 -266.506752) (xy 363.920295 -266.527042) (xy 363.962581 -266.554668) (xy 363.999743 -266.588878)
			(xy 364.030767 -266.628738) (xy 364.054808 -266.673161) (xy 364.071209 -266.720935) (xy 364.079522 -266.770757)
			(xy 364.080044 -266.796012) (xy 364.080044 -266.79652) (xy 364.07928 -266.826321) (xy 364.06764 -266.884778)
			(xy 364.05693 -266.912598) (xy 364.05693 -266.912852) (xy 364.056676 -266.91336) (xy 364.052645 -266.925164)
			(xy 364.055294 -266.949937) (xy 364.061756 -266.960604) (xy 364.108492 -267.030454) (xy 364.109508 -267.031978)
			(xy 364.117119 -267.041363) (xy 364.138593 -267.052369) (xy 364.150656 -267.05306) (xy 365.27867 -267.05306)
			(xy 365.290113 -267.052535) (xy 365.310736 -267.042618) (xy 365.318294 -267.03401) (xy 365.319818 -267.032232)
			(xy 365.367824 -266.960604) (xy 365.374298 -266.949866) (xy 365.376976 -266.924963) (xy 365.372904 -266.913106)
			(xy 365.37265 -266.912852) (xy 365.37265 -266.912598) (xy 365.361935 -266.884779) (xy 365.350288 -266.826322)
			(xy 365.349536 -266.79652) (xy 365.349536 -266.796012) (xy 365.350058 -266.770757) (xy 365.358371 -266.720935)
			(xy 365.374772 -266.673161) (xy 365.398813 -266.628738) (xy 365.429837 -266.588878) (xy 365.466999 -266.554668)
			(xy 365.509285 -266.527042) (xy 365.555541 -266.506752) (xy 365.604506 -266.494352) (xy 365.654844 -266.490181)
			(xy 365.705182 -266.494352) (xy 365.754147 -266.506752) (xy 365.800403 -266.527042) (xy 365.842689 -266.554668)
			(xy 365.879851 -266.588878) (xy 365.910875 -266.628738) (xy 365.934916 -266.673161) (xy 365.951317 -266.720935)
			(xy 365.95963 -266.770757) (xy 365.960152 -266.796012) (xy 365.960152 -266.79652) (xy 365.959388 -266.826321)
			(xy 365.947748 -266.884778) (xy 365.937038 -266.912598) (xy 365.937038 -266.912852) (xy 365.936784 -266.91336)
			(xy 365.932753 -266.925163) (xy 365.935402 -266.949937) (xy 365.941864 -266.960604) (xy 365.9886 -267.030454)
			(xy 365.989616 -267.031978) (xy 365.997227 -267.041362) (xy 366.018701 -267.052365) (xy 366.030764 -267.05306)
			(xy 366.218724 -267.05306) (xy 366.230171 -267.052545) (xy 366.25081 -267.042639) (xy 366.258348 -267.03401)
			(xy 366.259872 -267.032232) (xy 366.307878 -266.960604) (xy 366.314356 -266.949867) (xy 366.317037 -266.924962)
			(xy 366.312958 -266.913106) (xy 366.312704 -266.912852) (xy 366.312704 -266.912598) (xy 366.301991 -266.884778)
			(xy 366.290345 -266.826321) (xy 366.28959 -266.79652) (xy 366.28959 -266.796012) (xy 366.290112 -266.770757)
			(xy 366.298425 -266.720935) (xy 366.314826 -266.673161) (xy 366.338867 -266.628738) (xy 366.369891 -266.588878)
			(xy 366.407053 -266.554668) (xy 366.449339 -266.527042) (xy 366.495595 -266.506752) (xy 366.54456 -266.494352)
			(xy 366.594898 -266.490181) (xy 366.645236 -266.494352) (xy 366.694201 -266.506752) (xy 366.740457 -266.527042)
			(xy 366.782743 -266.554668) (xy 366.819905 -266.588878) (xy 366.850929 -266.628738) (xy 366.87497 -266.673161)
			(xy 366.891371 -266.720935) (xy 366.899684 -266.770757) (xy 366.900206 -266.796012) (xy 366.900206 -266.79652)
			(xy 366.899442 -266.826321) (xy 366.8878 -266.884777) (xy 366.877092 -266.912598) (xy 366.877092 -266.912852)
			(xy 366.876838 -266.91336) (xy 366.872809 -266.925164) (xy 366.875456 -266.949938) (xy 366.881918 -266.960604)
			(xy 366.928654 -267.030454) (xy 366.92967 -267.031978) (xy 366.937285 -267.041353) (xy 366.95876 -267.052333)
			(xy 366.970818 -267.05306) (xy 367.158524 -267.05306) (xy 367.169971 -267.052545) (xy 367.19061 -267.042639)
			(xy 367.198148 -267.03401) (xy 367.199672 -267.032232) (xy 367.247678 -266.960604) (xy 367.254156 -266.949867)
			(xy 367.256837 -266.924962) (xy 367.252758 -266.913106) (xy 367.252504 -266.912852) (xy 367.252504 -266.912598)
			(xy 367.241791 -266.884778) (xy 367.230145 -266.826321) (xy 367.22939 -266.79652) (xy 367.22939 -266.796012)
			(xy 367.229912 -266.770757) (xy 367.238225 -266.720935) (xy 367.254626 -266.673161) (xy 367.278667 -266.628738)
			(xy 367.309691 -266.588878) (xy 367.346853 -266.554668) (xy 367.389139 -266.527042) (xy 367.435395 -266.506752)
			(xy 367.48436 -266.494352) (xy 367.534698 -266.490181) (xy 367.585036 -266.494352) (xy 367.634001 -266.506752)
			(xy 367.680257 -266.527042) (xy 367.722543 -266.554668) (xy 367.759705 -266.588878) (xy 367.790729 -266.628738)
			(xy 367.81477 -266.673161) (xy 367.831171 -266.720935) (xy 367.839484 -266.770757) (xy 367.840006 -266.796012)
			(xy 367.840006 -266.79652) (xy 367.839242 -266.826321) (xy 367.8276 -266.884777) (xy 367.816892 -266.912598)
			(xy 367.816892 -266.912852) (xy 367.816638 -266.91336) (xy 367.812609 -266.925164) (xy 367.815256 -266.949938)
			(xy 367.821718 -266.960604) (xy 367.868454 -267.030454) (xy 367.86947 -267.031978) (xy 367.877085 -267.041353)
			(xy 367.89856 -267.052333) (xy 367.910618 -267.05306) (xy 369.038632 -267.05306) (xy 369.050079 -267.052543)
			(xy 369.070715 -267.042635) (xy 369.078256 -267.03401) (xy 369.07978 -267.032232) (xy 369.127786 -266.960604)
			(xy 369.134263 -266.949867) (xy 369.136944 -266.924962) (xy 369.132866 -266.913106) (xy 369.132612 -266.912852)
			(xy 369.132612 -266.912598) (xy 369.121898 -266.884778) (xy 369.110253 -266.826322) (xy 369.109498 -266.79652)
			(xy 369.109498 -266.796012) (xy 369.11002 -266.770757) (xy 369.118333 -266.720935) (xy 369.134734 -266.673161)
			(xy 369.158775 -266.628738) (xy 369.189799 -266.588878) (xy 369.226961 -266.554668) (xy 369.269247 -266.527042)
			(xy 369.315503 -266.506752) (xy 369.364468 -266.494352) (xy 369.414806 -266.490181) (xy 369.465144 -266.494352)
			(xy 369.514109 -266.506752) (xy 369.560365 -266.527042) (xy 369.602651 -266.554668) (xy 369.639813 -266.588878)
			(xy 369.670837 -266.628738) (xy 369.694878 -266.673161) (xy 369.711279 -266.720935) (xy 369.719592 -266.770757)
			(xy 369.720114 -266.796012) (xy 369.720114 -266.79652) (xy 369.71935 -266.826321) (xy 369.707709 -266.884777)
			(xy 369.697 -266.912598) (xy 369.697 -266.912852) (xy 369.696746 -266.91336) (xy 369.692716 -266.925164)
			(xy 369.695364 -266.949937) (xy 369.701826 -266.960604) (xy 369.748562 -267.030454) (xy 369.749578 -267.031978)
			(xy 369.757187 -267.041368) (xy 369.77866 -267.052387) (xy 369.790726 -267.05306) (xy 369.978686 -267.05306)
			(xy 369.990103 -267.052428) (xy 370.010679 -267.042527) (xy 370.01831 -267.03401) (xy 370.019834 -267.032232)
			(xy 370.06784 -266.960604) (xy 370.074321 -266.949868) (xy 370.077004 -266.924961) (xy 370.07292 -266.913106)
			(xy 370.072666 -266.912852) (xy 370.072666 -266.912598) (xy 370.061954 -266.884778) (xy 370.05031 -266.826321)
			(xy 370.049552 -266.79652) (xy 370.049552 -266.796012) (xy 370.050074 -266.770757) (xy 370.058387 -266.720935)
			(xy 370.074788 -266.673161) (xy 370.098829 -266.628738) (xy 370.129853 -266.588878) (xy 370.167015 -266.554668)
			(xy 370.209301 -266.527042) (xy 370.255557 -266.506752) (xy 370.304522 -266.494352) (xy 370.35486 -266.490181)
			(xy 370.405198 -266.494352) (xy 370.454163 -266.506752) (xy 370.500419 -266.527042) (xy 370.542705 -266.554668)
			(xy 370.579867 -266.588878) (xy 370.610891 -266.628738) (xy 370.634932 -266.673161) (xy 370.651333 -266.720935)
			(xy 370.659646 -266.770757) (xy 370.660168 -266.796012) (xy 370.660168 -266.79652) (xy 370.659404 -266.826321)
			(xy 370.647761 -266.884776) (xy 370.637054 -266.912598) (xy 370.637054 -266.912852) (xy 370.6368 -266.91336)
			(xy 370.632768 -266.925163) (xy 370.635418 -266.949937) (xy 370.64188 -266.960604) (xy 370.688616 -267.030454)
			(xy 370.689632 -267.031978) (xy 370.697244 -267.041359) (xy 370.718719 -267.052356) (xy 370.73078 -267.05306)
			(xy 370.91874 -267.05306) (xy 370.930186 -267.052542) (xy 370.950819 -267.042632) (xy 370.958364 -267.03401)
			(xy 370.959888 -267.032232) (xy 371.007894 -266.960604) (xy 371.01437 -266.949866) (xy 371.017051 -266.924962)
			(xy 371.012974 -266.913106) (xy 371.01272 -266.912852) (xy 371.01272 -266.912598) (xy 371.002006 -266.884778)
			(xy 370.99036 -266.826322) (xy 370.989606 -266.79652) (xy 370.989606 -266.796012) (xy 370.990128 -266.770757)
			(xy 370.998441 -266.720935) (xy 371.014842 -266.673161) (xy 371.038883 -266.628738) (xy 371.069907 -266.588878)
			(xy 371.107069 -266.554668) (xy 371.149355 -266.527042) (xy 371.195611 -266.506752) (xy 371.244576 -266.494352)
			(xy 371.294914 -266.490181) (xy 371.345252 -266.494352) (xy 371.394217 -266.506752) (xy 371.440473 -266.527042)
			(xy 371.482759 -266.554668) (xy 371.519921 -266.588878) (xy 371.550945 -266.628738) (xy 371.574986 -266.673161)
			(xy 371.591387 -266.720935) (xy 371.5997 -266.770757) (xy 371.600222 -266.796012) (xy 371.600222 -266.79652)
			(xy 371.599458 -266.826321) (xy 371.587817 -266.884777) (xy 371.577108 -266.912598) (xy 371.577108 -266.912852)
			(xy 371.576854 -266.91336) (xy 371.572824 -266.925164) (xy 371.575472 -266.949937) (xy 371.581934 -266.960604)
			(xy 371.62867 -267.030454) (xy 371.629686 -267.031978) (xy 371.637295 -267.041367) (xy 371.658769 -267.052383)
			(xy 371.670834 -267.05306) (xy 372.798594 -267.05306) (xy 372.81001 -267.052427) (xy 372.830584 -267.042524)
			(xy 372.838218 -267.03401) (xy 372.839742 -267.032232) (xy 372.887748 -266.960604) (xy 372.894229 -266.949868)
			(xy 372.896911 -266.924961) (xy 372.892828 -266.913106) (xy 372.892574 -266.912852) (xy 372.892574 -266.912598)
			(xy 372.881862 -266.884778) (xy 372.870218 -266.826321) (xy 372.86946 -266.79652) (xy 372.86946 -266.796012)
			(xy 372.869982 -266.770757) (xy 372.878295 -266.720935) (xy 372.894696 -266.673161) (xy 372.918737 -266.628738)
			(xy 372.949761 -266.588878) (xy 372.986923 -266.554668) (xy 373.029209 -266.527042) (xy 373.075465 -266.506752)
			(xy 373.12443 -266.494352) (xy 373.174768 -266.490181) (xy 373.225106 -266.494352) (xy 373.274071 -266.506752)
			(xy 373.320327 -266.527042) (xy 373.362613 -266.554668) (xy 373.399775 -266.588878) (xy 373.430799 -266.628738)
			(xy 373.45484 -266.673161) (xy 373.471241 -266.720935) (xy 373.479554 -266.770757) (xy 373.480076 -266.796012)
			(xy 373.480076 -266.79652) (xy 373.479312 -266.826321) (xy 373.467669 -266.884777) (xy 373.456962 -266.912598)
			(xy 373.456962 -266.912852) (xy 373.456708 -266.91336) (xy 373.452676 -266.925163) (xy 373.455326 -266.949937)
			(xy 373.461788 -266.960604) (xy 373.508524 -267.030454) (xy 373.50954 -267.031978) (xy 373.517153 -267.041358)
			(xy 373.538627 -267.052351) (xy 373.550688 -267.05306) (xy 373.738648 -267.05306) (xy 373.750093 -267.05254)
			(xy 373.770724 -267.042628) (xy 373.778272 -267.03401) (xy 373.779796 -267.032232) (xy 373.827802 -266.960604)
			(xy 373.834278 -266.949866) (xy 373.836957 -266.924963) (xy 373.832882 -266.913106) (xy 373.832628 -266.912852)
			(xy 373.832628 -266.912598) (xy 373.821914 -266.884778) (xy 373.810268 -266.826322) (xy 373.809514 -266.79652)
			(xy 373.809514 -266.796012) (xy 373.810036 -266.770757) (xy 373.818349 -266.720935) (xy 373.83475 -266.673161)
			(xy 373.858791 -266.628738) (xy 373.889815 -266.588878) (xy 373.926977 -266.554668) (xy 373.969263 -266.527042)
			(xy 374.015519 -266.506752) (xy 374.064484 -266.494352) (xy 374.114822 -266.490181) (xy 374.16516 -266.494352)
			(xy 374.214125 -266.506752) (xy 374.260381 -266.527042) (xy 374.302667 -266.554668) (xy 374.339829 -266.588878)
			(xy 374.370853 -266.628738) (xy 374.394894 -266.673161) (xy 374.411295 -266.720935) (xy 374.419608 -266.770757)
			(xy 374.42013 -266.796012) (xy 374.749072 -266.796012) (xy 374.753032 -266.746958) (xy 374.764809 -266.699174)
			(xy 374.7841 -266.653898) (xy 374.810403 -266.612302) (xy 374.843038 -266.575465) (xy 374.881159 -266.54434)
			(xy 374.92378 -266.519733) (xy 374.969796 -266.502281) (xy 375.018015 -266.492437) (xy 375.06719 -266.490456)
			(xy 375.116045 -266.496388) (xy 375.163316 -266.51008) (xy 375.207778 -266.531178) (xy 375.248281 -266.559134)
			(xy 375.283774 -266.593226) (xy 375.313339 -266.63257) (xy 375.33621 -266.676147) (xy 375.351794 -266.722828)
			(xy 375.359689 -266.771405) (xy 375.360184 -266.796012) (xy 375.678695 -266.796012) (xy 375.68279 -266.745284)
			(xy 375.694969 -266.69587) (xy 375.714917 -266.64905) (xy 375.742118 -266.606036) (xy 375.775866 -266.567942)
			(xy 375.815288 -266.535755) (xy 375.859362 -266.510309) (xy 375.906948 -266.492262) (xy 375.956812 -266.482082)
			(xy 376.007664 -266.480033) (xy 376.058185 -266.486167) (xy 376.107069 -266.500327) (xy 376.153048 -266.522144)
			(xy 376.194932 -266.551054) (xy 376.231636 -266.586309) (xy 376.262209 -266.626995) (xy 376.28586 -266.672058)
			(xy 376.301976 -266.720332) (xy 376.31014 -266.770566) (xy 376.310652 -266.796012) (xy 376.628926 -266.796012)
			(xy 376.632886 -266.746958) (xy 376.644663 -266.699174) (xy 376.663954 -266.653898) (xy 376.690257 -266.612302)
			(xy 376.722892 -266.575465) (xy 376.761013 -266.54434) (xy 376.803634 -266.519733) (xy 376.84965 -266.502281)
			(xy 376.897869 -266.492437) (xy 376.947044 -266.490456) (xy 376.995899 -266.496388) (xy 377.04317 -266.51008)
			(xy 377.087632 -266.531178) (xy 377.128135 -266.559134) (xy 377.163628 -266.593226) (xy 377.193193 -266.63257)
			(xy 377.216064 -266.676147) (xy 377.231648 -266.722828) (xy 377.239543 -266.771405) (xy 377.240038 -266.796012)
			(xy 377.558549 -266.796012) (xy 377.562644 -266.745284) (xy 377.574823 -266.69587) (xy 377.594771 -266.64905)
			(xy 377.621972 -266.606036) (xy 377.65572 -266.567942) (xy 377.695142 -266.535755) (xy 377.739216 -266.510309)
			(xy 377.786802 -266.492262) (xy 377.836666 -266.482082) (xy 377.887518 -266.480033) (xy 377.938039 -266.486167)
			(xy 377.986923 -266.500327) (xy 378.032902 -266.522144) (xy 378.074786 -266.551054) (xy 378.11149 -266.586309)
			(xy 378.142063 -266.626995) (xy 378.165714 -266.672058) (xy 378.18183 -266.720332) (xy 378.189994 -266.770566)
			(xy 378.190506 -266.796012) (xy 378.509034 -266.796012) (xy 378.512994 -266.746958) (xy 378.524771 -266.699174)
			(xy 378.544062 -266.653898) (xy 378.570365 -266.612302) (xy 378.603 -266.575465) (xy 378.641121 -266.54434)
			(xy 378.683742 -266.519733) (xy 378.729758 -266.502281) (xy 378.777977 -266.492437) (xy 378.827152 -266.490456)
			(xy 378.876007 -266.496388) (xy 378.923278 -266.51008) (xy 378.96774 -266.531178) (xy 379.008243 -266.559134)
			(xy 379.043736 -266.593226) (xy 379.073301 -266.63257) (xy 379.096172 -266.676147) (xy 379.111756 -266.722828)
			(xy 379.119651 -266.771405) (xy 379.120146 -266.796012) (xy 379.438657 -266.796012) (xy 379.442752 -266.745284)
			(xy 379.454931 -266.69587) (xy 379.474879 -266.64905) (xy 379.50208 -266.606036) (xy 379.535828 -266.567942)
			(xy 379.57525 -266.535755) (xy 379.619324 -266.510309) (xy 379.66691 -266.492262) (xy 379.716774 -266.482082)
			(xy 379.767626 -266.480033) (xy 379.818147 -266.486167) (xy 379.867031 -266.500327) (xy 379.91301 -266.522144)
			(xy 379.954894 -266.551054) (xy 379.991598 -266.586309) (xy 380.022171 -266.626995) (xy 380.045822 -266.672058)
			(xy 380.061938 -266.720332) (xy 380.070102 -266.770566) (xy 380.070614 -266.796012) (xy 380.378711 -266.796012)
			(xy 380.382806 -266.745284) (xy 380.394985 -266.69587) (xy 380.414933 -266.64905) (xy 380.442134 -266.606036)
			(xy 380.475882 -266.567942) (xy 380.515304 -266.535755) (xy 380.559378 -266.510309) (xy 380.606964 -266.492262)
			(xy 380.656828 -266.482082) (xy 380.70768 -266.480033) (xy 380.758201 -266.486167) (xy 380.807085 -266.500327)
			(xy 380.853064 -266.522144) (xy 380.894948 -266.551054) (xy 380.931652 -266.586309) (xy 380.962225 -266.626995)
			(xy 380.985876 -266.672058) (xy 381.001992 -266.720332) (xy 381.010156 -266.770566) (xy 381.010668 -266.796012)
			(xy 381.010156 -266.821458) (xy 381.001992 -266.871692) (xy 380.985876 -266.919966) (xy 380.962225 -266.965029)
			(xy 380.931652 -267.005715) (xy 380.894948 -267.04097) (xy 380.853064 -267.06988) (xy 380.807085 -267.091697)
			(xy 380.758201 -267.105857) (xy 380.70768 -267.111991) (xy 380.656828 -267.109942) (xy 380.606964 -267.099762)
			(xy 380.559378 -267.081715) (xy 380.515304 -267.056269) (xy 380.475882 -267.024082) (xy 380.442134 -266.985988)
			(xy 380.414933 -266.942974) (xy 380.394985 -266.896154) (xy 380.382806 -266.84674) (xy 380.378711 -266.796012)
			(xy 380.070614 -266.796012) (xy 380.070102 -266.821458) (xy 380.061938 -266.871692) (xy 380.045822 -266.919966)
			(xy 380.022171 -266.965029) (xy 379.991598 -267.005715) (xy 379.954894 -267.04097) (xy 379.91301 -267.06988)
			(xy 379.867031 -267.091697) (xy 379.818147 -267.105857) (xy 379.767626 -267.111991) (xy 379.716774 -267.109942)
			(xy 379.66691 -267.099762) (xy 379.619324 -267.081715) (xy 379.57525 -267.056269) (xy 379.535828 -267.024082)
			(xy 379.50208 -266.985988) (xy 379.474879 -266.942974) (xy 379.454931 -266.896154) (xy 379.442752 -266.84674)
			(xy 379.438657 -266.796012) (xy 379.120146 -266.796012) (xy 379.119651 -266.820619) (xy 379.111756 -266.869196)
			(xy 379.096172 -266.915877) (xy 379.073301 -266.959454) (xy 379.043736 -266.998798) (xy 379.008243 -267.03289)
			(xy 378.96774 -267.060846) (xy 378.923278 -267.081944) (xy 378.876007 -267.095636) (xy 378.827152 -267.101568)
			(xy 378.777977 -267.099587) (xy 378.729758 -267.089743) (xy 378.683742 -267.072291) (xy 378.641121 -267.047684)
			(xy 378.603 -267.016559) (xy 378.570365 -266.979722) (xy 378.544062 -266.938126) (xy 378.524771 -266.89285)
			(xy 378.512994 -266.845066) (xy 378.509034 -266.796012) (xy 378.190506 -266.796012) (xy 378.189994 -266.821458)
			(xy 378.18183 -266.871692) (xy 378.165714 -266.919966) (xy 378.142063 -266.965029) (xy 378.11149 -267.005715)
			(xy 378.074786 -267.04097) (xy 378.032902 -267.06988) (xy 377.986923 -267.091697) (xy 377.938039 -267.105857)
			(xy 377.887518 -267.111991) (xy 377.836666 -267.109942) (xy 377.786802 -267.099762) (xy 377.739216 -267.081715)
			(xy 377.695142 -267.056269) (xy 377.65572 -267.024082) (xy 377.621972 -266.985988) (xy 377.594771 -266.942974)
			(xy 377.574823 -266.896154) (xy 377.562644 -266.84674) (xy 377.558549 -266.796012) (xy 377.240038 -266.796012)
			(xy 377.239543 -266.820619) (xy 377.231648 -266.869196) (xy 377.216064 -266.915877) (xy 377.193193 -266.959454)
			(xy 377.163628 -266.998798) (xy 377.128135 -267.03289) (xy 377.087632 -267.060846) (xy 377.04317 -267.081944)
			(xy 376.995899 -267.095636) (xy 376.947044 -267.101568) (xy 376.897869 -267.099587) (xy 376.84965 -267.089743)
			(xy 376.803634 -267.072291) (xy 376.761013 -267.047684) (xy 376.722892 -267.016559) (xy 376.690257 -266.979722)
			(xy 376.663954 -266.938126) (xy 376.644663 -266.89285) (xy 376.632886 -266.845066) (xy 376.628926 -266.796012)
			(xy 376.310652 -266.796012) (xy 376.31014 -266.821458) (xy 376.301976 -266.871692) (xy 376.28586 -266.919966)
			(xy 376.262209 -266.965029) (xy 376.231636 -267.005715) (xy 376.194932 -267.04097) (xy 376.153048 -267.06988)
			(xy 376.107069 -267.091697) (xy 376.058185 -267.105857) (xy 376.007664 -267.111991) (xy 375.956812 -267.109942)
			(xy 375.906948 -267.099762) (xy 375.859362 -267.081715) (xy 375.815288 -267.056269) (xy 375.775866 -267.024082)
			(xy 375.742118 -266.985988) (xy 375.714917 -266.942974) (xy 375.694969 -266.896154) (xy 375.68279 -266.84674)
			(xy 375.678695 -266.796012) (xy 375.360184 -266.796012) (xy 375.359689 -266.820619) (xy 375.351794 -266.869196)
			(xy 375.33621 -266.915877) (xy 375.313339 -266.959454) (xy 375.283774 -266.998798) (xy 375.248281 -267.03289)
			(xy 375.207778 -267.060846) (xy 375.163316 -267.081944) (xy 375.116045 -267.095636) (xy 375.06719 -267.101568)
			(xy 375.018015 -267.099587) (xy 374.969796 -267.089743) (xy 374.92378 -267.072291) (xy 374.881159 -267.047684)
			(xy 374.843038 -267.016559) (xy 374.810403 -266.979722) (xy 374.7841 -266.938126) (xy 374.764809 -266.89285)
			(xy 374.753032 -266.845066) (xy 374.749072 -266.796012) (xy 374.42013 -266.796012) (xy 374.42013 -266.79652)
			(xy 374.419366 -266.826321) (xy 374.407725 -266.884777) (xy 374.397016 -266.912598) (xy 374.397016 -266.912852)
			(xy 374.396762 -266.91336) (xy 374.392732 -266.925164) (xy 374.395381 -266.949937) (xy 374.401842 -266.960604)
			(xy 374.448578 -267.030454) (xy 374.449594 -267.031978) (xy 374.457204 -267.041366) (xy 374.478678 -267.052378)
			(xy 374.490742 -267.05306) (xy 374.567958 -267.05306) (xy 374.578022 -267.053495) (xy 374.596606 -267.061231)
			(xy 374.604026 -267.068046) (xy 375.141998 -267.606018) (xy 376.159026 -267.606018) (xy 376.162986 -267.556964)
			(xy 376.174763 -267.50918) (xy 376.194054 -267.463904) (xy 376.220357 -267.422308) (xy 376.252992 -267.385471)
			(xy 376.291113 -267.354346) (xy 376.333734 -267.329739) (xy 376.37975 -267.312287) (xy 376.427969 -267.302443)
			(xy 376.477144 -267.300462) (xy 376.525999 -267.306394) (xy 376.57327 -267.320086) (xy 376.617732 -267.341184)
			(xy 376.658235 -267.36914) (xy 376.693728 -267.403232) (xy 376.723293 -267.442576) (xy 376.746164 -267.486153)
			(xy 376.761748 -267.532834) (xy 376.769643 -267.581411) (xy 376.770138 -267.606018) (xy 377.088649 -267.606018)
			(xy 377.092744 -267.55529) (xy 377.104923 -267.505876) (xy 377.124871 -267.459056) (xy 377.152072 -267.416042)
			(xy 377.18582 -267.377948) (xy 377.225242 -267.345761) (xy 377.269316 -267.320315) (xy 377.316902 -267.302268)
			(xy 377.366766 -267.292088) (xy 377.417618 -267.290039) (xy 377.468139 -267.296173) (xy 377.517023 -267.310333)
			(xy 377.563002 -267.33215) (xy 377.604886 -267.36106) (xy 377.64159 -267.396315) (xy 377.672163 -267.437001)
			(xy 377.695814 -267.482064) (xy 377.71193 -267.530338) (xy 377.720094 -267.580572) (xy 377.720606 -267.606018)
			(xy 378.039134 -267.606018) (xy 378.043094 -267.556964) (xy 378.054871 -267.50918) (xy 378.074162 -267.463904)
			(xy 378.100465 -267.422308) (xy 378.1331 -267.385471) (xy 378.171221 -267.354346) (xy 378.213842 -267.329739)
			(xy 378.259858 -267.312287) (xy 378.308077 -267.302443) (xy 378.357252 -267.300462) (xy 378.406107 -267.306394)
			(xy 378.453378 -267.320086) (xy 378.49784 -267.341184) (xy 378.538343 -267.36914) (xy 378.573836 -267.403232)
			(xy 378.603401 -267.442576) (xy 378.626272 -267.486153) (xy 378.641856 -267.532834) (xy 378.649751 -267.581411)
			(xy 378.650246 -267.606018) (xy 378.978934 -267.606018) (xy 378.982894 -267.556964) (xy 378.994671 -267.50918)
			(xy 379.013962 -267.463904) (xy 379.040265 -267.422308) (xy 379.0729 -267.385471) (xy 379.111021 -267.354346)
			(xy 379.153642 -267.329739) (xy 379.199658 -267.312287) (xy 379.247877 -267.302443) (xy 379.297052 -267.300462)
			(xy 379.345907 -267.306394) (xy 379.393178 -267.320086) (xy 379.43764 -267.341184) (xy 379.478143 -267.36914)
			(xy 379.513636 -267.403232) (xy 379.543201 -267.442576) (xy 379.566072 -267.486153) (xy 379.581656 -267.532834)
			(xy 379.589551 -267.581411) (xy 379.590046 -267.606018) (xy 379.918988 -267.606018) (xy 379.922948 -267.556964)
			(xy 379.934725 -267.50918) (xy 379.954016 -267.463904) (xy 379.980319 -267.422308) (xy 380.012954 -267.385471)
			(xy 380.051075 -267.354346) (xy 380.093696 -267.329739) (xy 380.139712 -267.312287) (xy 380.187931 -267.302443)
			(xy 380.237106 -267.300462) (xy 380.285961 -267.306394) (xy 380.333232 -267.320086) (xy 380.377694 -267.341184)
			(xy 380.418197 -267.36914) (xy 380.45369 -267.403232) (xy 380.483255 -267.442576) (xy 380.506126 -267.486153)
			(xy 380.52171 -267.532834) (xy 380.529605 -267.581411) (xy 380.5301 -267.606018) (xy 380.848611 -267.606018)
			(xy 380.852706 -267.55529) (xy 380.864885 -267.505876) (xy 380.884833 -267.459056) (xy 380.912034 -267.416042)
			(xy 380.945782 -267.377948) (xy 380.985204 -267.345761) (xy 381.029278 -267.320315) (xy 381.076864 -267.302268)
			(xy 381.126728 -267.292088) (xy 381.17758 -267.290039) (xy 381.228101 -267.296173) (xy 381.276985 -267.310333)
			(xy 381.322964 -267.33215) (xy 381.364848 -267.36106) (xy 381.401552 -267.396315) (xy 381.432125 -267.437001)
			(xy 381.455776 -267.482064) (xy 381.471892 -267.530338) (xy 381.480056 -267.580572) (xy 381.480568 -267.606018)
			(xy 381.480056 -267.631464) (xy 381.471892 -267.681698) (xy 381.455776 -267.729972) (xy 381.432125 -267.775035)
			(xy 381.401552 -267.815721) (xy 381.364848 -267.850976) (xy 381.322964 -267.879886) (xy 381.276985 -267.901703)
			(xy 381.228101 -267.915863) (xy 381.17758 -267.921997) (xy 381.126728 -267.919948) (xy 381.076864 -267.909768)
			(xy 381.029278 -267.891721) (xy 380.985204 -267.866275) (xy 380.945782 -267.834088) (xy 380.912034 -267.795994)
			(xy 380.884833 -267.75298) (xy 380.864885 -267.70616) (xy 380.852706 -267.656746) (xy 380.848611 -267.606018)
			(xy 380.5301 -267.606018) (xy 380.529605 -267.630625) (xy 380.52171 -267.679202) (xy 380.506126 -267.725883)
			(xy 380.483255 -267.76946) (xy 380.45369 -267.808804) (xy 380.418197 -267.842896) (xy 380.377694 -267.870852)
			(xy 380.333232 -267.89195) (xy 380.285961 -267.905642) (xy 380.237106 -267.911574) (xy 380.187931 -267.909593)
			(xy 380.139712 -267.899749) (xy 380.093696 -267.882297) (xy 380.051075 -267.85769) (xy 380.012954 -267.826565)
			(xy 379.980319 -267.789728) (xy 379.954016 -267.748132) (xy 379.934725 -267.702856) (xy 379.922948 -267.655072)
			(xy 379.918988 -267.606018) (xy 379.590046 -267.606018) (xy 379.589551 -267.630625) (xy 379.581656 -267.679202)
			(xy 379.566072 -267.725883) (xy 379.543201 -267.76946) (xy 379.513636 -267.808804) (xy 379.478143 -267.842896)
			(xy 379.43764 -267.870852) (xy 379.393178 -267.89195) (xy 379.345907 -267.905642) (xy 379.297052 -267.911574)
			(xy 379.247877 -267.909593) (xy 379.199658 -267.899749) (xy 379.153642 -267.882297) (xy 379.111021 -267.85769)
			(xy 379.0729 -267.826565) (xy 379.040265 -267.789728) (xy 379.013962 -267.748132) (xy 378.994671 -267.702856)
			(xy 378.982894 -267.655072) (xy 378.978934 -267.606018) (xy 378.650246 -267.606018) (xy 378.649751 -267.630625)
			(xy 378.641856 -267.679202) (xy 378.626272 -267.725883) (xy 378.603401 -267.76946) (xy 378.573836 -267.808804)
			(xy 378.538343 -267.842896) (xy 378.49784 -267.870852) (xy 378.453378 -267.89195) (xy 378.406107 -267.905642)
			(xy 378.357252 -267.911574) (xy 378.308077 -267.909593) (xy 378.259858 -267.899749) (xy 378.213842 -267.882297)
			(xy 378.171221 -267.85769) (xy 378.1331 -267.826565) (xy 378.100465 -267.789728) (xy 378.074162 -267.748132)
			(xy 378.054871 -267.702856) (xy 378.043094 -267.655072) (xy 378.039134 -267.606018) (xy 377.720606 -267.606018)
			(xy 377.720094 -267.631464) (xy 377.71193 -267.681698) (xy 377.695814 -267.729972) (xy 377.672163 -267.775035)
			(xy 377.64159 -267.815721) (xy 377.604886 -267.850976) (xy 377.563002 -267.879886) (xy 377.517023 -267.901703)
			(xy 377.468139 -267.915863) (xy 377.417618 -267.921997) (xy 377.366766 -267.919948) (xy 377.316902 -267.909768)
			(xy 377.269316 -267.891721) (xy 377.225242 -267.866275) (xy 377.18582 -267.834088) (xy 377.152072 -267.795994)
			(xy 377.124871 -267.75298) (xy 377.104923 -267.70616) (xy 377.092744 -267.656746) (xy 377.088649 -267.606018)
			(xy 376.770138 -267.606018) (xy 376.769643 -267.630625) (xy 376.761748 -267.679202) (xy 376.746164 -267.725883)
			(xy 376.723293 -267.76946) (xy 376.693728 -267.808804) (xy 376.658235 -267.842896) (xy 376.617732 -267.870852)
			(xy 376.57327 -267.89195) (xy 376.525999 -267.905642) (xy 376.477144 -267.911574) (xy 376.427969 -267.909593)
			(xy 376.37975 -267.899749) (xy 376.333734 -267.882297) (xy 376.291113 -267.85769) (xy 376.252992 -267.826565)
			(xy 376.220357 -267.789728) (xy 376.194054 -267.748132) (xy 376.174763 -267.702856) (xy 376.162986 -267.655072)
			(xy 376.159026 -267.606018) (xy 375.141998 -267.606018) (xy 375.193814 -267.657834) (xy 375.200665 -267.66523)
			(xy 375.2084 -267.683829) (xy 375.2088 -267.693902) (xy 375.2088 -268.111986) (xy 375.208971 -268.117994)
			(xy 375.211803 -268.129673) (xy 375.214388 -268.1351) (xy 375.224548 -268.154912) (xy 375.231152 -268.164818)
			(xy 375.234708 -268.168882) (xy 375.23928 -268.172438) (xy 375.239534 -268.172692) (xy 375.259602 -268.188598)
			(xy 375.294634 -268.225944) (xy 375.322951 -268.268606) (xy 375.343763 -268.31539) (xy 375.356486 -268.364989)
			(xy 375.360766 -268.416015) (xy 375.360765 -268.416024) (xy 375.689126 -268.416024) (xy 375.693086 -268.36697)
			(xy 375.704863 -268.319186) (xy 375.724154 -268.27391) (xy 375.750457 -268.232314) (xy 375.783092 -268.195477)
			(xy 375.821213 -268.164352) (xy 375.863834 -268.139745) (xy 375.90985 -268.122293) (xy 375.958069 -268.112449)
			(xy 376.007244 -268.110468) (xy 376.056099 -268.1164) (xy 376.10337 -268.130092) (xy 376.147832 -268.15119)
			(xy 376.188335 -268.179146) (xy 376.223828 -268.213238) (xy 376.253393 -268.252582) (xy 376.276264 -268.296159)
			(xy 376.291848 -268.34284) (xy 376.299743 -268.391417) (xy 376.300238 -268.416024) (xy 376.628926 -268.416024)
			(xy 376.632886 -268.36697) (xy 376.644663 -268.319186) (xy 376.663954 -268.27391) (xy 376.690257 -268.232314)
			(xy 376.722892 -268.195477) (xy 376.761013 -268.164352) (xy 376.803634 -268.139745) (xy 376.84965 -268.122293)
			(xy 376.897869 -268.112449) (xy 376.947044 -268.110468) (xy 376.995899 -268.1164) (xy 377.04317 -268.130092)
			(xy 377.087632 -268.15119) (xy 377.128135 -268.179146) (xy 377.163628 -268.213238) (xy 377.193193 -268.252582)
			(xy 377.216064 -268.296159) (xy 377.231648 -268.34284) (xy 377.239543 -268.391417) (xy 377.240038 -268.416024)
			(xy 377.56898 -268.416024) (xy 377.57294 -268.36697) (xy 377.584717 -268.319186) (xy 377.604008 -268.27391)
			(xy 377.630311 -268.232314) (xy 377.662946 -268.195477) (xy 377.701067 -268.164352) (xy 377.743688 -268.139745)
			(xy 377.789704 -268.122293) (xy 377.837923 -268.112449) (xy 377.887098 -268.110468) (xy 377.935953 -268.1164)
			(xy 377.983224 -268.130092) (xy 378.027686 -268.15119) (xy 378.068189 -268.179146) (xy 378.103682 -268.213238)
			(xy 378.133247 -268.252582) (xy 378.156118 -268.296159) (xy 378.171702 -268.34284) (xy 378.179597 -268.391417)
			(xy 378.180092 -268.416024) (xy 379.449088 -268.416024) (xy 379.453048 -268.36697) (xy 379.464825 -268.319186)
			(xy 379.484116 -268.27391) (xy 379.510419 -268.232314) (xy 379.543054 -268.195477) (xy 379.581175 -268.164352)
			(xy 379.623796 -268.139745) (xy 379.669812 -268.122293) (xy 379.718031 -268.112449) (xy 379.767206 -268.110468)
			(xy 379.816061 -268.1164) (xy 379.863332 -268.130092) (xy 379.907794 -268.15119) (xy 379.948297 -268.179146)
			(xy 379.98379 -268.213238) (xy 380.013355 -268.252582) (xy 380.036226 -268.296159) (xy 380.05181 -268.34284)
			(xy 380.059705 -268.391417) (xy 380.0602 -268.416024) (xy 380.388888 -268.416024) (xy 380.392848 -268.36697)
			(xy 380.404625 -268.319186) (xy 380.423916 -268.27391) (xy 380.450219 -268.232314) (xy 380.482854 -268.195477)
			(xy 380.520975 -268.164352) (xy 380.563596 -268.139745) (xy 380.609612 -268.122293) (xy 380.657831 -268.112449)
			(xy 380.707006 -268.110468) (xy 380.755861 -268.1164) (xy 380.803132 -268.130092) (xy 380.847594 -268.15119)
			(xy 380.888097 -268.179146) (xy 380.92359 -268.213238) (xy 380.953155 -268.252582) (xy 380.976026 -268.296159)
			(xy 380.99161 -268.34284) (xy 380.999505 -268.391417) (xy 381 -268.416024) (xy 380.999505 -268.440631)
			(xy 380.99161 -268.489208) (xy 380.976026 -268.535889) (xy 380.953155 -268.579466) (xy 380.92359 -268.61881)
			(xy 380.888097 -268.652902) (xy 380.847594 -268.680858) (xy 380.803132 -268.701956) (xy 380.755861 -268.715648)
			(xy 380.707006 -268.72158) (xy 380.657831 -268.719599) (xy 380.609612 -268.709755) (xy 380.563596 -268.692303)
			(xy 380.520975 -268.667696) (xy 380.482854 -268.636571) (xy 380.450219 -268.599734) (xy 380.423916 -268.558138)
			(xy 380.404625 -268.512862) (xy 380.392848 -268.465078) (xy 380.388888 -268.416024) (xy 380.0602 -268.416024)
			(xy 380.059705 -268.440631) (xy 380.05181 -268.489208) (xy 380.036226 -268.535889) (xy 380.013355 -268.579466)
			(xy 379.98379 -268.61881) (xy 379.948297 -268.652902) (xy 379.907794 -268.680858) (xy 379.863332 -268.701956)
			(xy 379.816061 -268.715648) (xy 379.767206 -268.72158) (xy 379.718031 -268.719599) (xy 379.669812 -268.709755)
			(xy 379.623796 -268.692303) (xy 379.581175 -268.667696) (xy 379.543054 -268.636571) (xy 379.510419 -268.599734)
			(xy 379.484116 -268.558138) (xy 379.464825 -268.512862) (xy 379.453048 -268.465078) (xy 379.449088 -268.416024)
			(xy 378.180092 -268.416024) (xy 378.179597 -268.440631) (xy 378.171702 -268.489208) (xy 378.156118 -268.535889)
			(xy 378.133247 -268.579466) (xy 378.103682 -268.61881) (xy 378.068189 -268.652902) (xy 378.027686 -268.680858)
			(xy 377.983224 -268.701956) (xy 377.935953 -268.715648) (xy 377.887098 -268.72158) (xy 377.837923 -268.719599)
			(xy 377.789704 -268.709755) (xy 377.743688 -268.692303) (xy 377.701067 -268.667696) (xy 377.662946 -268.636571)
			(xy 377.630311 -268.599734) (xy 377.604008 -268.558138) (xy 377.584717 -268.512862) (xy 377.57294 -268.465078)
			(xy 377.56898 -268.416024) (xy 377.240038 -268.416024) (xy 377.239543 -268.440631) (xy 377.231648 -268.489208)
			(xy 377.216064 -268.535889) (xy 377.193193 -268.579466) (xy 377.163628 -268.61881) (xy 377.128135 -268.652902)
			(xy 377.087632 -268.680858) (xy 377.04317 -268.701956) (xy 376.995899 -268.715648) (xy 376.947044 -268.72158)
			(xy 376.897869 -268.719599) (xy 376.84965 -268.709755) (xy 376.803634 -268.692303) (xy 376.761013 -268.667696)
			(xy 376.722892 -268.636571) (xy 376.690257 -268.599734) (xy 376.663954 -268.558138) (xy 376.644663 -268.512862)
			(xy 376.632886 -268.465078) (xy 376.628926 -268.416024) (xy 376.300238 -268.416024) (xy 376.299743 -268.440631)
			(xy 376.291848 -268.489208) (xy 376.276264 -268.535889) (xy 376.253393 -268.579466) (xy 376.223828 -268.61881)
			(xy 376.188335 -268.652902) (xy 376.147832 -268.680858) (xy 376.10337 -268.701956) (xy 376.056099 -268.715648)
			(xy 376.007244 -268.72158) (xy 375.958069 -268.719599) (xy 375.90985 -268.709755) (xy 375.863834 -268.692303)
			(xy 375.821213 -268.667696) (xy 375.783092 -268.636571) (xy 375.750457 -268.599734) (xy 375.724154 -268.558138)
			(xy 375.704863 -268.512862) (xy 375.693086 -268.465078) (xy 375.689126 -268.416024) (xy 375.360765 -268.416024)
			(xy 375.356481 -268.46704) (xy 375.343753 -268.516637) (xy 375.322937 -268.56342) (xy 375.294616 -268.606079)
			(xy 375.259581 -268.643421) (xy 375.239534 -268.659356) (xy 375.23928 -268.65961) (xy 375.234708 -268.663166)
			(xy 375.231152 -268.66723) (xy 375.224548 -268.677136) (xy 375.214388 -268.696948) (xy 375.211806 -268.702375)
			(xy 375.208984 -268.714055) (xy 375.2088 -268.720062) (xy 375.2088 -268.879828) (xy 375.20939 -268.892453)
			(xy 375.221243 -268.914737) (xy 375.231406 -268.922246) (xy 375.2342 -268.924024) (xy 375.312432 -268.967712)
			(xy 375.320453 -268.971809) (xy 375.33823 -268.97463) (xy 375.355878 -268.971092) (xy 375.36374 -268.966696)
			(xy 375.363994 -268.966442) (xy 375.38835 -268.952135) (xy 375.441018 -268.93174) (xy 375.496536 -268.921363)
			(xy 375.524776 -268.920722) (xy 375.550033 -268.921213) (xy 375.599857 -268.929523) (xy 375.647634 -268.945922)
			(xy 375.69206 -268.969961) (xy 375.731924 -269.000985) (xy 375.766137 -269.038147) (xy 375.793766 -269.080434)
			(xy 375.814058 -269.126692) (xy 375.826458 -269.17566) (xy 375.83063 -269.226) (xy 375.830628 -269.22603)
			(xy 376.159026 -269.22603) (xy 376.162986 -269.176976) (xy 376.174763 -269.129192) (xy 376.194054 -269.083916)
			(xy 376.220357 -269.04232) (xy 376.252992 -269.005483) (xy 376.291113 -268.974358) (xy 376.333734 -268.949751)
			(xy 376.37975 -268.932299) (xy 376.427969 -268.922455) (xy 376.477144 -268.920474) (xy 376.525999 -268.926406)
			(xy 376.57327 -268.940098) (xy 376.617732 -268.961196) (xy 376.658235 -268.989152) (xy 376.693728 -269.023244)
			(xy 376.723293 -269.062588) (xy 376.746164 -269.106165) (xy 376.761748 -269.152846) (xy 376.769643 -269.201423)
			(xy 376.770138 -269.22603) (xy 377.088649 -269.22603) (xy 377.092744 -269.175302) (xy 377.104923 -269.125888)
			(xy 377.124871 -269.079068) (xy 377.152072 -269.036054) (xy 377.18582 -268.99796) (xy 377.225242 -268.965773)
			(xy 377.269316 -268.940327) (xy 377.316902 -268.92228) (xy 377.366766 -268.9121) (xy 377.417618 -268.910051)
			(xy 377.468139 -268.916185) (xy 377.517023 -268.930345) (xy 377.563002 -268.952162) (xy 377.604886 -268.981072)
			(xy 377.64159 -269.016327) (xy 377.672163 -269.057013) (xy 377.695814 -269.102076) (xy 377.71193 -269.15035)
			(xy 377.720094 -269.200584) (xy 377.720606 -269.22603) (xy 378.039134 -269.22603) (xy 378.043094 -269.176976)
			(xy 378.054871 -269.129192) (xy 378.074162 -269.083916) (xy 378.100465 -269.04232) (xy 378.1331 -269.005483)
			(xy 378.171221 -268.974358) (xy 378.213842 -268.949751) (xy 378.259858 -268.932299) (xy 378.308077 -268.922455)
			(xy 378.357252 -268.920474) (xy 378.406107 -268.926406) (xy 378.453378 -268.940098) (xy 378.49784 -268.961196)
			(xy 378.538343 -268.989152) (xy 378.573836 -269.023244) (xy 378.603401 -269.062588) (xy 378.626272 -269.106165)
			(xy 378.641856 -269.152846) (xy 378.649751 -269.201423) (xy 378.650246 -269.22603) (xy 378.978934 -269.22603)
			(xy 378.982894 -269.176976) (xy 378.994671 -269.129192) (xy 379.013962 -269.083916) (xy 379.040265 -269.04232)
			(xy 379.0729 -269.005483) (xy 379.111021 -268.974358) (xy 379.153642 -268.949751) (xy 379.199658 -268.932299)
			(xy 379.247877 -268.922455) (xy 379.297052 -268.920474) (xy 379.345907 -268.926406) (xy 379.393178 -268.940098)
			(xy 379.43764 -268.961196) (xy 379.478143 -268.989152) (xy 379.513636 -269.023244) (xy 379.543201 -269.062588)
			(xy 379.566072 -269.106165) (xy 379.581656 -269.152846) (xy 379.589551 -269.201423) (xy 379.590046 -269.22603)
			(xy 379.918988 -269.22603) (xy 379.922948 -269.176976) (xy 379.934725 -269.129192) (xy 379.954016 -269.083916)
			(xy 379.980319 -269.04232) (xy 380.012954 -269.005483) (xy 380.051075 -268.974358) (xy 380.093696 -268.949751)
			(xy 380.139712 -268.932299) (xy 380.187931 -268.922455) (xy 380.237106 -268.920474) (xy 380.285961 -268.926406)
			(xy 380.333232 -268.940098) (xy 380.377694 -268.961196) (xy 380.418197 -268.989152) (xy 380.45369 -269.023244)
			(xy 380.483255 -269.062588) (xy 380.506126 -269.106165) (xy 380.52171 -269.152846) (xy 380.529605 -269.201423)
			(xy 380.5301 -269.22603) (xy 380.848611 -269.22603) (xy 380.852706 -269.175302) (xy 380.864885 -269.125888)
			(xy 380.884833 -269.079068) (xy 380.912034 -269.036054) (xy 380.945782 -268.99796) (xy 380.985204 -268.965773)
			(xy 381.029278 -268.940327) (xy 381.076864 -268.92228) (xy 381.126728 -268.9121) (xy 381.17758 -268.910051)
			(xy 381.228101 -268.916185) (xy 381.276985 -268.930345) (xy 381.322964 -268.952162) (xy 381.364848 -268.981072)
			(xy 381.401552 -269.016327) (xy 381.432125 -269.057013) (xy 381.455776 -269.102076) (xy 381.471892 -269.15035)
			(xy 381.480056 -269.200584) (xy 381.480568 -269.22603) (xy 381.480056 -269.251476) (xy 381.471892 -269.30171)
			(xy 381.455776 -269.349984) (xy 381.432125 -269.395047) (xy 381.401552 -269.435733) (xy 381.364848 -269.470988)
			(xy 381.322964 -269.499898) (xy 381.276985 -269.521715) (xy 381.228101 -269.535875) (xy 381.17758 -269.542009)
			(xy 381.126728 -269.53996) (xy 381.076864 -269.52978) (xy 381.029278 -269.511733) (xy 380.985204 -269.486287)
			(xy 380.945782 -269.4541) (xy 380.912034 -269.416006) (xy 380.884833 -269.372992) (xy 380.864885 -269.326172)
			(xy 380.852706 -269.276758) (xy 380.848611 -269.22603) (xy 380.5301 -269.22603) (xy 380.529605 -269.250637)
			(xy 380.52171 -269.299214) (xy 380.506126 -269.345895) (xy 380.483255 -269.389472) (xy 380.45369 -269.428816)
			(xy 380.418197 -269.462908) (xy 380.377694 -269.490864) (xy 380.333232 -269.511962) (xy 380.285961 -269.525654)
			(xy 380.237106 -269.531586) (xy 380.187931 -269.529605) (xy 380.139712 -269.519761) (xy 380.093696 -269.502309)
			(xy 380.051075 -269.477702) (xy 380.012954 -269.446577) (xy 379.980319 -269.40974) (xy 379.954016 -269.368144)
			(xy 379.934725 -269.322868) (xy 379.922948 -269.275084) (xy 379.918988 -269.22603) (xy 379.590046 -269.22603)
			(xy 379.589551 -269.250637) (xy 379.581656 -269.299214) (xy 379.566072 -269.345895) (xy 379.543201 -269.389472)
			(xy 379.513636 -269.428816) (xy 379.478143 -269.462908) (xy 379.43764 -269.490864) (xy 379.393178 -269.511962)
			(xy 379.345907 -269.525654) (xy 379.297052 -269.531586) (xy 379.247877 -269.529605) (xy 379.199658 -269.519761)
			(xy 379.153642 -269.502309) (xy 379.111021 -269.477702) (xy 379.0729 -269.446577) (xy 379.040265 -269.40974)
			(xy 379.013962 -269.368144) (xy 378.994671 -269.322868) (xy 378.982894 -269.275084) (xy 378.978934 -269.22603)
			(xy 378.650246 -269.22603) (xy 378.649751 -269.250637) (xy 378.641856 -269.299214) (xy 378.626272 -269.345895)
			(xy 378.603401 -269.389472) (xy 378.573836 -269.428816) (xy 378.538343 -269.462908) (xy 378.49784 -269.490864)
			(xy 378.453378 -269.511962) (xy 378.406107 -269.525654) (xy 378.357252 -269.531586) (xy 378.308077 -269.529605)
			(xy 378.259858 -269.519761) (xy 378.213842 -269.502309) (xy 378.171221 -269.477702) (xy 378.1331 -269.446577)
			(xy 378.100465 -269.40974) (xy 378.074162 -269.368144) (xy 378.054871 -269.322868) (xy 378.043094 -269.275084)
			(xy 378.039134 -269.22603) (xy 377.720606 -269.22603) (xy 377.720094 -269.251476) (xy 377.71193 -269.30171)
			(xy 377.695814 -269.349984) (xy 377.672163 -269.395047) (xy 377.64159 -269.435733) (xy 377.604886 -269.470988)
			(xy 377.563002 -269.499898) (xy 377.517023 -269.521715) (xy 377.468139 -269.535875) (xy 377.417618 -269.542009)
			(xy 377.366766 -269.53996) (xy 377.316902 -269.52978) (xy 377.269316 -269.511733) (xy 377.225242 -269.486287)
			(xy 377.18582 -269.4541) (xy 377.152072 -269.416006) (xy 377.124871 -269.372992) (xy 377.104923 -269.326172)
			(xy 377.092744 -269.276758) (xy 377.088649 -269.22603) (xy 376.770138 -269.22603) (xy 376.769643 -269.250637)
			(xy 376.761748 -269.299214) (xy 376.746164 -269.345895) (xy 376.723293 -269.389472) (xy 376.693728 -269.428816)
			(xy 376.658235 -269.462908) (xy 376.617732 -269.490864) (xy 376.57327 -269.511962) (xy 376.525999 -269.525654)
			(xy 376.477144 -269.531586) (xy 376.427969 -269.529605) (xy 376.37975 -269.519761) (xy 376.333734 -269.502309)
			(xy 376.291113 -269.477702) (xy 376.252992 -269.446577) (xy 376.220357 -269.40974) (xy 376.194054 -269.368144)
			(xy 376.174763 -269.322868) (xy 376.162986 -269.275084) (xy 376.159026 -269.22603) (xy 375.830628 -269.22603)
			(xy 375.826458 -269.27634) (xy 375.814058 -269.325308) (xy 375.793766 -269.371566) (xy 375.766137 -269.413853)
			(xy 375.731924 -269.451015) (xy 375.69206 -269.482039) (xy 375.647634 -269.506078) (xy 375.599857 -269.522477)
			(xy 375.550033 -269.530787) (xy 375.524776 -269.531338) (xy 375.496538 -269.530685) (xy 375.441022 -269.520308)
			(xy 375.388357 -269.499912) (xy 375.363994 -269.485618) (xy 375.36374 -269.485364) (xy 375.355871 -269.481002)
			(xy 375.33823 -269.477522) (xy 375.320465 -269.480296) (xy 375.312432 -269.484348) (xy 375.234962 -269.527528)
			(xy 375.234708 -269.527782) (xy 375.227062 -269.5325) (xy 375.215414 -269.546166) (xy 375.209171 -269.563002)
			(xy 375.2088 -269.571978) (xy 375.2088 -269.731998) (xy 375.208973 -269.738006) (xy 375.211807 -269.749683)
			(xy 375.214388 -269.755112) (xy 375.224548 -269.774924) (xy 375.231152 -269.78483) (xy 375.234708 -269.788894)
			(xy 375.23928 -269.79245) (xy 375.239534 -269.792704) (xy 375.259601 -269.80861) (xy 375.294631 -269.845956)
			(xy 375.322946 -269.888617) (xy 375.343756 -269.9354) (xy 375.356478 -269.984998) (xy 375.360756 -270.036022)
			(xy 375.360755 -270.036036) (xy 375.678695 -270.036036) (xy 375.68279 -269.985308) (xy 375.694969 -269.935894)
			(xy 375.714917 -269.889074) (xy 375.742118 -269.84606) (xy 375.775866 -269.807966) (xy 375.815288 -269.775779)
			(xy 375.859362 -269.750333) (xy 375.906948 -269.732286) (xy 375.956812 -269.722106) (xy 376.007664 -269.720057)
			(xy 376.058185 -269.726191) (xy 376.107069 -269.740351) (xy 376.153048 -269.762168) (xy 376.194932 -269.791078)
			(xy 376.231636 -269.826333) (xy 376.262209 -269.867019) (xy 376.28586 -269.912082) (xy 376.301976 -269.960356)
			(xy 376.31014 -270.01059) (xy 376.310652 -270.036036) (xy 376.628926 -270.036036) (xy 376.632886 -269.986982)
			(xy 376.644663 -269.939198) (xy 376.663954 -269.893922) (xy 376.690257 -269.852326) (xy 376.722892 -269.815489)
			(xy 376.761013 -269.784364) (xy 376.803634 -269.759757) (xy 376.84965 -269.742305) (xy 376.897869 -269.732461)
			(xy 376.947044 -269.73048) (xy 376.995899 -269.736412) (xy 377.04317 -269.750104) (xy 377.087632 -269.771202)
			(xy 377.128135 -269.799158) (xy 377.163628 -269.83325) (xy 377.193193 -269.872594) (xy 377.216064 -269.916171)
			(xy 377.231648 -269.962852) (xy 377.239543 -270.011429) (xy 377.240038 -270.036036) (xy 377.558549 -270.036036)
			(xy 377.562644 -269.985308) (xy 377.574823 -269.935894) (xy 377.594771 -269.889074) (xy 377.621972 -269.84606)
			(xy 377.65572 -269.807966) (xy 377.695142 -269.775779) (xy 377.739216 -269.750333) (xy 377.786802 -269.732286)
			(xy 377.836666 -269.722106) (xy 377.887518 -269.720057) (xy 377.938039 -269.726191) (xy 377.986923 -269.740351)
			(xy 378.032902 -269.762168) (xy 378.074786 -269.791078) (xy 378.11149 -269.826333) (xy 378.142063 -269.867019)
			(xy 378.165714 -269.912082) (xy 378.18183 -269.960356) (xy 378.189994 -270.01059) (xy 378.190506 -270.036036)
			(xy 378.509034 -270.036036) (xy 378.512994 -269.986982) (xy 378.524771 -269.939198) (xy 378.544062 -269.893922)
			(xy 378.570365 -269.852326) (xy 378.603 -269.815489) (xy 378.641121 -269.784364) (xy 378.683742 -269.759757)
			(xy 378.729758 -269.742305) (xy 378.777977 -269.732461) (xy 378.827152 -269.73048) (xy 378.876007 -269.736412)
			(xy 378.923278 -269.750104) (xy 378.96774 -269.771202) (xy 379.008243 -269.799158) (xy 379.043736 -269.83325)
			(xy 379.073301 -269.872594) (xy 379.096172 -269.916171) (xy 379.111756 -269.962852) (xy 379.119651 -270.011429)
			(xy 379.120146 -270.036036) (xy 379.438657 -270.036036) (xy 379.442752 -269.985308) (xy 379.454931 -269.935894)
			(xy 379.474879 -269.889074) (xy 379.50208 -269.84606) (xy 379.535828 -269.807966) (xy 379.57525 -269.775779)
			(xy 379.619324 -269.750333) (xy 379.66691 -269.732286) (xy 379.716774 -269.722106) (xy 379.767626 -269.720057)
			(xy 379.818147 -269.726191) (xy 379.867031 -269.740351) (xy 379.91301 -269.762168) (xy 379.954894 -269.791078)
			(xy 379.991598 -269.826333) (xy 380.022171 -269.867019) (xy 380.045822 -269.912082) (xy 380.061938 -269.960356)
			(xy 380.070102 -270.01059) (xy 380.070614 -270.036036) (xy 380.378711 -270.036036) (xy 380.382806 -269.985308)
			(xy 380.394985 -269.935894) (xy 380.414933 -269.889074) (xy 380.442134 -269.84606) (xy 380.475882 -269.807966)
			(xy 380.515304 -269.775779) (xy 380.559378 -269.750333) (xy 380.606964 -269.732286) (xy 380.656828 -269.722106)
			(xy 380.70768 -269.720057) (xy 380.758201 -269.726191) (xy 380.807085 -269.740351) (xy 380.853064 -269.762168)
			(xy 380.894948 -269.791078) (xy 380.931652 -269.826333) (xy 380.962225 -269.867019) (xy 380.985876 -269.912082)
			(xy 381.001992 -269.960356) (xy 381.010156 -270.01059) (xy 381.010668 -270.036036) (xy 381.010156 -270.061482)
			(xy 381.001992 -270.111716) (xy 380.985876 -270.15999) (xy 380.962225 -270.205053) (xy 380.931652 -270.245739)
			(xy 380.894948 -270.280994) (xy 380.853064 -270.309904) (xy 380.807085 -270.331721) (xy 380.758201 -270.345881)
			(xy 380.70768 -270.352015) (xy 380.656828 -270.349966) (xy 380.606964 -270.339786) (xy 380.559378 -270.321739)
			(xy 380.515304 -270.296293) (xy 380.475882 -270.264106) (xy 380.442134 -270.226012) (xy 380.414933 -270.182998)
			(xy 380.394985 -270.136178) (xy 380.382806 -270.086764) (xy 380.378711 -270.036036) (xy 380.070614 -270.036036)
			(xy 380.070102 -270.061482) (xy 380.061938 -270.111716) (xy 380.045822 -270.15999) (xy 380.022171 -270.205053)
			(xy 379.991598 -270.245739) (xy 379.954894 -270.280994) (xy 379.91301 -270.309904) (xy 379.867031 -270.331721)
			(xy 379.818147 -270.345881) (xy 379.767626 -270.352015) (xy 379.716774 -270.349966) (xy 379.66691 -270.339786)
			(xy 379.619324 -270.321739) (xy 379.57525 -270.296293) (xy 379.535828 -270.264106) (xy 379.50208 -270.226012)
			(xy 379.474879 -270.182998) (xy 379.454931 -270.136178) (xy 379.442752 -270.086764) (xy 379.438657 -270.036036)
			(xy 379.120146 -270.036036) (xy 379.119651 -270.060643) (xy 379.111756 -270.10922) (xy 379.096172 -270.155901)
			(xy 379.073301 -270.199478) (xy 379.043736 -270.238822) (xy 379.008243 -270.272914) (xy 378.96774 -270.30087)
			(xy 378.923278 -270.321968) (xy 378.876007 -270.33566) (xy 378.827152 -270.341592) (xy 378.777977 -270.339611)
			(xy 378.729758 -270.329767) (xy 378.683742 -270.312315) (xy 378.641121 -270.287708) (xy 378.603 -270.256583)
			(xy 378.570365 -270.219746) (xy 378.544062 -270.17815) (xy 378.524771 -270.132874) (xy 378.512994 -270.08509)
			(xy 378.509034 -270.036036) (xy 378.190506 -270.036036) (xy 378.189994 -270.061482) (xy 378.18183 -270.111716)
			(xy 378.165714 -270.15999) (xy 378.142063 -270.205053) (xy 378.11149 -270.245739) (xy 378.074786 -270.280994)
			(xy 378.032902 -270.309904) (xy 377.986923 -270.331721) (xy 377.938039 -270.345881) (xy 377.887518 -270.352015)
			(xy 377.836666 -270.349966) (xy 377.786802 -270.339786) (xy 377.739216 -270.321739) (xy 377.695142 -270.296293)
			(xy 377.65572 -270.264106) (xy 377.621972 -270.226012) (xy 377.594771 -270.182998) (xy 377.574823 -270.136178)
			(xy 377.562644 -270.086764) (xy 377.558549 -270.036036) (xy 377.240038 -270.036036) (xy 377.239543 -270.060643)
			(xy 377.231648 -270.10922) (xy 377.216064 -270.155901) (xy 377.193193 -270.199478) (xy 377.163628 -270.238822)
			(xy 377.128135 -270.272914) (xy 377.087632 -270.30087) (xy 377.04317 -270.321968) (xy 376.995899 -270.33566)
			(xy 376.947044 -270.341592) (xy 376.897869 -270.339611) (xy 376.84965 -270.329767) (xy 376.803634 -270.312315)
			(xy 376.761013 -270.287708) (xy 376.722892 -270.256583) (xy 376.690257 -270.219746) (xy 376.663954 -270.17815)
			(xy 376.644663 -270.132874) (xy 376.632886 -270.08509) (xy 376.628926 -270.036036) (xy 376.310652 -270.036036)
			(xy 376.31014 -270.061482) (xy 376.301976 -270.111716) (xy 376.28586 -270.15999) (xy 376.262209 -270.205053)
			(xy 376.231636 -270.245739) (xy 376.194932 -270.280994) (xy 376.153048 -270.309904) (xy 376.107069 -270.331721)
			(xy 376.058185 -270.345881) (xy 376.007664 -270.352015) (xy 375.956812 -270.349966) (xy 375.906948 -270.339786)
			(xy 375.859362 -270.321739) (xy 375.815288 -270.296293) (xy 375.775866 -270.264106) (xy 375.742118 -270.226012)
			(xy 375.714917 -270.182998) (xy 375.694969 -270.136178) (xy 375.68279 -270.086764) (xy 375.678695 -270.036036)
			(xy 375.360755 -270.036036) (xy 375.356471 -270.087045) (xy 375.343742 -270.136641) (xy 375.322925 -270.183421)
			(xy 375.294604 -270.226078) (xy 375.259569 -270.263419) (xy 375.239534 -270.279368) (xy 375.23928 -270.279622)
			(xy 375.234708 -270.283178) (xy 375.231152 -270.287242) (xy 375.224548 -270.297148) (xy 375.214388 -270.31696)
			(xy 375.211807 -270.322387) (xy 375.208988 -270.334067) (xy 375.2088 -270.340074) (xy 375.2088 -270.846042)
			(xy 376.148595 -270.846042) (xy 376.15269 -270.795314) (xy 376.164869 -270.7459) (xy 376.184817 -270.69908)
			(xy 376.212018 -270.656066) (xy 376.245766 -270.617972) (xy 376.285188 -270.585785) (xy 376.329262 -270.560339)
			(xy 376.376848 -270.542292) (xy 376.426712 -270.532112) (xy 376.477564 -270.530063) (xy 376.528085 -270.536197)
			(xy 376.576969 -270.550357) (xy 376.622948 -270.572174) (xy 376.664832 -270.601084) (xy 376.701536 -270.636339)
			(xy 376.732109 -270.677025) (xy 376.75576 -270.722088) (xy 376.771876 -270.770362) (xy 376.78004 -270.820596)
			(xy 376.780552 -270.846042) (xy 377.088649 -270.846042) (xy 377.092744 -270.795314) (xy 377.104923 -270.7459)
			(xy 377.124871 -270.69908) (xy 377.152072 -270.656066) (xy 377.18582 -270.617972) (xy 377.225242 -270.585785)
			(xy 377.269316 -270.560339) (xy 377.316902 -270.542292) (xy 377.366766 -270.532112) (xy 377.417618 -270.530063)
			(xy 377.468139 -270.536197) (xy 377.517023 -270.550357) (xy 377.563002 -270.572174) (xy 377.604886 -270.601084)
			(xy 377.64159 -270.636339) (xy 377.672163 -270.677025) (xy 377.695814 -270.722088) (xy 377.71193 -270.770362)
			(xy 377.720094 -270.820596) (xy 377.720606 -270.846042) (xy 378.968503 -270.846042) (xy 378.972598 -270.795314)
			(xy 378.984777 -270.7459) (xy 379.004725 -270.69908) (xy 379.031926 -270.656066) (xy 379.065674 -270.617972)
			(xy 379.105096 -270.585785) (xy 379.14917 -270.560339) (xy 379.196756 -270.542292) (xy 379.24662 -270.532112)
			(xy 379.297472 -270.530063) (xy 379.347993 -270.536197) (xy 379.396877 -270.550357) (xy 379.442856 -270.572174)
			(xy 379.48474 -270.601084) (xy 379.521444 -270.636339) (xy 379.552017 -270.677025) (xy 379.575668 -270.722088)
			(xy 379.591784 -270.770362) (xy 379.599948 -270.820596) (xy 379.60046 -270.846042) (xy 379.918988 -270.846042)
			(xy 379.922948 -270.796988) (xy 379.934725 -270.749204) (xy 379.954016 -270.703928) (xy 379.980319 -270.662332)
			(xy 380.012954 -270.625495) (xy 380.051075 -270.59437) (xy 380.093696 -270.569763) (xy 380.139712 -270.552311)
			(xy 380.187931 -270.542467) (xy 380.237106 -270.540486) (xy 380.285961 -270.546418) (xy 380.333232 -270.56011)
			(xy 380.377694 -270.581208) (xy 380.418197 -270.609164) (xy 380.45369 -270.643256) (xy 380.483255 -270.6826)
			(xy 380.506126 -270.726177) (xy 380.52171 -270.772858) (xy 380.529605 -270.821435) (xy 380.5301 -270.846042)
			(xy 380.848611 -270.846042) (xy 380.852706 -270.795314) (xy 380.864885 -270.7459) (xy 380.884833 -270.69908)
			(xy 380.912034 -270.656066) (xy 380.945782 -270.617972) (xy 380.985204 -270.585785) (xy 381.029278 -270.560339)
			(xy 381.076864 -270.542292) (xy 381.126728 -270.532112) (xy 381.17758 -270.530063) (xy 381.228101 -270.536197)
			(xy 381.276985 -270.550357) (xy 381.322964 -270.572174) (xy 381.364848 -270.601084) (xy 381.401552 -270.636339)
			(xy 381.432125 -270.677025) (xy 381.455776 -270.722088) (xy 381.471892 -270.770362) (xy 381.480056 -270.820596)
			(xy 381.480568 -270.846042) (xy 381.480056 -270.871488) (xy 381.471892 -270.921722) (xy 381.455776 -270.969996)
			(xy 381.432125 -271.015059) (xy 381.401552 -271.055745) (xy 381.364848 -271.091) (xy 381.322964 -271.11991)
			(xy 381.276985 -271.141727) (xy 381.228101 -271.155887) (xy 381.17758 -271.162021) (xy 381.126728 -271.159972)
			(xy 381.076864 -271.149792) (xy 381.029278 -271.131745) (xy 380.985204 -271.106299) (xy 380.945782 -271.074112)
			(xy 380.912034 -271.036018) (xy 380.884833 -270.993004) (xy 380.864885 -270.946184) (xy 380.852706 -270.89677)
			(xy 380.848611 -270.846042) (xy 380.5301 -270.846042) (xy 380.529605 -270.870649) (xy 380.52171 -270.919226)
			(xy 380.506126 -270.965907) (xy 380.483255 -271.009484) (xy 380.45369 -271.048828) (xy 380.418197 -271.08292)
			(xy 380.377694 -271.110876) (xy 380.333232 -271.131974) (xy 380.285961 -271.145666) (xy 380.237106 -271.151598)
			(xy 380.187931 -271.149617) (xy 380.139712 -271.139773) (xy 380.093696 -271.122321) (xy 380.051075 -271.097714)
			(xy 380.012954 -271.066589) (xy 379.980319 -271.029752) (xy 379.954016 -270.988156) (xy 379.934725 -270.94288)
			(xy 379.922948 -270.895096) (xy 379.918988 -270.846042) (xy 379.60046 -270.846042) (xy 379.599948 -270.871488)
			(xy 379.591784 -270.921722) (xy 379.575668 -270.969996) (xy 379.552017 -271.015059) (xy 379.521444 -271.055745)
			(xy 379.48474 -271.091) (xy 379.442856 -271.11991) (xy 379.396877 -271.141727) (xy 379.347993 -271.155887)
			(xy 379.297472 -271.162021) (xy 379.24662 -271.159972) (xy 379.196756 -271.149792) (xy 379.14917 -271.131745)
			(xy 379.105096 -271.106299) (xy 379.065674 -271.074112) (xy 379.031926 -271.036018) (xy 379.004725 -270.993004)
			(xy 378.984777 -270.946184) (xy 378.972598 -270.89677) (xy 378.968503 -270.846042) (xy 377.720606 -270.846042)
			(xy 377.720094 -270.871488) (xy 377.71193 -270.921722) (xy 377.695814 -270.969996) (xy 377.672163 -271.015059)
			(xy 377.64159 -271.055745) (xy 377.604886 -271.091) (xy 377.563002 -271.11991) (xy 377.517023 -271.141727)
			(xy 377.468139 -271.155887) (xy 377.417618 -271.162021) (xy 377.366766 -271.159972) (xy 377.316902 -271.149792)
			(xy 377.269316 -271.131745) (xy 377.225242 -271.106299) (xy 377.18582 -271.074112) (xy 377.152072 -271.036018)
			(xy 377.124871 -270.993004) (xy 377.104923 -270.946184) (xy 377.092744 -270.89677) (xy 377.088649 -270.846042)
			(xy 376.780552 -270.846042) (xy 376.78004 -270.871488) (xy 376.771876 -270.921722) (xy 376.75576 -270.969996)
			(xy 376.732109 -271.015059) (xy 376.701536 -271.055745) (xy 376.664832 -271.091) (xy 376.622948 -271.11991)
			(xy 376.576969 -271.141727) (xy 376.528085 -271.155887) (xy 376.477564 -271.162021) (xy 376.426712 -271.159972)
			(xy 376.376848 -271.149792) (xy 376.329262 -271.131745) (xy 376.285188 -271.106299) (xy 376.245766 -271.074112)
			(xy 376.212018 -271.036018) (xy 376.184817 -270.993004) (xy 376.164869 -270.946184) (xy 376.15269 -270.89677)
			(xy 376.148595 -270.846042) (xy 375.2088 -270.846042) (xy 375.2088 -271.35201) (xy 375.208963 -271.358021)
			(xy 375.211778 -271.369707) (xy 375.214388 -271.375124) (xy 375.224548 -271.394936) (xy 375.231152 -271.404842)
			(xy 375.234708 -271.408906) (xy 375.23928 -271.412462) (xy 375.239534 -271.412716) (xy 375.2596 -271.428622)
			(xy 375.294628 -271.465967) (xy 375.322941 -271.508628) (xy 375.343749 -271.55541) (xy 375.35647 -271.605007)
			(xy 375.360746 -271.656029) (xy 375.360744 -271.656048) (xy 375.678695 -271.656048) (xy 375.68279 -271.60532)
			(xy 375.694969 -271.555906) (xy 375.714917 -271.509086) (xy 375.742118 -271.466072) (xy 375.775866 -271.427978)
			(xy 375.815288 -271.395791) (xy 375.859362 -271.370345) (xy 375.906948 -271.352298) (xy 375.956812 -271.342118)
			(xy 376.007664 -271.340069) (xy 376.058185 -271.346203) (xy 376.107069 -271.360363) (xy 376.153048 -271.38218)
			(xy 376.194932 -271.41109) (xy 376.231636 -271.446345) (xy 376.262209 -271.487031) (xy 376.28586 -271.532094)
			(xy 376.301976 -271.580368) (xy 376.31014 -271.630602) (xy 376.310652 -271.656048) (xy 376.628926 -271.656048)
			(xy 376.632886 -271.606994) (xy 376.644663 -271.55921) (xy 376.663954 -271.513934) (xy 376.690257 -271.472338)
			(xy 376.722892 -271.435501) (xy 376.761013 -271.404376) (xy 376.803634 -271.379769) (xy 376.84965 -271.362317)
			(xy 376.897869 -271.352473) (xy 376.947044 -271.350492) (xy 376.995899 -271.356424) (xy 377.04317 -271.370116)
			(xy 377.087632 -271.391214) (xy 377.128135 -271.41917) (xy 377.163628 -271.453262) (xy 377.193193 -271.492606)
			(xy 377.216064 -271.536183) (xy 377.231648 -271.582864) (xy 377.239543 -271.631441) (xy 377.240038 -271.656048)
			(xy 377.558549 -271.656048) (xy 377.562644 -271.60532) (xy 377.574823 -271.555906) (xy 377.594771 -271.509086)
			(xy 377.621972 -271.466072) (xy 377.65572 -271.427978) (xy 377.695142 -271.395791) (xy 377.739216 -271.370345)
			(xy 377.786802 -271.352298) (xy 377.836666 -271.342118) (xy 377.887518 -271.340069) (xy 377.938039 -271.346203)
			(xy 377.986923 -271.360363) (xy 378.032902 -271.38218) (xy 378.074786 -271.41109) (xy 378.11149 -271.446345)
			(xy 378.142063 -271.487031) (xy 378.165714 -271.532094) (xy 378.18183 -271.580368) (xy 378.189994 -271.630602)
			(xy 378.190506 -271.656048) (xy 378.509034 -271.656048) (xy 378.512994 -271.606994) (xy 378.524771 -271.55921)
			(xy 378.544062 -271.513934) (xy 378.570365 -271.472338) (xy 378.603 -271.435501) (xy 378.641121 -271.404376)
			(xy 378.683742 -271.379769) (xy 378.729758 -271.362317) (xy 378.777977 -271.352473) (xy 378.827152 -271.350492)
			(xy 378.876007 -271.356424) (xy 378.923278 -271.370116) (xy 378.96774 -271.391214) (xy 379.008243 -271.41917)
			(xy 379.043736 -271.453262) (xy 379.073301 -271.492606) (xy 379.096172 -271.536183) (xy 379.111756 -271.582864)
			(xy 379.119651 -271.631441) (xy 379.120146 -271.656048) (xy 379.438657 -271.656048) (xy 379.442752 -271.60532)
			(xy 379.454931 -271.555906) (xy 379.474879 -271.509086) (xy 379.50208 -271.466072) (xy 379.535828 -271.427978)
			(xy 379.57525 -271.395791) (xy 379.619324 -271.370345) (xy 379.66691 -271.352298) (xy 379.716774 -271.342118)
			(xy 379.767626 -271.340069) (xy 379.818147 -271.346203) (xy 379.867031 -271.360363) (xy 379.91301 -271.38218)
			(xy 379.954894 -271.41109) (xy 379.991598 -271.446345) (xy 380.022171 -271.487031) (xy 380.045822 -271.532094)
			(xy 380.061938 -271.580368) (xy 380.070102 -271.630602) (xy 380.070614 -271.656048) (xy 380.378711 -271.656048)
			(xy 380.382806 -271.60532) (xy 380.394985 -271.555906) (xy 380.414933 -271.509086) (xy 380.442134 -271.466072)
			(xy 380.475882 -271.427978) (xy 380.515304 -271.395791) (xy 380.559378 -271.370345) (xy 380.606964 -271.352298)
			(xy 380.656828 -271.342118) (xy 380.70768 -271.340069) (xy 380.758201 -271.346203) (xy 380.807085 -271.360363)
			(xy 380.853064 -271.38218) (xy 380.894948 -271.41109) (xy 380.931652 -271.446345) (xy 380.962225 -271.487031)
			(xy 380.985876 -271.532094) (xy 381.001992 -271.580368) (xy 381.010156 -271.630602) (xy 381.010668 -271.656048)
			(xy 381.010156 -271.681494) (xy 381.001992 -271.731728) (xy 380.985876 -271.780002) (xy 380.962225 -271.825065)
			(xy 380.931652 -271.865751) (xy 380.894948 -271.901006) (xy 380.853064 -271.929916) (xy 380.807085 -271.951733)
			(xy 380.758201 -271.965893) (xy 380.70768 -271.972027) (xy 380.656828 -271.969978) (xy 380.606964 -271.959798)
			(xy 380.559378 -271.941751) (xy 380.515304 -271.916305) (xy 380.475882 -271.884118) (xy 380.442134 -271.846024)
			(xy 380.414933 -271.80301) (xy 380.394985 -271.75619) (xy 380.382806 -271.706776) (xy 380.378711 -271.656048)
			(xy 380.070614 -271.656048) (xy 380.070102 -271.681494) (xy 380.061938 -271.731728) (xy 380.045822 -271.780002)
			(xy 380.022171 -271.825065) (xy 379.991598 -271.865751) (xy 379.954894 -271.901006) (xy 379.91301 -271.929916)
			(xy 379.867031 -271.951733) (xy 379.818147 -271.965893) (xy 379.767626 -271.972027) (xy 379.716774 -271.969978)
			(xy 379.66691 -271.959798) (xy 379.619324 -271.941751) (xy 379.57525 -271.916305) (xy 379.535828 -271.884118)
			(xy 379.50208 -271.846024) (xy 379.474879 -271.80301) (xy 379.454931 -271.75619) (xy 379.442752 -271.706776)
			(xy 379.438657 -271.656048) (xy 379.120146 -271.656048) (xy 379.119651 -271.680655) (xy 379.111756 -271.729232)
			(xy 379.096172 -271.775913) (xy 379.073301 -271.81949) (xy 379.043736 -271.858834) (xy 379.008243 -271.892926)
			(xy 378.96774 -271.920882) (xy 378.923278 -271.94198) (xy 378.876007 -271.955672) (xy 378.827152 -271.961604)
			(xy 378.777977 -271.959623) (xy 378.729758 -271.949779) (xy 378.683742 -271.932327) (xy 378.641121 -271.90772)
			(xy 378.603 -271.876595) (xy 378.570365 -271.839758) (xy 378.544062 -271.798162) (xy 378.524771 -271.752886)
			(xy 378.512994 -271.705102) (xy 378.509034 -271.656048) (xy 378.190506 -271.656048) (xy 378.189994 -271.681494)
			(xy 378.18183 -271.731728) (xy 378.165714 -271.780002) (xy 378.142063 -271.825065) (xy 378.11149 -271.865751)
			(xy 378.074786 -271.901006) (xy 378.032902 -271.929916) (xy 377.986923 -271.951733) (xy 377.938039 -271.965893)
			(xy 377.887518 -271.972027) (xy 377.836666 -271.969978) (xy 377.786802 -271.959798) (xy 377.739216 -271.941751)
			(xy 377.695142 -271.916305) (xy 377.65572 -271.884118) (xy 377.621972 -271.846024) (xy 377.594771 -271.80301)
			(xy 377.574823 -271.75619) (xy 377.562644 -271.706776) (xy 377.558549 -271.656048) (xy 377.240038 -271.656048)
			(xy 377.239543 -271.680655) (xy 377.231648 -271.729232) (xy 377.216064 -271.775913) (xy 377.193193 -271.81949)
			(xy 377.163628 -271.858834) (xy 377.128135 -271.892926) (xy 377.087632 -271.920882) (xy 377.04317 -271.94198)
			(xy 376.995899 -271.955672) (xy 376.947044 -271.961604) (xy 376.897869 -271.959623) (xy 376.84965 -271.949779)
			(xy 376.803634 -271.932327) (xy 376.761013 -271.90772) (xy 376.722892 -271.876595) (xy 376.690257 -271.839758)
			(xy 376.663954 -271.798162) (xy 376.644663 -271.752886) (xy 376.632886 -271.705102) (xy 376.628926 -271.656048)
			(xy 376.310652 -271.656048) (xy 376.31014 -271.681494) (xy 376.301976 -271.731728) (xy 376.28586 -271.780002)
			(xy 376.262209 -271.825065) (xy 376.231636 -271.865751) (xy 376.194932 -271.901006) (xy 376.153048 -271.929916)
			(xy 376.107069 -271.951733) (xy 376.058185 -271.965893) (xy 376.007664 -271.972027) (xy 375.956812 -271.969978)
			(xy 375.906948 -271.959798) (xy 375.859362 -271.941751) (xy 375.815288 -271.916305) (xy 375.775866 -271.884118)
			(xy 375.742118 -271.846024) (xy 375.714917 -271.80301) (xy 375.694969 -271.75619) (xy 375.68279 -271.706776)
			(xy 375.678695 -271.656048) (xy 375.360744 -271.656048) (xy 375.35646 -271.707051) (xy 375.34373 -271.756644)
			(xy 375.322913 -271.803423) (xy 375.294592 -271.846078) (xy 375.259557 -271.883417) (xy 375.239534 -271.89938)
			(xy 375.23928 -271.899634) (xy 375.234708 -271.90319) (xy 375.231152 -271.907254) (xy 375.224548 -271.91716)
			(xy 375.214388 -271.936972) (xy 375.211808 -271.9424) (xy 375.208992 -271.954079) (xy 375.2088 -271.960086)
			(xy 375.2088 -272.119852) (xy 375.209395 -272.132474) (xy 375.221254 -272.154749) (xy 375.231406 -272.16227)
			(xy 375.2342 -272.164048) (xy 375.312432 -272.207736) (xy 375.320454 -272.211831) (xy 375.33823 -272.214651)
			(xy 375.355877 -272.211115) (xy 375.36374 -272.20672) (xy 375.363994 -272.206466) (xy 375.38835 -272.192158)
			(xy 375.441018 -272.171761) (xy 375.496536 -272.161384) (xy 375.524776 -272.160746) (xy 375.550039 -272.161237)
			(xy 375.599876 -272.16955) (xy 375.647665 -272.185952) (xy 375.692102 -272.209997) (xy 375.731975 -272.241029)
			(xy 375.766197 -272.278201) (xy 375.793833 -272.320498) (xy 375.81413 -272.366768) (xy 375.826533 -272.415747)
			(xy 375.830702 -272.466054) (xy 376.148595 -272.466054) (xy 376.15269 -272.415326) (xy 376.164869 -272.365912)
			(xy 376.184817 -272.319092) (xy 376.212018 -272.276078) (xy 376.245766 -272.237984) (xy 376.285188 -272.205797)
			(xy 376.329262 -272.180351) (xy 376.376848 -272.162304) (xy 376.426712 -272.152124) (xy 376.477564 -272.150075)
			(xy 376.528085 -272.156209) (xy 376.576969 -272.170369) (xy 376.622948 -272.192186) (xy 376.664832 -272.221096)
			(xy 376.701536 -272.256351) (xy 376.732109 -272.297037) (xy 376.75576 -272.3421) (xy 376.771876 -272.390374)
			(xy 376.78004 -272.440608) (xy 376.780552 -272.466054) (xy 377.088649 -272.466054) (xy 377.092744 -272.415326)
			(xy 377.104923 -272.365912) (xy 377.124871 -272.319092) (xy 377.152072 -272.276078) (xy 377.18582 -272.237984)
			(xy 377.225242 -272.205797) (xy 377.269316 -272.180351) (xy 377.316902 -272.162304) (xy 377.366766 -272.152124)
			(xy 377.417618 -272.150075) (xy 377.468139 -272.156209) (xy 377.517023 -272.170369) (xy 377.563002 -272.192186)
			(xy 377.604886 -272.221096) (xy 377.64159 -272.256351) (xy 377.672163 -272.297037) (xy 377.695814 -272.3421)
			(xy 377.71193 -272.390374) (xy 377.720094 -272.440608) (xy 377.720606 -272.466054) (xy 378.039134 -272.466054)
			(xy 378.043094 -272.417) (xy 378.054871 -272.369216) (xy 378.074162 -272.32394) (xy 378.100465 -272.282344)
			(xy 378.1331 -272.245507) (xy 378.171221 -272.214382) (xy 378.213842 -272.189775) (xy 378.259858 -272.172323)
			(xy 378.308077 -272.162479) (xy 378.357252 -272.160498) (xy 378.406107 -272.16643) (xy 378.453378 -272.180122)
			(xy 378.49784 -272.20122) (xy 378.538343 -272.229176) (xy 378.573836 -272.263268) (xy 378.603401 -272.302612)
			(xy 378.626272 -272.346189) (xy 378.641856 -272.39287) (xy 378.649751 -272.441447) (xy 378.650246 -272.466054)
			(xy 378.968503 -272.466054) (xy 378.972598 -272.415326) (xy 378.984777 -272.365912) (xy 379.004725 -272.319092)
			(xy 379.031926 -272.276078) (xy 379.065674 -272.237984) (xy 379.105096 -272.205797) (xy 379.14917 -272.180351)
			(xy 379.196756 -272.162304) (xy 379.24662 -272.152124) (xy 379.297472 -272.150075) (xy 379.347993 -272.156209)
			(xy 379.396877 -272.170369) (xy 379.442856 -272.192186) (xy 379.48474 -272.221096) (xy 379.521444 -272.256351)
			(xy 379.552017 -272.297037) (xy 379.575668 -272.3421) (xy 379.591784 -272.390374) (xy 379.599948 -272.440608)
			(xy 379.60046 -272.466054) (xy 379.918988 -272.466054) (xy 379.922948 -272.417) (xy 379.934725 -272.369216)
			(xy 379.954016 -272.32394) (xy 379.980319 -272.282344) (xy 380.012954 -272.245507) (xy 380.051075 -272.214382)
			(xy 380.093696 -272.189775) (xy 380.139712 -272.172323) (xy 380.187931 -272.162479) (xy 380.237106 -272.160498)
			(xy 380.285961 -272.16643) (xy 380.333232 -272.180122) (xy 380.377694 -272.20122) (xy 380.418197 -272.229176)
			(xy 380.45369 -272.263268) (xy 380.483255 -272.302612) (xy 380.506126 -272.346189) (xy 380.52171 -272.39287)
			(xy 380.529605 -272.441447) (xy 380.5301 -272.466054) (xy 380.848611 -272.466054) (xy 380.852706 -272.415326)
			(xy 380.864885 -272.365912) (xy 380.884833 -272.319092) (xy 380.912034 -272.276078) (xy 380.945782 -272.237984)
			(xy 380.985204 -272.205797) (xy 381.029278 -272.180351) (xy 381.076864 -272.162304) (xy 381.126728 -272.152124)
			(xy 381.17758 -272.150075) (xy 381.228101 -272.156209) (xy 381.276985 -272.170369) (xy 381.322964 -272.192186)
			(xy 381.364848 -272.221096) (xy 381.401552 -272.256351) (xy 381.432125 -272.297037) (xy 381.455776 -272.3421)
			(xy 381.471892 -272.390374) (xy 381.480056 -272.440608) (xy 381.480568 -272.466054) (xy 381.480056 -272.4915)
			(xy 381.471892 -272.541734) (xy 381.455776 -272.590008) (xy 381.432125 -272.635071) (xy 381.401552 -272.675757)
			(xy 381.364848 -272.711012) (xy 381.322964 -272.739922) (xy 381.276985 -272.761739) (xy 381.228101 -272.775899)
			(xy 381.17758 -272.782033) (xy 381.126728 -272.779984) (xy 381.076864 -272.769804) (xy 381.029278 -272.751757)
			(xy 380.985204 -272.726311) (xy 380.945782 -272.694124) (xy 380.912034 -272.65603) (xy 380.884833 -272.613016)
			(xy 380.864885 -272.566196) (xy 380.852706 -272.516782) (xy 380.848611 -272.466054) (xy 380.5301 -272.466054)
			(xy 380.529605 -272.490661) (xy 380.52171 -272.539238) (xy 380.506126 -272.585919) (xy 380.483255 -272.629496)
			(xy 380.45369 -272.66884) (xy 380.418197 -272.702932) (xy 380.377694 -272.730888) (xy 380.333232 -272.751986)
			(xy 380.285961 -272.765678) (xy 380.237106 -272.77161) (xy 380.187931 -272.769629) (xy 380.139712 -272.759785)
			(xy 380.093696 -272.742333) (xy 380.051075 -272.717726) (xy 380.012954 -272.686601) (xy 379.980319 -272.649764)
			(xy 379.954016 -272.608168) (xy 379.934725 -272.562892) (xy 379.922948 -272.515108) (xy 379.918988 -272.466054)
			(xy 379.60046 -272.466054) (xy 379.599948 -272.4915) (xy 379.591784 -272.541734) (xy 379.575668 -272.590008)
			(xy 379.552017 -272.635071) (xy 379.521444 -272.675757) (xy 379.48474 -272.711012) (xy 379.442856 -272.739922)
			(xy 379.396877 -272.761739) (xy 379.347993 -272.775899) (xy 379.297472 -272.782033) (xy 379.24662 -272.779984)
			(xy 379.196756 -272.769804) (xy 379.14917 -272.751757) (xy 379.105096 -272.726311) (xy 379.065674 -272.694124)
			(xy 379.031926 -272.65603) (xy 379.004725 -272.613016) (xy 378.984777 -272.566196) (xy 378.972598 -272.516782)
			(xy 378.968503 -272.466054) (xy 378.650246 -272.466054) (xy 378.649751 -272.490661) (xy 378.641856 -272.539238)
			(xy 378.626272 -272.585919) (xy 378.603401 -272.629496) (xy 378.573836 -272.66884) (xy 378.538343 -272.702932)
			(xy 378.49784 -272.730888) (xy 378.453378 -272.751986) (xy 378.406107 -272.765678) (xy 378.357252 -272.77161)
			(xy 378.308077 -272.769629) (xy 378.259858 -272.759785) (xy 378.213842 -272.742333) (xy 378.171221 -272.717726)
			(xy 378.1331 -272.686601) (xy 378.100465 -272.649764) (xy 378.074162 -272.608168) (xy 378.054871 -272.562892)
			(xy 378.043094 -272.515108) (xy 378.039134 -272.466054) (xy 377.720606 -272.466054) (xy 377.720094 -272.4915)
			(xy 377.71193 -272.541734) (xy 377.695814 -272.590008) (xy 377.672163 -272.635071) (xy 377.64159 -272.675757)
			(xy 377.604886 -272.711012) (xy 377.563002 -272.739922) (xy 377.517023 -272.761739) (xy 377.468139 -272.775899)
			(xy 377.417618 -272.782033) (xy 377.366766 -272.779984) (xy 377.316902 -272.769804) (xy 377.269316 -272.751757)
			(xy 377.225242 -272.726311) (xy 377.18582 -272.694124) (xy 377.152072 -272.65603) (xy 377.124871 -272.613016)
			(xy 377.104923 -272.566196) (xy 377.092744 -272.516782) (xy 377.088649 -272.466054) (xy 376.780552 -272.466054)
			(xy 376.78004 -272.4915) (xy 376.771876 -272.541734) (xy 376.75576 -272.590008) (xy 376.732109 -272.635071)
			(xy 376.701536 -272.675757) (xy 376.664832 -272.711012) (xy 376.622948 -272.739922) (xy 376.576969 -272.761739)
			(xy 376.528085 -272.775899) (xy 376.477564 -272.782033) (xy 376.426712 -272.779984) (xy 376.376848 -272.769804)
			(xy 376.329262 -272.751757) (xy 376.285188 -272.726311) (xy 376.245766 -272.694124) (xy 376.212018 -272.65603)
			(xy 376.184817 -272.613016) (xy 376.164869 -272.566196) (xy 376.15269 -272.516782) (xy 376.148595 -272.466054)
			(xy 375.830702 -272.466054) (xy 375.830706 -272.4661) (xy 375.826533 -272.516453) (xy 375.81413 -272.565432)
			(xy 375.793833 -272.611702) (xy 375.766197 -272.653999) (xy 375.731975 -272.691171) (xy 375.692102 -272.722203)
			(xy 375.647665 -272.746248) (xy 375.599876 -272.76265) (xy 375.550039 -272.770963) (xy 375.524776 -272.771362)
			(xy 375.496537 -272.770709) (xy 375.441022 -272.760333) (xy 375.388356 -272.739938) (xy 375.363994 -272.725642)
			(xy 375.36374 -272.725388) (xy 375.355871 -272.721025) (xy 375.33823 -272.717543) (xy 375.320464 -272.720318)
			(xy 375.312432 -272.724372) (xy 375.234962 -272.767552) (xy 375.234708 -272.767806) (xy 375.227065 -272.772526)
			(xy 375.215424 -272.786192) (xy 375.209189 -272.803027) (xy 375.2088 -272.812002) (xy 375.2088 -272.983706)
			(xy 375.210324 -272.996406) (xy 375.210578 -272.997422) (xy 375.213197 -273.005859) (xy 375.223188 -273.020416)
			(xy 375.230136 -273.02587) (xy 375.230644 -273.026378) (xy 375.230898 -273.026632) (xy 375.249396 -273.040172)
			(xy 375.282496 -273.071885) (xy 375.310483 -273.10819) (xy 375.332729 -273.148271) (xy 375.348732 -273.191227)
			(xy 375.353834 -273.213576) (xy 375.355358 -273.220942) (xy 375.358914 -273.2278) (xy 375.360714 -273.230912)
			(xy 375.365051 -273.236645) (xy 375.36755 -273.23923) (xy 375.40438 -273.27606) (xy 375.678695 -273.27606)
			(xy 375.68279 -273.225332) (xy 375.694969 -273.175918) (xy 375.714917 -273.129098) (xy 375.742118 -273.086084)
			(xy 375.775866 -273.04799) (xy 375.815288 -273.015803) (xy 375.859362 -272.990357) (xy 375.906948 -272.97231)
			(xy 375.956812 -272.96213) (xy 376.007664 -272.960081) (xy 376.058185 -272.966215) (xy 376.107069 -272.980375)
			(xy 376.153048 -273.002192) (xy 376.194932 -273.031102) (xy 376.231636 -273.066357) (xy 376.262209 -273.107043)
			(xy 376.28586 -273.152106) (xy 376.301976 -273.20038) (xy 376.31014 -273.250614) (xy 376.310652 -273.27606)
			(xy 376.628926 -273.27606) (xy 376.632886 -273.227006) (xy 376.644663 -273.179222) (xy 376.663954 -273.133946)
			(xy 376.690257 -273.09235) (xy 376.722892 -273.055513) (xy 376.761013 -273.024388) (xy 376.803634 -272.999781)
			(xy 376.84965 -272.982329) (xy 376.897869 -272.972485) (xy 376.947044 -272.970504) (xy 376.995899 -272.976436)
			(xy 377.04317 -272.990128) (xy 377.087632 -273.011226) (xy 377.128135 -273.039182) (xy 377.163628 -273.073274)
			(xy 377.193193 -273.112618) (xy 377.216064 -273.156195) (xy 377.231648 -273.202876) (xy 377.239543 -273.251453)
			(xy 377.240038 -273.27606) (xy 377.558549 -273.27606) (xy 377.562644 -273.225332) (xy 377.574823 -273.175918)
			(xy 377.594771 -273.129098) (xy 377.621972 -273.086084) (xy 377.65572 -273.04799) (xy 377.695142 -273.015803)
			(xy 377.739216 -272.990357) (xy 377.786802 -272.97231) (xy 377.836666 -272.96213) (xy 377.887518 -272.960081)
			(xy 377.938039 -272.966215) (xy 377.986923 -272.980375) (xy 378.032902 -273.002192) (xy 378.074786 -273.031102)
			(xy 378.11149 -273.066357) (xy 378.142063 -273.107043) (xy 378.165714 -273.152106) (xy 378.18183 -273.20038)
			(xy 378.189994 -273.250614) (xy 378.190506 -273.27606) (xy 379.438657 -273.27606) (xy 379.442752 -273.225332)
			(xy 379.454931 -273.175918) (xy 379.474879 -273.129098) (xy 379.50208 -273.086084) (xy 379.535828 -273.04799)
			(xy 379.57525 -273.015803) (xy 379.619324 -272.990357) (xy 379.66691 -272.97231) (xy 379.716774 -272.96213)
			(xy 379.767626 -272.960081) (xy 379.818147 -272.966215) (xy 379.867031 -272.980375) (xy 379.91301 -273.002192)
			(xy 379.954894 -273.031102) (xy 379.991598 -273.066357) (xy 380.022171 -273.107043) (xy 380.045822 -273.152106)
			(xy 380.061938 -273.20038) (xy 380.070102 -273.250614) (xy 380.070614 -273.27606) (xy 380.378711 -273.27606)
			(xy 380.382806 -273.225332) (xy 380.394985 -273.175918) (xy 380.414933 -273.129098) (xy 380.442134 -273.086084)
			(xy 380.475882 -273.04799) (xy 380.515304 -273.015803) (xy 380.559378 -272.990357) (xy 380.606964 -272.97231)
			(xy 380.656828 -272.96213) (xy 380.70768 -272.960081) (xy 380.758201 -272.966215) (xy 380.807085 -272.980375)
			(xy 380.853064 -273.002192) (xy 380.894948 -273.031102) (xy 380.931652 -273.066357) (xy 380.962225 -273.107043)
			(xy 380.985876 -273.152106) (xy 381.001992 -273.20038) (xy 381.010156 -273.250614) (xy 381.010668 -273.27606)
			(xy 381.010156 -273.301506) (xy 381.001992 -273.35174) (xy 380.985876 -273.400014) (xy 380.962225 -273.445077)
			(xy 380.931652 -273.485763) (xy 380.894948 -273.521018) (xy 380.853064 -273.549928) (xy 380.807085 -273.571745)
			(xy 380.758201 -273.585905) (xy 380.70768 -273.592039) (xy 380.656828 -273.58999) (xy 380.606964 -273.57981)
			(xy 380.559378 -273.561763) (xy 380.515304 -273.536317) (xy 380.475882 -273.50413) (xy 380.442134 -273.466036)
			(xy 380.414933 -273.423022) (xy 380.394985 -273.376202) (xy 380.382806 -273.326788) (xy 380.378711 -273.27606)
			(xy 380.070614 -273.27606) (xy 380.070102 -273.301506) (xy 380.061938 -273.35174) (xy 380.045822 -273.400014)
			(xy 380.022171 -273.445077) (xy 379.991598 -273.485763) (xy 379.954894 -273.521018) (xy 379.91301 -273.549928)
			(xy 379.867031 -273.571745) (xy 379.818147 -273.585905) (xy 379.767626 -273.592039) (xy 379.716774 -273.58999)
			(xy 379.66691 -273.57981) (xy 379.619324 -273.561763) (xy 379.57525 -273.536317) (xy 379.535828 -273.50413)
			(xy 379.50208 -273.466036) (xy 379.474879 -273.423022) (xy 379.454931 -273.376202) (xy 379.442752 -273.326788)
			(xy 379.438657 -273.27606) (xy 378.190506 -273.27606) (xy 378.189994 -273.301506) (xy 378.18183 -273.35174)
			(xy 378.165714 -273.400014) (xy 378.142063 -273.445077) (xy 378.11149 -273.485763) (xy 378.074786 -273.521018)
			(xy 378.032902 -273.549928) (xy 377.986923 -273.571745) (xy 377.938039 -273.585905) (xy 377.887518 -273.592039)
			(xy 377.836666 -273.58999) (xy 377.786802 -273.57981) (xy 377.739216 -273.561763) (xy 377.695142 -273.536317)
			(xy 377.65572 -273.50413) (xy 377.621972 -273.466036) (xy 377.594771 -273.423022) (xy 377.574823 -273.376202)
			(xy 377.562644 -273.326788) (xy 377.558549 -273.27606) (xy 377.240038 -273.27606) (xy 377.239543 -273.300667)
			(xy 377.231648 -273.349244) (xy 377.216064 -273.395925) (xy 377.193193 -273.439502) (xy 377.163628 -273.478846)
			(xy 377.128135 -273.512938) (xy 377.087632 -273.540894) (xy 377.04317 -273.561992) (xy 376.995899 -273.575684)
			(xy 376.947044 -273.581616) (xy 376.897869 -273.579635) (xy 376.84965 -273.569791) (xy 376.803634 -273.552339)
			(xy 376.761013 -273.527732) (xy 376.722892 -273.496607) (xy 376.690257 -273.45977) (xy 376.663954 -273.418174)
			(xy 376.644663 -273.372898) (xy 376.632886 -273.325114) (xy 376.628926 -273.27606) (xy 376.310652 -273.27606)
			(xy 376.31014 -273.301506) (xy 376.301976 -273.35174) (xy 376.28586 -273.400014) (xy 376.262209 -273.445077)
			(xy 376.231636 -273.485763) (xy 376.194932 -273.521018) (xy 376.153048 -273.549928) (xy 376.107069 -273.571745)
			(xy 376.058185 -273.585905) (xy 376.007664 -273.592039) (xy 375.956812 -273.58999) (xy 375.906948 -273.57981)
			(xy 375.859362 -273.561763) (xy 375.815288 -273.536317) (xy 375.775866 -273.50413) (xy 375.742118 -273.466036)
			(xy 375.714917 -273.423022) (xy 375.694969 -273.376202) (xy 375.68279 -273.326788) (xy 375.678695 -273.27606)
			(xy 375.40438 -273.27606) (xy 375.780554 -273.652234) (xy 375.7874 -273.659632) (xy 375.795129 -273.678231)
			(xy 375.79554 -273.688302) (xy 375.79554 -273.880834) (xy 375.79579 -273.888014) (xy 375.799793 -273.901806)
			(xy 375.803414 -273.908012) (xy 375.817455 -273.93094) (xy 375.838712 -273.98032) (xy 375.851696 -274.032489)
			(xy 375.856066 -274.086066) (xy 376.148595 -274.086066) (xy 376.15269 -274.035338) (xy 376.164869 -273.985924)
			(xy 376.184817 -273.939104) (xy 376.212018 -273.89609) (xy 376.245766 -273.857996) (xy 376.285188 -273.825809)
			(xy 376.329262 -273.800363) (xy 376.376848 -273.782316) (xy 376.426712 -273.772136) (xy 376.477564 -273.770087)
			(xy 376.528085 -273.776221) (xy 376.576969 -273.790381) (xy 376.622948 -273.812198) (xy 376.664832 -273.841108)
			(xy 376.701536 -273.876363) (xy 376.732109 -273.917049) (xy 376.75576 -273.962112) (xy 376.771876 -274.010386)
			(xy 376.78004 -274.06062) (xy 376.780552 -274.086066) (xy 377.088649 -274.086066) (xy 377.092744 -274.035338)
			(xy 377.104923 -273.985924) (xy 377.124871 -273.939104) (xy 377.152072 -273.89609) (xy 377.18582 -273.857996)
			(xy 377.225242 -273.825809) (xy 377.269316 -273.800363) (xy 377.316902 -273.782316) (xy 377.366766 -273.772136)
			(xy 377.417618 -273.770087) (xy 377.468139 -273.776221) (xy 377.517023 -273.790381) (xy 377.563002 -273.812198)
			(xy 377.604886 -273.841108) (xy 377.64159 -273.876363) (xy 377.672163 -273.917049) (xy 377.695814 -273.962112)
			(xy 377.71193 -274.010386) (xy 377.720094 -274.06062) (xy 377.720606 -274.086066) (xy 378.039134 -274.086066)
			(xy 378.043094 -274.037012) (xy 378.054871 -273.989228) (xy 378.074162 -273.943952) (xy 378.100465 -273.902356)
			(xy 378.1331 -273.865519) (xy 378.171221 -273.834394) (xy 378.213842 -273.809787) (xy 378.259858 -273.792335)
			(xy 378.308077 -273.782491) (xy 378.357252 -273.78051) (xy 378.406107 -273.786442) (xy 378.453378 -273.800134)
			(xy 378.49784 -273.821232) (xy 378.538343 -273.849188) (xy 378.573836 -273.88328) (xy 378.603401 -273.922624)
			(xy 378.626272 -273.966201) (xy 378.641856 -274.012882) (xy 378.649751 -274.061459) (xy 378.650246 -274.086066)
			(xy 378.968503 -274.086066) (xy 378.972598 -274.035338) (xy 378.984777 -273.985924) (xy 379.004725 -273.939104)
			(xy 379.031926 -273.89609) (xy 379.065674 -273.857996) (xy 379.105096 -273.825809) (xy 379.14917 -273.800363)
			(xy 379.196756 -273.782316) (xy 379.24662 -273.772136) (xy 379.297472 -273.770087) (xy 379.347993 -273.776221)
			(xy 379.396877 -273.790381) (xy 379.442856 -273.812198) (xy 379.48474 -273.841108) (xy 379.521444 -273.876363)
			(xy 379.552017 -273.917049) (xy 379.575668 -273.962112) (xy 379.591784 -274.010386) (xy 379.599948 -274.06062)
			(xy 379.60046 -274.086066) (xy 379.918988 -274.086066) (xy 379.922948 -274.037012) (xy 379.934725 -273.989228)
			(xy 379.954016 -273.943952) (xy 379.980319 -273.902356) (xy 380.012954 -273.865519) (xy 380.051075 -273.834394)
			(xy 380.093696 -273.809787) (xy 380.139712 -273.792335) (xy 380.187931 -273.782491) (xy 380.237106 -273.78051)
			(xy 380.285961 -273.786442) (xy 380.333232 -273.800134) (xy 380.377694 -273.821232) (xy 380.418197 -273.849188)
			(xy 380.45369 -273.88328) (xy 380.483255 -273.922624) (xy 380.506126 -273.966201) (xy 380.52171 -274.012882)
			(xy 380.529605 -274.061459) (xy 380.5301 -274.086066) (xy 380.848611 -274.086066) (xy 380.852706 -274.035338)
			(xy 380.864885 -273.985924) (xy 380.884833 -273.939104) (xy 380.912034 -273.89609) (xy 380.945782 -273.857996)
			(xy 380.985204 -273.825809) (xy 381.029278 -273.800363) (xy 381.076864 -273.782316) (xy 381.126728 -273.772136)
			(xy 381.17758 -273.770087) (xy 381.228101 -273.776221) (xy 381.276985 -273.790381) (xy 381.322964 -273.812198)
			(xy 381.364848 -273.841108) (xy 381.401552 -273.876363) (xy 381.432125 -273.917049) (xy 381.455776 -273.962112)
			(xy 381.471892 -274.010386) (xy 381.480056 -274.06062) (xy 381.480568 -274.086066) (xy 381.480056 -274.111512)
			(xy 381.471892 -274.161746) (xy 381.455776 -274.21002) (xy 381.432125 -274.255083) (xy 381.401552 -274.295769)
			(xy 381.364848 -274.331024) (xy 381.322964 -274.359934) (xy 381.276985 -274.381751) (xy 381.228101 -274.395911)
			(xy 381.17758 -274.402045) (xy 381.126728 -274.399996) (xy 381.076864 -274.389816) (xy 381.029278 -274.371769)
			(xy 380.985204 -274.346323) (xy 380.945782 -274.314136) (xy 380.912034 -274.276042) (xy 380.884833 -274.233028)
			(xy 380.864885 -274.186208) (xy 380.852706 -274.136794) (xy 380.848611 -274.086066) (xy 380.5301 -274.086066)
			(xy 380.529605 -274.110673) (xy 380.52171 -274.15925) (xy 380.506126 -274.205931) (xy 380.483255 -274.249508)
			(xy 380.45369 -274.288852) (xy 380.418197 -274.322944) (xy 380.377694 -274.3509) (xy 380.333232 -274.371998)
			(xy 380.285961 -274.38569) (xy 380.237106 -274.391622) (xy 380.187931 -274.389641) (xy 380.139712 -274.379797)
			(xy 380.093696 -274.362345) (xy 380.051075 -274.337738) (xy 380.012954 -274.306613) (xy 379.980319 -274.269776)
			(xy 379.954016 -274.22818) (xy 379.934725 -274.182904) (xy 379.922948 -274.13512) (xy 379.918988 -274.086066)
			(xy 379.60046 -274.086066) (xy 379.599948 -274.111512) (xy 379.591784 -274.161746) (xy 379.575668 -274.21002)
			(xy 379.552017 -274.255083) (xy 379.521444 -274.295769) (xy 379.48474 -274.331024) (xy 379.442856 -274.359934)
			(xy 379.396877 -274.381751) (xy 379.347993 -274.395911) (xy 379.297472 -274.402045) (xy 379.24662 -274.399996)
			(xy 379.196756 -274.389816) (xy 379.14917 -274.371769) (xy 379.105096 -274.346323) (xy 379.065674 -274.314136)
			(xy 379.031926 -274.276042) (xy 379.004725 -274.233028) (xy 378.984777 -274.186208) (xy 378.972598 -274.136794)
			(xy 378.968503 -274.086066) (xy 378.650246 -274.086066) (xy 378.649751 -274.110673) (xy 378.641856 -274.15925)
			(xy 378.626272 -274.205931) (xy 378.603401 -274.249508) (xy 378.573836 -274.288852) (xy 378.538343 -274.322944)
			(xy 378.49784 -274.3509) (xy 378.453378 -274.371998) (xy 378.406107 -274.38569) (xy 378.357252 -274.391622)
			(xy 378.308077 -274.389641) (xy 378.259858 -274.379797) (xy 378.213842 -274.362345) (xy 378.171221 -274.337738)
			(xy 378.1331 -274.306613) (xy 378.100465 -274.269776) (xy 378.074162 -274.22818) (xy 378.054871 -274.182904)
			(xy 378.043094 -274.13512) (xy 378.039134 -274.086066) (xy 377.720606 -274.086066) (xy 377.720094 -274.111512)
			(xy 377.71193 -274.161746) (xy 377.695814 -274.21002) (xy 377.672163 -274.255083) (xy 377.64159 -274.295769)
			(xy 377.604886 -274.331024) (xy 377.563002 -274.359934) (xy 377.517023 -274.381751) (xy 377.468139 -274.395911)
			(xy 377.417618 -274.402045) (xy 377.366766 -274.399996) (xy 377.316902 -274.389816) (xy 377.269316 -274.371769)
			(xy 377.225242 -274.346323) (xy 377.18582 -274.314136) (xy 377.152072 -274.276042) (xy 377.124871 -274.233028)
			(xy 377.104923 -274.186208) (xy 377.092744 -274.136794) (xy 377.088649 -274.086066) (xy 376.780552 -274.086066)
			(xy 376.78004 -274.111512) (xy 376.771876 -274.161746) (xy 376.75576 -274.21002) (xy 376.732109 -274.255083)
			(xy 376.701536 -274.295769) (xy 376.664832 -274.331024) (xy 376.622948 -274.359934) (xy 376.576969 -274.381751)
			(xy 376.528085 -274.395911) (xy 376.477564 -274.402045) (xy 376.426712 -274.399996) (xy 376.376848 -274.389816)
			(xy 376.329262 -274.371769) (xy 376.285188 -274.346323) (xy 376.245766 -274.314136) (xy 376.212018 -274.276042)
			(xy 376.184817 -274.233028) (xy 376.164869 -274.186208) (xy 376.15269 -274.136794) (xy 376.148595 -274.086066)
			(xy 375.856066 -274.086066) (xy 375.856066 -274.086071) (xy 375.851705 -274.139655) (xy 375.83873 -274.191826)
			(xy 375.817482 -274.241209) (xy 375.803414 -274.26412) (xy 375.799778 -274.270319) (xy 375.795774 -274.284115)
			(xy 375.79554 -274.291298) (xy 375.79554 -274.497038) (xy 375.797318 -274.507198) (xy 375.799446 -274.516136)
			(xy 375.809082 -274.531764) (xy 375.816114 -274.537678) (xy 375.887234 -274.593558) (xy 375.897648 -274.595844)
			(xy 375.921334 -274.588716) (xy 375.970199 -274.58106) (xy 375.99493 -274.580604) (xy 376.01972 -274.581092)
			(xy 376.06869 -274.588853) (xy 376.115843 -274.604177) (xy 376.160018 -274.62669) (xy 376.200128 -274.655835)
			(xy 376.235185 -274.690895) (xy 376.264326 -274.731008) (xy 376.286834 -274.775185) (xy 376.302154 -274.822339)
			(xy 376.30991 -274.87131) (xy 376.30991 -274.896072) (xy 376.628926 -274.896072) (xy 376.632886 -274.847018)
			(xy 376.644663 -274.799234) (xy 376.663954 -274.753958) (xy 376.690257 -274.712362) (xy 376.722892 -274.675525)
			(xy 376.761013 -274.6444) (xy 376.803634 -274.619793) (xy 376.84965 -274.602341) (xy 376.897869 -274.592497)
			(xy 376.947044 -274.590516) (xy 376.995899 -274.596448) (xy 377.04317 -274.61014) (xy 377.087632 -274.631238)
			(xy 377.128135 -274.659194) (xy 377.163628 -274.693286) (xy 377.193193 -274.73263) (xy 377.216064 -274.776207)
			(xy 377.231648 -274.822888) (xy 377.239543 -274.871465) (xy 377.240038 -274.896072) (xy 377.558549 -274.896072)
			(xy 377.562644 -274.845344) (xy 377.574823 -274.79593) (xy 377.594771 -274.74911) (xy 377.621972 -274.706096)
			(xy 377.65572 -274.668002) (xy 377.695142 -274.635815) (xy 377.739216 -274.610369) (xy 377.786802 -274.592322)
			(xy 377.836666 -274.582142) (xy 377.887518 -274.580093) (xy 377.938039 -274.586227) (xy 377.986923 -274.600387)
			(xy 378.032902 -274.622204) (xy 378.074786 -274.651114) (xy 378.11149 -274.686369) (xy 378.142063 -274.727055)
			(xy 378.165714 -274.772118) (xy 378.18183 -274.820392) (xy 378.189994 -274.870626) (xy 378.190506 -274.896072)
			(xy 378.509034 -274.896072) (xy 378.512994 -274.847018) (xy 378.524771 -274.799234) (xy 378.544062 -274.753958)
			(xy 378.570365 -274.712362) (xy 378.603 -274.675525) (xy 378.641121 -274.6444) (xy 378.683742 -274.619793)
			(xy 378.729758 -274.602341) (xy 378.777977 -274.592497) (xy 378.827152 -274.590516) (xy 378.876007 -274.596448)
			(xy 378.923278 -274.61014) (xy 378.96774 -274.631238) (xy 379.008243 -274.659194) (xy 379.043736 -274.693286)
			(xy 379.073301 -274.73263) (xy 379.096172 -274.776207) (xy 379.111756 -274.822888) (xy 379.119651 -274.871465)
			(xy 379.120146 -274.896072) (xy 379.438657 -274.896072) (xy 379.442752 -274.845344) (xy 379.454931 -274.79593)
			(xy 379.474879 -274.74911) (xy 379.50208 -274.706096) (xy 379.535828 -274.668002) (xy 379.57525 -274.635815)
			(xy 379.619324 -274.610369) (xy 379.66691 -274.592322) (xy 379.716774 -274.582142) (xy 379.767626 -274.580093)
			(xy 379.818147 -274.586227) (xy 379.867031 -274.600387) (xy 379.91301 -274.622204) (xy 379.954894 -274.651114)
			(xy 379.991598 -274.686369) (xy 380.022171 -274.727055) (xy 380.045822 -274.772118) (xy 380.061938 -274.820392)
			(xy 380.070102 -274.870626) (xy 380.070614 -274.896072) (xy 380.378711 -274.896072) (xy 380.382806 -274.845344)
			(xy 380.394985 -274.79593) (xy 380.414933 -274.74911) (xy 380.442134 -274.706096) (xy 380.475882 -274.668002)
			(xy 380.515304 -274.635815) (xy 380.559378 -274.610369) (xy 380.606964 -274.592322) (xy 380.656828 -274.582142)
			(xy 380.70768 -274.580093) (xy 380.758201 -274.586227) (xy 380.807085 -274.600387) (xy 380.853064 -274.622204)
			(xy 380.894948 -274.651114) (xy 380.931652 -274.686369) (xy 380.962225 -274.727055) (xy 380.985876 -274.772118)
			(xy 381.001992 -274.820392) (xy 381.010156 -274.870626) (xy 381.010668 -274.896072) (xy 381.010156 -274.921518)
			(xy 381.001992 -274.971752) (xy 380.985876 -275.020026) (xy 380.962225 -275.065089) (xy 380.931652 -275.105775)
			(xy 380.894948 -275.14103) (xy 380.853064 -275.16994) (xy 380.807085 -275.191757) (xy 380.758201 -275.205917)
			(xy 380.70768 -275.212051) (xy 380.656828 -275.210002) (xy 380.606964 -275.199822) (xy 380.559378 -275.181775)
			(xy 380.515304 -275.156329) (xy 380.475882 -275.124142) (xy 380.442134 -275.086048) (xy 380.414933 -275.043034)
			(xy 380.394985 -274.996214) (xy 380.382806 -274.9468) (xy 380.378711 -274.896072) (xy 380.070614 -274.896072)
			(xy 380.070102 -274.921518) (xy 380.061938 -274.971752) (xy 380.045822 -275.020026) (xy 380.022171 -275.065089)
			(xy 379.991598 -275.105775) (xy 379.954894 -275.14103) (xy 379.91301 -275.16994) (xy 379.867031 -275.191757)
			(xy 379.818147 -275.205917) (xy 379.767626 -275.212051) (xy 379.716774 -275.210002) (xy 379.66691 -275.199822)
			(xy 379.619324 -275.181775) (xy 379.57525 -275.156329) (xy 379.535828 -275.124142) (xy 379.50208 -275.086048)
			(xy 379.474879 -275.043034) (xy 379.454931 -274.996214) (xy 379.442752 -274.9468) (xy 379.438657 -274.896072)
			(xy 379.120146 -274.896072) (xy 379.119651 -274.920679) (xy 379.111756 -274.969256) (xy 379.096172 -275.015937)
			(xy 379.073301 -275.059514) (xy 379.043736 -275.098858) (xy 379.008243 -275.13295) (xy 378.96774 -275.160906)
			(xy 378.923278 -275.182004) (xy 378.876007 -275.195696) (xy 378.827152 -275.201628) (xy 378.777977 -275.199647)
			(xy 378.729758 -275.189803) (xy 378.683742 -275.172351) (xy 378.641121 -275.147744) (xy 378.603 -275.116619)
			(xy 378.570365 -275.079782) (xy 378.544062 -275.038186) (xy 378.524771 -274.99291) (xy 378.512994 -274.945126)
			(xy 378.509034 -274.896072) (xy 378.190506 -274.896072) (xy 378.189994 -274.921518) (xy 378.18183 -274.971752)
			(xy 378.165714 -275.020026) (xy 378.142063 -275.065089) (xy 378.11149 -275.105775) (xy 378.074786 -275.14103)
			(xy 378.032902 -275.16994) (xy 377.986923 -275.191757) (xy 377.938039 -275.205917) (xy 377.887518 -275.212051)
			(xy 377.836666 -275.210002) (xy 377.786802 -275.199822) (xy 377.739216 -275.181775) (xy 377.695142 -275.156329)
			(xy 377.65572 -275.124142) (xy 377.621972 -275.086048) (xy 377.594771 -275.043034) (xy 377.574823 -274.996214)
			(xy 377.562644 -274.9468) (xy 377.558549 -274.896072) (xy 377.240038 -274.896072) (xy 377.239543 -274.920679)
			(xy 377.231648 -274.969256) (xy 377.216064 -275.015937) (xy 377.193193 -275.059514) (xy 377.163628 -275.098858)
			(xy 377.128135 -275.13295) (xy 377.087632 -275.160906) (xy 377.04317 -275.182004) (xy 376.995899 -275.195696)
			(xy 376.947044 -275.201628) (xy 376.897869 -275.199647) (xy 376.84965 -275.189803) (xy 376.803634 -275.172351)
			(xy 376.761013 -275.147744) (xy 376.722892 -275.116619) (xy 376.690257 -275.079782) (xy 376.663954 -275.038186)
			(xy 376.644663 -274.99291) (xy 376.632886 -274.945126) (xy 376.628926 -274.896072) (xy 376.30991 -274.896072)
			(xy 376.30991 -274.92089) (xy 376.302154 -274.969861) (xy 376.286834 -275.017015) (xy 376.264326 -275.061192)
			(xy 376.235185 -275.101305) (xy 376.200128 -275.136365) (xy 376.160018 -275.16551) (xy 376.115843 -275.188023)
			(xy 376.06869 -275.203347) (xy 376.01972 -275.211108) (xy 375.99493 -275.21154) (xy 375.970195 -275.211128)
			(xy 375.921322 -275.203478) (xy 375.897648 -275.1963) (xy 375.887234 -275.198586) (xy 375.815098 -275.254974)
			(xy 375.809873 -275.259348) (xy 375.801761 -275.270292) (xy 375.799096 -275.276564) (xy 375.79554 -275.285708)
			(xy 375.79554 -275.559012) (xy 375.797826 -275.56968) (xy 375.800366 -275.575014) (xy 375.809712 -275.595587)
			(xy 375.822923 -275.6388) (xy 375.829633 -275.683485) (xy 375.830084 -275.706078) (xy 376.148595 -275.706078)
			(xy 376.15269 -275.65535) (xy 376.164869 -275.605936) (xy 376.184817 -275.559116) (xy 376.212018 -275.516102)
			(xy 376.245766 -275.478008) (xy 376.285188 -275.445821) (xy 376.329262 -275.420375) (xy 376.376848 -275.402328)
			(xy 376.426712 -275.392148) (xy 376.477564 -275.390099) (xy 376.528085 -275.396233) (xy 376.576969 -275.410393)
			(xy 376.622948 -275.43221) (xy 376.664832 -275.46112) (xy 376.701536 -275.496375) (xy 376.732109 -275.537061)
			(xy 376.75576 -275.582124) (xy 376.771876 -275.630398) (xy 376.78004 -275.680632) (xy 376.780552 -275.706078)
			(xy 377.088649 -275.706078) (xy 377.092744 -275.65535) (xy 377.104923 -275.605936) (xy 377.124871 -275.559116)
			(xy 377.152072 -275.516102) (xy 377.18582 -275.478008) (xy 377.225242 -275.445821) (xy 377.269316 -275.420375)
			(xy 377.316902 -275.402328) (xy 377.366766 -275.392148) (xy 377.417618 -275.390099) (xy 377.468139 -275.396233)
			(xy 377.517023 -275.410393) (xy 377.563002 -275.43221) (xy 377.604886 -275.46112) (xy 377.64159 -275.496375)
			(xy 377.672163 -275.537061) (xy 377.695814 -275.582124) (xy 377.71193 -275.630398) (xy 377.720094 -275.680632)
			(xy 377.720606 -275.706078) (xy 378.968503 -275.706078) (xy 378.972598 -275.65535) (xy 378.984777 -275.605936)
			(xy 379.004725 -275.559116) (xy 379.031926 -275.516102) (xy 379.065674 -275.478008) (xy 379.105096 -275.445821)
			(xy 379.14917 -275.420375) (xy 379.196756 -275.402328) (xy 379.24662 -275.392148) (xy 379.297472 -275.390099)
			(xy 379.347993 -275.396233) (xy 379.396877 -275.410393) (xy 379.442856 -275.43221) (xy 379.48474 -275.46112)
			(xy 379.521444 -275.496375) (xy 379.552017 -275.537061) (xy 379.575668 -275.582124) (xy 379.591784 -275.630398)
			(xy 379.599948 -275.680632) (xy 379.60046 -275.706078) (xy 379.918988 -275.706078) (xy 379.922948 -275.657024)
			(xy 379.934725 -275.60924) (xy 379.954016 -275.563964) (xy 379.980319 -275.522368) (xy 380.012954 -275.485531)
			(xy 380.051075 -275.454406) (xy 380.093696 -275.429799) (xy 380.139712 -275.412347) (xy 380.187931 -275.402503)
			(xy 380.237106 -275.400522) (xy 380.285961 -275.406454) (xy 380.333232 -275.420146) (xy 380.377694 -275.441244)
			(xy 380.418197 -275.4692) (xy 380.45369 -275.503292) (xy 380.483255 -275.542636) (xy 380.506126 -275.586213)
			(xy 380.52171 -275.632894) (xy 380.529605 -275.681471) (xy 380.5301 -275.706078) (xy 380.848611 -275.706078)
			(xy 380.852706 -275.65535) (xy 380.864885 -275.605936) (xy 380.884833 -275.559116) (xy 380.912034 -275.516102)
			(xy 380.945782 -275.478008) (xy 380.985204 -275.445821) (xy 381.029278 -275.420375) (xy 381.076864 -275.402328)
			(xy 381.126728 -275.392148) (xy 381.17758 -275.390099) (xy 381.228101 -275.396233) (xy 381.276985 -275.410393)
			(xy 381.322964 -275.43221) (xy 381.364848 -275.46112) (xy 381.401552 -275.496375) (xy 381.432125 -275.537061)
			(xy 381.455776 -275.582124) (xy 381.471892 -275.630398) (xy 381.480056 -275.680632) (xy 381.480568 -275.706078)
			(xy 381.480056 -275.731524) (xy 381.471892 -275.781758) (xy 381.455776 -275.830032) (xy 381.432125 -275.875095)
			(xy 381.401552 -275.915781) (xy 381.364848 -275.951036) (xy 381.322964 -275.979946) (xy 381.276985 -276.001763)
			(xy 381.228101 -276.015923) (xy 381.17758 -276.022057) (xy 381.126728 -276.020008) (xy 381.076864 -276.009828)
			(xy 381.029278 -275.991781) (xy 380.985204 -275.966335) (xy 380.945782 -275.934148) (xy 380.912034 -275.896054)
			(xy 380.884833 -275.85304) (xy 380.864885 -275.80622) (xy 380.852706 -275.756806) (xy 380.848611 -275.706078)
			(xy 380.5301 -275.706078) (xy 380.529605 -275.730685) (xy 380.52171 -275.779262) (xy 380.506126 -275.825943)
			(xy 380.483255 -275.86952) (xy 380.45369 -275.908864) (xy 380.418197 -275.942956) (xy 380.377694 -275.970912)
			(xy 380.333232 -275.99201) (xy 380.285961 -276.005702) (xy 380.237106 -276.011634) (xy 380.187931 -276.009653)
			(xy 380.139712 -275.999809) (xy 380.093696 -275.982357) (xy 380.051075 -275.95775) (xy 380.012954 -275.926625)
			(xy 379.980319 -275.889788) (xy 379.954016 -275.848192) (xy 379.934725 -275.802916) (xy 379.922948 -275.755132)
			(xy 379.918988 -275.706078) (xy 379.60046 -275.706078) (xy 379.599948 -275.731524) (xy 379.591784 -275.781758)
			(xy 379.575668 -275.830032) (xy 379.552017 -275.875095) (xy 379.521444 -275.915781) (xy 379.48474 -275.951036)
			(xy 379.442856 -275.979946) (xy 379.396877 -276.001763) (xy 379.347993 -276.015923) (xy 379.297472 -276.022057)
			(xy 379.24662 -276.020008) (xy 379.196756 -276.009828) (xy 379.14917 -275.991781) (xy 379.105096 -275.966335)
			(xy 379.065674 -275.934148) (xy 379.031926 -275.896054) (xy 379.004725 -275.85304) (xy 378.984777 -275.80622)
			(xy 378.972598 -275.756806) (xy 378.968503 -275.706078) (xy 377.720606 -275.706078) (xy 377.720094 -275.731524)
			(xy 377.71193 -275.781758) (xy 377.695814 -275.830032) (xy 377.672163 -275.875095) (xy 377.64159 -275.915781)
			(xy 377.604886 -275.951036) (xy 377.563002 -275.979946) (xy 377.517023 -276.001763) (xy 377.468139 -276.015923)
			(xy 377.417618 -276.022057) (xy 377.366766 -276.020008) (xy 377.316902 -276.009828) (xy 377.269316 -275.991781)
			(xy 377.225242 -275.966335) (xy 377.18582 -275.934148) (xy 377.152072 -275.896054) (xy 377.124871 -275.85304)
			(xy 377.104923 -275.80622) (xy 377.092744 -275.756806) (xy 377.088649 -275.706078) (xy 376.780552 -275.706078)
			(xy 376.78004 -275.731524) (xy 376.771876 -275.781758) (xy 376.75576 -275.830032) (xy 376.732109 -275.875095)
			(xy 376.701536 -275.915781) (xy 376.664832 -275.951036) (xy 376.622948 -275.979946) (xy 376.576969 -276.001763)
			(xy 376.528085 -276.015923) (xy 376.477564 -276.022057) (xy 376.426712 -276.020008) (xy 376.376848 -276.009828)
			(xy 376.329262 -275.991781) (xy 376.285188 -275.966335) (xy 376.245766 -275.934148) (xy 376.212018 -275.896054)
			(xy 376.184817 -275.85304) (xy 376.164869 -275.80622) (xy 376.15269 -275.756806) (xy 376.148595 -275.706078)
			(xy 375.830084 -275.706078) (xy 375.82966 -275.728673) (xy 375.822959 -275.773364) (xy 375.809731 -275.816575)
			(xy 375.800366 -275.837142) (xy 375.797826 -275.842476) (xy 375.79554 -275.853144) (xy 375.79554 -276.11705)
			(xy 375.797318 -276.12721) (xy 375.799448 -276.136147) (xy 375.809086 -276.151772) (xy 375.816114 -276.15769)
			(xy 375.887234 -276.21357) (xy 375.897648 -276.215856) (xy 375.921334 -276.208728) (xy 375.970199 -276.201072)
			(xy 375.99493 -276.200616) (xy 376.019719 -276.201104) (xy 376.068687 -276.208864) (xy 376.115838 -276.224189)
			(xy 376.160012 -276.2467) (xy 376.20012 -276.275844) (xy 376.235176 -276.310903) (xy 376.264316 -276.351014)
			(xy 376.286823 -276.39519) (xy 376.302143 -276.442342) (xy 376.309898 -276.491311) (xy 376.309898 -276.516084)
			(xy 376.628926 -276.516084) (xy 376.632886 -276.46703) (xy 376.644663 -276.419246) (xy 376.663954 -276.37397)
			(xy 376.690257 -276.332374) (xy 376.722892 -276.295537) (xy 376.761013 -276.264412) (xy 376.803634 -276.239805)
			(xy 376.84965 -276.222353) (xy 376.897869 -276.212509) (xy 376.947044 -276.210528) (xy 376.995899 -276.21646)
			(xy 377.04317 -276.230152) (xy 377.087632 -276.25125) (xy 377.128135 -276.279206) (xy 377.163628 -276.313298)
			(xy 377.193193 -276.352642) (xy 377.216064 -276.396219) (xy 377.231648 -276.4429) (xy 377.239543 -276.491477)
			(xy 377.240038 -276.516084) (xy 377.558549 -276.516084) (xy 377.562644 -276.465356) (xy 377.574823 -276.415942)
			(xy 377.594771 -276.369122) (xy 377.621972 -276.326108) (xy 377.65572 -276.288014) (xy 377.695142 -276.255827)
			(xy 377.739216 -276.230381) (xy 377.786802 -276.212334) (xy 377.836666 -276.202154) (xy 377.887518 -276.200105)
			(xy 377.938039 -276.206239) (xy 377.986923 -276.220399) (xy 378.032902 -276.242216) (xy 378.074786 -276.271126)
			(xy 378.11149 -276.306381) (xy 378.142063 -276.347067) (xy 378.165714 -276.39213) (xy 378.18183 -276.440404)
			(xy 378.189994 -276.490638) (xy 378.190506 -276.516084) (xy 378.509034 -276.516084) (xy 378.512994 -276.46703)
			(xy 378.524771 -276.419246) (xy 378.544062 -276.37397) (xy 378.570365 -276.332374) (xy 378.603 -276.295537)
			(xy 378.641121 -276.264412) (xy 378.683742 -276.239805) (xy 378.729758 -276.222353) (xy 378.777977 -276.212509)
			(xy 378.827152 -276.210528) (xy 378.876007 -276.21646) (xy 378.923278 -276.230152) (xy 378.96774 -276.25125)
			(xy 379.008243 -276.279206) (xy 379.043736 -276.313298) (xy 379.073301 -276.352642) (xy 379.096172 -276.396219)
			(xy 379.111756 -276.4429) (xy 379.119651 -276.491477) (xy 379.120146 -276.516084) (xy 379.438657 -276.516084)
			(xy 379.442752 -276.465356) (xy 379.454931 -276.415942) (xy 379.474879 -276.369122) (xy 379.50208 -276.326108)
			(xy 379.535828 -276.288014) (xy 379.57525 -276.255827) (xy 379.619324 -276.230381) (xy 379.66691 -276.212334)
			(xy 379.716774 -276.202154) (xy 379.767626 -276.200105) (xy 379.818147 -276.206239) (xy 379.867031 -276.220399)
			(xy 379.91301 -276.242216) (xy 379.954894 -276.271126) (xy 379.991598 -276.306381) (xy 380.022171 -276.347067)
			(xy 380.045822 -276.39213) (xy 380.061938 -276.440404) (xy 380.070102 -276.490638) (xy 380.070614 -276.516084)
			(xy 380.378711 -276.516084) (xy 380.382806 -276.465356) (xy 380.394985 -276.415942) (xy 380.414933 -276.369122)
			(xy 380.442134 -276.326108) (xy 380.475882 -276.288014) (xy 380.515304 -276.255827) (xy 380.559378 -276.230381)
			(xy 380.606964 -276.212334) (xy 380.656828 -276.202154) (xy 380.70768 -276.200105) (xy 380.758201 -276.206239)
			(xy 380.807085 -276.220399) (xy 380.853064 -276.242216) (xy 380.894948 -276.271126) (xy 380.931652 -276.306381)
			(xy 380.962225 -276.347067) (xy 380.985876 -276.39213) (xy 381.001992 -276.440404) (xy 381.010156 -276.490638)
			(xy 381.010668 -276.516084) (xy 381.010156 -276.54153) (xy 381.001992 -276.591764) (xy 380.985876 -276.640038)
			(xy 380.962225 -276.685101) (xy 380.931652 -276.725787) (xy 380.894948 -276.761042) (xy 380.853064 -276.789952)
			(xy 380.807085 -276.811769) (xy 380.758201 -276.825929) (xy 380.70768 -276.832063) (xy 380.656828 -276.830014)
			(xy 380.606964 -276.819834) (xy 380.559378 -276.801787) (xy 380.515304 -276.776341) (xy 380.475882 -276.744154)
			(xy 380.442134 -276.70606) (xy 380.414933 -276.663046) (xy 380.394985 -276.616226) (xy 380.382806 -276.566812)
			(xy 380.378711 -276.516084) (xy 380.070614 -276.516084) (xy 380.070102 -276.54153) (xy 380.061938 -276.591764)
			(xy 380.045822 -276.640038) (xy 380.022171 -276.685101) (xy 379.991598 -276.725787) (xy 379.954894 -276.761042)
			(xy 379.91301 -276.789952) (xy 379.867031 -276.811769) (xy 379.818147 -276.825929) (xy 379.767626 -276.832063)
			(xy 379.716774 -276.830014) (xy 379.66691 -276.819834) (xy 379.619324 -276.801787) (xy 379.57525 -276.776341)
			(xy 379.535828 -276.744154) (xy 379.50208 -276.70606) (xy 379.474879 -276.663046) (xy 379.454931 -276.616226)
			(xy 379.442752 -276.566812) (xy 379.438657 -276.516084) (xy 379.120146 -276.516084) (xy 379.119651 -276.540691)
			(xy 379.111756 -276.589268) (xy 379.096172 -276.635949) (xy 379.073301 -276.679526) (xy 379.043736 -276.71887)
			(xy 379.008243 -276.752962) (xy 378.96774 -276.780918) (xy 378.923278 -276.802016) (xy 378.876007 -276.815708)
			(xy 378.827152 -276.82164) (xy 378.777977 -276.819659) (xy 378.729758 -276.809815) (xy 378.683742 -276.792363)
			(xy 378.641121 -276.767756) (xy 378.603 -276.736631) (xy 378.570365 -276.699794) (xy 378.544062 -276.658198)
			(xy 378.524771 -276.612922) (xy 378.512994 -276.565138) (xy 378.509034 -276.516084) (xy 378.190506 -276.516084)
			(xy 378.189994 -276.54153) (xy 378.18183 -276.591764) (xy 378.165714 -276.640038) (xy 378.142063 -276.685101)
			(xy 378.11149 -276.725787) (xy 378.074786 -276.761042) (xy 378.032902 -276.789952) (xy 377.986923 -276.811769)
			(xy 377.938039 -276.825929) (xy 377.887518 -276.832063) (xy 377.836666 -276.830014) (xy 377.786802 -276.819834)
			(xy 377.739216 -276.801787) (xy 377.695142 -276.776341) (xy 377.65572 -276.744154) (xy 377.621972 -276.70606)
			(xy 377.594771 -276.663046) (xy 377.574823 -276.616226) (xy 377.562644 -276.566812) (xy 377.558549 -276.516084)
			(xy 377.240038 -276.516084) (xy 377.239543 -276.540691) (xy 377.231648 -276.589268) (xy 377.216064 -276.635949)
			(xy 377.193193 -276.679526) (xy 377.163628 -276.71887) (xy 377.128135 -276.752962) (xy 377.087632 -276.780918)
			(xy 377.04317 -276.802016) (xy 376.995899 -276.815708) (xy 376.947044 -276.82164) (xy 376.897869 -276.819659)
			(xy 376.84965 -276.809815) (xy 376.803634 -276.792363) (xy 376.761013 -276.767756) (xy 376.722892 -276.736631)
			(xy 376.690257 -276.699794) (xy 376.663954 -276.658198) (xy 376.644663 -276.612922) (xy 376.632886 -276.565138)
			(xy 376.628926 -276.516084) (xy 376.309898 -276.516084) (xy 376.309898 -276.540889) (xy 376.302143 -276.589858)
			(xy 376.286823 -276.63701) (xy 376.264316 -276.681186) (xy 376.235176 -276.721297) (xy 376.20012 -276.756356)
			(xy 376.160012 -276.7855) (xy 376.115838 -276.808011) (xy 376.068687 -276.823336) (xy 376.019719 -276.831096)
			(xy 375.99493 -276.831552) (xy 375.970195 -276.83114) (xy 375.921322 -276.82349) (xy 375.897648 -276.816312)
			(xy 375.887234 -276.818598) (xy 375.815098 -276.874986) (xy 375.809874 -276.879361) (xy 375.801765 -276.890306)
			(xy 375.799096 -276.896576) (xy 375.79554 -276.90572) (xy 375.79554 -277.120858) (xy 375.795793 -277.128037)
			(xy 375.799802 -277.141825) (xy 375.803414 -277.148036) (xy 375.817453 -277.170964) (xy 375.838706 -277.220343)
			(xy 375.851687 -277.272511) (xy 375.856053 -277.32609) (xy 376.148595 -277.32609) (xy 376.15269 -277.275362)
			(xy 376.164869 -277.225948) (xy 376.184817 -277.179128) (xy 376.212018 -277.136114) (xy 376.245766 -277.09802)
			(xy 376.285188 -277.065833) (xy 376.329262 -277.040387) (xy 376.376848 -277.02234) (xy 376.426712 -277.01216)
			(xy 376.477564 -277.010111) (xy 376.528085 -277.016245) (xy 376.576969 -277.030405) (xy 376.622948 -277.052222)
			(xy 376.664832 -277.081132) (xy 376.701536 -277.116387) (xy 376.732109 -277.157073) (xy 376.75576 -277.202136)
			(xy 376.771876 -277.25041) (xy 376.78004 -277.300644) (xy 376.780552 -277.32609) (xy 377.088649 -277.32609)
			(xy 377.092744 -277.275362) (xy 377.104923 -277.225948) (xy 377.124871 -277.179128) (xy 377.152072 -277.136114)
			(xy 377.18582 -277.09802) (xy 377.225242 -277.065833) (xy 377.269316 -277.040387) (xy 377.316902 -277.02234)
			(xy 377.366766 -277.01216) (xy 377.417618 -277.010111) (xy 377.468139 -277.016245) (xy 377.517023 -277.030405)
			(xy 377.563002 -277.052222) (xy 377.604886 -277.081132) (xy 377.64159 -277.116387) (xy 377.672163 -277.157073)
			(xy 377.695814 -277.202136) (xy 377.71193 -277.25041) (xy 377.720094 -277.300644) (xy 377.720606 -277.32609)
			(xy 378.039134 -277.32609) (xy 378.043094 -277.277036) (xy 378.054871 -277.229252) (xy 378.074162 -277.183976)
			(xy 378.100465 -277.14238) (xy 378.1331 -277.105543) (xy 378.171221 -277.074418) (xy 378.213842 -277.049811)
			(xy 378.259858 -277.032359) (xy 378.308077 -277.022515) (xy 378.357252 -277.020534) (xy 378.406107 -277.026466)
			(xy 378.453378 -277.040158) (xy 378.49784 -277.061256) (xy 378.538343 -277.089212) (xy 378.573836 -277.123304)
			(xy 378.603401 -277.162648) (xy 378.626272 -277.206225) (xy 378.641856 -277.252906) (xy 378.649751 -277.301483)
			(xy 378.650246 -277.32609) (xy 378.968503 -277.32609) (xy 378.972598 -277.275362) (xy 378.984777 -277.225948)
			(xy 379.004725 -277.179128) (xy 379.031926 -277.136114) (xy 379.065674 -277.09802) (xy 379.105096 -277.065833)
			(xy 379.14917 -277.040387) (xy 379.196756 -277.02234) (xy 379.24662 -277.01216) (xy 379.297472 -277.010111)
			(xy 379.347993 -277.016245) (xy 379.396877 -277.030405) (xy 379.442856 -277.052222) (xy 379.48474 -277.081132)
			(xy 379.521444 -277.116387) (xy 379.552017 -277.157073) (xy 379.575668 -277.202136) (xy 379.591784 -277.25041)
			(xy 379.599948 -277.300644) (xy 379.60046 -277.32609) (xy 379.918988 -277.32609) (xy 379.922948 -277.277036)
			(xy 379.934725 -277.229252) (xy 379.954016 -277.183976) (xy 379.980319 -277.14238) (xy 380.012954 -277.105543)
			(xy 380.051075 -277.074418) (xy 380.093696 -277.049811) (xy 380.139712 -277.032359) (xy 380.187931 -277.022515)
			(xy 380.237106 -277.020534) (xy 380.285961 -277.026466) (xy 380.333232 -277.040158) (xy 380.377694 -277.061256)
			(xy 380.418197 -277.089212) (xy 380.45369 -277.123304) (xy 380.483255 -277.162648) (xy 380.506126 -277.206225)
			(xy 380.52171 -277.252906) (xy 380.529605 -277.301483) (xy 380.5301 -277.32609) (xy 380.848611 -277.32609)
			(xy 380.852706 -277.275362) (xy 380.864885 -277.225948) (xy 380.884833 -277.179128) (xy 380.912034 -277.136114)
			(xy 380.945782 -277.09802) (xy 380.985204 -277.065833) (xy 381.029278 -277.040387) (xy 381.076864 -277.02234)
			(xy 381.126728 -277.01216) (xy 381.17758 -277.010111) (xy 381.228101 -277.016245) (xy 381.276985 -277.030405)
			(xy 381.322964 -277.052222) (xy 381.364848 -277.081132) (xy 381.401552 -277.116387) (xy 381.432125 -277.157073)
			(xy 381.455776 -277.202136) (xy 381.471892 -277.25041) (xy 381.480056 -277.300644) (xy 381.480568 -277.32609)
			(xy 381.480056 -277.351536) (xy 381.471892 -277.40177) (xy 381.455776 -277.450044) (xy 381.432125 -277.495107)
			(xy 381.401552 -277.535793) (xy 381.364848 -277.571048) (xy 381.322964 -277.599958) (xy 381.276985 -277.621775)
			(xy 381.228101 -277.635935) (xy 381.17758 -277.642069) (xy 381.126728 -277.64002) (xy 381.076864 -277.62984)
			(xy 381.029278 -277.611793) (xy 380.985204 -277.586347) (xy 380.945782 -277.55416) (xy 380.912034 -277.516066)
			(xy 380.884833 -277.473052) (xy 380.864885 -277.426232) (xy 380.852706 -277.376818) (xy 380.848611 -277.32609)
			(xy 380.5301 -277.32609) (xy 380.529605 -277.350697) (xy 380.52171 -277.399274) (xy 380.506126 -277.445955)
			(xy 380.483255 -277.489532) (xy 380.45369 -277.528876) (xy 380.418197 -277.562968) (xy 380.377694 -277.590924)
			(xy 380.333232 -277.612022) (xy 380.285961 -277.625714) (xy 380.237106 -277.631646) (xy 380.187931 -277.629665)
			(xy 380.139712 -277.619821) (xy 380.093696 -277.602369) (xy 380.051075 -277.577762) (xy 380.012954 -277.546637)
			(xy 379.980319 -277.5098) (xy 379.954016 -277.468204) (xy 379.934725 -277.422928) (xy 379.922948 -277.375144)
			(xy 379.918988 -277.32609) (xy 379.60046 -277.32609) (xy 379.599948 -277.351536) (xy 379.591784 -277.40177)
			(xy 379.575668 -277.450044) (xy 379.552017 -277.495107) (xy 379.521444 -277.535793) (xy 379.48474 -277.571048)
			(xy 379.442856 -277.599958) (xy 379.396877 -277.621775) (xy 379.347993 -277.635935) (xy 379.297472 -277.642069)
			(xy 379.24662 -277.64002) (xy 379.196756 -277.62984) (xy 379.14917 -277.611793) (xy 379.105096 -277.586347)
			(xy 379.065674 -277.55416) (xy 379.031926 -277.516066) (xy 379.004725 -277.473052) (xy 378.984777 -277.426232)
			(xy 378.972598 -277.376818) (xy 378.968503 -277.32609) (xy 378.650246 -277.32609) (xy 378.649751 -277.350697)
			(xy 378.641856 -277.399274) (xy 378.626272 -277.445955) (xy 378.603401 -277.489532) (xy 378.573836 -277.528876)
			(xy 378.538343 -277.562968) (xy 378.49784 -277.590924) (xy 378.453378 -277.612022) (xy 378.406107 -277.625714)
			(xy 378.357252 -277.631646) (xy 378.308077 -277.629665) (xy 378.259858 -277.619821) (xy 378.213842 -277.602369)
			(xy 378.171221 -277.577762) (xy 378.1331 -277.546637) (xy 378.100465 -277.5098) (xy 378.074162 -277.468204)
			(xy 378.054871 -277.422928) (xy 378.043094 -277.375144) (xy 378.039134 -277.32609) (xy 377.720606 -277.32609)
			(xy 377.720094 -277.351536) (xy 377.71193 -277.40177) (xy 377.695814 -277.450044) (xy 377.672163 -277.495107)
			(xy 377.64159 -277.535793) (xy 377.604886 -277.571048) (xy 377.563002 -277.599958) (xy 377.517023 -277.621775)
			(xy 377.468139 -277.635935) (xy 377.417618 -277.642069) (xy 377.366766 -277.64002) (xy 377.316902 -277.62984)
			(xy 377.269316 -277.611793) (xy 377.225242 -277.586347) (xy 377.18582 -277.55416) (xy 377.152072 -277.516066)
			(xy 377.124871 -277.473052) (xy 377.104923 -277.426232) (xy 377.092744 -277.376818) (xy 377.088649 -277.32609)
			(xy 376.780552 -277.32609) (xy 376.78004 -277.351536) (xy 376.771876 -277.40177) (xy 376.75576 -277.450044)
			(xy 376.732109 -277.495107) (xy 376.701536 -277.535793) (xy 376.664832 -277.571048) (xy 376.622948 -277.599958)
			(xy 376.576969 -277.621775) (xy 376.528085 -277.635935) (xy 376.477564 -277.642069) (xy 376.426712 -277.64002)
			(xy 376.376848 -277.62984) (xy 376.329262 -277.611793) (xy 376.285188 -277.586347) (xy 376.245766 -277.55416)
			(xy 376.212018 -277.516066) (xy 376.184817 -277.473052) (xy 376.164869 -277.426232) (xy 376.15269 -277.376818)
			(xy 376.148595 -277.32609) (xy 375.856053 -277.32609) (xy 375.856053 -277.326092) (xy 375.851689 -277.379673)
			(xy 375.838711 -277.431841) (xy 375.817461 -277.481221) (xy 375.803414 -277.504144) (xy 375.799781 -277.510344)
			(xy 375.795783 -277.52414) (xy 375.79554 -277.531322) (xy 375.79554 -277.737062) (xy 375.797318 -277.747222)
			(xy 375.79945 -277.756158) (xy 375.80909 -277.77178) (xy 375.816114 -277.777702) (xy 375.887234 -277.833582)
			(xy 375.897648 -277.835868) (xy 375.921334 -277.82874) (xy 375.970199 -277.821083) (xy 375.99493 -277.820628)
			(xy 376.019718 -277.821116) (xy 376.068684 -277.828876) (xy 376.115833 -277.8442) (xy 376.160005 -277.86671)
			(xy 376.200112 -277.895853) (xy 376.235167 -277.930911) (xy 376.264306 -277.97102) (xy 376.286812 -278.015194)
			(xy 376.302131 -278.062345) (xy 376.309886 -278.111312) (xy 376.309886 -278.136096) (xy 376.628926 -278.136096)
			(xy 376.632886 -278.087042) (xy 376.644663 -278.039258) (xy 376.663954 -277.993982) (xy 376.690257 -277.952386)
			(xy 376.722892 -277.915549) (xy 376.761013 -277.884424) (xy 376.803634 -277.859817) (xy 376.84965 -277.842365)
			(xy 376.897869 -277.832521) (xy 376.947044 -277.83054) (xy 376.995899 -277.836472) (xy 377.04317 -277.850164)
			(xy 377.087632 -277.871262) (xy 377.128135 -277.899218) (xy 377.163628 -277.93331) (xy 377.193193 -277.972654)
			(xy 377.216064 -278.016231) (xy 377.231648 -278.062912) (xy 377.239543 -278.111489) (xy 377.240038 -278.136096)
			(xy 377.558549 -278.136096) (xy 377.562644 -278.085368) (xy 377.574823 -278.035954) (xy 377.594771 -277.989134)
			(xy 377.621972 -277.94612) (xy 377.65572 -277.908026) (xy 377.695142 -277.875839) (xy 377.739216 -277.850393)
			(xy 377.786802 -277.832346) (xy 377.836666 -277.822166) (xy 377.887518 -277.820117) (xy 377.938039 -277.826251)
			(xy 377.986923 -277.840411) (xy 378.032902 -277.862228) (xy 378.074786 -277.891138) (xy 378.11149 -277.926393)
			(xy 378.142063 -277.967079) (xy 378.165714 -278.012142) (xy 378.18183 -278.060416) (xy 378.189994 -278.11065)
			(xy 378.190506 -278.136096) (xy 379.438657 -278.136096) (xy 379.442752 -278.085368) (xy 379.454931 -278.035954)
			(xy 379.474879 -277.989134) (xy 379.50208 -277.94612) (xy 379.535828 -277.908026) (xy 379.57525 -277.875839)
			(xy 379.619324 -277.850393) (xy 379.66691 -277.832346) (xy 379.716774 -277.822166) (xy 379.767626 -277.820117)
			(xy 379.818147 -277.826251) (xy 379.867031 -277.840411) (xy 379.91301 -277.862228) (xy 379.954894 -277.891138)
			(xy 379.991598 -277.926393) (xy 380.022171 -277.967079) (xy 380.045822 -278.012142) (xy 380.061938 -278.060416)
			(xy 380.070102 -278.11065) (xy 380.070614 -278.136096) (xy 380.378711 -278.136096) (xy 380.382806 -278.085368)
			(xy 380.394985 -278.035954) (xy 380.414933 -277.989134) (xy 380.442134 -277.94612) (xy 380.475882 -277.908026)
			(xy 380.515304 -277.875839) (xy 380.559378 -277.850393) (xy 380.606964 -277.832346) (xy 380.656828 -277.822166)
			(xy 380.70768 -277.820117) (xy 380.758201 -277.826251) (xy 380.807085 -277.840411) (xy 380.853064 -277.862228)
			(xy 380.894948 -277.891138) (xy 380.931652 -277.926393) (xy 380.962225 -277.967079) (xy 380.985876 -278.012142)
			(xy 381.001992 -278.060416) (xy 381.010156 -278.11065) (xy 381.010668 -278.136096) (xy 381.010156 -278.161542)
			(xy 381.001992 -278.211776) (xy 380.985876 -278.26005) (xy 380.962225 -278.305113) (xy 380.931652 -278.345799)
			(xy 380.894948 -278.381054) (xy 380.853064 -278.409964) (xy 380.807085 -278.431781) (xy 380.758201 -278.445941)
			(xy 380.70768 -278.452075) (xy 380.656828 -278.450026) (xy 380.606964 -278.439846) (xy 380.559378 -278.421799)
			(xy 380.515304 -278.396353) (xy 380.475882 -278.364166) (xy 380.442134 -278.326072) (xy 380.414933 -278.283058)
			(xy 380.394985 -278.236238) (xy 380.382806 -278.186824) (xy 380.378711 -278.136096) (xy 380.070614 -278.136096)
			(xy 380.070102 -278.161542) (xy 380.061938 -278.211776) (xy 380.045822 -278.26005) (xy 380.022171 -278.305113)
			(xy 379.991598 -278.345799) (xy 379.954894 -278.381054) (xy 379.91301 -278.409964) (xy 379.867031 -278.431781)
			(xy 379.818147 -278.445941) (xy 379.767626 -278.452075) (xy 379.716774 -278.450026) (xy 379.66691 -278.439846)
			(xy 379.619324 -278.421799) (xy 379.57525 -278.396353) (xy 379.535828 -278.364166) (xy 379.50208 -278.326072)
			(xy 379.474879 -278.283058) (xy 379.454931 -278.236238) (xy 379.442752 -278.186824) (xy 379.438657 -278.136096)
			(xy 378.190506 -278.136096) (xy 378.189994 -278.161542) (xy 378.18183 -278.211776) (xy 378.165714 -278.26005)
			(xy 378.142063 -278.305113) (xy 378.11149 -278.345799) (xy 378.074786 -278.381054) (xy 378.032902 -278.409964)
			(xy 377.986923 -278.431781) (xy 377.938039 -278.445941) (xy 377.887518 -278.452075) (xy 377.836666 -278.450026)
			(xy 377.786802 -278.439846) (xy 377.739216 -278.421799) (xy 377.695142 -278.396353) (xy 377.65572 -278.364166)
			(xy 377.621972 -278.326072) (xy 377.594771 -278.283058) (xy 377.574823 -278.236238) (xy 377.562644 -278.186824)
			(xy 377.558549 -278.136096) (xy 377.240038 -278.136096) (xy 377.239543 -278.160703) (xy 377.231648 -278.20928)
			(xy 377.216064 -278.255961) (xy 377.193193 -278.299538) (xy 377.163628 -278.338882) (xy 377.128135 -278.372974)
			(xy 377.087632 -278.40093) (xy 377.04317 -278.422028) (xy 376.995899 -278.43572) (xy 376.947044 -278.441652)
			(xy 376.897869 -278.439671) (xy 376.84965 -278.429827) (xy 376.803634 -278.412375) (xy 376.761013 -278.387768)
			(xy 376.722892 -278.356643) (xy 376.690257 -278.319806) (xy 376.663954 -278.27821) (xy 376.644663 -278.232934)
			(xy 376.632886 -278.18515) (xy 376.628926 -278.136096) (xy 376.309886 -278.136096) (xy 376.309886 -278.160888)
			(xy 376.302131 -278.209855) (xy 376.286812 -278.257006) (xy 376.264306 -278.30118) (xy 376.235167 -278.341289)
			(xy 376.200112 -278.376347) (xy 376.160005 -278.40549) (xy 376.115833 -278.428) (xy 376.068684 -278.443324)
			(xy 376.019718 -278.451084) (xy 375.99493 -278.451564) (xy 375.970195 -278.451151) (xy 375.921323 -278.443499)
			(xy 375.897648 -278.436324) (xy 375.887234 -278.43861) (xy 375.815098 -278.494998) (xy 375.809875 -278.499374)
			(xy 375.801768 -278.510319) (xy 375.799096 -278.516588) (xy 375.79554 -278.525732) (xy 375.79554 -278.799036)
			(xy 375.797826 -278.809704) (xy 375.800366 -278.815038) (xy 375.809717 -278.83561) (xy 375.822939 -278.878822)
			(xy 375.82966 -278.923508) (xy 375.830084 -278.946102) (xy 376.148595 -278.946102) (xy 376.15269 -278.895374)
			(xy 376.164869 -278.84596) (xy 376.184817 -278.79914) (xy 376.212018 -278.756126) (xy 376.245766 -278.718032)
			(xy 376.285188 -278.685845) (xy 376.329262 -278.660399) (xy 376.376848 -278.642352) (xy 376.426712 -278.632172)
			(xy 376.477564 -278.630123) (xy 376.528085 -278.636257) (xy 376.576969 -278.650417) (xy 376.622948 -278.672234)
			(xy 376.664832 -278.701144) (xy 376.701536 -278.736399) (xy 376.732109 -278.777085) (xy 376.75576 -278.822148)
			(xy 376.771876 -278.870422) (xy 376.78004 -278.920656) (xy 376.780552 -278.946102) (xy 377.088649 -278.946102)
			(xy 377.092744 -278.895374) (xy 377.104923 -278.84596) (xy 377.124871 -278.79914) (xy 377.152072 -278.756126)
			(xy 377.18582 -278.718032) (xy 377.225242 -278.685845) (xy 377.269316 -278.660399) (xy 377.316902 -278.642352)
			(xy 377.366766 -278.632172) (xy 377.417618 -278.630123) (xy 377.468139 -278.636257) (xy 377.517023 -278.650417)
			(xy 377.563002 -278.672234) (xy 377.604886 -278.701144) (xy 377.64159 -278.736399) (xy 377.672163 -278.777085)
			(xy 377.695814 -278.822148) (xy 377.71193 -278.870422) (xy 377.720094 -278.920656) (xy 377.720606 -278.946102)
			(xy 378.039134 -278.946102) (xy 378.043094 -278.897048) (xy 378.054871 -278.849264) (xy 378.074162 -278.803988)
			(xy 378.100465 -278.762392) (xy 378.1331 -278.725555) (xy 378.171221 -278.69443) (xy 378.213842 -278.669823)
			(xy 378.259858 -278.652371) (xy 378.308077 -278.642527) (xy 378.357252 -278.640546) (xy 378.406107 -278.646478)
			(xy 378.453378 -278.66017) (xy 378.49784 -278.681268) (xy 378.538343 -278.709224) (xy 378.573836 -278.743316)
			(xy 378.603401 -278.78266) (xy 378.626272 -278.826237) (xy 378.641856 -278.872918) (xy 378.649751 -278.921495)
			(xy 378.650246 -278.946102) (xy 378.968503 -278.946102) (xy 378.972598 -278.895374) (xy 378.984777 -278.84596)
			(xy 379.004725 -278.79914) (xy 379.031926 -278.756126) (xy 379.065674 -278.718032) (xy 379.105096 -278.685845)
			(xy 379.14917 -278.660399) (xy 379.196756 -278.642352) (xy 379.24662 -278.632172) (xy 379.297472 -278.630123)
			(xy 379.347993 -278.636257) (xy 379.396877 -278.650417) (xy 379.442856 -278.672234) (xy 379.48474 -278.701144)
			(xy 379.521444 -278.736399) (xy 379.552017 -278.777085) (xy 379.575668 -278.822148) (xy 379.591784 -278.870422)
			(xy 379.599948 -278.920656) (xy 379.60046 -278.946102) (xy 379.918988 -278.946102) (xy 379.922948 -278.897048)
			(xy 379.934725 -278.849264) (xy 379.954016 -278.803988) (xy 379.980319 -278.762392) (xy 380.012954 -278.725555)
			(xy 380.051075 -278.69443) (xy 380.093696 -278.669823) (xy 380.139712 -278.652371) (xy 380.187931 -278.642527)
			(xy 380.237106 -278.640546) (xy 380.285961 -278.646478) (xy 380.333232 -278.66017) (xy 380.377694 -278.681268)
			(xy 380.418197 -278.709224) (xy 380.45369 -278.743316) (xy 380.483255 -278.78266) (xy 380.506126 -278.826237)
			(xy 380.52171 -278.872918) (xy 380.529605 -278.921495) (xy 380.5301 -278.946102) (xy 380.848611 -278.946102)
			(xy 380.852706 -278.895374) (xy 380.864885 -278.84596) (xy 380.884833 -278.79914) (xy 380.912034 -278.756126)
			(xy 380.945782 -278.718032) (xy 380.985204 -278.685845) (xy 381.029278 -278.660399) (xy 381.076864 -278.642352)
			(xy 381.126728 -278.632172) (xy 381.17758 -278.630123) (xy 381.228101 -278.636257) (xy 381.276985 -278.650417)
			(xy 381.322964 -278.672234) (xy 381.364848 -278.701144) (xy 381.401552 -278.736399) (xy 381.432125 -278.777085)
			(xy 381.455776 -278.822148) (xy 381.471892 -278.870422) (xy 381.480056 -278.920656) (xy 381.480568 -278.946102)
			(xy 381.480056 -278.971548) (xy 381.471892 -279.021782) (xy 381.455776 -279.070056) (xy 381.432125 -279.115119)
			(xy 381.401552 -279.155805) (xy 381.364848 -279.19106) (xy 381.322964 -279.21997) (xy 381.276985 -279.241787)
			(xy 381.228101 -279.255947) (xy 381.17758 -279.262081) (xy 381.126728 -279.260032) (xy 381.076864 -279.249852)
			(xy 381.029278 -279.231805) (xy 380.985204 -279.206359) (xy 380.945782 -279.174172) (xy 380.912034 -279.136078)
			(xy 380.884833 -279.093064) (xy 380.864885 -279.046244) (xy 380.852706 -278.99683) (xy 380.848611 -278.946102)
			(xy 380.5301 -278.946102) (xy 380.529605 -278.970709) (xy 380.52171 -279.019286) (xy 380.506126 -279.065967)
			(xy 380.483255 -279.109544) (xy 380.45369 -279.148888) (xy 380.418197 -279.18298) (xy 380.377694 -279.210936)
			(xy 380.333232 -279.232034) (xy 380.285961 -279.245726) (xy 380.237106 -279.251658) (xy 380.187931 -279.249677)
			(xy 380.139712 -279.239833) (xy 380.093696 -279.222381) (xy 380.051075 -279.197774) (xy 380.012954 -279.166649)
			(xy 379.980319 -279.129812) (xy 379.954016 -279.088216) (xy 379.934725 -279.04294) (xy 379.922948 -278.995156)
			(xy 379.918988 -278.946102) (xy 379.60046 -278.946102) (xy 379.599948 -278.971548) (xy 379.591784 -279.021782)
			(xy 379.575668 -279.070056) (xy 379.552017 -279.115119) (xy 379.521444 -279.155805) (xy 379.48474 -279.19106)
			(xy 379.442856 -279.21997) (xy 379.396877 -279.241787) (xy 379.347993 -279.255947) (xy 379.297472 -279.262081)
			(xy 379.24662 -279.260032) (xy 379.196756 -279.249852) (xy 379.14917 -279.231805) (xy 379.105096 -279.206359)
			(xy 379.065674 -279.174172) (xy 379.031926 -279.136078) (xy 379.004725 -279.093064) (xy 378.984777 -279.046244)
			(xy 378.972598 -278.99683) (xy 378.968503 -278.946102) (xy 378.650246 -278.946102) (xy 378.649751 -278.970709)
			(xy 378.641856 -279.019286) (xy 378.626272 -279.065967) (xy 378.603401 -279.109544) (xy 378.573836 -279.148888)
			(xy 378.538343 -279.18298) (xy 378.49784 -279.210936) (xy 378.453378 -279.232034) (xy 378.406107 -279.245726)
			(xy 378.357252 -279.251658) (xy 378.308077 -279.249677) (xy 378.259858 -279.239833) (xy 378.213842 -279.222381)
			(xy 378.171221 -279.197774) (xy 378.1331 -279.166649) (xy 378.100465 -279.129812) (xy 378.074162 -279.088216)
			(xy 378.054871 -279.04294) (xy 378.043094 -278.995156) (xy 378.039134 -278.946102) (xy 377.720606 -278.946102)
			(xy 377.720094 -278.971548) (xy 377.71193 -279.021782) (xy 377.695814 -279.070056) (xy 377.672163 -279.115119)
			(xy 377.64159 -279.155805) (xy 377.604886 -279.19106) (xy 377.563002 -279.21997) (xy 377.517023 -279.241787)
			(xy 377.468139 -279.255947) (xy 377.417618 -279.262081) (xy 377.366766 -279.260032) (xy 377.316902 -279.249852)
			(xy 377.269316 -279.231805) (xy 377.225242 -279.206359) (xy 377.18582 -279.174172) (xy 377.152072 -279.136078)
			(xy 377.124871 -279.093064) (xy 377.104923 -279.046244) (xy 377.092744 -278.99683) (xy 377.088649 -278.946102)
			(xy 376.780552 -278.946102) (xy 376.78004 -278.971548) (xy 376.771876 -279.021782) (xy 376.75576 -279.070056)
			(xy 376.732109 -279.115119) (xy 376.701536 -279.155805) (xy 376.664832 -279.19106) (xy 376.622948 -279.21997)
			(xy 376.576969 -279.241787) (xy 376.528085 -279.255947) (xy 376.477564 -279.262081) (xy 376.426712 -279.260032)
			(xy 376.376848 -279.249852) (xy 376.329262 -279.231805) (xy 376.285188 -279.206359) (xy 376.245766 -279.174172)
			(xy 376.212018 -279.136078) (xy 376.184817 -279.093064) (xy 376.164869 -279.046244) (xy 376.15269 -278.99683)
			(xy 376.148595 -278.946102) (xy 375.830084 -278.946102) (xy 375.829658 -278.968697) (xy 375.822954 -279.013386)
			(xy 375.809723 -279.056595) (xy 375.800366 -279.077166) (xy 375.797826 -279.0825) (xy 375.79554 -279.093168)
			(xy 375.79554 -279.357074) (xy 375.797318 -279.367234) (xy 375.799451 -279.376169) (xy 375.809094 -279.391788)
			(xy 375.816114 -279.397714) (xy 375.887234 -279.453594) (xy 375.897648 -279.45588) (xy 375.921334 -279.448752)
			(xy 375.970199 -279.441094) (xy 375.99493 -279.44064) (xy 376.019717 -279.441129) (xy 376.068681 -279.448888)
			(xy 376.115829 -279.464211) (xy 376.159999 -279.486721) (xy 376.200104 -279.515862) (xy 376.235157 -279.550919)
			(xy 376.264295 -279.591027) (xy 376.2868 -279.635199) (xy 376.302119 -279.682348) (xy 376.309874 -279.731313)
			(xy 376.309874 -279.756108) (xy 376.628926 -279.756108) (xy 376.632886 -279.707054) (xy 376.644663 -279.65927)
			(xy 376.663954 -279.613994) (xy 376.690257 -279.572398) (xy 376.722892 -279.535561) (xy 376.761013 -279.504436)
			(xy 376.803634 -279.479829) (xy 376.84965 -279.462377) (xy 376.897869 -279.452533) (xy 376.947044 -279.450552)
			(xy 376.995899 -279.456484) (xy 377.04317 -279.470176) (xy 377.087632 -279.491274) (xy 377.128135 -279.51923)
			(xy 377.163628 -279.553322) (xy 377.193193 -279.592666) (xy 377.216064 -279.636243) (xy 377.231648 -279.682924)
			(xy 377.239543 -279.731501) (xy 377.240038 -279.756108) (xy 377.558549 -279.756108) (xy 377.562644 -279.70538)
			(xy 377.574823 -279.655966) (xy 377.594771 -279.609146) (xy 377.621972 -279.566132) (xy 377.65572 -279.528038)
			(xy 377.695142 -279.495851) (xy 377.739216 -279.470405) (xy 377.786802 -279.452358) (xy 377.836666 -279.442178)
			(xy 377.887518 -279.440129) (xy 377.938039 -279.446263) (xy 377.986923 -279.460423) (xy 378.032902 -279.48224)
			(xy 378.074786 -279.51115) (xy 378.11149 -279.546405) (xy 378.142063 -279.587091) (xy 378.165714 -279.632154)
			(xy 378.18183 -279.680428) (xy 378.189994 -279.730662) (xy 378.190506 -279.756108) (xy 378.509034 -279.756108)
			(xy 378.512994 -279.707054) (xy 378.524771 -279.65927) (xy 378.544062 -279.613994) (xy 378.570365 -279.572398)
			(xy 378.603 -279.535561) (xy 378.641121 -279.504436) (xy 378.683742 -279.479829) (xy 378.729758 -279.462377)
			(xy 378.777977 -279.452533) (xy 378.827152 -279.450552) (xy 378.876007 -279.456484) (xy 378.923278 -279.470176)
			(xy 378.96774 -279.491274) (xy 379.008243 -279.51923) (xy 379.043736 -279.553322) (xy 379.073301 -279.592666)
			(xy 379.096172 -279.636243) (xy 379.111756 -279.682924) (xy 379.119651 -279.731501) (xy 379.120146 -279.756108)
			(xy 379.438657 -279.756108) (xy 379.442752 -279.70538) (xy 379.454931 -279.655966) (xy 379.474879 -279.609146)
			(xy 379.50208 -279.566132) (xy 379.535828 -279.528038) (xy 379.57525 -279.495851) (xy 379.619324 -279.470405)
			(xy 379.66691 -279.452358) (xy 379.716774 -279.442178) (xy 379.767626 -279.440129) (xy 379.818147 -279.446263)
			(xy 379.867031 -279.460423) (xy 379.91301 -279.48224) (xy 379.954894 -279.51115) (xy 379.991598 -279.546405)
			(xy 380.022171 -279.587091) (xy 380.045822 -279.632154) (xy 380.061938 -279.680428) (xy 380.070102 -279.730662)
			(xy 380.070614 -279.756108) (xy 380.378711 -279.756108) (xy 380.382806 -279.70538) (xy 380.394985 -279.655966)
			(xy 380.414933 -279.609146) (xy 380.442134 -279.566132) (xy 380.475882 -279.528038) (xy 380.515304 -279.495851)
			(xy 380.559378 -279.470405) (xy 380.606964 -279.452358) (xy 380.656828 -279.442178) (xy 380.70768 -279.440129)
			(xy 380.758201 -279.446263) (xy 380.807085 -279.460423) (xy 380.853064 -279.48224) (xy 380.894948 -279.51115)
			(xy 380.931652 -279.546405) (xy 380.962225 -279.587091) (xy 380.985876 -279.632154) (xy 381.001992 -279.680428)
			(xy 381.010156 -279.730662) (xy 381.010668 -279.756108) (xy 381.010156 -279.781554) (xy 381.001992 -279.831788)
			(xy 380.985876 -279.880062) (xy 380.962225 -279.925125) (xy 380.931652 -279.965811) (xy 380.894948 -280.001066)
			(xy 380.853064 -280.029976) (xy 380.807085 -280.051793) (xy 380.758201 -280.065953) (xy 380.70768 -280.072087)
			(xy 380.656828 -280.070038) (xy 380.606964 -280.059858) (xy 380.559378 -280.041811) (xy 380.515304 -280.016365)
			(xy 380.475882 -279.984178) (xy 380.442134 -279.946084) (xy 380.414933 -279.90307) (xy 380.394985 -279.85625)
			(xy 380.382806 -279.806836) (xy 380.378711 -279.756108) (xy 380.070614 -279.756108) (xy 380.070102 -279.781554)
			(xy 380.061938 -279.831788) (xy 380.045822 -279.880062) (xy 380.022171 -279.925125) (xy 379.991598 -279.965811)
			(xy 379.954894 -280.001066) (xy 379.91301 -280.029976) (xy 379.867031 -280.051793) (xy 379.818147 -280.065953)
			(xy 379.767626 -280.072087) (xy 379.716774 -280.070038) (xy 379.66691 -280.059858) (xy 379.619324 -280.041811)
			(xy 379.57525 -280.016365) (xy 379.535828 -279.984178) (xy 379.50208 -279.946084) (xy 379.474879 -279.90307)
			(xy 379.454931 -279.85625) (xy 379.442752 -279.806836) (xy 379.438657 -279.756108) (xy 379.120146 -279.756108)
			(xy 379.119651 -279.780715) (xy 379.111756 -279.829292) (xy 379.096172 -279.875973) (xy 379.073301 -279.91955)
			(xy 379.043736 -279.958894) (xy 379.008243 -279.992986) (xy 378.96774 -280.020942) (xy 378.923278 -280.04204)
			(xy 378.876007 -280.055732) (xy 378.827152 -280.061664) (xy 378.777977 -280.059683) (xy 378.729758 -280.049839)
			(xy 378.683742 -280.032387) (xy 378.641121 -280.00778) (xy 378.603 -279.976655) (xy 378.570365 -279.939818)
			(xy 378.544062 -279.898222) (xy 378.524771 -279.852946) (xy 378.512994 -279.805162) (xy 378.509034 -279.756108)
			(xy 378.190506 -279.756108) (xy 378.189994 -279.781554) (xy 378.18183 -279.831788) (xy 378.165714 -279.880062)
			(xy 378.142063 -279.925125) (xy 378.11149 -279.965811) (xy 378.074786 -280.001066) (xy 378.032902 -280.029976)
			(xy 377.986923 -280.051793) (xy 377.938039 -280.065953) (xy 377.887518 -280.072087) (xy 377.836666 -280.070038)
			(xy 377.786802 -280.059858) (xy 377.739216 -280.041811) (xy 377.695142 -280.016365) (xy 377.65572 -279.984178)
			(xy 377.621972 -279.946084) (xy 377.594771 -279.90307) (xy 377.574823 -279.85625) (xy 377.562644 -279.806836)
			(xy 377.558549 -279.756108) (xy 377.240038 -279.756108) (xy 377.239543 -279.780715) (xy 377.231648 -279.829292)
			(xy 377.216064 -279.875973) (xy 377.193193 -279.91955) (xy 377.163628 -279.958894) (xy 377.128135 -279.992986)
			(xy 377.087632 -280.020942) (xy 377.04317 -280.04204) (xy 376.995899 -280.055732) (xy 376.947044 -280.061664)
			(xy 376.897869 -280.059683) (xy 376.84965 -280.049839) (xy 376.803634 -280.032387) (xy 376.761013 -280.00778)
			(xy 376.722892 -279.976655) (xy 376.690257 -279.939818) (xy 376.663954 -279.898222) (xy 376.644663 -279.852946)
			(xy 376.632886 -279.805162) (xy 376.628926 -279.756108) (xy 376.309874 -279.756108) (xy 376.309874 -279.780887)
			(xy 376.302119 -279.829852) (xy 376.2868 -279.877001) (xy 376.264295 -279.921173) (xy 376.235157 -279.961281)
			(xy 376.200104 -279.996338) (xy 376.159999 -280.025479) (xy 376.115829 -280.047989) (xy 376.068681 -280.063312)
			(xy 376.019717 -280.071071) (xy 375.99493 -280.071576) (xy 375.970195 -280.071163) (xy 375.921323 -280.063512)
			(xy 375.897648 -280.056336) (xy 375.887234 -280.058622) (xy 375.815098 -280.11501) (xy 375.809875 -280.119386)
			(xy 375.801771 -280.130333) (xy 375.799096 -280.1366) (xy 375.79554 -280.145744) (xy 375.79554 -280.419048)
			(xy 375.797826 -280.429716) (xy 375.800366 -280.43505) (xy 375.809717 -280.455623) (xy 375.822936 -280.498834)
			(xy 375.829655 -280.54352) (xy 375.830084 -280.566114) (xy 376.148595 -280.566114) (xy 376.15269 -280.515386)
			(xy 376.164869 -280.465972) (xy 376.184817 -280.419152) (xy 376.212018 -280.376138) (xy 376.245766 -280.338044)
			(xy 376.285188 -280.305857) (xy 376.329262 -280.280411) (xy 376.376848 -280.262364) (xy 376.426712 -280.252184)
			(xy 376.477564 -280.250135) (xy 376.528085 -280.256269) (xy 376.576969 -280.270429) (xy 376.622948 -280.292246)
			(xy 376.664832 -280.321156) (xy 376.701536 -280.356411) (xy 376.732109 -280.397097) (xy 376.75576 -280.44216)
			(xy 376.771876 -280.490434) (xy 376.78004 -280.540668) (xy 376.780552 -280.566114) (xy 377.088649 -280.566114)
			(xy 377.092744 -280.515386) (xy 377.104923 -280.465972) (xy 377.124871 -280.419152) (xy 377.152072 -280.376138)
			(xy 377.18582 -280.338044) (xy 377.225242 -280.305857) (xy 377.269316 -280.280411) (xy 377.316902 -280.262364)
			(xy 377.366766 -280.252184) (xy 377.417618 -280.250135) (xy 377.468139 -280.256269) (xy 377.517023 -280.270429)
			(xy 377.563002 -280.292246) (xy 377.604886 -280.321156) (xy 377.64159 -280.356411) (xy 377.672163 -280.397097)
			(xy 377.695814 -280.44216) (xy 377.71193 -280.490434) (xy 377.720094 -280.540668) (xy 377.720606 -280.566114)
			(xy 378.968503 -280.566114) (xy 378.972598 -280.515386) (xy 378.984777 -280.465972) (xy 379.004725 -280.419152)
			(xy 379.031926 -280.376138) (xy 379.065674 -280.338044) (xy 379.105096 -280.305857) (xy 379.14917 -280.280411)
			(xy 379.196756 -280.262364) (xy 379.24662 -280.252184) (xy 379.297472 -280.250135) (xy 379.347993 -280.256269)
			(xy 379.396877 -280.270429) (xy 379.442856 -280.292246) (xy 379.48474 -280.321156) (xy 379.521444 -280.356411)
			(xy 379.552017 -280.397097) (xy 379.575668 -280.44216) (xy 379.591784 -280.490434) (xy 379.599948 -280.540668)
			(xy 379.60046 -280.566114) (xy 379.918988 -280.566114) (xy 379.922948 -280.51706) (xy 379.934725 -280.469276)
			(xy 379.954016 -280.424) (xy 379.980319 -280.382404) (xy 380.012954 -280.345567) (xy 380.051075 -280.314442)
			(xy 380.093696 -280.289835) (xy 380.139712 -280.272383) (xy 380.187931 -280.262539) (xy 380.237106 -280.260558)
			(xy 380.285961 -280.26649) (xy 380.333232 -280.280182) (xy 380.377694 -280.30128) (xy 380.418197 -280.329236)
			(xy 380.45369 -280.363328) (xy 380.483255 -280.402672) (xy 380.506126 -280.446249) (xy 380.52171 -280.49293)
			(xy 380.529605 -280.541507) (xy 380.5301 -280.566114) (xy 380.848611 -280.566114) (xy 380.852706 -280.515386)
			(xy 380.864885 -280.465972) (xy 380.884833 -280.419152) (xy 380.912034 -280.376138) (xy 380.945782 -280.338044)
			(xy 380.985204 -280.305857) (xy 381.029278 -280.280411) (xy 381.076864 -280.262364) (xy 381.126728 -280.252184)
			(xy 381.17758 -280.250135) (xy 381.228101 -280.256269) (xy 381.276985 -280.270429) (xy 381.322964 -280.292246)
			(xy 381.364848 -280.321156) (xy 381.401552 -280.356411) (xy 381.432125 -280.397097) (xy 381.455776 -280.44216)
			(xy 381.471892 -280.490434) (xy 381.480056 -280.540668) (xy 381.480568 -280.566114) (xy 381.480056 -280.59156)
			(xy 381.471892 -280.641794) (xy 381.455776 -280.690068) (xy 381.432125 -280.735131) (xy 381.401552 -280.775817)
			(xy 381.364848 -280.811072) (xy 381.322964 -280.839982) (xy 381.276985 -280.861799) (xy 381.228101 -280.875959)
			(xy 381.17758 -280.882093) (xy 381.126728 -280.880044) (xy 381.076864 -280.869864) (xy 381.029278 -280.851817)
			(xy 380.985204 -280.826371) (xy 380.945782 -280.794184) (xy 380.912034 -280.75609) (xy 380.884833 -280.713076)
			(xy 380.864885 -280.666256) (xy 380.852706 -280.616842) (xy 380.848611 -280.566114) (xy 380.5301 -280.566114)
			(xy 380.529605 -280.590721) (xy 380.52171 -280.639298) (xy 380.506126 -280.685979) (xy 380.483255 -280.729556)
			(xy 380.45369 -280.7689) (xy 380.418197 -280.802992) (xy 380.377694 -280.830948) (xy 380.333232 -280.852046)
			(xy 380.285961 -280.865738) (xy 380.237106 -280.87167) (xy 380.187931 -280.869689) (xy 380.139712 -280.859845)
			(xy 380.093696 -280.842393) (xy 380.051075 -280.817786) (xy 380.012954 -280.786661) (xy 379.980319 -280.749824)
			(xy 379.954016 -280.708228) (xy 379.934725 -280.662952) (xy 379.922948 -280.615168) (xy 379.918988 -280.566114)
			(xy 379.60046 -280.566114) (xy 379.599948 -280.59156) (xy 379.591784 -280.641794) (xy 379.575668 -280.690068)
			(xy 379.552017 -280.735131) (xy 379.521444 -280.775817) (xy 379.48474 -280.811072) (xy 379.442856 -280.839982)
			(xy 379.396877 -280.861799) (xy 379.347993 -280.875959) (xy 379.297472 -280.882093) (xy 379.24662 -280.880044)
			(xy 379.196756 -280.869864) (xy 379.14917 -280.851817) (xy 379.105096 -280.826371) (xy 379.065674 -280.794184)
			(xy 379.031926 -280.75609) (xy 379.004725 -280.713076) (xy 378.984777 -280.666256) (xy 378.972598 -280.616842)
			(xy 378.968503 -280.566114) (xy 377.720606 -280.566114) (xy 377.720094 -280.59156) (xy 377.71193 -280.641794)
			(xy 377.695814 -280.690068) (xy 377.672163 -280.735131) (xy 377.64159 -280.775817) (xy 377.604886 -280.811072)
			(xy 377.563002 -280.839982) (xy 377.517023 -280.861799) (xy 377.468139 -280.875959) (xy 377.417618 -280.882093)
			(xy 377.366766 -280.880044) (xy 377.316902 -280.869864) (xy 377.269316 -280.851817) (xy 377.225242 -280.826371)
			(xy 377.18582 -280.794184) (xy 377.152072 -280.75609) (xy 377.124871 -280.713076) (xy 377.104923 -280.666256)
			(xy 377.092744 -280.616842) (xy 377.088649 -280.566114) (xy 376.780552 -280.566114) (xy 376.78004 -280.59156)
			(xy 376.771876 -280.641794) (xy 376.75576 -280.690068) (xy 376.732109 -280.735131) (xy 376.701536 -280.775817)
			(xy 376.664832 -280.811072) (xy 376.622948 -280.839982) (xy 376.576969 -280.861799) (xy 376.528085 -280.875959)
			(xy 376.477564 -280.882093) (xy 376.426712 -280.880044) (xy 376.376848 -280.869864) (xy 376.329262 -280.851817)
			(xy 376.285188 -280.826371) (xy 376.245766 -280.794184) (xy 376.212018 -280.75609) (xy 376.184817 -280.713076)
			(xy 376.164869 -280.666256) (xy 376.15269 -280.616842) (xy 376.148595 -280.566114) (xy 375.830084 -280.566114)
			(xy 375.829657 -280.588708) (xy 375.822951 -280.633397) (xy 375.809719 -280.676606) (xy 375.800366 -280.697178)
			(xy 375.797826 -280.702512) (xy 375.79554 -280.71318) (xy 375.79554 -280.977086) (xy 375.797318 -280.987246)
			(xy 375.799453 -280.99618) (xy 375.809098 -281.011796) (xy 375.816114 -281.017726) (xy 375.887234 -281.073606)
			(xy 375.897648 -281.075892) (xy 375.921334 -281.068765) (xy 375.970199 -281.06111) (xy 375.99493 -281.060652)
			(xy 376.019716 -281.061141) (xy 376.068679 -281.0689) (xy 376.115824 -281.084222) (xy 376.159992 -281.106731)
			(xy 376.200096 -281.135871) (xy 376.235148 -281.170927) (xy 376.264285 -281.211033) (xy 376.286789 -281.255204)
			(xy 376.302107 -281.302351) (xy 376.309862 -281.351313) (xy 376.309862 -281.37612) (xy 376.628926 -281.37612)
			(xy 376.632886 -281.327066) (xy 376.644663 -281.279282) (xy 376.663954 -281.234006) (xy 376.690257 -281.19241)
			(xy 376.722892 -281.155573) (xy 376.761013 -281.124448) (xy 376.803634 -281.099841) (xy 376.84965 -281.082389)
			(xy 376.897869 -281.072545) (xy 376.947044 -281.070564) (xy 376.995899 -281.076496) (xy 377.04317 -281.090188)
			(xy 377.087632 -281.111286) (xy 377.128135 -281.139242) (xy 377.163628 -281.173334) (xy 377.193193 -281.212678)
			(xy 377.216064 -281.256255) (xy 377.231648 -281.302936) (xy 377.239543 -281.351513) (xy 377.240038 -281.37612)
			(xy 377.558549 -281.37612) (xy 377.562644 -281.325392) (xy 377.574823 -281.275978) (xy 377.594771 -281.229158)
			(xy 377.621972 -281.186144) (xy 377.65572 -281.14805) (xy 377.695142 -281.115863) (xy 377.739216 -281.090417)
			(xy 377.786802 -281.07237) (xy 377.836666 -281.06219) (xy 377.887518 -281.060141) (xy 377.938039 -281.066275)
			(xy 377.986923 -281.080435) (xy 378.032902 -281.102252) (xy 378.074786 -281.131162) (xy 378.11149 -281.166417)
			(xy 378.142063 -281.207103) (xy 378.165714 -281.252166) (xy 378.18183 -281.30044) (xy 378.189994 -281.350674)
			(xy 378.190506 -281.37612) (xy 378.509034 -281.37612) (xy 378.512994 -281.327066) (xy 378.524771 -281.279282)
			(xy 378.544062 -281.234006) (xy 378.570365 -281.19241) (xy 378.603 -281.155573) (xy 378.641121 -281.124448)
			(xy 378.683742 -281.099841) (xy 378.729758 -281.082389) (xy 378.777977 -281.072545) (xy 378.827152 -281.070564)
			(xy 378.876007 -281.076496) (xy 378.923278 -281.090188) (xy 378.96774 -281.111286) (xy 379.008243 -281.139242)
			(xy 379.043736 -281.173334) (xy 379.073301 -281.212678) (xy 379.096172 -281.256255) (xy 379.111756 -281.302936)
			(xy 379.119651 -281.351513) (xy 379.120146 -281.37612) (xy 379.438657 -281.37612) (xy 379.442752 -281.325392)
			(xy 379.454931 -281.275978) (xy 379.474879 -281.229158) (xy 379.50208 -281.186144) (xy 379.535828 -281.14805)
			(xy 379.57525 -281.115863) (xy 379.619324 -281.090417) (xy 379.66691 -281.07237) (xy 379.716774 -281.06219)
			(xy 379.767626 -281.060141) (xy 379.818147 -281.066275) (xy 379.867031 -281.080435) (xy 379.91301 -281.102252)
			(xy 379.954894 -281.131162) (xy 379.991598 -281.166417) (xy 380.022171 -281.207103) (xy 380.045822 -281.252166)
			(xy 380.061938 -281.30044) (xy 380.070102 -281.350674) (xy 380.070614 -281.37612) (xy 380.378711 -281.37612)
			(xy 380.382806 -281.325392) (xy 380.394985 -281.275978) (xy 380.414933 -281.229158) (xy 380.442134 -281.186144)
			(xy 380.475882 -281.14805) (xy 380.515304 -281.115863) (xy 380.559378 -281.090417) (xy 380.606964 -281.07237)
			(xy 380.656828 -281.06219) (xy 380.70768 -281.060141) (xy 380.758201 -281.066275) (xy 380.807085 -281.080435)
			(xy 380.853064 -281.102252) (xy 380.894948 -281.131162) (xy 380.931652 -281.166417) (xy 380.962225 -281.207103)
			(xy 380.985876 -281.252166) (xy 381.001992 -281.30044) (xy 381.010156 -281.350674) (xy 381.010668 -281.37612)
			(xy 381.010156 -281.401566) (xy 381.001992 -281.4518) (xy 380.985876 -281.500074) (xy 380.962225 -281.545137)
			(xy 380.931652 -281.585823) (xy 380.894948 -281.621078) (xy 380.853064 -281.649988) (xy 380.807085 -281.671805)
			(xy 380.758201 -281.685965) (xy 380.70768 -281.692099) (xy 380.656828 -281.69005) (xy 380.606964 -281.67987)
			(xy 380.559378 -281.661823) (xy 380.515304 -281.636377) (xy 380.475882 -281.60419) (xy 380.442134 -281.566096)
			(xy 380.414933 -281.523082) (xy 380.394985 -281.476262) (xy 380.382806 -281.426848) (xy 380.378711 -281.37612)
			(xy 380.070614 -281.37612) (xy 380.070102 -281.401566) (xy 380.061938 -281.4518) (xy 380.045822 -281.500074)
			(xy 380.022171 -281.545137) (xy 379.991598 -281.585823) (xy 379.954894 -281.621078) (xy 379.91301 -281.649988)
			(xy 379.867031 -281.671805) (xy 379.818147 -281.685965) (xy 379.767626 -281.692099) (xy 379.716774 -281.69005)
			(xy 379.66691 -281.67987) (xy 379.619324 -281.661823) (xy 379.57525 -281.636377) (xy 379.535828 -281.60419)
			(xy 379.50208 -281.566096) (xy 379.474879 -281.523082) (xy 379.454931 -281.476262) (xy 379.442752 -281.426848)
			(xy 379.438657 -281.37612) (xy 379.120146 -281.37612) (xy 379.119651 -281.400727) (xy 379.111756 -281.449304)
			(xy 379.096172 -281.495985) (xy 379.073301 -281.539562) (xy 379.043736 -281.578906) (xy 379.008243 -281.612998)
			(xy 378.96774 -281.640954) (xy 378.923278 -281.662052) (xy 378.876007 -281.675744) (xy 378.827152 -281.681676)
			(xy 378.777977 -281.679695) (xy 378.729758 -281.669851) (xy 378.683742 -281.652399) (xy 378.641121 -281.627792)
			(xy 378.603 -281.596667) (xy 378.570365 -281.55983) (xy 378.544062 -281.518234) (xy 378.524771 -281.472958)
			(xy 378.512994 -281.425174) (xy 378.509034 -281.37612) (xy 378.190506 -281.37612) (xy 378.189994 -281.401566)
			(xy 378.18183 -281.4518) (xy 378.165714 -281.500074) (xy 378.142063 -281.545137) (xy 378.11149 -281.585823)
			(xy 378.074786 -281.621078) (xy 378.032902 -281.649988) (xy 377.986923 -281.671805) (xy 377.938039 -281.685965)
			(xy 377.887518 -281.692099) (xy 377.836666 -281.69005) (xy 377.786802 -281.67987) (xy 377.739216 -281.661823)
			(xy 377.695142 -281.636377) (xy 377.65572 -281.60419) (xy 377.621972 -281.566096) (xy 377.594771 -281.523082)
			(xy 377.574823 -281.476262) (xy 377.562644 -281.426848) (xy 377.558549 -281.37612) (xy 377.240038 -281.37612)
			(xy 377.239543 -281.400727) (xy 377.231648 -281.449304) (xy 377.216064 -281.495985) (xy 377.193193 -281.539562)
			(xy 377.163628 -281.578906) (xy 377.128135 -281.612998) (xy 377.087632 -281.640954) (xy 377.04317 -281.662052)
			(xy 376.995899 -281.675744) (xy 376.947044 -281.681676) (xy 376.897869 -281.679695) (xy 376.84965 -281.669851)
			(xy 376.803634 -281.652399) (xy 376.761013 -281.627792) (xy 376.722892 -281.596667) (xy 376.690257 -281.55983)
			(xy 376.663954 -281.518234) (xy 376.644663 -281.472958) (xy 376.632886 -281.425174) (xy 376.628926 -281.37612)
			(xy 376.309862 -281.37612) (xy 376.309862 -281.400887) (xy 376.302107 -281.449849) (xy 376.286789 -281.496996)
			(xy 376.264285 -281.541167) (xy 376.235148 -281.581273) (xy 376.200096 -281.616329) (xy 376.159992 -281.645469)
			(xy 376.115824 -281.667978) (xy 376.068679 -281.6833) (xy 376.019716 -281.691059) (xy 375.99493 -281.691588)
			(xy 375.970195 -281.691175) (xy 375.921322 -281.683524) (xy 375.897648 -281.676348) (xy 375.887234 -281.678634)
			(xy 375.815098 -281.735022) (xy 375.809876 -281.739399) (xy 375.801774 -281.750347) (xy 375.799096 -281.756612)
			(xy 375.79554 -281.765756) (xy 375.79554 -281.980894) (xy 375.795785 -281.988076) (xy 375.799779 -282.001873)
			(xy 375.803414 -282.008072) (xy 375.81745 -282.031) (xy 375.838697 -282.080378) (xy 375.851672 -282.132544)
			(xy 375.856033 -282.186122) (xy 375.856033 -282.186126) (xy 376.148595 -282.186126) (xy 376.15269 -282.135398)
			(xy 376.164869 -282.085984) (xy 376.184817 -282.039164) (xy 376.212018 -281.99615) (xy 376.245766 -281.958056)
			(xy 376.285188 -281.925869) (xy 376.329262 -281.900423) (xy 376.376848 -281.882376) (xy 376.426712 -281.872196)
			(xy 376.477564 -281.870147) (xy 376.528085 -281.876281) (xy 376.576969 -281.890441) (xy 376.622948 -281.912258)
			(xy 376.664832 -281.941168) (xy 376.701536 -281.976423) (xy 376.732109 -282.017109) (xy 376.75576 -282.062172)
			(xy 376.771876 -282.110446) (xy 376.78004 -282.16068) (xy 376.780552 -282.186126) (xy 377.088649 -282.186126)
			(xy 377.092744 -282.135398) (xy 377.104923 -282.085984) (xy 377.124871 -282.039164) (xy 377.152072 -281.99615)
			(xy 377.18582 -281.958056) (xy 377.225242 -281.925869) (xy 377.269316 -281.900423) (xy 377.316902 -281.882376)
			(xy 377.366766 -281.872196) (xy 377.417618 -281.870147) (xy 377.468139 -281.876281) (xy 377.517023 -281.890441)
			(xy 377.563002 -281.912258) (xy 377.604886 -281.941168) (xy 377.64159 -281.976423) (xy 377.672163 -282.017109)
			(xy 377.695814 -282.062172) (xy 377.71193 -282.110446) (xy 377.720094 -282.16068) (xy 377.720606 -282.186126)
			(xy 378.039134 -282.186126) (xy 378.043094 -282.137072) (xy 378.054871 -282.089288) (xy 378.074162 -282.044012)
			(xy 378.100465 -282.002416) (xy 378.1331 -281.965579) (xy 378.171221 -281.934454) (xy 378.213842 -281.909847)
			(xy 378.259858 -281.892395) (xy 378.308077 -281.882551) (xy 378.357252 -281.88057) (xy 378.406107 -281.886502)
			(xy 378.453378 -281.900194) (xy 378.49784 -281.921292) (xy 378.538343 -281.949248) (xy 378.573836 -281.98334)
			(xy 378.603401 -282.022684) (xy 378.626272 -282.066261) (xy 378.641856 -282.112942) (xy 378.649751 -282.161519)
			(xy 378.650246 -282.186126) (xy 378.968503 -282.186126) (xy 378.972598 -282.135398) (xy 378.984777 -282.085984)
			(xy 379.004725 -282.039164) (xy 379.031926 -281.99615) (xy 379.065674 -281.958056) (xy 379.105096 -281.925869)
			(xy 379.14917 -281.900423) (xy 379.196756 -281.882376) (xy 379.24662 -281.872196) (xy 379.297472 -281.870147)
			(xy 379.347993 -281.876281) (xy 379.396877 -281.890441) (xy 379.442856 -281.912258) (xy 379.48474 -281.941168)
			(xy 379.521444 -281.976423) (xy 379.552017 -282.017109) (xy 379.575668 -282.062172) (xy 379.591784 -282.110446)
			(xy 379.599948 -282.16068) (xy 379.60046 -282.186126) (xy 379.918988 -282.186126) (xy 379.922948 -282.137072)
			(xy 379.934725 -282.089288) (xy 379.954016 -282.044012) (xy 379.980319 -282.002416) (xy 380.012954 -281.965579)
			(xy 380.051075 -281.934454) (xy 380.093696 -281.909847) (xy 380.139712 -281.892395) (xy 380.187931 -281.882551)
			(xy 380.237106 -281.88057) (xy 380.285961 -281.886502) (xy 380.333232 -281.900194) (xy 380.377694 -281.921292)
			(xy 380.418197 -281.949248) (xy 380.45369 -281.98334) (xy 380.483255 -282.022684) (xy 380.506126 -282.066261)
			(xy 380.52171 -282.112942) (xy 380.529605 -282.161519) (xy 380.5301 -282.186126) (xy 380.848611 -282.186126)
			(xy 380.852706 -282.135398) (xy 380.864885 -282.085984) (xy 380.884833 -282.039164) (xy 380.912034 -281.99615)
			(xy 380.945782 -281.958056) (xy 380.985204 -281.925869) (xy 381.029278 -281.900423) (xy 381.076864 -281.882376)
			(xy 381.126728 -281.872196) (xy 381.17758 -281.870147) (xy 381.228101 -281.876281) (xy 381.276985 -281.890441)
			(xy 381.322964 -281.912258) (xy 381.364848 -281.941168) (xy 381.401552 -281.976423) (xy 381.432125 -282.017109)
			(xy 381.455776 -282.062172) (xy 381.471892 -282.110446) (xy 381.480056 -282.16068) (xy 381.480568 -282.186126)
			(xy 381.480056 -282.211572) (xy 381.471892 -282.261806) (xy 381.455776 -282.31008) (xy 381.432125 -282.355143)
			(xy 381.401552 -282.395829) (xy 381.364848 -282.431084) (xy 381.322964 -282.459994) (xy 381.276985 -282.481811)
			(xy 381.228101 -282.495971) (xy 381.17758 -282.502105) (xy 381.126728 -282.500056) (xy 381.076864 -282.489876)
			(xy 381.029278 -282.471829) (xy 380.985204 -282.446383) (xy 380.945782 -282.414196) (xy 380.912034 -282.376102)
			(xy 380.884833 -282.333088) (xy 380.864885 -282.286268) (xy 380.852706 -282.236854) (xy 380.848611 -282.186126)
			(xy 380.5301 -282.186126) (xy 380.529605 -282.210733) (xy 380.52171 -282.25931) (xy 380.506126 -282.305991)
			(xy 380.483255 -282.349568) (xy 380.45369 -282.388912) (xy 380.418197 -282.423004) (xy 380.377694 -282.45096)
			(xy 380.333232 -282.472058) (xy 380.285961 -282.48575) (xy 380.237106 -282.491682) (xy 380.187931 -282.489701)
			(xy 380.139712 -282.479857) (xy 380.093696 -282.462405) (xy 380.051075 -282.437798) (xy 380.012954 -282.406673)
			(xy 379.980319 -282.369836) (xy 379.954016 -282.32824) (xy 379.934725 -282.282964) (xy 379.922948 -282.23518)
			(xy 379.918988 -282.186126) (xy 379.60046 -282.186126) (xy 379.599948 -282.211572) (xy 379.591784 -282.261806)
			(xy 379.575668 -282.31008) (xy 379.552017 -282.355143) (xy 379.521444 -282.395829) (xy 379.48474 -282.431084)
			(xy 379.442856 -282.459994) (xy 379.396877 -282.481811) (xy 379.347993 -282.495971) (xy 379.297472 -282.502105)
			(xy 379.24662 -282.500056) (xy 379.196756 -282.489876) (xy 379.14917 -282.471829) (xy 379.105096 -282.446383)
			(xy 379.065674 -282.414196) (xy 379.031926 -282.376102) (xy 379.004725 -282.333088) (xy 378.984777 -282.286268)
			(xy 378.972598 -282.236854) (xy 378.968503 -282.186126) (xy 378.650246 -282.186126) (xy 378.649751 -282.210733)
			(xy 378.641856 -282.25931) (xy 378.626272 -282.305991) (xy 378.603401 -282.349568) (xy 378.573836 -282.388912)
			(xy 378.538343 -282.423004) (xy 378.49784 -282.45096) (xy 378.453378 -282.472058) (xy 378.406107 -282.48575)
			(xy 378.357252 -282.491682) (xy 378.308077 -282.489701) (xy 378.259858 -282.479857) (xy 378.213842 -282.462405)
			(xy 378.171221 -282.437798) (xy 378.1331 -282.406673) (xy 378.100465 -282.369836) (xy 378.074162 -282.32824)
			(xy 378.054871 -282.282964) (xy 378.043094 -282.23518) (xy 378.039134 -282.186126) (xy 377.720606 -282.186126)
			(xy 377.720094 -282.211572) (xy 377.71193 -282.261806) (xy 377.695814 -282.31008) (xy 377.672163 -282.355143)
			(xy 377.64159 -282.395829) (xy 377.604886 -282.431084) (xy 377.563002 -282.459994) (xy 377.517023 -282.481811)
			(xy 377.468139 -282.495971) (xy 377.417618 -282.502105) (xy 377.366766 -282.500056) (xy 377.316902 -282.489876)
			(xy 377.269316 -282.471829) (xy 377.225242 -282.446383) (xy 377.18582 -282.414196) (xy 377.152072 -282.376102)
			(xy 377.124871 -282.333088) (xy 377.104923 -282.286268) (xy 377.092744 -282.236854) (xy 377.088649 -282.186126)
			(xy 376.780552 -282.186126) (xy 376.78004 -282.211572) (xy 376.771876 -282.261806) (xy 376.75576 -282.31008)
			(xy 376.732109 -282.355143) (xy 376.701536 -282.395829) (xy 376.664832 -282.431084) (xy 376.622948 -282.459994)
			(xy 376.576969 -282.481811) (xy 376.528085 -282.495971) (xy 376.477564 -282.502105) (xy 376.426712 -282.500056)
			(xy 376.376848 -282.489876) (xy 376.329262 -282.471829) (xy 376.285188 -282.446383) (xy 376.245766 -282.414196)
			(xy 376.212018 -282.376102) (xy 376.184817 -282.333088) (xy 376.164869 -282.286268) (xy 376.15269 -282.236854)
			(xy 376.148595 -282.186126) (xy 375.856033 -282.186126) (xy 375.851665 -282.2397) (xy 375.838683 -282.291864)
			(xy 375.817429 -282.341239) (xy 375.803414 -282.36418) (xy 375.799785 -282.370381) (xy 375.795797 -282.384177)
			(xy 375.79554 -282.391358) (xy 375.79554 -282.597098) (xy 375.797318 -282.607258) (xy 375.799455 -282.616191)
			(xy 375.809102 -282.631804) (xy 375.816114 -282.637738) (xy 375.887234 -282.693618) (xy 375.897648 -282.695904)
			(xy 375.921334 -282.688777) (xy 375.970199 -282.681122) (xy 375.99493 -282.680664) (xy 376.019716 -282.681153)
			(xy 376.068676 -282.688911) (xy 376.11582 -282.704233) (xy 376.159986 -282.726741) (xy 376.200088 -282.755881)
			(xy 376.235139 -282.790934) (xy 376.264275 -282.831039) (xy 376.286778 -282.875208) (xy 376.302096 -282.922354)
			(xy 376.30985 -282.971314) (xy 376.30985 -282.996132) (xy 376.628926 -282.996132) (xy 376.632886 -282.947078)
			(xy 376.644663 -282.899294) (xy 376.663954 -282.854018) (xy 376.690257 -282.812422) (xy 376.722892 -282.775585)
			(xy 376.761013 -282.74446) (xy 376.803634 -282.719853) (xy 376.84965 -282.702401) (xy 376.897869 -282.692557)
			(xy 376.947044 -282.690576) (xy 376.995899 -282.696508) (xy 377.04317 -282.7102) (xy 377.087632 -282.731298)
			(xy 377.128135 -282.759254) (xy 377.163628 -282.793346) (xy 377.193193 -282.83269) (xy 377.216064 -282.876267)
			(xy 377.231648 -282.922948) (xy 377.239543 -282.971525) (xy 377.240038 -282.996132) (xy 377.558549 -282.996132)
			(xy 377.562644 -282.945404) (xy 377.574823 -282.89599) (xy 377.594771 -282.84917) (xy 377.621972 -282.806156)
			(xy 377.65572 -282.768062) (xy 377.695142 -282.735875) (xy 377.739216 -282.710429) (xy 377.786802 -282.692382)
			(xy 377.836666 -282.682202) (xy 377.887518 -282.680153) (xy 377.938039 -282.686287) (xy 377.986923 -282.700447)
			(xy 378.032902 -282.722264) (xy 378.074786 -282.751174) (xy 378.11149 -282.786429) (xy 378.142063 -282.827115)
			(xy 378.165714 -282.872178) (xy 378.18183 -282.920452) (xy 378.189994 -282.970686) (xy 378.190506 -282.996132)
			(xy 379.438657 -282.996132) (xy 379.442752 -282.945404) (xy 379.454931 -282.89599) (xy 379.474879 -282.84917)
			(xy 379.50208 -282.806156) (xy 379.535828 -282.768062) (xy 379.57525 -282.735875) (xy 379.619324 -282.710429)
			(xy 379.66691 -282.692382) (xy 379.716774 -282.682202) (xy 379.767626 -282.680153) (xy 379.818147 -282.686287)
			(xy 379.867031 -282.700447) (xy 379.91301 -282.722264) (xy 379.954894 -282.751174) (xy 379.991598 -282.786429)
			(xy 380.022171 -282.827115) (xy 380.045822 -282.872178) (xy 380.061938 -282.920452) (xy 380.070102 -282.970686)
			(xy 380.070614 -282.996132) (xy 380.378711 -282.996132) (xy 380.382806 -282.945404) (xy 380.394985 -282.89599)
			(xy 380.414933 -282.84917) (xy 380.442134 -282.806156) (xy 380.475882 -282.768062) (xy 380.515304 -282.735875)
			(xy 380.559378 -282.710429) (xy 380.606964 -282.692382) (xy 380.656828 -282.682202) (xy 380.70768 -282.680153)
			(xy 380.758201 -282.686287) (xy 380.807085 -282.700447) (xy 380.853064 -282.722264) (xy 380.894948 -282.751174)
			(xy 380.931652 -282.786429) (xy 380.962225 -282.827115) (xy 380.985876 -282.872178) (xy 381.001992 -282.920452)
			(xy 381.010156 -282.970686) (xy 381.010668 -282.996132) (xy 381.010156 -283.021578) (xy 381.001992 -283.071812)
			(xy 380.985876 -283.120086) (xy 380.962225 -283.165149) (xy 380.931652 -283.205835) (xy 380.894948 -283.24109)
			(xy 380.853064 -283.27) (xy 380.807085 -283.291817) (xy 380.758201 -283.305977) (xy 380.70768 -283.312111)
			(xy 380.656828 -283.310062) (xy 380.606964 -283.299882) (xy 380.559378 -283.281835) (xy 380.515304 -283.256389)
			(xy 380.475882 -283.224202) (xy 380.442134 -283.186108) (xy 380.414933 -283.143094) (xy 380.394985 -283.096274)
			(xy 380.382806 -283.04686) (xy 380.378711 -282.996132) (xy 380.070614 -282.996132) (xy 380.070102 -283.021578)
			(xy 380.061938 -283.071812) (xy 380.045822 -283.120086) (xy 380.022171 -283.165149) (xy 379.991598 -283.205835)
			(xy 379.954894 -283.24109) (xy 379.91301 -283.27) (xy 379.867031 -283.291817) (xy 379.818147 -283.305977)
			(xy 379.767626 -283.312111) (xy 379.716774 -283.310062) (xy 379.66691 -283.299882) (xy 379.619324 -283.281835)
			(xy 379.57525 -283.256389) (xy 379.535828 -283.224202) (xy 379.50208 -283.186108) (xy 379.474879 -283.143094)
			(xy 379.454931 -283.096274) (xy 379.442752 -283.04686) (xy 379.438657 -282.996132) (xy 378.190506 -282.996132)
			(xy 378.189994 -283.021578) (xy 378.18183 -283.071812) (xy 378.165714 -283.120086) (xy 378.142063 -283.165149)
			(xy 378.11149 -283.205835) (xy 378.074786 -283.24109) (xy 378.032902 -283.27) (xy 377.986923 -283.291817)
			(xy 377.938039 -283.305977) (xy 377.887518 -283.312111) (xy 377.836666 -283.310062) (xy 377.786802 -283.299882)
			(xy 377.739216 -283.281835) (xy 377.695142 -283.256389) (xy 377.65572 -283.224202) (xy 377.621972 -283.186108)
			(xy 377.594771 -283.143094) (xy 377.574823 -283.096274) (xy 377.562644 -283.04686) (xy 377.558549 -282.996132)
			(xy 377.240038 -282.996132) (xy 377.239543 -283.020739) (xy 377.231648 -283.069316) (xy 377.216064 -283.115997)
			(xy 377.193193 -283.159574) (xy 377.163628 -283.198918) (xy 377.128135 -283.23301) (xy 377.087632 -283.260966)
			(xy 377.04317 -283.282064) (xy 376.995899 -283.295756) (xy 376.947044 -283.301688) (xy 376.897869 -283.299707)
			(xy 376.84965 -283.289863) (xy 376.803634 -283.272411) (xy 376.761013 -283.247804) (xy 376.722892 -283.216679)
			(xy 376.690257 -283.179842) (xy 376.663954 -283.138246) (xy 376.644663 -283.09297) (xy 376.632886 -283.045186)
			(xy 376.628926 -282.996132) (xy 376.30985 -282.996132) (xy 376.30985 -283.020886) (xy 376.302096 -283.069846)
			(xy 376.286778 -283.116992) (xy 376.264275 -283.161161) (xy 376.235139 -283.201266) (xy 376.200088 -283.236319)
			(xy 376.159986 -283.265459) (xy 376.11582 -283.287967) (xy 376.068676 -283.303289) (xy 376.019716 -283.311047)
			(xy 375.99493 -283.3116) (xy 375.970195 -283.311187) (xy 375.921322 -283.303536) (xy 375.897648 -283.29636)
			(xy 375.887234 -283.298646) (xy 375.815098 -283.355034) (xy 375.809877 -283.359411) (xy 375.801778 -283.37036)
			(xy 375.799096 -283.376624) (xy 375.79554 -283.385768) (xy 375.79554 -283.659072) (xy 375.797826 -283.66974)
			(xy 375.800366 -283.675074) (xy 375.809715 -283.695647) (xy 375.822931 -283.738859) (xy 375.829647 -283.783545)
			(xy 375.830084 -283.806138) (xy 376.148595 -283.806138) (xy 376.15269 -283.75541) (xy 376.164869 -283.705996)
			(xy 376.184817 -283.659176) (xy 376.212018 -283.616162) (xy 376.245766 -283.578068) (xy 376.285188 -283.545881)
			(xy 376.329262 -283.520435) (xy 376.376848 -283.502388) (xy 376.426712 -283.492208) (xy 376.477564 -283.490159)
			(xy 376.528085 -283.496293) (xy 376.576969 -283.510453) (xy 376.622948 -283.53227) (xy 376.664832 -283.56118)
			(xy 376.701536 -283.596435) (xy 376.732109 -283.637121) (xy 376.75576 -283.682184) (xy 376.771876 -283.730458)
			(xy 376.78004 -283.780692) (xy 376.780552 -283.806138) (xy 377.088649 -283.806138) (xy 377.092744 -283.75541)
			(xy 377.104923 -283.705996) (xy 377.124871 -283.659176) (xy 377.152072 -283.616162) (xy 377.18582 -283.578068)
			(xy 377.225242 -283.545881) (xy 377.269316 -283.520435) (xy 377.316902 -283.502388) (xy 377.366766 -283.492208)
			(xy 377.417618 -283.490159) (xy 377.468139 -283.496293) (xy 377.517023 -283.510453) (xy 377.563002 -283.53227)
			(xy 377.604886 -283.56118) (xy 377.64159 -283.596435) (xy 377.672163 -283.637121) (xy 377.695814 -283.682184)
			(xy 377.71193 -283.730458) (xy 377.720094 -283.780692) (xy 377.720606 -283.806138) (xy 378.039134 -283.806138)
			(xy 378.043094 -283.757084) (xy 378.054871 -283.7093) (xy 378.074162 -283.664024) (xy 378.100465 -283.622428)
			(xy 378.1331 -283.585591) (xy 378.171221 -283.554466) (xy 378.213842 -283.529859) (xy 378.259858 -283.512407)
			(xy 378.308077 -283.502563) (xy 378.357252 -283.500582) (xy 378.406107 -283.506514) (xy 378.453378 -283.520206)
			(xy 378.49784 -283.541304) (xy 378.538343 -283.56926) (xy 378.573836 -283.603352) (xy 378.603401 -283.642696)
			(xy 378.626272 -283.686273) (xy 378.641856 -283.732954) (xy 378.649751 -283.781531) (xy 378.650246 -283.806138)
			(xy 378.968503 -283.806138) (xy 378.972598 -283.75541) (xy 378.984777 -283.705996) (xy 379.004725 -283.659176)
			(xy 379.031926 -283.616162) (xy 379.065674 -283.578068) (xy 379.105096 -283.545881) (xy 379.14917 -283.520435)
			(xy 379.196756 -283.502388) (xy 379.24662 -283.492208) (xy 379.297472 -283.490159) (xy 379.347993 -283.496293)
			(xy 379.396877 -283.510453) (xy 379.442856 -283.53227) (xy 379.48474 -283.56118) (xy 379.521444 -283.596435)
			(xy 379.552017 -283.637121) (xy 379.575668 -283.682184) (xy 379.591784 -283.730458) (xy 379.599948 -283.780692)
			(xy 379.60046 -283.806138) (xy 379.918988 -283.806138) (xy 379.922948 -283.757084) (xy 379.934725 -283.7093)
			(xy 379.954016 -283.664024) (xy 379.980319 -283.622428) (xy 380.012954 -283.585591) (xy 380.051075 -283.554466)
			(xy 380.093696 -283.529859) (xy 380.139712 -283.512407) (xy 380.187931 -283.502563) (xy 380.237106 -283.500582)
			(xy 380.285961 -283.506514) (xy 380.333232 -283.520206) (xy 380.377694 -283.541304) (xy 380.418197 -283.56926)
			(xy 380.45369 -283.603352) (xy 380.483255 -283.642696) (xy 380.506126 -283.686273) (xy 380.52171 -283.732954)
			(xy 380.529605 -283.781531) (xy 380.5301 -283.806138) (xy 380.848611 -283.806138) (xy 380.852706 -283.75541)
			(xy 380.864885 -283.705996) (xy 380.884833 -283.659176) (xy 380.912034 -283.616162) (xy 380.945782 -283.578068)
			(xy 380.985204 -283.545881) (xy 381.029278 -283.520435) (xy 381.076864 -283.502388) (xy 381.126728 -283.492208)
			(xy 381.17758 -283.490159) (xy 381.228101 -283.496293) (xy 381.276985 -283.510453) (xy 381.322964 -283.53227)
			(xy 381.364848 -283.56118) (xy 381.401552 -283.596435) (xy 381.432125 -283.637121) (xy 381.455776 -283.682184)
			(xy 381.471892 -283.730458) (xy 381.480056 -283.780692) (xy 381.480568 -283.806138) (xy 381.480056 -283.831584)
			(xy 381.471892 -283.881818) (xy 381.455776 -283.930092) (xy 381.432125 -283.975155) (xy 381.401552 -284.015841)
			(xy 381.364848 -284.051096) (xy 381.322964 -284.080006) (xy 381.276985 -284.101823) (xy 381.228101 -284.115983)
			(xy 381.17758 -284.122117) (xy 381.126728 -284.120068) (xy 381.076864 -284.109888) (xy 381.029278 -284.091841)
			(xy 380.985204 -284.066395) (xy 380.945782 -284.034208) (xy 380.912034 -283.996114) (xy 380.884833 -283.9531)
			(xy 380.864885 -283.90628) (xy 380.852706 -283.856866) (xy 380.848611 -283.806138) (xy 380.5301 -283.806138)
			(xy 380.529605 -283.830745) (xy 380.52171 -283.879322) (xy 380.506126 -283.926003) (xy 380.483255 -283.96958)
			(xy 380.45369 -284.008924) (xy 380.418197 -284.043016) (xy 380.377694 -284.070972) (xy 380.333232 -284.09207)
			(xy 380.285961 -284.105762) (xy 380.237106 -284.111694) (xy 380.187931 -284.109713) (xy 380.139712 -284.099869)
			(xy 380.093696 -284.082417) (xy 380.051075 -284.05781) (xy 380.012954 -284.026685) (xy 379.980319 -283.989848)
			(xy 379.954016 -283.948252) (xy 379.934725 -283.902976) (xy 379.922948 -283.855192) (xy 379.918988 -283.806138)
			(xy 379.60046 -283.806138) (xy 379.599948 -283.831584) (xy 379.591784 -283.881818) (xy 379.575668 -283.930092)
			(xy 379.552017 -283.975155) (xy 379.521444 -284.015841) (xy 379.48474 -284.051096) (xy 379.442856 -284.080006)
			(xy 379.396877 -284.101823) (xy 379.347993 -284.115983) (xy 379.297472 -284.122117) (xy 379.24662 -284.120068)
			(xy 379.196756 -284.109888) (xy 379.14917 -284.091841) (xy 379.105096 -284.066395) (xy 379.065674 -284.034208)
			(xy 379.031926 -283.996114) (xy 379.004725 -283.9531) (xy 378.984777 -283.90628) (xy 378.972598 -283.856866)
			(xy 378.968503 -283.806138) (xy 378.650246 -283.806138) (xy 378.649751 -283.830745) (xy 378.641856 -283.879322)
			(xy 378.626272 -283.926003) (xy 378.603401 -283.96958) (xy 378.573836 -284.008924) (xy 378.538343 -284.043016)
			(xy 378.49784 -284.070972) (xy 378.453378 -284.09207) (xy 378.406107 -284.105762) (xy 378.357252 -284.111694)
			(xy 378.308077 -284.109713) (xy 378.259858 -284.099869) (xy 378.213842 -284.082417) (xy 378.171221 -284.05781)
			(xy 378.1331 -284.026685) (xy 378.100465 -283.989848) (xy 378.074162 -283.948252) (xy 378.054871 -283.902976)
			(xy 378.043094 -283.855192) (xy 378.039134 -283.806138) (xy 377.720606 -283.806138) (xy 377.720094 -283.831584)
			(xy 377.71193 -283.881818) (xy 377.695814 -283.930092) (xy 377.672163 -283.975155) (xy 377.64159 -284.015841)
			(xy 377.604886 -284.051096) (xy 377.563002 -284.080006) (xy 377.517023 -284.101823) (xy 377.468139 -284.115983)
			(xy 377.417618 -284.122117) (xy 377.366766 -284.120068) (xy 377.316902 -284.109888) (xy 377.269316 -284.091841)
			(xy 377.225242 -284.066395) (xy 377.18582 -284.034208) (xy 377.152072 -283.996114) (xy 377.124871 -283.9531)
			(xy 377.104923 -283.90628) (xy 377.092744 -283.856866) (xy 377.088649 -283.806138) (xy 376.780552 -283.806138)
			(xy 376.78004 -283.831584) (xy 376.771876 -283.881818) (xy 376.75576 -283.930092) (xy 376.732109 -283.975155)
			(xy 376.701536 -284.015841) (xy 376.664832 -284.051096) (xy 376.622948 -284.080006) (xy 376.576969 -284.101823)
			(xy 376.528085 -284.115983) (xy 376.477564 -284.122117) (xy 376.426712 -284.120068) (xy 376.376848 -284.109888)
			(xy 376.329262 -284.091841) (xy 376.285188 -284.066395) (xy 376.245766 -284.034208) (xy 376.212018 -283.996114)
			(xy 376.184817 -283.9531) (xy 376.164869 -283.90628) (xy 376.15269 -283.856866) (xy 376.148595 -283.806138)
			(xy 375.830084 -283.806138) (xy 375.829663 -283.828734) (xy 375.822967 -283.873427) (xy 375.809744 -283.91664)
			(xy 375.800366 -283.937202) (xy 375.797826 -283.942536) (xy 375.79554 -283.953204) (xy 375.79554 -284.21711)
			(xy 375.797318 -284.22727) (xy 375.799457 -284.236202) (xy 375.809106 -284.251811) (xy 375.816114 -284.25775)
			(xy 375.887234 -284.31363) (xy 375.897648 -284.315916) (xy 375.921334 -284.308789) (xy 375.970199 -284.301133)
			(xy 375.99493 -284.300676) (xy 376.019715 -284.301165) (xy 376.068673 -284.308923) (xy 376.115815 -284.324244)
			(xy 376.15998 -284.346751) (xy 376.200081 -284.37589) (xy 376.23513 -284.410942) (xy 376.264264 -284.451046)
			(xy 376.286767 -284.495213) (xy 376.302084 -284.542356) (xy 376.309838 -284.591315) (xy 376.309838 -284.616144)
			(xy 376.628926 -284.616144) (xy 376.632886 -284.56709) (xy 376.644663 -284.519306) (xy 376.663954 -284.47403)
			(xy 376.690257 -284.432434) (xy 376.722892 -284.395597) (xy 376.761013 -284.364472) (xy 376.803634 -284.339865)
			(xy 376.84965 -284.322413) (xy 376.897869 -284.312569) (xy 376.947044 -284.310588) (xy 376.995899 -284.31652)
			(xy 377.04317 -284.330212) (xy 377.087632 -284.35131) (xy 377.128135 -284.379266) (xy 377.163628 -284.413358)
			(xy 377.193193 -284.452702) (xy 377.216064 -284.496279) (xy 377.231648 -284.54296) (xy 377.239543 -284.591537)
			(xy 377.240038 -284.616144) (xy 377.558549 -284.616144) (xy 377.562644 -284.565416) (xy 377.574823 -284.516002)
			(xy 377.594771 -284.469182) (xy 377.621972 -284.426168) (xy 377.65572 -284.388074) (xy 377.695142 -284.355887)
			(xy 377.739216 -284.330441) (xy 377.786802 -284.312394) (xy 377.836666 -284.302214) (xy 377.887518 -284.300165)
			(xy 377.938039 -284.306299) (xy 377.986923 -284.320459) (xy 378.032902 -284.342276) (xy 378.074786 -284.371186)
			(xy 378.11149 -284.406441) (xy 378.142063 -284.447127) (xy 378.165714 -284.49219) (xy 378.18183 -284.540464)
			(xy 378.189994 -284.590698) (xy 378.190506 -284.616144) (xy 378.509034 -284.616144) (xy 378.512994 -284.56709)
			(xy 378.524771 -284.519306) (xy 378.544062 -284.47403) (xy 378.570365 -284.432434) (xy 378.603 -284.395597)
			(xy 378.641121 -284.364472) (xy 378.683742 -284.339865) (xy 378.729758 -284.322413) (xy 378.777977 -284.312569)
			(xy 378.827152 -284.310588) (xy 378.876007 -284.31652) (xy 378.923278 -284.330212) (xy 378.96774 -284.35131)
			(xy 379.008243 -284.379266) (xy 379.043736 -284.413358) (xy 379.073301 -284.452702) (xy 379.096172 -284.496279)
			(xy 379.111756 -284.54296) (xy 379.119651 -284.591537) (xy 379.120146 -284.616144) (xy 379.438657 -284.616144)
			(xy 379.442752 -284.565416) (xy 379.454931 -284.516002) (xy 379.474879 -284.469182) (xy 379.50208 -284.426168)
			(xy 379.535828 -284.388074) (xy 379.57525 -284.355887) (xy 379.619324 -284.330441) (xy 379.66691 -284.312394)
			(xy 379.716774 -284.302214) (xy 379.767626 -284.300165) (xy 379.818147 -284.306299) (xy 379.867031 -284.320459)
			(xy 379.91301 -284.342276) (xy 379.954894 -284.371186) (xy 379.991598 -284.406441) (xy 380.022171 -284.447127)
			(xy 380.045822 -284.49219) (xy 380.061938 -284.540464) (xy 380.070102 -284.590698) (xy 380.070614 -284.616144)
			(xy 380.378711 -284.616144) (xy 380.382806 -284.565416) (xy 380.394985 -284.516002) (xy 380.414933 -284.469182)
			(xy 380.442134 -284.426168) (xy 380.475882 -284.388074) (xy 380.515304 -284.355887) (xy 380.559378 -284.330441)
			(xy 380.606964 -284.312394) (xy 380.656828 -284.302214) (xy 380.70768 -284.300165) (xy 380.758201 -284.306299)
			(xy 380.807085 -284.320459) (xy 380.853064 -284.342276) (xy 380.894948 -284.371186) (xy 380.931652 -284.406441)
			(xy 380.962225 -284.447127) (xy 380.985876 -284.49219) (xy 381.001992 -284.540464) (xy 381.010156 -284.590698)
			(xy 381.010668 -284.616144) (xy 381.010156 -284.64159) (xy 381.001992 -284.691824) (xy 380.985876 -284.740098)
			(xy 380.962225 -284.785161) (xy 380.931652 -284.825847) (xy 380.894948 -284.861102) (xy 380.853064 -284.890012)
			(xy 380.807085 -284.911829) (xy 380.758201 -284.925989) (xy 380.70768 -284.932123) (xy 380.656828 -284.930074)
			(xy 380.606964 -284.919894) (xy 380.559378 -284.901847) (xy 380.515304 -284.876401) (xy 380.475882 -284.844214)
			(xy 380.442134 -284.80612) (xy 380.414933 -284.763106) (xy 380.394985 -284.716286) (xy 380.382806 -284.666872)
			(xy 380.378711 -284.616144) (xy 380.070614 -284.616144) (xy 380.070102 -284.64159) (xy 380.061938 -284.691824)
			(xy 380.045822 -284.740098) (xy 380.022171 -284.785161) (xy 379.991598 -284.825847) (xy 379.954894 -284.861102)
			(xy 379.91301 -284.890012) (xy 379.867031 -284.911829) (xy 379.818147 -284.925989) (xy 379.767626 -284.932123)
			(xy 379.716774 -284.930074) (xy 379.66691 -284.919894) (xy 379.619324 -284.901847) (xy 379.57525 -284.876401)
			(xy 379.535828 -284.844214) (xy 379.50208 -284.80612) (xy 379.474879 -284.763106) (xy 379.454931 -284.716286)
			(xy 379.442752 -284.666872) (xy 379.438657 -284.616144) (xy 379.120146 -284.616144) (xy 379.119651 -284.640751)
			(xy 379.111756 -284.689328) (xy 379.096172 -284.736009) (xy 379.073301 -284.779586) (xy 379.043736 -284.81893)
			(xy 379.008243 -284.853022) (xy 378.96774 -284.880978) (xy 378.923278 -284.902076) (xy 378.876007 -284.915768)
			(xy 378.827152 -284.9217) (xy 378.777977 -284.919719) (xy 378.729758 -284.909875) (xy 378.683742 -284.892423)
			(xy 378.641121 -284.867816) (xy 378.603 -284.836691) (xy 378.570365 -284.799854) (xy 378.544062 -284.758258)
			(xy 378.524771 -284.712982) (xy 378.512994 -284.665198) (xy 378.509034 -284.616144) (xy 378.190506 -284.616144)
			(xy 378.189994 -284.64159) (xy 378.18183 -284.691824) (xy 378.165714 -284.740098) (xy 378.142063 -284.785161)
			(xy 378.11149 -284.825847) (xy 378.074786 -284.861102) (xy 378.032902 -284.890012) (xy 377.986923 -284.911829)
			(xy 377.938039 -284.925989) (xy 377.887518 -284.932123) (xy 377.836666 -284.930074) (xy 377.786802 -284.919894)
			(xy 377.739216 -284.901847) (xy 377.695142 -284.876401) (xy 377.65572 -284.844214) (xy 377.621972 -284.80612)
			(xy 377.594771 -284.763106) (xy 377.574823 -284.716286) (xy 377.562644 -284.666872) (xy 377.558549 -284.616144)
			(xy 377.240038 -284.616144) (xy 377.239543 -284.640751) (xy 377.231648 -284.689328) (xy 377.216064 -284.736009)
			(xy 377.193193 -284.779586) (xy 377.163628 -284.81893) (xy 377.128135 -284.853022) (xy 377.087632 -284.880978)
			(xy 377.04317 -284.902076) (xy 376.995899 -284.915768) (xy 376.947044 -284.9217) (xy 376.897869 -284.919719)
			(xy 376.84965 -284.909875) (xy 376.803634 -284.892423) (xy 376.761013 -284.867816) (xy 376.722892 -284.836691)
			(xy 376.690257 -284.799854) (xy 376.663954 -284.758258) (xy 376.644663 -284.712982) (xy 376.632886 -284.665198)
			(xy 376.628926 -284.616144) (xy 376.309838 -284.616144) (xy 376.309838 -284.640885) (xy 376.302084 -284.689844)
			(xy 376.286767 -284.736987) (xy 376.264264 -284.781154) (xy 376.23513 -284.821258) (xy 376.200081 -284.85631)
			(xy 376.15998 -284.885449) (xy 376.115815 -284.907956) (xy 376.068673 -284.923277) (xy 376.019715 -284.931035)
			(xy 375.99493 -284.931612) (xy 375.970195 -284.9312) (xy 375.921322 -284.923549) (xy 375.897648 -284.916372)
			(xy 375.887234 -284.918658) (xy 375.815098 -284.975046) (xy 375.809879 -284.979424) (xy 375.801782 -284.990374)
			(xy 375.799096 -284.996636) (xy 375.79554 -285.00578) (xy 375.79554 -285.220918) (xy 375.795788 -285.228099)
			(xy 375.799788 -285.241893) (xy 375.803414 -285.248096) (xy 375.817448 -285.271024) (xy 375.838691 -285.320401)
			(xy 375.851663 -285.372566) (xy 375.85602 -285.426142) (xy 375.856019 -285.42615) (xy 376.148595 -285.42615)
			(xy 376.15269 -285.375422) (xy 376.164869 -285.326008) (xy 376.184817 -285.279188) (xy 376.212018 -285.236174)
			(xy 376.245766 -285.19808) (xy 376.285188 -285.165893) (xy 376.329262 -285.140447) (xy 376.376848 -285.1224)
			(xy 376.426712 -285.11222) (xy 376.477564 -285.110171) (xy 376.528085 -285.116305) (xy 376.576969 -285.130465)
			(xy 376.622948 -285.152282) (xy 376.664832 -285.181192) (xy 376.701536 -285.216447) (xy 376.732109 -285.257133)
			(xy 376.75576 -285.302196) (xy 376.771876 -285.35047) (xy 376.78004 -285.400704) (xy 376.780552 -285.42615)
			(xy 377.088649 -285.42615) (xy 377.092744 -285.375422) (xy 377.104923 -285.326008) (xy 377.124871 -285.279188)
			(xy 377.152072 -285.236174) (xy 377.18582 -285.19808) (xy 377.225242 -285.165893) (xy 377.269316 -285.140447)
			(xy 377.316902 -285.1224) (xy 377.366766 -285.11222) (xy 377.417618 -285.110171) (xy 377.468139 -285.116305)
			(xy 377.517023 -285.130465) (xy 377.563002 -285.152282) (xy 377.604886 -285.181192) (xy 377.64159 -285.216447)
			(xy 377.672163 -285.257133) (xy 377.695814 -285.302196) (xy 377.71193 -285.35047) (xy 377.720094 -285.400704)
			(xy 377.720606 -285.42615) (xy 378.968503 -285.42615) (xy 378.972598 -285.375422) (xy 378.984777 -285.326008)
			(xy 379.004725 -285.279188) (xy 379.031926 -285.236174) (xy 379.065674 -285.19808) (xy 379.105096 -285.165893)
			(xy 379.14917 -285.140447) (xy 379.196756 -285.1224) (xy 379.24662 -285.11222) (xy 379.297472 -285.110171)
			(xy 379.347993 -285.116305) (xy 379.396877 -285.130465) (xy 379.442856 -285.152282) (xy 379.48474 -285.181192)
			(xy 379.521444 -285.216447) (xy 379.552017 -285.257133) (xy 379.575668 -285.302196) (xy 379.591784 -285.35047)
			(xy 379.599948 -285.400704) (xy 379.60046 -285.42615) (xy 379.918988 -285.42615) (xy 379.922948 -285.377096)
			(xy 379.934725 -285.329312) (xy 379.954016 -285.284036) (xy 379.980319 -285.24244) (xy 380.012954 -285.205603)
			(xy 380.051075 -285.174478) (xy 380.093696 -285.149871) (xy 380.139712 -285.132419) (xy 380.187931 -285.122575)
			(xy 380.237106 -285.120594) (xy 380.285961 -285.126526) (xy 380.333232 -285.140218) (xy 380.377694 -285.161316)
			(xy 380.418197 -285.189272) (xy 380.45369 -285.223364) (xy 380.483255 -285.262708) (xy 380.506126 -285.306285)
			(xy 380.52171 -285.352966) (xy 380.529605 -285.401543) (xy 380.5301 -285.42615) (xy 380.848611 -285.42615)
			(xy 380.852706 -285.375422) (xy 380.864885 -285.326008) (xy 380.884833 -285.279188) (xy 380.912034 -285.236174)
			(xy 380.945782 -285.19808) (xy 380.985204 -285.165893) (xy 381.029278 -285.140447) (xy 381.076864 -285.1224)
			(xy 381.126728 -285.11222) (xy 381.17758 -285.110171) (xy 381.228101 -285.116305) (xy 381.276985 -285.130465)
			(xy 381.322964 -285.152282) (xy 381.364848 -285.181192) (xy 381.401552 -285.216447) (xy 381.432125 -285.257133)
			(xy 381.455776 -285.302196) (xy 381.471892 -285.35047) (xy 381.480056 -285.400704) (xy 381.480568 -285.42615)
			(xy 381.480056 -285.451596) (xy 381.471892 -285.50183) (xy 381.455776 -285.550104) (xy 381.432125 -285.595167)
			(xy 381.401552 -285.635853) (xy 381.364848 -285.671108) (xy 381.322964 -285.700018) (xy 381.276985 -285.721835)
			(xy 381.228101 -285.735995) (xy 381.17758 -285.742129) (xy 381.126728 -285.74008) (xy 381.076864 -285.7299)
			(xy 381.029278 -285.711853) (xy 380.985204 -285.686407) (xy 380.945782 -285.65422) (xy 380.912034 -285.616126)
			(xy 380.884833 -285.573112) (xy 380.864885 -285.526292) (xy 380.852706 -285.476878) (xy 380.848611 -285.42615)
			(xy 380.5301 -285.42615) (xy 380.529605 -285.450757) (xy 380.52171 -285.499334) (xy 380.506126 -285.546015)
			(xy 380.483255 -285.589592) (xy 380.45369 -285.628936) (xy 380.418197 -285.663028) (xy 380.377694 -285.690984)
			(xy 380.333232 -285.712082) (xy 380.285961 -285.725774) (xy 380.237106 -285.731706) (xy 380.187931 -285.729725)
			(xy 380.139712 -285.719881) (xy 380.093696 -285.702429) (xy 380.051075 -285.677822) (xy 380.012954 -285.646697)
			(xy 379.980319 -285.60986) (xy 379.954016 -285.568264) (xy 379.934725 -285.522988) (xy 379.922948 -285.475204)
			(xy 379.918988 -285.42615) (xy 379.60046 -285.42615) (xy 379.599948 -285.451596) (xy 379.591784 -285.50183)
			(xy 379.575668 -285.550104) (xy 379.552017 -285.595167) (xy 379.521444 -285.635853) (xy 379.48474 -285.671108)
			(xy 379.442856 -285.700018) (xy 379.396877 -285.721835) (xy 379.347993 -285.735995) (xy 379.297472 -285.742129)
			(xy 379.24662 -285.74008) (xy 379.196756 -285.7299) (xy 379.14917 -285.711853) (xy 379.105096 -285.686407)
			(xy 379.065674 -285.65422) (xy 379.031926 -285.616126) (xy 379.004725 -285.573112) (xy 378.984777 -285.526292)
			(xy 378.972598 -285.476878) (xy 378.968503 -285.42615) (xy 377.720606 -285.42615) (xy 377.720094 -285.451596)
			(xy 377.71193 -285.50183) (xy 377.695814 -285.550104) (xy 377.672163 -285.595167) (xy 377.64159 -285.635853)
			(xy 377.604886 -285.671108) (xy 377.563002 -285.700018) (xy 377.517023 -285.721835) (xy 377.468139 -285.735995)
			(xy 377.417618 -285.742129) (xy 377.366766 -285.74008) (xy 377.316902 -285.7299) (xy 377.269316 -285.711853)
			(xy 377.225242 -285.686407) (xy 377.18582 -285.65422) (xy 377.152072 -285.616126) (xy 377.124871 -285.573112)
			(xy 377.104923 -285.526292) (xy 377.092744 -285.476878) (xy 377.088649 -285.42615) (xy 376.780552 -285.42615)
			(xy 376.78004 -285.451596) (xy 376.771876 -285.50183) (xy 376.75576 -285.550104) (xy 376.732109 -285.595167)
			(xy 376.701536 -285.635853) (xy 376.664832 -285.671108) (xy 376.622948 -285.700018) (xy 376.576969 -285.721835)
			(xy 376.528085 -285.735995) (xy 376.477564 -285.742129) (xy 376.426712 -285.74008) (xy 376.376848 -285.7299)
			(xy 376.329262 -285.711853) (xy 376.285188 -285.686407) (xy 376.245766 -285.65422) (xy 376.212018 -285.616126)
			(xy 376.184817 -285.573112) (xy 376.164869 -285.526292) (xy 376.15269 -285.476878) (xy 376.148595 -285.42615)
			(xy 375.856019 -285.42615) (xy 375.851649 -285.479717) (xy 375.838664 -285.531879) (xy 375.817408 -285.581251)
			(xy 375.803414 -285.604204) (xy 375.799788 -285.610406) (xy 375.795807 -285.624202) (xy 375.79554 -285.631382)
			(xy 375.79554 -285.837122) (xy 375.797318 -285.847282) (xy 375.799444 -285.856222) (xy 375.809077 -285.871854)
			(xy 375.816114 -285.877762) (xy 375.887234 -285.933642) (xy 375.897648 -285.935928) (xy 375.921334 -285.928801)
			(xy 375.970199 -285.921145) (xy 375.99493 -285.920688) (xy 376.019722 -285.921176) (xy 376.068694 -285.928937)
			(xy 376.115849 -285.944263) (xy 376.160026 -285.966776) (xy 376.200138 -285.995922) (xy 376.235197 -286.030985)
			(xy 376.26434 -286.071099) (xy 376.286849 -286.115279) (xy 376.30217 -286.162436) (xy 376.309926 -286.211408)
			(xy 376.309926 -286.236156) (xy 376.628926 -286.236156) (xy 376.632886 -286.187102) (xy 376.644663 -286.139318)
			(xy 376.663954 -286.094042) (xy 376.690257 -286.052446) (xy 376.722892 -286.015609) (xy 376.761013 -285.984484)
			(xy 376.803634 -285.959877) (xy 376.84965 -285.942425) (xy 376.897869 -285.932581) (xy 376.947044 -285.9306)
			(xy 376.995899 -285.936532) (xy 377.04317 -285.950224) (xy 377.087632 -285.971322) (xy 377.128135 -285.999278)
			(xy 377.163628 -286.03337) (xy 377.193193 -286.072714) (xy 377.216064 -286.116291) (xy 377.231648 -286.162972)
			(xy 377.239543 -286.211549) (xy 377.240038 -286.236156) (xy 377.558549 -286.236156) (xy 377.562644 -286.185428)
			(xy 377.574823 -286.136014) (xy 377.594771 -286.089194) (xy 377.621972 -286.04618) (xy 377.65572 -286.008086)
			(xy 377.695142 -285.975899) (xy 377.739216 -285.950453) (xy 377.786802 -285.932406) (xy 377.836666 -285.922226)
			(xy 377.887518 -285.920177) (xy 377.938039 -285.926311) (xy 377.986923 -285.940471) (xy 378.032902 -285.962288)
			(xy 378.074786 -285.991198) (xy 378.11149 -286.026453) (xy 378.142063 -286.067139) (xy 378.165714 -286.112202)
			(xy 378.18183 -286.160476) (xy 378.189994 -286.21071) (xy 378.190506 -286.236156) (xy 378.509034 -286.236156)
			(xy 378.512994 -286.187102) (xy 378.524771 -286.139318) (xy 378.544062 -286.094042) (xy 378.570365 -286.052446)
			(xy 378.603 -286.015609) (xy 378.641121 -285.984484) (xy 378.683742 -285.959877) (xy 378.729758 -285.942425)
			(xy 378.777977 -285.932581) (xy 378.827152 -285.9306) (xy 378.876007 -285.936532) (xy 378.923278 -285.950224)
			(xy 378.96774 -285.971322) (xy 379.008243 -285.999278) (xy 379.043736 -286.03337) (xy 379.073301 -286.072714)
			(xy 379.096172 -286.116291) (xy 379.111756 -286.162972) (xy 379.119651 -286.211549) (xy 379.120146 -286.236156)
			(xy 379.438657 -286.236156) (xy 379.442752 -286.185428) (xy 379.454931 -286.136014) (xy 379.474879 -286.089194)
			(xy 379.50208 -286.04618) (xy 379.535828 -286.008086) (xy 379.57525 -285.975899) (xy 379.619324 -285.950453)
			(xy 379.66691 -285.932406) (xy 379.716774 -285.922226) (xy 379.767626 -285.920177) (xy 379.818147 -285.926311)
			(xy 379.867031 -285.940471) (xy 379.91301 -285.962288) (xy 379.954894 -285.991198) (xy 379.991598 -286.026453)
			(xy 380.022171 -286.067139) (xy 380.045822 -286.112202) (xy 380.061938 -286.160476) (xy 380.070102 -286.21071)
			(xy 380.070614 -286.236156) (xy 380.378711 -286.236156) (xy 380.382806 -286.185428) (xy 380.394985 -286.136014)
			(xy 380.414933 -286.089194) (xy 380.442134 -286.04618) (xy 380.475882 -286.008086) (xy 380.515304 -285.975899)
			(xy 380.559378 -285.950453) (xy 380.606964 -285.932406) (xy 380.656828 -285.922226) (xy 380.70768 -285.920177)
			(xy 380.758201 -285.926311) (xy 380.807085 -285.940471) (xy 380.853064 -285.962288) (xy 380.894948 -285.991198)
			(xy 380.931652 -286.026453) (xy 380.962225 -286.067139) (xy 380.985876 -286.112202) (xy 381.001992 -286.160476)
			(xy 381.010156 -286.21071) (xy 381.010668 -286.236156) (xy 381.010156 -286.261602) (xy 381.001992 -286.311836)
			(xy 380.985876 -286.36011) (xy 380.962225 -286.405173) (xy 380.931652 -286.445859) (xy 380.894948 -286.481114)
			(xy 380.853064 -286.510024) (xy 380.807085 -286.531841) (xy 380.758201 -286.546001) (xy 380.70768 -286.552135)
			(xy 380.656828 -286.550086) (xy 380.606964 -286.539906) (xy 380.559378 -286.521859) (xy 380.515304 -286.496413)
			(xy 380.475882 -286.464226) (xy 380.442134 -286.426132) (xy 380.414933 -286.383118) (xy 380.394985 -286.336298)
			(xy 380.382806 -286.286884) (xy 380.378711 -286.236156) (xy 380.070614 -286.236156) (xy 380.070102 -286.261602)
			(xy 380.061938 -286.311836) (xy 380.045822 -286.36011) (xy 380.022171 -286.405173) (xy 379.991598 -286.445859)
			(xy 379.954894 -286.481114) (xy 379.91301 -286.510024) (xy 379.867031 -286.531841) (xy 379.818147 -286.546001)
			(xy 379.767626 -286.552135) (xy 379.716774 -286.550086) (xy 379.66691 -286.539906) (xy 379.619324 -286.521859)
			(xy 379.57525 -286.496413) (xy 379.535828 -286.464226) (xy 379.50208 -286.426132) (xy 379.474879 -286.383118)
			(xy 379.454931 -286.336298) (xy 379.442752 -286.286884) (xy 379.438657 -286.236156) (xy 379.120146 -286.236156)
			(xy 379.119651 -286.260763) (xy 379.111756 -286.30934) (xy 379.096172 -286.356021) (xy 379.073301 -286.399598)
			(xy 379.043736 -286.438942) (xy 379.008243 -286.473034) (xy 378.96774 -286.50099) (xy 378.923278 -286.522088)
			(xy 378.876007 -286.53578) (xy 378.827152 -286.541712) (xy 378.777977 -286.539731) (xy 378.729758 -286.529887)
			(xy 378.683742 -286.512435) (xy 378.641121 -286.487828) (xy 378.603 -286.456703) (xy 378.570365 -286.419866)
			(xy 378.544062 -286.37827) (xy 378.524771 -286.332994) (xy 378.512994 -286.28521) (xy 378.509034 -286.236156)
			(xy 378.190506 -286.236156) (xy 378.189994 -286.261602) (xy 378.18183 -286.311836) (xy 378.165714 -286.36011)
			(xy 378.142063 -286.405173) (xy 378.11149 -286.445859) (xy 378.074786 -286.481114) (xy 378.032902 -286.510024)
			(xy 377.986923 -286.531841) (xy 377.938039 -286.546001) (xy 377.887518 -286.552135) (xy 377.836666 -286.550086)
			(xy 377.786802 -286.539906) (xy 377.739216 -286.521859) (xy 377.695142 -286.496413) (xy 377.65572 -286.464226)
			(xy 377.621972 -286.426132) (xy 377.594771 -286.383118) (xy 377.574823 -286.336298) (xy 377.562644 -286.286884)
			(xy 377.558549 -286.236156) (xy 377.240038 -286.236156) (xy 377.239543 -286.260763) (xy 377.231648 -286.30934)
			(xy 377.216064 -286.356021) (xy 377.193193 -286.399598) (xy 377.163628 -286.438942) (xy 377.128135 -286.473034)
			(xy 377.087632 -286.50099) (xy 377.04317 -286.522088) (xy 376.995899 -286.53578) (xy 376.947044 -286.541712)
			(xy 376.897869 -286.539731) (xy 376.84965 -286.529887) (xy 376.803634 -286.512435) (xy 376.761013 -286.487828)
			(xy 376.722892 -286.456703) (xy 376.690257 -286.419866) (xy 376.663954 -286.37827) (xy 376.644663 -286.332994)
			(xy 376.632886 -286.28521) (xy 376.628926 -286.236156) (xy 376.309926 -286.236156) (xy 376.309926 -286.260992)
			(xy 376.30217 -286.309964) (xy 376.286849 -286.357121) (xy 376.26434 -286.401301) (xy 376.235197 -286.441415)
			(xy 376.200138 -286.476478) (xy 376.160026 -286.505624) (xy 376.115849 -286.528137) (xy 376.068694 -286.543463)
			(xy 376.019722 -286.551224) (xy 375.99493 -286.551624) (xy 375.970195 -286.551212) (xy 375.921322 -286.543561)
			(xy 375.897648 -286.536384) (xy 375.887234 -286.53867) (xy 375.815098 -286.595058) (xy 375.809872 -286.599432)
			(xy 375.801757 -286.610374) (xy 375.799096 -286.616648) (xy 375.79554 -286.625792) (xy 375.79554 -286.898842)
			(xy 375.797826 -286.90951) (xy 375.800366 -286.914844) (xy 375.809717 -286.935417) (xy 375.822938 -286.978628)
			(xy 375.829658 -287.023314) (xy 375.830084 -287.045908) (xy 376.148595 -287.045908) (xy 376.15269 -286.99518)
			(xy 376.164869 -286.945766) (xy 376.184817 -286.898946) (xy 376.212018 -286.855932) (xy 376.245766 -286.817838)
			(xy 376.285188 -286.785651) (xy 376.329262 -286.760205) (xy 376.376848 -286.742158) (xy 376.426712 -286.731978)
			(xy 376.477564 -286.729929) (xy 376.528085 -286.736063) (xy 376.576969 -286.750223) (xy 376.622948 -286.77204)
			(xy 376.664832 -286.80095) (xy 376.701536 -286.836205) (xy 376.732109 -286.876891) (xy 376.75576 -286.921954)
			(xy 376.771876 -286.970228) (xy 376.78004 -287.020462) (xy 376.780552 -287.045908) (xy 377.088649 -287.045908)
			(xy 377.092744 -286.99518) (xy 377.104923 -286.945766) (xy 377.124871 -286.898946) (xy 377.152072 -286.855932)
			(xy 377.18582 -286.817838) (xy 377.225242 -286.785651) (xy 377.269316 -286.760205) (xy 377.316902 -286.742158)
			(xy 377.366766 -286.731978) (xy 377.417618 -286.729929) (xy 377.468139 -286.736063) (xy 377.517023 -286.750223)
			(xy 377.563002 -286.77204) (xy 377.604886 -286.80095) (xy 377.64159 -286.836205) (xy 377.672163 -286.876891)
			(xy 377.695814 -286.921954) (xy 377.71193 -286.970228) (xy 377.720094 -287.020462) (xy 377.720606 -287.045908)
			(xy 377.720601 -287.046162) (xy 378.039134 -287.046162) (xy 378.043094 -286.997108) (xy 378.054871 -286.949324)
			(xy 378.074162 -286.904048) (xy 378.100465 -286.862452) (xy 378.1331 -286.825615) (xy 378.171221 -286.79449)
			(xy 378.213842 -286.769883) (xy 378.259858 -286.752431) (xy 378.308077 -286.742587) (xy 378.357252 -286.740606)
			(xy 378.406107 -286.746538) (xy 378.453378 -286.76023) (xy 378.49784 -286.781328) (xy 378.538343 -286.809284)
			(xy 378.573836 -286.843376) (xy 378.603401 -286.88272) (xy 378.626272 -286.926297) (xy 378.641856 -286.972978)
			(xy 378.649751 -287.021555) (xy 378.650241 -287.045908) (xy 378.968503 -287.045908) (xy 378.972598 -286.99518)
			(xy 378.984777 -286.945766) (xy 379.004725 -286.898946) (xy 379.031926 -286.855932) (xy 379.065674 -286.817838)
			(xy 379.105096 -286.785651) (xy 379.14917 -286.760205) (xy 379.196756 -286.742158) (xy 379.24662 -286.731978)
			(xy 379.297472 -286.729929) (xy 379.347993 -286.736063) (xy 379.396877 -286.750223) (xy 379.442856 -286.77204)
			(xy 379.48474 -286.80095) (xy 379.521444 -286.836205) (xy 379.552017 -286.876891) (xy 379.575668 -286.921954)
			(xy 379.591784 -286.970228) (xy 379.599948 -287.020462) (xy 379.60046 -287.045908) (xy 379.918988 -287.045908)
			(xy 379.922948 -286.996854) (xy 379.934725 -286.94907) (xy 379.954016 -286.903794) (xy 379.980319 -286.862198)
			(xy 380.012954 -286.825361) (xy 380.051075 -286.794236) (xy 380.093696 -286.769629) (xy 380.139712 -286.752177)
			(xy 380.187931 -286.742333) (xy 380.237106 -286.740352) (xy 380.285961 -286.746284) (xy 380.333232 -286.759976)
			(xy 380.377694 -286.781074) (xy 380.418197 -286.80903) (xy 380.45369 -286.843122) (xy 380.483255 -286.882466)
			(xy 380.506126 -286.926043) (xy 380.52171 -286.972724) (xy 380.529605 -287.021301) (xy 380.5301 -287.045908)
			(xy 380.848611 -287.045908) (xy 380.852706 -286.99518) (xy 380.864885 -286.945766) (xy 380.884833 -286.898946)
			(xy 380.912034 -286.855932) (xy 380.945782 -286.817838) (xy 380.985204 -286.785651) (xy 381.029278 -286.760205)
			(xy 381.076864 -286.742158) (xy 381.126728 -286.731978) (xy 381.17758 -286.729929) (xy 381.228101 -286.736063)
			(xy 381.276985 -286.750223) (xy 381.322964 -286.77204) (xy 381.364848 -286.80095) (xy 381.401552 -286.836205)
			(xy 381.432125 -286.876891) (xy 381.455776 -286.921954) (xy 381.471892 -286.970228) (xy 381.480056 -287.020462)
			(xy 381.480568 -287.045908) (xy 381.480056 -287.071354) (xy 381.471892 -287.121588) (xy 381.455776 -287.169862)
			(xy 381.432125 -287.214925) (xy 381.401552 -287.255611) (xy 381.364848 -287.290866) (xy 381.322964 -287.319776)
			(xy 381.276985 -287.341593) (xy 381.228101 -287.355753) (xy 381.17758 -287.361887) (xy 381.126728 -287.359838)
			(xy 381.076864 -287.349658) (xy 381.029278 -287.331611) (xy 380.985204 -287.306165) (xy 380.945782 -287.273978)
			(xy 380.912034 -287.235884) (xy 380.884833 -287.19287) (xy 380.864885 -287.14605) (xy 380.852706 -287.096636)
			(xy 380.848611 -287.045908) (xy 380.5301 -287.045908) (xy 380.529605 -287.070515) (xy 380.52171 -287.119092)
			(xy 380.506126 -287.165773) (xy 380.483255 -287.20935) (xy 380.45369 -287.248694) (xy 380.418197 -287.282786)
			(xy 380.377694 -287.310742) (xy 380.333232 -287.33184) (xy 380.285961 -287.345532) (xy 380.237106 -287.351464)
			(xy 380.187931 -287.349483) (xy 380.139712 -287.339639) (xy 380.093696 -287.322187) (xy 380.051075 -287.29758)
			(xy 380.012954 -287.266455) (xy 379.980319 -287.229618) (xy 379.954016 -287.188022) (xy 379.934725 -287.142746)
			(xy 379.922948 -287.094962) (xy 379.918988 -287.045908) (xy 379.60046 -287.045908) (xy 379.599948 -287.071354)
			(xy 379.591784 -287.121588) (xy 379.575668 -287.169862) (xy 379.552017 -287.214925) (xy 379.521444 -287.255611)
			(xy 379.48474 -287.290866) (xy 379.442856 -287.319776) (xy 379.396877 -287.341593) (xy 379.347993 -287.355753)
			(xy 379.297472 -287.361887) (xy 379.24662 -287.359838) (xy 379.196756 -287.349658) (xy 379.14917 -287.331611)
			(xy 379.105096 -287.306165) (xy 379.065674 -287.273978) (xy 379.031926 -287.235884) (xy 379.004725 -287.19287)
			(xy 378.984777 -287.14605) (xy 378.972598 -287.096636) (xy 378.968503 -287.045908) (xy 378.650241 -287.045908)
			(xy 378.650246 -287.046162) (xy 378.649751 -287.070769) (xy 378.641856 -287.119346) (xy 378.626272 -287.166027)
			(xy 378.603401 -287.209604) (xy 378.573836 -287.248948) (xy 378.538343 -287.28304) (xy 378.49784 -287.310996)
			(xy 378.453378 -287.332094) (xy 378.406107 -287.345786) (xy 378.357252 -287.351718) (xy 378.308077 -287.349737)
			(xy 378.259858 -287.339893) (xy 378.213842 -287.322441) (xy 378.171221 -287.297834) (xy 378.1331 -287.266709)
			(xy 378.100465 -287.229872) (xy 378.074162 -287.188276) (xy 378.054871 -287.143) (xy 378.043094 -287.095216)
			(xy 378.039134 -287.046162) (xy 377.720601 -287.046162) (xy 377.720094 -287.071354) (xy 377.71193 -287.121588)
			(xy 377.695814 -287.169862) (xy 377.672163 -287.214925) (xy 377.64159 -287.255611) (xy 377.604886 -287.290866)
			(xy 377.563002 -287.319776) (xy 377.517023 -287.341593) (xy 377.468139 -287.355753) (xy 377.417618 -287.361887)
			(xy 377.366766 -287.359838) (xy 377.316902 -287.349658) (xy 377.269316 -287.331611) (xy 377.225242 -287.306165)
			(xy 377.18582 -287.273978) (xy 377.152072 -287.235884) (xy 377.124871 -287.19287) (xy 377.104923 -287.14605)
			(xy 377.092744 -287.096636) (xy 377.088649 -287.045908) (xy 376.780552 -287.045908) (xy 376.78004 -287.071354)
			(xy 376.771876 -287.121588) (xy 376.75576 -287.169862) (xy 376.732109 -287.214925) (xy 376.701536 -287.255611)
			(xy 376.664832 -287.290866) (xy 376.622948 -287.319776) (xy 376.576969 -287.341593) (xy 376.528085 -287.355753)
			(xy 376.477564 -287.361887) (xy 376.426712 -287.359838) (xy 376.376848 -287.349658) (xy 376.329262 -287.331611)
			(xy 376.285188 -287.306165) (xy 376.245766 -287.273978) (xy 376.212018 -287.235884) (xy 376.184817 -287.19287)
			(xy 376.164869 -287.14605) (xy 376.15269 -287.096636) (xy 376.148595 -287.045908) (xy 375.830084 -287.045908)
			(xy 375.829658 -287.068502) (xy 375.822953 -287.113192) (xy 375.809721 -287.1564) (xy 375.800366 -287.176972)
			(xy 375.797826 -287.182306) (xy 375.79554 -287.192974) (xy 375.79554 -287.457134) (xy 375.797318 -287.467294)
			(xy 375.799446 -287.476233) (xy 375.809081 -287.491861) (xy 375.816114 -287.497774) (xy 375.887234 -287.553654)
			(xy 375.897648 -287.55594) (xy 375.921334 -287.548812) (xy 375.970199 -287.541156) (xy 375.99493 -287.5407)
			(xy 376.019721 -287.541188) (xy 376.068691 -287.548949) (xy 376.115844 -287.564274) (xy 376.16002 -287.586786)
			(xy 376.20013 -287.615932) (xy 376.235188 -287.650992) (xy 376.26433 -287.691106) (xy 376.286838 -287.735284)
			(xy 376.302158 -287.782438) (xy 376.309914 -287.831409) (xy 376.309914 -287.856168) (xy 376.628926 -287.856168)
			(xy 376.632886 -287.807114) (xy 376.644663 -287.75933) (xy 376.663954 -287.714054) (xy 376.690257 -287.672458)
			(xy 376.722892 -287.635621) (xy 376.761013 -287.604496) (xy 376.803634 -287.579889) (xy 376.84965 -287.562437)
			(xy 376.897869 -287.552593) (xy 376.947044 -287.550612) (xy 376.995899 -287.556544) (xy 377.04317 -287.570236)
			(xy 377.087632 -287.591334) (xy 377.128135 -287.61929) (xy 377.163628 -287.653382) (xy 377.193193 -287.692726)
			(xy 377.216064 -287.736303) (xy 377.231648 -287.782984) (xy 377.239543 -287.831561) (xy 377.240038 -287.856168)
			(xy 377.558549 -287.856168) (xy 377.562644 -287.80544) (xy 377.574823 -287.756026) (xy 377.594771 -287.709206)
			(xy 377.621972 -287.666192) (xy 377.65572 -287.628098) (xy 377.695142 -287.595911) (xy 377.739216 -287.570465)
			(xy 377.786802 -287.552418) (xy 377.836666 -287.542238) (xy 377.887518 -287.540189) (xy 377.938039 -287.546323)
			(xy 377.986923 -287.560483) (xy 378.032902 -287.5823) (xy 378.074786 -287.61121) (xy 378.11149 -287.646465)
			(xy 378.142063 -287.687151) (xy 378.165714 -287.732214) (xy 378.18183 -287.780488) (xy 378.189994 -287.830722)
			(xy 378.190506 -287.856168) (xy 379.438657 -287.856168) (xy 379.442752 -287.80544) (xy 379.454931 -287.756026)
			(xy 379.474879 -287.709206) (xy 379.50208 -287.666192) (xy 379.535828 -287.628098) (xy 379.57525 -287.595911)
			(xy 379.619324 -287.570465) (xy 379.66691 -287.552418) (xy 379.716774 -287.542238) (xy 379.767626 -287.540189)
			(xy 379.818147 -287.546323) (xy 379.867031 -287.560483) (xy 379.91301 -287.5823) (xy 379.954894 -287.61121)
			(xy 379.991598 -287.646465) (xy 380.022171 -287.687151) (xy 380.045822 -287.732214) (xy 380.061938 -287.780488)
			(xy 380.070102 -287.830722) (xy 380.070614 -287.856168) (xy 380.378711 -287.856168) (xy 380.382806 -287.80544)
			(xy 380.394985 -287.756026) (xy 380.414933 -287.709206) (xy 380.442134 -287.666192) (xy 380.475882 -287.628098)
			(xy 380.515304 -287.595911) (xy 380.559378 -287.570465) (xy 380.606964 -287.552418) (xy 380.656828 -287.542238)
			(xy 380.70768 -287.540189) (xy 380.758201 -287.546323) (xy 380.807085 -287.560483) (xy 380.853064 -287.5823)
			(xy 380.894948 -287.61121) (xy 380.931652 -287.646465) (xy 380.962225 -287.687151) (xy 380.985876 -287.732214)
			(xy 381.001992 -287.780488) (xy 381.010156 -287.830722) (xy 381.010668 -287.856168) (xy 381.010156 -287.881614)
			(xy 381.001992 -287.931848) (xy 380.985876 -287.980122) (xy 380.962225 -288.025185) (xy 380.931652 -288.065871)
			(xy 380.894948 -288.101126) (xy 380.853064 -288.130036) (xy 380.807085 -288.151853) (xy 380.758201 -288.166013)
			(xy 380.70768 -288.172147) (xy 380.656828 -288.170098) (xy 380.606964 -288.159918) (xy 380.559378 -288.141871)
			(xy 380.515304 -288.116425) (xy 380.475882 -288.084238) (xy 380.442134 -288.046144) (xy 380.414933 -288.00313)
			(xy 380.394985 -287.95631) (xy 380.382806 -287.906896) (xy 380.378711 -287.856168) (xy 380.070614 -287.856168)
			(xy 380.070102 -287.881614) (xy 380.061938 -287.931848) (xy 380.045822 -287.980122) (xy 380.022171 -288.025185)
			(xy 379.991598 -288.065871) (xy 379.954894 -288.101126) (xy 379.91301 -288.130036) (xy 379.867031 -288.151853)
			(xy 379.818147 -288.166013) (xy 379.767626 -288.172147) (xy 379.716774 -288.170098) (xy 379.66691 -288.159918)
			(xy 379.619324 -288.141871) (xy 379.57525 -288.116425) (xy 379.535828 -288.084238) (xy 379.50208 -288.046144)
			(xy 379.474879 -288.00313) (xy 379.454931 -287.95631) (xy 379.442752 -287.906896) (xy 379.438657 -287.856168)
			(xy 378.190506 -287.856168) (xy 378.189994 -287.881614) (xy 378.18183 -287.931848) (xy 378.165714 -287.980122)
			(xy 378.142063 -288.025185) (xy 378.11149 -288.065871) (xy 378.074786 -288.101126) (xy 378.032902 -288.130036)
			(xy 377.986923 -288.151853) (xy 377.938039 -288.166013) (xy 377.887518 -288.172147) (xy 377.836666 -288.170098)
			(xy 377.786802 -288.159918) (xy 377.739216 -288.141871) (xy 377.695142 -288.116425) (xy 377.65572 -288.084238)
			(xy 377.621972 -288.046144) (xy 377.594771 -288.00313) (xy 377.574823 -287.95631) (xy 377.562644 -287.906896)
			(xy 377.558549 -287.856168) (xy 377.240038 -287.856168) (xy 377.239543 -287.880775) (xy 377.231648 -287.929352)
			(xy 377.216064 -287.976033) (xy 377.193193 -288.01961) (xy 377.163628 -288.058954) (xy 377.128135 -288.093046)
			(xy 377.087632 -288.121002) (xy 377.04317 -288.1421) (xy 376.995899 -288.155792) (xy 376.947044 -288.161724)
			(xy 376.897869 -288.159743) (xy 376.84965 -288.149899) (xy 376.803634 -288.132447) (xy 376.761013 -288.10784)
			(xy 376.722892 -288.076715) (xy 376.690257 -288.039878) (xy 376.663954 -287.998282) (xy 376.644663 -287.953006)
			(xy 376.632886 -287.905222) (xy 376.628926 -287.856168) (xy 376.309914 -287.856168) (xy 376.309914 -287.880991)
			(xy 376.302158 -287.929962) (xy 376.286838 -287.977116) (xy 376.26433 -288.021294) (xy 376.235188 -288.061408)
			(xy 376.20013 -288.096468) (xy 376.16002 -288.125614) (xy 376.115844 -288.148126) (xy 376.068691 -288.163451)
			(xy 376.019721 -288.171212) (xy 375.99493 -288.171636) (xy 375.970195 -288.171224) (xy 375.921322 -288.163574)
			(xy 375.897648 -288.156396) (xy 375.887234 -288.158682) (xy 375.815098 -288.21507) (xy 375.809872 -288.219444)
			(xy 375.80176 -288.230388) (xy 375.799096 -288.23666) (xy 375.79554 -288.245804) (xy 375.79554 -288.460688)
			(xy 375.795784 -288.46787) (xy 375.799777 -288.481668) (xy 375.803414 -288.487866) (xy 375.81745 -288.510794)
			(xy 375.838699 -288.560172) (xy 375.851675 -288.612338) (xy 375.856037 -288.665917) (xy 375.856037 -288.66592)
			(xy 376.148595 -288.66592) (xy 376.15269 -288.615192) (xy 376.164869 -288.565778) (xy 376.184817 -288.518958)
			(xy 376.212018 -288.475944) (xy 376.245766 -288.43785) (xy 376.285188 -288.405663) (xy 376.329262 -288.380217)
			(xy 376.376848 -288.36217) (xy 376.426712 -288.35199) (xy 376.477564 -288.349941) (xy 376.528085 -288.356075)
			(xy 376.576969 -288.370235) (xy 376.622948 -288.392052) (xy 376.664832 -288.420962) (xy 376.701536 -288.456217)
			(xy 376.732109 -288.496903) (xy 376.75576 -288.541966) (xy 376.771876 -288.59024) (xy 376.78004 -288.640474)
			(xy 376.780552 -288.66592) (xy 377.088649 -288.66592) (xy 377.092744 -288.615192) (xy 377.104923 -288.565778)
			(xy 377.124871 -288.518958) (xy 377.152072 -288.475944) (xy 377.18582 -288.43785) (xy 377.225242 -288.405663)
			(xy 377.269316 -288.380217) (xy 377.316902 -288.36217) (xy 377.366766 -288.35199) (xy 377.417618 -288.349941)
			(xy 377.468139 -288.356075) (xy 377.517023 -288.370235) (xy 377.563002 -288.392052) (xy 377.604886 -288.420962)
			(xy 377.64159 -288.456217) (xy 377.672163 -288.496903) (xy 377.695814 -288.541966) (xy 377.71193 -288.59024)
			(xy 377.720094 -288.640474) (xy 377.720606 -288.66592) (xy 378.039134 -288.66592) (xy 378.043094 -288.616866)
			(xy 378.054871 -288.569082) (xy 378.074162 -288.523806) (xy 378.100465 -288.48221) (xy 378.1331 -288.445373)
			(xy 378.171221 -288.414248) (xy 378.213842 -288.389641) (xy 378.259858 -288.372189) (xy 378.308077 -288.362345)
			(xy 378.357252 -288.360364) (xy 378.406107 -288.366296) (xy 378.453378 -288.379988) (xy 378.49784 -288.401086)
			(xy 378.538343 -288.429042) (xy 378.573836 -288.463134) (xy 378.603401 -288.502478) (xy 378.626272 -288.546055)
			(xy 378.641856 -288.592736) (xy 378.649751 -288.641313) (xy 378.650246 -288.66592) (xy 378.968503 -288.66592)
			(xy 378.972598 -288.615192) (xy 378.984777 -288.565778) (xy 379.004725 -288.518958) (xy 379.031926 -288.475944)
			(xy 379.065674 -288.43785) (xy 379.105096 -288.405663) (xy 379.14917 -288.380217) (xy 379.196756 -288.36217)
			(xy 379.24662 -288.35199) (xy 379.297472 -288.349941) (xy 379.347993 -288.356075) (xy 379.396877 -288.370235)
			(xy 379.442856 -288.392052) (xy 379.48474 -288.420962) (xy 379.521444 -288.456217) (xy 379.552017 -288.496903)
			(xy 379.575668 -288.541966) (xy 379.591784 -288.59024) (xy 379.599948 -288.640474) (xy 379.60046 -288.66592)
			(xy 379.918988 -288.66592) (xy 379.922948 -288.616866) (xy 379.934725 -288.569082) (xy 379.954016 -288.523806)
			(xy 379.980319 -288.48221) (xy 380.012954 -288.445373) (xy 380.051075 -288.414248) (xy 380.093696 -288.389641)
			(xy 380.139712 -288.372189) (xy 380.187931 -288.362345) (xy 380.237106 -288.360364) (xy 380.285961 -288.366296)
			(xy 380.333232 -288.379988) (xy 380.377694 -288.401086) (xy 380.418197 -288.429042) (xy 380.45369 -288.463134)
			(xy 380.483255 -288.502478) (xy 380.506126 -288.546055) (xy 380.52171 -288.592736) (xy 380.529605 -288.641313)
			(xy 380.5301 -288.66592) (xy 380.848611 -288.66592) (xy 380.852706 -288.615192) (xy 380.864885 -288.565778)
			(xy 380.884833 -288.518958) (xy 380.912034 -288.475944) (xy 380.945782 -288.43785) (xy 380.985204 -288.405663)
			(xy 381.029278 -288.380217) (xy 381.076864 -288.36217) (xy 381.126728 -288.35199) (xy 381.17758 -288.349941)
			(xy 381.228101 -288.356075) (xy 381.276985 -288.370235) (xy 381.322964 -288.392052) (xy 381.364848 -288.420962)
			(xy 381.401552 -288.456217) (xy 381.432125 -288.496903) (xy 381.455776 -288.541966) (xy 381.471892 -288.59024)
			(xy 381.480056 -288.640474) (xy 381.480568 -288.66592) (xy 381.480056 -288.691366) (xy 381.471892 -288.7416)
			(xy 381.455776 -288.789874) (xy 381.432125 -288.834937) (xy 381.401552 -288.875623) (xy 381.364848 -288.910878)
			(xy 381.322964 -288.939788) (xy 381.276985 -288.961605) (xy 381.228101 -288.975765) (xy 381.17758 -288.981899)
			(xy 381.126728 -288.97985) (xy 381.076864 -288.96967) (xy 381.029278 -288.951623) (xy 380.985204 -288.926177)
			(xy 380.945782 -288.89399) (xy 380.912034 -288.855896) (xy 380.884833 -288.812882) (xy 380.864885 -288.766062)
			(xy 380.852706 -288.716648) (xy 380.848611 -288.66592) (xy 380.5301 -288.66592) (xy 380.529605 -288.690527)
			(xy 380.52171 -288.739104) (xy 380.506126 -288.785785) (xy 380.483255 -288.829362) (xy 380.45369 -288.868706)
			(xy 380.418197 -288.902798) (xy 380.377694 -288.930754) (xy 380.333232 -288.951852) (xy 380.285961 -288.965544)
			(xy 380.237106 -288.971476) (xy 380.187931 -288.969495) (xy 380.139712 -288.959651) (xy 380.093696 -288.942199)
			(xy 380.051075 -288.917592) (xy 380.012954 -288.886467) (xy 379.980319 -288.84963) (xy 379.954016 -288.808034)
			(xy 379.934725 -288.762758) (xy 379.922948 -288.714974) (xy 379.918988 -288.66592) (xy 379.60046 -288.66592)
			(xy 379.599948 -288.691366) (xy 379.591784 -288.7416) (xy 379.575668 -288.789874) (xy 379.552017 -288.834937)
			(xy 379.521444 -288.875623) (xy 379.48474 -288.910878) (xy 379.442856 -288.939788) (xy 379.396877 -288.961605)
			(xy 379.347993 -288.975765) (xy 379.297472 -288.981899) (xy 379.24662 -288.97985) (xy 379.196756 -288.96967)
			(xy 379.14917 -288.951623) (xy 379.105096 -288.926177) (xy 379.065674 -288.89399) (xy 379.031926 -288.855896)
			(xy 379.004725 -288.812882) (xy 378.984777 -288.766062) (xy 378.972598 -288.716648) (xy 378.968503 -288.66592)
			(xy 378.650246 -288.66592) (xy 378.649751 -288.690527) (xy 378.641856 -288.739104) (xy 378.626272 -288.785785)
			(xy 378.603401 -288.829362) (xy 378.573836 -288.868706) (xy 378.538343 -288.902798) (xy 378.49784 -288.930754)
			(xy 378.453378 -288.951852) (xy 378.406107 -288.965544) (xy 378.357252 -288.971476) (xy 378.308077 -288.969495)
			(xy 378.259858 -288.959651) (xy 378.213842 -288.942199) (xy 378.171221 -288.917592) (xy 378.1331 -288.886467)
			(xy 378.100465 -288.84963) (xy 378.074162 -288.808034) (xy 378.054871 -288.762758) (xy 378.043094 -288.714974)
			(xy 378.039134 -288.66592) (xy 377.720606 -288.66592) (xy 377.720094 -288.691366) (xy 377.71193 -288.7416)
			(xy 377.695814 -288.789874) (xy 377.672163 -288.834937) (xy 377.64159 -288.875623) (xy 377.604886 -288.910878)
			(xy 377.563002 -288.939788) (xy 377.517023 -288.961605) (xy 377.468139 -288.975765) (xy 377.417618 -288.981899)
			(xy 377.366766 -288.97985) (xy 377.316902 -288.96967) (xy 377.269316 -288.951623) (xy 377.225242 -288.926177)
			(xy 377.18582 -288.89399) (xy 377.152072 -288.855896) (xy 377.124871 -288.812882) (xy 377.104923 -288.766062)
			(xy 377.092744 -288.716648) (xy 377.088649 -288.66592) (xy 376.780552 -288.66592) (xy 376.78004 -288.691366)
			(xy 376.771876 -288.7416) (xy 376.75576 -288.789874) (xy 376.732109 -288.834937) (xy 376.701536 -288.875623)
			(xy 376.664832 -288.910878) (xy 376.622948 -288.939788) (xy 376.576969 -288.961605) (xy 376.528085 -288.975765)
			(xy 376.477564 -288.981899) (xy 376.426712 -288.97985) (xy 376.376848 -288.96967) (xy 376.329262 -288.951623)
			(xy 376.285188 -288.926177) (xy 376.245766 -288.89399) (xy 376.212018 -288.855896) (xy 376.184817 -288.812882)
			(xy 376.164869 -288.766062) (xy 376.15269 -288.716648) (xy 376.148595 -288.66592) (xy 375.856037 -288.66592)
			(xy 375.851669 -288.719495) (xy 375.838688 -288.77166) (xy 375.817435 -288.821036) (xy 375.803414 -288.843974)
			(xy 375.799784 -288.850175) (xy 375.795795 -288.863971) (xy 375.79554 -288.871152) (xy 375.79554 -289.077146)
			(xy 375.797572 -289.087306) (xy 375.799666 -289.096159) (xy 375.809168 -289.111657) (xy 375.816114 -289.117532)
			(xy 375.881138 -289.168586) (xy 375.904252 -289.173412) (xy 375.915682 -289.170364) (xy 375.93515 -289.165622)
			(xy 375.974895 -289.160531) (xy 375.99493 -289.160204) (xy 376.019736 -289.160693) (xy 376.068737 -289.168458)
			(xy 376.115919 -289.183793) (xy 376.160122 -289.206319) (xy 376.200258 -289.235483) (xy 376.235337 -289.270565)
			(xy 376.264497 -289.310703) (xy 376.287019 -289.354909) (xy 376.302349 -289.402093) (xy 376.310109 -289.451094)
			(xy 376.310109 -289.475926) (xy 376.628926 -289.475926) (xy 376.632886 -289.426872) (xy 376.644663 -289.379088)
			(xy 376.663954 -289.333812) (xy 376.690257 -289.292216) (xy 376.722892 -289.255379) (xy 376.761013 -289.224254)
			(xy 376.803634 -289.199647) (xy 376.84965 -289.182195) (xy 376.897869 -289.172351) (xy 376.947044 -289.17037)
			(xy 376.995899 -289.176302) (xy 377.04317 -289.189994) (xy 377.087632 -289.211092) (xy 377.128135 -289.239048)
			(xy 377.163628 -289.27314) (xy 377.193193 -289.312484) (xy 377.216064 -289.356061) (xy 377.231648 -289.402742)
			(xy 377.239543 -289.451319) (xy 377.240038 -289.475926) (xy 377.558549 -289.475926) (xy 377.562644 -289.425198)
			(xy 377.574823 -289.375784) (xy 377.594771 -289.328964) (xy 377.621972 -289.28595) (xy 377.65572 -289.247856)
			(xy 377.695142 -289.215669) (xy 377.739216 -289.190223) (xy 377.786802 -289.172176) (xy 377.836666 -289.161996)
			(xy 377.887518 -289.159947) (xy 377.938039 -289.166081) (xy 377.986923 -289.180241) (xy 378.032902 -289.202058)
			(xy 378.074786 -289.230968) (xy 378.11149 -289.266223) (xy 378.142063 -289.306909) (xy 378.165714 -289.351972)
			(xy 378.18183 -289.400246) (xy 378.189994 -289.45048) (xy 378.190506 -289.475926) (xy 378.509034 -289.475926)
			(xy 378.512994 -289.426872) (xy 378.524771 -289.379088) (xy 378.544062 -289.333812) (xy 378.570365 -289.292216)
			(xy 378.603 -289.255379) (xy 378.641121 -289.224254) (xy 378.683742 -289.199647) (xy 378.729758 -289.182195)
			(xy 378.777977 -289.172351) (xy 378.827152 -289.17037) (xy 378.876007 -289.176302) (xy 378.923278 -289.189994)
			(xy 378.96774 -289.211092) (xy 379.008243 -289.239048) (xy 379.043736 -289.27314) (xy 379.073301 -289.312484)
			(xy 379.096172 -289.356061) (xy 379.111756 -289.402742) (xy 379.119651 -289.451319) (xy 379.120146 -289.475926)
			(xy 379.438657 -289.475926) (xy 379.442752 -289.425198) (xy 379.454931 -289.375784) (xy 379.474879 -289.328964)
			(xy 379.50208 -289.28595) (xy 379.535828 -289.247856) (xy 379.57525 -289.215669) (xy 379.619324 -289.190223)
			(xy 379.66691 -289.172176) (xy 379.716774 -289.161996) (xy 379.767626 -289.159947) (xy 379.818147 -289.166081)
			(xy 379.867031 -289.180241) (xy 379.91301 -289.202058) (xy 379.954894 -289.230968) (xy 379.991598 -289.266223)
			(xy 380.022171 -289.306909) (xy 380.045822 -289.351972) (xy 380.061938 -289.400246) (xy 380.070102 -289.45048)
			(xy 380.070614 -289.475926) (xy 380.378711 -289.475926) (xy 380.382806 -289.425198) (xy 380.394985 -289.375784)
			(xy 380.414933 -289.328964) (xy 380.442134 -289.28595) (xy 380.475882 -289.247856) (xy 380.515304 -289.215669)
			(xy 380.559378 -289.190223) (xy 380.606964 -289.172176) (xy 380.656828 -289.161996) (xy 380.70768 -289.159947)
			(xy 380.758201 -289.166081) (xy 380.807085 -289.180241) (xy 380.853064 -289.202058) (xy 380.894948 -289.230968)
			(xy 380.931652 -289.266223) (xy 380.962225 -289.306909) (xy 380.985876 -289.351972) (xy 381.001992 -289.400246)
			(xy 381.010156 -289.45048) (xy 381.010668 -289.475926) (xy 381.010156 -289.501372) (xy 381.001992 -289.551606)
			(xy 380.985876 -289.59988) (xy 380.962225 -289.644943) (xy 380.931652 -289.685629) (xy 380.894948 -289.720884)
			(xy 380.853064 -289.749794) (xy 380.807085 -289.771611) (xy 380.758201 -289.785771) (xy 380.70768 -289.791905)
			(xy 380.656828 -289.789856) (xy 380.606964 -289.779676) (xy 380.559378 -289.761629) (xy 380.515304 -289.736183)
			(xy 380.475882 -289.703996) (xy 380.442134 -289.665902) (xy 380.414933 -289.622888) (xy 380.394985 -289.576068)
			(xy 380.382806 -289.526654) (xy 380.378711 -289.475926) (xy 380.070614 -289.475926) (xy 380.070102 -289.501372)
			(xy 380.061938 -289.551606) (xy 380.045822 -289.59988) (xy 380.022171 -289.644943) (xy 379.991598 -289.685629)
			(xy 379.954894 -289.720884) (xy 379.91301 -289.749794) (xy 379.867031 -289.771611) (xy 379.818147 -289.785771)
			(xy 379.767626 -289.791905) (xy 379.716774 -289.789856) (xy 379.66691 -289.779676) (xy 379.619324 -289.761629)
			(xy 379.57525 -289.736183) (xy 379.535828 -289.703996) (xy 379.50208 -289.665902) (xy 379.474879 -289.622888)
			(xy 379.454931 -289.576068) (xy 379.442752 -289.526654) (xy 379.438657 -289.475926) (xy 379.120146 -289.475926)
			(xy 379.119651 -289.500533) (xy 379.111756 -289.54911) (xy 379.096172 -289.595791) (xy 379.073301 -289.639368)
			(xy 379.043736 -289.678712) (xy 379.008243 -289.712804) (xy 378.96774 -289.74076) (xy 378.923278 -289.761858)
			(xy 378.876007 -289.77555) (xy 378.827152 -289.781482) (xy 378.777977 -289.779501) (xy 378.729758 -289.769657)
			(xy 378.683742 -289.752205) (xy 378.641121 -289.727598) (xy 378.603 -289.696473) (xy 378.570365 -289.659636)
			(xy 378.544062 -289.61804) (xy 378.524771 -289.572764) (xy 378.512994 -289.52498) (xy 378.509034 -289.475926)
			(xy 378.190506 -289.475926) (xy 378.189994 -289.501372) (xy 378.18183 -289.551606) (xy 378.165714 -289.59988)
			(xy 378.142063 -289.644943) (xy 378.11149 -289.685629) (xy 378.074786 -289.720884) (xy 378.032902 -289.749794)
			(xy 377.986923 -289.771611) (xy 377.938039 -289.785771) (xy 377.887518 -289.791905) (xy 377.836666 -289.789856)
			(xy 377.786802 -289.779676) (xy 377.739216 -289.761629) (xy 377.695142 -289.736183) (xy 377.65572 -289.703996)
			(xy 377.621972 -289.665902) (xy 377.594771 -289.622888) (xy 377.574823 -289.576068) (xy 377.562644 -289.526654)
			(xy 377.558549 -289.475926) (xy 377.240038 -289.475926) (xy 377.239543 -289.500533) (xy 377.231648 -289.54911)
			(xy 377.216064 -289.595791) (xy 377.193193 -289.639368) (xy 377.163628 -289.678712) (xy 377.128135 -289.712804)
			(xy 377.087632 -289.74076) (xy 377.04317 -289.761858) (xy 376.995899 -289.77555) (xy 376.947044 -289.781482)
			(xy 376.897869 -289.779501) (xy 376.84965 -289.769657) (xy 376.803634 -289.752205) (xy 376.761013 -289.727598)
			(xy 376.722892 -289.696473) (xy 376.690257 -289.659636) (xy 376.663954 -289.61804) (xy 376.644663 -289.572764)
			(xy 376.632886 -289.52498) (xy 376.628926 -289.475926) (xy 376.310109 -289.475926) (xy 376.310109 -289.500706)
			(xy 376.302349 -289.549707) (xy 376.287019 -289.596891) (xy 376.264497 -289.641097) (xy 376.235337 -289.681235)
			(xy 376.200258 -289.716317) (xy 376.160122 -289.745481) (xy 376.115919 -289.768007) (xy 376.068737 -289.783342)
			(xy 376.019736 -289.791107) (xy 375.99493 -289.791648) (xy 375.970255 -289.79111) (xy 375.921518 -289.783326)
			(xy 375.897902 -289.776154) (xy 375.88698 -289.778694) (xy 375.815098 -289.834828) (xy 375.809753 -289.839364)
			(xy 375.801508 -289.850696) (xy 375.798842 -289.85718) (xy 375.79554 -289.865816) (xy 375.79554 -290.138866)
			(xy 375.797826 -290.149534) (xy 375.800366 -290.154868) (xy 375.809715 -290.175441) (xy 375.822933 -290.218653)
			(xy 375.829649 -290.263339) (xy 375.830084 -290.285932) (xy 376.148595 -290.285932) (xy 376.15269 -290.235204)
			(xy 376.164869 -290.18579) (xy 376.184817 -290.13897) (xy 376.212018 -290.095956) (xy 376.245766 -290.057862)
			(xy 376.285188 -290.025675) (xy 376.329262 -290.000229) (xy 376.376848 -289.982182) (xy 376.426712 -289.972002)
			(xy 376.477564 -289.969953) (xy 376.528085 -289.976087) (xy 376.576969 -289.990247) (xy 376.622948 -290.012064)
			(xy 376.664832 -290.040974) (xy 376.701536 -290.076229) (xy 376.732109 -290.116915) (xy 376.75576 -290.161978)
			(xy 376.771876 -290.210252) (xy 376.78004 -290.260486) (xy 376.780552 -290.285932) (xy 377.088649 -290.285932)
			(xy 377.092744 -290.235204) (xy 377.104923 -290.18579) (xy 377.124871 -290.13897) (xy 377.152072 -290.095956)
			(xy 377.18582 -290.057862) (xy 377.225242 -290.025675) (xy 377.269316 -290.000229) (xy 377.316902 -289.982182)
			(xy 377.366766 -289.972002) (xy 377.417618 -289.969953) (xy 377.468139 -289.976087) (xy 377.517023 -289.990247)
			(xy 377.563002 -290.012064) (xy 377.604886 -290.040974) (xy 377.64159 -290.076229) (xy 377.672163 -290.116915)
			(xy 377.695814 -290.161978) (xy 377.71193 -290.210252) (xy 377.720094 -290.260486) (xy 377.720606 -290.285932)
			(xy 378.968503 -290.285932) (xy 378.972598 -290.235204) (xy 378.984777 -290.18579) (xy 379.004725 -290.13897)
			(xy 379.031926 -290.095956) (xy 379.065674 -290.057862) (xy 379.105096 -290.025675) (xy 379.14917 -290.000229)
			(xy 379.196756 -289.982182) (xy 379.24662 -289.972002) (xy 379.297472 -289.969953) (xy 379.347993 -289.976087)
			(xy 379.396877 -289.990247) (xy 379.442856 -290.012064) (xy 379.48474 -290.040974) (xy 379.521444 -290.076229)
			(xy 379.552017 -290.116915) (xy 379.575668 -290.161978) (xy 379.591784 -290.210252) (xy 379.599948 -290.260486)
			(xy 379.60046 -290.285932) (xy 379.918988 -290.285932) (xy 379.922948 -290.236878) (xy 379.934725 -290.189094)
			(xy 379.954016 -290.143818) (xy 379.980319 -290.102222) (xy 380.012954 -290.065385) (xy 380.051075 -290.03426)
			(xy 380.093696 -290.009653) (xy 380.139712 -289.992201) (xy 380.187931 -289.982357) (xy 380.237106 -289.980376)
			(xy 380.285961 -289.986308) (xy 380.333232 -290) (xy 380.377694 -290.021098) (xy 380.418197 -290.049054)
			(xy 380.45369 -290.083146) (xy 380.483255 -290.12249) (xy 380.506126 -290.166067) (xy 380.52171 -290.212748)
			(xy 380.529605 -290.261325) (xy 380.5301 -290.285932) (xy 380.848611 -290.285932) (xy 380.852706 -290.235204)
			(xy 380.864885 -290.18579) (xy 380.884833 -290.13897) (xy 380.912034 -290.095956) (xy 380.945782 -290.057862)
			(xy 380.985204 -290.025675) (xy 381.029278 -290.000229) (xy 381.076864 -289.982182) (xy 381.126728 -289.972002)
			(xy 381.17758 -289.969953) (xy 381.228101 -289.976087) (xy 381.276985 -289.990247) (xy 381.322964 -290.012064)
			(xy 381.364848 -290.040974) (xy 381.401552 -290.076229) (xy 381.432125 -290.116915) (xy 381.455776 -290.161978)
			(xy 381.471892 -290.210252) (xy 381.480056 -290.260486) (xy 381.480568 -290.285932) (xy 381.480056 -290.311378)
			(xy 381.471892 -290.361612) (xy 381.455776 -290.409886) (xy 381.432125 -290.454949) (xy 381.401552 -290.495635)
			(xy 381.364848 -290.53089) (xy 381.322964 -290.5598) (xy 381.276985 -290.581617) (xy 381.228101 -290.595777)
			(xy 381.17758 -290.601911) (xy 381.126728 -290.599862) (xy 381.076864 -290.589682) (xy 381.029278 -290.571635)
			(xy 380.985204 -290.546189) (xy 380.945782 -290.514002) (xy 380.912034 -290.475908) (xy 380.884833 -290.432894)
			(xy 380.864885 -290.386074) (xy 380.852706 -290.33666) (xy 380.848611 -290.285932) (xy 380.5301 -290.285932)
			(xy 380.529605 -290.310539) (xy 380.52171 -290.359116) (xy 380.506126 -290.405797) (xy 380.483255 -290.449374)
			(xy 380.45369 -290.488718) (xy 380.418197 -290.52281) (xy 380.377694 -290.550766) (xy 380.333232 -290.571864)
			(xy 380.285961 -290.585556) (xy 380.237106 -290.591488) (xy 380.187931 -290.589507) (xy 380.139712 -290.579663)
			(xy 380.093696 -290.562211) (xy 380.051075 -290.537604) (xy 380.012954 -290.506479) (xy 379.980319 -290.469642)
			(xy 379.954016 -290.428046) (xy 379.934725 -290.38277) (xy 379.922948 -290.334986) (xy 379.918988 -290.285932)
			(xy 379.60046 -290.285932) (xy 379.599948 -290.311378) (xy 379.591784 -290.361612) (xy 379.575668 -290.409886)
			(xy 379.552017 -290.454949) (xy 379.521444 -290.495635) (xy 379.48474 -290.53089) (xy 379.442856 -290.5598)
			(xy 379.396877 -290.581617) (xy 379.347993 -290.595777) (xy 379.297472 -290.601911) (xy 379.24662 -290.599862)
			(xy 379.196756 -290.589682) (xy 379.14917 -290.571635) (xy 379.105096 -290.546189) (xy 379.065674 -290.514002)
			(xy 379.031926 -290.475908) (xy 379.004725 -290.432894) (xy 378.984777 -290.386074) (xy 378.972598 -290.33666)
			(xy 378.968503 -290.285932) (xy 377.720606 -290.285932) (xy 377.720094 -290.311378) (xy 377.71193 -290.361612)
			(xy 377.695814 -290.409886) (xy 377.672163 -290.454949) (xy 377.64159 -290.495635) (xy 377.604886 -290.53089)
			(xy 377.563002 -290.5598) (xy 377.517023 -290.581617) (xy 377.468139 -290.595777) (xy 377.417618 -290.601911)
			(xy 377.366766 -290.599862) (xy 377.316902 -290.589682) (xy 377.269316 -290.571635) (xy 377.225242 -290.546189)
			(xy 377.18582 -290.514002) (xy 377.152072 -290.475908) (xy 377.124871 -290.432894) (xy 377.104923 -290.386074)
			(xy 377.092744 -290.33666) (xy 377.088649 -290.285932) (xy 376.780552 -290.285932) (xy 376.78004 -290.311378)
			(xy 376.771876 -290.361612) (xy 376.75576 -290.409886) (xy 376.732109 -290.454949) (xy 376.701536 -290.495635)
			(xy 376.664832 -290.53089) (xy 376.622948 -290.5598) (xy 376.576969 -290.581617) (xy 376.528085 -290.595777)
			(xy 376.477564 -290.601911) (xy 376.426712 -290.599862) (xy 376.376848 -290.589682) (xy 376.329262 -290.571635)
			(xy 376.285188 -290.546189) (xy 376.245766 -290.514002) (xy 376.212018 -290.475908) (xy 376.184817 -290.432894)
			(xy 376.164869 -290.386074) (xy 376.15269 -290.33666) (xy 376.148595 -290.285932) (xy 375.830084 -290.285932)
			(xy 375.829656 -290.308526) (xy 375.822948 -290.353214) (xy 375.809713 -290.396421) (xy 375.800366 -290.416996)
			(xy 375.797826 -290.42233) (xy 375.79554 -290.432998) (xy 375.79554 -290.697158) (xy 375.797572 -290.707318)
			(xy 375.799668 -290.71617) (xy 375.809172 -290.731665) (xy 375.816114 -290.737544) (xy 375.881138 -290.788598)
			(xy 375.904252 -290.793424) (xy 375.915682 -290.790376) (xy 375.93515 -290.785634) (xy 375.974895 -290.780543)
			(xy 375.99493 -290.780216) (xy 376.019735 -290.780705) (xy 376.068734 -290.78847) (xy 376.115915 -290.803804)
			(xy 376.160116 -290.826329) (xy 376.20025 -290.855492) (xy 376.235328 -290.890573) (xy 376.264486 -290.93071)
			(xy 376.287008 -290.974913) (xy 376.302337 -291.022095) (xy 376.310097 -291.071095) (xy 376.310097 -291.095938)
			(xy 376.628926 -291.095938) (xy 376.632886 -291.046884) (xy 376.644663 -290.9991) (xy 376.663954 -290.953824)
			(xy 376.690257 -290.912228) (xy 376.722892 -290.875391) (xy 376.761013 -290.844266) (xy 376.803634 -290.819659)
			(xy 376.84965 -290.802207) (xy 376.897869 -290.792363) (xy 376.947044 -290.790382) (xy 376.995899 -290.796314)
			(xy 377.04317 -290.810006) (xy 377.087632 -290.831104) (xy 377.128135 -290.85906) (xy 377.163628 -290.893152)
			(xy 377.193193 -290.932496) (xy 377.216064 -290.976073) (xy 377.231648 -291.022754) (xy 377.239543 -291.071331)
			(xy 377.240038 -291.095938) (xy 377.558549 -291.095938) (xy 377.562644 -291.04521) (xy 377.574823 -290.995796)
			(xy 377.594771 -290.948976) (xy 377.621972 -290.905962) (xy 377.65572 -290.867868) (xy 377.695142 -290.835681)
			(xy 377.739216 -290.810235) (xy 377.786802 -290.792188) (xy 377.836666 -290.782008) (xy 377.887518 -290.779959)
			(xy 377.938039 -290.786093) (xy 377.986923 -290.800253) (xy 378.032902 -290.82207) (xy 378.074786 -290.85098)
			(xy 378.11149 -290.886235) (xy 378.142063 -290.926921) (xy 378.165714 -290.971984) (xy 378.18183 -291.020258)
			(xy 378.189994 -291.070492) (xy 378.190506 -291.095938) (xy 378.509034 -291.095938) (xy 378.512994 -291.046884)
			(xy 378.524771 -290.9991) (xy 378.544062 -290.953824) (xy 378.570365 -290.912228) (xy 378.603 -290.875391)
			(xy 378.641121 -290.844266) (xy 378.683742 -290.819659) (xy 378.729758 -290.802207) (xy 378.777977 -290.792363)
			(xy 378.827152 -290.790382) (xy 378.876007 -290.796314) (xy 378.923278 -290.810006) (xy 378.96774 -290.831104)
			(xy 379.008243 -290.85906) (xy 379.043736 -290.893152) (xy 379.073301 -290.932496) (xy 379.096172 -290.976073)
			(xy 379.111756 -291.022754) (xy 379.119651 -291.071331) (xy 379.120146 -291.095938) (xy 379.438657 -291.095938)
			(xy 379.442752 -291.04521) (xy 379.454931 -290.995796) (xy 379.474879 -290.948976) (xy 379.50208 -290.905962)
			(xy 379.535828 -290.867868) (xy 379.57525 -290.835681) (xy 379.619324 -290.810235) (xy 379.66691 -290.792188)
			(xy 379.716774 -290.782008) (xy 379.767626 -290.779959) (xy 379.818147 -290.786093) (xy 379.867031 -290.800253)
			(xy 379.91301 -290.82207) (xy 379.954894 -290.85098) (xy 379.991598 -290.886235) (xy 380.022171 -290.926921)
			(xy 380.045822 -290.971984) (xy 380.061938 -291.020258) (xy 380.070102 -291.070492) (xy 380.070614 -291.095938)
			(xy 380.378711 -291.095938) (xy 380.382806 -291.04521) (xy 380.394985 -290.995796) (xy 380.414933 -290.948976)
			(xy 380.442134 -290.905962) (xy 380.475882 -290.867868) (xy 380.515304 -290.835681) (xy 380.559378 -290.810235)
			(xy 380.606964 -290.792188) (xy 380.656828 -290.782008) (xy 380.70768 -290.779959) (xy 380.758201 -290.786093)
			(xy 380.807085 -290.800253) (xy 380.853064 -290.82207) (xy 380.894948 -290.85098) (xy 380.931652 -290.886235)
			(xy 380.962225 -290.926921) (xy 380.985876 -290.971984) (xy 381.001992 -291.020258) (xy 381.010156 -291.070492)
			(xy 381.010668 -291.095938) (xy 381.010156 -291.121384) (xy 381.001992 -291.171618) (xy 380.985876 -291.219892)
			(xy 380.962225 -291.264955) (xy 380.931652 -291.305641) (xy 380.894948 -291.340896) (xy 380.853064 -291.369806)
			(xy 380.807085 -291.391623) (xy 380.758201 -291.405783) (xy 380.70768 -291.411917) (xy 380.656828 -291.409868)
			(xy 380.606964 -291.399688) (xy 380.559378 -291.381641) (xy 380.515304 -291.356195) (xy 380.475882 -291.324008)
			(xy 380.442134 -291.285914) (xy 380.414933 -291.2429) (xy 380.394985 -291.19608) (xy 380.382806 -291.146666)
			(xy 380.378711 -291.095938) (xy 380.070614 -291.095938) (xy 380.070102 -291.121384) (xy 380.061938 -291.171618)
			(xy 380.045822 -291.219892) (xy 380.022171 -291.264955) (xy 379.991598 -291.305641) (xy 379.954894 -291.340896)
			(xy 379.91301 -291.369806) (xy 379.867031 -291.391623) (xy 379.818147 -291.405783) (xy 379.767626 -291.411917)
			(xy 379.716774 -291.409868) (xy 379.66691 -291.399688) (xy 379.619324 -291.381641) (xy 379.57525 -291.356195)
			(xy 379.535828 -291.324008) (xy 379.50208 -291.285914) (xy 379.474879 -291.2429) (xy 379.454931 -291.19608)
			(xy 379.442752 -291.146666) (xy 379.438657 -291.095938) (xy 379.120146 -291.095938) (xy 379.119651 -291.120545)
			(xy 379.111756 -291.169122) (xy 379.096172 -291.215803) (xy 379.073301 -291.25938) (xy 379.043736 -291.298724)
			(xy 379.008243 -291.332816) (xy 378.96774 -291.360772) (xy 378.923278 -291.38187) (xy 378.876007 -291.395562)
			(xy 378.827152 -291.401494) (xy 378.777977 -291.399513) (xy 378.729758 -291.389669) (xy 378.683742 -291.372217)
			(xy 378.641121 -291.34761) (xy 378.603 -291.316485) (xy 378.570365 -291.279648) (xy 378.544062 -291.238052)
			(xy 378.524771 -291.192776) (xy 378.512994 -291.144992) (xy 378.509034 -291.095938) (xy 378.190506 -291.095938)
			(xy 378.189994 -291.121384) (xy 378.18183 -291.171618) (xy 378.165714 -291.219892) (xy 378.142063 -291.264955)
			(xy 378.11149 -291.305641) (xy 378.074786 -291.340896) (xy 378.032902 -291.369806) (xy 377.986923 -291.391623)
			(xy 377.938039 -291.405783) (xy 377.887518 -291.411917) (xy 377.836666 -291.409868) (xy 377.786802 -291.399688)
			(xy 377.739216 -291.381641) (xy 377.695142 -291.356195) (xy 377.65572 -291.324008) (xy 377.621972 -291.285914)
			(xy 377.594771 -291.2429) (xy 377.574823 -291.19608) (xy 377.562644 -291.146666) (xy 377.558549 -291.095938)
			(xy 377.240038 -291.095938) (xy 377.239543 -291.120545) (xy 377.231648 -291.169122) (xy 377.216064 -291.215803)
			(xy 377.193193 -291.25938) (xy 377.163628 -291.298724) (xy 377.128135 -291.332816) (xy 377.087632 -291.360772)
			(xy 377.04317 -291.38187) (xy 376.995899 -291.395562) (xy 376.947044 -291.401494) (xy 376.897869 -291.399513)
			(xy 376.84965 -291.389669) (xy 376.803634 -291.372217) (xy 376.761013 -291.34761) (xy 376.722892 -291.316485)
			(xy 376.690257 -291.279648) (xy 376.663954 -291.238052) (xy 376.644663 -291.192776) (xy 376.632886 -291.144992)
			(xy 376.628926 -291.095938) (xy 376.310097 -291.095938) (xy 376.310097 -291.120705) (xy 376.302337 -291.169705)
			(xy 376.287008 -291.216887) (xy 376.264486 -291.26109) (xy 376.235328 -291.301227) (xy 376.20025 -291.336308)
			(xy 376.160116 -291.365471) (xy 376.115915 -291.387996) (xy 376.068734 -291.40333) (xy 376.019735 -291.411095)
			(xy 375.99493 -291.41166) (xy 375.970254 -291.411122) (xy 375.921518 -291.403338) (xy 375.897902 -291.396166)
			(xy 375.88698 -291.398706) (xy 375.815098 -291.45484) (xy 375.809754 -291.459377) (xy 375.801512 -291.47071)
			(xy 375.798842 -291.477192) (xy 375.79554 -291.485828) (xy 375.79554 -291.758878) (xy 375.797826 -291.769546)
			(xy 375.800366 -291.77488) (xy 375.809715 -291.795453) (xy 375.82293 -291.838665) (xy 375.829645 -291.883351)
			(xy 375.830084 -291.905944) (xy 376.148595 -291.905944) (xy 376.15269 -291.855216) (xy 376.164869 -291.805802)
			(xy 376.184817 -291.758982) (xy 376.212018 -291.715968) (xy 376.245766 -291.677874) (xy 376.285188 -291.645687)
			(xy 376.329262 -291.620241) (xy 376.376848 -291.602194) (xy 376.426712 -291.592014) (xy 376.477564 -291.589965)
			(xy 376.528085 -291.596099) (xy 376.576969 -291.610259) (xy 376.622948 -291.632076) (xy 376.664832 -291.660986)
			(xy 376.701536 -291.696241) (xy 376.732109 -291.736927) (xy 376.75576 -291.78199) (xy 376.771876 -291.830264)
			(xy 376.78004 -291.880498) (xy 376.780552 -291.905944) (xy 377.088649 -291.905944) (xy 377.092744 -291.855216)
			(xy 377.104923 -291.805802) (xy 377.124871 -291.758982) (xy 377.152072 -291.715968) (xy 377.18582 -291.677874)
			(xy 377.225242 -291.645687) (xy 377.269316 -291.620241) (xy 377.316902 -291.602194) (xy 377.366766 -291.592014)
			(xy 377.417618 -291.589965) (xy 377.468139 -291.596099) (xy 377.517023 -291.610259) (xy 377.563002 -291.632076)
			(xy 377.604886 -291.660986) (xy 377.64159 -291.696241) (xy 377.672163 -291.736927) (xy 377.695814 -291.78199)
			(xy 377.71193 -291.830264) (xy 377.720094 -291.880498) (xy 377.720606 -291.905944) (xy 378.039134 -291.905944)
			(xy 378.043094 -291.85689) (xy 378.054871 -291.809106) (xy 378.074162 -291.76383) (xy 378.100465 -291.722234)
			(xy 378.1331 -291.685397) (xy 378.171221 -291.654272) (xy 378.213842 -291.629665) (xy 378.259858 -291.612213)
			(xy 378.308077 -291.602369) (xy 378.357252 -291.600388) (xy 378.406107 -291.60632) (xy 378.453378 -291.620012)
			(xy 378.49784 -291.64111) (xy 378.538343 -291.669066) (xy 378.573836 -291.703158) (xy 378.603401 -291.742502)
			(xy 378.626272 -291.786079) (xy 378.641856 -291.83276) (xy 378.649751 -291.881337) (xy 378.650246 -291.905944)
			(xy 378.968503 -291.905944) (xy 378.972598 -291.855216) (xy 378.984777 -291.805802) (xy 379.004725 -291.758982)
			(xy 379.031926 -291.715968) (xy 379.065674 -291.677874) (xy 379.105096 -291.645687) (xy 379.14917 -291.620241)
			(xy 379.196756 -291.602194) (xy 379.24662 -291.592014) (xy 379.297472 -291.589965) (xy 379.347993 -291.596099)
			(xy 379.396877 -291.610259) (xy 379.442856 -291.632076) (xy 379.48474 -291.660986) (xy 379.521444 -291.696241)
			(xy 379.552017 -291.736927) (xy 379.575668 -291.78199) (xy 379.591784 -291.830264) (xy 379.599948 -291.880498)
			(xy 379.60046 -291.905944) (xy 379.918988 -291.905944) (xy 379.922948 -291.85689) (xy 379.934725 -291.809106)
			(xy 379.954016 -291.76383) (xy 379.980319 -291.722234) (xy 380.012954 -291.685397) (xy 380.051075 -291.654272)
			(xy 380.093696 -291.629665) (xy 380.139712 -291.612213) (xy 380.187931 -291.602369) (xy 380.237106 -291.600388)
			(xy 380.285961 -291.60632) (xy 380.333232 -291.620012) (xy 380.377694 -291.64111) (xy 380.418197 -291.669066)
			(xy 380.45369 -291.703158) (xy 380.483255 -291.742502) (xy 380.506126 -291.786079) (xy 380.52171 -291.83276)
			(xy 380.529605 -291.881337) (xy 380.5301 -291.905944) (xy 380.848611 -291.905944) (xy 380.852706 -291.855216)
			(xy 380.864885 -291.805802) (xy 380.884833 -291.758982) (xy 380.912034 -291.715968) (xy 380.945782 -291.677874)
			(xy 380.985204 -291.645687) (xy 381.029278 -291.620241) (xy 381.076864 -291.602194) (xy 381.126728 -291.592014)
			(xy 381.17758 -291.589965) (xy 381.228101 -291.596099) (xy 381.276985 -291.610259) (xy 381.322964 -291.632076)
			(xy 381.364848 -291.660986) (xy 381.401552 -291.696241) (xy 381.432125 -291.736927) (xy 381.455776 -291.78199)
			(xy 381.471892 -291.830264) (xy 381.480056 -291.880498) (xy 381.480568 -291.905944) (xy 381.480056 -291.93139)
			(xy 381.471892 -291.981624) (xy 381.455776 -292.029898) (xy 381.432125 -292.074961) (xy 381.401552 -292.115647)
			(xy 381.364848 -292.150902) (xy 381.322964 -292.179812) (xy 381.276985 -292.201629) (xy 381.228101 -292.215789)
			(xy 381.17758 -292.221923) (xy 381.126728 -292.219874) (xy 381.076864 -292.209694) (xy 381.029278 -292.191647)
			(xy 380.985204 -292.166201) (xy 380.945782 -292.134014) (xy 380.912034 -292.09592) (xy 380.884833 -292.052906)
			(xy 380.864885 -292.006086) (xy 380.852706 -291.956672) (xy 380.848611 -291.905944) (xy 380.5301 -291.905944)
			(xy 380.529605 -291.930551) (xy 380.52171 -291.979128) (xy 380.506126 -292.025809) (xy 380.483255 -292.069386)
			(xy 380.45369 -292.10873) (xy 380.418197 -292.142822) (xy 380.377694 -292.170778) (xy 380.333232 -292.191876)
			(xy 380.285961 -292.205568) (xy 380.237106 -292.2115) (xy 380.187931 -292.209519) (xy 380.139712 -292.199675)
			(xy 380.093696 -292.182223) (xy 380.051075 -292.157616) (xy 380.012954 -292.126491) (xy 379.980319 -292.089654)
			(xy 379.954016 -292.048058) (xy 379.934725 -292.002782) (xy 379.922948 -291.954998) (xy 379.918988 -291.905944)
			(xy 379.60046 -291.905944) (xy 379.599948 -291.93139) (xy 379.591784 -291.981624) (xy 379.575668 -292.029898)
			(xy 379.552017 -292.074961) (xy 379.521444 -292.115647) (xy 379.48474 -292.150902) (xy 379.442856 -292.179812)
			(xy 379.396877 -292.201629) (xy 379.347993 -292.215789) (xy 379.297472 -292.221923) (xy 379.24662 -292.219874)
			(xy 379.196756 -292.209694) (xy 379.14917 -292.191647) (xy 379.105096 -292.166201) (xy 379.065674 -292.134014)
			(xy 379.031926 -292.09592) (xy 379.004725 -292.052906) (xy 378.984777 -292.006086) (xy 378.972598 -291.956672)
			(xy 378.968503 -291.905944) (xy 378.650246 -291.905944) (xy 378.649751 -291.930551) (xy 378.641856 -291.979128)
			(xy 378.626272 -292.025809) (xy 378.603401 -292.069386) (xy 378.573836 -292.10873) (xy 378.538343 -292.142822)
			(xy 378.49784 -292.170778) (xy 378.453378 -292.191876) (xy 378.406107 -292.205568) (xy 378.357252 -292.2115)
			(xy 378.308077 -292.209519) (xy 378.259858 -292.199675) (xy 378.213842 -292.182223) (xy 378.171221 -292.157616)
			(xy 378.1331 -292.126491) (xy 378.100465 -292.089654) (xy 378.074162 -292.048058) (xy 378.054871 -292.002782)
			(xy 378.043094 -291.954998) (xy 378.039134 -291.905944) (xy 377.720606 -291.905944) (xy 377.720094 -291.93139)
			(xy 377.71193 -291.981624) (xy 377.695814 -292.029898) (xy 377.672163 -292.074961) (xy 377.64159 -292.115647)
			(xy 377.604886 -292.150902) (xy 377.563002 -292.179812) (xy 377.517023 -292.201629) (xy 377.468139 -292.215789)
			(xy 377.417618 -292.221923) (xy 377.366766 -292.219874) (xy 377.316902 -292.209694) (xy 377.269316 -292.191647)
			(xy 377.225242 -292.166201) (xy 377.18582 -292.134014) (xy 377.152072 -292.09592) (xy 377.124871 -292.052906)
			(xy 377.104923 -292.006086) (xy 377.092744 -291.956672) (xy 377.088649 -291.905944) (xy 376.780552 -291.905944)
			(xy 376.78004 -291.93139) (xy 376.771876 -291.981624) (xy 376.75576 -292.029898) (xy 376.732109 -292.074961)
			(xy 376.701536 -292.115647) (xy 376.664832 -292.150902) (xy 376.622948 -292.179812) (xy 376.576969 -292.201629)
			(xy 376.528085 -292.215789) (xy 376.477564 -292.221923) (xy 376.426712 -292.219874) (xy 376.376848 -292.209694)
			(xy 376.329262 -292.191647) (xy 376.285188 -292.166201) (xy 376.245766 -292.134014) (xy 376.212018 -292.09592)
			(xy 376.184817 -292.052906) (xy 376.164869 -292.006086) (xy 376.15269 -291.956672) (xy 376.148595 -291.905944)
			(xy 375.830084 -291.905944) (xy 375.829662 -291.92854) (xy 375.822966 -291.973232) (xy 375.809742 -292.016446)
			(xy 375.800366 -292.037008) (xy 375.797826 -292.042342) (xy 375.79554 -292.05301) (xy 375.79554 -292.31717)
			(xy 375.797572 -292.32733) (xy 375.79967 -292.336181) (xy 375.809176 -292.351673) (xy 375.816114 -292.357556)
			(xy 375.881138 -292.40861) (xy 375.904252 -292.413436) (xy 375.915682 -292.410388) (xy 375.93515 -292.405646)
			(xy 375.974895 -292.400555) (xy 375.99493 -292.400228) (xy 376.019734 -292.400717) (xy 376.068731 -292.408481)
			(xy 376.11591 -292.423815) (xy 376.16011 -292.446339) (xy 376.200242 -292.475501) (xy 376.235319 -292.510581)
			(xy 376.264476 -292.550716) (xy 376.286997 -292.594918) (xy 376.302326 -292.642098) (xy 376.310086 -292.691096)
			(xy 376.310086 -292.71595) (xy 376.628926 -292.71595) (xy 376.632886 -292.666896) (xy 376.644663 -292.619112)
			(xy 376.663954 -292.573836) (xy 376.690257 -292.53224) (xy 376.722892 -292.495403) (xy 376.761013 -292.464278)
			(xy 376.803634 -292.439671) (xy 376.84965 -292.422219) (xy 376.897869 -292.412375) (xy 376.947044 -292.410394)
			(xy 376.995899 -292.416326) (xy 377.04317 -292.430018) (xy 377.087632 -292.451116) (xy 377.128135 -292.479072)
			(xy 377.163628 -292.513164) (xy 377.193193 -292.552508) (xy 377.216064 -292.596085) (xy 377.231648 -292.642766)
			(xy 377.239543 -292.691343) (xy 377.240038 -292.71595) (xy 377.558549 -292.71595) (xy 377.562644 -292.665222)
			(xy 377.574823 -292.615808) (xy 377.594771 -292.568988) (xy 377.621972 -292.525974) (xy 377.65572 -292.48788)
			(xy 377.695142 -292.455693) (xy 377.739216 -292.430247) (xy 377.786802 -292.4122) (xy 377.836666 -292.40202)
			(xy 377.887518 -292.399971) (xy 377.938039 -292.406105) (xy 377.986923 -292.420265) (xy 378.032902 -292.442082)
			(xy 378.074786 -292.470992) (xy 378.11149 -292.506247) (xy 378.142063 -292.546933) (xy 378.165714 -292.591996)
			(xy 378.18183 -292.64027) (xy 378.189994 -292.690504) (xy 378.190506 -292.71595) (xy 379.438657 -292.71595)
			(xy 379.442752 -292.665222) (xy 379.454931 -292.615808) (xy 379.474879 -292.568988) (xy 379.50208 -292.525974)
			(xy 379.535828 -292.48788) (xy 379.57525 -292.455693) (xy 379.619324 -292.430247) (xy 379.66691 -292.4122)
			(xy 379.716774 -292.40202) (xy 379.767626 -292.399971) (xy 379.818147 -292.406105) (xy 379.867031 -292.420265)
			(xy 379.91301 -292.442082) (xy 379.954894 -292.470992) (xy 379.991598 -292.506247) (xy 380.022171 -292.546933)
			(xy 380.045822 -292.591996) (xy 380.061938 -292.64027) (xy 380.070102 -292.690504) (xy 380.070614 -292.71595)
			(xy 380.378711 -292.71595) (xy 380.382806 -292.665222) (xy 380.394985 -292.615808) (xy 380.414933 -292.568988)
			(xy 380.442134 -292.525974) (xy 380.475882 -292.48788) (xy 380.515304 -292.455693) (xy 380.559378 -292.430247)
			(xy 380.606964 -292.4122) (xy 380.656828 -292.40202) (xy 380.70768 -292.399971) (xy 380.758201 -292.406105)
			(xy 380.807085 -292.420265) (xy 380.853064 -292.442082) (xy 380.894948 -292.470992) (xy 380.931652 -292.506247)
			(xy 380.962225 -292.546933) (xy 380.985876 -292.591996) (xy 381.001992 -292.64027) (xy 381.010156 -292.690504)
			(xy 381.010668 -292.71595) (xy 381.010156 -292.741396) (xy 381.001992 -292.79163) (xy 380.985876 -292.839904)
			(xy 380.962225 -292.884967) (xy 380.931652 -292.925653) (xy 380.894948 -292.960908) (xy 380.853064 -292.989818)
			(xy 380.807085 -293.011635) (xy 380.758201 -293.025795) (xy 380.70768 -293.031929) (xy 380.656828 -293.02988)
			(xy 380.606964 -293.0197) (xy 380.559378 -293.001653) (xy 380.515304 -292.976207) (xy 380.475882 -292.94402)
			(xy 380.442134 -292.905926) (xy 380.414933 -292.862912) (xy 380.394985 -292.816092) (xy 380.382806 -292.766678)
			(xy 380.378711 -292.71595) (xy 380.070614 -292.71595) (xy 380.070102 -292.741396) (xy 380.061938 -292.79163)
			(xy 380.045822 -292.839904) (xy 380.022171 -292.884967) (xy 379.991598 -292.925653) (xy 379.954894 -292.960908)
			(xy 379.91301 -292.989818) (xy 379.867031 -293.011635) (xy 379.818147 -293.025795) (xy 379.767626 -293.031929)
			(xy 379.716774 -293.02988) (xy 379.66691 -293.0197) (xy 379.619324 -293.001653) (xy 379.57525 -292.976207)
			(xy 379.535828 -292.94402) (xy 379.50208 -292.905926) (xy 379.474879 -292.862912) (xy 379.454931 -292.816092)
			(xy 379.442752 -292.766678) (xy 379.438657 -292.71595) (xy 378.190506 -292.71595) (xy 378.189994 -292.741396)
			(xy 378.18183 -292.79163) (xy 378.165714 -292.839904) (xy 378.142063 -292.884967) (xy 378.11149 -292.925653)
			(xy 378.074786 -292.960908) (xy 378.032902 -292.989818) (xy 377.986923 -293.011635) (xy 377.938039 -293.025795)
			(xy 377.887518 -293.031929) (xy 377.836666 -293.02988) (xy 377.786802 -293.0197) (xy 377.739216 -293.001653)
			(xy 377.695142 -292.976207) (xy 377.65572 -292.94402) (xy 377.621972 -292.905926) (xy 377.594771 -292.862912)
			(xy 377.574823 -292.816092) (xy 377.562644 -292.766678) (xy 377.558549 -292.71595) (xy 377.240038 -292.71595)
			(xy 377.239543 -292.740557) (xy 377.231648 -292.789134) (xy 377.216064 -292.835815) (xy 377.193193 -292.879392)
			(xy 377.163628 -292.918736) (xy 377.128135 -292.952828) (xy 377.087632 -292.980784) (xy 377.04317 -293.001882)
			(xy 376.995899 -293.015574) (xy 376.947044 -293.021506) (xy 376.897869 -293.019525) (xy 376.84965 -293.009681)
			(xy 376.803634 -292.992229) (xy 376.761013 -292.967622) (xy 376.722892 -292.936497) (xy 376.690257 -292.89966)
			(xy 376.663954 -292.858064) (xy 376.644663 -292.812788) (xy 376.632886 -292.765004) (xy 376.628926 -292.71595)
			(xy 376.310086 -292.71595) (xy 376.310086 -292.740704) (xy 376.302326 -292.789702) (xy 376.286997 -292.836882)
			(xy 376.264476 -292.881084) (xy 376.235319 -292.921219) (xy 376.200242 -292.956299) (xy 376.16011 -292.985461)
			(xy 376.11591 -293.007985) (xy 376.068731 -293.023319) (xy 376.019734 -293.031083) (xy 375.99493 -293.031672)
			(xy 375.970254 -293.031134) (xy 375.921518 -293.02335) (xy 375.897902 -293.016178) (xy 375.88698 -293.018718)
			(xy 375.815098 -293.074852) (xy 375.809755 -293.07939) (xy 375.801515 -293.090723) (xy 375.798842 -293.097204)
			(xy 375.79554 -293.10584) (xy 375.79554 -293.37889) (xy 375.797826 -293.389558) (xy 375.800366 -293.394892)
			(xy 375.809714 -293.415465) (xy 375.822928 -293.458677) (xy 375.829641 -293.503363) (xy 375.830084 -293.525956)
			(xy 376.148595 -293.525956) (xy 376.15269 -293.475228) (xy 376.164869 -293.425814) (xy 376.184817 -293.378994)
			(xy 376.212018 -293.33598) (xy 376.245766 -293.297886) (xy 376.285188 -293.265699) (xy 376.329262 -293.240253)
			(xy 376.376848 -293.222206) (xy 376.426712 -293.212026) (xy 376.477564 -293.209977) (xy 376.528085 -293.216111)
			(xy 376.576969 -293.230271) (xy 376.622948 -293.252088) (xy 376.664832 -293.280998) (xy 376.701536 -293.316253)
			(xy 376.732109 -293.356939) (xy 376.75576 -293.402002) (xy 376.771876 -293.450276) (xy 376.78004 -293.50051)
			(xy 376.780552 -293.525956) (xy 377.09908 -293.525956) (xy 377.10304 -293.476902) (xy 377.114817 -293.429118)
			(xy 377.134108 -293.383842) (xy 377.160411 -293.342246) (xy 377.193046 -293.305409) (xy 377.231167 -293.274284)
			(xy 377.273788 -293.249677) (xy 377.319804 -293.232225) (xy 377.368023 -293.222381) (xy 377.417198 -293.2204)
			(xy 377.466053 -293.226332) (xy 377.513324 -293.240024) (xy 377.557786 -293.261122) (xy 377.598289 -293.289078)
			(xy 377.633782 -293.32317) (xy 377.663347 -293.362514) (xy 377.686218 -293.406091) (xy 377.701802 -293.452772)
			(xy 377.709697 -293.501349) (xy 377.710192 -293.525956) (xy 378.039134 -293.525956) (xy 378.043094 -293.476902)
			(xy 378.054871 -293.429118) (xy 378.074162 -293.383842) (xy 378.100465 -293.342246) (xy 378.1331 -293.305409)
			(xy 378.171221 -293.274284) (xy 378.213842 -293.249677) (xy 378.259858 -293.232225) (xy 378.308077 -293.222381)
			(xy 378.357252 -293.2204) (xy 378.406107 -293.226332) (xy 378.453378 -293.240024) (xy 378.49784 -293.261122)
			(xy 378.538343 -293.289078) (xy 378.573836 -293.32317) (xy 378.603401 -293.362514) (xy 378.626272 -293.406091)
			(xy 378.641856 -293.452772) (xy 378.649751 -293.501349) (xy 378.650246 -293.525956) (xy 378.978934 -293.525956)
			(xy 378.982894 -293.476902) (xy 378.994671 -293.429118) (xy 379.013962 -293.383842) (xy 379.040265 -293.342246)
			(xy 379.0729 -293.305409) (xy 379.111021 -293.274284) (xy 379.153642 -293.249677) (xy 379.199658 -293.232225)
			(xy 379.247877 -293.222381) (xy 379.297052 -293.2204) (xy 379.345907 -293.226332) (xy 379.393178 -293.240024)
			(xy 379.43764 -293.261122) (xy 379.478143 -293.289078) (xy 379.513636 -293.32317) (xy 379.543201 -293.362514)
			(xy 379.566072 -293.406091) (xy 379.581656 -293.452772) (xy 379.589551 -293.501349) (xy 379.590046 -293.525956)
			(xy 379.918988 -293.525956) (xy 379.922948 -293.476902) (xy 379.934725 -293.429118) (xy 379.954016 -293.383842)
			(xy 379.980319 -293.342246) (xy 380.012954 -293.305409) (xy 380.051075 -293.274284) (xy 380.093696 -293.249677)
			(xy 380.139712 -293.232225) (xy 380.187931 -293.222381) (xy 380.237106 -293.2204) (xy 380.285961 -293.226332)
			(xy 380.333232 -293.240024) (xy 380.377694 -293.261122) (xy 380.418197 -293.289078) (xy 380.45369 -293.32317)
			(xy 380.483255 -293.362514) (xy 380.506126 -293.406091) (xy 380.52171 -293.452772) (xy 380.529605 -293.501349)
			(xy 380.5301 -293.525956) (xy 380.848611 -293.525956) (xy 380.852706 -293.475228) (xy 380.864885 -293.425814)
			(xy 380.884833 -293.378994) (xy 380.912034 -293.33598) (xy 380.945782 -293.297886) (xy 380.985204 -293.265699)
			(xy 381.029278 -293.240253) (xy 381.076864 -293.222206) (xy 381.126728 -293.212026) (xy 381.17758 -293.209977)
			(xy 381.228101 -293.216111) (xy 381.276985 -293.230271) (xy 381.322964 -293.252088) (xy 381.364848 -293.280998)
			(xy 381.401552 -293.316253) (xy 381.432125 -293.356939) (xy 381.455776 -293.402002) (xy 381.471892 -293.450276)
			(xy 381.480056 -293.50051) (xy 381.480568 -293.525956) (xy 381.480056 -293.551402) (xy 381.471892 -293.601636)
			(xy 381.455776 -293.64991) (xy 381.432125 -293.694973) (xy 381.401552 -293.735659) (xy 381.364848 -293.770914)
			(xy 381.322964 -293.799824) (xy 381.276985 -293.821641) (xy 381.228101 -293.835801) (xy 381.17758 -293.841935)
			(xy 381.126728 -293.839886) (xy 381.076864 -293.829706) (xy 381.029278 -293.811659) (xy 380.985204 -293.786213)
			(xy 380.945782 -293.754026) (xy 380.912034 -293.715932) (xy 380.884833 -293.672918) (xy 380.864885 -293.626098)
			(xy 380.852706 -293.576684) (xy 380.848611 -293.525956) (xy 380.5301 -293.525956) (xy 380.529605 -293.550563)
			(xy 380.52171 -293.59914) (xy 380.506126 -293.645821) (xy 380.483255 -293.689398) (xy 380.45369 -293.728742)
			(xy 380.418197 -293.762834) (xy 380.377694 -293.79079) (xy 380.333232 -293.811888) (xy 380.285961 -293.82558)
			(xy 380.237106 -293.831512) (xy 380.187931 -293.829531) (xy 380.139712 -293.819687) (xy 380.093696 -293.802235)
			(xy 380.051075 -293.777628) (xy 380.012954 -293.746503) (xy 379.980319 -293.709666) (xy 379.954016 -293.66807)
			(xy 379.934725 -293.622794) (xy 379.922948 -293.57501) (xy 379.918988 -293.525956) (xy 379.590046 -293.525956)
			(xy 379.589551 -293.550563) (xy 379.581656 -293.59914) (xy 379.566072 -293.645821) (xy 379.543201 -293.689398)
			(xy 379.513636 -293.728742) (xy 379.478143 -293.762834) (xy 379.43764 -293.79079) (xy 379.393178 -293.811888)
			(xy 379.345907 -293.82558) (xy 379.297052 -293.831512) (xy 379.247877 -293.829531) (xy 379.199658 -293.819687)
			(xy 379.153642 -293.802235) (xy 379.111021 -293.777628) (xy 379.0729 -293.746503) (xy 379.040265 -293.709666)
			(xy 379.013962 -293.66807) (xy 378.994671 -293.622794) (xy 378.982894 -293.57501) (xy 378.978934 -293.525956)
			(xy 378.650246 -293.525956) (xy 378.649751 -293.550563) (xy 378.641856 -293.59914) (xy 378.626272 -293.645821)
			(xy 378.603401 -293.689398) (xy 378.573836 -293.728742) (xy 378.538343 -293.762834) (xy 378.49784 -293.79079)
			(xy 378.453378 -293.811888) (xy 378.406107 -293.82558) (xy 378.357252 -293.831512) (xy 378.308077 -293.829531)
			(xy 378.259858 -293.819687) (xy 378.213842 -293.802235) (xy 378.171221 -293.777628) (xy 378.1331 -293.746503)
			(xy 378.100465 -293.709666) (xy 378.074162 -293.66807) (xy 378.054871 -293.622794) (xy 378.043094 -293.57501)
			(xy 378.039134 -293.525956) (xy 377.710192 -293.525956) (xy 377.709697 -293.550563) (xy 377.701802 -293.59914)
			(xy 377.686218 -293.645821) (xy 377.663347 -293.689398) (xy 377.633782 -293.728742) (xy 377.598289 -293.762834)
			(xy 377.557786 -293.79079) (xy 377.513324 -293.811888) (xy 377.466053 -293.82558) (xy 377.417198 -293.831512)
			(xy 377.368023 -293.829531) (xy 377.319804 -293.819687) (xy 377.273788 -293.802235) (xy 377.231167 -293.777628)
			(xy 377.193046 -293.746503) (xy 377.160411 -293.709666) (xy 377.134108 -293.66807) (xy 377.114817 -293.622794)
			(xy 377.10304 -293.57501) (xy 377.09908 -293.525956) (xy 376.780552 -293.525956) (xy 376.78004 -293.551402)
			(xy 376.771876 -293.601636) (xy 376.75576 -293.64991) (xy 376.732109 -293.694973) (xy 376.701536 -293.735659)
			(xy 376.664832 -293.770914) (xy 376.622948 -293.799824) (xy 376.576969 -293.821641) (xy 376.528085 -293.835801)
			(xy 376.477564 -293.841935) (xy 376.426712 -293.839886) (xy 376.376848 -293.829706) (xy 376.329262 -293.811659)
			(xy 376.285188 -293.786213) (xy 376.245766 -293.754026) (xy 376.212018 -293.715932) (xy 376.184817 -293.672918)
			(xy 376.164869 -293.626098) (xy 376.15269 -293.576684) (xy 376.148595 -293.525956) (xy 375.830084 -293.525956)
			(xy 375.829662 -293.548551) (xy 375.822964 -293.593243) (xy 375.809738 -293.636456) (xy 375.800366 -293.65702)
			(xy 375.797826 -293.662354) (xy 375.79554 -293.673022) (xy 375.79554 -293.940992) (xy 375.797572 -293.951406)
			(xy 375.799651 -293.960317) (xy 375.809163 -293.975934) (xy 375.816114 -293.981886) (xy 375.875804 -294.028876)
			(xy 375.882154 -294.03294) (xy 375.88792 -294.035991) (xy 375.900526 -294.039329) (xy 375.907046 -294.039544)
			(xy 375.92127 -294.039544) (xy 375.927112 -294.038274) (xy 375.927366 -294.038274) (xy 375.943719 -294.034782)
			(xy 375.976941 -294.030967) (xy 375.99366 -294.030654) (xy 375.998232 -294.030654) (xy 376.02205 -294.031372)
			(xy 376.069037 -294.039289) (xy 376.114223 -294.05441) (xy 376.156511 -294.076368) (xy 376.194873 -294.104631)
			(xy 376.228378 -294.138511) (xy 376.256212 -294.177185) (xy 376.277699 -294.219714) (xy 376.292317 -294.265065)
			(xy 376.299711 -294.312137) (xy 376.300238 -294.335962) (xy 376.628926 -294.335962) (xy 376.632886 -294.286908)
			(xy 376.644663 -294.239124) (xy 376.663954 -294.193848) (xy 376.690257 -294.152252) (xy 376.722892 -294.115415)
			(xy 376.761013 -294.08429) (xy 376.803634 -294.059683) (xy 376.84965 -294.042231) (xy 376.897869 -294.032387)
			(xy 376.947044 -294.030406) (xy 376.995899 -294.036338) (xy 377.04317 -294.05003) (xy 377.087632 -294.071128)
			(xy 377.128135 -294.099084) (xy 377.163628 -294.133176) (xy 377.193193 -294.17252) (xy 377.216064 -294.216097)
			(xy 377.231648 -294.262778) (xy 377.239543 -294.311355) (xy 377.240038 -294.335962) (xy 377.56898 -294.335962)
			(xy 377.57294 -294.286908) (xy 377.584717 -294.239124) (xy 377.604008 -294.193848) (xy 377.630311 -294.152252)
			(xy 377.662946 -294.115415) (xy 377.701067 -294.08429) (xy 377.743688 -294.059683) (xy 377.789704 -294.042231)
			(xy 377.837923 -294.032387) (xy 377.887098 -294.030406) (xy 377.935953 -294.036338) (xy 377.983224 -294.05003)
			(xy 378.027686 -294.071128) (xy 378.068189 -294.099084) (xy 378.103682 -294.133176) (xy 378.133247 -294.17252)
			(xy 378.156118 -294.216097) (xy 378.171702 -294.262778) (xy 378.179597 -294.311355) (xy 378.180092 -294.335962)
			(xy 378.509034 -294.335962) (xy 378.512994 -294.286908) (xy 378.524771 -294.239124) (xy 378.544062 -294.193848)
			(xy 378.570365 -294.152252) (xy 378.603 -294.115415) (xy 378.641121 -294.08429) (xy 378.683742 -294.059683)
			(xy 378.729758 -294.042231) (xy 378.777977 -294.032387) (xy 378.827152 -294.030406) (xy 378.876007 -294.036338)
			(xy 378.923278 -294.05003) (xy 378.96774 -294.071128) (xy 379.008243 -294.099084) (xy 379.043736 -294.133176)
			(xy 379.073301 -294.17252) (xy 379.096172 -294.216097) (xy 379.111756 -294.262778) (xy 379.119651 -294.311355)
			(xy 379.120146 -294.335962) (xy 380.389142 -294.335962) (xy 380.393102 -294.286908) (xy 380.404879 -294.239124)
			(xy 380.42417 -294.193848) (xy 380.450473 -294.152252) (xy 380.483108 -294.115415) (xy 380.521229 -294.08429)
			(xy 380.56385 -294.059683) (xy 380.609866 -294.042231) (xy 380.658085 -294.032387) (xy 380.70726 -294.030406)
			(xy 380.756115 -294.036338) (xy 380.803386 -294.05003) (xy 380.847848 -294.071128) (xy 380.888351 -294.099084)
			(xy 380.923844 -294.133176) (xy 380.953409 -294.17252) (xy 380.97628 -294.216097) (xy 380.991864 -294.262778)
			(xy 380.999759 -294.311355) (xy 381.000254 -294.335962) (xy 381.328942 -294.335962) (xy 381.332902 -294.286908)
			(xy 381.344679 -294.239124) (xy 381.36397 -294.193848) (xy 381.390273 -294.152252) (xy 381.422908 -294.115415)
			(xy 381.461029 -294.08429) (xy 381.50365 -294.059683) (xy 381.549666 -294.042231) (xy 381.597885 -294.032387)
			(xy 381.64706 -294.030406) (xy 381.695915 -294.036338) (xy 381.743186 -294.05003) (xy 381.787648 -294.071128)
			(xy 381.828151 -294.099084) (xy 381.863644 -294.133176) (xy 381.893209 -294.17252) (xy 381.91608 -294.216097)
			(xy 381.931664 -294.262778) (xy 381.939559 -294.311355) (xy 381.940054 -294.335962) (xy 381.939559 -294.360569)
			(xy 381.931664 -294.409146) (xy 381.91608 -294.455827) (xy 381.893209 -294.499404) (xy 381.863644 -294.538748)
			(xy 381.828151 -294.57284) (xy 381.787648 -294.600796) (xy 381.743186 -294.621894) (xy 381.695915 -294.635586)
			(xy 381.64706 -294.641518) (xy 381.597885 -294.639537) (xy 381.549666 -294.629693) (xy 381.50365 -294.612241)
			(xy 381.461029 -294.587634) (xy 381.422908 -294.556509) (xy 381.390273 -294.519672) (xy 381.36397 -294.478076)
			(xy 381.344679 -294.4328) (xy 381.332902 -294.385016) (xy 381.328942 -294.335962) (xy 381.000254 -294.335962)
			(xy 380.999759 -294.360569) (xy 380.991864 -294.409146) (xy 380.97628 -294.455827) (xy 380.953409 -294.499404)
			(xy 380.923844 -294.538748) (xy 380.888351 -294.57284) (xy 380.847848 -294.600796) (xy 380.803386 -294.621894)
			(xy 380.756115 -294.635586) (xy 380.70726 -294.641518) (xy 380.658085 -294.639537) (xy 380.609866 -294.629693)
			(xy 380.56385 -294.612241) (xy 380.521229 -294.587634) (xy 380.483108 -294.556509) (xy 380.450473 -294.519672)
			(xy 380.42417 -294.478076) (xy 380.404879 -294.4328) (xy 380.393102 -294.385016) (xy 380.389142 -294.335962)
			(xy 379.120146 -294.335962) (xy 379.119651 -294.360569) (xy 379.111756 -294.409146) (xy 379.096172 -294.455827)
			(xy 379.073301 -294.499404) (xy 379.043736 -294.538748) (xy 379.008243 -294.57284) (xy 378.96774 -294.600796)
			(xy 378.923278 -294.621894) (xy 378.876007 -294.635586) (xy 378.827152 -294.641518) (xy 378.777977 -294.639537)
			(xy 378.729758 -294.629693) (xy 378.683742 -294.612241) (xy 378.641121 -294.587634) (xy 378.603 -294.556509)
			(xy 378.570365 -294.519672) (xy 378.544062 -294.478076) (xy 378.524771 -294.4328) (xy 378.512994 -294.385016)
			(xy 378.509034 -294.335962) (xy 378.180092 -294.335962) (xy 378.179597 -294.360569) (xy 378.171702 -294.409146)
			(xy 378.156118 -294.455827) (xy 378.133247 -294.499404) (xy 378.103682 -294.538748) (xy 378.068189 -294.57284)
			(xy 378.027686 -294.600796) (xy 377.983224 -294.621894) (xy 377.935953 -294.635586) (xy 377.887098 -294.641518)
			(xy 377.837923 -294.639537) (xy 377.789704 -294.629693) (xy 377.743688 -294.612241) (xy 377.701067 -294.587634)
			(xy 377.662946 -294.556509) (xy 377.630311 -294.519672) (xy 377.604008 -294.478076) (xy 377.584717 -294.4328)
			(xy 377.57294 -294.385016) (xy 377.56898 -294.335962) (xy 377.240038 -294.335962) (xy 377.239543 -294.360569)
			(xy 377.231648 -294.409146) (xy 377.216064 -294.455827) (xy 377.193193 -294.499404) (xy 377.163628 -294.538748)
			(xy 377.128135 -294.57284) (xy 377.087632 -294.600796) (xy 377.04317 -294.621894) (xy 376.995899 -294.635586)
			(xy 376.947044 -294.641518) (xy 376.897869 -294.639537) (xy 376.84965 -294.629693) (xy 376.803634 -294.612241)
			(xy 376.761013 -294.587634) (xy 376.722892 -294.556509) (xy 376.690257 -294.519672) (xy 376.663954 -294.478076)
			(xy 376.644663 -294.4328) (xy 376.632886 -294.385016) (xy 376.628926 -294.335962) (xy 376.300238 -294.335962)
			(xy 376.299795 -294.359958) (xy 376.292293 -294.40736) (xy 376.277468 -294.453004) (xy 376.255685 -294.495768)
			(xy 376.227481 -294.534597) (xy 376.193549 -294.568537) (xy 376.154726 -294.59675) (xy 376.111967 -294.618542)
			(xy 376.066326 -294.633377) (xy 376.018926 -294.640889) (xy 375.99493 -294.64127) (xy 375.973789 -294.64091)
			(xy 375.93191 -294.635086) (xy 375.89123 -294.623558) (xy 375.87174 -294.615362) (xy 375.867422 -294.61333)
			(xy 375.857516 -294.611044) (xy 375.846212 -294.609137) (xy 375.823902 -294.614267) (xy 375.81459 -294.62095)
			(xy 375.805446 -294.628316) (xy 375.79554 -294.64889) (xy 375.79554 -294.667178) (xy 375.796009 -294.677052)
			(xy 375.803461 -294.69534) (xy 375.810018 -294.702738) (xy 375.810272 -294.702992) (xy 375.981468 -294.874188)
			(xy 375.987198 -294.880469) (xy 375.994592 -294.895767) (xy 375.995946 -294.90416) (xy 376.024566 -295.145968)
			(xy 377.09908 -295.145968) (xy 377.10304 -295.096914) (xy 377.114817 -295.04913) (xy 377.134108 -295.003854)
			(xy 377.160411 -294.962258) (xy 377.193046 -294.925421) (xy 377.231167 -294.894296) (xy 377.273788 -294.869689)
			(xy 377.319804 -294.852237) (xy 377.368023 -294.842393) (xy 377.417198 -294.840412) (xy 377.466053 -294.846344)
			(xy 377.513324 -294.860036) (xy 377.557786 -294.881134) (xy 377.598289 -294.90909) (xy 377.633782 -294.943182)
			(xy 377.663347 -294.982526) (xy 377.686218 -295.026103) (xy 377.701802 -295.072784) (xy 377.709697 -295.121361)
			(xy 377.710192 -295.145968) (xy 378.039134 -295.145968) (xy 378.043094 -295.096914) (xy 378.054871 -295.04913)
			(xy 378.074162 -295.003854) (xy 378.100465 -294.962258) (xy 378.1331 -294.925421) (xy 378.171221 -294.894296)
			(xy 378.213842 -294.869689) (xy 378.259858 -294.852237) (xy 378.308077 -294.842393) (xy 378.357252 -294.840412)
			(xy 378.406107 -294.846344) (xy 378.453378 -294.860036) (xy 378.49784 -294.881134) (xy 378.538343 -294.90909)
			(xy 378.573836 -294.943182) (xy 378.603401 -294.982526) (xy 378.626272 -295.026103) (xy 378.641856 -295.072784)
			(xy 378.649751 -295.121361) (xy 378.650246 -295.145968) (xy 378.978934 -295.145968) (xy 378.982894 -295.096914)
			(xy 378.994671 -295.04913) (xy 379.013962 -295.003854) (xy 379.040265 -294.962258) (xy 379.0729 -294.925421)
			(xy 379.111021 -294.894296) (xy 379.153642 -294.869689) (xy 379.199658 -294.852237) (xy 379.247877 -294.842393)
			(xy 379.297052 -294.840412) (xy 379.345907 -294.846344) (xy 379.393178 -294.860036) (xy 379.43764 -294.881134)
			(xy 379.478143 -294.90909) (xy 379.513636 -294.943182) (xy 379.543201 -294.982526) (xy 379.566072 -295.026103)
			(xy 379.581656 -295.072784) (xy 379.589551 -295.121361) (xy 379.590046 -295.145968) (xy 380.859042 -295.145968)
			(xy 380.863002 -295.096914) (xy 380.874779 -295.04913) (xy 380.89407 -295.003854) (xy 380.920373 -294.962258)
			(xy 380.953008 -294.925421) (xy 380.991129 -294.894296) (xy 381.03375 -294.869689) (xy 381.079766 -294.852237)
			(xy 381.127985 -294.842393) (xy 381.17716 -294.840412) (xy 381.226015 -294.846344) (xy 381.273286 -294.860036)
			(xy 381.317748 -294.881134) (xy 381.358251 -294.90909) (xy 381.393744 -294.943182) (xy 381.423309 -294.982526)
			(xy 381.44618 -295.026103) (xy 381.461764 -295.072784) (xy 381.469659 -295.121361) (xy 381.470154 -295.145968)
			(xy 381.799096 -295.145968) (xy 381.803056 -295.096914) (xy 381.814833 -295.04913) (xy 381.834124 -295.003854)
			(xy 381.860427 -294.962258) (xy 381.893062 -294.925421) (xy 381.931183 -294.894296) (xy 381.973804 -294.869689)
			(xy 382.01982 -294.852237) (xy 382.068039 -294.842393) (xy 382.117214 -294.840412) (xy 382.166069 -294.846344)
			(xy 382.21334 -294.860036) (xy 382.257802 -294.881134) (xy 382.298305 -294.90909) (xy 382.333798 -294.943182)
			(xy 382.363363 -294.982526) (xy 382.386234 -295.026103) (xy 382.401818 -295.072784) (xy 382.409713 -295.121361)
			(xy 382.410208 -295.145968) (xy 384.619004 -295.145968) (xy 384.622964 -295.096914) (xy 384.634741 -295.04913)
			(xy 384.654032 -295.003854) (xy 384.680335 -294.962258) (xy 384.71297 -294.925421) (xy 384.751091 -294.894296)
			(xy 384.793712 -294.869689) (xy 384.839728 -294.852237) (xy 384.887947 -294.842393) (xy 384.937122 -294.840412)
			(xy 384.985977 -294.846344) (xy 385.033248 -294.860036) (xy 385.07771 -294.881134) (xy 385.118213 -294.90909)
			(xy 385.153706 -294.943182) (xy 385.183271 -294.982526) (xy 385.206142 -295.026103) (xy 385.221726 -295.072784)
			(xy 385.229621 -295.121361) (xy 385.230116 -295.145968) (xy 385.559058 -295.145968) (xy 385.563018 -295.096914)
			(xy 385.574795 -295.04913) (xy 385.594086 -295.003854) (xy 385.620389 -294.962258) (xy 385.653024 -294.925421)
			(xy 385.691145 -294.894296) (xy 385.733766 -294.869689) (xy 385.779782 -294.852237) (xy 385.828001 -294.842393)
			(xy 385.877176 -294.840412) (xy 385.926031 -294.846344) (xy 385.973302 -294.860036) (xy 386.017764 -294.881134)
			(xy 386.058267 -294.90909) (xy 386.09376 -294.943182) (xy 386.123325 -294.982526) (xy 386.146196 -295.026103)
			(xy 386.16178 -295.072784) (xy 386.169675 -295.121361) (xy 386.17017 -295.145968) (xy 388.378966 -295.145968)
			(xy 388.382926 -295.096914) (xy 388.394703 -295.04913) (xy 388.413994 -295.003854) (xy 388.440297 -294.962258)
			(xy 388.472932 -294.925421) (xy 388.511053 -294.894296) (xy 388.553674 -294.869689) (xy 388.59969 -294.852237)
			(xy 388.647909 -294.842393) (xy 388.697084 -294.840412) (xy 388.745939 -294.846344) (xy 388.79321 -294.860036)
			(xy 388.837672 -294.881134) (xy 388.878175 -294.90909) (xy 388.913668 -294.943182) (xy 388.943233 -294.982526)
			(xy 388.966104 -295.026103) (xy 388.981688 -295.072784) (xy 388.989583 -295.121361) (xy 388.990078 -295.145968)
			(xy 389.31902 -295.145968) (xy 389.32298 -295.096914) (xy 389.334757 -295.04913) (xy 389.354048 -295.003854)
			(xy 389.380351 -294.962258) (xy 389.412986 -294.925421) (xy 389.451107 -294.894296) (xy 389.493728 -294.869689)
			(xy 389.539744 -294.852237) (xy 389.587963 -294.842393) (xy 389.637138 -294.840412) (xy 389.685993 -294.846344)
			(xy 389.733264 -294.860036) (xy 389.777726 -294.881134) (xy 389.818229 -294.90909) (xy 389.853722 -294.943182)
			(xy 389.883287 -294.982526) (xy 389.906158 -295.026103) (xy 389.921742 -295.072784) (xy 389.929637 -295.121361)
			(xy 389.930132 -295.145968) (xy 390.259074 -295.145968) (xy 390.263034 -295.096914) (xy 390.274811 -295.04913)
			(xy 390.294102 -295.003854) (xy 390.320405 -294.962258) (xy 390.35304 -294.925421) (xy 390.391161 -294.894296)
			(xy 390.433782 -294.869689) (xy 390.479798 -294.852237) (xy 390.528017 -294.842393) (xy 390.577192 -294.840412)
			(xy 390.626047 -294.846344) (xy 390.673318 -294.860036) (xy 390.71778 -294.881134) (xy 390.758283 -294.90909)
			(xy 390.793776 -294.943182) (xy 390.823341 -294.982526) (xy 390.846212 -295.026103) (xy 390.861796 -295.072784)
			(xy 390.869691 -295.121361) (xy 390.870186 -295.145968) (xy 390.869691 -295.170575) (xy 390.861796 -295.219152)
			(xy 390.846212 -295.265833) (xy 390.823341 -295.30941) (xy 390.793776 -295.348754) (xy 390.758283 -295.382846)
			(xy 390.71778 -295.410802) (xy 390.673318 -295.4319) (xy 390.626047 -295.445592) (xy 390.577192 -295.451524)
			(xy 390.528017 -295.449543) (xy 390.479798 -295.439699) (xy 390.433782 -295.422247) (xy 390.391161 -295.39764)
			(xy 390.35304 -295.366515) (xy 390.320405 -295.329678) (xy 390.294102 -295.288082) (xy 390.274811 -295.242806)
			(xy 390.263034 -295.195022) (xy 390.259074 -295.145968) (xy 389.930132 -295.145968) (xy 389.929637 -295.170575)
			(xy 389.921742 -295.219152) (xy 389.906158 -295.265833) (xy 389.883287 -295.30941) (xy 389.853722 -295.348754)
			(xy 389.818229 -295.382846) (xy 389.777726 -295.410802) (xy 389.733264 -295.4319) (xy 389.685993 -295.445592)
			(xy 389.637138 -295.451524) (xy 389.587963 -295.449543) (xy 389.539744 -295.439699) (xy 389.493728 -295.422247)
			(xy 389.451107 -295.39764) (xy 389.412986 -295.366515) (xy 389.380351 -295.329678) (xy 389.354048 -295.288082)
			(xy 389.334757 -295.242806) (xy 389.32298 -295.195022) (xy 389.31902 -295.145968) (xy 388.990078 -295.145968)
			(xy 388.989583 -295.170575) (xy 388.981688 -295.219152) (xy 388.966104 -295.265833) (xy 388.943233 -295.30941)
			(xy 388.913668 -295.348754) (xy 388.878175 -295.382846) (xy 388.837672 -295.410802) (xy 388.79321 -295.4319)
			(xy 388.745939 -295.445592) (xy 388.697084 -295.451524) (xy 388.647909 -295.449543) (xy 388.59969 -295.439699)
			(xy 388.553674 -295.422247) (xy 388.511053 -295.39764) (xy 388.472932 -295.366515) (xy 388.440297 -295.329678)
			(xy 388.413994 -295.288082) (xy 388.394703 -295.242806) (xy 388.382926 -295.195022) (xy 388.378966 -295.145968)
			(xy 386.17017 -295.145968) (xy 386.169675 -295.170575) (xy 386.16178 -295.219152) (xy 386.146196 -295.265833)
			(xy 386.123325 -295.30941) (xy 386.09376 -295.348754) (xy 386.058267 -295.382846) (xy 386.017764 -295.410802)
			(xy 385.973302 -295.4319) (xy 385.926031 -295.445592) (xy 385.877176 -295.451524) (xy 385.828001 -295.449543)
			(xy 385.779782 -295.439699) (xy 385.733766 -295.422247) (xy 385.691145 -295.39764) (xy 385.653024 -295.366515)
			(xy 385.620389 -295.329678) (xy 385.594086 -295.288082) (xy 385.574795 -295.242806) (xy 385.563018 -295.195022)
			(xy 385.559058 -295.145968) (xy 385.230116 -295.145968) (xy 385.229621 -295.170575) (xy 385.221726 -295.219152)
			(xy 385.206142 -295.265833) (xy 385.183271 -295.30941) (xy 385.153706 -295.348754) (xy 385.118213 -295.382846)
			(xy 385.07771 -295.410802) (xy 385.033248 -295.4319) (xy 384.985977 -295.445592) (xy 384.937122 -295.451524)
			(xy 384.887947 -295.449543) (xy 384.839728 -295.439699) (xy 384.793712 -295.422247) (xy 384.751091 -295.39764)
			(xy 384.71297 -295.366515) (xy 384.680335 -295.329678) (xy 384.654032 -295.288082) (xy 384.634741 -295.242806)
			(xy 384.622964 -295.195022) (xy 384.619004 -295.145968) (xy 382.410208 -295.145968) (xy 382.409713 -295.170575)
			(xy 382.401818 -295.219152) (xy 382.386234 -295.265833) (xy 382.363363 -295.30941) (xy 382.333798 -295.348754)
			(xy 382.298305 -295.382846) (xy 382.257802 -295.410802) (xy 382.21334 -295.4319) (xy 382.166069 -295.445592)
			(xy 382.117214 -295.451524) (xy 382.068039 -295.449543) (xy 382.01982 -295.439699) (xy 381.973804 -295.422247)
			(xy 381.931183 -295.39764) (xy 381.893062 -295.366515) (xy 381.860427 -295.329678) (xy 381.834124 -295.288082)
			(xy 381.814833 -295.242806) (xy 381.803056 -295.195022) (xy 381.799096 -295.145968) (xy 381.470154 -295.145968)
			(xy 381.469659 -295.170575) (xy 381.461764 -295.219152) (xy 381.44618 -295.265833) (xy 381.423309 -295.30941)
			(xy 381.393744 -295.348754) (xy 381.358251 -295.382846) (xy 381.317748 -295.410802) (xy 381.273286 -295.4319)
			(xy 381.226015 -295.445592) (xy 381.17716 -295.451524) (xy 381.127985 -295.449543) (xy 381.079766 -295.439699)
			(xy 381.03375 -295.422247) (xy 380.991129 -295.39764) (xy 380.953008 -295.366515) (xy 380.920373 -295.329678)
			(xy 380.89407 -295.288082) (xy 380.874779 -295.242806) (xy 380.863002 -295.195022) (xy 380.859042 -295.145968)
			(xy 379.590046 -295.145968) (xy 379.589551 -295.170575) (xy 379.581656 -295.219152) (xy 379.566072 -295.265833)
			(xy 379.543201 -295.30941) (xy 379.513636 -295.348754) (xy 379.478143 -295.382846) (xy 379.43764 -295.410802)
			(xy 379.393178 -295.4319) (xy 379.345907 -295.445592) (xy 379.297052 -295.451524) (xy 379.247877 -295.449543)
			(xy 379.199658 -295.439699) (xy 379.153642 -295.422247) (xy 379.111021 -295.39764) (xy 379.0729 -295.366515)
			(xy 379.040265 -295.329678) (xy 379.013962 -295.288082) (xy 378.994671 -295.242806) (xy 378.982894 -295.195022)
			(xy 378.978934 -295.145968) (xy 378.650246 -295.145968) (xy 378.649751 -295.170575) (xy 378.641856 -295.219152)
			(xy 378.626272 -295.265833) (xy 378.603401 -295.30941) (xy 378.573836 -295.348754) (xy 378.538343 -295.382846)
			(xy 378.49784 -295.410802) (xy 378.453378 -295.4319) (xy 378.406107 -295.445592) (xy 378.357252 -295.451524)
			(xy 378.308077 -295.449543) (xy 378.259858 -295.439699) (xy 378.213842 -295.422247) (xy 378.171221 -295.39764)
			(xy 378.1331 -295.366515) (xy 378.100465 -295.329678) (xy 378.074162 -295.288082) (xy 378.054871 -295.242806)
			(xy 378.043094 -295.195022) (xy 378.039134 -295.145968) (xy 377.710192 -295.145968) (xy 377.709697 -295.170575)
			(xy 377.701802 -295.219152) (xy 377.686218 -295.265833) (xy 377.663347 -295.30941) (xy 377.633782 -295.348754)
			(xy 377.598289 -295.382846) (xy 377.557786 -295.410802) (xy 377.513324 -295.4319) (xy 377.466053 -295.445592)
			(xy 377.417198 -295.451524) (xy 377.368023 -295.449543) (xy 377.319804 -295.439699) (xy 377.273788 -295.422247)
			(xy 377.231167 -295.39764) (xy 377.193046 -295.366515) (xy 377.160411 -295.329678) (xy 377.134108 -295.288082)
			(xy 377.114817 -295.242806) (xy 377.10304 -295.195022) (xy 377.09908 -295.145968) (xy 376.024566 -295.145968)
			(xy 376.053096 -295.387014) (xy 376.056652 -295.39438) (xy 376.0597 -295.401492) (xy 376.176286 -295.65981)
			(xy 376.188264 -295.687296) (xy 376.207009 -295.744249) (xy 376.219611 -295.802869) (xy 376.225928 -295.862494)
			(xy 376.226324 -295.892474) (xy 376.226324 -295.955974) (xy 377.56898 -295.955974) (xy 377.57294 -295.90692)
			(xy 377.584717 -295.859136) (xy 377.604008 -295.81386) (xy 377.630311 -295.772264) (xy 377.662946 -295.735427)
			(xy 377.701067 -295.704302) (xy 377.743688 -295.679695) (xy 377.789704 -295.662243) (xy 377.837923 -295.652399)
			(xy 377.887098 -295.650418) (xy 377.935953 -295.65635) (xy 377.983224 -295.670042) (xy 378.027686 -295.69114)
			(xy 378.068189 -295.719096) (xy 378.103682 -295.753188) (xy 378.133247 -295.792532) (xy 378.156118 -295.836109)
			(xy 378.171702 -295.88279) (xy 378.179597 -295.931367) (xy 378.180092 -295.955974) (xy 378.179597 -295.980581)
			(xy 378.177789 -295.991708) (xy 378.512342 -295.991708) (xy 378.515026 -295.942131) (xy 378.525696 -295.893641)
			(xy 378.54407 -295.847516) (xy 378.569664 -295.804972) (xy 378.601804 -295.767129) (xy 378.639644 -295.734984)
			(xy 378.682186 -295.709385) (xy 378.728308 -295.691006) (xy 378.776797 -295.680331) (xy 378.826374 -295.677641)
			(xy 378.875733 -295.683008) (xy 378.923573 -295.696289) (xy 378.968634 -295.717136) (xy 379.009729 -295.744998)
			(xy 379.045775 -295.779142) (xy 379.075822 -295.818668) (xy 379.099078 -295.862534) (xy 379.114931 -295.909585)
			(xy 379.122962 -295.958581) (xy 379.123448 -295.983406) (xy 379.123284 -295.998815) (xy 379.120228 -296.029481)
			(xy 379.117352 -296.04462) (xy 379.114812 -296.057066) (xy 379.12167 -296.080688) (xy 379.1966 -296.159428)
			(xy 379.220222 -296.167302) (xy 379.232668 -296.16527) (xy 379.246421 -296.163246) (xy 379.274139 -296.161086)
			(xy 379.28804 -296.160952) (xy 379.302005 -296.161073) (xy 379.32985 -296.163231) (xy 379.343666 -296.16527)
			(xy 379.356112 -296.167302) (xy 379.379734 -296.159428) (xy 379.454664 -296.080688) (xy 379.461522 -296.057066)
			(xy 379.458982 -296.04462) (xy 379.45611 -296.02948) (xy 379.453054 -295.998815) (xy 379.452886 -295.983406)
			(xy 379.453408 -295.958151) (xy 379.461721 -295.908329) (xy 379.478122 -295.860555) (xy 379.502163 -295.816132)
			(xy 379.533187 -295.776272) (xy 379.570349 -295.742062) (xy 379.612635 -295.714436) (xy 379.658891 -295.694146)
			(xy 379.707856 -295.681746) (xy 379.758194 -295.677575) (xy 379.808532 -295.681746) (xy 379.857497 -295.694146)
			(xy 379.903753 -295.714436) (xy 379.946039 -295.742062) (xy 379.983201 -295.776272) (xy 380.014225 -295.816132)
			(xy 380.038266 -295.860555) (xy 380.054667 -295.908329) (xy 380.06298 -295.958151) (xy 380.063502 -295.983406)
			(xy 380.063339 -295.998815) (xy 380.060282 -296.029481) (xy 380.057406 -296.04462) (xy 380.054866 -296.056812)
			(xy 380.061724 -296.080688) (xy 380.136654 -296.159174) (xy 380.160276 -296.167302) (xy 380.172722 -296.16527)
			(xy 380.186413 -296.163261) (xy 380.214003 -296.161098) (xy 380.22784 -296.160952) (xy 380.241868 -296.161064)
			(xy 380.269841 -296.163223) (xy 380.28372 -296.16527) (xy 380.296166 -296.167302) (xy 380.319534 -296.159428)
			(xy 380.394718 -296.080688) (xy 380.401576 -296.057066) (xy 380.399036 -296.04462) (xy 380.396163 -296.02948)
			(xy 380.393108 -295.998815) (xy 380.39294 -295.983406) (xy 380.393371 -295.958585) (xy 380.401401 -295.909598)
			(xy 380.41725 -295.862555) (xy 380.440501 -295.818695) (xy 380.470541 -295.779175) (xy 380.506579 -295.745035)
			(xy 380.547665 -295.717175) (xy 380.592717 -295.696329) (xy 380.640548 -295.683046) (xy 380.689898 -295.677676)
			(xy 380.739467 -295.68036) (xy 380.787948 -295.691028) (xy 380.834065 -295.709398) (xy 380.876603 -295.734988)
			(xy 380.91444 -295.767121) (xy 380.946581 -295.804953) (xy 380.972178 -295.847486) (xy 380.990556 -295.8936)
			(xy 381.001233 -295.942079) (xy 381.003926 -295.991648) (xy 381.003919 -295.991713) (xy 381.332233 -295.991713)
			(xy 381.334917 -295.942135) (xy 381.345586 -295.893643) (xy 381.36396 -295.847516) (xy 381.389555 -295.80497)
			(xy 381.421696 -295.767125) (xy 381.459536 -295.734979) (xy 381.502079 -295.709379) (xy 381.548203 -295.690998)
			(xy 381.596693 -295.680322) (xy 381.646271 -295.677632) (xy 381.695632 -295.682999) (xy 381.743474 -295.696281)
			(xy 381.788537 -295.717128) (xy 381.829633 -295.744991) (xy 381.86568 -295.779136) (xy 381.895728 -295.818663)
			(xy 381.918985 -295.86253) (xy 381.934839 -295.909583) (xy 381.942871 -295.95858) (xy 381.943356 -295.983406)
			(xy 381.943192 -295.998815) (xy 381.940136 -296.029481) (xy 381.93726 -296.04462) (xy 381.93472 -296.057066)
			(xy 381.941578 -296.080688) (xy 382.016508 -296.159428) (xy 382.04013 -296.167302) (xy 382.052576 -296.16527)
			(xy 382.066329 -296.163246) (xy 382.094047 -296.161086) (xy 382.107948 -296.160952) (xy 382.121913 -296.161072)
			(xy 382.149758 -296.16323) (xy 382.163574 -296.16527) (xy 382.17602 -296.167302) (xy 382.199642 -296.159428)
			(xy 382.274572 -296.080688) (xy 382.28143 -296.057066) (xy 382.27889 -296.04462) (xy 382.276018 -296.02948)
			(xy 382.272962 -295.998815) (xy 382.272794 -295.983406) (xy 382.273316 -295.958151) (xy 382.281629 -295.908329)
			(xy 382.29803 -295.860555) (xy 382.322071 -295.816132) (xy 382.353095 -295.776272) (xy 382.390257 -295.742062)
			(xy 382.432543 -295.714436) (xy 382.478799 -295.694146) (xy 382.527764 -295.681746) (xy 382.578102 -295.677575)
			(xy 382.62844 -295.681746) (xy 382.677405 -295.694146) (xy 382.723661 -295.714436) (xy 382.765947 -295.742062)
			(xy 382.803109 -295.776272) (xy 382.834133 -295.816132) (xy 382.858174 -295.860555) (xy 382.874575 -295.908329)
			(xy 382.882888 -295.958151) (xy 382.88341 -295.983406) (xy 382.883246 -295.998815) (xy 382.88019 -296.029481)
			(xy 382.877314 -296.04462) (xy 382.874774 -296.057066) (xy 382.881632 -296.080688) (xy 382.956562 -296.159428)
			(xy 382.980184 -296.167302) (xy 382.99263 -296.16527) (xy 383.006384 -296.163251) (xy 383.034101 -296.161088)
			(xy 383.048002 -296.160952) (xy 383.061967 -296.161066) (xy 383.089813 -296.163228) (xy 383.103628 -296.16527)
			(xy 383.116074 -296.167302) (xy 383.139696 -296.159428) (xy 383.214626 -296.080688) (xy 383.221484 -296.057066)
			(xy 383.218944 -296.04462) (xy 383.216072 -296.02948) (xy 383.213016 -295.998815) (xy 383.212848 -295.983406)
			(xy 383.213371 -295.958584) (xy 383.221402 -295.909593) (xy 383.237254 -295.862547) (xy 383.260507 -295.818686)
			(xy 383.290551 -295.779164) (xy 383.326593 -295.745024) (xy 383.367683 -295.717165) (xy 383.41274 -295.696321)
			(xy 383.460575 -295.683041) (xy 383.509929 -295.677675) (xy 383.5595 -295.680364) (xy 383.607983 -295.691039)
			(xy 383.654101 -295.709416) (xy 383.696638 -295.735013) (xy 383.734473 -295.767154) (xy 383.76661 -295.804993)
			(xy 383.792201 -295.847533) (xy 383.810573 -295.893653) (xy 383.821241 -295.942138) (xy 383.82199 -295.955974)
			(xy 388.84912 -295.955974) (xy 388.85308 -295.90692) (xy 388.864857 -295.859136) (xy 388.884148 -295.81386)
			(xy 388.910451 -295.772264) (xy 388.943086 -295.735427) (xy 388.981207 -295.704302) (xy 389.023828 -295.679695)
			(xy 389.069844 -295.662243) (xy 389.118063 -295.652399) (xy 389.167238 -295.650418) (xy 389.216093 -295.65635)
			(xy 389.263364 -295.670042) (xy 389.307826 -295.69114) (xy 389.348329 -295.719096) (xy 389.383822 -295.753188)
			(xy 389.413387 -295.792532) (xy 389.436258 -295.836109) (xy 389.451842 -295.88279) (xy 389.459737 -295.931367)
			(xy 389.460232 -295.955974) (xy 389.459737 -295.980581) (xy 389.451842 -296.029158) (xy 389.436258 -296.075839)
			(xy 389.413387 -296.119416) (xy 389.383822 -296.15876) (xy 389.348329 -296.192852) (xy 389.307826 -296.220808)
			(xy 389.263364 -296.241906) (xy 389.216093 -296.255598) (xy 389.167238 -296.26153) (xy 389.118063 -296.259549)
			(xy 389.069844 -296.249705) (xy 389.023828 -296.232253) (xy 388.981207 -296.207646) (xy 388.943086 -296.176521)
			(xy 388.910451 -296.139684) (xy 388.884148 -296.098088) (xy 388.864857 -296.052812) (xy 388.85308 -296.005028)
			(xy 388.84912 -295.955974) (xy 383.82199 -295.955974) (xy 383.823924 -295.99171) (xy 383.818552 -296.041062)
			(xy 383.805266 -296.088896) (xy 383.784416 -296.13395) (xy 383.756552 -296.175037) (xy 383.722407 -296.211075)
			(xy 383.682882 -296.241113) (xy 383.639018 -296.264362) (xy 383.59197 -296.280207) (xy 383.542978 -296.288232)
			(xy 383.518156 -296.288714) (xy 383.495042 -296.287952) (xy 383.482596 -296.286936) (xy 383.459736 -296.296588)
			(xy 383.39141 -296.38117) (xy 383.38633 -296.4053) (xy 383.389886 -296.417492) (xy 383.39653 -296.441846)
			(xy 383.403671 -296.49182) (xy 383.40411 -296.51706) (xy 383.403612 -296.543709) (xy 383.395669 -296.596413)
			(xy 383.379959 -296.647343) (xy 383.356833 -296.695364) (xy 383.326809 -296.739401) (xy 383.290557 -296.778472)
			(xy 383.248886 -296.811703) (xy 383.202728 -296.838352) (xy 383.153114 -296.857824) (xy 383.101152 -296.869684)
			(xy 383.048002 -296.873668) (xy 382.994852 -296.869684) (xy 382.94289 -296.857824) (xy 382.893276 -296.838352)
			(xy 382.847118 -296.811703) (xy 382.805447 -296.778472) (xy 382.769195 -296.739401) (xy 382.739171 -296.695364)
			(xy 382.716045 -296.647343) (xy 382.700335 -296.596413) (xy 382.692392 -296.543709) (xy 382.691894 -296.51706)
			(xy 382.69234 -296.49182) (xy 382.699482 -296.441848) (xy 382.706118 -296.417492) (xy 382.709674 -296.405554)
			(xy 382.704594 -296.38117) (xy 382.636268 -296.296842) (xy 382.613408 -296.286936) (xy 382.600962 -296.287952)
			(xy 382.578102 -296.288714) (xy 382.554988 -296.287952) (xy 382.542542 -296.286936) (xy 382.519682 -296.296588)
			(xy 382.451356 -296.38117) (xy 382.446276 -296.4053) (xy 382.449832 -296.417492) (xy 382.456475 -296.441847)
			(xy 382.463617 -296.49182) (xy 382.464056 -296.51706) (xy 382.463558 -296.543709) (xy 382.455615 -296.596413)
			(xy 382.439905 -296.647343) (xy 382.416779 -296.695364) (xy 382.386755 -296.739401) (xy 382.350503 -296.778472)
			(xy 382.308832 -296.811703) (xy 382.262674 -296.838352) (xy 382.21306 -296.857824) (xy 382.161098 -296.869684)
			(xy 382.107948 -296.873668) (xy 382.054798 -296.869684) (xy 382.002836 -296.857824) (xy 381.953222 -296.838352)
			(xy 381.907064 -296.811703) (xy 381.865393 -296.778472) (xy 381.829141 -296.739401) (xy 381.799117 -296.695364)
			(xy 381.775991 -296.647343) (xy 381.760281 -296.596413) (xy 381.752338 -296.543709) (xy 381.75184 -296.51706)
			(xy 381.752284 -296.49182) (xy 381.759428 -296.441848) (xy 381.766064 -296.417492) (xy 381.76962 -296.405554)
			(xy 381.76454 -296.38117) (xy 381.696214 -296.296842) (xy 381.673354 -296.286936) (xy 381.660908 -296.287952)
			(xy 381.638048 -296.288714) (xy 381.613222 -296.288274) (xy 381.564224 -296.280249) (xy 381.517169 -296.264402)
			(xy 381.473298 -296.241151) (xy 381.433767 -296.211108) (xy 381.399617 -296.175066) (xy 381.371748 -296.133973)
			(xy 381.350895 -296.088913) (xy 381.337607 -296.041073) (xy 381.332233 -295.991713) (xy 381.003919 -295.991713)
			(xy 380.998564 -296.040998) (xy 380.98529 -296.088832) (xy 380.964451 -296.133888) (xy 380.936599 -296.174979)
			(xy 380.902465 -296.211023) (xy 380.86295 -296.24107) (xy 380.819095 -296.264328) (xy 380.772055 -296.280186)
			(xy 380.723069 -296.288224) (xy 380.698248 -296.288714) (xy 380.675134 -296.287952) (xy 380.662434 -296.286936)
			(xy 380.639574 -296.296588) (xy 380.570994 -296.38117) (xy 380.566168 -296.4053) (xy 380.569724 -296.417492)
			(xy 380.576367 -296.441847) (xy 380.583509 -296.49182) (xy 380.583948 -296.51706) (xy 380.58345 -296.543709)
			(xy 380.575507 -296.596413) (xy 380.559797 -296.647343) (xy 380.536671 -296.695364) (xy 380.506647 -296.739401)
			(xy 380.470395 -296.778472) (xy 380.428724 -296.811703) (xy 380.382566 -296.838352) (xy 380.332952 -296.857824)
			(xy 380.28099 -296.869684) (xy 380.22784 -296.873668) (xy 380.17469 -296.869684) (xy 380.122728 -296.857824)
			(xy 380.073114 -296.838352) (xy 380.026956 -296.811703) (xy 379.985285 -296.778472) (xy 379.949033 -296.739401)
			(xy 379.919009 -296.695364) (xy 379.895883 -296.647343) (xy 379.880173 -296.596413) (xy 379.87223 -296.543709)
			(xy 379.871732 -296.51706) (xy 379.872177 -296.49182) (xy 379.87932 -296.441848) (xy 379.885956 -296.417492)
			(xy 379.889512 -296.405554) (xy 379.884432 -296.38117) (xy 379.816106 -296.296842) (xy 379.7935 -296.286936)
			(xy 379.7808 -296.287952) (xy 379.758194 -296.288714) (xy 379.73508 -296.287952) (xy 379.722634 -296.286936)
			(xy 379.699774 -296.296588) (xy 379.631448 -296.38117) (xy 379.626368 -296.4053) (xy 379.629924 -296.417492)
			(xy 379.636567 -296.441847) (xy 379.643709 -296.49182) (xy 379.644148 -296.51706) (xy 379.64365 -296.543709)
			(xy 379.635707 -296.596413) (xy 379.619997 -296.647343) (xy 379.596871 -296.695364) (xy 379.566847 -296.739401)
			(xy 379.530595 -296.778472) (xy 379.488924 -296.811703) (xy 379.442766 -296.838352) (xy 379.393152 -296.857824)
			(xy 379.34119 -296.869684) (xy 379.28804 -296.873668) (xy 379.23489 -296.869684) (xy 379.182928 -296.857824)
			(xy 379.133314 -296.838352) (xy 379.087156 -296.811703) (xy 379.045485 -296.778472) (xy 379.009233 -296.739401)
			(xy 378.979209 -296.695364) (xy 378.956083 -296.647343) (xy 378.940373 -296.596413) (xy 378.93243 -296.543709)
			(xy 378.931932 -296.51706) (xy 378.932377 -296.49182) (xy 378.93952 -296.441848) (xy 378.946156 -296.417492)
			(xy 378.949712 -296.405554) (xy 378.944632 -296.38117) (xy 378.876306 -296.296842) (xy 378.853446 -296.286936)
			(xy 378.841 -296.287952) (xy 378.81814 -296.288714) (xy 378.793315 -296.288265) (xy 378.744318 -296.280239)
			(xy 378.697266 -296.264391) (xy 378.653397 -296.24114) (xy 378.613868 -296.211098) (xy 378.57972 -296.175056)
			(xy 378.551853 -296.133964) (xy 378.531001 -296.088905) (xy 378.517714 -296.041066) (xy 378.512342 -295.991708)
			(xy 378.177789 -295.991708) (xy 378.171702 -296.029158) (xy 378.156118 -296.075839) (xy 378.133247 -296.119416)
			(xy 378.103682 -296.15876) (xy 378.068189 -296.192852) (xy 378.027686 -296.220808) (xy 377.983224 -296.241906)
			(xy 377.935953 -296.255598) (xy 377.887098 -296.26153) (xy 377.837923 -296.259549) (xy 377.789704 -296.249705)
			(xy 377.743688 -296.232253) (xy 377.701067 -296.207646) (xy 377.662946 -296.176521) (xy 377.630311 -296.139684)
			(xy 377.604008 -296.098088) (xy 377.584717 -296.052812) (xy 377.57294 -296.005028) (xy 377.56898 -295.955974)
			(xy 376.226324 -295.955974) (xy 376.226324 -296.344594) (xy 376.226471 -296.350176) (xy 376.228911 -296.361069)
			(xy 376.23115 -296.366184) (xy 376.244285 -296.395136) (xy 376.264879 -296.455288) (xy 376.278774 -296.517331)
			(xy 376.2858 -296.580521) (xy 376.286268 -296.61231) (xy 376.286268 -296.819574) (xy 376.286362 -296.824593)
			(xy 376.288285 -296.834443) (xy 376.290078 -296.839132) (xy 376.390682 -297.081913) (xy 385.826756 -297.081913)
			(xy 385.826756 -297.017991) (xy 385.834767 -296.954573) (xy 385.850664 -296.892659) (xy 385.874196 -296.833226)
			(xy 385.90499 -296.777211) (xy 385.942563 -296.725496) (xy 385.98632 -296.678899) (xy 386.035573 -296.638154)
			(xy 386.089544 -296.603903) (xy 386.147383 -296.576686) (xy 386.208176 -296.556933) (xy 386.270966 -296.544955)
			(xy 386.334762 -296.540942) (xy 386.398558 -296.544955) (xy 386.461348 -296.556933) (xy 386.522141 -296.576686)
			(xy 386.57998 -296.603903) (xy 386.633951 -296.638154) (xy 386.683204 -296.678899) (xy 386.726961 -296.725496)
			(xy 386.764534 -296.777211) (xy 386.795328 -296.833226) (xy 386.81886 -296.892659) (xy 386.834757 -296.954573)
			(xy 386.842768 -297.017991) (xy 386.84327 -297.049952) (xy 386.842768 -297.081913) (xy 386.834757 -297.145331)
			(xy 386.81886 -297.207245) (xy 386.795328 -297.266678) (xy 386.764534 -297.322693) (xy 386.726961 -297.374408)
			(xy 386.683204 -297.421005) (xy 386.633951 -297.46175) (xy 386.57998 -297.496001) (xy 386.522141 -297.523218)
			(xy 386.461348 -297.542971) (xy 386.398558 -297.554949) (xy 386.334762 -297.558963) (xy 386.270966 -297.554949)
			(xy 386.208176 -297.542971) (xy 386.147383 -297.523218) (xy 386.089544 -297.496001) (xy 386.035573 -297.46175)
			(xy 385.98632 -297.421005) (xy 385.942563 -297.374408) (xy 385.90499 -297.322693) (xy 385.874196 -297.266678)
			(xy 385.850664 -297.207245) (xy 385.834767 -297.145331) (xy 385.826756 -297.081913) (xy 376.390682 -297.081913)
			(xy 377.351559 -299.400722) (xy 379.192026 -299.400722) (xy 379.196097 -299.3451) (xy 379.208223 -299.290663)
			(xy 379.228146 -299.238572) (xy 379.255442 -299.189937) (xy 379.289528 -299.145794) (xy 379.329677 -299.107085)
			(xy 379.375035 -299.074634) (xy 379.424635 -299.049133) (xy 379.477419 -299.031126) (xy 379.532262 -299.020996)
			(xy 379.587996 -299.018959) (xy 379.643433 -299.025059) (xy 379.69739 -299.039165) (xy 379.748719 -299.060977)
			(xy 379.796325 -299.090031) (xy 379.839193 -299.125706) (xy 379.87641 -299.167243) (xy 379.907183 -299.213756)
			(xy 379.930855 -299.264253) (xy 379.935385 -299.27931) (xy 381.753362 -299.27931) (xy 381.757433 -299.223688)
			(xy 381.769559 -299.169251) (xy 381.789482 -299.11716) (xy 381.816778 -299.068525) (xy 381.850864 -299.024382)
			(xy 381.891013 -298.985673) (xy 381.936371 -298.953222) (xy 381.985971 -298.927721) (xy 382.038755 -298.909714)
			(xy 382.093598 -298.899584) (xy 382.149332 -298.897547) (xy 382.204769 -298.903647) (xy 382.258726 -298.917753)
			(xy 382.310055 -298.939565) (xy 382.357661 -298.968619) (xy 382.400529 -299.004294) (xy 382.437746 -299.045831)
			(xy 382.468519 -299.092344) (xy 382.492191 -299.142841) (xy 382.508259 -299.196248) (xy 382.516379 -299.251424)
			(xy 382.516888 -299.27931) (xy 384.039362 -299.27931) (xy 384.043433 -299.223688) (xy 384.055559 -299.169251)
			(xy 384.075482 -299.11716) (xy 384.102778 -299.068525) (xy 384.136864 -299.024382) (xy 384.177013 -298.985673)
			(xy 384.222371 -298.953222) (xy 384.271971 -298.927721) (xy 384.324755 -298.909714) (xy 384.379598 -298.899584)
			(xy 384.435332 -298.897547) (xy 384.490769 -298.903647) (xy 384.544726 -298.917753) (xy 384.596055 -298.939565)
			(xy 384.643661 -298.968619) (xy 384.686529 -299.004294) (xy 384.723746 -299.045831) (xy 384.754519 -299.092344)
			(xy 384.762249 -299.108833) (xy 387.935718 -299.108833) (xy 387.935718 -299.044911) (xy 387.943729 -298.981493)
			(xy 387.959626 -298.919579) (xy 387.983158 -298.860146) (xy 388.013952 -298.804131) (xy 388.051525 -298.752416)
			(xy 388.095282 -298.705819) (xy 388.144535 -298.665074) (xy 388.198506 -298.630823) (xy 388.256345 -298.603606)
			(xy 388.317138 -298.583853) (xy 388.379928 -298.571875) (xy 388.443724 -298.567862) (xy 388.50752 -298.571875)
			(xy 388.57031 -298.583853) (xy 388.631103 -298.603606) (xy 388.688942 -298.630823) (xy 388.742913 -298.665074)
			(xy 388.792166 -298.705819) (xy 388.835923 -298.752416) (xy 388.873496 -298.804131) (xy 388.90429 -298.860146)
			(xy 388.927822 -298.919579) (xy 388.943719 -298.981493) (xy 388.95173 -299.044911) (xy 388.952232 -299.076872)
			(xy 388.95173 -299.108833) (xy 388.943719 -299.172251) (xy 388.927822 -299.234165) (xy 388.90429 -299.293598)
			(xy 388.873496 -299.349613) (xy 388.835923 -299.401328) (xy 388.792166 -299.447925) (xy 388.742913 -299.48867)
			(xy 388.688942 -299.522921) (xy 388.631103 -299.550138) (xy 388.57031 -299.569891) (xy 388.50752 -299.581869)
			(xy 388.443724 -299.585883) (xy 388.379928 -299.581869) (xy 388.317138 -299.569891) (xy 388.256345 -299.550138)
			(xy 388.198506 -299.522921) (xy 388.144535 -299.48867) (xy 388.095282 -299.447925) (xy 388.051525 -299.401328)
			(xy 388.013952 -299.349613) (xy 387.983158 -299.293598) (xy 387.959626 -299.234165) (xy 387.943729 -299.172251)
			(xy 387.935718 -299.108833) (xy 384.762249 -299.108833) (xy 384.778191 -299.142841) (xy 384.794259 -299.196248)
			(xy 384.802379 -299.251424) (xy 384.802888 -299.27931) (xy 384.802379 -299.307196) (xy 384.794259 -299.362372)
			(xy 384.778191 -299.415779) (xy 384.754519 -299.466276) (xy 384.723746 -299.512789) (xy 384.686529 -299.554326)
			(xy 384.643661 -299.590001) (xy 384.596055 -299.619055) (xy 384.544726 -299.640867) (xy 384.490769 -299.654973)
			(xy 384.435332 -299.661073) (xy 384.379598 -299.659036) (xy 384.324755 -299.648906) (xy 384.271971 -299.630899)
			(xy 384.222371 -299.605398) (xy 384.177013 -299.572947) (xy 384.136864 -299.534238) (xy 384.102778 -299.490095)
			(xy 384.075482 -299.44146) (xy 384.055559 -299.389369) (xy 384.043433 -299.334932) (xy 384.039362 -299.27931)
			(xy 382.516888 -299.27931) (xy 382.516379 -299.307196) (xy 382.508259 -299.362372) (xy 382.492191 -299.415779)
			(xy 382.468519 -299.466276) (xy 382.437746 -299.512789) (xy 382.400529 -299.554326) (xy 382.357661 -299.590001)
			(xy 382.310055 -299.619055) (xy 382.258726 -299.640867) (xy 382.204769 -299.654973) (xy 382.149332 -299.661073)
			(xy 382.093598 -299.659036) (xy 382.038755 -299.648906) (xy 381.985971 -299.630899) (xy 381.936371 -299.605398)
			(xy 381.891013 -299.572947) (xy 381.850864 -299.534238) (xy 381.816778 -299.490095) (xy 381.789482 -299.44146)
			(xy 381.769559 -299.389369) (xy 381.757433 -299.334932) (xy 381.753362 -299.27931) (xy 379.935385 -299.27931)
			(xy 379.946923 -299.31766) (xy 379.955043 -299.372836) (xy 379.955552 -299.400722) (xy 379.955043 -299.428608)
			(xy 379.946923 -299.483784) (xy 379.930855 -299.537191) (xy 379.907183 -299.587688) (xy 379.87641 -299.634201)
			(xy 379.839193 -299.675738) (xy 379.796325 -299.711413) (xy 379.748719 -299.740467) (xy 379.69739 -299.762279)
			(xy 379.643433 -299.776385) (xy 379.587996 -299.782485) (xy 379.532262 -299.780448) (xy 379.477419 -299.770318)
			(xy 379.424635 -299.752311) (xy 379.375035 -299.72681) (xy 379.329677 -299.694359) (xy 379.289528 -299.65565)
			(xy 379.255442 -299.611507) (xy 379.228146 -299.562872) (xy 379.208223 -299.510781) (xy 379.196097 -299.456344)
			(xy 379.192026 -299.400722) (xy 377.351559 -299.400722) (xy 378.04874 -301.083175) (xy 386.695944 -301.083175)
			(xy 386.695944 -301.019253) (xy 386.703955 -300.955835) (xy 386.719852 -300.893921) (xy 386.743384 -300.834488)
			(xy 386.774178 -300.778473) (xy 386.811751 -300.726758) (xy 386.855508 -300.680161) (xy 386.904761 -300.639416)
			(xy 386.958732 -300.605165) (xy 387.016571 -300.577948) (xy 387.077364 -300.558195) (xy 387.140154 -300.546217)
			(xy 387.20395 -300.542204) (xy 387.267746 -300.546217) (xy 387.330536 -300.558195) (xy 387.391329 -300.577948)
			(xy 387.449168 -300.605165) (xy 387.503139 -300.639416) (xy 387.552392 -300.680161) (xy 387.596149 -300.726758)
			(xy 387.633722 -300.778473) (xy 387.664516 -300.834488) (xy 387.688048 -300.893921) (xy 387.703945 -300.955835)
			(xy 387.711956 -301.019253) (xy 387.712458 -301.051214) (xy 387.711956 -301.083175) (xy 387.703945 -301.146593)
			(xy 387.688048 -301.208507) (xy 387.664516 -301.26794) (xy 387.633722 -301.323955) (xy 387.596149 -301.37567)
			(xy 387.552392 -301.422267) (xy 387.503139 -301.463012) (xy 387.449168 -301.497263) (xy 387.391329 -301.52448)
			(xy 387.330536 -301.544233) (xy 387.267746 -301.556211) (xy 387.20395 -301.560225) (xy 387.140154 -301.556211)
			(xy 387.077364 -301.544233) (xy 387.016571 -301.52448) (xy 386.958732 -301.497263) (xy 386.904761 -301.463012)
			(xy 386.855508 -301.422267) (xy 386.811751 -301.37567) (xy 386.774178 -301.323955) (xy 386.743384 -301.26794)
			(xy 386.719852 -301.208507) (xy 386.703955 -301.146593) (xy 386.695944 -301.083175) (xy 378.04874 -301.083175)
			(xy 378.558903 -302.314313) (xy 385.881112 -302.314313) (xy 385.881112 -302.250391) (xy 385.889123 -302.186973)
			(xy 385.90502 -302.125059) (xy 385.928552 -302.065626) (xy 385.959346 -302.009611) (xy 385.996919 -301.957896)
			(xy 386.040676 -301.911299) (xy 386.089929 -301.870554) (xy 386.1439 -301.836303) (xy 386.201739 -301.809086)
			(xy 386.262532 -301.789333) (xy 386.325322 -301.777355) (xy 386.389118 -301.773342) (xy 386.452914 -301.777355)
			(xy 386.515704 -301.789333) (xy 386.576497 -301.809086) (xy 386.634336 -301.836303) (xy 386.688307 -301.870554)
			(xy 386.73756 -301.911299) (xy 386.781317 -301.957896) (xy 386.81889 -302.009611) (xy 386.849684 -302.065626)
			(xy 386.873216 -302.125059) (xy 386.889113 -302.186973) (xy 386.897124 -302.250391) (xy 386.897626 -302.282352)
			(xy 386.897124 -302.314313) (xy 386.889113 -302.377731) (xy 386.873216 -302.439645) (xy 386.849684 -302.499078)
			(xy 386.81889 -302.555093) (xy 386.781317 -302.606808) (xy 386.73756 -302.653405) (xy 386.688307 -302.69415)
			(xy 386.634336 -302.728401) (xy 386.576497 -302.755618) (xy 386.515704 -302.775371) (xy 386.452914 -302.787349)
			(xy 386.389118 -302.791363) (xy 386.325322 -302.787349) (xy 386.262532 -302.775371) (xy 386.201739 -302.755618)
			(xy 386.1439 -302.728401) (xy 386.089929 -302.69415) (xy 386.040676 -302.653405) (xy 385.996919 -302.606808)
			(xy 385.959346 -302.555093) (xy 385.928552 -302.499078) (xy 385.90502 -302.439645) (xy 385.889123 -302.377731)
			(xy 385.881112 -302.314313) (xy 378.558903 -302.314313) (xy 380.85776 -307.86197) (xy 380.858268 -307.862986)
			(xy 381.39213 -309.074312) (xy 389.3345 -309.074312) (xy 389.338571 -309.01869) (xy 389.350697 -308.964253)
			(xy 389.37062 -308.912162) (xy 389.397916 -308.863527) (xy 389.432002 -308.819384) (xy 389.472151 -308.780675)
			(xy 389.517509 -308.748224) (xy 389.567109 -308.722723) (xy 389.619893 -308.704716) (xy 389.674736 -308.694586)
			(xy 389.73047 -308.692549) (xy 389.785907 -308.698649) (xy 389.839864 -308.712755) (xy 389.891193 -308.734567)
			(xy 389.938799 -308.763621) (xy 389.981667 -308.799296) (xy 390.018884 -308.840833) (xy 390.049657 -308.887346)
			(xy 390.073329 -308.937843) (xy 390.089397 -308.99125) (xy 390.097517 -309.046426) (xy 390.098026 -309.074312)
			(xy 390.097517 -309.102198) (xy 390.089397 -309.157374) (xy 390.079235 -309.191152) (xy 393.28674 -309.191152)
			(xy 393.290811 -309.13553) (xy 393.302937 -309.081093) (xy 393.32286 -309.029002) (xy 393.350156 -308.980367)
			(xy 393.384242 -308.936224) (xy 393.424391 -308.897515) (xy 393.469749 -308.865064) (xy 393.519349 -308.839563)
			(xy 393.572133 -308.821556) (xy 393.626976 -308.811426) (xy 393.68271 -308.809389) (xy 393.738147 -308.815489)
			(xy 393.792104 -308.829595) (xy 393.843433 -308.851407) (xy 393.891039 -308.880461) (xy 393.933907 -308.916136)
			(xy 393.971124 -308.957673) (xy 394.001897 -309.004186) (xy 394.025569 -309.054683) (xy 394.041637 -309.10809)
			(xy 394.049757 -309.163266) (xy 394.050266 -309.191152) (xy 394.049757 -309.219038) (xy 394.041637 -309.274214)
			(xy 394.025569 -309.327621) (xy 394.001897 -309.378118) (xy 393.971124 -309.424631) (xy 393.933907 -309.466168)
			(xy 393.891039 -309.501843) (xy 393.843433 -309.530897) (xy 393.792104 -309.552709) (xy 393.738147 -309.566815)
			(xy 393.68271 -309.572915) (xy 393.626976 -309.570878) (xy 393.572133 -309.560748) (xy 393.519349 -309.542741)
			(xy 393.469749 -309.51724) (xy 393.424391 -309.484789) (xy 393.384242 -309.44608) (xy 393.350156 -309.401937)
			(xy 393.32286 -309.353302) (xy 393.302937 -309.301211) (xy 393.290811 -309.246774) (xy 393.28674 -309.191152)
			(xy 390.079235 -309.191152) (xy 390.073329 -309.210781) (xy 390.049657 -309.261278) (xy 390.018884 -309.307791)
			(xy 389.981667 -309.349328) (xy 389.938799 -309.385003) (xy 389.891193 -309.414057) (xy 389.839864 -309.435869)
			(xy 389.785907 -309.449975) (xy 389.73047 -309.456075) (xy 389.674736 -309.454038) (xy 389.619893 -309.443908)
			(xy 389.567109 -309.425901) (xy 389.517509 -309.4004) (xy 389.472151 -309.367949) (xy 389.432002 -309.32924)
			(xy 389.397916 -309.285097) (xy 389.37062 -309.236462) (xy 389.350697 -309.184371) (xy 389.338571 -309.129934)
			(xy 389.3345 -309.074312) (xy 381.39213 -309.074312) (xy 381.891401 -310.207152) (xy 393.28674 -310.207152)
			(xy 393.290811 -310.15153) (xy 393.302937 -310.097093) (xy 393.32286 -310.045002) (xy 393.350156 -309.996367)
			(xy 393.384242 -309.952224) (xy 393.424391 -309.913515) (xy 393.469749 -309.881064) (xy 393.519349 -309.855563)
			(xy 393.572133 -309.837556) (xy 393.626976 -309.827426) (xy 393.68271 -309.825389) (xy 393.738147 -309.831489)
			(xy 393.792104 -309.845595) (xy 393.843433 -309.867407) (xy 393.891039 -309.896461) (xy 393.933907 -309.932136)
			(xy 393.971124 -309.973673) (xy 394.001897 -310.020186) (xy 394.025569 -310.070683) (xy 394.041637 -310.12409)
			(xy 394.049757 -310.179266) (xy 394.050266 -310.207152) (xy 394.049757 -310.235038) (xy 394.041637 -310.290214)
			(xy 394.025569 -310.343621) (xy 394.001897 -310.394118) (xy 393.971124 -310.440631) (xy 393.933907 -310.482168)
			(xy 393.891039 -310.517843) (xy 393.843433 -310.546897) (xy 393.792104 -310.568709) (xy 393.738147 -310.582815)
			(xy 393.68271 -310.588915) (xy 393.626976 -310.586878) (xy 393.572133 -310.576748) (xy 393.519349 -310.558741)
			(xy 393.469749 -310.53324) (xy 393.424391 -310.500789) (xy 393.384242 -310.46208) (xy 393.350156 -310.417937)
			(xy 393.32286 -310.369302) (xy 393.302937 -310.317211) (xy 393.290811 -310.262774) (xy 393.28674 -310.207152)
			(xy 381.891401 -310.207152) (xy 382.603365 -311.822592) (xy 388.54964 -311.822592) (xy 388.553711 -311.76697)
			(xy 388.565837 -311.712533) (xy 388.58576 -311.660442) (xy 388.613056 -311.611807) (xy 388.647142 -311.567664)
			(xy 388.687291 -311.528955) (xy 388.732649 -311.496504) (xy 388.782249 -311.471003) (xy 388.835033 -311.452996)
			(xy 388.889876 -311.442866) (xy 388.94561 -311.440829) (xy 389.001047 -311.446929) (xy 389.055004 -311.461035)
			(xy 389.106333 -311.482847) (xy 389.153939 -311.511901) (xy 389.196807 -311.547576) (xy 389.234024 -311.589113)
			(xy 389.264797 -311.635626) (xy 389.288469 -311.686123) (xy 389.304537 -311.73953) (xy 389.312657 -311.794706)
			(xy 389.313166 -311.822592) (xy 390.83564 -311.822592) (xy 390.839711 -311.76697) (xy 390.851837 -311.712533)
			(xy 390.87176 -311.660442) (xy 390.899056 -311.611807) (xy 390.933142 -311.567664) (xy 390.973291 -311.528955)
			(xy 391.018649 -311.496504) (xy 391.068249 -311.471003) (xy 391.121033 -311.452996) (xy 391.175876 -311.442866)
			(xy 391.23161 -311.440829) (xy 391.287047 -311.446929) (xy 391.341004 -311.461035) (xy 391.392333 -311.482847)
			(xy 391.439939 -311.511901) (xy 391.482807 -311.547576) (xy 391.520024 -311.589113) (xy 391.550797 -311.635626)
			(xy 391.574469 -311.686123) (xy 391.590537 -311.73953) (xy 391.598657 -311.794706) (xy 391.599166 -311.822592)
			(xy 391.598657 -311.850478) (xy 391.590537 -311.905654) (xy 391.574469 -311.959061) (xy 391.550797 -312.009558)
			(xy 391.520024 -312.056071) (xy 391.482807 -312.097608) (xy 391.439939 -312.133283) (xy 391.392333 -312.162337)
			(xy 391.341004 -312.184149) (xy 391.287047 -312.198255) (xy 391.23161 -312.204355) (xy 391.175876 -312.202318)
			(xy 391.121033 -312.192188) (xy 391.068249 -312.174181) (xy 391.018649 -312.14868) (xy 390.973291 -312.116229)
			(xy 390.933142 -312.07752) (xy 390.899056 -312.033377) (xy 390.87176 -311.984742) (xy 390.851837 -311.932651)
			(xy 390.839711 -311.878214) (xy 390.83564 -311.822592) (xy 389.313166 -311.822592) (xy 389.312657 -311.850478)
			(xy 389.304537 -311.905654) (xy 389.288469 -311.959061) (xy 389.264797 -312.009558) (xy 389.234024 -312.056071)
			(xy 389.196807 -312.097608) (xy 389.153939 -312.133283) (xy 389.106333 -312.162337) (xy 389.055004 -312.184149)
			(xy 389.001047 -312.198255) (xy 388.94561 -312.204355) (xy 388.889876 -312.202318) (xy 388.835033 -312.192188)
			(xy 388.782249 -312.174181) (xy 388.732649 -312.14868) (xy 388.687291 -312.116229) (xy 388.647142 -312.07752)
			(xy 388.613056 -312.033377) (xy 388.58576 -311.984742) (xy 388.565837 -311.932651) (xy 388.553711 -311.878214)
			(xy 388.54964 -311.822592) (xy 382.603365 -311.822592) (xy 383.408019 -313.648344) (xy 388.973566 -313.648344)
			(xy 388.977637 -313.592722) (xy 388.989763 -313.538285) (xy 389.009686 -313.486194) (xy 389.036982 -313.437559)
			(xy 389.071068 -313.393416) (xy 389.111217 -313.354707) (xy 389.156575 -313.322256) (xy 389.206175 -313.296755)
			(xy 389.258959 -313.278748) (xy 389.313802 -313.268618) (xy 389.369536 -313.266581) (xy 389.424973 -313.272681)
			(xy 389.47893 -313.286787) (xy 389.530259 -313.308599) (xy 389.577865 -313.337653) (xy 389.620733 -313.373328)
			(xy 389.65795 -313.414865) (xy 389.688723 -313.461378) (xy 389.712395 -313.511875) (xy 389.728463 -313.565282)
			(xy 389.736583 -313.620458) (xy 389.736693 -313.6265) (xy 392.774932 -313.6265) (xy 392.775415 -313.593352)
			(xy 392.78403 -313.527618) (xy 392.801115 -313.463561) (xy 392.82638 -313.402267) (xy 392.859395 -313.344777)
			(xy 392.899602 -313.292064) (xy 392.946319 -313.245024) (xy 392.998752 -313.204454) (xy 393.056013 -313.171041)
			(xy 393.11713 -313.145353) (xy 393.181067 -313.127826) (xy 393.24674 -313.118756) (xy 393.279884 -313.117992)
			(xy 393.288774 -313.117473) (xy 393.305413 -313.111168) (xy 393.318895 -313.099557) (xy 393.327597 -313.084037)
			(xy 393.329414 -313.07532) (xy 393.335229 -313.043285) (xy 393.353924 -312.980919) (xy 393.380424 -312.921448)
			(xy 393.414297 -312.865846) (xy 393.454989 -312.81502) (xy 393.501833 -312.769803) (xy 393.554065 -312.730933)
			(xy 393.61083 -312.699046) (xy 393.6712 -312.674664) (xy 393.734188 -312.658185) (xy 393.798764 -312.649879)
			(xy 393.831318 -312.649362) (xy 393.862048 -312.649839) (xy 393.92306 -312.657249) (xy 393.982735 -312.671959)
			(xy 394.040201 -312.693754) (xy 394.094621 -312.722316) (xy 394.145202 -312.75723) (xy 394.191206 -312.797985)
			(xy 394.231963 -312.843988) (xy 394.266878 -312.894569) (xy 394.295441 -312.948988) (xy 394.317238 -313.006454)
			(xy 394.331949 -313.066128) (xy 394.33936 -313.12714) (xy 394.339826 -313.15787) (xy 394.339258 -313.191015)
			(xy 394.330647 -313.256744) (xy 394.313568 -313.320796) (xy 394.288311 -313.382085) (xy 394.255302 -313.439573)
			(xy 394.215104 -313.492284) (xy 394.168396 -313.539324) (xy 394.115971 -313.579895) (xy 394.058719 -313.61331)
			(xy 393.99761 -313.639002) (xy 393.93368 -313.656534) (xy 393.868014 -313.66561) (xy 393.834874 -313.666378)
			(xy 393.825984 -313.666887) (xy 393.809348 -313.673201) (xy 393.795868 -313.684814) (xy 393.787164 -313.700333)
			(xy 393.785344 -313.70905) (xy 393.779218 -313.742705) (xy 393.759078 -313.80808) (xy 393.745212 -313.839352)
			(xy 393.739116 -313.852814) (xy 393.742672 -313.881262) (xy 393.787662 -313.935872) (xy 394.732762 -313.935872)
			(xy 394.736833 -313.88025) (xy 394.748959 -313.825813) (xy 394.768882 -313.773722) (xy 394.796178 -313.725087)
			(xy 394.830264 -313.680944) (xy 394.870413 -313.642235) (xy 394.915771 -313.609784) (xy 394.965371 -313.584283)
			(xy 395.018155 -313.566276) (xy 395.072998 -313.556146) (xy 395.128732 -313.554109) (xy 395.184169 -313.560209)
			(xy 395.238126 -313.574315) (xy 395.289455 -313.596127) (xy 395.337061 -313.625181) (xy 395.379929 -313.660856)
			(xy 395.417146 -313.702393) (xy 395.447919 -313.748906) (xy 395.471591 -313.799403) (xy 395.487659 -313.85281)
			(xy 395.495779 -313.907986) (xy 395.496288 -313.935872) (xy 395.495779 -313.963758) (xy 395.487659 -314.018934)
			(xy 395.471591 -314.072341) (xy 395.447919 -314.122838) (xy 395.417146 -314.169351) (xy 395.379929 -314.210888)
			(xy 395.337061 -314.246563) (xy 395.289455 -314.275617) (xy 395.238126 -314.297429) (xy 395.184169 -314.311535)
			(xy 395.128732 -314.317635) (xy 395.072998 -314.315598) (xy 395.018155 -314.305468) (xy 394.965371 -314.287461)
			(xy 394.915771 -314.26196) (xy 394.870413 -314.229509) (xy 394.830264 -314.1908) (xy 394.796178 -314.146657)
			(xy 394.768882 -314.098022) (xy 394.748959 -314.045931) (xy 394.736833 -313.991494) (xy 394.732762 -313.935872)
			(xy 393.787662 -313.935872) (xy 393.819888 -313.974988) (xy 393.84732 -313.983878) (xy 393.861798 -313.980322)
			(xy 393.891559 -313.97352) (xy 393.952176 -313.966263) (xy 393.982702 -313.965844) (xy 394.014244 -313.96637)
			(xy 394.076842 -313.974173) (xy 394.137995 -313.98966) (xy 394.196762 -314.012591) (xy 394.252241 -314.042616)
			(xy 394.303581 -314.079273) (xy 394.349992 -314.121999) (xy 394.390761 -314.170138) (xy 394.425263 -314.222949)
			(xy 394.452968 -314.279623) (xy 394.473449 -314.339289) (xy 394.486393 -314.40103) (xy 394.4916 -314.463898)
			(xy 394.488991 -314.526927) (xy 394.478606 -314.589149) (xy 394.460603 -314.649609) (xy 394.435261 -314.707377)
			(xy 394.402967 -314.761568) (xy 394.364218 -314.811347) (xy 394.31961 -314.855951) (xy 394.269826 -314.894695)
			(xy 394.215633 -314.926984) (xy 394.157862 -314.952321) (xy 394.0974 -314.970317) (xy 394.035177 -314.980696)
			(xy 393.972147 -314.983299) (xy 393.90928 -314.978086) (xy 393.847541 -314.965136) (xy 393.787877 -314.944649)
			(xy 393.731206 -314.916939) (xy 393.678398 -314.882431) (xy 393.630263 -314.841657) (xy 393.587542 -314.795242)
			(xy 393.55089 -314.743899) (xy 393.52087 -314.688417) (xy 393.497944 -314.629647) (xy 393.482464 -314.568493)
			(xy 393.474667 -314.505894) (xy 393.474194 -314.474352) (xy 393.474857 -314.437732) (xy 393.485384 -314.365252)
			(xy 393.506184 -314.295027) (xy 393.52093 -314.2615) (xy 393.527026 -314.248038) (xy 393.52347 -314.21959)
			(xy 393.446254 -314.125864) (xy 393.418822 -314.116974) (xy 393.404344 -314.12053) (xy 393.374581 -314.127324)
			(xy 393.313965 -314.134587) (xy 393.28344 -314.135008) (xy 393.252709 -314.134525) (xy 393.191694 -314.127121)
			(xy 393.132016 -314.112416) (xy 393.074547 -314.090624) (xy 393.020123 -314.062064) (xy 392.969538 -314.027152)
			(xy 392.923531 -313.986397) (xy 392.882773 -313.940393) (xy 392.847856 -313.889811) (xy 392.819292 -313.83539)
			(xy 392.797496 -313.777922) (xy 392.782786 -313.718246) (xy 392.775378 -313.657231) (xy 392.774932 -313.6265)
			(xy 389.736693 -313.6265) (xy 389.737092 -313.648344) (xy 389.736583 -313.67623) (xy 389.728463 -313.731406)
			(xy 389.712395 -313.784813) (xy 389.688723 -313.83531) (xy 389.65795 -313.881823) (xy 389.620733 -313.92336)
			(xy 389.577865 -313.959035) (xy 389.530259 -313.988089) (xy 389.47893 -314.009901) (xy 389.424973 -314.024007)
			(xy 389.369536 -314.030107) (xy 389.313802 -314.02807) (xy 389.258959 -314.01794) (xy 389.206175 -313.999933)
			(xy 389.156575 -313.974432) (xy 389.111217 -313.941981) (xy 389.071068 -313.903272) (xy 389.036982 -313.859129)
			(xy 389.009686 -313.810494) (xy 388.989763 -313.758403) (xy 388.977637 -313.703966) (xy 388.973566 -313.648344)
			(xy 383.408019 -313.648344) (xy 384.080579 -315.174376) (xy 389.994646 -315.174376) (xy 389.998717 -315.118754)
			(xy 390.010843 -315.064317) (xy 390.030766 -315.012226) (xy 390.058062 -314.963591) (xy 390.092148 -314.919448)
			(xy 390.132297 -314.880739) (xy 390.177655 -314.848288) (xy 390.227255 -314.822787) (xy 390.280039 -314.80478)
			(xy 390.334882 -314.79465) (xy 390.390616 -314.792613) (xy 390.446053 -314.798713) (xy 390.50001 -314.812819)
			(xy 390.551339 -314.834631) (xy 390.598945 -314.863685) (xy 390.641813 -314.89936) (xy 390.67903 -314.940897)
			(xy 390.709803 -314.98741) (xy 390.733475 -315.037907) (xy 390.749543 -315.091314) (xy 390.757663 -315.14649)
			(xy 390.758172 -315.174376) (xy 390.757663 -315.202262) (xy 390.757047 -315.206451) (xy 390.99488 -315.206451)
			(xy 390.99488 -315.151949) (xy 391.002636 -315.098001) (xy 391.017991 -315.045707) (xy 391.040632 -314.99613)
			(xy 391.070098 -314.95028) (xy 391.10579 -314.90909) (xy 391.14698 -314.873398) (xy 391.19283 -314.843932)
			(xy 391.242407 -314.821291) (xy 391.294701 -314.805936) (xy 391.348649 -314.79818) (xy 391.3759 -314.797694)
			(xy 391.405482 -314.798249) (xy 391.463936 -314.807382) (xy 391.52028 -314.82543) (xy 391.573162 -314.851959)
			(xy 391.621315 -314.886334) (xy 391.663584 -314.92773) (xy 391.681716 -314.95111) (xy 391.688574 -314.960254)
			(xy 391.708386 -314.970922) (xy 391.809224 -314.976256) (xy 391.830052 -314.96762) (xy 391.837672 -314.959238)
			(xy 391.855812 -314.940252) (xy 391.8964 -314.906935) (xy 391.941171 -314.879494) (xy 391.989279 -314.858447)
			(xy 392.039817 -314.84419) (xy 392.091833 -314.836993) (xy 392.118088 -314.836556) (xy 392.145339 -314.83709)
			(xy 392.199286 -314.844845) (xy 392.25158 -314.860199) (xy 392.301157 -314.882838) (xy 392.347008 -314.912303)
			(xy 392.388198 -314.947994) (xy 392.423889 -314.989183) (xy 392.453356 -315.035032) (xy 392.475997 -315.084608)
			(xy 392.491352 -315.136902) (xy 392.499109 -315.190849) (xy 392.499109 -315.245351) (xy 392.491352 -315.299298)
			(xy 392.475997 -315.351592) (xy 392.453356 -315.401168) (xy 392.423889 -315.447017) (xy 392.388198 -315.488206)
			(xy 392.347008 -315.523897) (xy 392.301157 -315.553362) (xy 392.25158 -315.576001) (xy 392.199286 -315.591355)
			(xy 392.145339 -315.59911) (xy 392.118088 -315.599572) (xy 392.088505 -315.59904) (xy 392.030049 -315.589904)
			(xy 391.973704 -315.571852) (xy 391.920822 -315.545319) (xy 391.87267 -315.510939) (xy 391.830403 -315.469538)
			(xy 391.812272 -315.446156) (xy 391.805414 -315.437012) (xy 391.785602 -315.426344) (xy 391.684764 -315.42101)
			(xy 391.663936 -315.429646) (xy 391.656316 -315.438028) (xy 391.638195 -315.457033) (xy 391.597601 -315.490345)
			(xy 391.552826 -315.517782) (xy 391.504715 -315.538826) (xy 391.454174 -315.553079) (xy 391.402156 -315.560274)
			(xy 391.3759 -315.56071) (xy 391.348649 -315.56022) (xy 391.294701 -315.552464) (xy 391.242407 -315.537109)
			(xy 391.19283 -315.514468) (xy 391.14698 -315.485002) (xy 391.10579 -315.44931) (xy 391.070098 -315.40812)
			(xy 391.040632 -315.36227) (xy 391.017991 -315.312693) (xy 391.002636 -315.260399) (xy 390.99488 -315.206451)
			(xy 390.757047 -315.206451) (xy 390.749543 -315.257438) (xy 390.733475 -315.310845) (xy 390.709803 -315.361342)
			(xy 390.67903 -315.407855) (xy 390.641813 -315.449392) (xy 390.598945 -315.485067) (xy 390.551339 -315.514121)
			(xy 390.50001 -315.535933) (xy 390.446053 -315.550039) (xy 390.390616 -315.556139) (xy 390.334882 -315.554102)
			(xy 390.280039 -315.543972) (xy 390.227255 -315.525965) (xy 390.177655 -315.500464) (xy 390.132297 -315.468013)
			(xy 390.092148 -315.429304) (xy 390.058062 -315.385161) (xy 390.030766 -315.336526) (xy 390.010843 -315.284435)
			(xy 389.998717 -315.229998) (xy 389.994646 -315.174376) (xy 384.080579 -315.174376) (xy 384.567181 -316.278471)
			(xy 390.293092 -316.278471) (xy 390.293092 -316.214549) (xy 390.301103 -316.151131) (xy 390.317 -316.089217)
			(xy 390.340532 -316.029784) (xy 390.371326 -315.973769) (xy 390.408899 -315.922054) (xy 390.452656 -315.875457)
			(xy 390.501909 -315.834712) (xy 390.55588 -315.800461) (xy 390.613719 -315.773244) (xy 390.674512 -315.753491)
			(xy 390.737302 -315.741513) (xy 390.801098 -315.7375) (xy 390.864894 -315.741513) (xy 390.927684 -315.753491)
			(xy 390.988477 -315.773244) (xy 391.046316 -315.800461) (xy 391.100287 -315.834712) (xy 391.14954 -315.875457)
			(xy 391.193297 -315.922054) (xy 391.23087 -315.973769) (xy 391.261664 -316.029784) (xy 391.285196 -316.089217)
			(xy 391.301093 -316.151131) (xy 391.309104 -316.214549) (xy 391.309606 -316.24651) (xy 391.309104 -316.278471)
			(xy 391.301093 -316.341889) (xy 391.285196 -316.403803) (xy 391.261664 -316.463236) (xy 391.23087 -316.519251)
			(xy 391.193297 -316.570966) (xy 391.14954 -316.617563) (xy 391.100287 -316.658308) (xy 391.046316 -316.692559)
			(xy 390.988477 -316.719776) (xy 390.927684 -316.739529) (xy 390.864894 -316.751507) (xy 390.801098 -316.755521)
			(xy 390.737302 -316.751507) (xy 390.674512 -316.739529) (xy 390.613719 -316.719776) (xy 390.55588 -316.692559)
			(xy 390.501909 -316.658308) (xy 390.452656 -316.617563) (xy 390.408899 -316.570966) (xy 390.371326 -316.519251)
			(xy 390.340532 -316.463236) (xy 390.317 -316.403803) (xy 390.301103 -316.341889) (xy 390.293092 -316.278471)
			(xy 384.567181 -316.278471) (xy 384.9046 -317.04407) (xy 391.545318 -317.04407) (xy 391.545797 -317.010881)
			(xy 391.554413 -316.945065) (xy 391.571521 -316.88093) (xy 391.59683 -316.819566) (xy 391.629909 -316.762018)
			(xy 391.670196 -316.709264) (xy 391.717006 -316.662202) (xy 391.769542 -316.621632) (xy 391.826912 -316.588243)
			(xy 391.888138 -316.562605) (xy 391.95218 -316.545152) (xy 391.984992 -316.540134) (xy 391.996168 -316.53861)
			(xy 392.014964 -316.526672) (xy 392.068558 -316.441328) (xy 392.071352 -316.419484) (xy 392.067796 -316.408562)
			(xy 392.056424 -316.370644) (xy 392.044171 -316.292439) (xy 392.043412 -316.25286) (xy 392.043914 -316.220899)
			(xy 392.051925 -316.157481) (xy 392.067822 -316.095567) (xy 392.091354 -316.036134) (xy 392.122148 -315.980119)
			(xy 392.159721 -315.928404) (xy 392.203478 -315.881807) (xy 392.252731 -315.841062) (xy 392.306702 -315.806811)
			(xy 392.364541 -315.779594) (xy 392.425334 -315.759841) (xy 392.488124 -315.747863) (xy 392.55192 -315.74385)
			(xy 392.615716 -315.747863) (xy 392.678506 -315.759841) (xy 392.739299 -315.779594) (xy 392.797138 -315.806811)
			(xy 392.851109 -315.841062) (xy 392.900362 -315.881807) (xy 392.944119 -315.928404) (xy 392.981692 -315.980119)
			(xy 393.012486 -316.036134) (xy 393.036018 -316.095567) (xy 393.051915 -316.157481) (xy 393.059926 -316.220899)
			(xy 393.060428 -316.25286) (xy 393.059845 -316.286046) (xy 393.051238 -316.351856) (xy 393.034141 -316.415987)
			(xy 393.008842 -316.477347) (xy 392.975774 -316.534894) (xy 392.935497 -316.587647) (xy 392.888698 -316.63471)
			(xy 392.836172 -316.675282) (xy 392.778813 -316.708674) (xy 392.717596 -316.734317) (xy 392.653562 -316.751775)
			(xy 392.620754 -316.756796) (xy 392.609578 -316.75832) (xy 392.590782 -316.770258) (xy 392.537188 -316.855602)
			(xy 392.534394 -316.877446) (xy 392.53795 -316.888368) (xy 392.549327 -316.926285) (xy 392.561577 -317.004491)
			(xy 392.562334 -317.04407) (xy 392.561832 -317.076031) (xy 392.553821 -317.139449) (xy 392.537924 -317.201363)
			(xy 392.514392 -317.260796) (xy 392.483598 -317.316811) (xy 392.446025 -317.368526) (xy 392.402268 -317.415123)
			(xy 392.353015 -317.455868) (xy 392.299044 -317.490119) (xy 392.241205 -317.517336) (xy 392.180412 -317.537089)
			(xy 392.117622 -317.549067) (xy 392.053826 -317.553081) (xy 391.99003 -317.549067) (xy 391.92724 -317.537089)
			(xy 391.866447 -317.517336) (xy 391.808608 -317.490119) (xy 391.754637 -317.455868) (xy 391.705384 -317.415123)
			(xy 391.661627 -317.368526) (xy 391.624054 -317.316811) (xy 391.59326 -317.260796) (xy 391.569728 -317.201363)
			(xy 391.553831 -317.139449) (xy 391.54582 -317.076031) (xy 391.545318 -317.04407) (xy 384.9046 -317.04407)
			(xy 385.508759 -318.4149) (xy 391.348676 -318.4149) (xy 391.352691 -318.351099) (xy 391.36467 -318.288305)
			(xy 391.384425 -318.227507) (xy 391.411645 -318.169665) (xy 391.4459 -318.115691) (xy 391.48665 -318.066436)
			(xy 391.533253 -318.022677) (xy 391.584972 -317.985104) (xy 391.640993 -317.95431) (xy 391.700432 -317.93078)
			(xy 391.762351 -317.914886) (xy 391.825775 -317.906879) (xy 391.857738 -317.9064) (xy 391.8886 -317.906806)
			(xy 391.949868 -317.914286) (xy 392.009779 -317.92913) (xy 392.067452 -317.95112) (xy 392.122037 -317.979933)
			(xy 392.172731 -318.015145) (xy 392.218788 -318.056236) (xy 392.2395 -318.07912) (xy 392.245609 -318.085475)
			(xy 392.261079 -318.093909) (xy 392.269726 -318.09563) (xy 392.29919 -318.100456) (xy 392.307865 -318.101459)
			(xy 392.325011 -318.098213) (xy 392.332718 -318.094106) (xy 392.362018 -318.077604) (xy 392.424053 -318.051651)
			(xy 392.488971 -318.034109) (xy 392.555635 -318.025284) (xy 392.589258 -318.024764) (xy 392.62122 -318.025298)
			(xy 392.684641 -318.033305) (xy 392.746559 -318.049199) (xy 392.805996 -318.072727) (xy 392.862015 -318.10352)
			(xy 392.913733 -318.141091) (xy 392.960334 -318.184848) (xy 393.001083 -318.234102) (xy 393.035337 -318.288074)
			(xy 393.062556 -318.345914) (xy 393.082311 -318.406709) (xy 393.094289 -318.469502) (xy 393.098304 -318.5333)
			(xy 393.094289 -318.597098) (xy 393.082311 -318.659891) (xy 393.062556 -318.720686) (xy 393.035337 -318.778526)
			(xy 393.001083 -318.832498) (xy 392.960334 -318.881752) (xy 392.913733 -318.925509) (xy 392.862015 -318.96308)
			(xy 392.805996 -318.993873) (xy 392.746559 -319.017401) (xy 392.684641 -319.033295) (xy 392.62122 -319.041302)
			(xy 392.589258 -319.04178) (xy 392.5584 -319.04128) (xy 392.497136 -319.033814) (xy 392.437228 -319.018983)
			(xy 392.379556 -318.997007) (xy 392.32497 -318.968209) (xy 392.274273 -318.933013) (xy 392.228211 -318.891936)
			(xy 392.207496 -318.86906) (xy 392.201391 -318.8627) (xy 392.185918 -318.854269) (xy 392.17727 -318.85255)
			(xy 392.147806 -318.847724) (xy 392.139131 -318.846722) (xy 392.121985 -318.849968) (xy 392.114278 -318.854074)
			(xy 392.084978 -318.870575) (xy 392.022943 -318.896529) (xy 391.958025 -318.914071) (xy 391.891361 -318.922896)
			(xy 391.857738 -318.923416) (xy 391.825775 -318.922921) (xy 391.762351 -318.914914) (xy 391.700432 -318.89902)
			(xy 391.640993 -318.87549) (xy 391.584972 -318.844696) (xy 391.533253 -318.807123) (xy 391.48665 -318.763364)
			(xy 391.4459 -318.714109) (xy 391.411645 -318.660135) (xy 391.384425 -318.602293) (xy 391.36467 -318.541495)
			(xy 391.352691 -318.478701) (xy 391.348676 -318.4149) (xy 385.508759 -318.4149) (xy 386.03602 -319.611248)
			(xy 391.662412 -319.611248) (xy 391.662883 -319.580516) (xy 391.670286 -319.5195) (xy 391.684991 -319.459821)
			(xy 391.706783 -319.40235) (xy 391.735343 -319.347925) (xy 391.770257 -319.29734) (xy 391.811013 -319.251333)
			(xy 391.857018 -319.210574) (xy 391.907602 -319.175658) (xy 391.962025 -319.147094) (xy 392.019495 -319.125299)
			(xy 392.079172 -319.110591) (xy 392.140188 -319.103184) (xy 392.17092 -319.10274) (xy 392.201363 -319.103172)
			(xy 392.261813 -319.110438) (xy 392.320962 -319.124874) (xy 392.377962 -319.146275) (xy 392.431997 -319.174334)
			(xy 392.482292 -319.208648) (xy 392.528127 -319.248726) (xy 392.568844 -319.293993) (xy 392.586718 -319.31864)
			(xy 392.59256 -319.327022) (xy 392.609832 -319.33769) (xy 392.701526 -319.35293) (xy 392.721084 -319.348358)
			(xy 392.729466 -319.342262) (xy 392.75404 -319.325065) (xy 392.807478 -319.297832) (xy 392.86452 -319.279298)
			(xy 392.923759 -319.269918) (xy 392.953748 -319.269364) (xy 392.980999 -319.269833) (xy 393.034946 -319.277595)
			(xy 393.087239 -319.292955) (xy 393.136815 -319.3156) (xy 393.182664 -319.345069) (xy 393.223853 -319.380762)
			(xy 393.259543 -319.421952) (xy 393.28901 -319.467803) (xy 393.311652 -319.517379) (xy 393.327009 -319.569674)
			(xy 393.334768 -319.623621) (xy 393.335256 -319.650872) (xy 393.334771 -319.678511) (xy 393.326811 -319.733211)
			(xy 393.311039 -319.78619) (xy 393.287785 -319.836338) (xy 393.257537 -319.882604) (xy 393.220927 -319.924019)
			(xy 393.178723 -319.959717) (xy 393.131808 -319.988949) (xy 393.081165 -320.011103) (xy 393.027854 -320.025716)
			(xy 393.000484 -320.029586) (xy 392.990324 -320.030856) (xy 392.972798 -320.040762) (xy 392.916156 -320.113406)
			(xy 392.910822 -320.132964) (xy 392.912092 -320.14287) (xy 392.9139 -320.158619) (xy 392.915808 -320.190264)
			(xy 392.915902 -320.206116) (xy 392.9154 -320.238077) (xy 392.907389 -320.301495) (xy 392.891492 -320.363409)
			(xy 392.86796 -320.422842) (xy 392.837166 -320.478857) (xy 392.799593 -320.530572) (xy 392.755836 -320.577169)
			(xy 392.706583 -320.617914) (xy 392.652612 -320.652165) (xy 392.594773 -320.679382) (xy 392.53398 -320.699135)
			(xy 392.47119 -320.711113) (xy 392.407394 -320.715127) (xy 392.343598 -320.711113) (xy 392.280808 -320.699135)
			(xy 392.220015 -320.679382) (xy 392.162176 -320.652165) (xy 392.108205 -320.617914) (xy 392.058952 -320.577169)
			(xy 392.015195 -320.530572) (xy 391.977622 -320.478857) (xy 391.946828 -320.422842) (xy 391.923296 -320.363409)
			(xy 391.907399 -320.301495) (xy 391.899388 -320.238077) (xy 391.898886 -320.206116) (xy 391.899295 -320.176765)
			(xy 391.90604 -320.118452) (xy 391.912348 -320.089784) (xy 391.914248 -320.079586) (xy 391.910697 -320.059172)
			(xy 391.899372 -320.041821) (xy 391.891012 -320.035682) (xy 391.865055 -320.018004) (xy 391.817273 -319.977244)
			(xy 391.774877 -319.93091) (xy 391.738511 -319.879706) (xy 391.708729 -319.824413) (xy 391.685984 -319.765872)
			(xy 391.670624 -319.704975) (xy 391.662882 -319.64265) (xy 391.662412 -319.611248) (xy 386.03602 -319.611248)
			(xy 386.727387 -321.179952) (xy 394.285976 -321.179952) (xy 394.290047 -321.12433) (xy 394.302173 -321.069893)
			(xy 394.322096 -321.017802) (xy 394.349392 -320.969167) (xy 394.383478 -320.925024) (xy 394.423627 -320.886315)
			(xy 394.468985 -320.853864) (xy 394.518585 -320.828363) (xy 394.571369 -320.810356) (xy 394.626212 -320.800226)
			(xy 394.681946 -320.798189) (xy 394.737383 -320.804289) (xy 394.79134 -320.818395) (xy 394.842669 -320.840207)
			(xy 394.890275 -320.869261) (xy 394.933143 -320.904936) (xy 394.97036 -320.946473) (xy 395.001133 -320.992986)
			(xy 395.024805 -321.043483) (xy 395.040873 -321.09689) (xy 395.048993 -321.152066) (xy 395.049502 -321.179952)
			(xy 395.048993 -321.207838) (xy 395.040873 -321.263014) (xy 395.024805 -321.316421) (xy 395.001133 -321.366918)
			(xy 394.97036 -321.413431) (xy 394.933143 -321.454968) (xy 394.890275 -321.490643) (xy 394.842669 -321.519697)
			(xy 394.79134 -321.541509) (xy 394.737383 -321.555615) (xy 394.681946 -321.561715) (xy 394.626212 -321.559678)
			(xy 394.571369 -321.549548) (xy 394.518585 -321.531541) (xy 394.468985 -321.50604) (xy 394.423627 -321.473589)
			(xy 394.383478 -321.43488) (xy 394.349392 -321.390737) (xy 394.322096 -321.342102) (xy 394.302173 -321.290011)
			(xy 394.290047 -321.235574) (xy 394.285976 -321.179952) (xy 386.727387 -321.179952) (xy 387.309518 -322.5008)
			(xy 394.382741 -322.5008) (xy 394.386755 -322.437001) (xy 394.398733 -322.374207) (xy 394.418486 -322.31341)
			(xy 394.445703 -322.255568) (xy 394.479955 -322.201593) (xy 394.520701 -322.152336) (xy 394.5673 -322.108575)
			(xy 394.619015 -322.070998) (xy 394.675032 -322.040199) (xy 394.734468 -322.016664) (xy 394.796384 -322.000763)
			(xy 394.859805 -321.992747) (xy 394.891768 -321.992244) (xy 394.92281 -321.992722) (xy 394.984433 -322.000281)
			(xy 395.044676 -322.01529) (xy 395.102643 -322.037525) (xy 395.130274 -322.05168) (xy 395.138195 -322.055535)
			(xy 395.155628 -322.058003) (xy 395.16431 -322.056506) (xy 395.19352 -322.05041) (xy 395.20209 -322.04824)
			(xy 395.217162 -322.039028) (xy 395.222984 -322.032376) (xy 395.243742 -322.0073) (xy 395.290571 -321.962081)
			(xy 395.342788 -321.923209) (xy 395.399539 -321.89132) (xy 395.459897 -321.866934) (xy 395.522873 -321.850451)
			(xy 395.587437 -321.842141) (xy 395.619986 -321.841622) (xy 395.651951 -321.842042) (xy 395.715376 -321.850053)
			(xy 395.777298 -321.86595) (xy 395.836739 -321.889483) (xy 395.892761 -321.92028) (xy 395.944482 -321.957856)
			(xy 395.991085 -322.001619) (xy 396.031836 -322.050877) (xy 396.066092 -322.104854) (xy 396.093312 -322.162699)
			(xy 396.113068 -322.223499) (xy 396.125047 -322.286297) (xy 396.129062 -322.3501) (xy 396.125047 -322.413903)
			(xy 396.113068 -322.476701) (xy 396.093312 -322.537501) (xy 396.070106 -322.586815) (xy 396.221452 -322.586815)
			(xy 396.221452 -322.522893) (xy 396.229463 -322.459475) (xy 396.24536 -322.397561) (xy 396.268892 -322.338128)
			(xy 396.299686 -322.282113) (xy 396.337259 -322.230398) (xy 396.381016 -322.183801) (xy 396.430269 -322.143056)
			(xy 396.48424 -322.108805) (xy 396.542079 -322.081588) (xy 396.602872 -322.061835) (xy 396.665662 -322.049857)
			(xy 396.729458 -322.045844) (xy 396.793254 -322.049857) (xy 396.856044 -322.061835) (xy 396.916837 -322.081588)
			(xy 396.974676 -322.108805) (xy 397.028647 -322.143056) (xy 397.0779 -322.183801) (xy 397.121657 -322.230398)
			(xy 397.15923 -322.282113) (xy 397.190024 -322.338128) (xy 397.213556 -322.397561) (xy 397.229453 -322.459475)
			(xy 397.237464 -322.522893) (xy 397.237966 -322.554854) (xy 397.237464 -322.586815) (xy 397.229453 -322.650233)
			(xy 397.213556 -322.712147) (xy 397.190024 -322.77158) (xy 397.15923 -322.827595) (xy 397.121657 -322.87931)
			(xy 397.0779 -322.925907) (xy 397.028647 -322.966652) (xy 397.022812 -322.970355) (xy 397.697192 -322.970355)
			(xy 397.697192 -322.906433) (xy 397.705203 -322.843015) (xy 397.7211 -322.781101) (xy 397.744632 -322.721668)
			(xy 397.775426 -322.665653) (xy 397.812999 -322.613938) (xy 397.856756 -322.567341) (xy 397.906009 -322.526596)
			(xy 397.95998 -322.492345) (xy 398.017819 -322.465128) (xy 398.078612 -322.445375) (xy 398.141402 -322.433397)
			(xy 398.205198 -322.429384) (xy 398.268994 -322.433397) (xy 398.331784 -322.445375) (xy 398.392577 -322.465128)
			(xy 398.450416 -322.492345) (xy 398.504387 -322.526596) (xy 398.55364 -322.567341) (xy 398.597397 -322.613938)
			(xy 398.63497 -322.665653) (xy 398.665764 -322.721668) (xy 398.689296 -322.781101) (xy 398.69877 -322.818)
			(xy 400.068587 -322.818) (xy 400.072601 -322.754207) (xy 400.084577 -322.69142) (xy 400.104328 -322.630629)
			(xy 400.131542 -322.572793) (xy 400.16579 -322.518824) (xy 400.206532 -322.469572) (xy 400.253125 -322.425814)
			(xy 400.304835 -322.388241) (xy 400.360846 -322.357445) (xy 400.420274 -322.333911) (xy 400.482184 -322.31801)
			(xy 400.545599 -322.309994) (xy 400.577558 -322.30949) (xy 400.607225 -322.309885) (xy 400.666157 -322.316787)
			(xy 400.723884 -322.330501) (xy 400.779623 -322.350842) (xy 400.832615 -322.377532) (xy 400.88214 -322.410209)
			(xy 400.927525 -322.448429) (xy 400.948144 -322.469764) (xy 400.955256 -322.477384) (xy 400.97456 -322.485766)
			(xy 401.069556 -322.485766) (xy 401.08886 -322.477384) (xy 401.095972 -322.469764) (xy 401.116606 -322.448446)
			(xy 401.161993 -322.410234) (xy 401.211518 -322.377563) (xy 401.264508 -322.350876) (xy 401.320243 -322.330536)
			(xy 401.377966 -322.316818) (xy 401.436893 -322.30991) (xy 401.466558 -322.30949) (xy 401.498939 -322.309993)
			(xy 401.563177 -322.318216) (xy 401.62585 -322.334532) (xy 401.685943 -322.358679) (xy 401.74248 -322.390264)
			(xy 401.794548 -322.428776) (xy 401.8413 -322.47359) (xy 401.862036 -322.498466) (xy 401.86864 -322.506594)
			(xy 401.887182 -322.516246) (xy 401.982178 -322.523358) (xy 402.00199 -322.5165) (xy 402.00961 -322.509388)
			(xy 402.033129 -322.488499) (xy 402.084399 -322.452051) (xy 402.139772 -322.422202) (xy 402.198402 -322.399407)
			(xy 402.259394 -322.384013) (xy 402.321819 -322.376255) (xy 402.353272 -322.375784) (xy 402.384511 -322.3763)
			(xy 402.446515 -322.383972) (xy 402.507113 -322.399181) (xy 402.565392 -322.421697) (xy 402.620475 -322.451181)
			(xy 402.671532 -322.48719) (xy 402.717794 -322.52918) (xy 402.758566 -322.57652) (xy 402.793233 -322.628498)
			(xy 402.807678 -322.6562) (xy 402.811996 -322.664582) (xy 402.825204 -322.676774) (xy 402.904706 -322.709032)
			(xy 402.92274 -322.70954) (xy 402.93163 -322.706492) (xy 402.951648 -322.699892) (xy 402.992761 -322.690598)
			(xy 403.013672 -322.68795) (xy 403.02561 -322.68668) (xy 403.04593 -322.673472) (xy 403.099016 -322.582286)
			(xy 403.10054 -322.558156) (xy 403.095714 -322.54698) (xy 403.082776 -322.51526) (xy 403.064572 -322.449219)
			(xy 403.055382 -322.381334) (xy 403.05482 -322.347082) (xy 403.055322 -322.315121) (xy 403.063333 -322.251703)
			(xy 403.07923 -322.189789) (xy 403.102762 -322.130356) (xy 403.133556 -322.074341) (xy 403.171129 -322.022626)
			(xy 403.214886 -321.976029) (xy 403.264139 -321.935284) (xy 403.31811 -321.901033) (xy 403.375949 -321.873816)
			(xy 403.436742 -321.854063) (xy 403.499532 -321.842085) (xy 403.563328 -321.838072) (xy 403.627124 -321.842085)
			(xy 403.689914 -321.854063) (xy 403.750707 -321.873816) (xy 403.808546 -321.901033) (xy 403.862517 -321.935284)
			(xy 403.91177 -321.976029) (xy 403.955527 -322.022626) (xy 403.9931 -322.074341) (xy 404.023894 -322.130356)
			(xy 404.047426 -322.189789) (xy 404.063323 -322.251703) (xy 404.071334 -322.315121) (xy 404.071836 -322.347082)
			(xy 404.071836 -322.351908) (xy 404.072148 -322.36114) (xy 404.078534 -322.378458) (xy 404.084282 -322.38569)
			(xy 404.104348 -322.408804) (xy 404.110706 -322.415512) (xy 404.126993 -322.424225) (xy 404.136098 -322.425822)
			(xy 404.169096 -322.430673) (xy 404.233526 -322.447911) (xy 404.29515 -322.473422) (xy 404.352911 -322.50677)
			(xy 404.379684 -322.52666) (xy 404.388401 -322.532687) (xy 404.408969 -322.537689) (xy 404.429801 -322.533928)
			(xy 404.438866 -322.528438) (xy 404.464133 -322.512009) (xy 404.517765 -322.484513) (xy 404.57427 -322.463545)
			(xy 404.632856 -322.449399) (xy 404.692703 -322.442272) (xy 404.722838 -322.441824) (xy 404.757535 -322.442401)
			(xy 404.826282 -322.451853) (xy 404.893106 -322.470563) (xy 404.956766 -322.498182) (xy 405.016081 -322.5342)
			(xy 405.043386 -322.555616) (xy 405.050277 -322.560819) (xy 405.06651 -322.566665) (xy 405.075136 -322.567046)
			(xy 405.104854 -322.567046) (xy 405.113436 -322.566759) (xy 405.129665 -322.561182) (xy 405.136604 -322.556124)
			(xy 405.163717 -322.535256) (xy 405.222463 -322.500189) (xy 405.285382 -322.473316) (xy 405.351336 -322.455124)
			(xy 405.419134 -322.445941) (xy 405.453342 -322.44538) (xy 405.487001 -322.44592) (xy 405.553728 -322.454829)
			(xy 405.618693 -322.472473) (xy 405.649938 -322.485004) (xy 405.660573 -322.488702) (xy 405.68303 -322.487631)
			(xy 405.702906 -322.477122) (xy 405.710136 -322.468494) (xy 405.715216 -322.46189) (xy 405.721148 -322.453671)
			(xy 405.726517 -322.434142) (xy 405.72563 -322.424044) (xy 405.721566 -322.393056) (xy 405.719925 -322.383051)
			(xy 405.709812 -322.365495) (xy 405.702008 -322.35902) (xy 405.675808 -322.338333) (xy 405.628504 -322.291231)
			(xy 405.587772 -322.238343) (xy 405.554311 -322.180579) (xy 405.528699 -322.118933) (xy 405.511375 -322.054465)
			(xy 405.502637 -321.988284) (xy 405.50211 -321.954906) (xy 405.502612 -321.922945) (xy 405.510623 -321.859527)
			(xy 405.52652 -321.797613) (xy 405.550052 -321.73818) (xy 405.580846 -321.682165) (xy 405.618419 -321.63045)
			(xy 405.662176 -321.583853) (xy 405.711429 -321.543108) (xy 405.7654 -321.508857) (xy 405.823239 -321.48164)
			(xy 405.884032 -321.461887) (xy 405.946822 -321.449909) (xy 406.010618 -321.445896) (xy 406.074414 -321.449909)
			(xy 406.137204 -321.461887) (xy 406.197997 -321.48164) (xy 406.255836 -321.508857) (xy 406.309807 -321.543108)
			(xy 406.35906 -321.583853) (xy 406.402817 -321.63045) (xy 406.44039 -321.682165) (xy 406.471184 -321.73818)
			(xy 406.494716 -321.797613) (xy 406.510613 -321.859527) (xy 406.518624 -321.922945) (xy 406.519126 -321.954906)
			(xy 406.518627 -321.986247) (xy 406.510926 -322.048453) (xy 406.495643 -322.109242) (xy 406.473007 -322.167694)
			(xy 406.443363 -322.222922) (xy 406.425654 -322.248784) (xy 406.420066 -322.256658) (xy 406.415494 -322.274946)
			(xy 406.426924 -322.362322) (xy 406.435814 -322.378832) (xy 406.44318 -322.385182) (xy 406.465954 -322.404863)
			(xy 406.507201 -322.448702) (xy 406.542981 -322.497108) (xy 406.572791 -322.549401) (xy 406.584912 -322.576952)
			(xy 406.590754 -322.590668) (xy 406.614884 -322.607432) (xy 406.737058 -322.611496) (xy 406.762458 -322.59651)
			(xy 406.769316 -322.583048) (xy 406.786954 -322.549011) (xy 406.828028 -322.484278) (xy 406.875392 -322.423994)
			(xy 406.928566 -322.368767) (xy 406.987014 -322.319155) (xy 407.050145 -322.27566) (xy 407.117323 -322.23872)
			(xy 407.187869 -322.208707) (xy 407.261071 -322.185926) (xy 407.336189 -322.170607) (xy 407.412466 -322.162903)
			(xy 407.450798 -322.162424) (xy 407.489862 -322.162941) (xy 407.567581 -322.170918) (xy 407.644077 -322.1868)
			(xy 407.718548 -322.210419) (xy 407.790214 -322.241528) (xy 407.858325 -322.279802) (xy 407.922165 -322.324839)
			(xy 407.95194 -322.35013) (xy 407.958904 -322.355649) (xy 407.975445 -322.362088) (xy 407.99319 -322.362504)
			(xy 408.001724 -322.360036) (xy 408.041142 -322.347293) (xy 408.122039 -322.329432) (xy 408.204395 -322.320449)
			(xy 408.245818 -322.319904) (xy 408.284463 -322.32037) (xy 408.361357 -322.328191) (xy 408.437065 -322.343751)
			(xy 408.51081 -322.366891) (xy 408.581837 -322.397372) (xy 408.649415 -322.434882) (xy 408.712851 -322.479037)
			(xy 408.771495 -322.529382) (xy 408.824745 -322.585402) (xy 408.872055 -322.646522) (xy 408.912938 -322.712115)
			(xy 408.946976 -322.781507) (xy 408.973819 -322.853986) (xy 408.993192 -322.928809) (xy 409.004895 -323.005209)
			(xy 409.00881 -323.0824) (xy 409.004895 -323.159591) (xy 408.993192 -323.235991) (xy 408.973819 -323.310814)
			(xy 408.946976 -323.383293) (xy 408.912938 -323.452685) (xy 408.872055 -323.518278) (xy 408.824745 -323.579398)
			(xy 408.771495 -323.635418) (xy 408.712851 -323.685763) (xy 408.649415 -323.729918) (xy 408.581837 -323.767428)
			(xy 408.51081 -323.797909) (xy 408.437065 -323.821049) (xy 408.361357 -323.836609) (xy 408.284463 -323.84443)
			(xy 408.245818 -323.84492) (xy 408.206754 -323.844407) (xy 408.129035 -323.83643) (xy 408.052538 -323.820549)
			(xy 407.978066 -323.79693) (xy 407.9064 -323.765819) (xy 407.83829 -323.727544) (xy 407.774451 -323.682506)
			(xy 407.744676 -323.657214) (xy 407.737757 -323.651634) (xy 407.721191 -323.645217) (xy 407.70343 -323.644827)
			(xy 407.694892 -323.647308) (xy 407.655474 -323.660048) (xy 407.574577 -323.67791) (xy 407.492221 -323.686894)
			(xy 407.450798 -323.68744) (xy 407.411769 -323.686989) (xy 407.334117 -323.679033) (xy 407.257684 -323.663183)
			(xy 407.183272 -323.639606) (xy 407.111658 -323.608548) (xy 407.043593 -323.570335) (xy 406.979789 -323.525366)
			(xy 406.920914 -323.474113) (xy 406.867585 -323.417112) (xy 406.82036 -323.35496) (xy 406.779733 -323.288308)
			(xy 406.746129 -323.217853) (xy 406.719902 -323.144332) (xy 406.710134 -323.106542) (xy 406.706578 -323.092064)
			(xy 406.685242 -323.071744) (xy 406.565354 -323.048376) (xy 406.537922 -323.059298) (xy 406.529032 -323.07149)
			(xy 406.51107 -323.095661) (xy 406.470388 -323.140062) (xy 406.424744 -323.179346) (xy 406.374778 -323.21296)
			(xy 406.32119 -323.240434) (xy 406.264731 -323.261383) (xy 406.206191 -323.275514) (xy 406.146392 -323.282628)
			(xy 406.116282 -323.283072) (xy 406.082623 -323.282528) (xy 406.015896 -323.273621) (xy 405.950931 -323.255978)
			(xy 405.919686 -323.243448) (xy 405.909076 -323.23966) (xy 405.886594 -323.240759) (xy 405.866712 -323.251309)
			(xy 405.859488 -323.259958) (xy 405.838816 -323.286468) (xy 405.791634 -323.334354) (xy 405.738554 -323.375604)
			(xy 405.6805 -323.409501) (xy 405.618487 -323.435453) (xy 405.553594 -323.453007) (xy 405.486954 -323.461858)
			(xy 405.453342 -323.462396) (xy 405.418645 -323.461826) (xy 405.349898 -323.452372) (xy 405.283074 -323.43366)
			(xy 405.219414 -323.406039) (xy 405.160099 -323.37002) (xy 405.132794 -323.348604) (xy 405.125907 -323.343395)
			(xy 405.109671 -323.337552) (xy 405.101044 -323.337174) (xy 405.071326 -323.337174) (xy 405.062745 -323.337467)
			(xy 405.046517 -323.343042) (xy 405.039576 -323.348096) (xy 405.012462 -323.368961) (xy 404.953717 -323.404032)
			(xy 404.890799 -323.430906) (xy 404.824845 -323.449099) (xy 404.757047 -323.45828) (xy 404.722838 -323.45884)
			(xy 404.689534 -323.458306) (xy 404.623498 -323.449604) (xy 404.559162 -323.432357) (xy 404.497628 -323.406859)
			(xy 404.439948 -323.373548) (xy 404.413212 -323.353684) (xy 404.404496 -323.347657) (xy 404.383927 -323.342662)
			(xy 404.363097 -323.34642) (xy 404.35403 -323.351906) (xy 404.328768 -323.368342) (xy 404.275133 -323.395835)
			(xy 404.218627 -323.416801) (xy 404.160041 -323.430946) (xy 404.100193 -323.438072) (xy 404.070058 -323.43852)
			(xy 404.039327 -323.438084) (xy 403.978312 -323.430671) (xy 403.918636 -323.415958) (xy 403.861169 -323.394159)
			(xy 403.806747 -323.365593) (xy 403.756166 -323.330676) (xy 403.710161 -323.289917) (xy 403.669405 -323.243911)
			(xy 403.634491 -323.193327) (xy 403.605928 -323.138904) (xy 403.584133 -323.081435) (xy 403.569424 -323.021758)
			(xy 403.562014 -322.960743) (xy 403.56155 -322.930012) (xy 403.56155 -322.925186) (xy 403.561244 -322.915953)
			(xy 403.554854 -322.898635) (xy 403.549104 -322.891404) (xy 403.529038 -322.86829) (xy 403.522685 -322.861576)
			(xy 403.506394 -322.852866) (xy 403.497288 -322.851272) (xy 403.490684 -322.85051) (xy 403.481992 -322.849674)
			(xy 403.464906 -322.853208) (xy 403.449989 -322.86226) (xy 403.444202 -322.868798) (xy 403.424644 -322.892674)
			(xy 403.419479 -322.899603) (xy 403.413756 -322.915902) (xy 403.413735 -322.933176) (xy 403.416262 -322.941442)
			(xy 403.426221 -322.971916) (xy 403.436944 -323.035119) (xy 403.437598 -323.067172) (xy 403.437119 -323.094425)
			(xy 403.429365 -323.148375) (xy 403.414012 -323.200674) (xy 403.391372 -323.250254) (xy 403.361906 -323.296108)
			(xy 403.326214 -323.337301) (xy 403.285023 -323.372995) (xy 403.23917 -323.402464) (xy 403.189591 -323.425106)
			(xy 403.137293 -323.440461) (xy 403.083343 -323.448217) (xy 403.05609 -323.44868) (xy 403.029324 -323.448243)
			(xy 402.976317 -323.44077) (xy 402.924875 -323.425958) (xy 402.87601 -323.404098) (xy 402.830682 -323.37562)
			(xy 402.789782 -323.341083) (xy 402.77161 -323.321426) (xy 402.76526 -323.314314) (xy 402.749258 -323.305932)
			(xy 402.664168 -323.295518) (xy 402.646642 -323.299836) (xy 402.638768 -323.30517) (xy 402.613428 -323.321824)
			(xy 402.559539 -323.349629) (xy 402.502728 -323.370837) (xy 402.443801 -323.385148) (xy 402.383592 -323.392359)
			(xy 402.353272 -323.3928) (xy 402.320891 -323.392279) (xy 402.256654 -323.38406) (xy 402.193981 -323.367747)
			(xy 402.133889 -323.343604) (xy 402.077351 -323.312021) (xy 402.025283 -323.273512) (xy 401.97853 -323.228699)
			(xy 401.957794 -323.203824) (xy 401.95119 -323.195696) (xy 401.932648 -323.186044) (xy 401.837652 -323.178932)
			(xy 401.81784 -323.18579) (xy 401.81022 -323.192902) (xy 401.786687 -323.213775) (xy 401.73542 -323.250225)
			(xy 401.680051 -323.280076) (xy 401.621423 -323.302875) (xy 401.560433 -323.318272) (xy 401.49801 -323.326033)
			(xy 401.466558 -323.326506) (xy 401.436891 -323.326101) (xy 401.37796 -323.319201) (xy 401.320233 -323.305488)
			(xy 401.264494 -323.285149) (xy 401.211502 -323.258461) (xy 401.161976 -323.225785) (xy 401.116591 -323.187566)
			(xy 401.095972 -323.166232) (xy 401.08886 -323.158612) (xy 401.069556 -323.15023) (xy 400.97456 -323.15023)
			(xy 400.955256 -323.158612) (xy 400.948144 -323.166232) (xy 400.927501 -323.187541) (xy 400.882116 -323.225754)
			(xy 400.832593 -323.258426) (xy 400.779604 -323.285114) (xy 400.723871 -323.305456) (xy 400.666149 -323.319175)
			(xy 400.607223 -323.326085) (xy 400.577558 -323.326506) (xy 400.545599 -323.326006) (xy 400.482184 -323.31799)
			(xy 400.420274 -323.302089) (xy 400.360846 -323.278555) (xy 400.304835 -323.247759) (xy 400.253125 -323.210186)
			(xy 400.206532 -323.166428) (xy 400.16579 -323.117176) (xy 400.131542 -323.063207) (xy 400.104328 -323.005371)
			(xy 400.084577 -322.94458) (xy 400.072601 -322.881793) (xy 400.068587 -322.818) (xy 398.69877 -322.818)
			(xy 398.705193 -322.843015) (xy 398.713204 -322.906433) (xy 398.713706 -322.938394) (xy 398.713204 -322.970355)
			(xy 398.705193 -323.033773) (xy 398.689296 -323.095687) (xy 398.665764 -323.15512) (xy 398.63497 -323.211135)
			(xy 398.597397 -323.26285) (xy 398.55364 -323.309447) (xy 398.504387 -323.350192) (xy 398.450416 -323.384443)
			(xy 398.392577 -323.41166) (xy 398.331784 -323.431413) (xy 398.268994 -323.443391) (xy 398.205198 -323.447405)
			(xy 398.141402 -323.443391) (xy 398.078612 -323.431413) (xy 398.017819 -323.41166) (xy 397.95998 -323.384443)
			(xy 397.906009 -323.350192) (xy 397.856756 -323.309447) (xy 397.812999 -323.26285) (xy 397.775426 -323.211135)
			(xy 397.744632 -323.15512) (xy 397.7211 -323.095687) (xy 397.705203 -323.033773) (xy 397.697192 -322.970355)
			(xy 397.022812 -322.970355) (xy 396.974676 -323.000903) (xy 396.916837 -323.02812) (xy 396.856044 -323.047873)
			(xy 396.793254 -323.059851) (xy 396.729458 -323.063865) (xy 396.665662 -323.059851) (xy 396.602872 -323.047873)
			(xy 396.542079 -323.02812) (xy 396.48424 -323.000903) (xy 396.430269 -322.966652) (xy 396.381016 -322.925907)
			(xy 396.337259 -322.87931) (xy 396.299686 -322.827595) (xy 396.268892 -322.77158) (xy 396.24536 -322.712147)
			(xy 396.229463 -322.650233) (xy 396.221452 -322.586815) (xy 396.070106 -322.586815) (xy 396.066092 -322.595346)
			(xy 396.031836 -322.649323) (xy 395.991085 -322.698581) (xy 395.944482 -322.742344) (xy 395.892761 -322.77992)
			(xy 395.836739 -322.810717) (xy 395.777298 -322.83425) (xy 395.715376 -322.850147) (xy 395.651951 -322.858158)
			(xy 395.619986 -322.858638) (xy 395.588943 -322.858181) (xy 395.527319 -322.850616) (xy 395.467076 -322.835601)
			(xy 395.409111 -322.81336) (xy 395.38148 -322.799202) (xy 395.373548 -322.795372) (xy 395.356124 -322.792889)
			(xy 395.347444 -322.794376) (xy 395.318234 -322.800472) (xy 395.309659 -322.802628) (xy 395.29459 -322.81185)
			(xy 395.28877 -322.818506) (xy 395.268034 -322.843601) (xy 395.221202 -322.888819) (xy 395.168981 -322.92769)
			(xy 395.112226 -322.959577) (xy 395.051865 -322.98396) (xy 394.988885 -323.000439) (xy 394.924318 -323.008744)
			(xy 394.891768 -323.00926) (xy 394.859805 -323.008853) (xy 394.796384 -323.000837) (xy 394.734468 -322.984936)
			(xy 394.675032 -322.961401) (xy 394.619015 -322.930602) (xy 394.5673 -322.893025) (xy 394.520701 -322.849264)
			(xy 394.479955 -322.800007) (xy 394.445703 -322.746032) (xy 394.418486 -322.68819) (xy 394.398733 -322.627393)
			(xy 394.386755 -322.564599) (xy 394.382741 -322.5008) (xy 387.309518 -322.5008) (xy 387.967728 -323.994272)
			(xy 387.968744 -323.996812) (xy 388.274501 -324.8058) (xy 394.302791 -324.8058) (xy 394.306805 -324.742008)
			(xy 394.318781 -324.679221) (xy 394.338532 -324.618431) (xy 394.365746 -324.560595) (xy 394.399994 -324.506626)
			(xy 394.440735 -324.457374) (xy 394.487328 -324.413617) (xy 394.539037 -324.376044) (xy 394.595047 -324.345248)
			(xy 394.654476 -324.321715) (xy 394.716385 -324.305814) (xy 394.779799 -324.297798) (xy 394.811758 -324.297294)
			(xy 394.843961 -324.297763) (xy 394.907855 -324.30588) (xy 394.970211 -324.322) (xy 395.030032 -324.345867)
			(xy 395.08636 -324.377098) (xy 395.138293 -324.415193) (xy 395.184998 -324.459542) (xy 395.225729 -324.509434)
			(xy 395.259832 -324.564071) (xy 395.286762 -324.622577) (xy 395.296898 -324.653148) (xy 395.299946 -324.663308)
			(xy 395.313408 -324.678802) (xy 395.398752 -324.720458) (xy 395.419326 -324.721474) (xy 395.429232 -324.717664)
			(xy 395.457832 -324.707433) (xy 395.516856 -324.693081) (xy 395.577168 -324.685849) (xy 395.60754 -324.685406)
			(xy 395.634722 -324.685758) (xy 395.688777 -324.691557) (xy 395.741905 -324.703085) (xy 395.767814 -324.711314)
			(xy 395.776958 -324.714362) (xy 395.795246 -324.7136) (xy 395.875256 -324.678548) (xy 395.88821 -324.665594)
			(xy 395.892274 -324.656958) (xy 395.906101 -324.627702) (xy 395.940086 -324.572635) (xy 395.980783 -324.522325)
			(xy 396.027535 -324.477586) (xy 396.079586 -324.439142) (xy 396.136095 -324.407613) (xy 396.196148 -324.38351)
			(xy 396.258774 -324.367222) (xy 396.322961 -324.359013) (xy 396.355316 -324.358508) (xy 396.387277 -324.358979)
			(xy 396.450696 -324.366992) (xy 396.51261 -324.382891) (xy 396.572043 -324.406424) (xy 396.628059 -324.43722)
			(xy 396.679773 -324.474794) (xy 396.72637 -324.518553) (xy 396.739976 -324.535) (xy 412.55037 -324.535)
			(xy 412.554361 -324.446137) (xy 412.566301 -324.357989) (xy 412.586096 -324.271267) (xy 412.613584 -324.186668)
			(xy 412.648545 -324.104873) (xy 412.690697 -324.026542) (xy 412.739701 -323.952305) (xy 412.795163 -323.882759)
			(xy 412.856636 -323.818465) (xy 412.923624 -323.759941) (xy 412.995589 -323.707656) (xy 413.071951 -323.662033)
			(xy 413.152095 -323.623439) (xy 413.235376 -323.592185) (xy 413.321123 -323.568521) (xy 413.408647 -323.55264)
			(xy 413.497242 -323.544667) (xy 413.541718 -323.544184) (xy 415.294318 -323.544184) (xy 415.338796 -323.544608)
			(xy 415.427394 -323.552583) (xy 415.51492 -323.568468) (xy 415.600671 -323.592135) (xy 415.683954 -323.623393)
			(xy 415.7641 -323.661991) (xy 415.840464 -323.707617) (xy 415.912431 -323.759905) (xy 415.97942 -323.818434)
			(xy 416.040894 -323.882731) (xy 416.096357 -323.952281) (xy 416.145362 -324.026521) (xy 416.187515 -324.104856)
			(xy 416.220786 -324.182697) (xy 417.363396 -324.182697) (xy 417.363396 -324.118775) (xy 417.371407 -324.055357)
			(xy 417.387304 -323.993443) (xy 417.410836 -323.93401) (xy 417.44163 -323.877995) (xy 417.479203 -323.82628)
			(xy 417.52296 -323.779683) (xy 417.572213 -323.738938) (xy 417.626184 -323.704687) (xy 417.684023 -323.67747)
			(xy 417.744816 -323.657717) (xy 417.807606 -323.645739) (xy 417.871402 -323.641726) (xy 417.935198 -323.645739)
			(xy 417.997988 -323.657717) (xy 418.058781 -323.67747) (xy 418.11662 -323.704687) (xy 418.170591 -323.738938)
			(xy 418.219844 -323.779683) (xy 418.263601 -323.82628) (xy 418.301174 -323.877995) (xy 418.331968 -323.93401)
			(xy 418.3555 -323.993443) (xy 418.371397 -324.055357) (xy 418.379408 -324.118775) (xy 418.37991 -324.150736)
			(xy 418.379408 -324.182697) (xy 418.371397 -324.246115) (xy 418.3555 -324.308029) (xy 418.331968 -324.367462)
			(xy 418.301174 -324.423477) (xy 418.263601 -324.475192) (xy 418.219844 -324.521789) (xy 418.203874 -324.535)
			(xy 420.094484 -324.535) (xy 420.098475 -324.446141) (xy 420.110415 -324.357997) (xy 420.130207 -324.271278)
			(xy 420.157694 -324.186683) (xy 420.192652 -324.104892) (xy 420.234801 -324.026563) (xy 420.283802 -323.952328)
			(xy 420.33926 -323.882785) (xy 420.400728 -323.818492) (xy 420.467712 -323.759968) (xy 420.539673 -323.707684)
			(xy 420.61603 -323.662061) (xy 420.696169 -323.623466) (xy 420.779445 -323.59221) (xy 420.865188 -323.568544)
			(xy 420.952707 -323.55266) (xy 421.041298 -323.544684) (xy 421.085772 -323.544184) (xy 422.838372 -323.544184)
			(xy 422.882852 -323.544591) (xy 422.971454 -323.552563) (xy 423.058985 -323.568445) (xy 423.14474 -323.59211)
			(xy 423.228028 -323.623366) (xy 423.308179 -323.661963) (xy 423.384548 -323.707589) (xy 423.456519 -323.759878)
			(xy 423.523513 -323.818407) (xy 423.584991 -323.882706) (xy 423.640458 -323.952257) (xy 423.689466 -324.0265)
			(xy 423.731622 -324.104838) (xy 423.766587 -324.186639) (xy 423.794077 -324.271245) (xy 423.813873 -324.357974)
			(xy 423.825815 -324.446129) (xy 423.829806 -324.535) (xy 427.63847 -324.535) (xy 427.642461 -324.446136)
			(xy 427.654402 -324.357988) (xy 427.674196 -324.271265) (xy 427.701684 -324.186666) (xy 427.736646 -324.104871)
			(xy 427.778799 -324.02654) (xy 427.827803 -323.952302) (xy 427.883265 -323.882757) (xy 427.944739 -323.818463)
			(xy 428.011727 -323.759938) (xy 428.083693 -323.707653) (xy 428.160055 -323.662031) (xy 428.2402 -323.623437)
			(xy 428.323482 -323.592183) (xy 428.40923 -323.56852) (xy 428.496754 -323.552639) (xy 428.585349 -323.544667)
			(xy 428.629826 -323.544184) (xy 430.382426 -323.544184) (xy 430.426904 -323.544608) (xy 430.515501 -323.552584)
			(xy 430.603027 -323.56847) (xy 430.688777 -323.592137) (xy 430.772059 -323.623396) (xy 430.852205 -323.661994)
			(xy 430.928568 -323.70762) (xy 431.000534 -323.759908) (xy 431.067523 -323.818437) (xy 431.128996 -323.882734)
			(xy 431.184459 -323.952283) (xy 431.233463 -324.026524) (xy 431.275616 -324.104858) (xy 431.310577 -324.186656)
			(xy 431.338066 -324.271258) (xy 431.35786 -324.357983) (xy 431.369801 -324.446134) (xy 431.373792 -324.535)
			(xy 435.182584 -324.535) (xy 435.186575 -324.44614) (xy 435.198515 -324.357996) (xy 435.218308 -324.271277)
			(xy 435.245794 -324.186681) (xy 435.280753 -324.104889) (xy 435.322903 -324.026561) (xy 435.371904 -323.952326)
			(xy 435.427363 -323.882782) (xy 435.488831 -323.818489) (xy 435.555816 -323.759965) (xy 435.627777 -323.707682)
			(xy 435.704135 -323.662059) (xy 435.784275 -323.623464) (xy 435.867551 -323.592208) (xy 435.953295 -323.568543)
			(xy 436.040814 -323.552659) (xy 436.129405 -323.544684) (xy 436.17388 -323.544184) (xy 437.92648 -323.544184)
			(xy 437.97096 -323.544591) (xy 438.059562 -323.552564) (xy 438.147092 -323.568447) (xy 438.232846 -323.592112)
			(xy 438.316134 -323.623369) (xy 438.396284 -323.661966) (xy 438.472652 -323.707592) (xy 438.544623 -323.75988)
			(xy 438.611616 -323.81841) (xy 438.673094 -323.882709) (xy 438.72856 -323.95226) (xy 438.777568 -324.026503)
			(xy 438.819723 -324.10484) (xy 438.854687 -324.186641) (xy 438.882178 -324.271246) (xy 438.901973 -324.357975)
			(xy 438.913915 -324.44613) (xy 438.917906 -324.535) (xy 438.913915 -324.62387) (xy 438.901973 -324.712025)
			(xy 438.882178 -324.798754) (xy 438.854687 -324.883359) (xy 438.819723 -324.96516) (xy 438.777568 -325.043497)
			(xy 438.72856 -325.11774) (xy 438.673094 -325.187291) (xy 438.611616 -325.25159) (xy 438.544623 -325.31012)
			(xy 438.472652 -325.362408) (xy 438.396284 -325.408034) (xy 438.316134 -325.446631) (xy 438.232846 -325.477888)
			(xy 438.147092 -325.501553) (xy 438.059562 -325.517436) (xy 437.97096 -325.525409) (xy 437.92648 -325.525892)
			(xy 436.17388 -325.525892) (xy 436.129405 -325.525316) (xy 436.040814 -325.517341) (xy 435.953295 -325.501457)
			(xy 435.867551 -325.477792) (xy 435.784275 -325.446536) (xy 435.704135 -325.407941) (xy 435.627777 -325.362318)
			(xy 435.555816 -325.310035) (xy 435.488831 -325.251511) (xy 435.427363 -325.187218) (xy 435.371904 -325.117674)
			(xy 435.322903 -325.043439) (xy 435.280753 -324.965111) (xy 435.245794 -324.883319) (xy 435.218308 -324.798723)
			(xy 435.198515 -324.712004) (xy 435.186575 -324.62386) (xy 435.182584 -324.535) (xy 431.373792 -324.535)
			(xy 431.369801 -324.623866) (xy 431.35786 -324.712017) (xy 431.338066 -324.798742) (xy 431.310577 -324.883344)
			(xy 431.275616 -324.965142) (xy 431.233463 -325.043476) (xy 431.184459 -325.117717) (xy 431.128996 -325.187266)
			(xy 431.067523 -325.251563) (xy 431.000534 -325.310092) (xy 430.928568 -325.36238) (xy 430.852205 -325.408006)
			(xy 430.772059 -325.446604) (xy 430.688777 -325.477863) (xy 430.603027 -325.50153) (xy 430.515501 -325.517416)
			(xy 430.426904 -325.525392) (xy 430.382426 -325.525892) (xy 428.629826 -325.525892) (xy 428.585349 -325.525333)
			(xy 428.496754 -325.517361) (xy 428.40923 -325.50148) (xy 428.323482 -325.477817) (xy 428.2402 -325.446563)
			(xy 428.160055 -325.407969) (xy 428.083693 -325.362347) (xy 428.011727 -325.310062) (xy 427.944739 -325.251537)
			(xy 427.883265 -325.187243) (xy 427.827803 -325.117698) (xy 427.778799 -325.04346) (xy 427.736646 -324.965129)
			(xy 427.701684 -324.883334) (xy 427.674196 -324.798735) (xy 427.654402 -324.712012) (xy 427.642461 -324.623864)
			(xy 427.63847 -324.535) (xy 423.829806 -324.535) (xy 423.825815 -324.623871) (xy 423.813873 -324.712026)
			(xy 423.794077 -324.798755) (xy 423.766587 -324.883361) (xy 423.731622 -324.965162) (xy 423.689466 -325.0435)
			(xy 423.640458 -325.117743) (xy 423.584991 -325.187294) (xy 423.523513 -325.251593) (xy 423.456519 -325.310122)
			(xy 423.384548 -325.362411) (xy 423.308179 -325.408037) (xy 423.228028 -325.446634) (xy 423.14474 -325.47789)
			(xy 423.058985 -325.501555) (xy 422.971454 -325.517437) (xy 422.882852 -325.525409) (xy 422.838372 -325.525892)
			(xy 421.085772 -325.525892) (xy 421.041298 -325.525316) (xy 420.952707 -325.51734) (xy 420.865188 -325.501456)
			(xy 420.779445 -325.47779) (xy 420.696169 -325.446534) (xy 420.61603 -325.407939) (xy 420.539673 -325.362316)
			(xy 420.467712 -325.310032) (xy 420.400728 -325.251508) (xy 420.33926 -325.187215) (xy 420.283802 -325.117672)
			(xy 420.234801 -325.043437) (xy 420.192652 -324.965108) (xy 420.157694 -324.883317) (xy 420.130207 -324.798722)
			(xy 420.110415 -324.712003) (xy 420.098475 -324.623859) (xy 420.094484 -324.535) (xy 418.203874 -324.535)
			(xy 418.170591 -324.562534) (xy 418.11662 -324.596785) (xy 418.058781 -324.624002) (xy 417.997988 -324.643755)
			(xy 417.935198 -324.655733) (xy 417.871402 -324.659747) (xy 417.807606 -324.655733) (xy 417.744816 -324.643755)
			(xy 417.684023 -324.624002) (xy 417.626184 -324.596785) (xy 417.572213 -324.562534) (xy 417.52296 -324.521789)
			(xy 417.479203 -324.475192) (xy 417.44163 -324.423477) (xy 417.410836 -324.367462) (xy 417.387304 -324.308029)
			(xy 417.371407 -324.246115) (xy 417.363396 -324.182697) (xy 416.220786 -324.182697) (xy 416.222477 -324.186654)
			(xy 416.249965 -324.271256) (xy 416.26976 -324.357982) (xy 416.281701 -324.446133) (xy 416.285692 -324.535)
			(xy 416.281701 -324.623867) (xy 416.26976 -324.712018) (xy 416.249965 -324.798744) (xy 416.222477 -324.883346)
			(xy 416.187515 -324.965144) (xy 416.145362 -325.043479) (xy 416.096357 -325.117719) (xy 416.040894 -325.187269)
			(xy 415.97942 -325.251566) (xy 415.912431 -325.310095) (xy 415.840464 -325.362383) (xy 415.7641 -325.408009)
			(xy 415.683954 -325.446607) (xy 415.600671 -325.477865) (xy 415.51492 -325.501532) (xy 415.427394 -325.517417)
			(xy 415.338796 -325.525392) (xy 415.294318 -325.525892) (xy 413.541718 -325.525892) (xy 413.497242 -325.525333)
			(xy 413.408647 -325.51736) (xy 413.321123 -325.501479) (xy 413.235376 -325.477815) (xy 413.152095 -325.446561)
			(xy 413.071951 -325.407967) (xy 412.995589 -325.362344) (xy 412.923624 -325.310059) (xy 412.856636 -325.251535)
			(xy 412.795163 -325.187241) (xy 412.739701 -325.117695) (xy 412.690697 -325.043458) (xy 412.648545 -324.965127)
			(xy 412.613584 -324.883332) (xy 412.586096 -324.798733) (xy 412.566301 -324.712011) (xy 412.554361 -324.623863)
			(xy 412.55037 -324.535) (xy 396.739976 -324.535) (xy 396.767115 -324.567807) (xy 396.801366 -324.621779)
			(xy 396.828582 -324.679618) (xy 396.848335 -324.740413) (xy 396.860313 -324.803203) (xy 396.864327 -324.867)
			(xy 396.860313 -324.930797) (xy 396.848335 -324.993587) (xy 396.828582 -325.054382) (xy 396.801366 -325.112221)
			(xy 396.767115 -325.166193) (xy 396.72637 -325.215447) (xy 396.679773 -325.259206) (xy 396.628059 -325.29678)
			(xy 396.572043 -325.327576) (xy 396.51261 -325.351109) (xy 396.450696 -325.367008) (xy 396.387277 -325.375021)
			(xy 396.355316 -325.375524) (xy 396.328134 -325.375156) (xy 396.27408 -325.369363) (xy 396.220952 -325.357841)
			(xy 396.195042 -325.349616) (xy 396.185898 -325.346568) (xy 396.16761 -325.34733) (xy 396.0876 -325.382382)
			(xy 396.074646 -325.395336) (xy 396.070582 -325.403972) (xy 396.056756 -325.433229) (xy 396.022775 -325.4883)
			(xy 395.98208 -325.538612) (xy 395.935328 -325.583353) (xy 395.883276 -325.621799) (xy 395.826766 -325.653327)
			(xy 395.766712 -325.677429) (xy 395.704084 -325.693714) (xy 395.639895 -325.70192) (xy 395.60754 -325.702422)
			(xy 395.575337 -325.701943) (xy 395.511445 -325.693827) (xy 395.449089 -325.677707) (xy 395.389268 -325.65384)
			(xy 395.332941 -325.62261) (xy 395.281008 -325.584516) (xy 395.234303 -325.540169) (xy 395.193572 -325.490278)
			(xy 395.159468 -325.435643) (xy 395.132537 -325.377138) (xy 395.1224 -325.346568) (xy 395.119352 -325.336408)
			(xy 395.10589 -325.320914) (xy 395.020546 -325.279258) (xy 394.999972 -325.278242) (xy 394.990066 -325.282052)
			(xy 394.961465 -325.29228) (xy 394.902441 -325.306634) (xy 394.84213 -325.313866) (xy 394.811758 -325.31431)
			(xy 394.779799 -325.313802) (xy 394.716385 -325.305786) (xy 394.654476 -325.289885) (xy 394.595047 -325.266352)
			(xy 394.539037 -325.235556) (xy 394.487328 -325.197983) (xy 394.440735 -325.154226) (xy 394.399994 -325.104974)
			(xy 394.365746 -325.051005) (xy 394.338532 -324.993169) (xy 394.318781 -324.932379) (xy 394.306805 -324.869592)
			(xy 394.302791 -324.8058) (xy 388.274501 -324.8058) (xy 389.23939 -327.358756) (xy 394.010896 -327.358756)
			(xy 394.011383 -327.326676) (xy 394.019462 -327.263025) (xy 394.035488 -327.200898) (xy 394.059204 -327.141281)
			(xy 394.090234 -327.085123) (xy 394.128085 -327.033316) (xy 394.172154 -326.986685) (xy 394.221742 -326.945969)
			(xy 394.24864 -326.92848) (xy 394.2588 -326.921876) (xy 394.270992 -326.90181) (xy 394.279882 -326.796654)
			(xy 394.271246 -326.77481) (xy 394.262102 -326.766682) (xy 394.239633 -326.745975) (xy 394.199313 -326.700061)
			(xy 394.164783 -326.649648) (xy 394.136543 -326.595461) (xy 394.114999 -326.53828) (xy 394.10046 -326.478931)
			(xy 394.093137 -326.418266) (xy 394.092684 -326.387714) (xy 394.093186 -326.355753) (xy 394.101197 -326.292335)
			(xy 394.117094 -326.230421) (xy 394.140626 -326.170988) (xy 394.17142 -326.114973) (xy 394.208993 -326.063258)
			(xy 394.25275 -326.016661) (xy 394.302003 -325.975916) (xy 394.355974 -325.941665) (xy 394.413813 -325.914448)
			(xy 394.474606 -325.894695) (xy 394.537396 -325.882717) (xy 394.601192 -325.878704) (xy 394.664988 -325.882717)
			(xy 394.727778 -325.894695) (xy 394.788571 -325.914448) (xy 394.84641 -325.941665) (xy 394.900381 -325.975916)
			(xy 394.928092 -325.99884) (xy 398.057622 -325.99884) (xy 398.061693 -325.943218) (xy 398.073819 -325.888781)
			(xy 398.093742 -325.83669) (xy 398.121038 -325.788055) (xy 398.155124 -325.743912) (xy 398.195273 -325.705203)
			(xy 398.240631 -325.672752) (xy 398.290231 -325.647251) (xy 398.343015 -325.629244) (xy 398.397858 -325.619114)
			(xy 398.453592 -325.617077) (xy 398.509029 -325.623177) (xy 398.562986 -325.637283) (xy 398.614315 -325.659095)
			(xy 398.661921 -325.688149) (xy 398.704789 -325.723824) (xy 398.742006 -325.765361) (xy 398.772779 -325.811874)
			(xy 398.796451 -325.862371) (xy 398.812519 -325.915778) (xy 398.820639 -325.970954) (xy 398.82099 -325.990161)
			(xy 399.330666 -325.990161) (xy 399.330666 -325.926239) (xy 399.338677 -325.862821) (xy 399.354574 -325.800907)
			(xy 399.378106 -325.741474) (xy 399.4089 -325.685459) (xy 399.446473 -325.633744) (xy 399.49023 -325.587147)
			(xy 399.539483 -325.546402) (xy 399.593454 -325.512151) (xy 399.651293 -325.484934) (xy 399.712086 -325.465181)
			(xy 399.774876 -325.453203) (xy 399.838672 -325.44919) (xy 399.902468 -325.453203) (xy 399.965258 -325.465181)
			(xy 400.026051 -325.484934) (xy 400.08389 -325.512151) (xy 400.137861 -325.546402) (xy 400.187114 -325.587147)
			(xy 400.230871 -325.633744) (xy 400.268444 -325.685459) (xy 400.299238 -325.741474) (xy 400.32277 -325.800907)
			(xy 400.338667 -325.862821) (xy 400.346678 -325.926239) (xy 400.34718 -325.9582) (xy 400.346678 -325.990161)
			(xy 400.346357 -325.992701) (xy 400.479254 -325.992701) (xy 400.479254 -325.928779) (xy 400.487265 -325.865361)
			(xy 400.503162 -325.803447) (xy 400.526694 -325.744014) (xy 400.557488 -325.687999) (xy 400.595061 -325.636284)
			(xy 400.638818 -325.589687) (xy 400.688071 -325.548942) (xy 400.742042 -325.514691) (xy 400.799881 -325.487474)
			(xy 400.860674 -325.467721) (xy 400.923464 -325.455743) (xy 400.98726 -325.45173) (xy 401.051056 -325.455743)
			(xy 401.113846 -325.467721) (xy 401.174639 -325.487474) (xy 401.232478 -325.514691) (xy 401.286449 -325.548942)
			(xy 401.335702 -325.589687) (xy 401.379459 -325.636284) (xy 401.417032 -325.687999) (xy 401.447826 -325.744014)
			(xy 401.460015 -325.7748) (xy 404.40558 -325.7748) (xy 404.409594 -325.711002) (xy 404.421573 -325.648211)
			(xy 404.441326 -325.587416) (xy 404.468544 -325.529576) (xy 404.502796 -325.475603) (xy 404.543543 -325.426349)
			(xy 404.590142 -325.382591) (xy 404.641858 -325.345018) (xy 404.697875 -325.314223) (xy 404.75731 -325.290692)
			(xy 404.819226 -325.274795) (xy 404.882646 -325.266784) (xy 404.914608 -325.266304) (xy 404.946608 -325.266765)
			(xy 405.010102 -325.274794) (xy 405.072088 -325.290723) (xy 405.131586 -325.3143) (xy 405.187657 -325.345155)
			(xy 405.21382 -325.363586) (xy 405.221476 -325.368662) (xy 405.23919 -325.373475) (xy 405.248364 -325.372984)
			(xy 405.278844 -325.37019) (xy 405.287998 -325.368906) (xy 405.304543 -325.3607) (xy 405.311102 -325.354188)
			(xy 405.331768 -325.332721) (xy 405.377243 -325.294214) (xy 405.426905 -325.261282) (xy 405.480074 -325.234378)
			(xy 405.536023 -325.21387) (xy 405.593984 -325.200038) (xy 405.653164 -325.193071) (xy 405.682958 -325.192644)
			(xy 405.713686 -325.193195) (xy 405.774695 -325.200598) (xy 405.834367 -325.215301) (xy 405.891832 -325.237088)
			(xy 405.946251 -325.265644) (xy 405.996832 -325.300551) (xy 406.042836 -325.3413) (xy 406.083594 -325.387297)
			(xy 406.118509 -325.437872) (xy 406.147075 -325.492286) (xy 406.168873 -325.549747) (xy 406.183586 -325.609416)
			(xy 406.190999 -325.670424) (xy 406.191466 -325.701152) (xy 406.190955 -325.732147) (xy 406.183402 -325.793676)
			(xy 406.168428 -325.85383) (xy 406.146253 -325.911719) (xy 406.117208 -325.966483) (xy 406.081721 -326.017312)
			(xy 406.040321 -326.063451) (xy 405.993619 -326.104216) (xy 405.94231 -326.139003) (xy 405.887153 -326.167296)
			(xy 405.858218 -326.178418) (xy 405.845772 -326.18299) (xy 405.8285 -326.203056) (xy 405.806148 -326.314054)
			(xy 405.814022 -326.338946) (xy 405.823674 -326.34809) (xy 405.845081 -326.368717) (xy 405.883445 -326.414131)
			(xy 405.916256 -326.463707) (xy 405.943065 -326.516769) (xy 405.963508 -326.572593) (xy 405.977306 -326.630419)
			(xy 405.983942 -326.686672) (xy 407.364946 -326.686672) (xy 407.36543 -326.655942) (xy 407.37284 -326.594931)
			(xy 407.387551 -326.535258) (xy 407.409346 -326.477792) (xy 407.437908 -326.423373) (xy 407.472821 -326.372792)
			(xy 407.513576 -326.326789) (xy 407.559578 -326.286032) (xy 407.610157 -326.251117) (xy 407.664576 -326.222553)
			(xy 407.72204 -326.200756) (xy 407.781713 -326.186044) (xy 407.842724 -326.178631) (xy 407.873454 -326.178164)
			(xy 407.906827 -326.178697) (xy 407.972998 -326.187443) (xy 408.037454 -326.204777) (xy 408.099086 -326.230401)
			(xy 408.156833 -326.263873) (xy 408.183588 -326.283828) (xy 408.191426 -326.289349) (xy 408.209825 -326.294696)
			(xy 408.219402 -326.294242) (xy 408.250136 -326.291448) (xy 408.259562 -326.29012) (xy 408.276525 -326.281513)
			(xy 408.283156 -326.274684) (xy 408.30388 -326.252422) (xy 408.349723 -326.21245) (xy 408.400005 -326.178227)
			(xy 408.454008 -326.150243) (xy 408.510962 -326.128897) (xy 408.570054 -326.114493) (xy 408.630443 -326.107237)
			(xy 408.660854 -326.10679) (xy 408.692818 -326.107272) (xy 408.756243 -326.115279) (xy 408.818164 -326.131173)
			(xy 408.877604 -326.154702) (xy 408.933627 -326.185496) (xy 408.985348 -326.22307) (xy 409.031951 -326.266829)
			(xy 409.072703 -326.316085) (xy 409.106959 -326.37006) (xy 409.13418 -326.427903) (xy 409.153936 -326.488702)
			(xy 409.165915 -326.551498) (xy 409.16993 -326.6153) (xy 409.165915 -326.679102) (xy 409.153936 -326.741898)
			(xy 409.13418 -326.802697) (xy 409.106959 -326.86054) (xy 409.072703 -326.914515) (xy 409.031951 -326.963771)
			(xy 408.985348 -327.00753) (xy 408.933627 -327.045104) (xy 408.877604 -327.075898) (xy 408.818164 -327.099427)
			(xy 408.756243 -327.115321) (xy 408.692818 -327.123328) (xy 408.660854 -327.123806) (xy 408.627482 -327.123254)
			(xy 408.561312 -327.114511) (xy 408.496857 -327.09718) (xy 408.435225 -327.071561) (xy 408.377477 -327.038094)
			(xy 408.35072 -327.018142) (xy 408.342882 -327.012622) (xy 408.324483 -327.007275) (xy 408.314906 -327.007728)
			(xy 408.284172 -327.010522) (xy 408.274742 -327.011834) (xy 408.25778 -327.020451) (xy 408.251152 -327.027286)
			(xy 408.230984 -327.04901) (xy 408.186419 -327.088099) (xy 408.162252 -327.105264) (xy 408.155257 -327.110518)
			(xy 408.144986 -327.124663) (xy 408.142186 -327.13295) (xy 408.133804 -327.161906) (xy 408.131781 -327.170253)
			(xy 408.132832 -327.187387) (xy 408.135836 -327.195434) (xy 408.145117 -327.218737) (xy 408.158133 -327.267179)
			(xy 408.164671 -327.316911) (xy 408.165046 -327.341992) (xy 408.16456 -327.369243) (xy 408.156804 -327.423191)
			(xy 408.141449 -327.475486) (xy 408.118807 -327.525063) (xy 408.089341 -327.570913) (xy 408.05365 -327.612104)
			(xy 408.012459 -327.647795) (xy 407.966609 -327.677261) (xy 407.917032 -327.699903) (xy 407.864737 -327.715258)
			(xy 407.810789 -327.723014) (xy 407.756287 -327.723014) (xy 407.702339 -327.715258) (xy 407.650044 -327.699903)
			(xy 407.600467 -327.677261) (xy 407.554617 -327.647795) (xy 407.513426 -327.612104) (xy 407.477735 -327.570913)
			(xy 407.448269 -327.525063) (xy 407.425627 -327.475486) (xy 407.410272 -327.423191) (xy 407.402516 -327.369243)
			(xy 407.40203 -327.341992) (xy 407.402424 -327.316538) (xy 407.409201 -327.266083) (xy 407.422633 -327.216979)
			(xy 407.442482 -327.170099) (xy 407.468394 -327.126279) (xy 407.483818 -327.106026) (xy 407.488898 -327.099026)
			(xy 407.494481 -327.082667) (xy 407.49474 -327.074022) (xy 407.494486 -327.04405) (xy 407.494093 -327.035337)
			(xy 407.488108 -327.018968) (xy 407.482802 -327.012046) (xy 407.464298 -326.989153) (xy 407.432099 -326.939874)
			(xy 407.4058 -326.887209) (xy 407.385751 -326.831863) (xy 407.37222 -326.774573) (xy 407.365387 -326.716105)
			(xy 407.364946 -326.686672) (xy 405.983942 -326.686672) (xy 405.984271 -326.689459) (xy 405.98471 -326.719184)
			(xy 405.984208 -326.751145) (xy 405.976197 -326.814563) (xy 405.9603 -326.876477) (xy 405.936768 -326.93591)
			(xy 405.905974 -326.991925) (xy 405.868401 -327.04364) (xy 405.824644 -327.090237) (xy 405.775391 -327.130982)
			(xy 405.72142 -327.165233) (xy 405.663581 -327.19245) (xy 405.602788 -327.212203) (xy 405.539998 -327.224181)
			(xy 405.476202 -327.228195) (xy 405.412406 -327.224181) (xy 405.349616 -327.212203) (xy 405.288823 -327.19245)
			(xy 405.230984 -327.165233) (xy 405.177013 -327.130982) (xy 405.12776 -327.090237) (xy 405.084003 -327.04364)
			(xy 405.04643 -326.991925) (xy 405.015636 -326.93591) (xy 404.992104 -326.876477) (xy 404.976207 -326.814563)
			(xy 404.968196 -326.751145) (xy 404.967694 -326.719184) (xy 404.968108 -326.689472) (xy 404.975045 -326.630455)
			(xy 404.988811 -326.572647) (xy 405.009218 -326.516838) (xy 405.035988 -326.463786) (xy 405.052022 -326.438768)
			(xy 405.06015 -326.426322) (xy 405.060912 -326.397366) (xy 404.998936 -326.293226) (xy 404.973282 -326.280018)
			(xy 404.95855 -326.281542) (xy 404.914608 -326.28332) (xy 404.882646 -326.282816) (xy 404.819226 -326.274805)
			(xy 404.75731 -326.258908) (xy 404.697875 -326.235377) (xy 404.641858 -326.204582) (xy 404.590142 -326.167009)
			(xy 404.543543 -326.123251) (xy 404.502796 -326.073997) (xy 404.468544 -326.020024) (xy 404.441326 -325.962184)
			(xy 404.421573 -325.901389) (xy 404.409594 -325.838598) (xy 404.40558 -325.7748) (xy 401.460015 -325.7748)
			(xy 401.471358 -325.803447) (xy 401.487255 -325.865361) (xy 401.495266 -325.928779) (xy 401.495768 -325.96074)
			(xy 401.495266 -325.992701) (xy 401.487255 -326.056119) (xy 401.471358 -326.118033) (xy 401.447826 -326.177466)
			(xy 401.417032 -326.233481) (xy 401.379459 -326.285196) (xy 401.335702 -326.331793) (xy 401.286449 -326.372538)
			(xy 401.232478 -326.406789) (xy 401.174639 -326.434006) (xy 401.1351 -326.446853) (xy 402.155654 -326.446853)
			(xy 402.155654 -326.382931) (xy 402.163665 -326.319513) (xy 402.179562 -326.257599) (xy 402.203094 -326.198166)
			(xy 402.233888 -326.142151) (xy 402.271461 -326.090436) (xy 402.315218 -326.043839) (xy 402.364471 -326.003094)
			(xy 402.418442 -325.968843) (xy 402.476281 -325.941626) (xy 402.537074 -325.921873) (xy 402.599864 -325.909895)
			(xy 402.66366 -325.905882) (xy 402.727456 -325.909895) (xy 402.790246 -325.921873) (xy 402.851039 -325.941626)
			(xy 402.908878 -325.968843) (xy 402.962849 -326.003094) (xy 403.012102 -326.043839) (xy 403.055859 -326.090436)
			(xy 403.093432 -326.142151) (xy 403.124226 -326.198166) (xy 403.147758 -326.257599) (xy 403.163655 -326.319513)
			(xy 403.171666 -326.382931) (xy 403.172168 -326.414892) (xy 403.171666 -326.446853) (xy 403.163655 -326.510271)
			(xy 403.147758 -326.572185) (xy 403.124226 -326.631618) (xy 403.093432 -326.687633) (xy 403.055859 -326.739348)
			(xy 403.012102 -326.785945) (xy 402.962849 -326.82669) (xy 402.908878 -326.860941) (xy 402.851039 -326.888158)
			(xy 402.790246 -326.907911) (xy 402.727456 -326.919889) (xy 402.66366 -326.923903) (xy 402.599864 -326.919889)
			(xy 402.537074 -326.907911) (xy 402.476281 -326.888158) (xy 402.418442 -326.860941) (xy 402.364471 -326.82669)
			(xy 402.315218 -326.785945) (xy 402.271461 -326.739348) (xy 402.233888 -326.687633) (xy 402.203094 -326.631618)
			(xy 402.179562 -326.572185) (xy 402.163665 -326.510271) (xy 402.155654 -326.446853) (xy 401.1351 -326.446853)
			(xy 401.113846 -326.453759) (xy 401.051056 -326.465737) (xy 400.98726 -326.469751) (xy 400.923464 -326.465737)
			(xy 400.860674 -326.453759) (xy 400.799881 -326.434006) (xy 400.742042 -326.406789) (xy 400.688071 -326.372538)
			(xy 400.638818 -326.331793) (xy 400.595061 -326.285196) (xy 400.557488 -326.233481) (xy 400.526694 -326.177466)
			(xy 400.503162 -326.118033) (xy 400.487265 -326.056119) (xy 400.479254 -325.992701) (xy 400.346357 -325.992701)
			(xy 400.338667 -326.053579) (xy 400.32277 -326.115493) (xy 400.299238 -326.174926) (xy 400.268444 -326.230941)
			(xy 400.230871 -326.282656) (xy 400.187114 -326.329253) (xy 400.137861 -326.369998) (xy 400.08389 -326.404249)
			(xy 400.026051 -326.431466) (xy 399.965258 -326.451219) (xy 399.902468 -326.463197) (xy 399.838672 -326.467211)
			(xy 399.774876 -326.463197) (xy 399.712086 -326.451219) (xy 399.651293 -326.431466) (xy 399.593454 -326.404249)
			(xy 399.539483 -326.369998) (xy 399.49023 -326.329253) (xy 399.446473 -326.282656) (xy 399.4089 -326.230941)
			(xy 399.378106 -326.174926) (xy 399.354574 -326.115493) (xy 399.338677 -326.053579) (xy 399.330666 -325.990161)
			(xy 398.82099 -325.990161) (xy 398.821148 -325.99884) (xy 398.820639 -326.026726) (xy 398.812519 -326.081902)
			(xy 398.796451 -326.135309) (xy 398.772779 -326.185806) (xy 398.742006 -326.232319) (xy 398.704789 -326.273856)
			(xy 398.661921 -326.309531) (xy 398.614315 -326.338585) (xy 398.562986 -326.360397) (xy 398.509029 -326.374503)
			(xy 398.453592 -326.380603) (xy 398.397858 -326.378566) (xy 398.343015 -326.368436) (xy 398.290231 -326.350429)
			(xy 398.240631 -326.324928) (xy 398.195273 -326.292477) (xy 398.155124 -326.253768) (xy 398.121038 -326.209625)
			(xy 398.093742 -326.16099) (xy 398.073819 -326.108899) (xy 398.061693 -326.054462) (xy 398.057622 -325.99884)
			(xy 394.928092 -325.99884) (xy 394.949634 -326.016661) (xy 394.993391 -326.063258) (xy 395.030964 -326.114973)
			(xy 395.061758 -326.170988) (xy 395.08529 -326.230421) (xy 395.101187 -326.292335) (xy 395.109198 -326.355753)
			(xy 395.1097 -326.387714) (xy 395.109191 -326.419794) (xy 395.101115 -326.483443) (xy 395.085093 -326.54557)
			(xy 395.06138 -326.605186) (xy 395.030353 -326.661345) (xy 394.992505 -326.713152) (xy 394.948438 -326.759784)
			(xy 394.898853 -326.8005) (xy 394.871956 -326.81799) (xy 394.861796 -326.824594) (xy 394.849604 -326.84466)
			(xy 394.840714 -326.949816) (xy 394.84935 -326.97166) (xy 394.849587 -326.971871) (xy 395.523968 -326.971871)
			(xy 395.523968 -326.907949) (xy 395.531979 -326.844531) (xy 395.547876 -326.782617) (xy 395.571408 -326.723184)
			(xy 395.602202 -326.667169) (xy 395.639775 -326.615454) (xy 395.683532 -326.568857) (xy 395.732785 -326.528112)
			(xy 395.786756 -326.493861) (xy 395.844595 -326.466644) (xy 395.905388 -326.446891) (xy 395.968178 -326.434913)
			(xy 396.031974 -326.4309) (xy 396.09577 -326.434913) (xy 396.15856 -326.446891) (xy 396.219353 -326.466644)
			(xy 396.277192 -326.493861) (xy 396.331163 -326.528112) (xy 396.380416 -326.568857) (xy 396.424173 -326.615454)
			(xy 396.461746 -326.667169) (xy 396.49254 -326.723184) (xy 396.516072 -326.782617) (xy 396.531969 -326.844531)
			(xy 396.53998 -326.907949) (xy 396.540482 -326.93991) (xy 396.53998 -326.971871) (xy 396.531969 -327.035289)
			(xy 396.516072 -327.097203) (xy 396.49254 -327.156636) (xy 396.461746 -327.212651) (xy 396.424173 -327.264366)
			(xy 396.380416 -327.310963) (xy 396.331163 -327.351708) (xy 396.277192 -327.385959) (xy 396.219353 -327.413176)
			(xy 396.15856 -327.432929) (xy 396.09577 -327.444907) (xy 396.031974 -327.448921) (xy 395.968178 -327.444907)
			(xy 395.905388 -327.432929) (xy 395.844595 -327.413176) (xy 395.786756 -327.385959) (xy 395.732785 -327.351708)
			(xy 395.683532 -327.310963) (xy 395.639775 -327.264366) (xy 395.602202 -327.212651) (xy 395.571408 -327.156636)
			(xy 395.547876 -327.097203) (xy 395.531979 -327.035289) (xy 395.523968 -326.971871) (xy 394.849587 -326.971871)
			(xy 394.858494 -326.979788) (xy 394.880947 -327.000512) (xy 394.921269 -327.046422) (xy 394.9558 -327.096832)
			(xy 394.984042 -327.151017) (xy 395.005589 -327.208195) (xy 395.020131 -327.267542) (xy 395.027457 -327.328204)
			(xy 395.027912 -327.358756) (xy 395.02741 -327.390717) (xy 395.019399 -327.454135) (xy 395.003502 -327.516049)
			(xy 394.97997 -327.575482) (xy 394.949176 -327.631497) (xy 394.911603 -327.683212) (xy 394.867846 -327.729809)
			(xy 394.818593 -327.770554) (xy 394.764622 -327.804805) (xy 394.706783 -327.832022) (xy 394.64599 -327.851775)
			(xy 394.5832 -327.863753) (xy 394.519404 -327.867767) (xy 394.455608 -327.863753) (xy 394.392818 -327.851775)
			(xy 394.332025 -327.832022) (xy 394.274186 -327.804805) (xy 394.220215 -327.770554) (xy 394.170962 -327.729809)
			(xy 394.127205 -327.683212) (xy 394.089632 -327.631497) (xy 394.058838 -327.575482) (xy 394.035306 -327.516049)
			(xy 394.019409 -327.454135) (xy 394.011398 -327.390717) (xy 394.010896 -327.358756) (xy 389.23939 -327.358756)
			(xy 389.579595 -328.258889) (xy 394.846804 -328.258889) (xy 394.846804 -328.194967) (xy 394.854815 -328.131549)
			(xy 394.870712 -328.069635) (xy 394.894244 -328.010202) (xy 394.925038 -327.954187) (xy 394.962611 -327.902472)
			(xy 395.006368 -327.855875) (xy 395.055621 -327.81513) (xy 395.109592 -327.780879) (xy 395.167431 -327.753662)
			(xy 395.228224 -327.733909) (xy 395.291014 -327.721931) (xy 395.35481 -327.717918) (xy 395.418606 -327.721931)
			(xy 395.481396 -327.733909) (xy 395.542189 -327.753662) (xy 395.600028 -327.780879) (xy 395.653999 -327.81513)
			(xy 395.703252 -327.855875) (xy 395.747009 -327.902472) (xy 395.784582 -327.954187) (xy 395.815376 -328.010202)
			(xy 395.838908 -328.069635) (xy 395.854805 -328.131549) (xy 395.862816 -328.194967) (xy 395.863318 -328.226928)
			(xy 395.862816 -328.258889) (xy 395.854805 -328.322307) (xy 395.838908 -328.384221) (xy 395.815376 -328.443654)
			(xy 395.784582 -328.499669) (xy 395.758706 -328.535284) (xy 397.509492 -328.535284) (xy 397.509949 -328.504662)
			(xy 397.517318 -328.443862) (xy 397.531934 -328.384387) (xy 397.553587 -328.327098) (xy 397.581963 -328.272824)
			(xy 397.616651 -328.22235) (xy 397.657149 -328.176406) (xy 397.702871 -328.135659) (xy 397.753156 -328.100697)
			(xy 397.780002 -328.085958) (xy 397.788384 -328.081386) (xy 397.800576 -328.067416) (xy 397.830294 -327.985374)
			(xy 397.83004 -327.966832) (xy 397.826484 -327.957942) (xy 397.814569 -327.927392) (xy 397.79783 -327.86399)
			(xy 397.789399 -327.798959) (xy 397.788892 -327.766172) (xy 397.789394 -327.734211) (xy 397.797405 -327.670793)
			(xy 397.813302 -327.608879) (xy 397.836834 -327.549446) (xy 397.867628 -327.493431) (xy 397.905201 -327.441716)
			(xy 397.948958 -327.395119) (xy 397.998211 -327.354374) (xy 398.052182 -327.320123) (xy 398.110021 -327.292906)
			(xy 398.170814 -327.273153) (xy 398.233604 -327.261175) (xy 398.2974 -327.257162) (xy 398.361196 -327.261175)
			(xy 398.423986 -327.273153) (xy 398.484779 -327.292906) (xy 398.542618 -327.320123) (xy 398.596589 -327.354374)
			(xy 398.645842 -327.395119) (xy 398.689599 -327.441716) (xy 398.727172 -327.493431) (xy 398.757966 -327.549446)
			(xy 398.781498 -327.608879) (xy 398.788102 -327.6346) (xy 400.943089 -327.6346) (xy 400.947103 -327.570806)
			(xy 400.95908 -327.508017) (xy 400.978832 -327.447225) (xy 401.006048 -327.389388) (xy 401.040297 -327.335418)
			(xy 401.081041 -327.286165) (xy 401.127636 -327.242408) (xy 401.179348 -327.204835) (xy 401.235361 -327.17404)
			(xy 401.294792 -327.150507) (xy 401.356704 -327.134609) (xy 401.42012 -327.126595) (xy 401.45208 -327.126092)
			(xy 401.482694 -327.126544) (xy 401.543477 -327.133922) (xy 401.602933 -327.14855) (xy 401.660201 -327.170215)
			(xy 401.687538 -327.184004) (xy 401.695673 -327.187843) (xy 401.71349 -327.1902) (xy 401.722336 -327.188576)
			(xy 401.752054 -327.181718) (xy 401.760528 -327.179359) (xy 401.775337 -327.169896) (xy 401.78101 -327.163176)
			(xy 401.799202 -327.140384) (xy 401.841317 -327.100051) (xy 401.889079 -327.066595) (xy 401.941375 -327.040796)
			(xy 401.996987 -327.023254) (xy 402.054621 -327.014378) (xy 402.083778 -327.013824) (xy 402.111034 -327.014221)
			(xy 402.164992 -327.021977) (xy 402.217297 -327.037332) (xy 402.266884 -327.059975) (xy 402.312744 -327.089445)
			(xy 402.353943 -327.125142) (xy 402.389642 -327.166338) (xy 402.419114 -327.212197) (xy 402.44176 -327.261782)
			(xy 402.457119 -327.314086) (xy 402.464877 -327.368044) (xy 402.464877 -327.410529) (xy 403.607264 -327.410529)
			(xy 403.607264 -327.346607) (xy 403.615275 -327.283189) (xy 403.631172 -327.221275) (xy 403.654704 -327.161842)
			(xy 403.685498 -327.105827) (xy 403.723071 -327.054112) (xy 403.766828 -327.007515) (xy 403.816081 -326.96677)
			(xy 403.870052 -326.932519) (xy 403.927891 -326.905302) (xy 403.988684 -326.885549) (xy 404.051474 -326.873571)
			(xy 404.11527 -326.869558) (xy 404.179066 -326.873571) (xy 404.241856 -326.885549) (xy 404.302649 -326.905302)
			(xy 404.360488 -326.932519) (xy 404.414459 -326.96677) (xy 404.463712 -327.007515) (xy 404.507469 -327.054112)
			(xy 404.545042 -327.105827) (xy 404.575836 -327.161842) (xy 404.599368 -327.221275) (xy 404.615265 -327.283189)
			(xy 404.623276 -327.346607) (xy 404.623778 -327.378568) (xy 404.623276 -327.410529) (xy 404.615265 -327.473947)
			(xy 404.599368 -327.535861) (xy 404.575836 -327.595294) (xy 404.545042 -327.651309) (xy 404.507469 -327.703024)
			(xy 404.463712 -327.749621) (xy 404.414459 -327.790366) (xy 404.360488 -327.824617) (xy 404.302649 -327.851834)
			(xy 404.241856 -327.871587) (xy 404.179066 -327.883565) (xy 404.11527 -327.887579) (xy 404.051474 -327.883565)
			(xy 403.988684 -327.871587) (xy 403.927891 -327.851834) (xy 403.870052 -327.824617) (xy 403.816081 -327.790366)
			(xy 403.766828 -327.749621) (xy 403.723071 -327.703024) (xy 403.685498 -327.651309) (xy 403.654704 -327.595294)
			(xy 403.631172 -327.535861) (xy 403.615275 -327.473947) (xy 403.607264 -327.410529) (xy 402.464877 -327.410529)
			(xy 402.464877 -327.422556) (xy 402.457119 -327.476514) (xy 402.44176 -327.528818) (xy 402.419114 -327.578403)
			(xy 402.389642 -327.624262) (xy 402.353943 -327.665458) (xy 402.312744 -327.701155) (xy 402.266884 -327.730625)
			(xy 402.217297 -327.753268) (xy 402.164992 -327.768623) (xy 402.111034 -327.776379) (xy 402.083778 -327.77684)
			(xy 402.065435 -327.776599) (xy 402.028922 -327.773042) (xy 402.01088 -327.769728) (xy 402.00216 -327.768405)
			(xy 401.984748 -327.771146) (xy 401.976844 -327.775062) (xy 401.950174 -327.789794) (xy 401.94243 -327.794387)
			(xy 401.930581 -327.807924) (xy 401.92706 -327.81621) (xy 401.915689 -327.84469) (xy 401.887057 -327.898921)
			(xy 401.85211 -327.949315) (xy 401.811355 -327.99514) (xy 401.765385 -328.03573) (xy 401.714867 -328.070497)
			(xy 401.660534 -328.098936) (xy 401.603176 -328.120634) (xy 401.543624 -328.135276) (xy 401.482743 -328.142649)
			(xy 401.45208 -328.143108) (xy 401.42012 -328.142605) (xy 401.356704 -328.134591) (xy 401.294792 -328.118693)
			(xy 401.235361 -328.09516) (xy 401.179348 -328.064365) (xy 401.127636 -328.026792) (xy 401.081041 -327.983035)
			(xy 401.040297 -327.933782) (xy 401.006048 -327.879812) (xy 400.978832 -327.821975) (xy 400.95908 -327.761183)
			(xy 400.947103 -327.698394) (xy 400.943089 -327.6346) (xy 398.788102 -327.6346) (xy 398.797395 -327.670793)
			(xy 398.805406 -327.734211) (xy 398.805908 -327.766172) (xy 398.805414 -327.796793) (xy 398.798051 -327.857591)
			(xy 398.78344 -327.917065) (xy 398.761792 -327.974354) (xy 398.733421 -328.028629) (xy 398.698737 -328.079103)
			(xy 398.658242 -328.125047) (xy 398.612524 -328.165795) (xy 398.562242 -328.200758) (xy 398.535398 -328.215498)
			(xy 398.527016 -328.22007) (xy 398.514824 -328.23404) (xy 398.485106 -328.316082) (xy 398.48536 -328.334624)
			(xy 398.488916 -328.343514) (xy 398.500818 -328.374069) (xy 398.517562 -328.437469) (xy 398.525999 -328.502497)
			(xy 398.526508 -328.535284) (xy 398.526006 -328.567245) (xy 398.517995 -328.630663) (xy 398.502098 -328.692577)
			(xy 398.478566 -328.75201) (xy 398.447772 -328.808025) (xy 398.410199 -328.85974) (xy 398.366442 -328.906337)
			(xy 398.317189 -328.947082) (xy 398.263218 -328.981333) (xy 398.205379 -329.00855) (xy 398.144586 -329.028303)
			(xy 398.081796 -329.040281) (xy 398.018 -329.044295) (xy 397.954204 -329.040281) (xy 397.891414 -329.028303)
			(xy 397.830621 -329.00855) (xy 397.772782 -328.981333) (xy 397.718811 -328.947082) (xy 397.669558 -328.906337)
			(xy 397.625801 -328.85974) (xy 397.588228 -328.808025) (xy 397.557434 -328.75201) (xy 397.533902 -328.692577)
			(xy 397.518005 -328.630663) (xy 397.509994 -328.567245) (xy 397.509492 -328.535284) (xy 395.758706 -328.535284)
			(xy 395.747009 -328.551384) (xy 395.703252 -328.597981) (xy 395.653999 -328.638726) (xy 395.600028 -328.672977)
			(xy 395.542189 -328.700194) (xy 395.481396 -328.719947) (xy 395.418606 -328.731925) (xy 395.35481 -328.735939)
			(xy 395.291014 -328.731925) (xy 395.228224 -328.719947) (xy 395.167431 -328.700194) (xy 395.109592 -328.672977)
			(xy 395.055621 -328.638726) (xy 395.006368 -328.597981) (xy 394.962611 -328.551384) (xy 394.925038 -328.499669)
			(xy 394.894244 -328.443654) (xy 394.870712 -328.384221) (xy 394.854815 -328.322307) (xy 394.846804 -328.258889)
			(xy 389.579595 -328.258889) (xy 389.98068 -329.320101) (xy 399.430234 -329.320101) (xy 399.430234 -329.256179)
			(xy 399.438245 -329.192761) (xy 399.454142 -329.130847) (xy 399.477674 -329.071414) (xy 399.508468 -329.015399)
			(xy 399.546041 -328.963684) (xy 399.589798 -328.917087) (xy 399.639051 -328.876342) (xy 399.693022 -328.842091)
			(xy 399.750861 -328.814874) (xy 399.811654 -328.795121) (xy 399.874444 -328.783143) (xy 399.93824 -328.77913)
			(xy 400.002036 -328.783143) (xy 400.064826 -328.795121) (xy 400.125619 -328.814874) (xy 400.183458 -328.842091)
			(xy 400.237429 -328.876342) (xy 400.286682 -328.917087) (xy 400.330439 -328.963684) (xy 400.368012 -329.015399)
			(xy 400.398806 -329.071414) (xy 400.422338 -329.130847) (xy 400.438235 -329.192761) (xy 400.444374 -329.241361)
			(xy 400.814534 -329.241361) (xy 400.814534 -329.177439) (xy 400.822545 -329.114021) (xy 400.838442 -329.052107)
			(xy 400.861974 -328.992674) (xy 400.892768 -328.936659) (xy 400.930341 -328.884944) (xy 400.974098 -328.838347)
			(xy 401.023351 -328.797602) (xy 401.077322 -328.763351) (xy 401.135161 -328.736134) (xy 401.195954 -328.716381)
			(xy 401.258744 -328.704403) (xy 401.32254 -328.70039) (xy 401.386336 -328.704403) (xy 401.449126 -328.716381)
			(xy 401.509919 -328.736134) (xy 401.567758 -328.763351) (xy 401.621729 -328.797602) (xy 401.670982 -328.838347)
			(xy 401.714739 -328.884944) (xy 401.752312 -328.936659) (xy 401.783106 -328.992674) (xy 401.806638 -329.052107)
			(xy 401.814666 -329.083373) (xy 402.378412 -329.083373) (xy 402.378412 -329.019451) (xy 402.386423 -328.956033)
			(xy 402.40232 -328.894119) (xy 402.425852 -328.834686) (xy 402.456646 -328.778671) (xy 402.494219 -328.726956)
			(xy 402.537976 -328.680359) (xy 402.587229 -328.639614) (xy 402.6412 -328.605363) (xy 402.699039 -328.578146)
			(xy 402.759832 -328.558393) (xy 402.822622 -328.546415) (xy 402.886418 -328.542402) (xy 402.950214 -328.546415)
			(xy 403.013004 -328.558393) (xy 403.073797 -328.578146) (xy 403.131636 -328.605363) (xy 403.185607 -328.639614)
			(xy 403.23486 -328.680359) (xy 403.278617 -328.726956) (xy 403.31619 -328.778671) (xy 403.346984 -328.834686)
			(xy 403.370516 -328.894119) (xy 403.386413 -328.956033) (xy 403.392365 -329.003152) (xy 404.630888 -329.003152)
			(xy 404.634959 -328.94753) (xy 404.647085 -328.893093) (xy 404.667008 -328.841002) (xy 404.694304 -328.792367)
			(xy 404.72839 -328.748224) (xy 404.768539 -328.709515) (xy 404.813897 -328.677064) (xy 404.863497 -328.651563)
			(xy 404.916281 -328.633556) (xy 404.971124 -328.623426) (xy 405.026858 -328.621389) (xy 405.082295 -328.627489)
			(xy 405.136252 -328.641595) (xy 405.187581 -328.663407) (xy 405.235187 -328.692461) (xy 405.278055 -328.728136)
			(xy 405.315272 -328.769673) (xy 405.346045 -328.816186) (xy 405.366158 -328.859091) (xy 407.253434 -328.859091)
			(xy 407.253434 -328.795169) (xy 407.261445 -328.731751) (xy 407.277342 -328.669837) (xy 407.300874 -328.610404)
			(xy 407.331668 -328.554389) (xy 407.369241 -328.502674) (xy 407.412998 -328.456077) (xy 407.462251 -328.415332)
			(xy 407.516222 -328.381081) (xy 407.574061 -328.353864) (xy 407.634854 -328.334111) (xy 407.697644 -328.322133)
			(xy 407.76144 -328.31812) (xy 407.825236 -328.322133) (xy 407.888026 -328.334111) (xy 407.948819 -328.353864)
			(xy 408.006658 -328.381081) (xy 408.060629 -328.415332) (xy 408.109882 -328.456077) (xy 408.153639 -328.502674)
			(xy 408.191212 -328.554389) (xy 408.222006 -328.610404) (xy 408.245538 -328.669837) (xy 408.261435 -328.731751)
			(xy 408.269446 -328.795169) (xy 408.269948 -328.82713) (xy 408.269446 -328.859091) (xy 408.261435 -328.922509)
			(xy 408.245538 -328.984423) (xy 408.222006 -329.043856) (xy 408.191212 -329.099871) (xy 408.153639 -329.151586)
			(xy 408.109882 -329.198183) (xy 408.060629 -329.238928) (xy 408.006658 -329.273179) (xy 407.948819 -329.300396)
			(xy 407.888026 -329.320149) (xy 407.825236 -329.332127) (xy 407.76144 -329.336141) (xy 407.697644 -329.332127)
			(xy 407.634854 -329.320149) (xy 407.574061 -329.300396) (xy 407.516222 -329.273179) (xy 407.462251 -329.238928)
			(xy 407.412998 -329.198183) (xy 407.369241 -329.151586) (xy 407.331668 -329.099871) (xy 407.300874 -329.043856)
			(xy 407.277342 -328.984423) (xy 407.261445 -328.922509) (xy 407.253434 -328.859091) (xy 405.366158 -328.859091)
			(xy 405.369717 -328.866683) (xy 405.385785 -328.92009) (xy 405.393905 -328.975266) (xy 405.394414 -329.003152)
			(xy 405.393905 -329.031038) (xy 405.385785 -329.086214) (xy 405.369717 -329.139621) (xy 405.346045 -329.190118)
			(xy 405.315272 -329.236631) (xy 405.278055 -329.278168) (xy 405.235187 -329.313843) (xy 405.187581 -329.342897)
			(xy 405.136252 -329.364709) (xy 405.082295 -329.378815) (xy 405.026858 -329.384915) (xy 404.971124 -329.382878)
			(xy 404.916281 -329.372748) (xy 404.863497 -329.354741) (xy 404.813897 -329.32924) (xy 404.768539 -329.296789)
			(xy 404.72839 -329.25808) (xy 404.694304 -329.213937) (xy 404.667008 -329.165302) (xy 404.647085 -329.113211)
			(xy 404.634959 -329.058774) (xy 404.630888 -329.003152) (xy 403.392365 -329.003152) (xy 403.394424 -329.019451)
			(xy 403.394926 -329.051412) (xy 403.394424 -329.083373) (xy 403.386413 -329.146791) (xy 403.370516 -329.208705)
			(xy 403.346984 -329.268138) (xy 403.31619 -329.324153) (xy 403.278617 -329.375868) (xy 403.23486 -329.422465)
			(xy 403.185607 -329.46321) (xy 403.131636 -329.497461) (xy 403.073797 -329.524678) (xy 403.013004 -329.544431)
			(xy 402.950214 -329.556409) (xy 402.886418 -329.560423) (xy 402.822622 -329.556409) (xy 402.759832 -329.544431)
			(xy 402.699039 -329.524678) (xy 402.6412 -329.497461) (xy 402.587229 -329.46321) (xy 402.537976 -329.422465)
			(xy 402.494219 -329.375868) (xy 402.456646 -329.324153) (xy 402.425852 -329.268138) (xy 402.40232 -329.208705)
			(xy 402.386423 -329.146791) (xy 402.378412 -329.083373) (xy 401.814666 -329.083373) (xy 401.822535 -329.114021)
			(xy 401.830546 -329.177439) (xy 401.831048 -329.2094) (xy 401.830546 -329.241361) (xy 401.822535 -329.304779)
			(xy 401.806638 -329.366693) (xy 401.783106 -329.426126) (xy 401.752312 -329.482141) (xy 401.714739 -329.533856)
			(xy 401.670982 -329.580453) (xy 401.621729 -329.621198) (xy 401.567758 -329.655449) (xy 401.509919 -329.682666)
			(xy 401.449126 -329.702419) (xy 401.386336 -329.714397) (xy 401.32254 -329.718411) (xy 401.258744 -329.714397)
			(xy 401.195954 -329.702419) (xy 401.135161 -329.682666) (xy 401.077322 -329.655449) (xy 401.023351 -329.621198)
			(xy 400.974098 -329.580453) (xy 400.930341 -329.533856) (xy 400.892768 -329.482141) (xy 400.861974 -329.426126)
			(xy 400.838442 -329.366693) (xy 400.822545 -329.304779) (xy 400.814534 -329.241361) (xy 400.444374 -329.241361)
			(xy 400.446246 -329.256179) (xy 400.446748 -329.28814) (xy 400.446246 -329.320101) (xy 400.438235 -329.383519)
			(xy 400.422338 -329.445433) (xy 400.398806 -329.504866) (xy 400.368012 -329.560881) (xy 400.330439 -329.612596)
			(xy 400.286682 -329.659193) (xy 400.237429 -329.699938) (xy 400.183458 -329.734189) (xy 400.125619 -329.761406)
			(xy 400.064826 -329.781159) (xy 400.002036 -329.793137) (xy 399.93824 -329.797151) (xy 399.874444 -329.793137)
			(xy 399.811654 -329.781159) (xy 399.750861 -329.761406) (xy 399.693022 -329.734189) (xy 399.639051 -329.699938)
			(xy 399.589798 -329.659193) (xy 399.546041 -329.612596) (xy 399.508468 -329.560881) (xy 399.477674 -329.504866)
			(xy 399.454142 -329.445433) (xy 399.438245 -329.383519) (xy 399.430234 -329.320101) (xy 389.98068 -329.320101)
			(xy 390.589987 -330.932239) (xy 394.518382 -330.932239) (xy 394.518382 -330.868317) (xy 394.526393 -330.804899)
			(xy 394.54229 -330.742985) (xy 394.565822 -330.683552) (xy 394.596616 -330.627537) (xy 394.634189 -330.575822)
			(xy 394.677946 -330.529225) (xy 394.727199 -330.48848) (xy 394.78117 -330.454229) (xy 394.839009 -330.427012)
			(xy 394.899802 -330.407259) (xy 394.962592 -330.395281) (xy 395.026388 -330.391268) (xy 395.090184 -330.395281)
			(xy 395.152974 -330.407259) (xy 395.213767 -330.427012) (xy 395.271606 -330.454229) (xy 395.325577 -330.48848)
			(xy 395.37483 -330.529225) (xy 395.418587 -330.575822) (xy 395.45616 -330.627537) (xy 395.486954 -330.683552)
			(xy 395.510486 -330.742985) (xy 395.526383 -330.804899) (xy 395.534394 -330.868317) (xy 395.534896 -330.900278)
			(xy 395.534394 -330.932239) (xy 395.526383 -330.995657) (xy 395.52459 -331.00264) (xy 398.885156 -331.00264)
			(xy 398.885658 -330.970679) (xy 398.893669 -330.907261) (xy 398.909566 -330.845347) (xy 398.933098 -330.785914)
			(xy 398.963892 -330.729899) (xy 399.001465 -330.678184) (xy 399.045222 -330.631587) (xy 399.094475 -330.590842)
			(xy 399.148446 -330.556591) (xy 399.206285 -330.529374) (xy 399.267078 -330.509621) (xy 399.329868 -330.497643)
			(xy 399.393664 -330.49363) (xy 399.45746 -330.497643) (xy 399.52025 -330.509621) (xy 399.581043 -330.529374)
			(xy 399.638882 -330.556591) (xy 399.692853 -330.590842) (xy 399.742106 -330.631587) (xy 399.785863 -330.678184)
			(xy 399.823436 -330.729899) (xy 399.85423 -330.785914) (xy 399.877762 -330.845347) (xy 399.893659 -330.907261)
			(xy 399.90167 -330.970679) (xy 399.902172 -331.00264) (xy 399.901716 -331.032835) (xy 399.894535 -331.092797)
			(xy 399.880304 -331.151486) (xy 399.870168 -331.179932) (xy 399.865596 -331.192632) (xy 399.869914 -331.219302)
			(xy 399.94205 -331.308202) (xy 399.967196 -331.317854) (xy 399.980658 -331.315822) (xy 399.999407 -331.313201)
			(xy 400.037165 -331.310401) (xy 400.056096 -331.310234) (xy 400.088061 -331.310631) (xy 400.151487 -331.318643)
			(xy 400.213409 -331.334541) (xy 400.240548 -331.345286) (xy 402.47697 -331.345286) (xy 402.477443 -331.314556)
			(xy 402.484853 -331.253543) (xy 402.499562 -331.193868) (xy 402.521357 -331.136401) (xy 402.54992 -331.081981)
			(xy 402.584833 -331.031399) (xy 402.625589 -330.985395) (xy 402.671593 -330.944638) (xy 402.722174 -330.909724)
			(xy 402.776594 -330.88116) (xy 402.834061 -330.859364) (xy 402.893735 -330.844654) (xy 402.954748 -330.837243)
			(xy 402.985478 -330.836778) (xy 403.017697 -330.837294) (xy 403.08162 -330.845432) (xy 403.144002 -330.861581)
			(xy 403.203844 -330.885482) (xy 403.260187 -330.916751) (xy 403.312128 -330.954889) (xy 403.358834 -330.999282)
			(xy 403.399558 -331.049221) (xy 403.417024 -331.0763) (xy 403.422358 -331.084936) (xy 403.43836 -331.096366)
			(xy 403.527768 -331.117702) (xy 403.547326 -331.1144) (xy 403.555962 -331.109066) (xy 403.585976 -331.091432)
			(xy 403.64982 -331.063681) (xy 403.716854 -331.044902) (xy 403.785823 -331.035447) (xy 403.82063 -331.034898)
			(xy 403.851362 -331.035328) (xy 403.912377 -331.04274) (xy 403.972054 -331.057452) (xy 404.029523 -331.07925)
			(xy 404.030596 -331.079813) (xy 408.089602 -331.079813) (xy 408.089602 -331.015891) (xy 408.097613 -330.952473)
			(xy 408.11351 -330.890559) (xy 408.137042 -330.831126) (xy 408.167836 -330.775111) (xy 408.205409 -330.723396)
			(xy 408.249166 -330.676799) (xy 408.298419 -330.636054) (xy 408.35239 -330.601803) (xy 408.410229 -330.574586)
			(xy 408.471022 -330.554833) (xy 408.533812 -330.542855) (xy 408.597608 -330.538842) (xy 408.661404 -330.542855)
			(xy 408.724194 -330.554833) (xy 408.784987 -330.574586) (xy 408.842826 -330.601803) (xy 408.896797 -330.636054)
			(xy 408.94605 -330.676799) (xy 408.989807 -330.723396) (xy 409.02738 -330.775111) (xy 409.058174 -330.831126)
			(xy 409.081706 -330.890559) (xy 409.097603 -330.952473) (xy 409.105614 -331.015891) (xy 409.106116 -331.047852)
			(xy 409.105614 -331.079813) (xy 409.097603 -331.143231) (xy 409.081706 -331.205145) (xy 409.058174 -331.264578)
			(xy 409.02738 -331.320593) (xy 408.989807 -331.372308) (xy 408.94605 -331.418905) (xy 408.896797 -331.45965)
			(xy 408.842826 -331.493901) (xy 408.784987 -331.521118) (xy 408.724194 -331.540871) (xy 408.661404 -331.552849)
			(xy 408.597608 -331.556863) (xy 408.533812 -331.552849) (xy 408.471022 -331.540871) (xy 408.410229 -331.521118)
			(xy 408.35239 -331.493901) (xy 408.298419 -331.45965) (xy 408.249166 -331.418905) (xy 408.205409 -331.372308)
			(xy 408.167836 -331.320593) (xy 408.137042 -331.264578) (xy 408.11351 -331.205145) (xy 408.097613 -331.143231)
			(xy 408.089602 -331.079813) (xy 404.030596 -331.079813) (xy 404.083945 -331.107816) (xy 404.134527 -331.142734)
			(xy 404.180532 -331.183494) (xy 404.221288 -331.229501) (xy 404.256202 -331.280086) (xy 404.284764 -331.33451)
			(xy 404.306558 -331.39198) (xy 404.321267 -331.451658) (xy 404.328674 -331.512674) (xy 404.329138 -331.543406)
			(xy 404.328664 -331.576088) (xy 404.320287 -331.640913) (xy 404.303672 -331.70413) (xy 404.279093 -331.764697)
			(xy 404.246954 -331.821615) (xy 404.207787 -331.873945) (xy 404.185374 -331.897736) (xy 404.175722 -331.907642)
			(xy 404.169118 -331.933296) (xy 404.19909 -332.043786) (xy 404.217632 -332.062582) (xy 404.23084 -332.066392)
			(xy 404.262492 -332.07581) (xy 404.323256 -332.101666) (xy 404.380161 -332.135172) (xy 404.432249 -332.175763)
			(xy 404.478643 -332.222757) (xy 404.518563 -332.275361) (xy 404.551337 -332.332691) (xy 404.576412 -332.393782)
			(xy 404.593367 -332.457605) (xy 404.601916 -332.523086) (xy 404.602442 -332.556104) (xy 404.60194 -332.588065)
			(xy 404.593929 -332.651483) (xy 404.586723 -332.679548) (xy 405.63927 -332.679548) (xy 405.639799 -332.646088)
			(xy 405.648566 -332.579745) (xy 405.665967 -332.515128) (xy 405.691702 -332.453354) (xy 405.725324 -332.395494)
			(xy 405.766251 -332.342549) (xy 405.789638 -332.318614) (xy 405.796242 -332.31201) (xy 405.803862 -332.295754)
			(xy 405.809958 -332.210664) (xy 405.805132 -332.193392) (xy 405.799544 -332.185772) (xy 405.780481 -332.159356)
			(xy 405.748545 -332.102575) (xy 405.724116 -332.042184) (xy 405.707591 -331.979169) (xy 405.699243 -331.91456)
			(xy 405.698706 -331.881988) (xy 405.699208 -331.850027) (xy 405.707219 -331.786609) (xy 405.723116 -331.724695)
			(xy 405.746648 -331.665262) (xy 405.777442 -331.609247) (xy 405.815015 -331.557532) (xy 405.858772 -331.510935)
			(xy 405.908025 -331.47019) (xy 405.961996 -331.435939) (xy 406.019835 -331.408722) (xy 406.080628 -331.388969)
			(xy 406.143418 -331.376991) (xy 406.207214 -331.372978) (xy 406.27101 -331.376991) (xy 406.3338 -331.388969)
			(xy 406.394593 -331.408722) (xy 406.452432 -331.435939) (xy 406.506403 -331.47019) (xy 406.555656 -331.510935)
			(xy 406.599413 -331.557532) (xy 406.636986 -331.609247) (xy 406.66778 -331.665262) (xy 406.691312 -331.724695)
			(xy 406.707209 -331.786609) (xy 406.707707 -331.790548) (xy 406.90876 -331.790548) (xy 406.912831 -331.734926)
			(xy 406.924957 -331.680489) (xy 406.94488 -331.628398) (xy 406.972176 -331.579763) (xy 407.006262 -331.53562)
			(xy 407.046411 -331.496911) (xy 407.091769 -331.46446) (xy 407.141369 -331.438959) (xy 407.194153 -331.420952)
			(xy 407.248996 -331.410822) (xy 407.30473 -331.408785) (xy 407.360167 -331.414885) (xy 407.414124 -331.428991)
			(xy 407.465453 -331.450803) (xy 407.513059 -331.479857) (xy 407.555927 -331.515532) (xy 407.593144 -331.557069)
			(xy 407.623917 -331.603582) (xy 407.647589 -331.654079) (xy 407.663657 -331.707486) (xy 407.671777 -331.762662)
			(xy 407.672286 -331.790548) (xy 407.671777 -331.818434) (xy 407.663657 -331.87361) (xy 407.647589 -331.927017)
			(xy 407.623917 -331.977514) (xy 407.593144 -332.024027) (xy 407.555927 -332.065564) (xy 407.513059 -332.101239)
			(xy 407.465453 -332.130293) (xy 407.414124 -332.152105) (xy 407.360167 -332.166211) (xy 407.30473 -332.172311)
			(xy 407.248996 -332.170274) (xy 407.194153 -332.160144) (xy 407.141369 -332.142137) (xy 407.091769 -332.116636)
			(xy 407.046411 -332.084185) (xy 407.006262 -332.045476) (xy 406.972176 -332.001333) (xy 406.94488 -331.952698)
			(xy 406.924957 -331.900607) (xy 406.912831 -331.84617) (xy 406.90876 -331.790548) (xy 406.707707 -331.790548)
			(xy 406.71522 -331.850027) (xy 406.715722 -331.881988) (xy 406.715218 -331.915449) (xy 406.706447 -331.981793)
			(xy 406.689041 -332.046411) (xy 406.663302 -332.108184) (xy 406.629675 -332.166044) (xy 406.588743 -332.218987)
			(xy 406.565354 -332.242922) (xy 406.55875 -332.249526) (xy 406.55113 -332.265782) (xy 406.545034 -332.350872)
			(xy 406.54986 -332.368144) (xy 406.555448 -332.375764) (xy 406.574481 -332.402201) (xy 406.606422 -332.458976)
			(xy 406.630858 -332.519362) (xy 406.647389 -332.582372) (xy 406.655745 -332.646977) (xy 406.656286 -332.679548)
			(xy 406.655784 -332.711509) (xy 406.647773 -332.774927) (xy 406.631876 -332.836841) (xy 406.608344 -332.896274)
			(xy 406.57755 -332.952289) (xy 406.539977 -333.004004) (xy 406.527666 -333.017114) (xy 412.326074 -333.017114)
			(xy 412.326516 -332.979937) (xy 412.333767 -332.905936) (xy 412.348191 -332.832993) (xy 412.36965 -332.761802)
			(xy 412.397942 -332.69304) (xy 412.414974 -332.65999) (xy 412.420272 -332.64863) (xy 412.420278 -332.623594)
			(xy 412.414974 -332.612238) (xy 412.397952 -332.579185) (xy 412.369676 -332.510418) (xy 412.348224 -332.439227)
			(xy 412.333798 -332.366287) (xy 412.326535 -332.29229) (xy 412.326074 -332.255114) (xy 412.326563 -332.216469)
			(xy 412.334383 -332.139575) (xy 412.349941 -332.063867) (xy 412.373079 -331.990121) (xy 412.403559 -331.919094)
			(xy 412.441068 -331.851516) (xy 412.485222 -331.788078) (xy 412.535567 -331.729434) (xy 412.591586 -331.676183)
			(xy 412.652705 -331.628873) (xy 412.718298 -331.587989) (xy 412.787689 -331.553951) (xy 412.860169 -331.527108)
			(xy 412.934992 -331.507735) (xy 413.011391 -331.496031) (xy 413.088582 -331.492116) (xy 413.165773 -331.496031)
			(xy 413.242172 -331.507735) (xy 413.316995 -331.527108) (xy 413.389475 -331.553951) (xy 413.458866 -331.587989)
			(xy 413.524459 -331.628873) (xy 413.585578 -331.676183) (xy 413.641597 -331.729434) (xy 413.691942 -331.788078)
			(xy 413.736096 -331.851516) (xy 413.740744 -331.85989) (xy 419.01999 -331.85989) (xy 419.02051 -331.831151)
			(xy 419.029134 -331.774324) (xy 419.046185 -331.719433) (xy 419.071277 -331.667721) (xy 419.103843 -331.620359)
			(xy 419.123114 -331.599032) (xy 419.129718 -331.59192) (xy 419.13683 -331.574394) (xy 419.13683 -331.484986)
			(xy 419.129718 -331.46746) (xy 419.123114 -331.460348) (xy 419.103834 -331.43903) (xy 419.07127 -331.391665)
			(xy 419.046179 -331.339952) (xy 419.02913 -331.28506) (xy 419.020509 -331.228232) (xy 419.02051 -331.170753)
			(xy 419.029134 -331.113925) (xy 419.046185 -331.059034) (xy 419.071277 -331.007322) (xy 419.103843 -330.959959)
			(xy 419.123114 -330.938632) (xy 419.129718 -330.93152) (xy 419.13683 -330.913994) (xy 419.13683 -330.824586)
			(xy 419.129718 -330.80706) (xy 419.123114 -330.799948) (xy 419.103834 -330.77863) (xy 419.07127 -330.731265)
			(xy 419.046179 -330.679552) (xy 419.02913 -330.62466) (xy 419.020509 -330.567832) (xy 419.02051 -330.510353)
			(xy 419.029134 -330.453525) (xy 419.046185 -330.398634) (xy 419.071277 -330.346922) (xy 419.103843 -330.299559)
			(xy 419.123114 -330.278232) (xy 419.129718 -330.27112) (xy 419.13683 -330.253594) (xy 419.13683 -330.164186)
			(xy 419.129718 -330.14666) (xy 419.123114 -330.139548) (xy 419.103835 -330.118229) (xy 419.07127 -330.070864)
			(xy 419.04618 -330.01915) (xy 419.029131 -329.964258) (xy 419.02051 -329.907429) (xy 419.01999 -329.87869)
			(xy 419.020476 -329.851439) (xy 419.028232 -329.797491) (xy 419.043587 -329.745196) (xy 419.066229 -329.695619)
			(xy 419.095695 -329.649769) (xy 419.131386 -329.608578) (xy 419.172577 -329.572887) (xy 419.218427 -329.543421)
			(xy 419.268004 -329.520779) (xy 419.320299 -329.505424) (xy 419.374247 -329.497668) (xy 419.428749 -329.497668)
			(xy 419.482697 -329.505424) (xy 419.534992 -329.520779) (xy 419.584569 -329.543421) (xy 419.630419 -329.572887)
			(xy 419.67161 -329.608578) (xy 419.707301 -329.649769) (xy 419.736767 -329.695619) (xy 419.759409 -329.745196)
			(xy 419.774764 -329.797491) (xy 419.78252 -329.851439) (xy 419.783006 -329.87869) (xy 419.782475 -329.907429)
			(xy 419.773854 -329.964256) (xy 419.756805 -330.019146) (xy 419.731715 -330.070858) (xy 419.699152 -330.118221)
			(xy 419.679882 -330.139548) (xy 419.673278 -330.14666) (xy 419.666166 -330.164186) (xy 419.666166 -330.253594)
			(xy 419.673278 -330.27112) (xy 419.679882 -330.278232) (xy 419.699143 -330.299568) (xy 419.731708 -330.346929)
			(xy 419.756799 -330.398639) (xy 419.77385 -330.453528) (xy 419.782473 -330.510354) (xy 419.782474 -330.567831)
			(xy 419.773853 -330.624657) (xy 419.756805 -330.679547) (xy 419.731715 -330.731259) (xy 419.699152 -330.778621)
			(xy 419.679882 -330.799948) (xy 419.673278 -330.80706) (xy 419.666166 -330.824586) (xy 419.666166 -330.913994)
			(xy 419.673278 -330.93152) (xy 419.679882 -330.938632) (xy 419.699143 -330.959968) (xy 419.731708 -331.007329)
			(xy 419.756799 -331.059039) (xy 419.77385 -331.113928) (xy 419.782473 -331.170754) (xy 419.782474 -331.228231)
			(xy 419.773853 -331.285057) (xy 419.756805 -331.339947) (xy 419.731715 -331.391659) (xy 419.699152 -331.439021)
			(xy 419.679882 -331.460348) (xy 419.673278 -331.46746) (xy 419.666166 -331.484986) (xy 419.666166 -331.574394)
			(xy 419.673278 -331.59192) (xy 419.679882 -331.599032) (xy 419.699151 -331.62036) (xy 419.731717 -331.667722)
			(xy 419.756809 -331.719434) (xy 419.77386 -331.774324) (xy 419.782484 -331.831151) (xy 419.783006 -331.85989)
			(xy 421.409368 -331.85989) (xy 421.409894 -331.831151) (xy 421.418518 -331.774324) (xy 421.435567 -331.719434)
			(xy 421.460658 -331.667722) (xy 421.493222 -331.620359) (xy 421.512492 -331.599032) (xy 421.519096 -331.59192)
			(xy 421.526208 -331.574394) (xy 421.526208 -331.484986) (xy 421.519096 -331.46746) (xy 421.512492 -331.460348)
			(xy 421.493213 -331.439029) (xy 421.46065 -331.391664) (xy 421.435562 -331.339951) (xy 421.418514 -331.285059)
			(xy 421.409893 -331.228232) (xy 421.409894 -331.170754) (xy 421.418517 -331.113926) (xy 421.435567 -331.059035)
			(xy 421.460658 -331.007323) (xy 421.493222 -330.95996) (xy 421.512492 -330.938632) (xy 421.519096 -330.93152)
			(xy 421.526208 -330.913994) (xy 421.526208 -330.824586) (xy 421.519096 -330.80706) (xy 421.512492 -330.799948)
			(xy 421.493213 -330.778629) (xy 421.46065 -330.731264) (xy 421.435562 -330.679551) (xy 421.418514 -330.624659)
			(xy 421.409893 -330.567832) (xy 421.409894 -330.510354) (xy 421.418517 -330.453526) (xy 421.435567 -330.398635)
			(xy 421.460658 -330.346923) (xy 421.493222 -330.29956) (xy 421.512492 -330.278232) (xy 421.519096 -330.27112)
			(xy 421.526208 -330.253594) (xy 421.526208 -330.164186) (xy 421.519096 -330.14666) (xy 421.512492 -330.139548)
			(xy 421.493226 -330.118217) (xy 421.460657 -330.070857) (xy 421.435563 -330.019146) (xy 421.418511 -329.964256)
			(xy 421.409889 -329.907429) (xy 421.409368 -329.87869) (xy 421.409854 -329.851439) (xy 421.41761 -329.797491)
			(xy 421.432965 -329.745196) (xy 421.455607 -329.695619) (xy 421.485073 -329.649769) (xy 421.520764 -329.608578)
			(xy 421.561955 -329.572887) (xy 421.607805 -329.543421) (xy 421.657382 -329.520779) (xy 421.709677 -329.505424)
			(xy 421.763625 -329.497668) (xy 421.818127 -329.497668) (xy 421.872075 -329.505424) (xy 421.92437 -329.520779)
			(xy 421.973947 -329.543421) (xy 422.019797 -329.572887) (xy 422.060988 -329.608578) (xy 422.096679 -329.649769)
			(xy 422.126145 -329.695619) (xy 422.148787 -329.745196) (xy 422.164142 -329.797491) (xy 422.171898 -329.851439)
			(xy 422.172384 -329.87869) (xy 422.171832 -329.907428) (xy 422.163213 -329.964253) (xy 422.146168 -330.019142)
			(xy 422.121083 -330.070854) (xy 422.088526 -330.118219) (xy 422.06926 -330.139548) (xy 422.062656 -330.14666)
			(xy 422.055544 -330.164186) (xy 422.055544 -330.253594) (xy 422.062656 -330.27112) (xy 422.06926 -330.278232)
			(xy 422.088522 -330.299567) (xy 422.121089 -330.346928) (xy 422.146182 -330.398638) (xy 422.163233 -330.453528)
			(xy 422.171857 -330.510354) (xy 422.171858 -330.567831) (xy 422.163237 -330.624658) (xy 422.146187 -330.679548)
			(xy 422.121096 -330.73126) (xy 422.088531 -330.778622) (xy 422.06926 -330.799948) (xy 422.062656 -330.80706)
			(xy 422.055544 -330.824586) (xy 422.055544 -330.913994) (xy 422.062656 -330.93152) (xy 422.06926 -330.938632)
			(xy 422.088522 -330.959967) (xy 422.121089 -331.007328) (xy 422.146182 -331.059038) (xy 422.163233 -331.113928)
			(xy 422.171857 -331.170754) (xy 422.171858 -331.228231) (xy 422.163237 -331.285058) (xy 422.146187 -331.339948)
			(xy 422.121096 -331.39166) (xy 422.088531 -331.439022) (xy 422.06926 -331.460348) (xy 422.062656 -331.46746)
			(xy 422.055544 -331.484986) (xy 422.055544 -331.574394) (xy 422.062656 -331.59192) (xy 422.06926 -331.599032)
			(xy 422.088526 -331.620363) (xy 422.121093 -331.667724) (xy 422.146186 -331.719435) (xy 422.163238 -331.774325)
			(xy 422.171862 -331.831151) (xy 422.172384 -331.85989) (xy 425.11599 -331.85989) (xy 425.11651 -331.831151)
			(xy 425.125134 -331.774324) (xy 425.142185 -331.719433) (xy 425.167277 -331.667721) (xy 425.199843 -331.620359)
			(xy 425.219114 -331.599032) (xy 425.225718 -331.59192) (xy 425.23283 -331.574394) (xy 425.23283 -331.484986)
			(xy 425.225718 -331.46746) (xy 425.219114 -331.460348) (xy 425.199834 -331.43903) (xy 425.16727 -331.391665)
			(xy 425.142179 -331.339952) (xy 425.12513 -331.28506) (xy 425.116509 -331.228232) (xy 425.11651 -331.170753)
			(xy 425.125134 -331.113925) (xy 425.142185 -331.059034) (xy 425.167277 -331.007322) (xy 425.199843 -330.959959)
			(xy 425.219114 -330.938632) (xy 425.225718 -330.93152) (xy 425.23283 -330.913994) (xy 425.23283 -330.824586)
			(xy 425.225718 -330.80706) (xy 425.219114 -330.799948) (xy 425.199834 -330.77863) (xy 425.16727 -330.731265)
			(xy 425.142179 -330.679552) (xy 425.12513 -330.62466) (xy 425.116509 -330.567832) (xy 425.11651 -330.510353)
			(xy 425.125134 -330.453525) (xy 425.142185 -330.398634) (xy 425.167277 -330.346922) (xy 425.199843 -330.299559)
			(xy 425.219114 -330.278232) (xy 425.225718 -330.27112) (xy 425.23283 -330.253594) (xy 425.23283 -330.164186)
			(xy 425.225718 -330.14666) (xy 425.219114 -330.139548) (xy 425.199835 -330.118229) (xy 425.16727 -330.070864)
			(xy 425.14218 -330.01915) (xy 425.125131 -329.964258) (xy 425.11651 -329.907429) (xy 425.11599 -329.87869)
			(xy 425.116476 -329.851439) (xy 425.124232 -329.797491) (xy 425.139587 -329.745196) (xy 425.162229 -329.695619)
			(xy 425.191695 -329.649769) (xy 425.227386 -329.608578) (xy 425.268577 -329.572887) (xy 425.314427 -329.543421)
			(xy 425.364004 -329.520779) (xy 425.416299 -329.505424) (xy 425.470247 -329.497668) (xy 425.524749 -329.497668)
			(xy 425.578697 -329.505424) (xy 425.630992 -329.520779) (xy 425.680569 -329.543421) (xy 425.726419 -329.572887)
			(xy 425.76761 -329.608578) (xy 425.803301 -329.649769) (xy 425.832767 -329.695619) (xy 425.855409 -329.745196)
			(xy 425.870764 -329.797491) (xy 425.87852 -329.851439) (xy 425.879006 -329.87869) (xy 425.878475 -329.907429)
			(xy 425.869854 -329.964256) (xy 425.852805 -330.019146) (xy 425.827715 -330.070858) (xy 425.795152 -330.118221)
			(xy 425.775882 -330.139548) (xy 425.769278 -330.14666) (xy 425.762166 -330.164186) (xy 425.762166 -330.253594)
			(xy 425.769278 -330.27112) (xy 425.775882 -330.278232) (xy 425.795143 -330.299568) (xy 425.827708 -330.346929)
			(xy 425.852799 -330.398639) (xy 425.86985 -330.453528) (xy 425.878473 -330.510354) (xy 425.878474 -330.567831)
			(xy 425.869853 -330.624657) (xy 425.852805 -330.679547) (xy 425.827715 -330.731259) (xy 425.795152 -330.778621)
			(xy 425.775882 -330.799948) (xy 425.769278 -330.80706) (xy 425.762166 -330.824586) (xy 425.762166 -330.913994)
			(xy 425.769278 -330.93152) (xy 425.775882 -330.938632) (xy 425.795143 -330.959968) (xy 425.827708 -331.007329)
			(xy 425.852799 -331.059039) (xy 425.86985 -331.113928) (xy 425.878473 -331.170754) (xy 425.878474 -331.228231)
			(xy 425.869853 -331.285057) (xy 425.852805 -331.339947) (xy 425.827715 -331.391659) (xy 425.795152 -331.439021)
			(xy 425.775882 -331.460348) (xy 425.769278 -331.46746) (xy 425.762166 -331.484986) (xy 425.762166 -331.574394)
			(xy 425.769278 -331.59192) (xy 425.775882 -331.599032) (xy 425.795151 -331.62036) (xy 425.827717 -331.667722)
			(xy 425.852809 -331.719434) (xy 425.86986 -331.774324) (xy 425.871281 -331.78369) (xy 427.534324 -331.78369)
			(xy 427.534862 -331.754952) (xy 427.543484 -331.698126) (xy 427.560532 -331.643236) (xy 427.58562 -331.591524)
			(xy 427.61818 -331.54416) (xy 427.637448 -331.522832) (xy 427.644052 -331.51572) (xy 427.651164 -331.498194)
			(xy 427.651164 -331.408786) (xy 427.644052 -331.39126) (xy 427.637448 -331.384148) (xy 427.618166 -331.36283)
			(xy 427.585599 -331.315467) (xy 427.560507 -331.263754) (xy 427.543456 -331.208862) (xy 427.534834 -331.152032)
			(xy 427.534835 -331.094553) (xy 427.543459 -331.037724) (xy 427.560512 -330.982833) (xy 427.585607 -330.93112)
			(xy 427.618175 -330.883758) (xy 427.637448 -330.862432) (xy 427.644052 -330.85532) (xy 427.651164 -330.837794)
			(xy 427.651164 -330.748386) (xy 427.644052 -330.73086) (xy 427.637448 -330.723748) (xy 427.618166 -330.70243)
			(xy 427.585599 -330.655067) (xy 427.560507 -330.603354) (xy 427.543456 -330.548462) (xy 427.534834 -330.491632)
			(xy 427.534835 -330.434153) (xy 427.543459 -330.377324) (xy 427.560512 -330.322433) (xy 427.585607 -330.27072)
			(xy 427.618175 -330.223358) (xy 427.637448 -330.202032) (xy 427.644052 -330.19492) (xy 427.651164 -330.177394)
			(xy 427.651164 -330.087986) (xy 427.644052 -330.07046) (xy 427.637448 -330.063348) (xy 427.618174 -330.042024)
			(xy 427.585608 -329.994661) (xy 427.560516 -329.942949) (xy 427.543466 -329.888057) (xy 427.534844 -329.831229)
			(xy 427.534324 -329.80249) (xy 427.53481 -329.775239) (xy 427.542566 -329.721291) (xy 427.557921 -329.668996)
			(xy 427.580563 -329.619419) (xy 427.610029 -329.573569) (xy 427.64572 -329.532378) (xy 427.686911 -329.496687)
			(xy 427.732761 -329.467221) (xy 427.782338 -329.444579) (xy 427.834633 -329.429224) (xy 427.888581 -329.421468)
			(xy 427.943083 -329.421468) (xy 427.997031 -329.429224) (xy 428.049326 -329.444579) (xy 428.098903 -329.467221)
			(xy 428.144753 -329.496687) (xy 428.185944 -329.532378) (xy 428.221635 -329.573569) (xy 428.251101 -329.619419)
			(xy 428.273743 -329.668996) (xy 428.289098 -329.721291) (xy 428.296854 -329.775239) (xy 428.29734 -329.80249)
			(xy 428.296799 -329.831228) (xy 428.288179 -329.888054) (xy 428.271133 -329.942944) (xy 428.246045 -329.994656)
			(xy 428.213484 -330.04202) (xy 428.194216 -330.063348) (xy 428.187612 -330.07046) (xy 428.1805 -330.087986)
			(xy 428.1805 -330.177394) (xy 428.187612 -330.19492) (xy 428.194216 -330.202032) (xy 428.213475 -330.223368)
			(xy 428.246037 -330.27073) (xy 428.271127 -330.322441) (xy 428.288176 -330.37733) (xy 428.296798 -330.434155)
			(xy 428.296799 -330.491631) (xy 428.288179 -330.548456) (xy 428.271132 -330.603346) (xy 428.246045 -330.655057)
			(xy 428.213484 -330.70242) (xy 428.194216 -330.723748) (xy 428.187612 -330.73086) (xy 428.1805 -330.748386)
			(xy 428.1805 -330.837794) (xy 428.187612 -330.85532) (xy 428.194216 -330.862432) (xy 428.213475 -330.883768)
			(xy 428.246037 -330.93113) (xy 428.271127 -330.982841) (xy 428.288176 -331.03773) (xy 428.296798 -331.094555)
			(xy 428.296799 -331.152031) (xy 428.288179 -331.208856) (xy 428.271132 -331.263746) (xy 428.246045 -331.315457)
			(xy 428.213484 -331.36282) (xy 428.194216 -331.384148) (xy 428.187612 -331.39126) (xy 428.1805 -331.408786)
			(xy 428.1805 -331.498194) (xy 428.187612 -331.51572) (xy 428.194216 -331.522832) (xy 428.213474 -331.54417)
			(xy 428.246044 -331.591528) (xy 428.27114 -331.643237) (xy 428.288193 -331.698126) (xy 428.296818 -331.754952)
			(xy 428.29734 -331.78369) (xy 431.18659 -331.78369) (xy 431.18711 -331.754951) (xy 431.195734 -331.698124)
			(xy 431.212785 -331.643233) (xy 431.237877 -331.591521) (xy 431.270443 -331.544159) (xy 431.289714 -331.522832)
			(xy 431.296318 -331.51572) (xy 431.30343 -331.498194) (xy 431.30343 -331.408786) (xy 431.296318 -331.39126)
			(xy 431.289714 -331.384148) (xy 431.270434 -331.36283) (xy 431.23787 -331.315465) (xy 431.212779 -331.263752)
			(xy 431.19573 -331.20886) (xy 431.187109 -331.152032) (xy 431.18711 -331.094553) (xy 431.195734 -331.037725)
			(xy 431.212785 -330.982834) (xy 431.237877 -330.931122) (xy 431.270443 -330.883759) (xy 431.289714 -330.862432)
			(xy 431.296318 -330.85532) (xy 431.30343 -330.837794) (xy 431.30343 -330.748386) (xy 431.296318 -330.73086)
			(xy 431.289714 -330.723748) (xy 431.270434 -330.70243) (xy 431.23787 -330.655065) (xy 431.212779 -330.603352)
			(xy 431.19573 -330.54846) (xy 431.187109 -330.491632) (xy 431.18711 -330.434153) (xy 431.195734 -330.377325)
			(xy 431.212785 -330.322434) (xy 431.237877 -330.270722) (xy 431.270443 -330.223359) (xy 431.289714 -330.202032)
			(xy 431.296318 -330.19492) (xy 431.30343 -330.177394) (xy 431.30343 -330.087986) (xy 431.296318 -330.07046)
			(xy 431.289714 -330.063348) (xy 431.270435 -330.042029) (xy 431.23787 -329.994664) (xy 431.21278 -329.94295)
			(xy 431.195731 -329.888058) (xy 431.18711 -329.831229) (xy 431.18659 -329.80249) (xy 431.187076 -329.775239)
			(xy 431.194832 -329.721291) (xy 431.210187 -329.668996) (xy 431.232829 -329.619419) (xy 431.262295 -329.573569)
			(xy 431.297986 -329.532378) (xy 431.339177 -329.496687) (xy 431.385027 -329.467221) (xy 431.434604 -329.444579)
			(xy 431.486899 -329.429224) (xy 431.540847 -329.421468) (xy 431.595349 -329.421468) (xy 431.649297 -329.429224)
			(xy 431.701592 -329.444579) (xy 431.751169 -329.467221) (xy 431.797019 -329.496687) (xy 431.83821 -329.532378)
			(xy 431.873901 -329.573569) (xy 431.903367 -329.619419) (xy 431.926009 -329.668996) (xy 431.941364 -329.721291)
			(xy 431.94912 -329.775239) (xy 431.949606 -329.80249) (xy 431.949075 -329.831229) (xy 431.940454 -329.888056)
			(xy 431.923405 -329.942946) (xy 431.898315 -329.994658) (xy 431.865752 -330.042021) (xy 431.846482 -330.063348)
			(xy 431.839878 -330.07046) (xy 431.832766 -330.087986) (xy 431.832766 -330.177394) (xy 431.839878 -330.19492)
			(xy 431.846482 -330.202032) (xy 431.865743 -330.223368) (xy 431.898308 -330.270729) (xy 431.923399 -330.322439)
			(xy 431.94045 -330.377328) (xy 431.949073 -330.434154) (xy 431.949074 -330.491631) (xy 431.940453 -330.548457)
			(xy 431.923405 -330.603347) (xy 431.898315 -330.655059) (xy 431.865752 -330.702421) (xy 431.846482 -330.723748)
			(xy 431.839878 -330.73086) (xy 431.832766 -330.748386) (xy 431.832766 -330.837794) (xy 431.839878 -330.85532)
			(xy 431.846482 -330.862432) (xy 431.865743 -330.883768) (xy 431.898308 -330.931129) (xy 431.923399 -330.982839)
			(xy 431.94045 -331.037728) (xy 431.949073 -331.094554) (xy 431.949074 -331.152031) (xy 431.940453 -331.208857)
			(xy 431.923405 -331.263747) (xy 431.898315 -331.315459) (xy 431.865752 -331.362821) (xy 431.846482 -331.384148)
			(xy 431.839878 -331.39126) (xy 431.832766 -331.408786) (xy 431.832766 -331.498194) (xy 431.839878 -331.51572)
			(xy 431.846482 -331.522832) (xy 431.865751 -331.54416) (xy 431.898317 -331.591522) (xy 431.923409 -331.643234)
			(xy 431.94046 -331.698124) (xy 431.949084 -331.754951) (xy 431.949389 -331.771752) (xy 433.642008 -331.771752)
			(xy 433.6425 -331.743012) (xy 433.65113 -331.686183) (xy 433.668188 -331.631292) (xy 433.693286 -331.579581)
			(xy 433.725858 -331.53222) (xy 433.745132 -331.510894) (xy 433.751736 -331.503782) (xy 433.758848 -331.486256)
			(xy 433.758848 -331.396848) (xy 433.751736 -331.379322) (xy 433.745132 -331.37221) (xy 433.725813 -331.350925)
			(xy 433.693249 -331.303555) (xy 433.668159 -331.251837) (xy 433.651113 -331.19694) (xy 433.642494 -331.140106)
			(xy 433.6425 -331.082624) (xy 433.651128 -331.025792) (xy 433.668185 -330.970898) (xy 433.693284 -330.919184)
			(xy 433.725857 -330.871821) (xy 433.745132 -330.850494) (xy 433.751736 -330.843382) (xy 433.758848 -330.825856)
			(xy 433.758848 -330.736448) (xy 433.751736 -330.718922) (xy 433.745132 -330.71181) (xy 433.725813 -330.690525)
			(xy 433.693249 -330.643155) (xy 433.668159 -330.591437) (xy 433.651113 -330.53654) (xy 433.642494 -330.479706)
			(xy 433.6425 -330.422224) (xy 433.651128 -330.365392) (xy 433.668185 -330.310498) (xy 433.693284 -330.258784)
			(xy 433.725857 -330.211421) (xy 433.745132 -330.190094) (xy 433.751736 -330.182982) (xy 433.758848 -330.165456)
			(xy 433.758848 -330.076048) (xy 433.751736 -330.058522) (xy 433.745132 -330.05141) (xy 433.725838 -330.030103)
			(xy 433.693275 -329.982736) (xy 433.668187 -329.931019) (xy 433.651142 -329.876124) (xy 433.642525 -329.819292)
			(xy 433.642008 -329.790552) (xy 433.642494 -329.763301) (xy 433.65025 -329.709353) (xy 433.665605 -329.657058)
			(xy 433.688247 -329.607481) (xy 433.717713 -329.561631) (xy 433.753404 -329.52044) (xy 433.794595 -329.484749)
			(xy 433.840445 -329.455283) (xy 433.890022 -329.432641) (xy 433.942317 -329.417286) (xy 433.996265 -329.40953)
			(xy 434.050767 -329.40953) (xy 434.104715 -329.417286) (xy 434.15701 -329.432641) (xy 434.206587 -329.455283)
			(xy 434.252437 -329.484749) (xy 434.293628 -329.52044) (xy 434.329319 -329.561631) (xy 434.358785 -329.607481)
			(xy 434.381427 -329.657058) (xy 434.396782 -329.709353) (xy 434.404538 -329.763301) (xy 434.405024 -329.790552)
			(xy 434.404525 -329.819292) (xy 434.395896 -329.87612) (xy 434.378839 -329.931011) (xy 434.353742 -329.982722)
			(xy 434.321173 -330.030084) (xy 434.3019 -330.05141) (xy 434.295296 -330.058522) (xy 434.288184 -330.076048)
			(xy 434.288184 -330.165456) (xy 434.295296 -330.182982) (xy 434.3019 -330.190094) (xy 434.321122 -330.211463)
			(xy 434.353687 -330.258819) (xy 434.37878 -330.310524) (xy 434.395832 -330.365408) (xy 434.404458 -330.422229)
			(xy 434.404464 -330.479701) (xy 434.395848 -330.536524) (xy 434.378805 -330.591411) (xy 434.353722 -330.643121)
			(xy 434.321166 -330.690483) (xy 434.3019 -330.71181) (xy 434.295296 -330.718922) (xy 434.288184 -330.736448)
			(xy 434.288184 -330.825856) (xy 434.295296 -330.843382) (xy 434.3019 -330.850494) (xy 434.321122 -330.871863)
			(xy 434.353687 -330.919219) (xy 434.37878 -330.970924) (xy 434.395832 -331.025808) (xy 434.404458 -331.082629)
			(xy 434.404464 -331.140101) (xy 434.395848 -331.196924) (xy 434.378805 -331.251811) (xy 434.353722 -331.303521)
			(xy 434.321166 -331.350883) (xy 434.3019 -331.37221) (xy 434.295296 -331.379322) (xy 434.290658 -331.390752)
			(xy 436.944008 -331.390752) (xy 436.9445 -331.362012) (xy 436.95313 -331.305183) (xy 436.970188 -331.250292)
			(xy 436.995286 -331.198581) (xy 437.027858 -331.15122) (xy 437.047132 -331.129894) (xy 437.053736 -331.122782)
			(xy 437.060848 -331.105256) (xy 437.060848 -331.015848) (xy 437.053736 -330.998322) (xy 437.047132 -330.99121)
			(xy 437.027813 -330.969925) (xy 436.995249 -330.922555) (xy 436.970159 -330.870837) (xy 436.953113 -330.81594)
			(xy 436.944494 -330.759106) (xy 436.9445 -330.701624) (xy 436.953128 -330.644792) (xy 436.970185 -330.589898)
			(xy 436.995284 -330.538184) (xy 437.027857 -330.490821) (xy 437.047132 -330.469494) (xy 437.053736 -330.462382)
			(xy 437.060848 -330.444856) (xy 437.060848 -330.355448) (xy 437.053736 -330.337922) (xy 437.047132 -330.33081)
			(xy 437.027838 -330.309503) (xy 436.995275 -330.262136) (xy 436.970187 -330.210419) (xy 436.953142 -330.155524)
			(xy 436.944525 -330.098692) (xy 436.944008 -330.069952) (xy 436.944494 -330.042701) (xy 436.95225 -329.988753)
			(xy 436.967605 -329.936458) (xy 436.990247 -329.886881) (xy 437.019713 -329.841031) (xy 437.055404 -329.79984)
			(xy 437.096595 -329.764149) (xy 437.142445 -329.734683) (xy 437.192022 -329.712041) (xy 437.244317 -329.696686)
			(xy 437.298265 -329.68893) (xy 437.352767 -329.68893) (xy 437.406715 -329.696686) (xy 437.45901 -329.712041)
			(xy 437.508587 -329.734683) (xy 437.554437 -329.764149) (xy 437.595628 -329.79984) (xy 437.631319 -329.841031)
			(xy 437.660785 -329.886881) (xy 437.683427 -329.936458) (xy 437.698782 -329.988753) (xy 437.706538 -330.042701)
			(xy 437.707024 -330.069952) (xy 437.706525 -330.098692) (xy 437.697896 -330.15552) (xy 437.680839 -330.210411)
			(xy 437.655742 -330.262122) (xy 437.623173 -330.309484) (xy 437.6039 -330.33081) (xy 437.597296 -330.337922)
			(xy 437.590184 -330.355448) (xy 437.590184 -330.444856) (xy 437.597296 -330.462382) (xy 437.6039 -330.469494)
			(xy 437.623122 -330.490863) (xy 437.655687 -330.538219) (xy 437.68078 -330.589924) (xy 437.697832 -330.644808)
			(xy 437.706458 -330.701629) (xy 437.706464 -330.759101) (xy 437.697848 -330.815924) (xy 437.680805 -330.870811)
			(xy 437.655722 -330.922521) (xy 437.623166 -330.969883) (xy 437.6039 -330.99121) (xy 437.597296 -330.998322)
			(xy 437.590184 -331.015848) (xy 437.590184 -331.105256) (xy 437.597296 -331.122782) (xy 437.6039 -331.129894)
			(xy 437.623185 -331.151209) (xy 437.655751 -331.198573) (xy 437.680842 -331.250288) (xy 437.697889 -331.305182)
			(xy 437.706506 -331.362012) (xy 437.707024 -331.390752) (xy 437.706507 -331.418283) (xy 437.70202 -331.449172)
			(xy 439.704988 -331.449172) (xy 439.705498 -331.420433) (xy 439.714124 -331.363605) (xy 439.731178 -331.308714)
			(xy 439.756272 -331.257003) (xy 439.78884 -331.209641) (xy 439.808112 -331.188314) (xy 439.814716 -331.181202)
			(xy 439.821828 -331.163676) (xy 439.821828 -331.074268) (xy 439.814716 -331.056742) (xy 439.808112 -331.04963)
			(xy 439.788814 -331.028327) (xy 439.756251 -330.98096) (xy 439.731161 -330.929244) (xy 439.714114 -330.87435)
			(xy 439.705494 -330.81752) (xy 439.705497 -330.760039) (xy 439.714123 -330.70321) (xy 439.731176 -330.648318)
			(xy 439.756271 -330.596604) (xy 439.78884 -330.549241) (xy 439.808112 -330.527914) (xy 439.814716 -330.520802)
			(xy 439.821828 -330.503276) (xy 439.821828 -330.413868) (xy 439.814716 -330.396342) (xy 439.808112 -330.38923)
			(xy 439.788824 -330.367918) (xy 439.756261 -330.320552) (xy 439.731172 -330.268836) (xy 439.714126 -330.213942)
			(xy 439.705507 -330.157112) (xy 439.704988 -330.128372) (xy 439.705474 -330.101121) (xy 439.71323 -330.047173)
			(xy 439.728585 -329.994878) (xy 439.751227 -329.945301) (xy 439.780693 -329.899451) (xy 439.816384 -329.85826)
			(xy 439.857575 -329.822569) (xy 439.903425 -329.793103) (xy 439.953002 -329.770461) (xy 440.005297 -329.755106)
			(xy 440.059245 -329.74735) (xy 440.113747 -329.74735) (xy 440.167695 -329.755106) (xy 440.21999 -329.770461)
			(xy 440.269567 -329.793103) (xy 440.315417 -329.822569) (xy 440.356608 -329.85826) (xy 440.392299 -329.899451)
			(xy 440.421765 -329.945301) (xy 440.444407 -329.994878) (xy 440.459762 -330.047173) (xy 440.467518 -330.101121)
			(xy 440.468004 -330.128372) (xy 440.467462 -330.15711) (xy 440.458844 -330.213937) (xy 440.441798 -330.268827)
			(xy 440.41671 -330.320539) (xy 440.384149 -330.367903) (xy 440.36488 -330.38923) (xy 440.358276 -330.396342)
			(xy 440.351164 -330.413868) (xy 440.351164 -330.503276) (xy 440.358276 -330.520802) (xy 440.36488 -330.527914)
			(xy 440.384123 -330.549265) (xy 440.416689 -330.596623) (xy 440.441782 -330.648331) (xy 440.458833 -330.703218)
			(xy 440.467459 -330.760042) (xy 440.467462 -330.817517) (xy 440.458843 -330.874342) (xy 440.441797 -330.929231)
			(xy 440.416709 -330.980941) (xy 440.384149 -331.028303) (xy 440.36488 -331.04963) (xy 440.358276 -331.056742)
			(xy 440.351164 -331.074268) (xy 440.351164 -331.163676) (xy 440.358276 -331.181202) (xy 440.36488 -331.188314)
			(xy 440.38414 -331.20965) (xy 440.416707 -331.25701) (xy 440.441802 -331.308719) (xy 440.458855 -331.363608)
			(xy 440.467481 -331.420434) (xy 440.468004 -331.449172) (xy 440.467503 -331.476704) (xy 440.459585 -331.531196)
			(xy 440.443922 -331.583985) (xy 440.42084 -331.633978) (xy 440.390817 -331.680138) (xy 440.373008 -331.70114)
			(xy 440.366658 -331.708506) (xy 440.360054 -331.72654) (xy 440.363356 -331.815948) (xy 440.370976 -331.833728)
			(xy 440.378088 -331.840586) (xy 440.399205 -331.862229) (xy 440.435007 -331.910954) (xy 440.462674 -331.964717)
			(xy 440.481512 -332.022172) (xy 440.491049 -332.08188) (xy 440.491626 -332.112112) (xy 440.49114 -332.139363)
			(xy 440.483384 -332.193311) (xy 440.468029 -332.245606) (xy 440.445387 -332.295183) (xy 440.415921 -332.341033)
			(xy 440.38023 -332.382224) (xy 440.339039 -332.417915) (xy 440.293189 -332.447381) (xy 440.243612 -332.470023)
			(xy 440.191317 -332.485378) (xy 440.137369 -332.493134) (xy 440.082867 -332.493134) (xy 440.028919 -332.485378)
			(xy 439.976624 -332.470023) (xy 439.927047 -332.447381) (xy 439.881197 -332.417915) (xy 439.840006 -332.382224)
			(xy 439.804315 -332.341033) (xy 439.774849 -332.295183) (xy 439.752207 -332.245606) (xy 439.736852 -332.193311)
			(xy 439.729096 -332.139363) (xy 439.72861 -332.112112) (xy 439.729098 -332.084579) (xy 439.737019 -332.030087)
			(xy 439.752685 -331.977297) (xy 439.77577 -331.927305) (xy 439.805796 -331.881146) (xy 439.823606 -331.860144)
			(xy 439.829956 -331.852778) (xy 439.83656 -331.834744) (xy 439.833258 -331.745336) (xy 439.825638 -331.727556)
			(xy 439.818526 -331.720698) (xy 439.797404 -331.69906) (xy 439.761602 -331.650334) (xy 439.733936 -331.596569)
			(xy 439.715099 -331.539113) (xy 439.705563 -331.479405) (xy 439.704988 -331.449172) (xy 437.70202 -331.449172)
			(xy 437.698592 -331.472774) (xy 437.682933 -331.525564) (xy 437.659854 -331.575557) (xy 437.629835 -331.621717)
			(xy 437.612028 -331.64272) (xy 437.605678 -331.650086) (xy 437.599074 -331.66812) (xy 437.602376 -331.757528)
			(xy 437.609996 -331.775308) (xy 437.617108 -331.782166) (xy 437.638201 -331.803831) (xy 437.67401 -331.852548)
			(xy 437.701682 -331.906306) (xy 437.720526 -331.963757) (xy 437.730068 -332.023461) (xy 437.730646 -332.053692)
			(xy 437.73016 -332.080943) (xy 437.722404 -332.134891) (xy 437.707049 -332.187186) (xy 437.684407 -332.236763)
			(xy 437.654941 -332.282613) (xy 437.61925 -332.323804) (xy 437.578059 -332.359495) (xy 437.532209 -332.388961)
			(xy 437.482632 -332.411603) (xy 437.430337 -332.426958) (xy 437.376389 -332.434714) (xy 437.321887 -332.434714)
			(xy 437.267939 -332.426958) (xy 437.215644 -332.411603) (xy 437.166067 -332.388961) (xy 437.120217 -332.359495)
			(xy 437.079026 -332.323804) (xy 437.043335 -332.282613) (xy 437.013869 -332.236763) (xy 436.991227 -332.187186)
			(xy 436.975872 -332.134891) (xy 436.968116 -332.080943) (xy 436.96763 -332.053692) (xy 436.968125 -332.02616)
			(xy 436.976048 -331.971669) (xy 436.991713 -331.918879) (xy 437.014795 -331.868887) (xy 437.044818 -331.822727)
			(xy 437.062626 -331.801724) (xy 437.068976 -331.794358) (xy 437.07558 -331.776324) (xy 437.072278 -331.686916)
			(xy 437.064658 -331.669136) (xy 437.057546 -331.662278) (xy 437.036418 -331.640646) (xy 437.000616 -331.591919)
			(xy 436.97295 -331.538153) (xy 436.954115 -331.480695) (xy 436.944582 -331.420985) (xy 436.944008 -331.390752)
			(xy 434.290658 -331.390752) (xy 434.288184 -331.396848) (xy 434.288184 -331.486256) (xy 434.295296 -331.503782)
			(xy 434.3019 -331.510894) (xy 434.321185 -331.532209) (xy 434.353751 -331.579573) (xy 434.378842 -331.631288)
			(xy 434.395889 -331.686182) (xy 434.404506 -331.743012) (xy 434.405024 -331.771752) (xy 434.404538 -331.799003)
			(xy 434.396782 -331.852951) (xy 434.381427 -331.905246) (xy 434.358785 -331.954823) (xy 434.329319 -332.000673)
			(xy 434.293628 -332.041864) (xy 434.252437 -332.077555) (xy 434.206587 -332.107021) (xy 434.15701 -332.129663)
			(xy 434.104715 -332.145018) (xy 434.050767 -332.152774) (xy 433.996265 -332.152774) (xy 433.942317 -332.145018)
			(xy 433.890022 -332.129663) (xy 433.840445 -332.107021) (xy 433.794595 -332.077555) (xy 433.753404 -332.041864)
			(xy 433.717713 -332.000673) (xy 433.688247 -331.954823) (xy 433.665605 -331.905246) (xy 433.65025 -331.852951)
			(xy 433.642494 -331.799003) (xy 433.642008 -331.771752) (xy 431.949389 -331.771752) (xy 431.949606 -331.78369)
			(xy 431.94912 -331.810941) (xy 431.941364 -331.864889) (xy 431.926009 -331.917184) (xy 431.903367 -331.966761)
			(xy 431.873901 -332.012611) (xy 431.83821 -332.053802) (xy 431.797019 -332.089493) (xy 431.751169 -332.118959)
			(xy 431.701592 -332.141601) (xy 431.649297 -332.156956) (xy 431.595349 -332.164712) (xy 431.540847 -332.164712)
			(xy 431.486899 -332.156956) (xy 431.434604 -332.141601) (xy 431.385027 -332.118959) (xy 431.339177 -332.089493)
			(xy 431.297986 -332.053802) (xy 431.262295 -332.012611) (xy 431.232829 -331.966761) (xy 431.210187 -331.917184)
			(xy 431.194832 -331.864889) (xy 431.187076 -331.810941) (xy 431.18659 -331.78369) (xy 428.29734 -331.78369)
			(xy 428.296854 -331.810941) (xy 428.289098 -331.864889) (xy 428.273743 -331.917184) (xy 428.251101 -331.966761)
			(xy 428.221635 -332.012611) (xy 428.185944 -332.053802) (xy 428.144753 -332.089493) (xy 428.098903 -332.118959)
			(xy 428.049326 -332.141601) (xy 427.997031 -332.156956) (xy 427.943083 -332.164712) (xy 427.888581 -332.164712)
			(xy 427.834633 -332.156956) (xy 427.782338 -332.141601) (xy 427.732761 -332.118959) (xy 427.686911 -332.089493)
			(xy 427.64572 -332.053802) (xy 427.610029 -332.012611) (xy 427.580563 -331.966761) (xy 427.557921 -331.917184)
			(xy 427.542566 -331.864889) (xy 427.53481 -331.810941) (xy 427.534324 -331.78369) (xy 425.871281 -331.78369)
			(xy 425.878484 -331.831151) (xy 425.879006 -331.85989) (xy 425.87852 -331.887141) (xy 425.870764 -331.941089)
			(xy 425.855409 -331.993384) (xy 425.832767 -332.042961) (xy 425.803301 -332.088811) (xy 425.76761 -332.130002)
			(xy 425.726419 -332.165693) (xy 425.680569 -332.195159) (xy 425.630992 -332.217801) (xy 425.578697 -332.233156)
			(xy 425.524749 -332.240912) (xy 425.470247 -332.240912) (xy 425.416299 -332.233156) (xy 425.364004 -332.217801)
			(xy 425.314427 -332.195159) (xy 425.268577 -332.165693) (xy 425.227386 -332.130002) (xy 425.191695 -332.088811)
			(xy 425.162229 -332.042961) (xy 425.139587 -331.993384) (xy 425.124232 -331.941089) (xy 425.116476 -331.887141)
			(xy 425.11599 -331.85989) (xy 422.172384 -331.85989) (xy 422.171898 -331.887141) (xy 422.164142 -331.941089)
			(xy 422.148787 -331.993384) (xy 422.126145 -332.042961) (xy 422.096679 -332.088811) (xy 422.060988 -332.130002)
			(xy 422.019797 -332.165693) (xy 421.973947 -332.195159) (xy 421.92437 -332.217801) (xy 421.872075 -332.233156)
			(xy 421.818127 -332.240912) (xy 421.763625 -332.240912) (xy 421.709677 -332.233156) (xy 421.657382 -332.217801)
			(xy 421.607805 -332.195159) (xy 421.561955 -332.165693) (xy 421.520764 -332.130002) (xy 421.485073 -332.088811)
			(xy 421.455607 -332.042961) (xy 421.432965 -331.993384) (xy 421.41761 -331.941089) (xy 421.409854 -331.887141)
			(xy 421.409368 -331.85989) (xy 419.783006 -331.85989) (xy 419.78252 -331.887141) (xy 419.774764 -331.941089)
			(xy 419.759409 -331.993384) (xy 419.736767 -332.042961) (xy 419.707301 -332.088811) (xy 419.67161 -332.130002)
			(xy 419.630419 -332.165693) (xy 419.584569 -332.195159) (xy 419.534992 -332.217801) (xy 419.482697 -332.233156)
			(xy 419.428749 -332.240912) (xy 419.374247 -332.240912) (xy 419.320299 -332.233156) (xy 419.268004 -332.217801)
			(xy 419.218427 -332.195159) (xy 419.172577 -332.165693) (xy 419.131386 -332.130002) (xy 419.095695 -332.088811)
			(xy 419.066229 -332.042961) (xy 419.043587 -331.993384) (xy 419.028232 -331.941089) (xy 419.020476 -331.887141)
			(xy 419.01999 -331.85989) (xy 413.740744 -331.85989) (xy 413.773605 -331.919094) (xy 413.804085 -331.990121)
			(xy 413.827223 -332.063867) (xy 413.842781 -332.139575) (xy 413.850601 -332.216469) (xy 413.85109 -332.255114)
			(xy 413.850622 -332.292291) (xy 413.843378 -332.366291) (xy 413.82896 -332.439233) (xy 413.807506 -332.510425)
			(xy 413.77922 -332.579188) (xy 413.76219 -332.612238) (xy 413.756868 -332.62359) (xy 413.756875 -332.648634)
			(xy 413.76219 -332.65999) (xy 413.779228 -332.693035) (xy 413.8075 -332.761805) (xy 413.828948 -332.832997)
			(xy 413.843371 -332.905939) (xy 413.85063 -332.979937) (xy 413.85109 -333.017114) (xy 413.850601 -333.055759)
			(xy 413.842781 -333.132653) (xy 413.827223 -333.208361) (xy 413.804085 -333.282107) (xy 413.773605 -333.353134)
			(xy 413.736096 -333.420712) (xy 413.691942 -333.48415) (xy 413.641597 -333.542794) (xy 413.585578 -333.596045)
			(xy 413.524459 -333.643355) (xy 413.458866 -333.684239) (xy 413.389475 -333.718277) (xy 413.316995 -333.74512)
			(xy 413.242172 -333.764493) (xy 413.165773 -333.776197) (xy 413.088582 -333.780112) (xy 413.011391 -333.776197)
			(xy 412.934992 -333.764493) (xy 412.860169 -333.74512) (xy 412.787689 -333.718277) (xy 412.718298 -333.684239)
			(xy 412.652705 -333.643355) (xy 412.591586 -333.596045) (xy 412.535567 -333.542794) (xy 412.485222 -333.48415)
			(xy 412.441068 -333.420712) (xy 412.403559 -333.353134) (xy 412.373079 -333.282107) (xy 412.349941 -333.208361)
			(xy 412.334383 -333.132653) (xy 412.326563 -333.055759) (xy 412.326074 -333.017114) (xy 406.527666 -333.017114)
			(xy 406.49622 -333.050601) (xy 406.446967 -333.091346) (xy 406.392996 -333.125597) (xy 406.335157 -333.152814)
			(xy 406.274364 -333.172567) (xy 406.211574 -333.184545) (xy 406.147778 -333.188559) (xy 406.083982 -333.184545)
			(xy 406.021192 -333.172567) (xy 405.960399 -333.152814) (xy 405.90256 -333.125597) (xy 405.848589 -333.091346)
			(xy 405.799336 -333.050601) (xy 405.755579 -333.004004) (xy 405.718006 -332.952289) (xy 405.687212 -332.896274)
			(xy 405.66368 -332.836841) (xy 405.647783 -332.774927) (xy 405.639772 -332.711509) (xy 405.63927 -332.679548)
			(xy 404.586723 -332.679548) (xy 404.578032 -332.713397) (xy 404.5545 -332.77283) (xy 404.523706 -332.828845)
			(xy 404.486133 -332.88056) (xy 404.442376 -332.927157) (xy 404.393123 -332.967902) (xy 404.339152 -333.002153)
			(xy 404.281313 -333.02937) (xy 404.22052 -333.049123) (xy 404.15773 -333.061101) (xy 404.093934 -333.065115)
			(xy 404.030138 -333.061101) (xy 403.967348 -333.049123) (xy 403.906555 -333.02937) (xy 403.848716 -333.002153)
			(xy 403.794745 -332.967902) (xy 403.745492 -332.927157) (xy 403.701735 -332.88056) (xy 403.664162 -332.828845)
			(xy 403.633368 -332.77283) (xy 403.609836 -332.713397) (xy 403.593939 -332.651483) (xy 403.585928 -332.588065)
			(xy 403.585426 -332.556104) (xy 403.585916 -332.523423) (xy 403.594291 -332.458598) (xy 403.610904 -332.395382)
			(xy 403.635481 -332.334815) (xy 403.667615 -332.277897) (xy 403.706779 -332.225566) (xy 403.72919 -332.201774)
			(xy 403.738842 -332.191868) (xy 403.745446 -332.166214) (xy 403.715474 -332.055724) (xy 403.696932 -332.036928)
			(xy 403.683724 -332.033118) (xy 403.667405 -332.028407) (xy 403.635375 -332.017093) (xy 403.619716 -332.010512)
			(xy 403.609048 -332.00594) (xy 403.586188 -332.006956) (xy 403.49551 -332.054962) (xy 403.482048 -332.07325)
			(xy 403.479762 -332.08468) (xy 403.474297 -332.110469) (xy 403.457343 -332.16038) (xy 403.433678 -332.207482)
			(xy 403.403752 -332.250876) (xy 403.368136 -332.289736) (xy 403.327507 -332.323321) (xy 403.282641 -332.35099)
			(xy 403.234391 -332.372218) (xy 403.183678 -332.386599) (xy 403.131468 -332.39386) (xy 403.105112 -332.394306)
			(xy 403.077859 -332.393834) (xy 403.023909 -332.386078) (xy 402.971611 -332.370724) (xy 402.922031 -332.348082)
			(xy 402.876177 -332.318615) (xy 402.834985 -332.282923) (xy 402.799291 -332.241731) (xy 402.769823 -332.195878)
			(xy 402.74718 -332.146299) (xy 402.731824 -332.094001) (xy 402.724067 -332.040051) (xy 402.723604 -332.012798)
			(xy 402.723998 -331.988541) (xy 402.730151 -331.940419) (xy 402.742357 -331.893466) (xy 402.751036 -331.870812)
			(xy 402.754103 -331.862428) (xy 402.754751 -331.8446) (xy 402.752306 -331.836014) (xy 402.742654 -331.807058)
			(xy 402.739502 -331.79864) (xy 402.728304 -331.784591) (xy 402.72081 -331.779626) (xy 402.693295 -331.76224)
			(xy 402.642504 -331.721539) (xy 402.597319 -331.674692) (xy 402.558478 -331.622465) (xy 402.526616 -331.56571)
			(xy 402.502252 -331.505355) (xy 402.485786 -331.442385) (xy 402.477487 -331.377829) (xy 402.47697 -331.345286)
			(xy 400.240548 -331.345286) (xy 400.27285 -331.358075) (xy 400.328873 -331.388874) (xy 400.380594 -331.426451)
			(xy 400.427197 -331.470214) (xy 400.467948 -331.519473) (xy 400.502204 -331.573451) (xy 400.529424 -331.631297)
			(xy 400.54918 -331.692098) (xy 400.561159 -331.754896) (xy 400.565174 -331.8187) (xy 400.561159 -331.882504)
			(xy 400.54918 -331.945302) (xy 400.529424 -332.006103) (xy 400.502204 -332.063949) (xy 400.467948 -332.117927)
			(xy 400.427197 -332.167186) (xy 400.380594 -332.210949) (xy 400.328873 -332.248526) (xy 400.27285 -332.279325)
			(xy 400.213409 -332.302859) (xy 400.151487 -332.318757) (xy 400.088061 -332.326769) (xy 400.056096 -332.32725)
			(xy 400.024874 -332.326819) (xy 399.962898 -332.319183) (xy 399.902325 -332.304013) (xy 399.844065 -332.281538)
			(xy 399.788997 -332.252098) (xy 399.737949 -332.216133) (xy 399.691691 -332.174188) (xy 399.650918 -332.126892)
			(xy 399.633186 -332.10119) (xy 399.627598 -332.092808) (xy 399.611596 -332.081886) (xy 399.523458 -332.062328)
			(xy 399.504408 -332.06563) (xy 399.495772 -332.07071) (xy 399.473243 -332.08395) (xy 399.425337 -332.104823)
			(xy 399.375034 -332.118974) (xy 399.323272 -332.12614) (xy 399.297144 -332.12659) (xy 399.269891 -332.126104)
			(xy 399.21594 -332.118352) (xy 399.163642 -332.103001) (xy 399.114061 -332.080362) (xy 399.068206 -332.050897)
			(xy 399.027013 -332.015206) (xy 398.991318 -331.974014) (xy 398.96185 -331.928162) (xy 398.939208 -331.878583)
			(xy 398.923853 -331.826285) (xy 398.916098 -331.772335) (xy 398.915636 -331.745082) (xy 398.916125 -331.716377)
			(xy 398.92473 -331.659616) (xy 398.941743 -331.604785) (xy 398.966779 -331.553122) (xy 398.999275 -331.505794)
			(xy 399.018506 -331.484478) (xy 399.02511 -331.477366) (xy 399.031968 -331.45984) (xy 399.032476 -331.371448)
			(xy 399.025618 -331.353668) (xy 399.019014 -331.346556) (xy 398.998096 -331.323024) (xy 398.961579 -331.27173)
			(xy 398.931672 -331.216323) (xy 398.90883 -331.157649) (xy 398.893404 -331.096604) (xy 398.88563 -331.034122)
			(xy 398.885156 -331.00264) (xy 395.52459 -331.00264) (xy 395.510486 -331.057571) (xy 395.486954 -331.117004)
			(xy 395.45616 -331.173019) (xy 395.418587 -331.224734) (xy 395.37483 -331.271331) (xy 395.325577 -331.312076)
			(xy 395.271606 -331.346327) (xy 395.213767 -331.373544) (xy 395.152974 -331.393297) (xy 395.090184 -331.405275)
			(xy 395.026388 -331.409289) (xy 394.962592 -331.405275) (xy 394.899802 -331.393297) (xy 394.839009 -331.373544)
			(xy 394.78117 -331.346327) (xy 394.727199 -331.312076) (xy 394.677946 -331.271331) (xy 394.634189 -331.224734)
			(xy 394.596616 -331.173019) (xy 394.565822 -331.117004) (xy 394.54229 -331.057571) (xy 394.526393 -330.995657)
			(xy 394.518382 -330.932239) (xy 390.589987 -330.932239) (xy 391.182606 -332.500224) (xy 391.184655 -332.505243)
			(xy 391.190539 -332.514345) (xy 391.19429 -332.518258) (xy 391.285433 -332.609401) (xy 396.448274 -332.609401)
			(xy 396.448274 -332.545479) (xy 396.456285 -332.482061) (xy 396.472182 -332.420147) (xy 396.495714 -332.360714)
			(xy 396.526508 -332.304699) (xy 396.564081 -332.252984) (xy 396.607838 -332.206387) (xy 396.657091 -332.165642)
			(xy 396.711062 -332.131391) (xy 396.768901 -332.104174) (xy 396.829694 -332.084421) (xy 396.892484 -332.072443)
			(xy 396.95628 -332.06843) (xy 397.020076 -332.072443) (xy 397.082866 -332.084421) (xy 397.143659 -332.104174)
			(xy 397.201498 -332.131391) (xy 397.255469 -332.165642) (xy 397.304722 -332.206387) (xy 397.348479 -332.252984)
			(xy 397.386052 -332.304699) (xy 397.416846 -332.360714) (xy 397.440378 -332.420147) (xy 397.456275 -332.482061)
			(xy 397.464286 -332.545479) (xy 397.464788 -332.57744) (xy 397.464286 -332.609401) (xy 397.456275 -332.672819)
			(xy 397.440378 -332.734733) (xy 397.416846 -332.794166) (xy 397.386052 -332.850181) (xy 397.348479 -332.901896)
			(xy 397.304722 -332.948493) (xy 397.255469 -332.989238) (xy 397.201498 -333.023489) (xy 397.143659 -333.050706)
			(xy 397.082866 -333.070459) (xy 397.020076 -333.082437) (xy 396.95628 -333.086451) (xy 396.892484 -333.082437)
			(xy 396.829694 -333.070459) (xy 396.768901 -333.050706) (xy 396.711062 -333.023489) (xy 396.657091 -332.989238)
			(xy 396.607838 -332.948493) (xy 396.564081 -332.901896) (xy 396.526508 -332.850181) (xy 396.495714 -332.794166)
			(xy 396.472182 -332.734733) (xy 396.456285 -332.672819) (xy 396.448274 -332.609401) (xy 391.285433 -332.609401)
			(xy 391.837375 -333.161343) (xy 397.879818 -333.161343) (xy 397.879818 -333.097421) (xy 397.887829 -333.034003)
			(xy 397.903726 -332.972089) (xy 397.927258 -332.912656) (xy 397.958052 -332.856641) (xy 397.995625 -332.804926)
			(xy 398.039382 -332.758329) (xy 398.088635 -332.717584) (xy 398.142606 -332.683333) (xy 398.200445 -332.656116)
			(xy 398.261238 -332.636363) (xy 398.324028 -332.624385) (xy 398.387824 -332.620372) (xy 398.45162 -332.624385)
			(xy 398.51441 -332.636363) (xy 398.575203 -332.656116) (xy 398.633042 -332.683333) (xy 398.687013 -332.717584)
			(xy 398.736266 -332.758329) (xy 398.780023 -332.804926) (xy 398.817596 -332.856641) (xy 398.84839 -332.912656)
			(xy 398.871922 -332.972089) (xy 398.887819 -333.034003) (xy 398.89583 -333.097421) (xy 398.896332 -333.129382)
			(xy 398.89583 -333.161343) (xy 398.887819 -333.224761) (xy 398.871922 -333.286675) (xy 398.84839 -333.346108)
			(xy 398.817596 -333.402123) (xy 398.780023 -333.453838) (xy 398.736266 -333.500435) (xy 398.687013 -333.54118)
			(xy 398.633042 -333.575431) (xy 398.57597 -333.602287) (xy 408.010608 -333.602287) (xy 408.010608 -333.538365)
			(xy 408.018619 -333.474947) (xy 408.034516 -333.413033) (xy 408.058048 -333.3536) (xy 408.088842 -333.297585)
			(xy 408.126415 -333.24587) (xy 408.170172 -333.199273) (xy 408.219425 -333.158528) (xy 408.273396 -333.124277)
			(xy 408.331235 -333.09706) (xy 408.392028 -333.077307) (xy 408.454818 -333.065329) (xy 408.518614 -333.061316)
			(xy 408.58241 -333.065329) (xy 408.6452 -333.077307) (xy 408.705993 -333.09706) (xy 408.763832 -333.124277)
			(xy 408.817803 -333.158528) (xy 408.867056 -333.199273) (xy 408.910813 -333.24587) (xy 408.948386 -333.297585)
			(xy 408.97918 -333.3536) (xy 409.002712 -333.413033) (xy 409.018609 -333.474947) (xy 409.02662 -333.538365)
			(xy 409.027122 -333.570326) (xy 409.02662 -333.602287) (xy 409.018609 -333.665705) (xy 409.002712 -333.727619)
			(xy 408.97918 -333.787052) (xy 408.948386 -333.843067) (xy 408.910813 -333.894782) (xy 408.867056 -333.941379)
			(xy 408.817803 -333.982124) (xy 408.763832 -334.016375) (xy 408.705993 -334.043592) (xy 408.6452 -334.063345)
			(xy 408.58241 -334.075323) (xy 408.518614 -334.079337) (xy 408.454818 -334.075323) (xy 408.392028 -334.063345)
			(xy 408.331235 -334.043592) (xy 408.273396 -334.016375) (xy 408.219425 -333.982124) (xy 408.170172 -333.941379)
			(xy 408.126415 -333.894782) (xy 408.088842 -333.843067) (xy 408.058048 -333.787052) (xy 408.034516 -333.727619)
			(xy 408.018619 -333.665705) (xy 408.010608 -333.602287) (xy 398.57597 -333.602287) (xy 398.575203 -333.602648)
			(xy 398.51441 -333.622401) (xy 398.45162 -333.634379) (xy 398.387824 -333.638393) (xy 398.324028 -333.634379)
			(xy 398.261238 -333.622401) (xy 398.200445 -333.602648) (xy 398.142606 -333.575431) (xy 398.088635 -333.54118)
			(xy 398.039382 -333.500435) (xy 397.995625 -333.453838) (xy 397.958052 -333.402123) (xy 397.927258 -333.346108)
			(xy 397.903726 -333.286675) (xy 397.887829 -333.224761) (xy 397.879818 -333.161343) (xy 391.837375 -333.161343)
			(xy 397.407638 -338.731606) (xy 407.775664 -338.731606) (xy 407.776126 -338.693372) (xy 407.783779 -338.617287)
			(xy 407.799 -338.542349) (xy 407.821634 -338.469307) (xy 407.836116 -338.433918) (xy 407.839679 -338.424327)
			(xy 407.839681 -338.403884) (xy 407.836116 -338.394294) (xy 407.821613 -338.358913) (xy 407.798959 -338.285874)
			(xy 407.783742 -338.210932) (xy 407.776115 -338.134842) (xy 407.775664 -338.096606) (xy 407.776153 -338.057961)
			(xy 407.783973 -337.981067) (xy 407.799531 -337.905359) (xy 407.822669 -337.831613) (xy 407.853149 -337.760586)
			(xy 407.890658 -337.693008) (xy 407.934812 -337.62957) (xy 407.985157 -337.570926) (xy 408.041176 -337.517675)
			(xy 408.102295 -337.470365) (xy 408.167888 -337.429481) (xy 408.237279 -337.395443) (xy 408.309759 -337.3686)
			(xy 408.384582 -337.349227) (xy 408.460981 -337.337523) (xy 408.538172 -337.333608) (xy 408.615363 -337.337523)
			(xy 408.691762 -337.349227) (xy 408.766585 -337.3686) (xy 408.839065 -337.395443) (xy 408.908456 -337.429481)
			(xy 408.974049 -337.470365) (xy 409.035168 -337.517675) (xy 409.091187 -337.570926) (xy 409.141532 -337.62957)
			(xy 409.185686 -337.693008) (xy 409.223195 -337.760586) (xy 409.253675 -337.831613) (xy 409.276813 -337.905359)
			(xy 409.292371 -337.981067) (xy 409.300191 -338.057961) (xy 409.30068 -338.096606) (xy 409.300218 -338.13484)
			(xy 409.292564 -338.210925) (xy 409.277344 -338.285863) (xy 409.254709 -338.358905) (xy 409.240228 -338.394294)
			(xy 409.236661 -338.403884) (xy 409.236664 -338.424327) (xy 409.240228 -338.433918) (xy 409.254738 -338.469297)
			(xy 409.277389 -338.542337) (xy 409.292604 -338.617279) (xy 409.300229 -338.69337) (xy 409.30068 -338.731606)
			(xy 409.300191 -338.770251) (xy 409.292371 -338.847145) (xy 409.276813 -338.922853) (xy 409.253675 -338.996599)
			(xy 409.223195 -339.067626) (xy 409.185686 -339.135204) (xy 409.141532 -339.198642) (xy 409.091187 -339.257286)
			(xy 409.035168 -339.310537) (xy 408.974049 -339.357847) (xy 408.908456 -339.398731) (xy 408.839065 -339.432769)
			(xy 408.766585 -339.459612) (xy 408.691762 -339.478985) (xy 408.615363 -339.490689) (xy 408.538172 -339.494604)
			(xy 408.460981 -339.490689) (xy 408.384582 -339.478985) (xy 408.309759 -339.459612) (xy 408.237279 -339.432769)
			(xy 408.167888 -339.398731) (xy 408.102295 -339.357847) (xy 408.041176 -339.310537) (xy 407.985157 -339.257286)
			(xy 407.934812 -339.198642) (xy 407.890658 -339.135204) (xy 407.853149 -339.067626) (xy 407.822669 -338.996599)
			(xy 407.799531 -338.922853) (xy 407.783973 -338.847145) (xy 407.776153 -338.770251) (xy 407.775664 -338.731606)
			(xy 397.407638 -338.731606) (xy 398.253712 -339.57768) (xy 398.260824 -339.58657) (xy 398.266666 -339.595968)
			(xy 398.273778 -339.604858) (xy 398.341342 -339.672422) (xy 406.46807 -339.672422) (xy 406.472141 -339.6168)
			(xy 406.484267 -339.562363) (xy 406.50419 -339.510272) (xy 406.531486 -339.461637) (xy 406.565572 -339.417494)
			(xy 406.605721 -339.378785) (xy 406.651079 -339.346334) (xy 406.700679 -339.320833) (xy 406.753463 -339.302826)
			(xy 406.808306 -339.292696) (xy 406.86404 -339.290659) (xy 406.919477 -339.296759) (xy 406.973434 -339.310865)
			(xy 407.024763 -339.332677) (xy 407.072369 -339.361731) (xy 407.115237 -339.397406) (xy 407.152454 -339.438943)
			(xy 407.183227 -339.485456) (xy 407.206899 -339.535953) (xy 407.222967 -339.58936) (xy 407.231087 -339.644536)
			(xy 407.231596 -339.672422) (xy 407.231087 -339.700308) (xy 407.222967 -339.755484) (xy 407.206899 -339.808891)
			(xy 407.183227 -339.859388) (xy 407.152454 -339.905901) (xy 407.115237 -339.947438) (xy 407.072369 -339.983113)
			(xy 407.024763 -340.012167) (xy 406.973434 -340.033979) (xy 406.919477 -340.048085) (xy 406.86404 -340.054185)
			(xy 406.808306 -340.052148) (xy 406.753463 -340.042018) (xy 406.700679 -340.024011) (xy 406.651079 -339.99851)
			(xy 406.605721 -339.966059) (xy 406.565572 -339.92735) (xy 406.531486 -339.883207) (xy 406.50419 -339.834572)
			(xy 406.484267 -339.782481) (xy 406.472141 -339.728044) (xy 406.46807 -339.672422) (xy 398.341342 -339.672422)
			(xy 400.155664 -341.486744) (xy 400.166796 -341.497179) (xy 400.193752 -341.511449) (xy 400.22372 -341.517118)
			(xy 400.254025 -341.513682) (xy 400.281963 -341.501447) (xy 400.30504 -341.481505) (xy 400.321196 -341.455636)
			(xy 400.32559 -341.441024) (xy 400.334315 -341.41024) (xy 400.358456 -341.350984) (xy 400.389839 -341.295224)
			(xy 400.42797 -341.243842) (xy 400.472244 -341.197648) (xy 400.496786 -341.177118) (xy 400.507252 -341.16806)
			(xy 400.523306 -341.145527) (xy 400.53272 -341.119512) (xy 400.534804 -341.091924) (xy 400.529403 -341.064789)
			(xy 400.516916 -341.040101) (xy 400.507962 -341.029544) (xy 400.489286 -341.008339) (xy 400.457751 -340.961453)
			(xy 400.433477 -340.910429) (xy 400.416997 -340.856381) (xy 400.40867 -340.800494) (xy 400.40814 -340.772242)
			(xy 400.408626 -340.744973) (xy 400.416388 -340.690989) (xy 400.431753 -340.638659) (xy 400.45441 -340.589049)
			(xy 400.483896 -340.543168) (xy 400.519611 -340.501951) (xy 400.560828 -340.466236) (xy 400.606709 -340.43675)
			(xy 400.656319 -340.414093) (xy 400.708649 -340.398728) (xy 400.762633 -340.390966) (xy 400.817171 -340.390966)
			(xy 400.871155 -340.398728) (xy 400.923485 -340.414093) (xy 400.973095 -340.43675) (xy 401.018976 -340.466236)
			(xy 401.060193 -340.501951) (xy 401.095908 -340.543168) (xy 401.125394 -340.589049) (xy 401.148051 -340.638659)
			(xy 401.163416 -340.690989) (xy 401.171178 -340.744973) (xy 401.171664 -340.772242) (xy 401.171244 -340.797916)
			(xy 401.164356 -340.848799) (xy 401.150709 -340.898299) (xy 401.130551 -340.945524) (xy 401.104245 -340.989621)
			(xy 401.088606 -341.009986) (xy 401.080362 -341.021085) (xy 401.069586 -341.046534) (xy 401.06604 -341.073942)
			(xy 401.069984 -341.101296) (xy 401.08113 -341.126586) (xy 401.098657 -341.147953) (xy 401.109688 -341.15629)
			(xy 401.134358 -341.174171) (xy 401.179668 -341.214908) (xy 401.219787 -341.260766) (xy 401.254139 -341.31109)
			(xy 401.282232 -341.365158) (xy 401.303664 -341.422195) (xy 401.318127 -341.481384) (xy 401.325414 -341.541877)
			(xy 401.325842 -341.572342) (xy 401.325842 -341.573358) (xy 401.325565 -341.596349) (xy 401.321371 -341.64214)
			(xy 401.31746 -341.664798) (xy 401.315258 -341.679519) (xy 401.318496 -341.709094) (xy 401.330114 -341.736483)
			(xy 401.349127 -341.759367) (xy 401.373925 -341.775806) (xy 401.402407 -341.784407) (xy 401.417282 -341.78494)
		)
		(stroke
			(width 0)
			(type solid)
		)
		(fill yes)
		(layer "In13.Cu")
		(net "PVDD11_S3_P0")
	)
	(gr_poly
		(pts
			(xy 349.294196 -263.78408) (xy 349.306224 -263.783416) (xy 349.327692 -263.772556) (xy 349.335344 -263.763252)
			(xy 349.39097 -263.686798) (xy 349.39478 -263.662668) (xy 349.39097 -263.650984) (xy 349.383866 -263.62788)
			(xy 349.376207 -263.580155) (xy 349.37573 -263.555988) (xy 349.376252 -263.530733) (xy 349.384565 -263.480911)
			(xy 349.400966 -263.433137) (xy 349.425007 -263.388714) (xy 349.456031 -263.348854) (xy 349.493193 -263.314644)
			(xy 349.535479 -263.287018) (xy 349.581735 -263.266728) (xy 349.6307 -263.254328) (xy 349.681038 -263.250157)
			(xy 349.731376 -263.254328) (xy 349.780341 -263.266728) (xy 349.826597 -263.287018) (xy 349.868883 -263.314644)
			(xy 349.906045 -263.348854) (xy 349.937069 -263.388714) (xy 349.96111 -263.433137) (xy 349.977511 -263.480911)
			(xy 349.985824 -263.530733) (xy 349.986346 -263.555988) (xy 349.985863 -263.580154) (xy 349.978201 -263.627877)
			(xy 349.971106 -263.650984) (xy 349.967296 -263.662668) (xy 349.971106 -263.686798) (xy 350.026732 -263.763252)
			(xy 350.034345 -263.772614) (xy 350.05583 -263.783516) (xy 350.06788 -263.78408) (xy 351.483676 -263.78408)
			(xy 351.493548 -263.783609) (xy 351.51183 -263.776149) (xy 351.519236 -263.769602) (xy 351.51949 -263.769348)
			(xy 352.063558 -263.22528) (xy 352.070119 -263.218181) (xy 352.077818 -263.200467) (xy 352.0784 -263.18116)
			(xy 352.075496 -263.17194) (xy 352.039174 -263.071356) (xy 352.015806 -263.053322) (xy 352.001074 -263.052052)
			(xy 351.976066 -263.049315) (xy 351.927368 -263.036711) (xy 351.881393 -263.016295) (xy 351.839387 -262.98862)
			(xy 351.802485 -262.954434) (xy 351.771685 -262.914662) (xy 351.74782 -262.87038) (xy 351.731535 -262.822786)
			(xy 351.723272 -262.773166) (xy 351.72269 -262.748014) (xy 351.723135 -262.72402) (xy 351.73064 -262.676623)
			(xy 351.745467 -262.630983) (xy 351.767252 -262.588225) (xy 351.795457 -262.549401) (xy 351.829389 -262.515468)
			(xy 351.868211 -262.48726) (xy 351.910968 -262.465474) (xy 351.956607 -262.450644) (xy 352.004004 -262.443136)
			(xy 352.027998 -262.442706) (xy 352.05316 -262.443212) (xy 352.102804 -262.451451) (xy 352.150425 -262.467722)
			(xy 352.19473 -262.491585) (xy 352.234521 -262.522393) (xy 352.268719 -262.559312) (xy 352.296397 -262.60134)
			(xy 352.316805 -262.64734) (xy 352.32939 -262.696064) (xy 352.332036 -262.72109) (xy 352.333306 -262.735822)
			(xy 352.35134 -262.75919) (xy 352.451924 -262.795512) (xy 352.461144 -262.798396) (xy 352.480438 -262.797788)
			(xy 352.498149 -262.790109) (xy 352.505264 -262.783574) (xy 353.072446 -262.216392) (xy 353.072954 -262.215884)
			(xy 353.079542 -262.208505) (xy 353.087005 -262.190206) (xy 353.087432 -262.180324) (xy 353.087432 -262.18007)
			(xy 353.087936 -262.153085) (xy 353.096384 -262.099781) (xy 353.113066 -262.048455) (xy 353.137572 -262.00037)
			(xy 353.169299 -261.956711) (xy 353.207465 -261.918553) (xy 353.25113 -261.886835) (xy 353.29922 -261.862339)
			(xy 353.350549 -261.845667) (xy 353.403855 -261.837231) (xy 353.43084 -261.836662) (xy 353.431094 -261.836662)
			(xy 353.440966 -261.83619) (xy 353.459251 -261.828734) (xy 353.466654 -261.822184) (xy 353.466908 -261.82193)
			(xy 353.543616 -261.745222) (xy 353.550675 -261.737507) (xy 353.558415 -261.718105) (xy 353.557776 -261.697225)
			(xy 353.553776 -261.687564) (xy 353.506278 -261.586472) (xy 353.478592 -261.57047) (xy 353.46259 -261.571994)
			(xy 353.43084 -261.573518) (xy 353.404724 -261.573034) (xy 353.353093 -261.56513) (xy 353.303255 -261.549499)
			(xy 353.256359 -261.526501) (xy 353.213486 -261.496667) (xy 353.175625 -261.460684) (xy 353.14365 -261.419383)
			(xy 353.118298 -261.373717) (xy 353.100153 -261.324737) (xy 353.089635 -261.273575) (xy 353.086986 -261.221411)
			(xy 353.092267 -261.169446) (xy 353.105356 -261.118881) (xy 353.125952 -261.070881) (xy 353.153578 -261.026553)
			(xy 353.187599 -260.98692) (xy 353.227229 -260.952896) (xy 353.271554 -260.925265) (xy 353.319552 -260.904666)
			(xy 353.370117 -260.891572) (xy 353.422081 -260.886287) (xy 353.474246 -260.888932) (xy 353.525408 -260.899445)
			(xy 353.574389 -260.917585) (xy 353.620058 -260.942933) (xy 353.661362 -260.974905) (xy 353.697348 -261.012762)
			(xy 353.727186 -261.055633) (xy 353.750188 -261.102527) (xy 353.765823 -261.152364) (xy 353.773731 -261.203994)
			(xy 353.774248 -261.23011) (xy 353.773814 -261.255395) (xy 353.766431 -261.305422) (xy 353.751795 -261.353828)
			(xy 353.730224 -261.399565) (xy 353.71659 -261.420864) (xy 353.711904 -261.428516) (xy 353.707708 -261.44595)
			(xy 353.709796 -261.46376) (xy 353.717909 -261.479751) (xy 353.72421 -261.486142) (xy 353.756214 -261.51586)
			(xy 353.773232 -261.515606) (xy 353.780632 -261.508764) (xy 353.79923 -261.50104) (xy 353.8093 -261.50062)
			(xy 353.933506 -261.50062) (xy 353.946058 -261.499974) (xy 353.968179 -261.488108) (xy 353.97567 -261.478014)
			(xy 354.02266 -261.40791) (xy 354.029071 -261.397212) (xy 354.031623 -261.37243) (xy 354.027486 -261.360666)
			(xy 354.027486 -261.360412) (xy 354.019366 -261.339659) (xy 354.007946 -261.296583) (xy 354.002194 -261.252392)
			(xy 354.001832 -261.23011) (xy 354.002312 -261.204411) (xy 354.009973 -261.153587) (xy 354.025122 -261.104473)
			(xy 354.047423 -261.058165) (xy 354.076376 -261.015698) (xy 354.111336 -260.978021) (xy 354.15152 -260.945975)
			(xy 354.196032 -260.920276) (xy 354.243877 -260.901499) (xy 354.293986 -260.890061) (xy 354.34524 -260.886221)
			(xy 354.396494 -260.890061) (xy 354.446603 -260.901499) (xy 354.494448 -260.920276) (xy 354.53896 -260.945975)
			(xy 354.579144 -260.978021) (xy 354.614104 -261.015698) (xy 354.643057 -261.058165) (xy 354.665358 -261.104473)
			(xy 354.680507 -261.153587) (xy 354.688168 -261.204411) (xy 354.688648 -261.23011) (xy 354.688294 -261.252392)
			(xy 354.682536 -261.296583) (xy 354.671116 -261.33966) (xy 354.662994 -261.360412) (xy 354.662994 -261.360666)
			(xy 354.65891 -261.372439) (xy 354.661449 -261.397199) (xy 354.66782 -261.40791) (xy 354.71481 -261.478014)
			(xy 354.722324 -261.488079) (xy 354.744433 -261.499938) (xy 354.756974 -261.50062) (xy 355.149658 -261.50062)
			(xy 355.160763 -261.500053) (xy 355.180903 -261.490689) (xy 355.18852 -261.482586) (xy 355.245924 -261.41426)
			(xy 355.251766 -261.392924) (xy 355.249734 -261.381748) (xy 355.247356 -261.367196) (xy 355.244816 -261.337818)
			(xy 355.244654 -261.323074) (xy 355.244654 -261.320788) (xy 355.245278 -261.295189) (xy 355.253181 -261.244597)
			(xy 355.268508 -261.195739) (xy 355.29092 -261.149699) (xy 355.31992 -261.107497) (xy 355.354865 -261.070069)
			(xy 355.39498 -261.038244) (xy 355.439375 -261.012729) (xy 355.487067 -260.994089) (xy 355.536999 -260.982737)
			(xy 355.588062 -260.978924) (xy 355.639125 -260.982737) (xy 355.689057 -260.994089) (xy 355.736749 -261.012729)
			(xy 355.781144 -261.038244) (xy 355.821259 -261.070069) (xy 355.856204 -261.107497) (xy 355.885204 -261.149699)
			(xy 355.907616 -261.195739) (xy 355.922943 -261.244597) (xy 355.930846 -261.295189) (xy 355.93147 -261.320788)
			(xy 355.93147 -261.32282) (xy 355.931307 -261.337627) (xy 355.928761 -261.367131) (xy 355.92639 -261.381748)
			(xy 355.924358 -261.392924) (xy 355.9302 -261.41426) (xy 355.987604 -261.482586) (xy 355.995188 -261.490734)
			(xy 356.015348 -261.500113) (xy 356.026466 -261.50062) (xy 356.099618 -261.50062) (xy 356.110727 -261.50006)
			(xy 356.130879 -261.490707) (xy 356.13848 -261.482586) (xy 356.195884 -261.41426) (xy 356.201726 -261.392924)
			(xy 356.199694 -261.381748) (xy 356.197316 -261.367196) (xy 356.194776 -261.337818) (xy 356.194614 -261.323074)
			(xy 356.194614 -261.320788) (xy 356.195238 -261.295189) (xy 356.203141 -261.244597) (xy 356.218468 -261.195739)
			(xy 356.24088 -261.149699) (xy 356.26988 -261.107497) (xy 356.304825 -261.070069) (xy 356.34494 -261.038244)
			(xy 356.389335 -261.012729) (xy 356.437027 -260.994089) (xy 356.486959 -260.982737) (xy 356.538022 -260.978924)
			(xy 356.589085 -260.982737) (xy 356.639017 -260.994089) (xy 356.686709 -261.012729) (xy 356.731104 -261.038244)
			(xy 356.771219 -261.070069) (xy 356.806164 -261.107497) (xy 356.835164 -261.149699) (xy 356.857576 -261.195739)
			(xy 356.872903 -261.244597) (xy 356.880806 -261.295189) (xy 356.88143 -261.320788) (xy 356.88143 -261.32282)
			(xy 356.881267 -261.337627) (xy 356.878721 -261.367131) (xy 356.87635 -261.381748) (xy 356.874318 -261.392924)
			(xy 356.88016 -261.41426) (xy 356.937564 -261.482586) (xy 356.945152 -261.490724) (xy 356.965312 -261.500079)
			(xy 356.976426 -261.50062) (xy 357.049578 -261.50062) (xy 357.060681 -261.500049) (xy 357.080815 -261.49068)
			(xy 357.08844 -261.482586) (xy 357.145844 -261.41426) (xy 357.151686 -261.392924) (xy 357.149654 -261.381748)
			(xy 357.147276 -261.367196) (xy 357.144735 -261.337818) (xy 357.144574 -261.323074) (xy 357.144574 -261.320788)
			(xy 357.145198 -261.295189) (xy 357.153101 -261.244597) (xy 357.168428 -261.195739) (xy 357.19084 -261.149699)
			(xy 357.21984 -261.107497) (xy 357.254785 -261.070069) (xy 357.2949 -261.038244) (xy 357.339295 -261.012729)
			(xy 357.386987 -260.994089) (xy 357.436919 -260.982737) (xy 357.487982 -260.978924) (xy 357.539045 -260.982737)
			(xy 357.588977 -260.994089) (xy 357.636669 -261.012729) (xy 357.681064 -261.038244) (xy 357.721179 -261.070069)
			(xy 357.756124 -261.107497) (xy 357.785124 -261.149699) (xy 357.807536 -261.195739) (xy 357.822863 -261.244597)
			(xy 357.830766 -261.295189) (xy 357.83139 -261.320788) (xy 357.83139 -261.32282) (xy 357.831227 -261.337627)
			(xy 357.828681 -261.367131) (xy 357.82631 -261.381748) (xy 357.824278 -261.392924) (xy 357.83012 -261.41426)
			(xy 357.887524 -261.482586) (xy 357.89511 -261.490731) (xy 357.915269 -261.500102) (xy 357.926386 -261.50062)
			(xy 357.999538 -261.50062) (xy 358.010645 -261.500057) (xy 358.030791 -261.490698) (xy 358.0384 -261.482586)
			(xy 358.095804 -261.41426) (xy 358.101646 -261.392924) (xy 358.099614 -261.381748) (xy 358.097236 -261.367196)
			(xy 358.094696 -261.337818) (xy 358.094534 -261.323074) (xy 358.094534 -261.320788) (xy 358.095158 -261.295189)
			(xy 358.103061 -261.244597) (xy 358.118388 -261.195739) (xy 358.1408 -261.149699) (xy 358.1698 -261.107497)
			(xy 358.204745 -261.070069) (xy 358.24486 -261.038244) (xy 358.289255 -261.012729) (xy 358.336947 -260.994089)
			(xy 358.386879 -260.982737) (xy 358.437942 -260.978924) (xy 358.489005 -260.982737) (xy 358.538937 -260.994089)
			(xy 358.586629 -261.012729) (xy 358.631024 -261.038244) (xy 358.671139 -261.070069) (xy 358.706084 -261.107497)
			(xy 358.735084 -261.149699) (xy 358.757496 -261.195739) (xy 358.772823 -261.244597) (xy 358.780726 -261.295189)
			(xy 358.78135 -261.320788) (xy 358.78135 -261.32282) (xy 358.781187 -261.337627) (xy 358.778641 -261.367131)
			(xy 358.77627 -261.381748) (xy 358.774238 -261.392924) (xy 358.78008 -261.41426) (xy 358.837484 -261.482586)
			(xy 358.845073 -261.490721) (xy 358.865234 -261.500068) (xy 358.876346 -261.50062) (xy 358.949498 -261.50062)
			(xy 358.960609 -261.500064) (xy 358.980768 -261.490716) (xy 358.98836 -261.482586) (xy 359.045764 -261.41426)
			(xy 359.051606 -261.392924) (xy 359.049574 -261.381748) (xy 359.047196 -261.367196) (xy 359.044656 -261.337818)
			(xy 359.044494 -261.323074) (xy 359.044494 -261.320788) (xy 359.045118 -261.295189) (xy 359.053021 -261.244597)
			(xy 359.068348 -261.195739) (xy 359.09076 -261.149699) (xy 359.11976 -261.107497) (xy 359.154705 -261.070069)
			(xy 359.19482 -261.038244) (xy 359.239215 -261.012729) (xy 359.286907 -260.994089) (xy 359.336839 -260.982737)
			(xy 359.387902 -260.978924) (xy 359.438965 -260.982737) (xy 359.488897 -260.994089) (xy 359.536589 -261.012729)
			(xy 359.580984 -261.038244) (xy 359.621099 -261.070069) (xy 359.656044 -261.107497) (xy 359.685044 -261.149699)
			(xy 359.707456 -261.195739) (xy 359.722783 -261.244597) (xy 359.730686 -261.295189) (xy 359.73131 -261.320788)
			(xy 359.73131 -261.32282) (xy 359.731147 -261.337627) (xy 359.728601 -261.367131) (xy 359.72623 -261.381748)
			(xy 359.724198 -261.392924) (xy 359.73004 -261.41426) (xy 359.787444 -261.482586) (xy 359.795031 -261.490727)
			(xy 359.815191 -261.50009) (xy 359.826306 -261.50062) (xy 359.899458 -261.50062) (xy 359.910563 -261.500053)
			(xy 359.930703 -261.490689) (xy 359.93832 -261.482586) (xy 359.995724 -261.41426) (xy 360.001566 -261.392924)
			(xy 359.999534 -261.381748) (xy 359.997156 -261.367196) (xy 359.994616 -261.337818) (xy 359.994454 -261.323074)
			(xy 359.994454 -261.320788) (xy 359.995078 -261.295189) (xy 360.002981 -261.244597) (xy 360.018308 -261.195739)
			(xy 360.04072 -261.149699) (xy 360.06972 -261.107497) (xy 360.104665 -261.070069) (xy 360.14478 -261.038244)
			(xy 360.189175 -261.012729) (xy 360.236867 -260.994089) (xy 360.286799 -260.982737) (xy 360.337862 -260.978924)
			(xy 360.388925 -260.982737) (xy 360.438857 -260.994089) (xy 360.486549 -261.012729) (xy 360.530944 -261.038244)
			(xy 360.571059 -261.070069) (xy 360.606004 -261.107497) (xy 360.635004 -261.149699) (xy 360.657416 -261.195739)
			(xy 360.672743 -261.244597) (xy 360.680646 -261.295189) (xy 360.68127 -261.320788) (xy 360.68127 -261.32282)
			(xy 360.681107 -261.337627) (xy 360.678561 -261.367131) (xy 360.67619 -261.381748) (xy 360.674158 -261.392924)
			(xy 360.68 -261.41426) (xy 360.737404 -261.482586) (xy 360.744988 -261.490734) (xy 360.765148 -261.500113)
			(xy 360.776266 -261.50062) (xy 360.849672 -261.50062) (xy 360.860775 -261.50005) (xy 360.880911 -261.490683)
			(xy 360.888534 -261.482586) (xy 360.945938 -261.41426) (xy 360.95178 -261.392924) (xy 360.949748 -261.381748)
			(xy 360.94737 -261.367196) (xy 360.944829 -261.337818) (xy 360.944668 -261.323074) (xy 360.944668 -261.320788)
			(xy 360.945292 -261.295189) (xy 360.953195 -261.244597) (xy 360.968522 -261.195739) (xy 360.990934 -261.149699)
			(xy 361.019934 -261.107497) (xy 361.054879 -261.070069) (xy 361.094994 -261.038244) (xy 361.139389 -261.012729)
			(xy 361.187081 -260.994089) (xy 361.237013 -260.982737) (xy 361.288076 -260.978924) (xy 361.339139 -260.982737)
			(xy 361.389071 -260.994089) (xy 361.436763 -261.012729) (xy 361.481158 -261.038244) (xy 361.521273 -261.070069)
			(xy 361.556218 -261.107497) (xy 361.585218 -261.149699) (xy 361.60763 -261.195739) (xy 361.622957 -261.244597)
			(xy 361.63086 -261.295189) (xy 361.631484 -261.320788) (xy 361.631484 -261.32282) (xy 361.631321 -261.337627)
			(xy 361.628775 -261.367131) (xy 361.626404 -261.381748) (xy 361.624372 -261.392924) (xy 361.630214 -261.41426)
			(xy 361.687618 -261.482586) (xy 361.695203 -261.490732) (xy 361.715363 -261.500105) (xy 361.72648 -261.50062)
			(xy 361.799632 -261.50062) (xy 361.810739 -261.500058) (xy 361.830888 -261.490701) (xy 361.838494 -261.482586)
			(xy 361.895898 -261.41426) (xy 361.90174 -261.392924) (xy 361.899708 -261.381748) (xy 361.89733 -261.367196)
			(xy 361.89479 -261.337818) (xy 361.894628 -261.323074) (xy 361.894628 -261.320788) (xy 361.895252 -261.295189)
			(xy 361.903155 -261.244597) (xy 361.918482 -261.195739) (xy 361.940894 -261.149699) (xy 361.969894 -261.107497)
			(xy 362.004839 -261.070069) (xy 362.044954 -261.038244) (xy 362.089349 -261.012729) (xy 362.137041 -260.994089)
			(xy 362.186973 -260.982737) (xy 362.238036 -260.978924) (xy 362.289099 -260.982737) (xy 362.339031 -260.994089)
			(xy 362.386723 -261.012729) (xy 362.431118 -261.038244) (xy 362.471233 -261.070069) (xy 362.506178 -261.107497)
			(xy 362.535178 -261.149699) (xy 362.55759 -261.195739) (xy 362.572917 -261.244597) (xy 362.58082 -261.295189)
			(xy 362.581444 -261.320788) (xy 362.581444 -261.32282) (xy 362.581281 -261.337627) (xy 362.578735 -261.367131)
			(xy 362.576364 -261.381748) (xy 362.574332 -261.392924) (xy 362.580174 -261.41426) (xy 362.637578 -261.482586)
			(xy 362.645167 -261.490722) (xy 362.665327 -261.500071) (xy 362.67644 -261.50062) (xy 362.749592 -261.50062)
			(xy 362.760703 -261.500066) (xy 362.780864 -261.490719) (xy 362.788454 -261.482586) (xy 362.845858 -261.41426)
			(xy 362.8517 -261.392924) (xy 362.849668 -261.381748) (xy 362.84729 -261.367196) (xy 362.84475 -261.337818)
			(xy 362.844588 -261.323074) (xy 362.844588 -261.320788) (xy 362.845212 -261.295189) (xy 362.853115 -261.244597)
			(xy 362.868442 -261.195739) (xy 362.890854 -261.149699) (xy 362.919854 -261.107497) (xy 362.954799 -261.070069)
			(xy 362.994914 -261.038244) (xy 363.039309 -261.012729) (xy 363.087001 -260.994089) (xy 363.136933 -260.982737)
			(xy 363.187996 -260.978924) (xy 363.239059 -260.982737) (xy 363.288991 -260.994089) (xy 363.336683 -261.012729)
			(xy 363.381078 -261.038244) (xy 363.421193 -261.070069) (xy 363.456138 -261.107497) (xy 363.485138 -261.149699)
			(xy 363.50755 -261.195739) (xy 363.522877 -261.244597) (xy 363.53078 -261.295189) (xy 363.531404 -261.320788)
			(xy 363.531404 -261.32282) (xy 363.531241 -261.337627) (xy 363.528695 -261.367131) (xy 363.526324 -261.381748)
			(xy 363.524292 -261.392924) (xy 363.530134 -261.41426) (xy 363.587538 -261.482586) (xy 363.595125 -261.490728)
			(xy 363.615284 -261.500093) (xy 363.6264 -261.50062) (xy 363.699552 -261.50062) (xy 363.710657 -261.500054)
			(xy 363.7308 -261.490692) (xy 363.738414 -261.482586) (xy 363.795818 -261.41426) (xy 363.80166 -261.392924)
			(xy 363.799628 -261.381748) (xy 363.79725 -261.367196) (xy 363.79471 -261.337818) (xy 363.794548 -261.323074)
			(xy 363.794548 -261.320788) (xy 363.795172 -261.295189) (xy 363.803075 -261.244597) (xy 363.818402 -261.195739)
			(xy 363.840814 -261.149699) (xy 363.869814 -261.107497) (xy 363.904759 -261.070069) (xy 363.944874 -261.038244)
			(xy 363.989269 -261.012729) (xy 364.036961 -260.994089) (xy 364.086893 -260.982737) (xy 364.137956 -260.978924)
			(xy 364.189019 -260.982737) (xy 364.238951 -260.994089) (xy 364.286643 -261.012729) (xy 364.331038 -261.038244)
			(xy 364.371153 -261.070069) (xy 364.406098 -261.107497) (xy 364.435098 -261.149699) (xy 364.45751 -261.195739)
			(xy 364.472837 -261.244597) (xy 364.48074 -261.295189) (xy 364.481364 -261.320788) (xy 364.481364 -261.32282)
			(xy 364.481201 -261.337627) (xy 364.478655 -261.367131) (xy 364.476284 -261.381748) (xy 364.474252 -261.392924)
			(xy 364.480094 -261.41426) (xy 364.537498 -261.482586) (xy 364.545082 -261.490735) (xy 364.565242 -261.500116)
			(xy 364.57636 -261.50062) (xy 364.969044 -261.50062) (xy 364.981592 -261.499966) (xy 365.003698 -261.48809)
			(xy 365.011208 -261.478014) (xy 365.058198 -261.40791) (xy 365.064606 -261.397211) (xy 365.067155 -261.372431)
			(xy 365.063024 -261.360666) (xy 365.063024 -261.360412) (xy 365.054906 -261.339659) (xy 365.043488 -261.296583)
			(xy 365.037737 -261.252392) (xy 365.03737 -261.23011) (xy 365.03785 -261.204411) (xy 365.045511 -261.153587)
			(xy 365.06066 -261.104473) (xy 365.082961 -261.058165) (xy 365.111914 -261.015698) (xy 365.146874 -260.978021)
			(xy 365.187058 -260.945975) (xy 365.23157 -260.920276) (xy 365.279415 -260.901499) (xy 365.329524 -260.890061)
			(xy 365.380778 -260.886221) (xy 365.432032 -260.890061) (xy 365.482141 -260.901499) (xy 365.529986 -260.920276)
			(xy 365.574498 -260.945975) (xy 365.614682 -260.978021) (xy 365.649642 -261.015698) (xy 365.678595 -261.058165)
			(xy 365.700896 -261.104473) (xy 365.707527 -261.12597) (xy 369.578902 -261.12597) (xy 369.582862 -261.076916)
			(xy 369.594639 -261.029132) (xy 369.61393 -260.983856) (xy 369.640233 -260.94226) (xy 369.672868 -260.905423)
			(xy 369.710989 -260.874298) (xy 369.75361 -260.849691) (xy 369.799626 -260.832239) (xy 369.847845 -260.822395)
			(xy 369.89702 -260.820414) (xy 369.945875 -260.826346) (xy 369.993146 -260.840038) (xy 370.037608 -260.861136)
			(xy 370.078111 -260.889092) (xy 370.113604 -260.923184) (xy 370.143169 -260.962528) (xy 370.16604 -261.006105)
			(xy 370.181624 -261.052786) (xy 370.189519 -261.101363) (xy 370.190014 -261.12597) (xy 371.45901 -261.12597)
			(xy 371.46297 -261.076916) (xy 371.474747 -261.029132) (xy 371.494038 -260.983856) (xy 371.520341 -260.94226)
			(xy 371.552976 -260.905423) (xy 371.591097 -260.874298) (xy 371.633718 -260.849691) (xy 371.679734 -260.832239)
			(xy 371.727953 -260.822395) (xy 371.777128 -260.820414) (xy 371.825983 -260.826346) (xy 371.873254 -260.840038)
			(xy 371.917716 -260.861136) (xy 371.958219 -260.889092) (xy 371.993712 -260.923184) (xy 372.023277 -260.962528)
			(xy 372.046148 -261.006105) (xy 372.061732 -261.052786) (xy 372.069627 -261.101363) (xy 372.070122 -261.12597)
			(xy 373.339118 -261.12597) (xy 373.343078 -261.076916) (xy 373.354855 -261.029132) (xy 373.374146 -260.983856)
			(xy 373.400449 -260.94226) (xy 373.433084 -260.905423) (xy 373.471205 -260.874298) (xy 373.513826 -260.849691)
			(xy 373.559842 -260.832239) (xy 373.608061 -260.822395) (xy 373.657236 -260.820414) (xy 373.706091 -260.826346)
			(xy 373.753362 -260.840038) (xy 373.797824 -260.861136) (xy 373.838327 -260.889092) (xy 373.87382 -260.923184)
			(xy 373.903385 -260.962528) (xy 373.926256 -261.006105) (xy 373.94184 -261.052786) (xy 373.949735 -261.101363)
			(xy 373.95023 -261.12597) (xy 375.218972 -261.12597) (xy 375.222932 -261.076916) (xy 375.234709 -261.029132)
			(xy 375.254 -260.983856) (xy 375.280303 -260.94226) (xy 375.312938 -260.905423) (xy 375.351059 -260.874298)
			(xy 375.39368 -260.849691) (xy 375.439696 -260.832239) (xy 375.487915 -260.822395) (xy 375.53709 -260.820414)
			(xy 375.585945 -260.826346) (xy 375.633216 -260.840038) (xy 375.677678 -260.861136) (xy 375.718181 -260.889092)
			(xy 375.753674 -260.923184) (xy 375.783239 -260.962528) (xy 375.80611 -261.006105) (xy 375.821694 -261.052786)
			(xy 375.829589 -261.101363) (xy 375.830084 -261.12597) (xy 376.159026 -261.12597) (xy 376.162986 -261.076916)
			(xy 376.174763 -261.029132) (xy 376.194054 -260.983856) (xy 376.220357 -260.94226) (xy 376.252992 -260.905423)
			(xy 376.291113 -260.874298) (xy 376.333734 -260.849691) (xy 376.37975 -260.832239) (xy 376.427969 -260.822395)
			(xy 376.477144 -260.820414) (xy 376.525999 -260.826346) (xy 376.57327 -260.840038) (xy 376.617732 -260.861136)
			(xy 376.658235 -260.889092) (xy 376.693728 -260.923184) (xy 376.723293 -260.962528) (xy 376.746164 -261.006105)
			(xy 376.761748 -261.052786) (xy 376.769643 -261.101363) (xy 376.770138 -261.12597) (xy 377.09908 -261.12597)
			(xy 377.10304 -261.076916) (xy 377.114817 -261.029132) (xy 377.134108 -260.983856) (xy 377.160411 -260.94226)
			(xy 377.193046 -260.905423) (xy 377.231167 -260.874298) (xy 377.273788 -260.849691) (xy 377.319804 -260.832239)
			(xy 377.368023 -260.822395) (xy 377.417198 -260.820414) (xy 377.466053 -260.826346) (xy 377.513324 -260.840038)
			(xy 377.557786 -260.861136) (xy 377.598289 -260.889092) (xy 377.633782 -260.923184) (xy 377.663347 -260.962528)
			(xy 377.686218 -261.006105) (xy 377.701802 -261.052786) (xy 377.709697 -261.101363) (xy 377.710192 -261.12597)
			(xy 378.039134 -261.12597) (xy 378.043094 -261.076916) (xy 378.054871 -261.029132) (xy 378.074162 -260.983856)
			(xy 378.100465 -260.94226) (xy 378.1331 -260.905423) (xy 378.171221 -260.874298) (xy 378.213842 -260.849691)
			(xy 378.259858 -260.832239) (xy 378.308077 -260.822395) (xy 378.357252 -260.820414) (xy 378.406107 -260.826346)
			(xy 378.453378 -260.840038) (xy 378.49784 -260.861136) (xy 378.538343 -260.889092) (xy 378.573836 -260.923184)
			(xy 378.603401 -260.962528) (xy 378.626272 -261.006105) (xy 378.641856 -261.052786) (xy 378.649751 -261.101363)
			(xy 378.650246 -261.12597) (xy 378.978934 -261.12597) (xy 378.982894 -261.076916) (xy 378.994671 -261.029132)
			(xy 379.013962 -260.983856) (xy 379.040265 -260.94226) (xy 379.0729 -260.905423) (xy 379.111021 -260.874298)
			(xy 379.153642 -260.849691) (xy 379.199658 -260.832239) (xy 379.247877 -260.822395) (xy 379.297052 -260.820414)
			(xy 379.345907 -260.826346) (xy 379.393178 -260.840038) (xy 379.43764 -260.861136) (xy 379.478143 -260.889092)
			(xy 379.513636 -260.923184) (xy 379.543201 -260.962528) (xy 379.566072 -261.006105) (xy 379.581656 -261.052786)
			(xy 379.589551 -261.101363) (xy 379.590046 -261.12597) (xy 379.918988 -261.12597) (xy 379.922948 -261.076916)
			(xy 379.934725 -261.029132) (xy 379.954016 -260.983856) (xy 379.980319 -260.94226) (xy 380.012954 -260.905423)
			(xy 380.051075 -260.874298) (xy 380.093696 -260.849691) (xy 380.139712 -260.832239) (xy 380.187931 -260.822395)
			(xy 380.237106 -260.820414) (xy 380.285961 -260.826346) (xy 380.333232 -260.840038) (xy 380.377694 -260.861136)
			(xy 380.418197 -260.889092) (xy 380.45369 -260.923184) (xy 380.483255 -260.962528) (xy 380.506126 -261.006105)
			(xy 380.52171 -261.052786) (xy 380.529605 -261.101363) (xy 380.5301 -261.12597) (xy 380.859042 -261.12597)
			(xy 380.863002 -261.076916) (xy 380.874779 -261.029132) (xy 380.89407 -260.983856) (xy 380.920373 -260.94226)
			(xy 380.953008 -260.905423) (xy 380.991129 -260.874298) (xy 381.03375 -260.849691) (xy 381.079766 -260.832239)
			(xy 381.127985 -260.822395) (xy 381.17716 -260.820414) (xy 381.226015 -260.826346) (xy 381.273286 -260.840038)
			(xy 381.317748 -260.861136) (xy 381.358251 -260.889092) (xy 381.393744 -260.923184) (xy 381.423309 -260.962528)
			(xy 381.44618 -261.006105) (xy 381.461764 -261.052786) (xy 381.469659 -261.101363) (xy 381.470154 -261.12597)
			(xy 381.469659 -261.150577) (xy 381.461764 -261.199154) (xy 381.44618 -261.245835) (xy 381.423309 -261.289412)
			(xy 381.393744 -261.328756) (xy 381.358251 -261.362848) (xy 381.317748 -261.390804) (xy 381.273286 -261.411902)
			(xy 381.226015 -261.425594) (xy 381.17716 -261.431526) (xy 381.127985 -261.429545) (xy 381.079766 -261.419701)
			(xy 381.03375 -261.402249) (xy 380.991129 -261.377642) (xy 380.953008 -261.346517) (xy 380.920373 -261.30968)
			(xy 380.89407 -261.268084) (xy 380.874779 -261.222808) (xy 380.863002 -261.175024) (xy 380.859042 -261.12597)
			(xy 380.5301 -261.12597) (xy 380.529605 -261.150577) (xy 380.52171 -261.199154) (xy 380.506126 -261.245835)
			(xy 380.483255 -261.289412) (xy 380.45369 -261.328756) (xy 380.418197 -261.362848) (xy 380.377694 -261.390804)
			(xy 380.333232 -261.411902) (xy 380.285961 -261.425594) (xy 380.237106 -261.431526) (xy 380.187931 -261.429545)
			(xy 380.139712 -261.419701) (xy 380.093696 -261.402249) (xy 380.051075 -261.377642) (xy 380.012954 -261.346517)
			(xy 379.980319 -261.30968) (xy 379.954016 -261.268084) (xy 379.934725 -261.222808) (xy 379.922948 -261.175024)
			(xy 379.918988 -261.12597) (xy 379.590046 -261.12597) (xy 379.589551 -261.150577) (xy 379.581656 -261.199154)
			(xy 379.566072 -261.245835) (xy 379.543201 -261.289412) (xy 379.513636 -261.328756) (xy 379.478143 -261.362848)
			(xy 379.43764 -261.390804) (xy 379.393178 -261.411902) (xy 379.345907 -261.425594) (xy 379.297052 -261.431526)
			(xy 379.247877 -261.429545) (xy 379.199658 -261.419701) (xy 379.153642 -261.402249) (xy 379.111021 -261.377642)
			(xy 379.0729 -261.346517) (xy 379.040265 -261.30968) (xy 379.013962 -261.268084) (xy 378.994671 -261.222808)
			(xy 378.982894 -261.175024) (xy 378.978934 -261.12597) (xy 378.650246 -261.12597) (xy 378.649751 -261.150577)
			(xy 378.641856 -261.199154) (xy 378.626272 -261.245835) (xy 378.603401 -261.289412) (xy 378.573836 -261.328756)
			(xy 378.538343 -261.362848) (xy 378.49784 -261.390804) (xy 378.453378 -261.411902) (xy 378.406107 -261.425594)
			(xy 378.357252 -261.431526) (xy 378.308077 -261.429545) (xy 378.259858 -261.419701) (xy 378.213842 -261.402249)
			(xy 378.171221 -261.377642) (xy 378.1331 -261.346517) (xy 378.100465 -261.30968) (xy 378.074162 -261.268084)
			(xy 378.054871 -261.222808) (xy 378.043094 -261.175024) (xy 378.039134 -261.12597) (xy 377.710192 -261.12597)
			(xy 377.709697 -261.150577) (xy 377.701802 -261.199154) (xy 377.686218 -261.245835) (xy 377.663347 -261.289412)
			(xy 377.633782 -261.328756) (xy 377.598289 -261.362848) (xy 377.557786 -261.390804) (xy 377.513324 -261.411902)
			(xy 377.466053 -261.425594) (xy 377.417198 -261.431526) (xy 377.368023 -261.429545) (xy 377.319804 -261.419701)
			(xy 377.273788 -261.402249) (xy 377.231167 -261.377642) (xy 377.193046 -261.346517) (xy 377.160411 -261.30968)
			(xy 377.134108 -261.268084) (xy 377.114817 -261.222808) (xy 377.10304 -261.175024) (xy 377.09908 -261.12597)
			(xy 376.770138 -261.12597) (xy 376.769643 -261.150577) (xy 376.761748 -261.199154) (xy 376.746164 -261.245835)
			(xy 376.723293 -261.289412) (xy 376.693728 -261.328756) (xy 376.658235 -261.362848) (xy 376.617732 -261.390804)
			(xy 376.57327 -261.411902) (xy 376.525999 -261.425594) (xy 376.477144 -261.431526) (xy 376.427969 -261.429545)
			(xy 376.37975 -261.419701) (xy 376.333734 -261.402249) (xy 376.291113 -261.377642) (xy 376.252992 -261.346517)
			(xy 376.220357 -261.30968) (xy 376.194054 -261.268084) (xy 376.174763 -261.222808) (xy 376.162986 -261.175024)
			(xy 376.159026 -261.12597) (xy 375.830084 -261.12597) (xy 375.829589 -261.150577) (xy 375.821694 -261.199154)
			(xy 375.80611 -261.245835) (xy 375.783239 -261.289412) (xy 375.753674 -261.328756) (xy 375.718181 -261.362848)
			(xy 375.677678 -261.390804) (xy 375.633216 -261.411902) (xy 375.585945 -261.425594) (xy 375.53709 -261.431526)
			(xy 375.487915 -261.429545) (xy 375.439696 -261.419701) (xy 375.39368 -261.402249) (xy 375.351059 -261.377642)
			(xy 375.312938 -261.346517) (xy 375.280303 -261.30968) (xy 375.254 -261.268084) (xy 375.234709 -261.222808)
			(xy 375.222932 -261.175024) (xy 375.218972 -261.12597) (xy 373.95023 -261.12597) (xy 373.949735 -261.150577)
			(xy 373.94184 -261.199154) (xy 373.926256 -261.245835) (xy 373.903385 -261.289412) (xy 373.87382 -261.328756)
			(xy 373.838327 -261.362848) (xy 373.797824 -261.390804) (xy 373.753362 -261.411902) (xy 373.706091 -261.425594)
			(xy 373.657236 -261.431526) (xy 373.608061 -261.429545) (xy 373.559842 -261.419701) (xy 373.513826 -261.402249)
			(xy 373.471205 -261.377642) (xy 373.433084 -261.346517) (xy 373.400449 -261.30968) (xy 373.374146 -261.268084)
			(xy 373.354855 -261.222808) (xy 373.343078 -261.175024) (xy 373.339118 -261.12597) (xy 372.070122 -261.12597)
			(xy 372.069627 -261.150577) (xy 372.061732 -261.199154) (xy 372.046148 -261.245835) (xy 372.023277 -261.289412)
			(xy 371.993712 -261.328756) (xy 371.958219 -261.362848) (xy 371.917716 -261.390804) (xy 371.873254 -261.411902)
			(xy 371.825983 -261.425594) (xy 371.777128 -261.431526) (xy 371.727953 -261.429545) (xy 371.679734 -261.419701)
			(xy 371.633718 -261.402249) (xy 371.591097 -261.377642) (xy 371.552976 -261.346517) (xy 371.520341 -261.30968)
			(xy 371.494038 -261.268084) (xy 371.474747 -261.222808) (xy 371.46297 -261.175024) (xy 371.45901 -261.12597)
			(xy 370.190014 -261.12597) (xy 370.189519 -261.150577) (xy 370.181624 -261.199154) (xy 370.16604 -261.245835)
			(xy 370.143169 -261.289412) (xy 370.113604 -261.328756) (xy 370.078111 -261.362848) (xy 370.037608 -261.390804)
			(xy 369.993146 -261.411902) (xy 369.945875 -261.425594) (xy 369.89702 -261.431526) (xy 369.847845 -261.429545)
			(xy 369.799626 -261.419701) (xy 369.75361 -261.402249) (xy 369.710989 -261.377642) (xy 369.672868 -261.346517)
			(xy 369.640233 -261.30968) (xy 369.61393 -261.268084) (xy 369.594639 -261.222808) (xy 369.582862 -261.175024)
			(xy 369.578902 -261.12597) (xy 365.707527 -261.12597) (xy 365.716045 -261.153587) (xy 365.723706 -261.204411)
			(xy 365.724186 -261.23011) (xy 365.723832 -261.252392) (xy 365.718072 -261.296583) (xy 365.706651 -261.339659)
			(xy 365.698532 -261.360412) (xy 365.698532 -261.360666) (xy 365.694446 -261.372438) (xy 365.696987 -261.397199)
			(xy 365.703358 -261.40791) (xy 365.750348 -261.478014) (xy 365.757865 -261.488072) (xy 365.779974 -261.499916)
			(xy 365.792512 -261.50062) (xy 367.953798 -261.50062) (xy 367.963868 -261.501043) (xy 367.982471 -261.508759)
			(xy 367.989866 -261.515606) (xy 368.410236 -261.935976) (xy 370.049056 -261.935976) (xy 370.053016 -261.886922)
			(xy 370.064793 -261.839138) (xy 370.084084 -261.793862) (xy 370.110387 -261.752266) (xy 370.143022 -261.715429)
			(xy 370.181143 -261.684304) (xy 370.223764 -261.659697) (xy 370.26978 -261.642245) (xy 370.317999 -261.632401)
			(xy 370.367174 -261.63042) (xy 370.416029 -261.636352) (xy 370.4633 -261.650044) (xy 370.507762 -261.671142)
			(xy 370.548265 -261.699098) (xy 370.583758 -261.73319) (xy 370.613323 -261.772534) (xy 370.636194 -261.816111)
			(xy 370.651778 -261.862792) (xy 370.659673 -261.911369) (xy 370.660168 -261.935976) (xy 371.92891 -261.935976)
			(xy 371.93287 -261.886922) (xy 371.944647 -261.839138) (xy 371.963938 -261.793862) (xy 371.990241 -261.752266)
			(xy 372.022876 -261.715429) (xy 372.060997 -261.684304) (xy 372.103618 -261.659697) (xy 372.149634 -261.642245)
			(xy 372.197853 -261.632401) (xy 372.247028 -261.63042) (xy 372.295883 -261.636352) (xy 372.343154 -261.650044)
			(xy 372.387616 -261.671142) (xy 372.428119 -261.699098) (xy 372.463612 -261.73319) (xy 372.493177 -261.772534)
			(xy 372.516048 -261.816111) (xy 372.531632 -261.862792) (xy 372.539527 -261.911369) (xy 372.540022 -261.935976)
			(xy 373.809018 -261.935976) (xy 373.812978 -261.886922) (xy 373.824755 -261.839138) (xy 373.844046 -261.793862)
			(xy 373.870349 -261.752266) (xy 373.902984 -261.715429) (xy 373.941105 -261.684304) (xy 373.983726 -261.659697)
			(xy 374.029742 -261.642245) (xy 374.077961 -261.632401) (xy 374.127136 -261.63042) (xy 374.175991 -261.636352)
			(xy 374.223262 -261.650044) (xy 374.267724 -261.671142) (xy 374.308227 -261.699098) (xy 374.34372 -261.73319)
			(xy 374.373285 -261.772534) (xy 374.396156 -261.816111) (xy 374.41174 -261.862792) (xy 374.419635 -261.911369)
			(xy 374.42013 -261.935976) (xy 375.678695 -261.935976) (xy 375.68279 -261.885248) (xy 375.694969 -261.835834)
			(xy 375.714917 -261.789014) (xy 375.742118 -261.746) (xy 375.775866 -261.707906) (xy 375.815288 -261.675719)
			(xy 375.859362 -261.650273) (xy 375.906948 -261.632226) (xy 375.956812 -261.622046) (xy 376.007664 -261.619997)
			(xy 376.058185 -261.626131) (xy 376.107069 -261.640291) (xy 376.153048 -261.662108) (xy 376.194932 -261.691018)
			(xy 376.231636 -261.726273) (xy 376.262209 -261.766959) (xy 376.28586 -261.812022) (xy 376.301976 -261.860296)
			(xy 376.31014 -261.91053) (xy 376.310652 -261.935976) (xy 376.628926 -261.935976) (xy 376.632886 -261.886922)
			(xy 376.644663 -261.839138) (xy 376.663954 -261.793862) (xy 376.690257 -261.752266) (xy 376.722892 -261.715429)
			(xy 376.761013 -261.684304) (xy 376.803634 -261.659697) (xy 376.84965 -261.642245) (xy 376.897869 -261.632401)
			(xy 376.947044 -261.63042) (xy 376.995899 -261.636352) (xy 377.04317 -261.650044) (xy 377.087632 -261.671142)
			(xy 377.128135 -261.699098) (xy 377.163628 -261.73319) (xy 377.193193 -261.772534) (xy 377.216064 -261.816111)
			(xy 377.231648 -261.862792) (xy 377.239543 -261.911369) (xy 377.240038 -261.935976) (xy 377.56898 -261.935976)
			(xy 377.57294 -261.886922) (xy 377.584717 -261.839138) (xy 377.604008 -261.793862) (xy 377.630311 -261.752266)
			(xy 377.662946 -261.715429) (xy 377.701067 -261.684304) (xy 377.743688 -261.659697) (xy 377.789704 -261.642245)
			(xy 377.837923 -261.632401) (xy 377.887098 -261.63042) (xy 377.935953 -261.636352) (xy 377.983224 -261.650044)
			(xy 378.027686 -261.671142) (xy 378.068189 -261.699098) (xy 378.103682 -261.73319) (xy 378.133247 -261.772534)
			(xy 378.156118 -261.816111) (xy 378.171702 -261.862792) (xy 378.179597 -261.911369) (xy 378.180092 -261.935976)
			(xy 378.509034 -261.935976) (xy 378.512994 -261.886922) (xy 378.524771 -261.839138) (xy 378.544062 -261.793862)
			(xy 378.570365 -261.752266) (xy 378.603 -261.715429) (xy 378.641121 -261.684304) (xy 378.683742 -261.659697)
			(xy 378.729758 -261.642245) (xy 378.777977 -261.632401) (xy 378.827152 -261.63042) (xy 378.876007 -261.636352)
			(xy 378.923278 -261.650044) (xy 378.96774 -261.671142) (xy 379.008243 -261.699098) (xy 379.043736 -261.73319)
			(xy 379.073301 -261.772534) (xy 379.096172 -261.816111) (xy 379.111756 -261.862792) (xy 379.119651 -261.911369)
			(xy 379.120146 -261.935976) (xy 379.438657 -261.935976) (xy 379.442752 -261.885248) (xy 379.454931 -261.835834)
			(xy 379.474879 -261.789014) (xy 379.50208 -261.746) (xy 379.535828 -261.707906) (xy 379.57525 -261.675719)
			(xy 379.619324 -261.650273) (xy 379.66691 -261.632226) (xy 379.716774 -261.622046) (xy 379.767626 -261.619997)
			(xy 379.818147 -261.626131) (xy 379.867031 -261.640291) (xy 379.91301 -261.662108) (xy 379.954894 -261.691018)
			(xy 379.991598 -261.726273) (xy 380.022171 -261.766959) (xy 380.045822 -261.812022) (xy 380.061938 -261.860296)
			(xy 380.070102 -261.91053) (xy 380.070614 -261.935976) (xy 380.070102 -261.961422) (xy 380.061938 -262.011656)
			(xy 380.045822 -262.05993) (xy 380.022171 -262.104993) (xy 379.991598 -262.145679) (xy 379.954894 -262.180934)
			(xy 379.91301 -262.209844) (xy 379.867031 -262.231661) (xy 379.818147 -262.245821) (xy 379.767626 -262.251955)
			(xy 379.716774 -262.249906) (xy 379.66691 -262.239726) (xy 379.619324 -262.221679) (xy 379.57525 -262.196233)
			(xy 379.535828 -262.164046) (xy 379.50208 -262.125952) (xy 379.474879 -262.082938) (xy 379.454931 -262.036118)
			(xy 379.442752 -261.986704) (xy 379.438657 -261.935976) (xy 379.120146 -261.935976) (xy 379.119651 -261.960583)
			(xy 379.111756 -262.00916) (xy 379.096172 -262.055841) (xy 379.073301 -262.099418) (xy 379.043736 -262.138762)
			(xy 379.008243 -262.172854) (xy 378.96774 -262.20081) (xy 378.923278 -262.221908) (xy 378.876007 -262.2356)
			(xy 378.827152 -262.241532) (xy 378.777977 -262.239551) (xy 378.729758 -262.229707) (xy 378.683742 -262.212255)
			(xy 378.641121 -262.187648) (xy 378.603 -262.156523) (xy 378.570365 -262.119686) (xy 378.544062 -262.07809)
			(xy 378.524771 -262.032814) (xy 378.512994 -261.98503) (xy 378.509034 -261.935976) (xy 378.180092 -261.935976)
			(xy 378.179597 -261.960583) (xy 378.171702 -262.00916) (xy 378.156118 -262.055841) (xy 378.133247 -262.099418)
			(xy 378.103682 -262.138762) (xy 378.068189 -262.172854) (xy 378.027686 -262.20081) (xy 377.983224 -262.221908)
			(xy 377.935953 -262.2356) (xy 377.887098 -262.241532) (xy 377.837923 -262.239551) (xy 377.789704 -262.229707)
			(xy 377.743688 -262.212255) (xy 377.701067 -262.187648) (xy 377.662946 -262.156523) (xy 377.630311 -262.119686)
			(xy 377.604008 -262.07809) (xy 377.584717 -262.032814) (xy 377.57294 -261.98503) (xy 377.56898 -261.935976)
			(xy 377.240038 -261.935976) (xy 377.239543 -261.960583) (xy 377.231648 -262.00916) (xy 377.216064 -262.055841)
			(xy 377.193193 -262.099418) (xy 377.163628 -262.138762) (xy 377.128135 -262.172854) (xy 377.087632 -262.20081)
			(xy 377.04317 -262.221908) (xy 376.995899 -262.2356) (xy 376.947044 -262.241532) (xy 376.897869 -262.239551)
			(xy 376.84965 -262.229707) (xy 376.803634 -262.212255) (xy 376.761013 -262.187648) (xy 376.722892 -262.156523)
			(xy 376.690257 -262.119686) (xy 376.663954 -262.07809) (xy 376.644663 -262.032814) (xy 376.632886 -261.98503)
			(xy 376.628926 -261.935976) (xy 376.310652 -261.935976) (xy 376.31014 -261.961422) (xy 376.301976 -262.011656)
			(xy 376.28586 -262.05993) (xy 376.262209 -262.104993) (xy 376.231636 -262.145679) (xy 376.194932 -262.180934)
			(xy 376.153048 -262.209844) (xy 376.107069 -262.231661) (xy 376.058185 -262.245821) (xy 376.007664 -262.251955)
			(xy 375.956812 -262.249906) (xy 375.906948 -262.239726) (xy 375.859362 -262.221679) (xy 375.815288 -262.196233)
			(xy 375.775866 -262.164046) (xy 375.742118 -262.125952) (xy 375.714917 -262.082938) (xy 375.694969 -262.036118)
			(xy 375.68279 -261.986704) (xy 375.678695 -261.935976) (xy 374.42013 -261.935976) (xy 374.419635 -261.960583)
			(xy 374.41174 -262.00916) (xy 374.396156 -262.055841) (xy 374.373285 -262.099418) (xy 374.34372 -262.138762)
			(xy 374.308227 -262.172854) (xy 374.267724 -262.20081) (xy 374.223262 -262.221908) (xy 374.175991 -262.2356)
			(xy 374.127136 -262.241532) (xy 374.077961 -262.239551) (xy 374.029742 -262.229707) (xy 373.983726 -262.212255)
			(xy 373.941105 -262.187648) (xy 373.902984 -262.156523) (xy 373.870349 -262.119686) (xy 373.844046 -262.07809)
			(xy 373.824755 -262.032814) (xy 373.812978 -261.98503) (xy 373.809018 -261.935976) (xy 372.540022 -261.935976)
			(xy 372.539527 -261.960583) (xy 372.531632 -262.00916) (xy 372.516048 -262.055841) (xy 372.493177 -262.099418)
			(xy 372.463612 -262.138762) (xy 372.428119 -262.172854) (xy 372.387616 -262.20081) (xy 372.343154 -262.221908)
			(xy 372.295883 -262.2356) (xy 372.247028 -262.241532) (xy 372.197853 -262.239551) (xy 372.149634 -262.229707)
			(xy 372.103618 -262.212255) (xy 372.060997 -262.187648) (xy 372.022876 -262.156523) (xy 371.990241 -262.119686)
			(xy 371.963938 -262.07809) (xy 371.944647 -262.032814) (xy 371.93287 -261.98503) (xy 371.92891 -261.935976)
			(xy 370.660168 -261.935976) (xy 370.659673 -261.960583) (xy 370.651778 -262.00916) (xy 370.636194 -262.055841)
			(xy 370.613323 -262.099418) (xy 370.583758 -262.138762) (xy 370.548265 -262.172854) (xy 370.507762 -262.20081)
			(xy 370.4633 -262.221908) (xy 370.416029 -262.2356) (xy 370.367174 -262.241532) (xy 370.317999 -262.239551)
			(xy 370.26978 -262.229707) (xy 370.223764 -262.212255) (xy 370.181143 -262.187648) (xy 370.143022 -262.156523)
			(xy 370.110387 -262.119686) (xy 370.084084 -262.07809) (xy 370.064793 -262.032814) (xy 370.053016 -261.98503)
			(xy 370.049056 -261.935976) (xy 368.410236 -261.935976) (xy 369.415314 -262.941054) (xy 369.415822 -262.941562)
			(xy 369.423202 -262.948148) (xy 369.441501 -262.955608) (xy 369.451382 -262.95604) (xy 369.49253 -262.95604)
			(xy 369.504287 -262.955448) (xy 369.525344 -262.944987) (xy 369.532916 -262.935974) (xy 369.58905 -262.86206)
			(xy 369.593622 -262.838946) (xy 369.59032 -262.827262) (xy 369.58522 -262.807524) (xy 369.579737 -262.767127)
			(xy 369.579398 -262.746744) (xy 369.579398 -262.745982) (xy 369.57992 -262.720727) (xy 369.588233 -262.670905)
			(xy 369.604634 -262.623131) (xy 369.628675 -262.578708) (xy 369.659699 -262.538848) (xy 369.696861 -262.504638)
			(xy 369.739147 -262.477012) (xy 369.785403 -262.456722) (xy 369.834368 -262.444322) (xy 369.884706 -262.440151)
			(xy 369.935044 -262.444322) (xy 369.984009 -262.456722) (xy 370.030265 -262.477012) (xy 370.072551 -262.504638)
			(xy 370.109713 -262.538848) (xy 370.140737 -262.578708) (xy 370.164778 -262.623131) (xy 370.181179 -262.670905)
			(xy 370.189492 -262.720727) (xy 370.190014 -262.745982) (xy 370.190014 -262.746744) (xy 370.189637 -262.767124)
			(xy 370.184153 -262.807516) (xy 370.179092 -262.827262) (xy 370.17579 -262.838946) (xy 370.180362 -262.86206)
			(xy 370.236496 -262.935974) (xy 370.244088 -262.94496) (xy 370.265134 -262.955411) (xy 370.276882 -262.95604)
			(xy 370.432584 -262.95604) (xy 370.444335 -262.955436) (xy 370.465373 -262.944962) (xy 370.47297 -262.935974)
			(xy 370.529104 -262.86206) (xy 370.533676 -262.838946) (xy 370.530374 -262.827262) (xy 370.525275 -262.807524)
			(xy 370.519793 -262.767127) (xy 370.519452 -262.746744) (xy 370.519452 -262.745982) (xy 370.519974 -262.720727)
			(xy 370.528287 -262.670905) (xy 370.544688 -262.623131) (xy 370.568729 -262.578708) (xy 370.599753 -262.538848)
			(xy 370.636915 -262.504638) (xy 370.679201 -262.477012) (xy 370.725457 -262.456722) (xy 370.774422 -262.444322)
			(xy 370.82476 -262.440151) (xy 370.875098 -262.444322) (xy 370.924063 -262.456722) (xy 370.970319 -262.477012)
			(xy 371.012605 -262.504638) (xy 371.049767 -262.538848) (xy 371.080791 -262.578708) (xy 371.104832 -262.623131)
			(xy 371.121233 -262.670905) (xy 371.129546 -262.720727) (xy 371.130068 -262.745982) (xy 371.130068 -262.746744)
			(xy 371.129692 -262.767125) (xy 371.124208 -262.807517) (xy 371.119146 -262.827262) (xy 371.115844 -262.838946)
			(xy 371.120416 -262.86206) (xy 371.17655 -262.935974) (xy 371.184139 -262.944967) (xy 371.205185 -262.955437)
			(xy 371.216936 -262.95604) (xy 371.372638 -262.95604) (xy 371.384394 -262.955446) (xy 371.405448 -262.944983)
			(xy 371.413024 -262.935974) (xy 371.469158 -262.86206) (xy 371.47373 -262.838946) (xy 371.470428 -262.827262)
			(xy 371.465328 -262.807524) (xy 371.459845 -262.767127) (xy 371.459506 -262.746744) (xy 371.459506 -262.745982)
			(xy 371.460028 -262.720727) (xy 371.468341 -262.670905) (xy 371.484742 -262.623131) (xy 371.508783 -262.578708)
			(xy 371.539807 -262.538848) (xy 371.576969 -262.504638) (xy 371.619255 -262.477012) (xy 371.665511 -262.456722)
			(xy 371.714476 -262.444322) (xy 371.764814 -262.440151) (xy 371.815152 -262.444322) (xy 371.864117 -262.456722)
			(xy 371.910373 -262.477012) (xy 371.952659 -262.504638) (xy 371.989821 -262.538848) (xy 372.020845 -262.578708)
			(xy 372.044886 -262.623131) (xy 372.061287 -262.670905) (xy 372.0696 -262.720727) (xy 372.070122 -262.745982)
			(xy 372.070122 -262.746744) (xy 372.069745 -262.767124) (xy 372.064261 -262.807516) (xy 372.0592 -262.827262)
			(xy 372.055898 -262.838946) (xy 372.06047 -262.86206) (xy 372.116604 -262.935974) (xy 372.124197 -262.944959)
			(xy 372.145243 -262.955406) (xy 372.15699 -262.95604) (xy 373.252746 -262.95604) (xy 373.264501 -262.955444)
			(xy 373.285552 -262.944979) (xy 373.293132 -262.935974) (xy 373.349266 -262.86206) (xy 373.353838 -262.838946)
			(xy 373.350536 -262.827262) (xy 373.345436 -262.807524) (xy 373.339953 -262.767127) (xy 373.339614 -262.746744)
			(xy 373.339614 -262.745982) (xy 373.340136 -262.720727) (xy 373.348449 -262.670905) (xy 373.36485 -262.623131)
			(xy 373.388891 -262.578708) (xy 373.419915 -262.538848) (xy 373.457077 -262.504638) (xy 373.499363 -262.477012)
			(xy 373.545619 -262.456722) (xy 373.594584 -262.444322) (xy 373.644922 -262.440151) (xy 373.69526 -262.444322)
			(xy 373.744225 -262.456722) (xy 373.790481 -262.477012) (xy 373.832767 -262.504638) (xy 373.869929 -262.538848)
			(xy 373.900953 -262.578708) (xy 373.924994 -262.623131) (xy 373.941395 -262.670905) (xy 373.949708 -262.720727)
			(xy 373.95023 -262.745982) (xy 373.95023 -262.746744) (xy 373.949853 -262.767124) (xy 373.944369 -262.807516)
			(xy 373.939308 -262.827262) (xy 373.936006 -262.838946) (xy 373.940578 -262.86206) (xy 373.996712 -262.935974)
			(xy 374.004299 -262.944974) (xy 374.025344 -262.955459) (xy 374.037098 -262.95604) (xy 375.1326 -262.95604)
			(xy 375.14436 -262.955454) (xy 375.165427 -262.945) (xy 375.172986 -262.935974) (xy 375.22912 -262.86206)
			(xy 375.233692 -262.838946) (xy 375.23039 -262.827262) (xy 375.22529 -262.807524) (xy 375.219809 -262.767127)
			(xy 375.219468 -262.746744) (xy 375.219468 -262.745982) (xy 375.21999 -262.720727) (xy 375.228303 -262.670905)
			(xy 375.244704 -262.623131) (xy 375.268745 -262.578708) (xy 375.299769 -262.538848) (xy 375.336931 -262.504638)
			(xy 375.379217 -262.477012) (xy 375.425473 -262.456722) (xy 375.474438 -262.444322) (xy 375.524776 -262.440151)
			(xy 375.575114 -262.444322) (xy 375.624079 -262.456722) (xy 375.670335 -262.477012) (xy 375.712621 -262.504638)
			(xy 375.749783 -262.538848) (xy 375.780807 -262.578708) (xy 375.804848 -262.623131) (xy 375.821249 -262.670905)
			(xy 375.829562 -262.720727) (xy 375.830084 -262.745982) (xy 375.830084 -262.746744) (xy 375.829708 -262.767125)
			(xy 375.824225 -262.807517) (xy 375.819162 -262.827262) (xy 375.81586 -262.838946) (xy 375.820432 -262.86206)
			(xy 375.876566 -262.935974) (xy 375.884156 -262.944965) (xy 375.905202 -262.955428) (xy 375.916952 -262.95604)
			(xy 376.06859 -262.95604) (xy 376.08034 -262.955435) (xy 376.101376 -262.944959) (xy 376.108976 -262.935974)
			(xy 376.16511 -262.862314) (xy 376.167396 -262.851138) (xy 376.158899 -262.825682) (xy 376.149705 -262.772812)
			(xy 376.149108 -262.745982) (xy 376.149595 -262.721172) (xy 376.157357 -262.672164) (xy 376.17269 -262.624974)
			(xy 376.195217 -262.580763) (xy 376.224382 -262.54062) (xy 376.259468 -262.505534) (xy 376.299611 -262.476369)
			(xy 376.343822 -262.453842) (xy 376.391012 -262.438509) (xy 376.44002 -262.430747) (xy 376.48964 -262.430747)
			(xy 376.538648 -262.438509) (xy 376.585838 -262.453842) (xy 376.630049 -262.476369) (xy 376.670192 -262.505534)
			(xy 376.705278 -262.54062) (xy 376.734443 -262.580763) (xy 376.75697 -262.624974) (xy 376.772303 -262.672164)
			(xy 376.780065 -262.721172) (xy 376.780552 -262.745982) (xy 376.779918 -262.772809) (xy 376.770724 -262.825672)
			(xy 376.762264 -262.851138) (xy 376.76455 -262.862314) (xy 376.820684 -262.935974) (xy 376.828276 -262.944962)
			(xy 376.849322 -262.955418) (xy 376.86107 -262.95604) (xy 377.008644 -262.95604) (xy 377.020399 -262.955445)
			(xy 377.041451 -262.94498) (xy 377.04903 -262.935974) (xy 377.105164 -262.862314) (xy 377.10745 -262.851138)
			(xy 377.099051 -262.825663) (xy 377.089979 -262.7728) (xy 377.089416 -262.745982) (xy 377.089902 -262.721192)
			(xy 377.097658 -262.672224) (xy 377.112979 -262.625071) (xy 377.135488 -262.580896) (xy 377.16463 -262.540785)
			(xy 377.199687 -262.505728) (xy 377.239798 -262.476586) (xy 377.283973 -262.454077) (xy 377.331126 -262.438756)
			(xy 377.380094 -262.431) (xy 377.429674 -262.431) (xy 377.478642 -262.438756) (xy 377.525795 -262.454077)
			(xy 377.56997 -262.476586) (xy 377.610081 -262.505728) (xy 377.645138 -262.540785) (xy 377.67428 -262.580896)
			(xy 377.696789 -262.625071) (xy 377.71211 -262.672224) (xy 377.719866 -262.721192) (xy 377.720352 -262.745982)
			(xy 377.719816 -262.772802) (xy 377.710748 -262.825671) (xy 377.702318 -262.851138) (xy 377.704604 -262.862314)
			(xy 377.760738 -262.935974) (xy 377.768326 -262.94497) (xy 377.789372 -262.955445) (xy 377.801124 -262.95604)
			(xy 377.952762 -262.95604) (xy 377.964515 -262.955441) (xy 377.985561 -262.944972) (xy 377.993148 -262.935974)
			(xy 378.049282 -262.86206) (xy 378.053854 -262.838946) (xy 378.050552 -262.827262) (xy 378.045453 -262.807524)
			(xy 378.039972 -262.767127) (xy 378.03963 -262.746744) (xy 378.03963 -262.745982) (xy 378.040152 -262.720727)
			(xy 378.048465 -262.670905) (xy 378.064866 -262.623131) (xy 378.088907 -262.578708) (xy 378.119931 -262.538848)
			(xy 378.157093 -262.504638) (xy 378.199379 -262.477012) (xy 378.245635 -262.456722) (xy 378.2946 -262.444322)
			(xy 378.344938 -262.440151) (xy 378.395276 -262.444322) (xy 378.444241 -262.456722) (xy 378.490497 -262.477012)
			(xy 378.532783 -262.504638) (xy 378.569945 -262.538848) (xy 378.600969 -262.578708) (xy 378.62501 -262.623131)
			(xy 378.641411 -262.670905) (xy 378.649724 -262.720727) (xy 378.650246 -262.745982) (xy 378.650246 -262.746744)
			(xy 378.64987 -262.767124) (xy 378.644386 -262.807516) (xy 378.639324 -262.827262) (xy 378.636022 -262.838946)
			(xy 378.640594 -262.86206) (xy 378.696728 -262.935974) (xy 378.704316 -262.944971) (xy 378.725361 -262.95545)
			(xy 378.737114 -262.95604) (xy 378.888498 -262.95604) (xy 378.900258 -262.955454) (xy 378.921326 -262.945001)
			(xy 378.928884 -262.935974) (xy 378.985018 -262.862314) (xy 378.987304 -262.851138) (xy 378.97881 -262.825681)
			(xy 378.969618 -262.772812) (xy 378.969016 -262.745982) (xy 378.969503 -262.721172) (xy 378.977265 -262.672164)
			(xy 378.992598 -262.624974) (xy 379.015125 -262.580763) (xy 379.04429 -262.54062) (xy 379.079376 -262.505534)
			(xy 379.119519 -262.476369) (xy 379.16373 -262.453842) (xy 379.21092 -262.438509) (xy 379.259928 -262.430747)
			(xy 379.309548 -262.430747) (xy 379.358556 -262.438509) (xy 379.405746 -262.453842) (xy 379.449957 -262.476369)
			(xy 379.4901 -262.505534) (xy 379.525186 -262.54062) (xy 379.554351 -262.580763) (xy 379.576878 -262.624974)
			(xy 379.592211 -262.672164) (xy 379.599973 -262.721172) (xy 379.60046 -262.745982) (xy 379.599826 -262.772809)
			(xy 379.590632 -262.825672) (xy 379.582172 -262.851138) (xy 379.584458 -262.862314) (xy 379.640592 -262.935974)
			(xy 379.648184 -262.94496) (xy 379.66923 -262.955413) (xy 379.680978 -262.95604) (xy 379.832616 -262.95604)
			(xy 379.844374 -262.95545) (xy 379.865436 -262.944993) (xy 379.873002 -262.935974) (xy 379.929136 -262.86206)
			(xy 379.933708 -262.838946) (xy 379.930406 -262.827262) (xy 379.925306 -262.807524) (xy 379.919824 -262.767127)
			(xy 379.919484 -262.746744) (xy 379.919484 -262.745982) (xy 379.919956 -262.721991) (xy 379.927464 -262.674601)
			(xy 379.942293 -262.628969) (xy 379.964078 -262.586219) (xy 379.992281 -262.547402) (xy 380.026209 -262.513475)
			(xy 380.065027 -262.485272) (xy 380.107779 -262.463489) (xy 380.153411 -262.448662) (xy 380.200801 -262.441155)
			(xy 380.224792 -262.440674) (xy 380.249702 -262.441167) (xy 380.29886 -262.449256) (xy 380.346051 -262.465221)
			(xy 380.390024 -262.488638) (xy 380.42961 -262.518886) (xy 380.447042 -262.536686) (xy 380.44755 -262.537194)
			(xy 380.454866 -262.544416) (xy 380.473612 -262.552807) (xy 380.483872 -262.55345) (xy 380.55677 -262.554466)
			(xy 380.566395 -262.554187) (xy 380.584399 -262.547393) (xy 380.591822 -262.541258) (xy 380.592838 -262.540242)
			(xy 380.720854 -262.412226) (xy 380.725934 -262.406384) (xy 380.732832 -262.395995) (xy 380.736548 -262.371364)
			(xy 380.733046 -262.359394) (xy 380.70282 -262.273034) (xy 380.700252 -262.266388) (xy 380.691999 -262.254781)
			(xy 380.686564 -262.250174) (xy 380.680826 -262.245817) (xy 380.667535 -262.240265) (xy 380.660402 -262.239252)
			(xy 380.635872 -262.23599) (xy 380.588246 -262.222562) (xy 380.543408 -262.201632) (xy 380.502531 -262.173747)
			(xy 380.466684 -262.139637) (xy 380.436805 -262.100193) (xy 380.413677 -262.056449) (xy 380.397903 -262.009548)
			(xy 380.389898 -261.960717) (xy 380.389384 -261.935976) (xy 380.389856 -261.911986) (xy 380.397365 -261.864597)
			(xy 380.412195 -261.818965) (xy 380.43398 -261.776215) (xy 380.462183 -261.737399) (xy 380.496111 -261.703473)
			(xy 380.534929 -261.675271) (xy 380.57768 -261.653489) (xy 380.623312 -261.638662) (xy 380.670702 -261.631155)
			(xy 380.694692 -261.630668) (xy 380.719442 -261.63114) (xy 380.768295 -261.639112) (xy 380.81522 -261.654866)
			(xy 380.858987 -261.677987) (xy 380.898448 -261.70787) (xy 380.932569 -261.74373) (xy 380.960454 -261.784627)
			(xy 380.981371 -261.829489) (xy 380.994773 -261.87714) (xy 380.997968 -261.901686) (xy 380.998984 -261.909052)
			(xy 381.004318 -261.92226) (xy 381.00889 -261.927848) (xy 381.013526 -261.933252) (xy 381.025122 -261.941504)
			(xy 381.03175 -261.944104) (xy 381.11811 -261.97433) (xy 381.130078 -261.977853) (xy 381.154719 -261.974134)
			(xy 381.1651 -261.967218) (xy 381.168148 -261.964932) (xy 381.663194 -261.469886) (xy 381.663702 -261.469378)
			(xy 381.670295 -261.462001) (xy 381.677764 -261.443701) (xy 381.67818 -261.433818) (xy 381.67818 -256.943098)
			(xy 381.678005 -256.936368) (xy 381.674522 -256.923368) (xy 381.671322 -256.917444) (xy 381.667766 -256.911602)
			(xy 381.658368 -256.902204) (xy 381.652526 -256.898902) (xy 381.631417 -256.886184) (xy 381.593234 -256.855032)
			(xy 381.560544 -256.818157) (xy 381.534195 -256.776513) (xy 381.51487 -256.731181) (xy 381.50307 -256.683336)
			(xy 381.499101 -256.634217) (xy 381.503065 -256.585098) (xy 381.51486 -256.537251) (xy 381.534179 -256.491917)
			(xy 381.560523 -256.45027) (xy 381.593209 -256.413391) (xy 381.631389 -256.382235) (xy 381.652526 -256.369566)
			(xy 381.658368 -256.366264) (xy 381.667766 -256.356866) (xy 381.671322 -256.351024) (xy 381.674487 -256.345087)
			(xy 381.677955 -256.332094) (xy 381.67818 -256.32537) (xy 381.67818 -256.151634) (xy 381.677748 -256.142247)
			(xy 381.670999 -256.124728) (xy 381.658421 -256.11079) (xy 381.65024 -256.106168) (xy 381.569468 -256.065274)
			(xy 381.56086 -256.061425) (xy 381.54211 -256.059574) (xy 381.523946 -256.064575) (xy 381.516128 -256.069846)
			(xy 381.496312 -256.083896) (xy 381.45316 -256.106199) (xy 381.407021 -256.121386) (xy 381.359059 -256.129075)
			(xy 381.334772 -256.129536) (xy 381.309516 -256.129012) (xy 381.259693 -256.120694) (xy 381.211919 -256.104289)
			(xy 381.167496 -256.080245) (xy 381.127636 -256.049218) (xy 381.093427 -256.012053) (xy 381.065801 -255.969765)
			(xy 381.045511 -255.923507) (xy 381.033112 -255.87454) (xy 381.028941 -255.8242) (xy 381.033112 -255.77386)
			(xy 381.045511 -255.724893) (xy 381.065801 -255.678635) (xy 381.093427 -255.636347) (xy 381.127636 -255.599182)
			(xy 381.167496 -255.568155) (xy 381.211919 -255.544111) (xy 381.259693 -255.527706) (xy 381.309516 -255.519388)
			(xy 381.334772 -255.51892) (xy 381.359059 -255.519387) (xy 381.407023 -255.527072) (xy 381.453164 -255.542253)
			(xy 381.496321 -255.564547) (xy 381.516128 -255.57861) (xy 381.523905 -255.583975) (xy 381.542094 -255.589042)
			(xy 381.560877 -255.587119) (xy 381.569468 -255.583182) (xy 381.65024 -255.542288) (xy 381.658478 -255.537737)
			(xy 381.671099 -255.523795) (xy 381.677814 -255.506228) (xy 381.67818 -255.496822) (xy 381.67818 -255.323086)
			(xy 381.678016 -255.316352) (xy 381.674553 -255.303341) (xy 381.671322 -255.297432) (xy 381.667766 -255.29159)
			(xy 381.658368 -255.282192) (xy 381.652526 -255.27889) (xy 381.631418 -255.266172) (xy 381.593236 -255.235021)
			(xy 381.560549 -255.198146) (xy 381.534202 -255.156503) (xy 381.514878 -255.111172) (xy 381.50308 -255.063328)
			(xy 381.499111 -255.014211) (xy 381.503076 -254.965093) (xy 381.514871 -254.917248) (xy 381.534191 -254.871916)
			(xy 381.560535 -254.830272) (xy 381.593221 -254.793395) (xy 381.6314 -254.76224) (xy 381.652526 -254.749554)
			(xy 381.658368 -254.746252) (xy 381.667766 -254.736854) (xy 381.671322 -254.731012) (xy 381.674485 -254.725075)
			(xy 381.67795 -254.712082) (xy 381.67818 -254.705358) (xy 381.67818 -254.531622) (xy 381.677746 -254.522237)
			(xy 381.670994 -254.504721) (xy 381.658415 -254.490786) (xy 381.65024 -254.486156) (xy 381.569468 -254.445262)
			(xy 381.560861 -254.441407) (xy 381.542111 -254.439553) (xy 381.523947 -254.444563) (xy 381.516128 -254.449834)
			(xy 381.496312 -254.463884) (xy 381.453161 -254.486188) (xy 381.407022 -254.501376) (xy 381.359059 -254.509065)
			(xy 381.334772 -254.509524) (xy 381.309517 -254.509) (xy 381.259696 -254.500682) (xy 381.211924 -254.484278)
			(xy 381.167503 -254.460235) (xy 381.127645 -254.429209) (xy 381.093436 -254.392046) (xy 381.065811 -254.349759)
			(xy 381.045523 -254.303503) (xy 381.033124 -254.254538) (xy 381.028953 -254.2042) (xy 381.033124 -254.153862)
			(xy 381.045523 -254.104897) (xy 381.065811 -254.058641) (xy 381.093436 -254.016354) (xy 381.127645 -253.979191)
			(xy 381.167503 -253.948165) (xy 381.211924 -253.924122) (xy 381.259696 -253.907718) (xy 381.309517 -253.8994)
			(xy 381.334772 -253.898908) (xy 381.35906 -253.899375) (xy 381.407023 -253.907059) (xy 381.453165 -253.92224)
			(xy 381.496322 -253.944533) (xy 381.516128 -253.958598) (xy 381.523905 -253.963964) (xy 381.542094 -253.969032)
			(xy 381.560877 -253.967109) (xy 381.569468 -253.96317) (xy 381.65024 -253.922276) (xy 381.658488 -253.91773)
			(xy 381.671134 -253.903791) (xy 381.677878 -253.886221) (xy 381.67818 -253.87681) (xy 381.67818 -253.703074)
			(xy 381.678015 -253.696341) (xy 381.674549 -253.683331) (xy 381.671322 -253.67742) (xy 381.667766 -253.671578)
			(xy 381.658368 -253.66218) (xy 381.652526 -253.658878) (xy 381.631419 -253.646161) (xy 381.593239 -253.615009)
			(xy 381.560553 -253.578135) (xy 381.534208 -253.536493) (xy 381.514886 -253.491163) (xy 381.503089 -253.443321)
			(xy 381.499122 -253.394205) (xy 381.503087 -253.345089) (xy 381.514883 -253.297246) (xy 381.534203 -253.251916)
			(xy 381.560547 -253.210273) (xy 381.593232 -253.173398) (xy 381.631411 -253.142245) (xy 381.652526 -253.129542)
			(xy 381.658368 -253.12624) (xy 381.667766 -253.116842) (xy 381.671322 -253.111) (xy 381.674496 -253.105065)
			(xy 381.677983 -253.092072) (xy 381.67818 -253.085346) (xy 381.67818 -252.91161) (xy 381.677744 -252.902226)
			(xy 381.67099 -252.884713) (xy 381.65841 -252.870782) (xy 381.65024 -252.866144) (xy 381.569468 -252.82525)
			(xy 381.560861 -252.821396) (xy 381.542111 -252.819542) (xy 381.523947 -252.824551) (xy 381.516128 -252.829822)
			(xy 381.496312 -252.843873) (xy 381.453161 -252.866177) (xy 381.407022 -252.881366) (xy 381.359059 -252.889055)
			(xy 381.334772 -252.889512) (xy 381.309518 -252.888988) (xy 381.259699 -252.880671) (xy 381.211929 -252.864267)
			(xy 381.167509 -252.840225) (xy 381.127653 -252.8092) (xy 381.093446 -252.772038) (xy 381.065822 -252.729754)
			(xy 381.045534 -252.683499) (xy 381.033136 -252.634536) (xy 381.028965 -252.5842) (xy 381.033136 -252.533864)
			(xy 381.045534 -252.484901) (xy 381.065822 -252.438646) (xy 381.093446 -252.396362) (xy 381.127653 -252.3592)
			(xy 381.167509 -252.328175) (xy 381.211929 -252.304133) (xy 381.259699 -252.287729) (xy 381.309518 -252.279412)
			(xy 381.334772 -252.278896) (xy 381.35906 -252.279362) (xy 381.407023 -252.287047) (xy 381.453166 -252.302227)
			(xy 381.496323 -252.32452) (xy 381.516128 -252.338586) (xy 381.523905 -252.343954) (xy 381.542094 -252.349022)
			(xy 381.560878 -252.347099) (xy 381.569468 -252.343158) (xy 381.65024 -252.302264) (xy 381.658486 -252.297717)
			(xy 381.671129 -252.283778) (xy 381.67787 -252.266209) (xy 381.67818 -252.256798) (xy 381.67818 -252.083062)
			(xy 381.678013 -252.076329) (xy 381.674544 -252.063321) (xy 381.671322 -252.057408) (xy 381.667766 -252.051566)
			(xy 381.658368 -252.042168) (xy 381.652526 -252.038866) (xy 381.63142 -252.026149) (xy 381.593242 -251.994997)
			(xy 381.560558 -251.958124) (xy 381.534214 -251.916483) (xy 381.514894 -251.871154) (xy 381.503098 -251.823313)
			(xy 381.499132 -251.774199) (xy 381.503098 -251.725085) (xy 381.514895 -251.677244) (xy 381.534215 -251.631915)
			(xy 381.560559 -251.590275) (xy 381.593244 -251.553401) (xy 381.631421 -251.52225) (xy 381.652526 -251.50953)
			(xy 381.658368 -251.506228) (xy 381.667766 -251.49683) (xy 381.671322 -251.490988) (xy 381.674495 -251.485053)
			(xy 381.677979 -251.47206) (xy 381.67818 -251.465334) (xy 381.67818 -251.291598) (xy 381.677742 -251.282215)
			(xy 381.670985 -251.264706) (xy 381.658405 -251.250778) (xy 381.65024 -251.246132) (xy 381.569468 -251.205238)
			(xy 381.560861 -251.201385) (xy 381.542111 -251.199532) (xy 381.523947 -251.204539) (xy 381.516128 -251.20981)
			(xy 381.496312 -251.223861) (xy 381.453161 -251.246167) (xy 381.407022 -251.261356) (xy 381.35906 -251.269045)
			(xy 381.334772 -251.2695) (xy 381.309519 -251.268976) (xy 381.259702 -251.260659) (xy 381.211933 -251.244256)
			(xy 381.167516 -251.220215) (xy 381.127661 -251.189191) (xy 381.093455 -251.152031) (xy 381.065832 -251.109748)
			(xy 381.045545 -251.063495) (xy 381.033148 -251.014534) (xy 381.028977 -250.9642) (xy 381.033148 -250.913866)
			(xy 381.045545 -250.864905) (xy 381.065832 -250.818652) (xy 381.093455 -250.776369) (xy 381.127661 -250.739209)
			(xy 381.167516 -250.708185) (xy 381.211933 -250.684144) (xy 381.259702 -250.667741) (xy 381.309519 -250.659424)
			(xy 381.334772 -250.658884) (xy 381.35906 -250.65935) (xy 381.407023 -250.667035) (xy 381.453166 -250.682214)
			(xy 381.496324 -250.704506) (xy 381.516128 -250.718574) (xy 381.523905 -250.723942) (xy 381.542094 -250.729012)
			(xy 381.560878 -250.727088) (xy 381.569468 -250.723146) (xy 381.65024 -250.682252) (xy 381.658485 -250.677704)
			(xy 381.671124 -250.663765) (xy 381.677861 -250.646196) (xy 381.67818 -250.636786) (xy 381.67818 -250.46305)
			(xy 381.678012 -250.456318) (xy 381.67454 -250.443311) (xy 381.671322 -250.437396) (xy 381.667766 -250.431554)
			(xy 381.658368 -250.422156) (xy 381.652526 -250.418854) (xy 381.631421 -250.406137) (xy 381.593245 -250.374986)
			(xy 381.560563 -250.338113) (xy 381.534221 -250.296473) (xy 381.514902 -250.251145) (xy 381.503107 -250.203306)
			(xy 381.499142 -250.154193) (xy 381.50311 -250.105081) (xy 381.514907 -250.057241) (xy 381.534227 -250.011915)
			(xy 381.560571 -249.970276) (xy 381.593255 -249.933405) (xy 381.631432 -249.902255) (xy 381.652526 -249.889518)
			(xy 381.658368 -249.886216) (xy 381.667766 -249.876818) (xy 381.671322 -249.870976) (xy 381.674493 -249.865041)
			(xy 381.677974 -249.852048) (xy 381.67818 -249.845322) (xy 381.67818 -249.671586) (xy 381.67774 -249.662204)
			(xy 381.67098 -249.644698) (xy 381.6584 -249.630774) (xy 381.65024 -249.62612) (xy 381.569468 -249.585226)
			(xy 381.560861 -249.581373) (xy 381.542111 -249.57952) (xy 381.523947 -249.584527) (xy 381.516128 -249.589798)
			(xy 381.496312 -249.60385) (xy 381.453162 -249.626156) (xy 381.407022 -249.641346) (xy 381.35906 -249.649036)
			(xy 381.334772 -249.649488) (xy 381.30952 -249.648964) (xy 381.259705 -249.640647) (xy 381.211938 -249.624245)
			(xy 381.167522 -249.600205) (xy 381.127669 -249.569182) (xy 381.093465 -249.532024) (xy 381.065843 -249.489742)
			(xy 381.045557 -249.443491) (xy 381.033159 -249.394532) (xy 381.028989 -249.3442) (xy 381.033159 -249.293868)
			(xy 381.045557 -249.244909) (xy 381.065843 -249.198658) (xy 381.093465 -249.156376) (xy 381.127669 -249.119218)
			(xy 381.167522 -249.088195) (xy 381.211938 -249.064155) (xy 381.259705 -249.047753) (xy 381.30952 -249.039436)
			(xy 381.334772 -249.038872) (xy 381.35906 -249.039338) (xy 381.407024 -249.047023) (xy 381.453167 -249.062202)
			(xy 381.496325 -249.084493) (xy 381.516128 -249.098562) (xy 381.523904 -249.103931) (xy 381.542094 -249.109003)
			(xy 381.560879 -249.107078) (xy 381.569468 -249.103134) (xy 381.65024 -249.06224) (xy 381.658483 -249.057692)
			(xy 381.67112 -249.043752) (xy 381.677852 -249.026183) (xy 381.67818 -249.016774) (xy 381.67818 -248.843038)
			(xy 381.67801 -248.836306) (xy 381.674536 -248.823301) (xy 381.671322 -248.817384) (xy 381.667766 -248.811542)
			(xy 381.658368 -248.802144) (xy 381.652526 -248.798842) (xy 381.631422 -248.786125) (xy 381.593248 -248.754974)
			(xy 381.560567 -248.718101) (xy 381.534227 -248.676463) (xy 381.51491 -248.631136) (xy 381.503117 -248.583298)
			(xy 381.499153 -248.534187) (xy 381.503121 -248.485076) (xy 381.514918 -248.437239) (xy 381.534239 -248.391914)
			(xy 381.560583 -248.350278) (xy 381.593267 -248.313408) (xy 381.631443 -248.282261) (xy 381.652526 -248.269506)
			(xy 381.658368 -248.266204) (xy 381.667766 -248.256806) (xy 381.671322 -248.250964) (xy 381.674491 -248.245028)
			(xy 381.677969 -248.232035) (xy 381.67818 -248.22531) (xy 381.67818 -248.051574) (xy 381.677738 -248.042193)
			(xy 381.670976 -248.024691) (xy 381.658395 -248.01077) (xy 381.65024 -248.006108) (xy 381.569468 -247.965214)
			(xy 381.56086 -247.961362) (xy 381.542111 -247.95951) (xy 381.523946 -247.964515) (xy 381.516128 -247.969786)
			(xy 381.496311 -247.983834) (xy 381.453159 -248.006134) (xy 381.40702 -248.021319) (xy 381.359059 -248.029007)
			(xy 381.334772 -248.029476) (xy 381.309521 -248.028952) (xy 381.259708 -248.020636) (xy 381.211943 -248.004234)
			(xy 381.167529 -247.980195) (xy 381.127677 -247.949174) (xy 381.093474 -247.912016) (xy 381.065854 -247.869736)
			(xy 381.045568 -247.823487) (xy 381.033171 -247.77453) (xy 381.029001 -247.7242) (xy 381.033171 -247.67387)
			(xy 381.045568 -247.624913) (xy 381.065854 -247.578664) (xy 381.093474 -247.536384) (xy 381.127677 -247.499226)
			(xy 381.167529 -247.468205) (xy 381.211943 -247.444166) (xy 381.259708 -247.427764) (xy 381.309521 -247.419448)
			(xy 381.334772 -247.41886) (xy 381.35906 -247.419326) (xy 381.407024 -247.42701) (xy 381.453167 -247.442189)
			(xy 381.496326 -247.464479) (xy 381.516128 -247.47855) (xy 381.523904 -247.48392) (xy 381.542094 -247.488993)
			(xy 381.560879 -247.487068) (xy 381.569468 -247.483122) (xy 381.65024 -247.442228) (xy 381.658482 -247.437679)
			(xy 381.671115 -247.423739) (xy 381.677844 -247.40617) (xy 381.67818 -247.396762) (xy 381.67818 -247.223026)
			(xy 381.678009 -247.216295) (xy 381.674532 -247.203291) (xy 381.671322 -247.197372) (xy 381.667766 -247.19153)
			(xy 381.658368 -247.182132) (xy 381.652526 -247.17883) (xy 381.631423 -247.166113) (xy 381.593251 -247.134962)
			(xy 381.560572 -247.09809) (xy 381.534234 -247.056452) (xy 381.514918 -247.011127) (xy 381.503126 -246.96329)
			(xy 381.499163 -246.914181) (xy 381.503132 -246.865072) (xy 381.51493 -246.817236) (xy 381.534251 -246.771914)
			(xy 381.560595 -246.730279) (xy 381.593278 -246.693411) (xy 381.631454 -246.662266) (xy 381.652526 -246.649494)
			(xy 381.658368 -246.646192) (xy 381.667766 -246.636794) (xy 381.671322 -246.630952) (xy 381.67449 -246.625016)
			(xy 381.677965 -246.612023) (xy 381.67818 -246.605298) (xy 381.67818 -246.431562) (xy 381.677753 -246.422173)
			(xy 381.671009 -246.404646) (xy 381.658433 -246.3907) (xy 381.65024 -246.386096) (xy 381.569468 -246.345202)
			(xy 381.56086 -246.341351) (xy 381.542111 -246.339499) (xy 381.523946 -246.344503) (xy 381.516128 -246.349774)
			(xy 381.496311 -246.363823) (xy 381.453159 -246.386124) (xy 381.40702 -246.401309) (xy 381.359059 -246.408997)
			(xy 381.334772 -246.409464) (xy 381.309522 -246.40894) (xy 381.259711 -246.400624) (xy 381.211948 -246.384223)
			(xy 381.167536 -246.360185) (xy 381.127685 -246.329165) (xy 381.093484 -246.292009) (xy 381.065864 -246.249731)
			(xy 381.045579 -246.203483) (xy 381.033183 -246.154528) (xy 381.029013 -246.1042) (xy 381.033183 -246.053872)
			(xy 381.045579 -246.004917) (xy 381.065864 -245.958669) (xy 381.093484 -245.916391) (xy 381.127685 -245.879235)
			(xy 381.167536 -245.848215) (xy 381.211948 -245.824177) (xy 381.259711 -245.807776) (xy 381.309522 -245.79946)
			(xy 381.334772 -245.798848) (xy 381.359059 -245.799315) (xy 381.407022 -245.807001) (xy 381.453163 -245.822183)
			(xy 381.496318 -245.844479) (xy 381.516128 -245.858538) (xy 381.523906 -245.863901) (xy 381.542094 -245.868964)
			(xy 381.560875 -245.867043) (xy 381.569468 -245.86311) (xy 381.65024 -245.822216) (xy 381.658481 -245.817667)
			(xy 381.67111 -245.803726) (xy 381.677835 -245.786157) (xy 381.67818 -245.77675) (xy 381.67818 -245.603014)
			(xy 381.678007 -245.596283) (xy 381.674527 -245.583281) (xy 381.671322 -245.57736) (xy 381.667766 -245.571518)
			(xy 381.658368 -245.56212) (xy 381.652526 -245.558818) (xy 381.631424 -245.546101) (xy 381.593254 -245.514951)
			(xy 381.560577 -245.478079) (xy 381.53424 -245.436442) (xy 381.514926 -245.391118) (xy 381.503135 -245.343283)
			(xy 381.499174 -245.294175) (xy 381.503143 -245.245068) (xy 381.514942 -245.197234) (xy 381.534263 -245.151913)
			(xy 381.560607 -245.110281) (xy 381.59329 -245.073415) (xy 381.631465 -245.042271) (xy 381.652526 -245.029482)
			(xy 381.658368 -245.02618) (xy 381.667766 -245.016782) (xy 381.671322 -245.01094) (xy 381.674488 -245.005004)
			(xy 381.67796 -244.992011) (xy 381.67818 -244.985286) (xy 381.67818 -244.81155) (xy 381.677751 -244.802162)
			(xy 381.671005 -244.784638) (xy 381.658428 -244.770696) (xy 381.65024 -244.766084) (xy 381.569468 -244.72519)
			(xy 381.56086 -244.72134) (xy 381.542111 -244.719488) (xy 381.523946 -244.724491) (xy 381.516128 -244.729762)
			(xy 381.496311 -244.743811) (xy 381.45316 -244.766113) (xy 381.407021 -244.781299) (xy 381.359059 -244.788987)
			(xy 381.334772 -244.789452) (xy 381.309515 -244.788929) (xy 381.259689 -244.78061) (xy 381.211912 -244.764204)
			(xy 381.167487 -244.740159) (xy 381.127625 -244.70913) (xy 381.093414 -244.671963) (xy 381.065786 -244.629673)
			(xy 381.045496 -244.583412) (xy 381.033096 -244.534443) (xy 381.028924 -244.4841) (xy 381.033096 -244.433757)
			(xy 381.045496 -244.384788) (xy 381.065786 -244.338527) (xy 381.093414 -244.296237) (xy 381.127625 -244.25907)
			(xy 381.167487 -244.228041) (xy 381.211912 -244.203996) (xy 381.259689 -244.18759) (xy 381.309515 -244.179271)
			(xy 381.334772 -244.178836) (xy 381.359059 -244.179303) (xy 381.407022 -244.186989) (xy 381.453164 -244.20217)
			(xy 381.49632 -244.224465) (xy 381.516128 -244.238526) (xy 381.523906 -244.24389) (xy 381.542094 -244.248954)
			(xy 381.560876 -244.247032) (xy 381.569468 -244.243098) (xy 381.65024 -244.202204) (xy 381.658479 -244.197654)
			(xy 381.671105 -244.183712) (xy 381.677826 -244.166145) (xy 381.67818 -244.156738) (xy 381.67818 -243.983002)
			(xy 381.678005 -243.976272) (xy 381.674523 -243.963271) (xy 381.671322 -243.957348) (xy 381.667766 -243.951506)
			(xy 381.658368 -243.942108) (xy 381.652526 -243.938806) (xy 381.631417 -243.926088) (xy 381.593233 -243.894936)
			(xy 381.560542 -243.85806) (xy 381.534193 -243.816417) (xy 381.514868 -243.771084) (xy 381.503067 -243.723239)
			(xy 381.499097 -243.674119) (xy 381.503061 -243.624999) (xy 381.514856 -243.577152) (xy 381.534175 -243.531817)
			(xy 381.560519 -243.49017) (xy 381.593205 -243.45329) (xy 381.631385 -243.422133) (xy 381.652526 -243.40947)
			(xy 381.658368 -243.406168) (xy 381.667766 -243.39677) (xy 381.671322 -243.390928) (xy 381.674487 -243.384991)
			(xy 381.677956 -243.371998) (xy 381.67818 -243.365274) (xy 381.67818 -243.191538) (xy 381.677749 -243.182151)
			(xy 381.671 -243.164631) (xy 381.658422 -243.150692) (xy 381.65024 -243.146072) (xy 381.569468 -243.105178)
			(xy 381.56086 -243.101328) (xy 381.54211 -243.099477) (xy 381.523946 -243.104479) (xy 381.516128 -243.10975)
			(xy 381.496312 -243.1238) (xy 381.45316 -243.146102) (xy 381.407021 -243.161289) (xy 381.359059 -243.168978)
			(xy 381.334772 -243.16944) (xy 381.309516 -243.168916) (xy 381.259692 -243.160598) (xy 381.211917 -243.144193)
			(xy 381.167494 -243.120149) (xy 381.127634 -243.089121) (xy 381.093424 -243.051956) (xy 381.065797 -243.009667)
			(xy 381.045508 -242.963408) (xy 381.033108 -242.91444) (xy 381.028937 -242.8641) (xy 381.033108 -242.81376)
			(xy 381.045508 -242.764792) (xy 381.065797 -242.718533) (xy 381.093424 -242.676244) (xy 381.127634 -242.639079)
			(xy 381.167494 -242.608051) (xy 381.211917 -242.584007) (xy 381.259692 -242.567602) (xy 381.309516 -242.559284)
			(xy 381.334772 -242.558824) (xy 381.359059 -242.559291) (xy 381.407022 -242.566976) (xy 381.453164 -242.582158)
			(xy 381.496321 -242.604452) (xy 381.516128 -242.618514) (xy 381.523906 -242.623879) (xy 381.542094 -242.628945)
			(xy 381.560876 -242.627022) (xy 381.569468 -242.623086) (xy 381.65024 -242.582192) (xy 381.658478 -242.577641)
			(xy 381.671101 -242.563699) (xy 381.677817 -242.546132) (xy 381.67818 -242.536726) (xy 381.67818 -242.36299)
			(xy 381.678004 -242.35626) (xy 381.674519 -242.343262) (xy 381.671322 -242.337336) (xy 381.667766 -242.331494)
			(xy 381.658368 -242.322096) (xy 381.652526 -242.318794) (xy 381.631418 -242.306076) (xy 381.593235 -242.274925)
			(xy 381.560547 -242.238049) (xy 381.534199 -242.196407) (xy 381.514876 -242.151075) (xy 381.503076 -242.103231)
			(xy 381.499108 -242.054113) (xy 381.503072 -242.004995) (xy 381.514867 -241.957149) (xy 381.534187 -241.911817)
			(xy 381.560531 -241.870171) (xy 381.593217 -241.833293) (xy 381.631396 -241.802138) (xy 381.652526 -241.789458)
			(xy 381.658368 -241.786156) (xy 381.667766 -241.776758) (xy 381.671322 -241.770916) (xy 381.674486 -241.764979)
			(xy 381.677952 -241.751986) (xy 381.67818 -241.745262) (xy 381.67818 -241.571526) (xy 381.677747 -241.56214)
			(xy 381.670996 -241.544623) (xy 381.658417 -241.530688) (xy 381.65024 -241.52606) (xy 381.569468 -241.485166)
			(xy 381.560861 -241.481311) (xy 381.542111 -241.479457) (xy 381.523947 -241.484467) (xy 381.516128 -241.489738)
			(xy 381.496312 -241.503788) (xy 381.45316 -241.526092) (xy 381.407021 -241.541279) (xy 381.359059 -241.548968)
			(xy 381.334772 -241.549428) (xy 381.309517 -241.548904) (xy 381.259695 -241.540586) (xy 381.211922 -241.524182)
			(xy 381.167501 -241.500139) (xy 381.127642 -241.469112) (xy 381.093433 -241.431948) (xy 381.065808 -241.389661)
			(xy 381.045519 -241.343404) (xy 381.03312 -241.294439) (xy 381.028949 -241.2441) (xy 381.03312 -241.193761)
			(xy 381.045519 -241.144796) (xy 381.065808 -241.098539) (xy 381.093433 -241.056252) (xy 381.127642 -241.019088)
			(xy 381.167501 -240.988061) (xy 381.211922 -240.964018) (xy 381.259695 -240.947614) (xy 381.309517 -240.939296)
			(xy 381.334772 -240.938812) (xy 381.35906 -240.939279) (xy 381.407023 -240.946964) (xy 381.453165 -240.962144)
			(xy 381.496322 -240.984438) (xy 381.516128 -240.998502) (xy 381.523905 -241.003868) (xy 381.542094 -241.008935)
			(xy 381.560877 -241.007012) (xy 381.569468 -241.003074) (xy 381.65024 -240.96218) (xy 381.658488 -240.957634)
			(xy 381.671135 -240.943696) (xy 381.677881 -240.926126) (xy 381.67818 -240.916714) (xy 381.67818 -240.742978)
			(xy 381.678015 -240.736245) (xy 381.67455 -240.723235) (xy 381.671322 -240.717324) (xy 381.667766 -240.711482)
			(xy 381.658368 -240.702084) (xy 381.652526 -240.698782) (xy 381.631419 -240.686065) (xy 381.593238 -240.654913)
			(xy 381.560552 -240.618038) (xy 381.534206 -240.576396) (xy 381.514884 -240.531066) (xy 381.503086 -240.483223)
			(xy 381.499118 -240.434107) (xy 381.503084 -240.384991) (xy 381.514879 -240.337147) (xy 381.534199 -240.291816)
			(xy 381.560543 -240.250173) (xy 381.593228 -240.213297) (xy 381.631407 -240.182143) (xy 381.652526 -240.169446)
			(xy 381.658368 -240.166144) (xy 381.667766 -240.156746) (xy 381.671322 -240.150904) (xy 381.674496 -240.14497)
			(xy 381.677985 -240.131976) (xy 381.67818 -240.12525) (xy 381.67818 -239.951514) (xy 381.677745 -239.942129)
			(xy 381.670991 -239.924616) (xy 381.658412 -239.910684) (xy 381.65024 -239.906048) (xy 381.569468 -239.865154)
			(xy 381.560861 -239.8613) (xy 381.542111 -239.859446) (xy 381.523947 -239.864455) (xy 381.516128 -239.869726)
			(xy 381.496312 -239.883777) (xy 381.453161 -239.906081) (xy 381.407022 -239.921269) (xy 381.359059 -239.928958)
			(xy 381.334772 -239.929416) (xy 381.309518 -239.928892) (xy 381.259698 -239.920575) (xy 381.211927 -239.904171)
			(xy 381.167507 -239.880128) (xy 381.12765 -239.849103) (xy 381.093443 -239.811941) (xy 381.065818 -239.769655)
			(xy 381.04553 -239.7234) (xy 381.033132 -239.674437) (xy 381.028961 -239.6241) (xy 381.033132 -239.573763)
			(xy 381.04553 -239.5248) (xy 381.065818 -239.478545) (xy 381.093443 -239.436259) (xy 381.12765 -239.399097)
			(xy 381.167507 -239.368072) (xy 381.211927 -239.344029) (xy 381.259698 -239.327625) (xy 381.309518 -239.319308)
			(xy 381.334772 -239.3188) (xy 381.35906 -239.319266) (xy 381.407023 -239.326951) (xy 381.453165 -239.342132)
			(xy 381.496323 -239.364424) (xy 381.516128 -239.37849) (xy 381.523905 -239.383857) (xy 381.542094 -239.388925)
			(xy 381.560878 -239.387002) (xy 381.569468 -239.383062) (xy 381.65024 -239.342168) (xy 381.658487 -239.337621)
			(xy 381.671131 -239.323683) (xy 381.677873 -239.306113) (xy 381.67818 -239.296702) (xy 381.67818 -239.122966)
			(xy 381.678014 -239.116233) (xy 381.674546 -239.103225) (xy 381.671322 -239.097312) (xy 381.667766 -239.09147)
			(xy 381.658368 -239.082072) (xy 381.652526 -239.07877) (xy 381.63142 -239.066053) (xy 381.593241 -239.034901)
			(xy 381.560556 -238.998027) (xy 381.534212 -238.956386) (xy 381.514892 -238.911057) (xy 381.503095 -238.863216)
			(xy 381.499129 -238.814101) (xy 381.503095 -238.764986) (xy 381.514891 -238.717144) (xy 381.534211 -238.671816)
			(xy 381.560555 -238.630174) (xy 381.59324 -238.5933) (xy 381.631418 -238.562149) (xy 381.652526 -238.549434)
			(xy 381.658368 -238.546132) (xy 381.667766 -238.536734) (xy 381.671322 -238.530892) (xy 381.674495 -238.524957)
			(xy 381.67798 -238.511964) (xy 381.67818 -238.505238) (xy 381.67818 -238.331502) (xy 381.677743 -238.322119)
			(xy 381.670987 -238.304608) (xy 381.658407 -238.29068) (xy 381.65024 -238.286036) (xy 381.569468 -238.245142)
			(xy 381.560861 -238.241289) (xy 381.542111 -238.239435) (xy 381.523947 -238.244443) (xy 381.516128 -238.249714)
			(xy 381.496312 -238.263765) (xy 381.453161 -238.28607) (xy 381.407022 -238.301259) (xy 381.35906 -238.308949)
			(xy 381.334772 -238.309404) (xy 381.309519 -238.30888) (xy 381.259701 -238.300563) (xy 381.211932 -238.28416)
			(xy 381.167514 -238.260118) (xy 381.127658 -238.229094) (xy 381.093452 -238.191934) (xy 381.065829 -238.14965)
			(xy 381.045542 -238.103396) (xy 381.033144 -238.054435) (xy 381.028973 -238.0041) (xy 381.033144 -237.953765)
			(xy 381.045542 -237.904804) (xy 381.065829 -237.85855) (xy 381.093452 -237.816266) (xy 381.127658 -237.779106)
			(xy 381.167514 -237.748082) (xy 381.211932 -237.72404) (xy 381.259701 -237.707637) (xy 381.309519 -237.69932)
			(xy 381.334772 -237.698788) (xy 381.35906 -237.699254) (xy 381.407023 -237.706939) (xy 381.453166 -237.722119)
			(xy 381.496324 -237.744411) (xy 381.516128 -237.758478) (xy 381.523904 -237.763846) (xy 381.542094 -237.768916)
			(xy 381.560878 -237.766992) (xy 381.569468 -237.76305) (xy 381.65024 -237.722156) (xy 381.658485 -237.717608)
			(xy 381.671126 -237.703669) (xy 381.677864 -237.6861) (xy 381.67818 -237.67669) (xy 381.67818 -237.502954)
			(xy 381.678012 -237.496222) (xy 381.674541 -237.483215) (xy 381.671322 -237.4773) (xy 381.667766 -237.471458)
			(xy 381.658368 -237.46206) (xy 381.652526 -237.458758) (xy 381.63142 -237.446041) (xy 381.593244 -237.41489)
			(xy 381.560561 -237.378016) (xy 381.534219 -237.336376) (xy 381.5149 -237.291048) (xy 381.503104 -237.243208)
			(xy 381.499139 -237.194095) (xy 381.503106 -237.144982) (xy 381.514903 -237.097142) (xy 381.534223 -237.051815)
			(xy 381.560567 -237.010176) (xy 381.593251 -236.973303) (xy 381.631429 -236.942154) (xy 381.652526 -236.929422)
			(xy 381.658368 -236.92612) (xy 381.667766 -236.916722) (xy 381.671322 -236.91088) (xy 381.674494 -236.904945)
			(xy 381.677976 -236.891952) (xy 381.67818 -236.885226) (xy 381.67818 -236.71149) (xy 381.677741 -236.702108)
			(xy 381.670982 -236.684601) (xy 381.658402 -236.670676) (xy 381.65024 -236.666024) (xy 381.569468 -236.62513)
			(xy 381.560861 -236.621277) (xy 381.542111 -236.619424) (xy 381.523947 -236.624431) (xy 381.516128 -236.629702)
			(xy 381.496312 -236.643754) (xy 381.453162 -236.66606) (xy 381.407022 -236.681249) (xy 381.35906 -236.688939)
			(xy 381.334772 -236.689392) (xy 381.30952 -236.688868) (xy 381.259704 -236.680551) (xy 381.211937 -236.664149)
			(xy 381.16752 -236.640108) (xy 381.127666 -236.609085) (xy 381.093462 -236.571926) (xy 381.06584 -236.529644)
			(xy 381.045553 -236.483392) (xy 381.033155 -236.434433) (xy 381.028985 -236.3841) (xy 381.033155 -236.333767)
			(xy 381.045553 -236.284808) (xy 381.06584 -236.238556) (xy 381.093462 -236.196274) (xy 381.127666 -236.159115)
			(xy 381.16752 -236.128092) (xy 381.211937 -236.104051) (xy 381.259704 -236.087649) (xy 381.30952 -236.079332)
			(xy 381.334772 -236.078776) (xy 381.35906 -236.079242) (xy 381.407024 -236.086927) (xy 381.453166 -236.102106)
			(xy 381.496325 -236.124397) (xy 381.516128 -236.138466) (xy 381.523904 -236.143835) (xy 381.542094 -236.148906)
			(xy 381.560878 -236.146981) (xy 381.569468 -236.143038) (xy 381.65024 -236.102144) (xy 381.658484 -236.097596)
			(xy 381.671121 -236.083656) (xy 381.677855 -236.066087) (xy 381.67818 -236.056678) (xy 381.67818 -235.882942)
			(xy 381.678011 -235.87621) (xy 381.674537 -235.863205) (xy 381.671322 -235.857288) (xy 381.667766 -235.851446)
			(xy 381.658368 -235.842048) (xy 381.652526 -235.838746) (xy 381.631421 -235.826029) (xy 381.593247 -235.794878)
			(xy 381.560566 -235.758005) (xy 381.534225 -235.716366) (xy 381.514907 -235.671039) (xy 381.503114 -235.623201)
			(xy 381.499149 -235.574089) (xy 381.503117 -235.524978) (xy 381.514914 -235.47714) (xy 381.534235 -235.431815)
			(xy 381.560579 -235.390177) (xy 381.593263 -235.353307) (xy 381.63144 -235.322159) (xy 381.652526 -235.30941)
			(xy 381.658368 -235.306108) (xy 381.667766 -235.29671) (xy 381.671322 -235.290868) (xy 381.674492 -235.284932)
			(xy 381.677971 -235.271939) (xy 381.67818 -235.265214) (xy 381.67818 -235.091478) (xy 381.677739 -235.082097)
			(xy 381.670977 -235.064593) (xy 381.658396 -235.050672) (xy 381.65024 -235.046012) (xy 381.569468 -235.005118)
			(xy 381.560861 -235.001266) (xy 381.542111 -234.999413) (xy 381.523946 -235.004419) (xy 381.516128 -235.00969)
			(xy 381.496311 -235.023738) (xy 381.453159 -235.046038) (xy 381.40702 -235.061223) (xy 381.359059 -235.06891)
			(xy 381.334772 -235.06938) (xy 381.309521 -235.068856) (xy 381.259707 -235.06054) (xy 381.211941 -235.044138)
			(xy 381.167527 -235.020098) (xy 381.127674 -234.989077) (xy 381.093471 -234.951919) (xy 381.06585 -234.909638)
			(xy 381.045564 -234.863388) (xy 381.033167 -234.814431) (xy 381.028997 -234.7641) (xy 381.033167 -234.713769)
			(xy 381.045564 -234.664812) (xy 381.06585 -234.618562) (xy 381.093471 -234.576281) (xy 381.127674 -234.539123)
			(xy 381.167527 -234.508102) (xy 381.211941 -234.484062) (xy 381.259707 -234.46766) (xy 381.309521 -234.459344)
			(xy 381.334772 -234.458764) (xy 381.35906 -234.45923) (xy 381.407024 -234.466914) (xy 381.453167 -234.482093)
			(xy 381.496326 -234.504384) (xy 381.516128 -234.518454) (xy 381.523904 -234.523824) (xy 381.542094 -234.528896)
			(xy 381.560879 -234.526971) (xy 381.569468 -234.523026) (xy 381.65024 -234.482132) (xy 381.658483 -234.477583)
			(xy 381.671116 -234.463643) (xy 381.677846 -234.446074) (xy 381.67818 -234.436666) (xy 381.67818 -234.26293)
			(xy 381.678009 -234.256199) (xy 381.674533 -234.243195) (xy 381.671322 -234.237276) (xy 381.667766 -234.231434)
			(xy 381.658368 -234.222036) (xy 381.652526 -234.218734) (xy 381.631422 -234.206017) (xy 381.59325 -234.174866)
			(xy 381.56057 -234.137994) (xy 381.534231 -234.096356) (xy 381.514915 -234.05103) (xy 381.503123 -234.003193)
			(xy 381.49916 -233.954083) (xy 381.503128 -233.904973) (xy 381.514926 -233.857137) (xy 381.534247 -233.811814)
			(xy 381.560591 -233.770179) (xy 381.593274 -233.73331) (xy 381.63145 -233.702164) (xy 381.652526 -233.689398)
			(xy 381.658368 -233.686096) (xy 381.667766 -233.676698) (xy 381.671322 -233.670856) (xy 381.67449 -233.66492)
			(xy 381.677966 -233.651927) (xy 381.67818 -233.645202) (xy 381.67818 -233.471466) (xy 381.677737 -233.462086)
			(xy 381.670973 -233.444586) (xy 381.658391 -233.430668) (xy 381.65024 -233.426) (xy 381.569468 -233.385106)
			(xy 381.56086 -233.381254) (xy 381.542111 -233.379402) (xy 381.523946 -233.384407) (xy 381.516128 -233.389678)
			(xy 381.496311 -233.403727) (xy 381.453159 -233.426027) (xy 381.40702 -233.441213) (xy 381.359059 -233.4489)
			(xy 381.334772 -233.449368) (xy 381.309521 -233.448844) (xy 381.25971 -233.440528) (xy 381.211946 -233.424127)
			(xy 381.167533 -233.400088) (xy 381.127683 -233.369068) (xy 381.093481 -233.331911) (xy 381.065861 -233.289633)
			(xy 381.045576 -233.243385) (xy 381.033179 -233.194429) (xy 381.029009 -233.1441) (xy 381.033179 -233.093771)
			(xy 381.045576 -233.044815) (xy 381.065861 -232.998567) (xy 381.093481 -232.956289) (xy 381.127683 -232.919132)
			(xy 381.167533 -232.888112) (xy 381.211946 -232.864073) (xy 381.25971 -232.847672) (xy 381.309522 -232.839356)
			(xy 381.334772 -232.838752) (xy 381.359059 -232.839219) (xy 381.407022 -232.846905) (xy 381.453163 -232.862087)
			(xy 381.496318 -232.884383) (xy 381.516128 -232.898442) (xy 381.523906 -232.903805) (xy 381.542094 -232.908868)
			(xy 381.560875 -232.906947) (xy 381.569468 -232.903014) (xy 381.65024 -232.86212) (xy 381.658481 -232.857571)
			(xy 381.671112 -232.84363) (xy 381.677838 -232.826062) (xy 381.67818 -232.816654) (xy 381.67818 -232.642918)
			(xy 381.678007 -232.636187) (xy 381.674529 -232.623185) (xy 381.671322 -232.617264) (xy 381.667766 -232.611422)
			(xy 381.658368 -232.602024) (xy 381.652526 -232.598722) (xy 381.631423 -232.586005) (xy 381.593253 -232.554855)
			(xy 381.560575 -232.517983) (xy 381.534238 -232.476346) (xy 381.514923 -232.431021) (xy 381.503132 -232.383185)
			(xy 381.49917 -232.334077) (xy 381.50314 -232.284969) (xy 381.514938 -232.237135) (xy 381.534259 -232.191814)
			(xy 381.560603 -232.15018) (xy 381.593286 -232.113313) (xy 381.631461 -232.082169) (xy 381.652526 -232.069386)
			(xy 381.658368 -232.066084) (xy 381.667766 -232.056686) (xy 381.671322 -232.050844) (xy 381.674489 -232.044908)
			(xy 381.677962 -232.031915) (xy 381.67818 -232.02519) (xy 381.67818 -231.851454) (xy 381.677751 -231.842065)
			(xy 381.671006 -231.824541) (xy 381.658429 -231.810597) (xy 381.65024 -231.805988) (xy 381.569468 -231.765094)
			(xy 381.56086 -231.761243) (xy 381.542111 -231.759392) (xy 381.523946 -231.764395) (xy 381.516128 -231.769666)
			(xy 381.496311 -231.783715) (xy 381.45316 -231.806016) (xy 381.407021 -231.821203) (xy 381.359059 -231.828891)
			(xy 381.334772 -231.829356) (xy 381.309514 -231.828833) (xy 381.259688 -231.820514) (xy 381.211911 -231.804108)
			(xy 381.167485 -231.780062) (xy 381.127623 -231.749033) (xy 381.093411 -231.711866) (xy 381.065783 -231.669575)
			(xy 381.045492 -231.623313) (xy 381.033092 -231.574343) (xy 381.02892 -231.524) (xy 381.033092 -231.473657)
			(xy 381.045492 -231.424687) (xy 381.065783 -231.378425) (xy 381.093411 -231.336134) (xy 381.127623 -231.298967)
			(xy 381.167485 -231.267938) (xy 381.211911 -231.243892) (xy 381.259688 -231.227486) (xy 381.309514 -231.219167)
			(xy 381.334772 -231.21874) (xy 381.359059 -231.219207) (xy 381.407022 -231.226893) (xy 381.453163 -231.242075)
			(xy 381.496319 -231.26437) (xy 381.516128 -231.27843) (xy 381.523906 -231.283793) (xy 381.542094 -231.288858)
			(xy 381.560876 -231.286936) (xy 381.569468 -231.283002) (xy 381.65024 -231.242108) (xy 381.65848 -231.237558)
			(xy 381.671107 -231.223617) (xy 381.677829 -231.206049) (xy 381.67818 -231.196642) (xy 381.67818 -231.02316)
			(xy 381.678013 -231.016427) (xy 381.674544 -231.00342) (xy 381.671322 -230.997506) (xy 381.667766 -230.991664)
			(xy 381.658368 -230.982266) (xy 381.652526 -230.978964) (xy 381.629698 -230.965121) (xy 381.588796 -230.930818)
			(xy 381.554472 -230.889935) (xy 381.527768 -230.843712) (xy 381.509496 -230.793555) (xy 381.50021 -230.740987)
			(xy 381.499618 -230.714296) (xy 381.499618 -230.714042) (xy 381.500166 -230.687331) (xy 381.509455 -230.634724)
			(xy 381.527758 -230.584536) (xy 381.554515 -230.538299) (xy 381.588911 -230.497425) (xy 381.629895 -230.463159)
			(xy 381.65278 -230.449374) (xy 381.664464 -230.442516) (xy 381.67818 -230.418894) (xy 381.67818 -230.231442)
			(xy 381.677749 -230.222055) (xy 381.671002 -230.204533) (xy 381.658424 -230.190593) (xy 381.65024 -230.185976)
			(xy 381.569468 -230.145082) (xy 381.56086 -230.141232) (xy 381.54211 -230.139381) (xy 381.523946 -230.144383)
			(xy 381.516128 -230.149654) (xy 381.496312 -230.163704) (xy 381.45316 -230.186006) (xy 381.407021 -230.201193)
			(xy 381.359059 -230.208881) (xy 381.334772 -230.209344) (xy 381.309515 -230.20882) (xy 381.259691 -230.200502)
			(xy 381.211916 -230.184097) (xy 381.167492 -230.160052) (xy 381.127631 -230.129024) (xy 381.093421 -230.091858)
			(xy 381.065794 -230.049569) (xy 381.045504 -230.003309) (xy 381.033104 -229.954341) (xy 381.028933 -229.904)
			(xy 381.033104 -229.853659) (xy 381.045504 -229.804691) (xy 381.065794 -229.758431) (xy 381.093421 -229.716142)
			(xy 381.127631 -229.678976) (xy 381.167492 -229.647948) (xy 381.211916 -229.623903) (xy 381.259691 -229.607498)
			(xy 381.309515 -229.59918) (xy 381.334772 -229.598728) (xy 381.359059 -229.599195) (xy 381.407022 -229.60688)
			(xy 381.453164 -229.622062) (xy 381.49632 -229.644356) (xy 381.516128 -229.658418) (xy 381.523906 -229.663783)
			(xy 381.542094 -229.668848) (xy 381.560876 -229.666926) (xy 381.569468 -229.66299) (xy 381.65024 -229.622096)
			(xy 381.658478 -229.617546) (xy 381.671102 -229.603604) (xy 381.67782 -229.586036) (xy 381.67818 -229.57663)
			(xy 381.67818 -229.403148) (xy 381.678011 -229.396416) (xy 381.674539 -229.38341) (xy 381.671322 -229.377494)
			(xy 381.667766 -229.371652) (xy 381.658368 -229.362254) (xy 381.652526 -229.358952) (xy 381.631421 -229.346235)
			(xy 381.593245 -229.315084) (xy 381.560563 -229.278211) (xy 381.534222 -229.236571) (xy 381.514903 -229.191244)
			(xy 381.503109 -229.143404) (xy 381.499144 -229.094292) (xy 381.503112 -229.04518) (xy 381.514909 -228.997341)
			(xy 381.534229 -228.952015) (xy 381.560573 -228.910377) (xy 381.593257 -228.873505) (xy 381.631434 -228.842356)
			(xy 381.652526 -228.829616) (xy 381.658368 -228.826314) (xy 381.667766 -228.816916) (xy 381.671322 -228.811074)
			(xy 381.674492 -228.805139) (xy 381.677973 -228.792146) (xy 381.67818 -228.78542) (xy 381.67818 -228.611684)
			(xy 381.67774 -228.602302) (xy 381.67098 -228.584797) (xy 381.658399 -228.570874) (xy 381.65024 -228.566218)
			(xy 381.569468 -228.525324) (xy 381.560861 -228.521471) (xy 381.542111 -228.519619) (xy 381.523947 -228.524625)
			(xy 381.516128 -228.529896) (xy 381.496313 -228.543948) (xy 381.453162 -228.566254) (xy 381.407023 -228.581444)
			(xy 381.35906 -228.589134) (xy 381.334772 -228.589586) (xy 381.30952 -228.589062) (xy 381.259705 -228.580746)
			(xy 381.211939 -228.564343) (xy 381.167523 -228.540303) (xy 381.12767 -228.509281) (xy 381.093466 -228.472122)
			(xy 381.065845 -228.429841) (xy 381.045559 -228.38359) (xy 381.033161 -228.334632) (xy 381.028991 -228.2843)
			(xy 381.033161 -228.233968) (xy 381.045559 -228.18501) (xy 381.065845 -228.138759) (xy 381.093466 -228.096478)
			(xy 381.12767 -228.059319) (xy 381.167524 -228.028297) (xy 381.211939 -228.004257) (xy 381.259705 -227.987854)
			(xy 381.30952 -227.979538) (xy 381.334772 -227.97897) (xy 381.35906 -227.979436) (xy 381.407024 -227.987121)
			(xy 381.453167 -228.0023) (xy 381.496325 -228.024591) (xy 381.516128 -228.03866) (xy 381.523904 -228.044029)
			(xy 381.542094 -228.049101) (xy 381.560879 -228.047176) (xy 381.569468 -228.043232) (xy 381.65024 -228.002338)
			(xy 381.658483 -227.99779) (xy 381.671119 -227.98385) (xy 381.677851 -227.966281) (xy 381.67818 -227.956872)
			(xy 381.67818 -227.783136) (xy 381.67801 -227.776404) (xy 381.674535 -227.7634) (xy 381.671322 -227.757482)
			(xy 381.667766 -227.75164) (xy 381.658368 -227.742242) (xy 381.652526 -227.73894) (xy 381.631422 -227.726223)
			(xy 381.593248 -227.695072) (xy 381.560568 -227.6582) (xy 381.534228 -227.616561) (xy 381.514911 -227.571235)
			(xy 381.503118 -227.523397) (xy 381.499155 -227.474286) (xy 381.503123 -227.425176) (xy 381.51492 -227.377338)
			(xy 381.534241 -227.332014) (xy 381.560585 -227.290378) (xy 381.593269 -227.253508) (xy 381.631445 -227.222361)
			(xy 381.652526 -227.209604) (xy 381.658368 -227.206302) (xy 381.667766 -227.196904) (xy 381.671322 -227.191062)
			(xy 381.674491 -227.185126) (xy 381.677969 -227.172133) (xy 381.67818 -227.165408) (xy 381.67818 -226.991672)
			(xy 381.677738 -226.982292) (xy 381.670975 -226.96479) (xy 381.658394 -226.95087) (xy 381.65024 -226.946206)
			(xy 381.569468 -226.905312) (xy 381.56086 -226.90146) (xy 381.542111 -226.899608) (xy 381.523946 -226.904613)
			(xy 381.516128 -226.909884) (xy 381.496311 -226.923932) (xy 381.453159 -226.946232) (xy 381.40702 -226.961418)
			(xy 381.359059 -226.969105) (xy 381.334772 -226.969574) (xy 381.309521 -226.96905) (xy 381.259708 -226.960734)
			(xy 381.211944 -226.944332) (xy 381.16753 -226.920293) (xy 381.127678 -226.889272) (xy 381.093476 -226.852115)
			(xy 381.065855 -226.809835) (xy 381.04557 -226.763587) (xy 381.033173 -226.71463) (xy 381.029003 -226.6643)
			(xy 381.033173 -226.61397) (xy 381.04557 -226.565013) (xy 381.065855 -226.518765) (xy 381.093476 -226.476485)
			(xy 381.127678 -226.439328) (xy 381.16753 -226.408307) (xy 381.211944 -226.384268) (xy 381.259708 -226.367866)
			(xy 381.309521 -226.35955) (xy 381.334772 -226.358958) (xy 381.35906 -226.359424) (xy 381.407024 -226.367108)
			(xy 381.453167 -226.382287) (xy 381.496326 -226.404577) (xy 381.516128 -226.418648) (xy 381.523906 -226.42401)
			(xy 381.542094 -226.429073) (xy 381.560875 -226.427152) (xy 381.569468 -226.42322) (xy 381.65024 -226.382326)
			(xy 381.658482 -226.377777) (xy 381.671114 -226.363836) (xy 381.677842 -226.346268) (xy 381.67818 -226.33686)
			(xy 381.67818 -226.163124) (xy 381.678008 -226.156393) (xy 381.674531 -226.14339) (xy 381.671322 -226.13747)
			(xy 381.667766 -226.131628) (xy 381.658368 -226.12223) (xy 381.652526 -226.118928) (xy 381.631423 -226.106211)
			(xy 381.593251 -226.07506) (xy 381.560573 -226.038189) (xy 381.534235 -225.996551) (xy 381.514919 -225.951226)
			(xy 381.503128 -225.903389) (xy 381.499165 -225.85428) (xy 381.503134 -225.805171) (xy 381.514932 -225.757336)
			(xy 381.534253 -225.712014) (xy 381.560597 -225.670379) (xy 381.59328 -225.633512) (xy 381.631456 -225.602367)
			(xy 381.652526 -225.589592) (xy 381.658368 -225.58629) (xy 381.667766 -225.576892) (xy 381.671322 -225.57105)
			(xy 381.67449 -225.565114) (xy 381.677964 -225.552121) (xy 381.67818 -225.545396) (xy 381.67818 -225.37166)
			(xy 381.677752 -225.362271) (xy 381.671009 -225.344745) (xy 381.658432 -225.330799) (xy 381.65024 -225.326194)
			(xy 381.569468 -225.2853) (xy 381.56086 -225.281449) (xy 381.542111 -225.279597) (xy 381.523946 -225.284601)
			(xy 381.516128 -225.289872) (xy 381.496311 -225.303921) (xy 381.453159 -225.326222) (xy 381.40702 -225.341408)
			(xy 381.359059 -225.349096) (xy 381.334772 -225.349562) (xy 381.309522 -225.349038) (xy 381.259711 -225.340722)
			(xy 381.211949 -225.324321) (xy 381.167537 -225.300283) (xy 381.127687 -225.269263) (xy 381.093485 -225.232108)
			(xy 381.065866 -225.18983) (xy 381.045581 -225.143583) (xy 381.033185 -225.094628) (xy 381.029015 -225.0443)
			(xy 381.033185 -224.993972) (xy 381.045581 -224.945017) (xy 381.065866 -224.89877) (xy 381.093485 -224.856492)
			(xy 381.127687 -224.819337) (xy 381.167537 -224.788317) (xy 381.211949 -224.764279) (xy 381.259711 -224.747878)
			(xy 381.309522 -224.739562) (xy 381.334772 -224.738946) (xy 381.359059 -224.739413) (xy 381.407022 -224.747099)
			(xy 381.453163 -224.762281) (xy 381.496319 -224.784577) (xy 381.516128 -224.798636) (xy 381.523906 -224.803999)
			(xy 381.542094 -224.809062) (xy 381.560876 -224.807141) (xy 381.569468 -224.803208) (xy 381.65024 -224.762314)
			(xy 381.658481 -224.757765) (xy 381.67111 -224.743823) (xy 381.677834 -224.726255) (xy 381.67818 -224.716848)
			(xy 381.67818 -223.751648) (xy 381.67775 -223.74226) (xy 381.671004 -223.724737) (xy 381.658427 -223.710795)
			(xy 381.65024 -223.706182) (xy 381.569468 -223.665288) (xy 381.56086 -223.661438) (xy 381.54211 -223.659586)
			(xy 381.523946 -223.664589) (xy 381.516128 -223.66986) (xy 381.496311 -223.683909) (xy 381.45316 -223.706211)
			(xy 381.407021 -223.721398) (xy 381.359059 -223.729086) (xy 381.334772 -223.72955) (xy 381.309515 -223.729026)
			(xy 381.25969 -223.720708) (xy 381.211913 -223.704302) (xy 381.167488 -223.680257) (xy 381.127627 -223.649228)
			(xy 381.093416 -223.612062) (xy 381.065789 -223.569772) (xy 381.045498 -223.523511) (xy 381.033098 -223.474542)
			(xy 381.028927 -223.4242) (xy 381.033098 -223.373858) (xy 381.045498 -223.324889) (xy 381.065789 -223.278628)
			(xy 381.093416 -223.236338) (xy 381.127627 -223.199172) (xy 381.167488 -223.168143) (xy 381.211913 -223.144098)
			(xy 381.25969 -223.127692) (xy 381.309515 -223.119374) (xy 381.334772 -223.118934) (xy 381.359059 -223.119401)
			(xy 381.407022 -223.127087) (xy 381.453164 -223.142268) (xy 381.49632 -223.164563) (xy 381.516128 -223.178624)
			(xy 381.523906 -223.183988) (xy 381.542094 -223.189053) (xy 381.560876 -223.187131) (xy 381.569468 -223.183196)
			(xy 381.65024 -223.142302) (xy 381.658479 -223.137752) (xy 381.671105 -223.12381) (xy 381.677824 -223.106242)
			(xy 381.67818 -223.096836) (xy 381.67818 -222.131636) (xy 381.677748 -222.122249) (xy 381.671 -222.10473)
			(xy 381.658422 -222.090791) (xy 381.65024 -222.08617) (xy 381.569468 -222.045276) (xy 381.56086 -222.041426)
			(xy 381.54211 -222.039576) (xy 381.523946 -222.044577) (xy 381.516128 -222.049848) (xy 381.496312 -222.063898)
			(xy 381.45316 -222.086201) (xy 381.407021 -222.101388) (xy 381.359059 -222.109076) (xy 381.334772 -222.109538)
			(xy 381.309516 -222.109014) (xy 381.259693 -222.100696) (xy 381.211918 -222.084291) (xy 381.167495 -222.060247)
			(xy 381.127635 -222.029219) (xy 381.093425 -221.992054) (xy 381.065799 -221.949766) (xy 381.045509 -221.903507)
			(xy 381.03311 -221.85454) (xy 381.028939 -221.8042) (xy 381.03311 -221.75386) (xy 381.045509 -221.704893)
			(xy 381.065799 -221.658634) (xy 381.093425 -221.616346) (xy 381.127635 -221.579181) (xy 381.167495 -221.548153)
			(xy 381.211918 -221.524109) (xy 381.259693 -221.507704) (xy 381.309516 -221.499386) (xy 381.334772 -221.498922)
			(xy 381.359059 -221.499389) (xy 381.407023 -221.507074) (xy 381.453164 -221.522255) (xy 381.496321 -221.54455)
			(xy 381.516128 -221.558612) (xy 381.523906 -221.563977) (xy 381.542094 -221.569043) (xy 381.560877 -221.567121)
			(xy 381.569468 -221.563184) (xy 381.65024 -221.52229) (xy 381.658478 -221.517739) (xy 381.6711 -221.503797)
			(xy 381.677816 -221.48623) (xy 381.67818 -221.476824) (xy 381.67818 -221.371922) (xy 381.678617 -221.361858)
			(xy 381.686349 -221.343272) (xy 381.693166 -221.335854) (xy 388.460488 -214.568532) (xy 388.474204 -214.554816)
			(xy 388.476744 -214.517224) (xy 388.46506 -214.50173) (xy 388.42264 -214.445069) (xy 388.343493 -214.327704)
			(xy 388.271072 -214.206074) (xy 388.205607 -214.080563) (xy 388.147305 -213.951569) (xy 388.09635 -213.819499)
			(xy 388.052904 -213.684773) (xy 388.017104 -213.547816) (xy 387.989065 -213.409063) (xy 387.968873 -213.268952)
			(xy 387.956594 -213.127928) (xy 387.952267 -212.986436) (xy 387.955904 -212.844924) (xy 387.967495 -212.703842)
			(xy 387.987003 -212.563634) (xy 388.014365 -212.424746) (xy 388.049496 -212.287616) (xy 388.092285 -212.152679)
			(xy 388.142595 -212.020363) (xy 388.200267 -211.891086) (xy 388.265119 -211.765257) (xy 388.336946 -211.643275)
			(xy 388.41552 -211.525526) (xy 388.500592 -211.412382) (xy 388.591893 -211.304203) (xy 388.689134 -211.20133)
			(xy 388.792008 -211.104089) (xy 388.900187 -211.012788) (xy 389.013331 -210.927716) (xy 389.13108 -210.849142)
			(xy 389.253063 -210.777316) (xy 389.378892 -210.712464) (xy 389.508169 -210.654792) (xy 389.640486 -210.604483)
			(xy 389.775422 -210.561695) (xy 389.912552 -210.526564) (xy 390.05144 -210.499202) (xy 390.191648 -210.479694)
			(xy 390.332731 -210.468104) (xy 390.474242 -210.464467) (xy 390.615734 -210.468795) (xy 390.756759 -210.481074)
			(xy 390.89687 -210.501266) (xy 391.035623 -210.529306) (xy 391.172579 -210.565106) (xy 391.307305 -210.608552)
			(xy 391.439375 -210.659507) (xy 391.568369 -210.71781) (xy 391.69388 -210.783275) (xy 391.81551 -210.855696)
			(xy 391.932874 -210.934844) (xy 391.989564 -210.977226) (xy 392.005058 -210.98891) (xy 392.04265 -210.98637)
			(xy 398.334992 -204.694028) (xy 398.337786 -204.68971) (xy 398.352642 -204.667706) (xy 398.387479 -204.627642)
			(xy 398.427535 -204.592796) (xy 398.449546 -204.57795) (xy 398.453864 -204.575156) (xy 404.636986 -198.392034)
			(xy 404.642828 -198.361808) (xy 404.636732 -198.34733) (xy 404.623893 -198.315762) (xy 404.605815 -198.250054)
			(xy 404.596664 -198.182522) (xy 404.596092 -198.148448) (xy 404.596535 -198.117714) (xy 404.603939 -198.056694)
			(xy 404.618644 -197.997011) (xy 404.640437 -197.939536) (xy 404.668999 -197.885107) (xy 404.703914 -197.834517)
			(xy 404.744672 -197.788506) (xy 404.79068 -197.747743) (xy 404.841265 -197.712824) (xy 404.895692 -197.684256)
			(xy 404.953165 -197.662458) (xy 405.012846 -197.647747) (xy 405.073866 -197.640338) (xy 405.1046 -197.63994)
			(xy 405.138675 -197.640503) (xy 405.20621 -197.649644) (xy 405.271916 -197.667734) (xy 405.303482 -197.68058)
			(xy 405.31796 -197.686676) (xy 405.348186 -197.680834) (xy 407.307034 -195.721986) (xy 407.31443 -195.715135)
			(xy 407.333029 -195.7074) (xy 407.343102 -195.707) (xy 409.2956 -195.707) (xy 409.305478 -195.706543)
			(xy 409.323782 -195.699104) (xy 409.33116 -195.692522) (xy 409.331414 -195.692268) (xy 410.247084 -194.776598)
			(xy 410.253202 -194.770031) (xy 410.260746 -194.75376) (xy 410.261816 -194.744848) (xy 410.261816 -194.744594)
			(xy 410.264911 -194.712087) (xy 410.278387 -194.648194) (xy 410.299931 -194.58655) (xy 410.329187 -194.528171)
			(xy 410.365675 -194.474017) (xy 410.408793 -194.424978) (xy 410.457834 -194.381861) (xy 410.51199 -194.345376)
			(xy 410.57037 -194.316122) (xy 410.632014 -194.294582) (xy 410.695909 -194.281108) (xy 410.728414 -194.277996)
			(xy 410.728668 -194.277996) (xy 410.737548 -194.276823) (xy 410.753775 -194.269274) (xy 410.760418 -194.263264)
			(xy 410.77642 -194.247262) (xy 410.783984 -194.238947) (xy 410.791645 -194.217845) (xy 410.789513 -194.195497)
			(xy 410.784294 -194.18554) (xy 410.784294 -194.185286) (xy 410.768205 -194.156704) (xy 410.742861 -194.096209)
			(xy 410.725702 -194.032904) (xy 410.717027 -193.96789) (xy 410.716476 -193.935096) (xy 410.716476 -193.928746)
			(xy 410.717017 -193.906889) (xy 410.721467 -193.863391) (xy 410.725366 -193.841878) (xy 410.726794 -193.832388)
			(xy 410.723272 -193.813539) (xy 410.713062 -193.797307) (xy 410.705554 -193.791332) (xy 410.672746 -193.766613)
			(xy 410.611405 -193.711971) (xy 410.555443 -193.65183) (xy 410.505352 -193.586719) (xy 410.46157 -193.517209)
			(xy 410.424481 -193.443908) (xy 410.394412 -193.367459) (xy 410.371624 -193.288533) (xy 410.356319 -193.207822)
			(xy 410.34863 -193.126033) (xy 410.348176 -193.084958) (xy 410.348664 -193.043231) (xy 410.356612 -192.960157)
			(xy 410.372423 -192.878214) (xy 410.395954 -192.798146) (xy 410.42699 -192.720678) (xy 410.445712 -192.683384)
			(xy 410.450697 -192.67222) (xy 410.450704 -192.647808) (xy 410.445712 -192.636648) (xy 410.427033 -192.599335)
			(xy 410.39601 -192.521866) (xy 410.372483 -192.441802) (xy 410.356664 -192.359866) (xy 410.348696 -192.276798)
			(xy 410.348176 -192.235074) (xy 410.348673 -192.19333) (xy 410.356609 -192.11022) (xy 410.372409 -192.028242)
			(xy 410.39593 -191.948136) (xy 410.426959 -191.870628) (xy 410.465216 -191.796422) (xy 410.510352 -191.726187)
			(xy 410.561961 -191.660561) (xy 410.619574 -191.600139) (xy 410.68267 -191.545466) (xy 410.750677 -191.497038)
			(xy 410.82298 -191.455294) (xy 410.898923 -191.420612) (xy 410.977819 -191.393306) (xy 411.058953 -191.373623)
			(xy 411.141591 -191.361742) (xy 411.224984 -191.357769) (xy 411.308377 -191.361742) (xy 411.391015 -191.373623)
			(xy 411.472149 -191.393306) (xy 411.551045 -191.420612) (xy 411.626988 -191.455294) (xy 411.699291 -191.497038)
			(xy 411.767298 -191.545466) (xy 411.830394 -191.600139) (xy 411.888007 -191.660561) (xy 411.939616 -191.726187)
			(xy 411.984752 -191.796422) (xy 412.023009 -191.870628) (xy 412.054038 -191.948136) (xy 412.077559 -192.028242)
			(xy 412.093359 -192.11022) (xy 412.101295 -192.19333) (xy 412.101792 -192.235074) (xy 412.101302 -192.2768)
			(xy 412.093351 -192.359874) (xy 412.077537 -192.441815) (xy 412.054003 -192.521881) (xy 412.022963 -192.599347)
			(xy 412.004256 -192.636648) (xy 411.999281 -192.647812) (xy 411.999288 -192.672216) (xy 412.004256 -192.683384)
			(xy 412.015376 -192.705232) (xy 412.035452 -192.749963) (xy 412.044388 -192.772792) (xy 412.044388 -192.773046)
			(xy 412.045404 -192.775586) (xy 412.049468 -192.786) (xy 412.057596 -192.793874) (xy 412.062817 -192.798733)
			(xy 412.075324 -192.805573) (xy 412.082234 -192.807336) (xy 412.1658 -192.825116) (xy 412.174126 -192.826596)
			(xy 412.190906 -192.824572) (xy 412.206101 -192.817171) (xy 412.212282 -192.8114) (xy 418.952934 -186.070748)
			(xy 418.953442 -186.07024) (xy 418.960025 -186.062859) (xy 418.967474 -186.04456) (xy 418.96792 -186.03468)
			(xy 418.96792 -176.02073) (xy 418.967485 -176.010665) (xy 418.959755 -175.992077) (xy 418.952934 -175.984662)
			(xy 417.97732 -175.009048) (xy 417.970208 -175.001682) (xy 417.951412 -174.994062) (xy 410.105606 -174.994062)
			(xy 410.097077 -174.994339) (xy 410.080946 -174.999872) (xy 410.067545 -175.010419) (xy 410.06268 -175.01743)
			(xy 410.054932 -175.029408) (xy 410.037897 -175.052293) (xy 410.028644 -175.06315) (xy 410.022548 -175.070262)
			(xy 410.016198 -175.087026) (xy 410.016198 -175.172878) (xy 410.022548 -175.189642) (xy 410.028644 -175.196754)
			(xy 410.046285 -175.217685) (xy 410.076009 -175.263652) (xy 410.098849 -175.313399) (xy 410.114334 -175.365903)
			(xy 410.122146 -175.420082) (xy 410.122624 -175.447452) (xy 410.122164 -175.474708) (xy 410.114413 -175.528665)
			(xy 410.099061 -175.580969) (xy 410.076422 -175.630556) (xy 410.046955 -175.676417) (xy 410.011262 -175.717617)
			(xy 409.970068 -175.753317) (xy 409.924213 -175.782791) (xy 409.874629 -175.805439) (xy 409.822327 -175.820799)
			(xy 409.768371 -175.82856) (xy 409.741116 -175.82896) (xy 409.714375 -175.828511) (xy 409.661418 -175.821041)
			(xy 409.610024 -175.806245) (xy 409.561201 -175.784414) (xy 409.515908 -175.755976) (xy 409.475031 -175.721488)
			(xy 409.439375 -175.681628) (xy 409.409637 -175.637176) (xy 409.386401 -175.589006) (xy 409.370123 -175.538062)
			(xy 409.361123 -175.485343) (xy 409.359862 -175.458628) (xy 409.359354 -175.443134) (xy 409.342082 -175.418496)
			(xy 409.240736 -175.378618) (xy 409.231434 -175.375464) (xy 409.211811 -175.375688) (xy 409.193698 -175.38324)
			(xy 409.18638 -175.389794) (xy 401.427442 -183.148732) (xy 401.420076 -183.169814) (xy 401.421092 -183.181498)
			(xy 401.423124 -183.22036) (xy 401.422649 -183.247729) (xy 401.414817 -183.301903) (xy 401.399325 -183.354402)
			(xy 401.376488 -183.404149) (xy 401.346777 -183.450121) (xy 401.329144 -183.471058) (xy 401.323048 -183.47817)
			(xy 401.316698 -183.494934) (xy 401.316698 -183.580786) (xy 401.323048 -183.59755) (xy 401.329144 -183.604662)
			(xy 401.346785 -183.625593) (xy 401.376508 -183.67156) (xy 401.399346 -183.721307) (xy 401.41483 -183.773811)
			(xy 401.422641 -183.82799) (xy 401.423124 -183.85536) (xy 401.422664 -183.882615) (xy 401.414912 -183.936571)
			(xy 401.399559 -183.988875) (xy 401.376919 -184.038461) (xy 401.347452 -184.084321) (xy 401.311759 -184.125519)
			(xy 401.270565 -184.161219) (xy 401.22471 -184.190692) (xy 401.175128 -184.21334) (xy 401.122826 -184.2287)
			(xy 401.068871 -184.23646) (xy 401.041616 -184.236868) (xy 401.01305 -184.236354) (xy 400.956558 -184.227821)
			(xy 400.90197 -184.210959) (xy 400.850508 -184.186145) (xy 400.803321 -184.153933) (xy 400.761466 -184.115045)
			(xy 400.725878 -184.07035) (xy 400.711162 -184.04586) (xy 400.705066 -184.0357) (xy 400.685508 -184.022492)
			(xy 400.59356 -184.010554) (xy 400.581899 -184.009603) (xy 400.559779 -184.017141) (xy 400.551142 -184.025032)
			(xy 397.991074 -186.5851) (xy 412.55033 -186.5851) (xy 412.554321 -186.496233) (xy 412.566262 -186.408082)
			(xy 412.586057 -186.321356) (xy 412.613546 -186.236754) (xy 412.648509 -186.154956) (xy 412.690663 -186.076622)
			(xy 412.739669 -186.002382) (xy 412.795133 -185.932833) (xy 412.856608 -185.868536) (xy 412.923599 -185.810009)
			(xy 412.995567 -185.757723) (xy 413.071932 -185.712098) (xy 413.152079 -185.673502) (xy 413.235364 -185.642247)
			(xy 413.321114 -185.618582) (xy 413.408641 -185.6027) (xy 413.49724 -185.594727) (xy 413.541718 -185.594244)
			(xy 415.294318 -185.594244) (xy 415.338794 -185.594748) (xy 415.427389 -185.602723) (xy 415.514912 -185.618607)
			(xy 415.600658 -185.642273) (xy 415.683938 -185.67353) (xy 415.764081 -185.712126) (xy 415.840442 -185.757751)
			(xy 415.912406 -185.810037) (xy 415.979393 -185.868563) (xy 416.040864 -185.932858) (xy 416.096324 -186.002404)
			(xy 416.145328 -186.076642) (xy 416.187479 -186.154973) (xy 416.222439 -186.236768) (xy 416.249927 -186.321367)
			(xy 416.26972 -186.408089) (xy 416.281661 -186.496237) (xy 416.285652 -186.5851) (xy 416.281661 -186.673963)
			(xy 416.26972 -186.762111) (xy 416.249927 -186.848833) (xy 416.222439 -186.933432) (xy 416.187479 -187.015227)
			(xy 416.145328 -187.093558) (xy 416.096324 -187.167796) (xy 416.040864 -187.237342) (xy 415.979393 -187.301637)
			(xy 415.912406 -187.360163) (xy 415.840442 -187.412449) (xy 415.764081 -187.458074) (xy 415.683938 -187.49667)
			(xy 415.600658 -187.527927) (xy 415.514912 -187.551593) (xy 415.427389 -187.567477) (xy 415.338794 -187.575452)
			(xy 415.294318 -187.575952) (xy 413.541718 -187.575952) (xy 413.49724 -187.575473) (xy 413.408641 -187.5675)
			(xy 413.321114 -187.551618) (xy 413.235364 -187.527953) (xy 413.152079 -187.496698) (xy 413.071932 -187.458102)
			(xy 412.995567 -187.412477) (xy 412.923599 -187.360191) (xy 412.856608 -187.301664) (xy 412.795133 -187.237367)
			(xy 412.739669 -187.167818) (xy 412.690663 -187.093578) (xy 412.648509 -187.015244) (xy 412.613546 -186.933446)
			(xy 412.586057 -186.848844) (xy 412.566262 -186.762118) (xy 412.554321 -186.673967) (xy 412.55033 -186.5851)
			(xy 397.991074 -186.5851) (xy 395.700504 -188.87567) (xy 395.697456 -188.912754) (xy 395.708378 -188.927994)
			(xy 395.725283 -188.952483) (xy 395.752107 -189.005596) (xy 395.770376 -189.062225) (xy 395.77965 -189.121001)
			(xy 395.78026 -189.150752) (xy 395.7798 -189.178006) (xy 395.772048 -189.231959) (xy 395.756696 -189.28426)
			(xy 395.734055 -189.333843) (xy 395.704588 -189.379699) (xy 395.668894 -189.420894) (xy 395.627699 -189.456588)
			(xy 395.581843 -189.486055) (xy 395.53226 -189.508696) (xy 395.479959 -189.524048) (xy 395.426006 -189.5318)
			(xy 395.398752 -189.53226) (xy 395.368996 -189.531697) (xy 395.310204 -189.522459) (xy 395.253567 -189.504185)
			(xy 395.200464 -189.477318) (xy 395.175994 -189.460378) (xy 395.160754 -189.449456) (xy 395.12367 -189.452504)
			(xy 393.92606 -190.650114) (xy 393.918694 -190.657226) (xy 393.911074 -190.676022) (xy 393.911074 -198.102474)
			(xy 393.910637 -198.112538) (xy 393.902901 -198.13112) (xy 393.896088 -198.138542) (xy 391.496042 -200.538588)
			(xy 396.618712 -200.538588) (xy 396.622783 -200.482966) (xy 396.634909 -200.428529) (xy 396.654832 -200.376438)
			(xy 396.682128 -200.327803) (xy 396.716214 -200.28366) (xy 396.756363 -200.244951) (xy 396.801721 -200.2125)
			(xy 396.851321 -200.186999) (xy 396.904105 -200.168992) (xy 396.958948 -200.158862) (xy 397.014682 -200.156825)
			(xy 397.070119 -200.162925) (xy 397.124076 -200.177031) (xy 397.175405 -200.198843) (xy 397.223011 -200.227897)
			(xy 397.265879 -200.263572) (xy 397.303096 -200.305109) (xy 397.333869 -200.351622) (xy 397.357541 -200.402119)
			(xy 397.373609 -200.455526) (xy 397.381729 -200.510702) (xy 397.382238 -200.538588) (xy 397.381729 -200.566474)
			(xy 397.373609 -200.62165) (xy 397.357541 -200.675057) (xy 397.333869 -200.725554) (xy 397.303096 -200.772067)
			(xy 397.265879 -200.813604) (xy 397.223011 -200.849279) (xy 397.175405 -200.878333) (xy 397.124076 -200.900145)
			(xy 397.070119 -200.914251) (xy 397.014682 -200.920351) (xy 396.958948 -200.918314) (xy 396.904105 -200.908184)
			(xy 396.851321 -200.890177) (xy 396.801721 -200.864676) (xy 396.756363 -200.832225) (xy 396.716214 -200.793516)
			(xy 396.682128 -200.749373) (xy 396.654832 -200.700738) (xy 396.634909 -200.648647) (xy 396.622783 -200.59421)
			(xy 396.618712 -200.538588) (xy 391.496042 -200.538588) (xy 389.173001 -202.861629) (xy 394.746728 -202.861629)
			(xy 394.746728 -202.797707) (xy 394.754739 -202.734289) (xy 394.770636 -202.672375) (xy 394.794168 -202.612942)
			(xy 394.824962 -202.556927) (xy 394.862535 -202.505212) (xy 394.906292 -202.458615) (xy 394.955545 -202.41787)
			(xy 395.009516 -202.383619) (xy 395.067355 -202.356402) (xy 395.128148 -202.336649) (xy 395.190938 -202.324671)
			(xy 395.254734 -202.320658) (xy 395.31853 -202.324671) (xy 395.38132 -202.336649) (xy 395.442113 -202.356402)
			(xy 395.499952 -202.383619) (xy 395.553923 -202.41787) (xy 395.603176 -202.458615) (xy 395.646933 -202.505212)
			(xy 395.684506 -202.556927) (xy 395.7153 -202.612942) (xy 395.738832 -202.672375) (xy 395.754729 -202.734289)
			(xy 395.76274 -202.797707) (xy 395.763242 -202.829668) (xy 395.76274 -202.861629) (xy 395.754729 -202.925047)
			(xy 395.738832 -202.986961) (xy 395.7153 -203.046394) (xy 395.684506 -203.102409) (xy 395.646933 -203.154124)
			(xy 395.603176 -203.200721) (xy 395.553923 -203.241466) (xy 395.527275 -203.258377) (xy 398.420076 -203.258377)
			(xy 398.420076 -203.194455) (xy 398.428087 -203.131037) (xy 398.443984 -203.069123) (xy 398.467516 -203.00969)
			(xy 398.49831 -202.953675) (xy 398.535883 -202.90196) (xy 398.57964 -202.855363) (xy 398.628893 -202.814618)
			(xy 398.682864 -202.780367) (xy 398.740703 -202.75315) (xy 398.801496 -202.733397) (xy 398.864286 -202.721419)
			(xy 398.928082 -202.717406) (xy 398.991878 -202.721419) (xy 399.054668 -202.733397) (xy 399.115461 -202.75315)
			(xy 399.1733 -202.780367) (xy 399.227271 -202.814618) (xy 399.276524 -202.855363) (xy 399.320281 -202.90196)
			(xy 399.357854 -202.953675) (xy 399.388648 -203.00969) (xy 399.41218 -203.069123) (xy 399.428077 -203.131037)
			(xy 399.436088 -203.194455) (xy 399.43659 -203.226416) (xy 399.436088 -203.258377) (xy 399.428077 -203.321795)
			(xy 399.41218 -203.383709) (xy 399.388648 -203.443142) (xy 399.357854 -203.499157) (xy 399.320281 -203.550872)
			(xy 399.276524 -203.597469) (xy 399.227271 -203.638214) (xy 399.1733 -203.672465) (xy 399.115461 -203.699682)
			(xy 399.054668 -203.719435) (xy 398.991878 -203.731413) (xy 398.928082 -203.735427) (xy 398.864286 -203.731413)
			(xy 398.801496 -203.719435) (xy 398.740703 -203.699682) (xy 398.682864 -203.672465) (xy 398.628893 -203.638214)
			(xy 398.57964 -203.597469) (xy 398.535883 -203.550872) (xy 398.49831 -203.499157) (xy 398.467516 -203.443142)
			(xy 398.443984 -203.383709) (xy 398.428087 -203.321795) (xy 398.420076 -203.258377) (xy 395.527275 -203.258377)
			(xy 395.499952 -203.275717) (xy 395.442113 -203.302934) (xy 395.38132 -203.322687) (xy 395.31853 -203.334665)
			(xy 395.254734 -203.338679) (xy 395.190938 -203.334665) (xy 395.128148 -203.322687) (xy 395.067355 -203.302934)
			(xy 395.009516 -203.275717) (xy 394.955545 -203.241466) (xy 394.906292 -203.200721) (xy 394.862535 -203.154124)
			(xy 394.824962 -203.102409) (xy 394.794168 -203.046394) (xy 394.770636 -202.986961) (xy 394.754739 -202.925047)
			(xy 394.746728 -202.861629) (xy 389.173001 -202.861629) (xy 388.475263 -203.559367) (xy 393.47749 -203.559367)
			(xy 393.47749 -203.495445) (xy 393.485501 -203.432027) (xy 393.501398 -203.370113) (xy 393.52493 -203.31068)
			(xy 393.555724 -203.254665) (xy 393.593297 -203.20295) (xy 393.637054 -203.156353) (xy 393.686307 -203.115608)
			(xy 393.740278 -203.081357) (xy 393.798117 -203.05414) (xy 393.85891 -203.034387) (xy 393.9217 -203.022409)
			(xy 393.985496 -203.018396) (xy 394.049292 -203.022409) (xy 394.112082 -203.034387) (xy 394.172875 -203.05414)
			(xy 394.230714 -203.081357) (xy 394.284685 -203.115608) (xy 394.333938 -203.156353) (xy 394.377695 -203.20295)
			(xy 394.415268 -203.254665) (xy 394.446062 -203.31068) (xy 394.469594 -203.370113) (xy 394.485491 -203.432027)
			(xy 394.493502 -203.495445) (xy 394.494004 -203.527406) (xy 394.493502 -203.559367) (xy 394.485491 -203.622785)
			(xy 394.469594 -203.684699) (xy 394.446062 -203.744132) (xy 394.415268 -203.800147) (xy 394.377695 -203.851862)
			(xy 394.333938 -203.898459) (xy 394.284685 -203.939204) (xy 394.230714 -203.973455) (xy 394.172875 -204.000672)
			(xy 394.112082 -204.020425) (xy 394.049292 -204.032403) (xy 393.985496 -204.036417) (xy 393.9217 -204.032403)
			(xy 393.85891 -204.020425) (xy 393.798117 -204.000672) (xy 393.740278 -203.973455) (xy 393.686307 -203.939204)
			(xy 393.637054 -203.898459) (xy 393.593297 -203.851862) (xy 393.555724 -203.800147) (xy 393.52493 -203.744132)
			(xy 393.501398 -203.684699) (xy 393.485501 -203.622785) (xy 393.47749 -203.559367) (xy 388.475263 -203.559367)
			(xy 386.943643 -205.090987) (xy 390.644882 -205.090987) (xy 390.644882 -205.027065) (xy 390.652893 -204.963647)
			(xy 390.66879 -204.901733) (xy 390.692322 -204.8423) (xy 390.723116 -204.786285) (xy 390.760689 -204.73457)
			(xy 390.804446 -204.687973) (xy 390.853699 -204.647228) (xy 390.90767 -204.612977) (xy 390.965509 -204.58576)
			(xy 391.026302 -204.566007) (xy 391.089092 -204.554029) (xy 391.152888 -204.550016) (xy 391.216684 -204.554029)
			(xy 391.279474 -204.566007) (xy 391.340267 -204.58576) (xy 391.398106 -204.612977) (xy 391.452077 -204.647228)
			(xy 391.50133 -204.687973) (xy 391.545087 -204.73457) (xy 391.58266 -204.786285) (xy 391.613454 -204.8423)
			(xy 391.636986 -204.901733) (xy 391.652883 -204.963647) (xy 391.660894 -205.027065) (xy 391.661196 -205.0463)
			(xy 392.571515 -205.0463) (xy 392.575529 -204.982508) (xy 392.587506 -204.919722) (xy 392.607258 -204.858932)
			(xy 392.634473 -204.801097) (xy 392.668721 -204.747128) (xy 392.709464 -204.697878) (xy 392.756058 -204.654123)
			(xy 392.807769 -204.616552) (xy 392.863781 -204.585759) (xy 392.923211 -204.562228) (xy 392.985121 -204.546332)
			(xy 393.048535 -204.53832) (xy 393.080494 -204.537818) (xy 393.113214 -204.538283) (xy 393.178112 -204.546685)
			(xy 393.241398 -204.563338) (xy 393.302027 -204.587967) (xy 393.358997 -204.620165) (xy 393.41137 -204.659402)
			(xy 393.458279 -204.70503) (xy 393.498952 -204.756295) (xy 393.532717 -204.812352) (xy 393.54633 -204.84211)
			(xy 393.552426 -204.85608) (xy 393.577572 -204.87259) (xy 393.701016 -204.87259) (xy 393.726162 -204.85608)
			(xy 393.732258 -204.84211) (xy 393.745871 -204.812354) (xy 393.779637 -204.756303) (xy 393.820311 -204.705043)
			(xy 393.867222 -204.659422) (xy 393.919596 -204.620193) (xy 393.976567 -204.588003) (xy 394.037195 -204.563384)
			(xy 394.10048 -204.546742) (xy 394.165376 -204.538351) (xy 394.230812 -204.538351) (xy 394.295708 -204.546742)
			(xy 394.358993 -204.563384) (xy 394.419621 -204.588003) (xy 394.476592 -204.620193) (xy 394.528966 -204.659422)
			(xy 394.575877 -204.705043) (xy 394.616551 -204.756303) (xy 394.650317 -204.812354) (xy 394.66393 -204.84211)
			(xy 394.670026 -204.85608) (xy 394.695172 -204.87259) (xy 394.818616 -204.87259) (xy 394.843762 -204.85608)
			(xy 394.849858 -204.84211) (xy 394.863492 -204.812363) (xy 394.897251 -204.756306) (xy 394.937919 -204.705041)
			(xy 394.984826 -204.659415) (xy 395.037197 -204.62018) (xy 395.094166 -204.587986) (xy 395.154794 -204.563362)
			(xy 395.218079 -204.546717) (xy 395.282975 -204.538325) (xy 395.315694 -204.537818) (xy 395.347658 -204.538247)
			(xy 395.411083 -204.546258) (xy 395.473003 -204.562156) (xy 395.532442 -204.585689) (xy 395.588463 -204.616486)
			(xy 395.640183 -204.654062) (xy 395.686785 -204.697824) (xy 395.727535 -204.747082) (xy 395.76179 -204.801058)
			(xy 395.789009 -204.858902) (xy 395.808764 -204.919702) (xy 395.820743 -204.982498) (xy 395.824758 -205.0463)
			(xy 395.820743 -205.110102) (xy 395.808764 -205.172898) (xy 395.789009 -205.233698) (xy 395.76179 -205.291542)
			(xy 395.727535 -205.345518) (xy 395.686785 -205.394776) (xy 395.640183 -205.438538) (xy 395.588463 -205.476114)
			(xy 395.532442 -205.506911) (xy 395.473003 -205.530444) (xy 395.411083 -205.546342) (xy 395.347658 -205.554353)
			(xy 395.315694 -205.554834) (xy 395.282975 -205.554348) (xy 395.218079 -205.545946) (xy 395.154795 -205.529294)
			(xy 395.094168 -205.504666) (xy 395.037198 -205.47247) (xy 394.984826 -205.433236) (xy 394.937915 -205.387612)
			(xy 394.897241 -205.336351) (xy 394.863473 -205.280298) (xy 394.849858 -205.250542) (xy 394.843762 -205.236572)
			(xy 394.818616 -205.220062) (xy 394.695172 -205.220062) (xy 394.670026 -205.236572) (xy 394.66393 -205.250542)
			(xy 394.650317 -205.280298) (xy 394.616551 -205.336349) (xy 394.575877 -205.387609) (xy 394.528966 -205.43323)
			(xy 394.476592 -205.472459) (xy 394.419621 -205.504649) (xy 394.358993 -205.529268) (xy 394.295708 -205.54591)
			(xy 394.230812 -205.554301) (xy 394.165376 -205.554301) (xy 394.10048 -205.54591) (xy 394.037195 -205.529268)
			(xy 393.976567 -205.504649) (xy 393.919596 -205.472459) (xy 393.867222 -205.43323) (xy 393.820311 -205.387609)
			(xy 393.779637 -205.336349) (xy 393.745871 -205.280298) (xy 393.732258 -205.250542) (xy 393.726162 -205.236572)
			(xy 393.701016 -205.220062) (xy 393.577572 -205.220062) (xy 393.552426 -205.236572) (xy 393.54633 -205.250542)
			(xy 393.532682 -205.280283) (xy 393.498927 -205.336342) (xy 393.458262 -205.387608) (xy 393.411357 -205.433236)
			(xy 393.358988 -205.472472) (xy 393.30202 -205.504668) (xy 393.241393 -205.529291) (xy 393.178109 -205.545936)
			(xy 393.113212 -205.554328) (xy 393.080494 -205.554834) (xy 393.048535 -205.55428) (xy 392.985121 -205.546268)
			(xy 392.923211 -205.530372) (xy 392.863781 -205.506841) (xy 392.807769 -205.476048) (xy 392.756058 -205.438477)
			(xy 392.709464 -205.394722) (xy 392.668721 -205.345472) (xy 392.634473 -205.291503) (xy 392.607258 -205.233668)
			(xy 392.587506 -205.172878) (xy 392.575529 -205.110092) (xy 392.571515 -205.0463) (xy 391.661196 -205.0463)
			(xy 391.661396 -205.059026) (xy 391.660894 -205.090987) (xy 391.652883 -205.154405) (xy 391.636986 -205.216319)
			(xy 391.613454 -205.275752) (xy 391.58266 -205.331767) (xy 391.545087 -205.383482) (xy 391.50133 -205.430079)
			(xy 391.452077 -205.470824) (xy 391.398106 -205.505075) (xy 391.340267 -205.532292) (xy 391.279474 -205.552045)
			(xy 391.216684 -205.564023) (xy 391.152888 -205.568037) (xy 391.089092 -205.564023) (xy 391.026302 -205.552045)
			(xy 390.965509 -205.532292) (xy 390.90767 -205.505075) (xy 390.853699 -205.470824) (xy 390.804446 -205.430079)
			(xy 390.760689 -205.383482) (xy 390.723116 -205.331767) (xy 390.692322 -205.275752) (xy 390.66879 -205.216319)
			(xy 390.652893 -205.154405) (xy 390.644882 -205.090987) (xy 386.943643 -205.090987) (xy 385.943856 -206.090774)
			(xy 385.935982 -206.109062) (xy 385.935982 -206.118968) (xy 385.935052 -206.151397) (xy 385.925968 -206.215635)
			(xy 385.908786 -206.278195) (xy 385.883785 -206.338061) (xy 385.851372 -206.39426) (xy 385.812073 -206.44588)
			(xy 385.766526 -206.49208) (xy 385.715472 -206.532111) (xy 385.659741 -206.565322) (xy 385.600237 -206.591174)
			(xy 385.537928 -206.609246) (xy 385.50596 -206.614776) (xy 385.496716 -206.616538) (xy 385.480387 -206.625867)
			(xy 385.468552 -206.640481) (xy 385.46532 -206.64932) (xy 385.455432 -206.678204) (xy 385.429698 -206.733569)
			(xy 385.397515 -206.785451) (xy 385.359346 -206.833102) (xy 385.315743 -206.875837) (xy 385.267333 -206.913038)
			(xy 385.241292 -206.928974) (xy 385.233832 -206.933856) (xy 385.222532 -206.94763) (xy 385.219194 -206.955898)
			(xy 385.210182 -206.980525) (xy 385.186356 -207.027241) (xy 385.156354 -207.070253) (xy 385.120743 -207.108748)
			(xy 385.080193 -207.142001) (xy 385.035469 -207.169385) (xy 384.987415 -207.190384) (xy 384.936938 -207.2046)
			(xy 384.884989 -207.211767) (xy 384.858768 -207.212184) (xy 384.84556 -207.21193) (xy 384.834892 -207.211676)
			(xy 384.815334 -207.219296) (xy 381.85344 -210.18119) (xy 381.845843 -210.189721) (xy 381.838315 -210.211255)
			(xy 381.840804 -210.233932) (xy 381.846328 -210.243928) (xy 381.864747 -210.274434) (xy 381.893803 -210.339503)
			(xy 381.913497 -210.407989) (xy 381.923442 -210.478553) (xy 381.924052 -210.514184) (xy 381.923589 -210.544917)
			(xy 381.916183 -210.605934) (xy 381.901476 -210.665614) (xy 381.879682 -210.723086) (xy 381.851121 -210.777512)
			(xy 381.816207 -210.828098) (xy 381.775451 -210.874108) (xy 381.729446 -210.91487) (xy 381.678863 -210.949789)
			(xy 381.62444 -210.978358) (xy 381.566971 -211.000158) (xy 381.507293 -211.014872) (xy 381.446277 -211.022286)
			(xy 381.415544 -211.022692) (xy 381.402822 -211.022612) (xy 381.37741 -211.02134) (xy 381.364744 -211.020152)
			(xy 381.364744 -211.020406) (xy 381.335668 -211.017077) (xy 381.278488 -211.004591) (xy 381.223119 -210.985625)
			(xy 381.170293 -210.96043) (xy 381.145288 -210.945222) (xy 381.130048 -210.93557) (xy 381.094996 -210.939634)
			(xy 375.133616 -216.901014) (xy 375.12625 -216.908126) (xy 375.11863 -216.926922) (xy 375.11863 -219.283788)
			(xy 380.102618 -219.283788) (xy 380.103086 -219.246611) (xy 380.11033 -219.172611) (xy 380.124748 -219.099668)
			(xy 380.146202 -219.028477) (xy 380.174488 -218.959714) (xy 380.191518 -218.926664) (xy 380.196838 -218.915311)
			(xy 380.196833 -218.890268) (xy 380.191518 -218.878912) (xy 380.174481 -218.845866) (xy 380.146209 -218.777097)
			(xy 380.12476 -218.705904) (xy 380.110338 -218.632963) (xy 380.103078 -218.558965) (xy 380.102618 -218.521788)
			(xy 380.103107 -218.483143) (xy 380.110927 -218.406249) (xy 380.126485 -218.330541) (xy 380.149623 -218.256795)
			(xy 380.180103 -218.185768) (xy 380.217612 -218.11819) (xy 380.261766 -218.054752) (xy 380.312111 -217.996108)
			(xy 380.36813 -217.942857) (xy 380.429249 -217.895547) (xy 380.494842 -217.854663) (xy 380.564233 -217.820625)
			(xy 380.636713 -217.793782) (xy 380.711536 -217.774409) (xy 380.787935 -217.762705) (xy 380.865126 -217.75879)
			(xy 380.942317 -217.762705) (xy 381.018716 -217.774409) (xy 381.093539 -217.793782) (xy 381.166019 -217.820625)
			(xy 381.23541 -217.854663) (xy 381.301003 -217.895547) (xy 381.362122 -217.942857) (xy 381.418141 -217.996108)
			(xy 381.468486 -218.054752) (xy 381.51264 -218.11819) (xy 381.550149 -218.185768) (xy 381.580629 -218.256795)
			(xy 381.603767 -218.330541) (xy 381.619325 -218.406249) (xy 381.627145 -218.483143) (xy 381.627634 -218.521788)
			(xy 381.627191 -218.558965) (xy 381.619941 -218.632966) (xy 381.605517 -218.705909) (xy 381.584058 -218.7771)
			(xy 381.555766 -218.845862) (xy 381.538734 -218.878912) (xy 381.533434 -218.890271) (xy 381.533429 -218.915308)
			(xy 381.538734 -218.926664) (xy 381.555757 -218.959717) (xy 381.584033 -219.028483) (xy 381.605485 -219.099674)
			(xy 381.619911 -219.172614) (xy 381.627173 -219.246612) (xy 381.627634 -219.283788) (xy 381.627145 -219.322433)
			(xy 381.619325 -219.399327) (xy 381.603767 -219.475035) (xy 381.580629 -219.548781) (xy 381.550149 -219.619808)
			(xy 381.51264 -219.687386) (xy 381.468486 -219.750824) (xy 381.418141 -219.809468) (xy 381.362122 -219.862719)
			(xy 381.301003 -219.910029) (xy 381.23541 -219.950913) (xy 381.166019 -219.984951) (xy 381.093539 -220.011794)
			(xy 381.018716 -220.031167) (xy 380.942317 -220.042871) (xy 380.865126 -220.046786) (xy 380.787935 -220.042871)
			(xy 380.711536 -220.031167) (xy 380.636713 -220.011794) (xy 380.564233 -219.984951) (xy 380.494842 -219.950913)
			(xy 380.429249 -219.910029) (xy 380.36813 -219.862719) (xy 380.312111 -219.809468) (xy 380.261766 -219.750824)
			(xy 380.217612 -219.687386) (xy 380.180103 -219.619808) (xy 380.149623 -219.548781) (xy 380.126485 -219.475035)
			(xy 380.110927 -219.399327) (xy 380.103107 -219.322433) (xy 380.102618 -219.283788) (xy 375.11863 -219.283788)
			(xy 375.11863 -221.80423) (xy 375.388898 -221.80423) (xy 375.392858 -221.755176) (xy 375.404635 -221.707392)
			(xy 375.423926 -221.662116) (xy 375.450229 -221.62052) (xy 375.482864 -221.583683) (xy 375.520985 -221.552558)
			(xy 375.563606 -221.527951) (xy 375.609622 -221.510499) (xy 375.657841 -221.500655) (xy 375.707016 -221.498674)
			(xy 375.755871 -221.504606) (xy 375.803142 -221.518298) (xy 375.847604 -221.539396) (xy 375.888107 -221.567352)
			(xy 375.9236 -221.601444) (xy 375.953165 -221.640788) (xy 375.976036 -221.684365) (xy 375.99162 -221.731046)
			(xy 375.999515 -221.779623) (xy 376.00001 -221.80423) (xy 375.999515 -221.828837) (xy 375.99162 -221.877414)
			(xy 375.976036 -221.924095) (xy 375.953165 -221.967672) (xy 375.9236 -222.007016) (xy 375.888107 -222.041108)
			(xy 375.847604 -222.069064) (xy 375.803142 -222.090162) (xy 375.755871 -222.103854) (xy 375.707016 -222.109786)
			(xy 375.657841 -222.107805) (xy 375.609622 -222.097961) (xy 375.563606 -222.080509) (xy 375.520985 -222.055902)
			(xy 375.482864 -222.024777) (xy 375.450229 -221.98794) (xy 375.423926 -221.946344) (xy 375.404635 -221.901068)
			(xy 375.392858 -221.853284) (xy 375.388898 -221.80423) (xy 375.11863 -221.80423) (xy 375.11863 -222.207328)
			(xy 375.119059 -222.217395) (xy 375.126784 -222.23599) (xy 375.133616 -222.243396) (xy 375.184924 -222.294196)
			(xy 375.192335 -222.300877) (xy 375.210771 -222.308451) (xy 375.220738 -222.308928) (xy 375.224802 -222.308928)
			(xy 375.250054 -222.30945) (xy 375.29987 -222.317763) (xy 375.347638 -222.334162) (xy 375.392055 -222.358199)
			(xy 375.43191 -222.38922) (xy 375.466116 -222.426377) (xy 375.493739 -222.468658) (xy 375.514026 -222.514909)
			(xy 375.526424 -222.563868) (xy 375.530595 -222.6142) (xy 375.530592 -222.614236) (xy 375.859052 -222.614236)
			(xy 375.863012 -222.565182) (xy 375.874789 -222.517398) (xy 375.89408 -222.472122) (xy 375.920383 -222.430526)
			(xy 375.953018 -222.393689) (xy 375.991139 -222.362564) (xy 376.03376 -222.337957) (xy 376.079776 -222.320505)
			(xy 376.127995 -222.310661) (xy 376.17717 -222.30868) (xy 376.226025 -222.314612) (xy 376.273296 -222.328304)
			(xy 376.317758 -222.349402) (xy 376.358261 -222.377358) (xy 376.393754 -222.41145) (xy 376.423319 -222.450794)
			(xy 376.44619 -222.494371) (xy 376.461774 -222.541052) (xy 376.469669 -222.589629) (xy 376.470164 -222.614236)
			(xy 376.799106 -222.614236) (xy 376.803066 -222.565182) (xy 376.814843 -222.517398) (xy 376.834134 -222.472122)
			(xy 376.860437 -222.430526) (xy 376.893072 -222.393689) (xy 376.931193 -222.362564) (xy 376.973814 -222.337957)
			(xy 377.01983 -222.320505) (xy 377.068049 -222.310661) (xy 377.117224 -222.30868) (xy 377.166079 -222.314612)
			(xy 377.21335 -222.328304) (xy 377.257812 -222.349402) (xy 377.298315 -222.377358) (xy 377.333808 -222.41145)
			(xy 377.363373 -222.450794) (xy 377.386244 -222.494371) (xy 377.401828 -222.541052) (xy 377.409723 -222.589629)
			(xy 377.410218 -222.614236) (xy 377.738906 -222.614236) (xy 377.742866 -222.565182) (xy 377.754643 -222.517398)
			(xy 377.773934 -222.472122) (xy 377.800237 -222.430526) (xy 377.832872 -222.393689) (xy 377.870993 -222.362564)
			(xy 377.913614 -222.337957) (xy 377.95963 -222.320505) (xy 378.007849 -222.310661) (xy 378.057024 -222.30868)
			(xy 378.105879 -222.314612) (xy 378.15315 -222.328304) (xy 378.197612 -222.349402) (xy 378.238115 -222.377358)
			(xy 378.273608 -222.41145) (xy 378.303173 -222.450794) (xy 378.326044 -222.494371) (xy 378.341628 -222.541052)
			(xy 378.349523 -222.589629) (xy 378.350018 -222.614236) (xy 378.67896 -222.614236) (xy 378.68292 -222.565182)
			(xy 378.694697 -222.517398) (xy 378.713988 -222.472122) (xy 378.740291 -222.430526) (xy 378.772926 -222.393689)
			(xy 378.811047 -222.362564) (xy 378.853668 -222.337957) (xy 378.899684 -222.320505) (xy 378.947903 -222.310661)
			(xy 378.997078 -222.30868) (xy 379.045933 -222.314612) (xy 379.093204 -222.328304) (xy 379.137666 -222.349402)
			(xy 379.178169 -222.377358) (xy 379.213662 -222.41145) (xy 379.243227 -222.450794) (xy 379.266098 -222.494371)
			(xy 379.281682 -222.541052) (xy 379.289577 -222.589629) (xy 379.290072 -222.614236) (xy 379.289577 -222.638843)
			(xy 379.281682 -222.68742) (xy 379.266098 -222.734101) (xy 379.243227 -222.777678) (xy 379.213662 -222.817022)
			(xy 379.178169 -222.851114) (xy 379.137666 -222.87907) (xy 379.093204 -222.900168) (xy 379.045933 -222.91386)
			(xy 378.997078 -222.919792) (xy 378.947903 -222.917811) (xy 378.899684 -222.907967) (xy 378.853668 -222.890515)
			(xy 378.811047 -222.865908) (xy 378.772926 -222.834783) (xy 378.740291 -222.797946) (xy 378.713988 -222.75635)
			(xy 378.694697 -222.711074) (xy 378.68292 -222.66329) (xy 378.67896 -222.614236) (xy 378.350018 -222.614236)
			(xy 378.349523 -222.638843) (xy 378.341628 -222.68742) (xy 378.326044 -222.734101) (xy 378.303173 -222.777678)
			(xy 378.273608 -222.817022) (xy 378.238115 -222.851114) (xy 378.197612 -222.87907) (xy 378.15315 -222.900168)
			(xy 378.105879 -222.91386) (xy 378.057024 -222.919792) (xy 378.007849 -222.917811) (xy 377.95963 -222.907967)
			(xy 377.913614 -222.890515) (xy 377.870993 -222.865908) (xy 377.832872 -222.834783) (xy 377.800237 -222.797946)
			(xy 377.773934 -222.75635) (xy 377.754643 -222.711074) (xy 377.742866 -222.66329) (xy 377.738906 -222.614236)
			(xy 377.410218 -222.614236) (xy 377.409723 -222.638843) (xy 377.401828 -222.68742) (xy 377.386244 -222.734101)
			(xy 377.363373 -222.777678) (xy 377.333808 -222.817022) (xy 377.298315 -222.851114) (xy 377.257812 -222.87907)
			(xy 377.21335 -222.900168) (xy 377.166079 -222.91386) (xy 377.117224 -222.919792) (xy 377.068049 -222.917811)
			(xy 377.01983 -222.907967) (xy 376.973814 -222.890515) (xy 376.931193 -222.865908) (xy 376.893072 -222.834783)
			(xy 376.860437 -222.797946) (xy 376.834134 -222.75635) (xy 376.814843 -222.711074) (xy 376.803066 -222.66329)
			(xy 376.799106 -222.614236) (xy 376.470164 -222.614236) (xy 376.469669 -222.638843) (xy 376.461774 -222.68742)
			(xy 376.44619 -222.734101) (xy 376.423319 -222.777678) (xy 376.393754 -222.817022) (xy 376.358261 -222.851114)
			(xy 376.317758 -222.87907) (xy 376.273296 -222.900168) (xy 376.226025 -222.91386) (xy 376.17717 -222.919792)
			(xy 376.127995 -222.917811) (xy 376.079776 -222.907967) (xy 376.03376 -222.890515) (xy 375.991139 -222.865908)
			(xy 375.953018 -222.834783) (xy 375.920383 -222.797946) (xy 375.89408 -222.75635) (xy 375.874789 -222.711074)
			(xy 375.863012 -222.66329) (xy 375.859052 -222.614236) (xy 375.530592 -222.614236) (xy 375.526424 -222.664532)
			(xy 375.514026 -222.713491) (xy 375.493739 -222.759742) (xy 375.466116 -222.802023) (xy 375.43191 -222.83918)
			(xy 375.392055 -222.870201) (xy 375.347638 -222.894238) (xy 375.29987 -222.910637) (xy 375.250054 -222.91895)
			(xy 375.224802 -222.919544) (xy 375.220738 -222.919544) (xy 375.210776 -222.920031) (xy 375.192355 -222.927622)
			(xy 375.184924 -222.934276) (xy 375.133616 -222.985076) (xy 375.12678 -222.992478) (xy 375.119071 -223.011076)
			(xy 375.11863 -223.021144) (xy 375.11863 -223.424242) (xy 375.388898 -223.424242) (xy 375.392858 -223.375188)
			(xy 375.404635 -223.327404) (xy 375.423926 -223.282128) (xy 375.450229 -223.240532) (xy 375.482864 -223.203695)
			(xy 375.520985 -223.17257) (xy 375.563606 -223.147963) (xy 375.609622 -223.130511) (xy 375.657841 -223.120667)
			(xy 375.707016 -223.118686) (xy 375.755871 -223.124618) (xy 375.803142 -223.13831) (xy 375.847604 -223.159408)
			(xy 375.888107 -223.187364) (xy 375.9236 -223.221456) (xy 375.953165 -223.2608) (xy 375.976036 -223.304377)
			(xy 375.99162 -223.351058) (xy 375.999515 -223.399635) (xy 376.00001 -223.424242) (xy 376.328952 -223.424242)
			(xy 376.332912 -223.375188) (xy 376.344689 -223.327404) (xy 376.36398 -223.282128) (xy 376.390283 -223.240532)
			(xy 376.422918 -223.203695) (xy 376.461039 -223.17257) (xy 376.50366 -223.147963) (xy 376.549676 -223.130511)
			(xy 376.597895 -223.120667) (xy 376.64707 -223.118686) (xy 376.695925 -223.124618) (xy 376.743196 -223.13831)
			(xy 376.787658 -223.159408) (xy 376.828161 -223.187364) (xy 376.863654 -223.221456) (xy 376.893219 -223.2608)
			(xy 376.91609 -223.304377) (xy 376.931674 -223.351058) (xy 376.939569 -223.399635) (xy 376.940064 -223.424242)
			(xy 377.269006 -223.424242) (xy 377.272966 -223.375188) (xy 377.284743 -223.327404) (xy 377.304034 -223.282128)
			(xy 377.330337 -223.240532) (xy 377.362972 -223.203695) (xy 377.401093 -223.17257) (xy 377.443714 -223.147963)
			(xy 377.48973 -223.130511) (xy 377.537949 -223.120667) (xy 377.587124 -223.118686) (xy 377.635979 -223.124618)
			(xy 377.68325 -223.13831) (xy 377.727712 -223.159408) (xy 377.768215 -223.187364) (xy 377.803708 -223.221456)
			(xy 377.833273 -223.2608) (xy 377.856144 -223.304377) (xy 377.871728 -223.351058) (xy 377.879623 -223.399635)
			(xy 377.880118 -223.424242) (xy 378.20906 -223.424242) (xy 378.21302 -223.375188) (xy 378.224797 -223.327404)
			(xy 378.244088 -223.282128) (xy 378.270391 -223.240532) (xy 378.303026 -223.203695) (xy 378.341147 -223.17257)
			(xy 378.383768 -223.147963) (xy 378.429784 -223.130511) (xy 378.478003 -223.120667) (xy 378.527178 -223.118686)
			(xy 378.576033 -223.124618) (xy 378.623304 -223.13831) (xy 378.667766 -223.159408) (xy 378.708269 -223.187364)
			(xy 378.743762 -223.221456) (xy 378.773327 -223.2608) (xy 378.796198 -223.304377) (xy 378.811782 -223.351058)
			(xy 378.819677 -223.399635) (xy 378.820172 -223.424242) (xy 378.819677 -223.448849) (xy 378.811782 -223.497426)
			(xy 378.796198 -223.544107) (xy 378.773327 -223.587684) (xy 378.743762 -223.627028) (xy 378.708269 -223.66112)
			(xy 378.667766 -223.689076) (xy 378.623304 -223.710174) (xy 378.576033 -223.723866) (xy 378.527178 -223.729798)
			(xy 378.478003 -223.727817) (xy 378.429784 -223.717973) (xy 378.383768 -223.700521) (xy 378.341147 -223.675914)
			(xy 378.303026 -223.644789) (xy 378.270391 -223.607952) (xy 378.244088 -223.566356) (xy 378.224797 -223.52108)
			(xy 378.21302 -223.473296) (xy 378.20906 -223.424242) (xy 377.880118 -223.424242) (xy 377.879623 -223.448849)
			(xy 377.871728 -223.497426) (xy 377.856144 -223.544107) (xy 377.833273 -223.587684) (xy 377.803708 -223.627028)
			(xy 377.768215 -223.66112) (xy 377.727712 -223.689076) (xy 377.68325 -223.710174) (xy 377.635979 -223.723866)
			(xy 377.587124 -223.729798) (xy 377.537949 -223.727817) (xy 377.48973 -223.717973) (xy 377.443714 -223.700521)
			(xy 377.401093 -223.675914) (xy 377.362972 -223.644789) (xy 377.330337 -223.607952) (xy 377.304034 -223.566356)
			(xy 377.284743 -223.52108) (xy 377.272966 -223.473296) (xy 377.269006 -223.424242) (xy 376.940064 -223.424242)
			(xy 376.939569 -223.448849) (xy 376.931674 -223.497426) (xy 376.91609 -223.544107) (xy 376.893219 -223.587684)
			(xy 376.863654 -223.627028) (xy 376.828161 -223.66112) (xy 376.787658 -223.689076) (xy 376.743196 -223.710174)
			(xy 376.695925 -223.723866) (xy 376.64707 -223.729798) (xy 376.597895 -223.727817) (xy 376.549676 -223.717973)
			(xy 376.50366 -223.700521) (xy 376.461039 -223.675914) (xy 376.422918 -223.644789) (xy 376.390283 -223.607952)
			(xy 376.36398 -223.566356) (xy 376.344689 -223.52108) (xy 376.332912 -223.473296) (xy 376.328952 -223.424242)
			(xy 376.00001 -223.424242) (xy 375.999515 -223.448849) (xy 375.99162 -223.497426) (xy 375.976036 -223.544107)
			(xy 375.953165 -223.587684) (xy 375.9236 -223.627028) (xy 375.888107 -223.66112) (xy 375.847604 -223.689076)
			(xy 375.803142 -223.710174) (xy 375.755871 -223.723866) (xy 375.707016 -223.729798) (xy 375.657841 -223.727817)
			(xy 375.609622 -223.717973) (xy 375.563606 -223.700521) (xy 375.520985 -223.675914) (xy 375.482864 -223.644789)
			(xy 375.450229 -223.607952) (xy 375.423926 -223.566356) (xy 375.404635 -223.52108) (xy 375.392858 -223.473296)
			(xy 375.388898 -223.424242) (xy 375.11863 -223.424242) (xy 375.11863 -224.234248) (xy 375.859052 -224.234248)
			(xy 375.863012 -224.185194) (xy 375.874789 -224.13741) (xy 375.89408 -224.092134) (xy 375.920383 -224.050538)
			(xy 375.953018 -224.013701) (xy 375.991139 -223.982576) (xy 376.03376 -223.957969) (xy 376.079776 -223.940517)
			(xy 376.127995 -223.930673) (xy 376.17717 -223.928692) (xy 376.226025 -223.934624) (xy 376.273296 -223.948316)
			(xy 376.317758 -223.969414) (xy 376.358261 -223.99737) (xy 376.393754 -224.031462) (xy 376.423319 -224.070806)
			(xy 376.44619 -224.114383) (xy 376.461774 -224.161064) (xy 376.469669 -224.209641) (xy 376.470164 -224.234248)
			(xy 376.799106 -224.234248) (xy 376.803066 -224.185194) (xy 376.814843 -224.13741) (xy 376.834134 -224.092134)
			(xy 376.860437 -224.050538) (xy 376.893072 -224.013701) (xy 376.931193 -223.982576) (xy 376.973814 -223.957969)
			(xy 377.01983 -223.940517) (xy 377.068049 -223.930673) (xy 377.117224 -223.928692) (xy 377.166079 -223.934624)
			(xy 377.21335 -223.948316) (xy 377.257812 -223.969414) (xy 377.298315 -223.99737) (xy 377.333808 -224.031462)
			(xy 377.363373 -224.070806) (xy 377.386244 -224.114383) (xy 377.401828 -224.161064) (xy 377.409723 -224.209641)
			(xy 377.410218 -224.234248) (xy 377.738906 -224.234248) (xy 377.742866 -224.185194) (xy 377.754643 -224.13741)
			(xy 377.773934 -224.092134) (xy 377.800237 -224.050538) (xy 377.832872 -224.013701) (xy 377.870993 -223.982576)
			(xy 377.913614 -223.957969) (xy 377.95963 -223.940517) (xy 378.007849 -223.930673) (xy 378.057024 -223.928692)
			(xy 378.105879 -223.934624) (xy 378.15315 -223.948316) (xy 378.197612 -223.969414) (xy 378.238115 -223.99737)
			(xy 378.273608 -224.031462) (xy 378.303173 -224.070806) (xy 378.326044 -224.114383) (xy 378.341628 -224.161064)
			(xy 378.349523 -224.209641) (xy 378.350018 -224.234248) (xy 378.67896 -224.234248) (xy 378.68292 -224.185194)
			(xy 378.694697 -224.13741) (xy 378.713988 -224.092134) (xy 378.740291 -224.050538) (xy 378.772926 -224.013701)
			(xy 378.811047 -223.982576) (xy 378.853668 -223.957969) (xy 378.899684 -223.940517) (xy 378.947903 -223.930673)
			(xy 378.997078 -223.928692) (xy 379.045933 -223.934624) (xy 379.093204 -223.948316) (xy 379.137666 -223.969414)
			(xy 379.178169 -223.99737) (xy 379.213662 -224.031462) (xy 379.243227 -224.070806) (xy 379.266098 -224.114383)
			(xy 379.281682 -224.161064) (xy 379.289577 -224.209641) (xy 379.290072 -224.234248) (xy 379.619014 -224.234248)
			(xy 379.622974 -224.185194) (xy 379.634751 -224.13741) (xy 379.654042 -224.092134) (xy 379.680345 -224.050538)
			(xy 379.71298 -224.013701) (xy 379.751101 -223.982576) (xy 379.793722 -223.957969) (xy 379.839738 -223.940517)
			(xy 379.887957 -223.930673) (xy 379.937132 -223.928692) (xy 379.985987 -223.934624) (xy 380.033258 -223.948316)
			(xy 380.07772 -223.969414) (xy 380.118223 -223.99737) (xy 380.153716 -224.031462) (xy 380.183281 -224.070806)
			(xy 380.206152 -224.114383) (xy 380.221736 -224.161064) (xy 380.229631 -224.209641) (xy 380.230126 -224.234248)
			(xy 380.559068 -224.234248) (xy 380.563028 -224.185194) (xy 380.574805 -224.13741) (xy 380.594096 -224.092134)
			(xy 380.620399 -224.050538) (xy 380.653034 -224.013701) (xy 380.691155 -223.982576) (xy 380.733776 -223.957969)
			(xy 380.779792 -223.940517) (xy 380.828011 -223.930673) (xy 380.877186 -223.928692) (xy 380.926041 -223.934624)
			(xy 380.973312 -223.948316) (xy 381.017774 -223.969414) (xy 381.058277 -223.99737) (xy 381.09377 -224.031462)
			(xy 381.123335 -224.070806) (xy 381.146206 -224.114383) (xy 381.16179 -224.161064) (xy 381.169685 -224.209641)
			(xy 381.17018 -224.234248) (xy 381.169685 -224.258855) (xy 381.16179 -224.307432) (xy 381.146206 -224.354113)
			(xy 381.123335 -224.39769) (xy 381.09377 -224.437034) (xy 381.058277 -224.471126) (xy 381.017774 -224.499082)
			(xy 380.973312 -224.52018) (xy 380.926041 -224.533872) (xy 380.877186 -224.539804) (xy 380.828011 -224.537823)
			(xy 380.779792 -224.527979) (xy 380.733776 -224.510527) (xy 380.691155 -224.48592) (xy 380.653034 -224.454795)
			(xy 380.620399 -224.417958) (xy 380.594096 -224.376362) (xy 380.574805 -224.331086) (xy 380.563028 -224.283302)
			(xy 380.559068 -224.234248) (xy 380.230126 -224.234248) (xy 380.229631 -224.258855) (xy 380.221736 -224.307432)
			(xy 380.206152 -224.354113) (xy 380.183281 -224.39769) (xy 380.153716 -224.437034) (xy 380.118223 -224.471126)
			(xy 380.07772 -224.499082) (xy 380.033258 -224.52018) (xy 379.985987 -224.533872) (xy 379.937132 -224.539804)
			(xy 379.887957 -224.537823) (xy 379.839738 -224.527979) (xy 379.793722 -224.510527) (xy 379.751101 -224.48592)
			(xy 379.71298 -224.454795) (xy 379.680345 -224.417958) (xy 379.654042 -224.376362) (xy 379.634751 -224.331086)
			(xy 379.622974 -224.283302) (xy 379.619014 -224.234248) (xy 379.290072 -224.234248) (xy 379.289577 -224.258855)
			(xy 379.281682 -224.307432) (xy 379.266098 -224.354113) (xy 379.243227 -224.39769) (xy 379.213662 -224.437034)
			(xy 379.178169 -224.471126) (xy 379.137666 -224.499082) (xy 379.093204 -224.52018) (xy 379.045933 -224.533872)
			(xy 378.997078 -224.539804) (xy 378.947903 -224.537823) (xy 378.899684 -224.527979) (xy 378.853668 -224.510527)
			(xy 378.811047 -224.48592) (xy 378.772926 -224.454795) (xy 378.740291 -224.417958) (xy 378.713988 -224.376362)
			(xy 378.694697 -224.331086) (xy 378.68292 -224.283302) (xy 378.67896 -224.234248) (xy 378.350018 -224.234248)
			(xy 378.349523 -224.258855) (xy 378.341628 -224.307432) (xy 378.326044 -224.354113) (xy 378.303173 -224.39769)
			(xy 378.273608 -224.437034) (xy 378.238115 -224.471126) (xy 378.197612 -224.499082) (xy 378.15315 -224.52018)
			(xy 378.105879 -224.533872) (xy 378.057024 -224.539804) (xy 378.007849 -224.537823) (xy 377.95963 -224.527979)
			(xy 377.913614 -224.510527) (xy 377.870993 -224.48592) (xy 377.832872 -224.454795) (xy 377.800237 -224.417958)
			(xy 377.773934 -224.376362) (xy 377.754643 -224.331086) (xy 377.742866 -224.283302) (xy 377.738906 -224.234248)
			(xy 377.410218 -224.234248) (xy 377.409723 -224.258855) (xy 377.401828 -224.307432) (xy 377.386244 -224.354113)
			(xy 377.363373 -224.39769) (xy 377.333808 -224.437034) (xy 377.298315 -224.471126) (xy 377.257812 -224.499082)
			(xy 377.21335 -224.52018) (xy 377.166079 -224.533872) (xy 377.117224 -224.539804) (xy 377.068049 -224.537823)
			(xy 377.01983 -224.527979) (xy 376.973814 -224.510527) (xy 376.931193 -224.48592) (xy 376.893072 -224.454795)
			(xy 376.860437 -224.417958) (xy 376.834134 -224.376362) (xy 376.814843 -224.331086) (xy 376.803066 -224.283302)
			(xy 376.799106 -224.234248) (xy 376.470164 -224.234248) (xy 376.469669 -224.258855) (xy 376.461774 -224.307432)
			(xy 376.44619 -224.354113) (xy 376.423319 -224.39769) (xy 376.393754 -224.437034) (xy 376.358261 -224.471126)
			(xy 376.317758 -224.499082) (xy 376.273296 -224.52018) (xy 376.226025 -224.533872) (xy 376.17717 -224.539804)
			(xy 376.127995 -224.537823) (xy 376.079776 -224.527979) (xy 376.03376 -224.510527) (xy 375.991139 -224.48592)
			(xy 375.953018 -224.454795) (xy 375.920383 -224.417958) (xy 375.89408 -224.376362) (xy 375.874789 -224.331086)
			(xy 375.863012 -224.283302) (xy 375.859052 -224.234248) (xy 375.11863 -224.234248) (xy 375.11863 -225.044254)
			(xy 375.388898 -225.044254) (xy 375.392858 -224.9952) (xy 375.404635 -224.947416) (xy 375.423926 -224.90214)
			(xy 375.450229 -224.860544) (xy 375.482864 -224.823707) (xy 375.520985 -224.792582) (xy 375.563606 -224.767975)
			(xy 375.609622 -224.750523) (xy 375.657841 -224.740679) (xy 375.707016 -224.738698) (xy 375.755871 -224.74463)
			(xy 375.803142 -224.758322) (xy 375.847604 -224.77942) (xy 375.888107 -224.807376) (xy 375.9236 -224.841468)
			(xy 375.953165 -224.880812) (xy 375.976036 -224.924389) (xy 375.99162 -224.97107) (xy 375.999515 -225.019647)
			(xy 376.00001 -225.044254) (xy 376.328952 -225.044254) (xy 376.332912 -224.9952) (xy 376.344689 -224.947416)
			(xy 376.36398 -224.90214) (xy 376.390283 -224.860544) (xy 376.422918 -224.823707) (xy 376.461039 -224.792582)
			(xy 376.50366 -224.767975) (xy 376.549676 -224.750523) (xy 376.597895 -224.740679) (xy 376.64707 -224.738698)
			(xy 376.695925 -224.74463) (xy 376.743196 -224.758322) (xy 376.787658 -224.77942) (xy 376.828161 -224.807376)
			(xy 376.863654 -224.841468) (xy 376.893219 -224.880812) (xy 376.91609 -224.924389) (xy 376.931674 -224.97107)
			(xy 376.939569 -225.019647) (xy 376.940064 -225.044254) (xy 377.258575 -225.044254) (xy 377.26267 -224.993526)
			(xy 377.274849 -224.944112) (xy 377.294797 -224.897292) (xy 377.321998 -224.854278) (xy 377.355746 -224.816184)
			(xy 377.395168 -224.783997) (xy 377.439242 -224.758551) (xy 377.486828 -224.740504) (xy 377.536692 -224.730324)
			(xy 377.587544 -224.728275) (xy 377.638065 -224.734409) (xy 377.686949 -224.748569) (xy 377.732928 -224.770386)
			(xy 377.774812 -224.799296) (xy 377.811516 -224.834551) (xy 377.842089 -224.875237) (xy 377.86574 -224.9203)
			(xy 377.881856 -224.968574) (xy 377.89002 -225.018808) (xy 377.890532 -225.044254) (xy 378.20906 -225.044254)
			(xy 378.21302 -224.9952) (xy 378.224797 -224.947416) (xy 378.244088 -224.90214) (xy 378.270391 -224.860544)
			(xy 378.303026 -224.823707) (xy 378.341147 -224.792582) (xy 378.383768 -224.767975) (xy 378.429784 -224.750523)
			(xy 378.478003 -224.740679) (xy 378.527178 -224.738698) (xy 378.576033 -224.74463) (xy 378.623304 -224.758322)
			(xy 378.667766 -224.77942) (xy 378.708269 -224.807376) (xy 378.743762 -224.841468) (xy 378.773327 -224.880812)
			(xy 378.796198 -224.924389) (xy 378.811782 -224.97107) (xy 378.819677 -225.019647) (xy 378.820172 -225.044254)
			(xy 379.149114 -225.044254) (xy 379.153074 -224.9952) (xy 379.164851 -224.947416) (xy 379.184142 -224.90214)
			(xy 379.210445 -224.860544) (xy 379.24308 -224.823707) (xy 379.281201 -224.792582) (xy 379.323822 -224.767975)
			(xy 379.369838 -224.750523) (xy 379.418057 -224.740679) (xy 379.467232 -224.738698) (xy 379.516087 -224.74463)
			(xy 379.563358 -224.758322) (xy 379.60782 -224.77942) (xy 379.648323 -224.807376) (xy 379.683816 -224.841468)
			(xy 379.713381 -224.880812) (xy 379.736252 -224.924389) (xy 379.751836 -224.97107) (xy 379.759731 -225.019647)
			(xy 379.760226 -225.044254) (xy 380.078483 -225.044254) (xy 380.082578 -224.993526) (xy 380.094757 -224.944112)
			(xy 380.114705 -224.897292) (xy 380.141906 -224.854278) (xy 380.175654 -224.816184) (xy 380.215076 -224.783997)
			(xy 380.25915 -224.758551) (xy 380.306736 -224.740504) (xy 380.3566 -224.730324) (xy 380.407452 -224.728275)
			(xy 380.457973 -224.734409) (xy 380.506857 -224.748569) (xy 380.552836 -224.770386) (xy 380.59472 -224.799296)
			(xy 380.631424 -224.834551) (xy 380.661997 -224.875237) (xy 380.685648 -224.9203) (xy 380.701764 -224.968574)
			(xy 380.709928 -225.018808) (xy 380.71044 -225.044254) (xy 380.709928 -225.0697) (xy 380.701764 -225.119934)
			(xy 380.685648 -225.168208) (xy 380.661997 -225.213271) (xy 380.631424 -225.253957) (xy 380.59472 -225.289212)
			(xy 380.552836 -225.318122) (xy 380.506857 -225.339939) (xy 380.457973 -225.354099) (xy 380.407452 -225.360233)
			(xy 380.3566 -225.358184) (xy 380.306736 -225.348004) (xy 380.25915 -225.329957) (xy 380.215076 -225.304511)
			(xy 380.175654 -225.272324) (xy 380.141906 -225.23423) (xy 380.114705 -225.191216) (xy 380.094757 -225.144396)
			(xy 380.082578 -225.094982) (xy 380.078483 -225.044254) (xy 379.760226 -225.044254) (xy 379.759731 -225.068861)
			(xy 379.751836 -225.117438) (xy 379.736252 -225.164119) (xy 379.713381 -225.207696) (xy 379.683816 -225.24704)
			(xy 379.648323 -225.281132) (xy 379.60782 -225.309088) (xy 379.563358 -225.330186) (xy 379.516087 -225.343878)
			(xy 379.467232 -225.34981) (xy 379.418057 -225.347829) (xy 379.369838 -225.337985) (xy 379.323822 -225.320533)
			(xy 379.281201 -225.295926) (xy 379.24308 -225.264801) (xy 379.210445 -225.227964) (xy 379.184142 -225.186368)
			(xy 379.164851 -225.141092) (xy 379.153074 -225.093308) (xy 379.149114 -225.044254) (xy 378.820172 -225.044254)
			(xy 378.819677 -225.068861) (xy 378.811782 -225.117438) (xy 378.796198 -225.164119) (xy 378.773327 -225.207696)
			(xy 378.743762 -225.24704) (xy 378.708269 -225.281132) (xy 378.667766 -225.309088) (xy 378.623304 -225.330186)
			(xy 378.576033 -225.343878) (xy 378.527178 -225.34981) (xy 378.478003 -225.347829) (xy 378.429784 -225.337985)
			(xy 378.383768 -225.320533) (xy 378.341147 -225.295926) (xy 378.303026 -225.264801) (xy 378.270391 -225.227964)
			(xy 378.244088 -225.186368) (xy 378.224797 -225.141092) (xy 378.21302 -225.093308) (xy 378.20906 -225.044254)
			(xy 377.890532 -225.044254) (xy 377.89002 -225.0697) (xy 377.881856 -225.119934) (xy 377.86574 -225.168208)
			(xy 377.842089 -225.213271) (xy 377.811516 -225.253957) (xy 377.774812 -225.289212) (xy 377.732928 -225.318122)
			(xy 377.686949 -225.339939) (xy 377.638065 -225.354099) (xy 377.587544 -225.360233) (xy 377.536692 -225.358184)
			(xy 377.486828 -225.348004) (xy 377.439242 -225.329957) (xy 377.395168 -225.304511) (xy 377.355746 -225.272324)
			(xy 377.321998 -225.23423) (xy 377.294797 -225.191216) (xy 377.274849 -225.144396) (xy 377.26267 -225.094982)
			(xy 377.258575 -225.044254) (xy 376.940064 -225.044254) (xy 376.939569 -225.068861) (xy 376.931674 -225.117438)
			(xy 376.91609 -225.164119) (xy 376.893219 -225.207696) (xy 376.863654 -225.24704) (xy 376.828161 -225.281132)
			(xy 376.787658 -225.309088) (xy 376.743196 -225.330186) (xy 376.695925 -225.343878) (xy 376.64707 -225.34981)
			(xy 376.597895 -225.347829) (xy 376.549676 -225.337985) (xy 376.50366 -225.320533) (xy 376.461039 -225.295926)
			(xy 376.422918 -225.264801) (xy 376.390283 -225.227964) (xy 376.36398 -225.186368) (xy 376.344689 -225.141092)
			(xy 376.332912 -225.093308) (xy 376.328952 -225.044254) (xy 376.00001 -225.044254) (xy 375.999515 -225.068861)
			(xy 375.99162 -225.117438) (xy 375.976036 -225.164119) (xy 375.953165 -225.207696) (xy 375.9236 -225.24704)
			(xy 375.888107 -225.281132) (xy 375.847604 -225.309088) (xy 375.803142 -225.330186) (xy 375.755871 -225.343878)
			(xy 375.707016 -225.34981) (xy 375.657841 -225.347829) (xy 375.609622 -225.337985) (xy 375.563606 -225.320533)
			(xy 375.520985 -225.295926) (xy 375.482864 -225.264801) (xy 375.450229 -225.227964) (xy 375.423926 -225.186368)
			(xy 375.404635 -225.141092) (xy 375.392858 -225.093308) (xy 375.388898 -225.044254) (xy 375.11863 -225.044254)
			(xy 375.11863 -225.447352) (xy 375.119063 -225.457417) (xy 375.126794 -225.476005) (xy 375.133616 -225.48342)
			(xy 375.184924 -225.53422) (xy 375.192336 -225.540898) (xy 375.210772 -225.548469) (xy 375.220738 -225.548952)
			(xy 375.224802 -225.548952) (xy 375.250061 -225.549474) (xy 375.299889 -225.557789) (xy 375.347668 -225.574192)
			(xy 375.392097 -225.598236) (xy 375.431962 -225.629264) (xy 375.466176 -225.666431) (xy 375.493806 -225.708722)
			(xy 375.514098 -225.754984) (xy 375.526499 -225.803955) (xy 375.530668 -225.85426) (xy 375.848621 -225.85426)
			(xy 375.852716 -225.803532) (xy 375.864895 -225.754118) (xy 375.884843 -225.707298) (xy 375.912044 -225.664284)
			(xy 375.945792 -225.62619) (xy 375.985214 -225.594003) (xy 376.029288 -225.568557) (xy 376.076874 -225.55051)
			(xy 376.126738 -225.54033) (xy 376.17759 -225.538281) (xy 376.228111 -225.544415) (xy 376.276995 -225.558575)
			(xy 376.322974 -225.580392) (xy 376.364858 -225.609302) (xy 376.401562 -225.644557) (xy 376.432135 -225.685243)
			(xy 376.455786 -225.730306) (xy 376.471902 -225.77858) (xy 376.480066 -225.828814) (xy 376.480578 -225.85426)
			(xy 376.788675 -225.85426) (xy 376.79277 -225.803532) (xy 376.804949 -225.754118) (xy 376.824897 -225.707298)
			(xy 376.852098 -225.664284) (xy 376.885846 -225.62619) (xy 376.925268 -225.594003) (xy 376.969342 -225.568557)
			(xy 377.016928 -225.55051) (xy 377.066792 -225.54033) (xy 377.117644 -225.538281) (xy 377.168165 -225.544415)
			(xy 377.217049 -225.558575) (xy 377.263028 -225.580392) (xy 377.304912 -225.609302) (xy 377.341616 -225.644557)
			(xy 377.372189 -225.685243) (xy 377.39584 -225.730306) (xy 377.411956 -225.77858) (xy 377.42012 -225.828814)
			(xy 377.420632 -225.85426) (xy 377.738906 -225.85426) (xy 377.742866 -225.805206) (xy 377.754643 -225.757422)
			(xy 377.773934 -225.712146) (xy 377.800237 -225.67055) (xy 377.832872 -225.633713) (xy 377.870993 -225.602588)
			(xy 377.913614 -225.577981) (xy 377.95963 -225.560529) (xy 378.007849 -225.550685) (xy 378.057024 -225.548704)
			(xy 378.105879 -225.554636) (xy 378.15315 -225.568328) (xy 378.197612 -225.589426) (xy 378.238115 -225.617382)
			(xy 378.273608 -225.651474) (xy 378.303173 -225.690818) (xy 378.326044 -225.734395) (xy 378.341628 -225.781076)
			(xy 378.349523 -225.829653) (xy 378.350018 -225.85426) (xy 378.668529 -225.85426) (xy 378.672624 -225.803532)
			(xy 378.684803 -225.754118) (xy 378.704751 -225.707298) (xy 378.731952 -225.664284) (xy 378.7657 -225.62619)
			(xy 378.805122 -225.594003) (xy 378.849196 -225.568557) (xy 378.896782 -225.55051) (xy 378.946646 -225.54033)
			(xy 378.997498 -225.538281) (xy 379.048019 -225.544415) (xy 379.096903 -225.558575) (xy 379.142882 -225.580392)
			(xy 379.184766 -225.609302) (xy 379.22147 -225.644557) (xy 379.252043 -225.685243) (xy 379.275694 -225.730306)
			(xy 379.29181 -225.77858) (xy 379.299974 -225.828814) (xy 379.300486 -225.85426) (xy 379.619014 -225.85426)
			(xy 379.622974 -225.805206) (xy 379.634751 -225.757422) (xy 379.654042 -225.712146) (xy 379.680345 -225.67055)
			(xy 379.71298 -225.633713) (xy 379.751101 -225.602588) (xy 379.793722 -225.577981) (xy 379.839738 -225.560529)
			(xy 379.887957 -225.550685) (xy 379.937132 -225.548704) (xy 379.985987 -225.554636) (xy 380.033258 -225.568328)
			(xy 380.07772 -225.589426) (xy 380.118223 -225.617382) (xy 380.153716 -225.651474) (xy 380.183281 -225.690818)
			(xy 380.206152 -225.734395) (xy 380.221736 -225.781076) (xy 380.229631 -225.829653) (xy 380.230126 -225.85426)
			(xy 380.548637 -225.85426) (xy 380.552732 -225.803532) (xy 380.564911 -225.754118) (xy 380.584859 -225.707298)
			(xy 380.61206 -225.664284) (xy 380.645808 -225.62619) (xy 380.68523 -225.594003) (xy 380.729304 -225.568557)
			(xy 380.77689 -225.55051) (xy 380.826754 -225.54033) (xy 380.877606 -225.538281) (xy 380.928127 -225.544415)
			(xy 380.977011 -225.558575) (xy 381.02299 -225.580392) (xy 381.064874 -225.609302) (xy 381.101578 -225.644557)
			(xy 381.132151 -225.685243) (xy 381.155802 -225.730306) (xy 381.171918 -225.77858) (xy 381.180082 -225.828814)
			(xy 381.180594 -225.85426) (xy 381.180082 -225.879706) (xy 381.171918 -225.92994) (xy 381.155802 -225.978214)
			(xy 381.132151 -226.023277) (xy 381.101578 -226.063963) (xy 381.064874 -226.099218) (xy 381.02299 -226.128128)
			(xy 380.977011 -226.149945) (xy 380.928127 -226.164105) (xy 380.877606 -226.170239) (xy 380.826754 -226.16819)
			(xy 380.77689 -226.15801) (xy 380.729304 -226.139963) (xy 380.68523 -226.114517) (xy 380.645808 -226.08233)
			(xy 380.61206 -226.044236) (xy 380.584859 -226.001222) (xy 380.564911 -225.954402) (xy 380.552732 -225.904988)
			(xy 380.548637 -225.85426) (xy 380.230126 -225.85426) (xy 380.229631 -225.878867) (xy 380.221736 -225.927444)
			(xy 380.206152 -225.974125) (xy 380.183281 -226.017702) (xy 380.153716 -226.057046) (xy 380.118223 -226.091138)
			(xy 380.07772 -226.119094) (xy 380.033258 -226.140192) (xy 379.985987 -226.153884) (xy 379.937132 -226.159816)
			(xy 379.887957 -226.157835) (xy 379.839738 -226.147991) (xy 379.793722 -226.130539) (xy 379.751101 -226.105932)
			(xy 379.71298 -226.074807) (xy 379.680345 -226.03797) (xy 379.654042 -225.996374) (xy 379.634751 -225.951098)
			(xy 379.622974 -225.903314) (xy 379.619014 -225.85426) (xy 379.300486 -225.85426) (xy 379.299974 -225.879706)
			(xy 379.29181 -225.92994) (xy 379.275694 -225.978214) (xy 379.252043 -226.023277) (xy 379.22147 -226.063963)
			(xy 379.184766 -226.099218) (xy 379.142882 -226.128128) (xy 379.096903 -226.149945) (xy 379.048019 -226.164105)
			(xy 378.997498 -226.170239) (xy 378.946646 -226.16819) (xy 378.896782 -226.15801) (xy 378.849196 -226.139963)
			(xy 378.805122 -226.114517) (xy 378.7657 -226.08233) (xy 378.731952 -226.044236) (xy 378.704751 -226.001222)
			(xy 378.684803 -225.954402) (xy 378.672624 -225.904988) (xy 378.668529 -225.85426) (xy 378.350018 -225.85426)
			(xy 378.349523 -225.878867) (xy 378.341628 -225.927444) (xy 378.326044 -225.974125) (xy 378.303173 -226.017702)
			(xy 378.273608 -226.057046) (xy 378.238115 -226.091138) (xy 378.197612 -226.119094) (xy 378.15315 -226.140192)
			(xy 378.105879 -226.153884) (xy 378.057024 -226.159816) (xy 378.007849 -226.157835) (xy 377.95963 -226.147991)
			(xy 377.913614 -226.130539) (xy 377.870993 -226.105932) (xy 377.832872 -226.074807) (xy 377.800237 -226.03797)
			(xy 377.773934 -225.996374) (xy 377.754643 -225.951098) (xy 377.742866 -225.903314) (xy 377.738906 -225.85426)
			(xy 377.420632 -225.85426) (xy 377.42012 -225.879706) (xy 377.411956 -225.92994) (xy 377.39584 -225.978214)
			(xy 377.372189 -226.023277) (xy 377.341616 -226.063963) (xy 377.304912 -226.099218) (xy 377.263028 -226.128128)
			(xy 377.217049 -226.149945) (xy 377.168165 -226.164105) (xy 377.117644 -226.170239) (xy 377.066792 -226.16819)
			(xy 377.016928 -226.15801) (xy 376.969342 -226.139963) (xy 376.925268 -226.114517) (xy 376.885846 -226.08233)
			(xy 376.852098 -226.044236) (xy 376.824897 -226.001222) (xy 376.804949 -225.954402) (xy 376.79277 -225.904988)
			(xy 376.788675 -225.85426) (xy 376.480578 -225.85426) (xy 376.480066 -225.879706) (xy 376.471902 -225.92994)
			(xy 376.455786 -225.978214) (xy 376.432135 -226.023277) (xy 376.401562 -226.063963) (xy 376.364858 -226.099218)
			(xy 376.322974 -226.128128) (xy 376.276995 -226.149945) (xy 376.228111 -226.164105) (xy 376.17759 -226.170239)
			(xy 376.126738 -226.16819) (xy 376.076874 -226.15801) (xy 376.029288 -226.139963) (xy 375.985214 -226.114517)
			(xy 375.945792 -226.08233) (xy 375.912044 -226.044236) (xy 375.884843 -226.001222) (xy 375.864895 -225.954402)
			(xy 375.852716 -225.904988) (xy 375.848621 -225.85426) (xy 375.530668 -225.85426) (xy 375.530671 -225.8543)
			(xy 375.526499 -225.904645) (xy 375.514098 -225.953616) (xy 375.493806 -225.999878) (xy 375.466176 -226.042169)
			(xy 375.431962 -226.079336) (xy 375.392097 -226.110364) (xy 375.347668 -226.134408) (xy 375.299889 -226.150811)
			(xy 375.250061 -226.159126) (xy 375.224802 -226.159568) (xy 375.220738 -226.159568) (xy 375.210775 -226.160053)
			(xy 375.192346 -226.167636) (xy 375.184924 -226.1743) (xy 375.133616 -226.2251) (xy 375.126768 -226.232498)
			(xy 375.119031 -226.251096) (xy 375.11863 -226.261168) (xy 375.11863 -226.664266) (xy 375.378467 -226.664266)
			(xy 375.382562 -226.613538) (xy 375.394741 -226.564124) (xy 375.414689 -226.517304) (xy 375.44189 -226.47429)
			(xy 375.475638 -226.436196) (xy 375.51506 -226.404009) (xy 375.559134 -226.378563) (xy 375.60672 -226.360516)
			(xy 375.656584 -226.350336) (xy 375.707436 -226.348287) (xy 375.757957 -226.354421) (xy 375.806841 -226.368581)
			(xy 375.85282 -226.390398) (xy 375.894704 -226.419308) (xy 375.931408 -226.454563) (xy 375.961981 -226.495249)
			(xy 375.985632 -226.540312) (xy 376.001748 -226.588586) (xy 376.009912 -226.63882) (xy 376.010424 -226.664266)
			(xy 376.328952 -226.664266) (xy 376.332912 -226.615212) (xy 376.344689 -226.567428) (xy 376.36398 -226.522152)
			(xy 376.390283 -226.480556) (xy 376.422918 -226.443719) (xy 376.461039 -226.412594) (xy 376.50366 -226.387987)
			(xy 376.549676 -226.370535) (xy 376.597895 -226.360691) (xy 376.64707 -226.35871) (xy 376.695925 -226.364642)
			(xy 376.743196 -226.378334) (xy 376.787658 -226.399432) (xy 376.828161 -226.427388) (xy 376.863654 -226.46148)
			(xy 376.893219 -226.500824) (xy 376.91609 -226.544401) (xy 376.931674 -226.591082) (xy 376.939569 -226.639659)
			(xy 376.940064 -226.664266) (xy 377.258575 -226.664266) (xy 377.26267 -226.613538) (xy 377.274849 -226.564124)
			(xy 377.294797 -226.517304) (xy 377.321998 -226.47429) (xy 377.355746 -226.436196) (xy 377.395168 -226.404009)
			(xy 377.439242 -226.378563) (xy 377.486828 -226.360516) (xy 377.536692 -226.350336) (xy 377.587544 -226.348287)
			(xy 377.638065 -226.354421) (xy 377.686949 -226.368581) (xy 377.732928 -226.390398) (xy 377.774812 -226.419308)
			(xy 377.811516 -226.454563) (xy 377.842089 -226.495249) (xy 377.86574 -226.540312) (xy 377.881856 -226.588586)
			(xy 377.89002 -226.63882) (xy 377.890532 -226.664266) (xy 378.20906 -226.664266) (xy 378.21302 -226.615212)
			(xy 378.224797 -226.567428) (xy 378.244088 -226.522152) (xy 378.270391 -226.480556) (xy 378.303026 -226.443719)
			(xy 378.341147 -226.412594) (xy 378.383768 -226.387987) (xy 378.429784 -226.370535) (xy 378.478003 -226.360691)
			(xy 378.527178 -226.35871) (xy 378.576033 -226.364642) (xy 378.623304 -226.378334) (xy 378.667766 -226.399432)
			(xy 378.708269 -226.427388) (xy 378.743762 -226.46148) (xy 378.773327 -226.500824) (xy 378.796198 -226.544401)
			(xy 378.811782 -226.591082) (xy 378.819677 -226.639659) (xy 378.820172 -226.664266) (xy 379.138683 -226.664266)
			(xy 379.142778 -226.613538) (xy 379.154957 -226.564124) (xy 379.174905 -226.517304) (xy 379.202106 -226.47429)
			(xy 379.235854 -226.436196) (xy 379.275276 -226.404009) (xy 379.31935 -226.378563) (xy 379.366936 -226.360516)
			(xy 379.4168 -226.350336) (xy 379.467652 -226.348287) (xy 379.518173 -226.354421) (xy 379.567057 -226.368581)
			(xy 379.613036 -226.390398) (xy 379.65492 -226.419308) (xy 379.691624 -226.454563) (xy 379.722197 -226.495249)
			(xy 379.745848 -226.540312) (xy 379.761964 -226.588586) (xy 379.770128 -226.63882) (xy 379.77064 -226.664266)
			(xy 380.078483 -226.664266) (xy 380.082578 -226.613538) (xy 380.094757 -226.564124) (xy 380.114705 -226.517304)
			(xy 380.141906 -226.47429) (xy 380.175654 -226.436196) (xy 380.215076 -226.404009) (xy 380.25915 -226.378563)
			(xy 380.306736 -226.360516) (xy 380.3566 -226.350336) (xy 380.407452 -226.348287) (xy 380.457973 -226.354421)
			(xy 380.506857 -226.368581) (xy 380.552836 -226.390398) (xy 380.59472 -226.419308) (xy 380.631424 -226.454563)
			(xy 380.661997 -226.495249) (xy 380.685648 -226.540312) (xy 380.701764 -226.588586) (xy 380.709928 -226.63882)
			(xy 380.71044 -226.664266) (xy 380.709928 -226.689712) (xy 380.701764 -226.739946) (xy 380.685648 -226.78822)
			(xy 380.661997 -226.833283) (xy 380.631424 -226.873969) (xy 380.59472 -226.909224) (xy 380.552836 -226.938134)
			(xy 380.506857 -226.959951) (xy 380.457973 -226.974111) (xy 380.407452 -226.980245) (xy 380.3566 -226.978196)
			(xy 380.306736 -226.968016) (xy 380.25915 -226.949969) (xy 380.215076 -226.924523) (xy 380.175654 -226.892336)
			(xy 380.141906 -226.854242) (xy 380.114705 -226.811228) (xy 380.094757 -226.764408) (xy 380.082578 -226.714994)
			(xy 380.078483 -226.664266) (xy 379.77064 -226.664266) (xy 379.770128 -226.689712) (xy 379.761964 -226.739946)
			(xy 379.745848 -226.78822) (xy 379.722197 -226.833283) (xy 379.691624 -226.873969) (xy 379.65492 -226.909224)
			(xy 379.613036 -226.938134) (xy 379.567057 -226.959951) (xy 379.518173 -226.974111) (xy 379.467652 -226.980245)
			(xy 379.4168 -226.978196) (xy 379.366936 -226.968016) (xy 379.31935 -226.949969) (xy 379.275276 -226.924523)
			(xy 379.235854 -226.892336) (xy 379.202106 -226.854242) (xy 379.174905 -226.811228) (xy 379.154957 -226.764408)
			(xy 379.142778 -226.714994) (xy 379.138683 -226.664266) (xy 378.820172 -226.664266) (xy 378.819677 -226.688873)
			(xy 378.811782 -226.73745) (xy 378.796198 -226.784131) (xy 378.773327 -226.827708) (xy 378.743762 -226.867052)
			(xy 378.708269 -226.901144) (xy 378.667766 -226.9291) (xy 378.623304 -226.950198) (xy 378.576033 -226.96389)
			(xy 378.527178 -226.969822) (xy 378.478003 -226.967841) (xy 378.429784 -226.957997) (xy 378.383768 -226.940545)
			(xy 378.341147 -226.915938) (xy 378.303026 -226.884813) (xy 378.270391 -226.847976) (xy 378.244088 -226.80638)
			(xy 378.224797 -226.761104) (xy 378.21302 -226.71332) (xy 378.20906 -226.664266) (xy 377.890532 -226.664266)
			(xy 377.89002 -226.689712) (xy 377.881856 -226.739946) (xy 377.86574 -226.78822) (xy 377.842089 -226.833283)
			(xy 377.811516 -226.873969) (xy 377.774812 -226.909224) (xy 377.732928 -226.938134) (xy 377.686949 -226.959951)
			(xy 377.638065 -226.974111) (xy 377.587544 -226.980245) (xy 377.536692 -226.978196) (xy 377.486828 -226.968016)
			(xy 377.439242 -226.949969) (xy 377.395168 -226.924523) (xy 377.355746 -226.892336) (xy 377.321998 -226.854242)
			(xy 377.294797 -226.811228) (xy 377.274849 -226.764408) (xy 377.26267 -226.714994) (xy 377.258575 -226.664266)
			(xy 376.940064 -226.664266) (xy 376.939569 -226.688873) (xy 376.931674 -226.73745) (xy 376.91609 -226.784131)
			(xy 376.893219 -226.827708) (xy 376.863654 -226.867052) (xy 376.828161 -226.901144) (xy 376.787658 -226.9291)
			(xy 376.743196 -226.950198) (xy 376.695925 -226.96389) (xy 376.64707 -226.969822) (xy 376.597895 -226.967841)
			(xy 376.549676 -226.957997) (xy 376.50366 -226.940545) (xy 376.461039 -226.915938) (xy 376.422918 -226.884813)
			(xy 376.390283 -226.847976) (xy 376.36398 -226.80638) (xy 376.344689 -226.761104) (xy 376.332912 -226.71332)
			(xy 376.328952 -226.664266) (xy 376.010424 -226.664266) (xy 376.009912 -226.689712) (xy 376.001748 -226.739946)
			(xy 375.985632 -226.78822) (xy 375.961981 -226.833283) (xy 375.931408 -226.873969) (xy 375.894704 -226.909224)
			(xy 375.85282 -226.938134) (xy 375.806841 -226.959951) (xy 375.757957 -226.974111) (xy 375.707436 -226.980245)
			(xy 375.656584 -226.978196) (xy 375.60672 -226.968016) (xy 375.559134 -226.949969) (xy 375.51506 -226.924523)
			(xy 375.475638 -226.892336) (xy 375.44189 -226.854242) (xy 375.414689 -226.811228) (xy 375.394741 -226.764408)
			(xy 375.382562 -226.714994) (xy 375.378467 -226.664266) (xy 375.11863 -226.664266) (xy 375.11863 -227.067364)
			(xy 375.119065 -227.077428) (xy 375.1268 -227.096013) (xy 375.133616 -227.103432) (xy 375.184924 -227.154232)
			(xy 375.192336 -227.160909) (xy 375.210772 -227.168477) (xy 375.220738 -227.168964) (xy 375.224802 -227.168964)
			(xy 375.25006 -227.169486) (xy 375.299886 -227.177801) (xy 375.347664 -227.194203) (xy 375.39209 -227.218246)
			(xy 375.431953 -227.249273) (xy 375.466166 -227.286438) (xy 375.493795 -227.328728) (xy 375.514087 -227.374988)
			(xy 375.526488 -227.423957) (xy 375.530657 -227.474272) (xy 375.848621 -227.474272) (xy 375.852716 -227.423544)
			(xy 375.864895 -227.37413) (xy 375.884843 -227.32731) (xy 375.912044 -227.284296) (xy 375.945792 -227.246202)
			(xy 375.985214 -227.214015) (xy 376.029288 -227.188569) (xy 376.076874 -227.170522) (xy 376.126738 -227.160342)
			(xy 376.17759 -227.158293) (xy 376.228111 -227.164427) (xy 376.276995 -227.178587) (xy 376.322974 -227.200404)
			(xy 376.364858 -227.229314) (xy 376.401562 -227.264569) (xy 376.432135 -227.305255) (xy 376.455786 -227.350318)
			(xy 376.471902 -227.398592) (xy 376.480066 -227.448826) (xy 376.480578 -227.474272) (xy 376.788675 -227.474272)
			(xy 376.79277 -227.423544) (xy 376.804949 -227.37413) (xy 376.824897 -227.32731) (xy 376.852098 -227.284296)
			(xy 376.885846 -227.246202) (xy 376.925268 -227.214015) (xy 376.969342 -227.188569) (xy 377.016928 -227.170522)
			(xy 377.066792 -227.160342) (xy 377.117644 -227.158293) (xy 377.168165 -227.164427) (xy 377.217049 -227.178587)
			(xy 377.263028 -227.200404) (xy 377.304912 -227.229314) (xy 377.341616 -227.264569) (xy 377.372189 -227.305255)
			(xy 377.39584 -227.350318) (xy 377.411956 -227.398592) (xy 377.42012 -227.448826) (xy 377.420632 -227.474272)
			(xy 378.668529 -227.474272) (xy 378.672624 -227.423544) (xy 378.684803 -227.37413) (xy 378.704751 -227.32731)
			(xy 378.731952 -227.284296) (xy 378.7657 -227.246202) (xy 378.805122 -227.214015) (xy 378.849196 -227.188569)
			(xy 378.896782 -227.170522) (xy 378.946646 -227.160342) (xy 378.997498 -227.158293) (xy 379.048019 -227.164427)
			(xy 379.096903 -227.178587) (xy 379.142882 -227.200404) (xy 379.184766 -227.229314) (xy 379.22147 -227.264569)
			(xy 379.252043 -227.305255) (xy 379.275694 -227.350318) (xy 379.29181 -227.398592) (xy 379.299974 -227.448826)
			(xy 379.300486 -227.474272) (xy 379.619014 -227.474272) (xy 379.622974 -227.425218) (xy 379.634751 -227.377434)
			(xy 379.654042 -227.332158) (xy 379.680345 -227.290562) (xy 379.71298 -227.253725) (xy 379.751101 -227.2226)
			(xy 379.793722 -227.197993) (xy 379.839738 -227.180541) (xy 379.887957 -227.170697) (xy 379.937132 -227.168716)
			(xy 379.985987 -227.174648) (xy 380.033258 -227.18834) (xy 380.07772 -227.209438) (xy 380.118223 -227.237394)
			(xy 380.153716 -227.271486) (xy 380.183281 -227.31083) (xy 380.206152 -227.354407) (xy 380.221736 -227.401088)
			(xy 380.229631 -227.449665) (xy 380.230126 -227.474272) (xy 380.548637 -227.474272) (xy 380.552732 -227.423544)
			(xy 380.564911 -227.37413) (xy 380.584859 -227.32731) (xy 380.61206 -227.284296) (xy 380.645808 -227.246202)
			(xy 380.68523 -227.214015) (xy 380.729304 -227.188569) (xy 380.77689 -227.170522) (xy 380.826754 -227.160342)
			(xy 380.877606 -227.158293) (xy 380.928127 -227.164427) (xy 380.977011 -227.178587) (xy 381.02299 -227.200404)
			(xy 381.064874 -227.229314) (xy 381.101578 -227.264569) (xy 381.132151 -227.305255) (xy 381.155802 -227.350318)
			(xy 381.171918 -227.398592) (xy 381.180082 -227.448826) (xy 381.180594 -227.474272) (xy 381.180082 -227.499718)
			(xy 381.171918 -227.549952) (xy 381.155802 -227.598226) (xy 381.132151 -227.643289) (xy 381.101578 -227.683975)
			(xy 381.064874 -227.71923) (xy 381.02299 -227.74814) (xy 380.977011 -227.769957) (xy 380.928127 -227.784117)
			(xy 380.877606 -227.790251) (xy 380.826754 -227.788202) (xy 380.77689 -227.778022) (xy 380.729304 -227.759975)
			(xy 380.68523 -227.734529) (xy 380.645808 -227.702342) (xy 380.61206 -227.664248) (xy 380.584859 -227.621234)
			(xy 380.564911 -227.574414) (xy 380.552732 -227.525) (xy 380.548637 -227.474272) (xy 380.230126 -227.474272)
			(xy 380.229631 -227.498879) (xy 380.221736 -227.547456) (xy 380.206152 -227.594137) (xy 380.183281 -227.637714)
			(xy 380.153716 -227.677058) (xy 380.118223 -227.71115) (xy 380.07772 -227.739106) (xy 380.033258 -227.760204)
			(xy 379.985987 -227.773896) (xy 379.937132 -227.779828) (xy 379.887957 -227.777847) (xy 379.839738 -227.768003)
			(xy 379.793722 -227.750551) (xy 379.751101 -227.725944) (xy 379.71298 -227.694819) (xy 379.680345 -227.657982)
			(xy 379.654042 -227.616386) (xy 379.634751 -227.57111) (xy 379.622974 -227.523326) (xy 379.619014 -227.474272)
			(xy 379.300486 -227.474272) (xy 379.299974 -227.499718) (xy 379.29181 -227.549952) (xy 379.275694 -227.598226)
			(xy 379.252043 -227.643289) (xy 379.22147 -227.683975) (xy 379.184766 -227.71923) (xy 379.142882 -227.74814)
			(xy 379.096903 -227.769957) (xy 379.048019 -227.784117) (xy 378.997498 -227.790251) (xy 378.946646 -227.788202)
			(xy 378.896782 -227.778022) (xy 378.849196 -227.759975) (xy 378.805122 -227.734529) (xy 378.7657 -227.702342)
			(xy 378.731952 -227.664248) (xy 378.704751 -227.621234) (xy 378.684803 -227.574414) (xy 378.672624 -227.525)
			(xy 378.668529 -227.474272) (xy 377.420632 -227.474272) (xy 377.42012 -227.499718) (xy 377.411956 -227.549952)
			(xy 377.39584 -227.598226) (xy 377.372189 -227.643289) (xy 377.341616 -227.683975) (xy 377.304912 -227.71923)
			(xy 377.263028 -227.74814) (xy 377.217049 -227.769957) (xy 377.168165 -227.784117) (xy 377.117644 -227.790251)
			(xy 377.066792 -227.788202) (xy 377.016928 -227.778022) (xy 376.969342 -227.759975) (xy 376.925268 -227.734529)
			(xy 376.885846 -227.702342) (xy 376.852098 -227.664248) (xy 376.824897 -227.621234) (xy 376.804949 -227.574414)
			(xy 376.79277 -227.525) (xy 376.788675 -227.474272) (xy 376.480578 -227.474272) (xy 376.480066 -227.499718)
			(xy 376.471902 -227.549952) (xy 376.455786 -227.598226) (xy 376.432135 -227.643289) (xy 376.401562 -227.683975)
			(xy 376.364858 -227.71923) (xy 376.322974 -227.74814) (xy 376.276995 -227.769957) (xy 376.228111 -227.784117)
			(xy 376.17759 -227.790251) (xy 376.126738 -227.788202) (xy 376.076874 -227.778022) (xy 376.029288 -227.759975)
			(xy 375.985214 -227.734529) (xy 375.945792 -227.702342) (xy 375.912044 -227.664248) (xy 375.884843 -227.621234)
			(xy 375.864895 -227.574414) (xy 375.852716 -227.525) (xy 375.848621 -227.474272) (xy 375.530657 -227.474272)
			(xy 375.530659 -227.4743) (xy 375.526488 -227.524643) (xy 375.514087 -227.573612) (xy 375.493795 -227.619872)
			(xy 375.466166 -227.662162) (xy 375.431953 -227.699327) (xy 375.39209 -227.730354) (xy 375.347664 -227.754397)
			(xy 375.299886 -227.770799) (xy 375.25006 -227.779114) (xy 375.224802 -227.77958) (xy 375.220738 -227.77958)
			(xy 375.210775 -227.780065) (xy 375.192348 -227.787649) (xy 375.184924 -227.794312) (xy 375.133616 -227.845112)
			(xy 375.12677 -227.852511) (xy 375.119037 -227.871109) (xy 375.11863 -227.88118) (xy 375.11863 -228.284278)
			(xy 375.378467 -228.284278) (xy 375.382562 -228.23355) (xy 375.394741 -228.184136) (xy 375.414689 -228.137316)
			(xy 375.44189 -228.094302) (xy 375.475638 -228.056208) (xy 375.51506 -228.024021) (xy 375.559134 -227.998575)
			(xy 375.60672 -227.980528) (xy 375.656584 -227.970348) (xy 375.707436 -227.968299) (xy 375.757957 -227.974433)
			(xy 375.806841 -227.988593) (xy 375.85282 -228.01041) (xy 375.894704 -228.03932) (xy 375.931408 -228.074575)
			(xy 375.961981 -228.115261) (xy 375.985632 -228.160324) (xy 376.001748 -228.208598) (xy 376.009912 -228.258832)
			(xy 376.010424 -228.284278) (xy 376.328952 -228.284278) (xy 376.332912 -228.235224) (xy 376.344689 -228.18744)
			(xy 376.36398 -228.142164) (xy 376.390283 -228.100568) (xy 376.422918 -228.063731) (xy 376.461039 -228.032606)
			(xy 376.50366 -228.007999) (xy 376.549676 -227.990547) (xy 376.597895 -227.980703) (xy 376.64707 -227.978722)
			(xy 376.695925 -227.984654) (xy 376.743196 -227.998346) (xy 376.787658 -228.019444) (xy 376.828161 -228.0474)
			(xy 376.863654 -228.081492) (xy 376.893219 -228.120836) (xy 376.91609 -228.164413) (xy 376.931674 -228.211094)
			(xy 376.939569 -228.259671) (xy 376.940064 -228.284278) (xy 377.258575 -228.284278) (xy 377.26267 -228.23355)
			(xy 377.274849 -228.184136) (xy 377.294797 -228.137316) (xy 377.321998 -228.094302) (xy 377.355746 -228.056208)
			(xy 377.395168 -228.024021) (xy 377.439242 -227.998575) (xy 377.486828 -227.980528) (xy 377.536692 -227.970348)
			(xy 377.587544 -227.968299) (xy 377.638065 -227.974433) (xy 377.686949 -227.988593) (xy 377.732928 -228.01041)
			(xy 377.774812 -228.03932) (xy 377.811516 -228.074575) (xy 377.842089 -228.115261) (xy 377.86574 -228.160324)
			(xy 377.881856 -228.208598) (xy 377.89002 -228.258832) (xy 377.890532 -228.284278) (xy 378.20906 -228.284278)
			(xy 378.21302 -228.235224) (xy 378.224797 -228.18744) (xy 378.244088 -228.142164) (xy 378.270391 -228.100568)
			(xy 378.303026 -228.063731) (xy 378.341147 -228.032606) (xy 378.383768 -228.007999) (xy 378.429784 -227.990547)
			(xy 378.478003 -227.980703) (xy 378.527178 -227.978722) (xy 378.576033 -227.984654) (xy 378.623304 -227.998346)
			(xy 378.667766 -228.019444) (xy 378.708269 -228.0474) (xy 378.743762 -228.081492) (xy 378.773327 -228.120836)
			(xy 378.796198 -228.164413) (xy 378.811782 -228.211094) (xy 378.819677 -228.259671) (xy 378.820172 -228.284278)
			(xy 379.138683 -228.284278) (xy 379.142778 -228.23355) (xy 379.154957 -228.184136) (xy 379.174905 -228.137316)
			(xy 379.202106 -228.094302) (xy 379.235854 -228.056208) (xy 379.275276 -228.024021) (xy 379.31935 -227.998575)
			(xy 379.366936 -227.980528) (xy 379.4168 -227.970348) (xy 379.467652 -227.968299) (xy 379.518173 -227.974433)
			(xy 379.567057 -227.988593) (xy 379.613036 -228.01041) (xy 379.65492 -228.03932) (xy 379.691624 -228.074575)
			(xy 379.722197 -228.115261) (xy 379.745848 -228.160324) (xy 379.761964 -228.208598) (xy 379.770128 -228.258832)
			(xy 379.77064 -228.284278) (xy 380.078483 -228.284278) (xy 380.082578 -228.23355) (xy 380.094757 -228.184136)
			(xy 380.114705 -228.137316) (xy 380.141906 -228.094302) (xy 380.175654 -228.056208) (xy 380.215076 -228.024021)
			(xy 380.25915 -227.998575) (xy 380.306736 -227.980528) (xy 380.3566 -227.970348) (xy 380.407452 -227.968299)
			(xy 380.457973 -227.974433) (xy 380.506857 -227.988593) (xy 380.552836 -228.01041) (xy 380.59472 -228.03932)
			(xy 380.631424 -228.074575) (xy 380.661997 -228.115261) (xy 380.685648 -228.160324) (xy 380.701764 -228.208598)
			(xy 380.709928 -228.258832) (xy 380.71044 -228.284278) (xy 380.709928 -228.309724) (xy 380.701764 -228.359958)
			(xy 380.685648 -228.408232) (xy 380.661997 -228.453295) (xy 380.631424 -228.493981) (xy 380.59472 -228.529236)
			(xy 380.552836 -228.558146) (xy 380.506857 -228.579963) (xy 380.457973 -228.594123) (xy 380.407452 -228.600257)
			(xy 380.3566 -228.598208) (xy 380.306736 -228.588028) (xy 380.25915 -228.569981) (xy 380.215076 -228.544535)
			(xy 380.175654 -228.512348) (xy 380.141906 -228.474254) (xy 380.114705 -228.43124) (xy 380.094757 -228.38442)
			(xy 380.082578 -228.335006) (xy 380.078483 -228.284278) (xy 379.77064 -228.284278) (xy 379.770128 -228.309724)
			(xy 379.761964 -228.359958) (xy 379.745848 -228.408232) (xy 379.722197 -228.453295) (xy 379.691624 -228.493981)
			(xy 379.65492 -228.529236) (xy 379.613036 -228.558146) (xy 379.567057 -228.579963) (xy 379.518173 -228.594123)
			(xy 379.467652 -228.600257) (xy 379.4168 -228.598208) (xy 379.366936 -228.588028) (xy 379.31935 -228.569981)
			(xy 379.275276 -228.544535) (xy 379.235854 -228.512348) (xy 379.202106 -228.474254) (xy 379.174905 -228.43124)
			(xy 379.154957 -228.38442) (xy 379.142778 -228.335006) (xy 379.138683 -228.284278) (xy 378.820172 -228.284278)
			(xy 378.819677 -228.308885) (xy 378.811782 -228.357462) (xy 378.796198 -228.404143) (xy 378.773327 -228.44772)
			(xy 378.743762 -228.487064) (xy 378.708269 -228.521156) (xy 378.667766 -228.549112) (xy 378.623304 -228.57021)
			(xy 378.576033 -228.583902) (xy 378.527178 -228.589834) (xy 378.478003 -228.587853) (xy 378.429784 -228.578009)
			(xy 378.383768 -228.560557) (xy 378.341147 -228.53595) (xy 378.303026 -228.504825) (xy 378.270391 -228.467988)
			(xy 378.244088 -228.426392) (xy 378.224797 -228.381116) (xy 378.21302 -228.333332) (xy 378.20906 -228.284278)
			(xy 377.890532 -228.284278) (xy 377.89002 -228.309724) (xy 377.881856 -228.359958) (xy 377.86574 -228.408232)
			(xy 377.842089 -228.453295) (xy 377.811516 -228.493981) (xy 377.774812 -228.529236) (xy 377.732928 -228.558146)
			(xy 377.686949 -228.579963) (xy 377.638065 -228.594123) (xy 377.587544 -228.600257) (xy 377.536692 -228.598208)
			(xy 377.486828 -228.588028) (xy 377.439242 -228.569981) (xy 377.395168 -228.544535) (xy 377.355746 -228.512348)
			(xy 377.321998 -228.474254) (xy 377.294797 -228.43124) (xy 377.274849 -228.38442) (xy 377.26267 -228.335006)
			(xy 377.258575 -228.284278) (xy 376.940064 -228.284278) (xy 376.939569 -228.308885) (xy 376.931674 -228.357462)
			(xy 376.91609 -228.404143) (xy 376.893219 -228.44772) (xy 376.863654 -228.487064) (xy 376.828161 -228.521156)
			(xy 376.787658 -228.549112) (xy 376.743196 -228.57021) (xy 376.695925 -228.583902) (xy 376.64707 -228.589834)
			(xy 376.597895 -228.587853) (xy 376.549676 -228.578009) (xy 376.50366 -228.560557) (xy 376.461039 -228.53595)
			(xy 376.422918 -228.504825) (xy 376.390283 -228.467988) (xy 376.36398 -228.426392) (xy 376.344689 -228.381116)
			(xy 376.332912 -228.333332) (xy 376.328952 -228.284278) (xy 376.010424 -228.284278) (xy 376.009912 -228.309724)
			(xy 376.001748 -228.359958) (xy 375.985632 -228.408232) (xy 375.961981 -228.453295) (xy 375.931408 -228.493981)
			(xy 375.894704 -228.529236) (xy 375.85282 -228.558146) (xy 375.806841 -228.579963) (xy 375.757957 -228.594123)
			(xy 375.707436 -228.600257) (xy 375.656584 -228.598208) (xy 375.60672 -228.588028) (xy 375.559134 -228.569981)
			(xy 375.51506 -228.544535) (xy 375.475638 -228.512348) (xy 375.44189 -228.474254) (xy 375.414689 -228.43124)
			(xy 375.394741 -228.38442) (xy 375.382562 -228.335006) (xy 375.378467 -228.284278) (xy 375.11863 -228.284278)
			(xy 375.11863 -229.094284) (xy 375.848621 -229.094284) (xy 375.852716 -229.043556) (xy 375.864895 -228.994142)
			(xy 375.884843 -228.947322) (xy 375.912044 -228.904308) (xy 375.945792 -228.866214) (xy 375.985214 -228.834027)
			(xy 376.029288 -228.808581) (xy 376.076874 -228.790534) (xy 376.126738 -228.780354) (xy 376.17759 -228.778305)
			(xy 376.228111 -228.784439) (xy 376.276995 -228.798599) (xy 376.322974 -228.820416) (xy 376.364858 -228.849326)
			(xy 376.401562 -228.884581) (xy 376.432135 -228.925267) (xy 376.455786 -228.97033) (xy 376.471902 -229.018604)
			(xy 376.480066 -229.068838) (xy 376.480578 -229.094284) (xy 376.788675 -229.094284) (xy 376.79277 -229.043556)
			(xy 376.804949 -228.994142) (xy 376.824897 -228.947322) (xy 376.852098 -228.904308) (xy 376.885846 -228.866214)
			(xy 376.925268 -228.834027) (xy 376.969342 -228.808581) (xy 377.016928 -228.790534) (xy 377.066792 -228.780354)
			(xy 377.117644 -228.778305) (xy 377.168165 -228.784439) (xy 377.217049 -228.798599) (xy 377.263028 -228.820416)
			(xy 377.304912 -228.849326) (xy 377.341616 -228.884581) (xy 377.372189 -228.925267) (xy 377.39584 -228.97033)
			(xy 377.411956 -229.018604) (xy 377.42012 -229.068838) (xy 377.420632 -229.094284) (xy 377.738906 -229.094284)
			(xy 377.742866 -229.04523) (xy 377.754643 -228.997446) (xy 377.773934 -228.95217) (xy 377.800237 -228.910574)
			(xy 377.832872 -228.873737) (xy 377.870993 -228.842612) (xy 377.913614 -228.818005) (xy 377.95963 -228.800553)
			(xy 378.007849 -228.790709) (xy 378.057024 -228.788728) (xy 378.105879 -228.79466) (xy 378.15315 -228.808352)
			(xy 378.197612 -228.82945) (xy 378.238115 -228.857406) (xy 378.273608 -228.891498) (xy 378.303173 -228.930842)
			(xy 378.326044 -228.974419) (xy 378.341628 -229.0211) (xy 378.349523 -229.069677) (xy 378.350018 -229.094284)
			(xy 378.668529 -229.094284) (xy 378.672624 -229.043556) (xy 378.684803 -228.994142) (xy 378.704751 -228.947322)
			(xy 378.731952 -228.904308) (xy 378.7657 -228.866214) (xy 378.805122 -228.834027) (xy 378.849196 -228.808581)
			(xy 378.896782 -228.790534) (xy 378.946646 -228.780354) (xy 378.997498 -228.778305) (xy 379.048019 -228.784439)
			(xy 379.096903 -228.798599) (xy 379.142882 -228.820416) (xy 379.184766 -228.849326) (xy 379.22147 -228.884581)
			(xy 379.252043 -228.925267) (xy 379.275694 -228.97033) (xy 379.29181 -229.018604) (xy 379.299974 -229.068838)
			(xy 379.300486 -229.094284) (xy 379.619014 -229.094284) (xy 379.622974 -229.04523) (xy 379.634751 -228.997446)
			(xy 379.654042 -228.95217) (xy 379.680345 -228.910574) (xy 379.71298 -228.873737) (xy 379.751101 -228.842612)
			(xy 379.793722 -228.818005) (xy 379.839738 -228.800553) (xy 379.887957 -228.790709) (xy 379.937132 -228.788728)
			(xy 379.985987 -228.79466) (xy 380.033258 -228.808352) (xy 380.07772 -228.82945) (xy 380.118223 -228.857406)
			(xy 380.153716 -228.891498) (xy 380.183281 -228.930842) (xy 380.206152 -228.974419) (xy 380.221736 -229.0211)
			(xy 380.229631 -229.069677) (xy 380.230126 -229.094284) (xy 380.548637 -229.094284) (xy 380.552732 -229.043556)
			(xy 380.564911 -228.994142) (xy 380.584859 -228.947322) (xy 380.61206 -228.904308) (xy 380.645808 -228.866214)
			(xy 380.68523 -228.834027) (xy 380.729304 -228.808581) (xy 380.77689 -228.790534) (xy 380.826754 -228.780354)
			(xy 380.877606 -228.778305) (xy 380.928127 -228.784439) (xy 380.977011 -228.798599) (xy 381.02299 -228.820416)
			(xy 381.064874 -228.849326) (xy 381.101578 -228.884581) (xy 381.132151 -228.925267) (xy 381.155802 -228.97033)
			(xy 381.171918 -229.018604) (xy 381.180082 -229.068838) (xy 381.180594 -229.094284) (xy 381.180082 -229.11973)
			(xy 381.171918 -229.169964) (xy 381.155802 -229.218238) (xy 381.132151 -229.263301) (xy 381.101578 -229.303987)
			(xy 381.064874 -229.339242) (xy 381.02299 -229.368152) (xy 380.977011 -229.389969) (xy 380.928127 -229.404129)
			(xy 380.877606 -229.410263) (xy 380.826754 -229.408214) (xy 380.77689 -229.398034) (xy 380.729304 -229.379987)
			(xy 380.68523 -229.354541) (xy 380.645808 -229.322354) (xy 380.61206 -229.28426) (xy 380.584859 -229.241246)
			(xy 380.564911 -229.194426) (xy 380.552732 -229.145012) (xy 380.548637 -229.094284) (xy 380.230126 -229.094284)
			(xy 380.229631 -229.118891) (xy 380.221736 -229.167468) (xy 380.206152 -229.214149) (xy 380.183281 -229.257726)
			(xy 380.153716 -229.29707) (xy 380.118223 -229.331162) (xy 380.07772 -229.359118) (xy 380.033258 -229.380216)
			(xy 379.985987 -229.393908) (xy 379.937132 -229.39984) (xy 379.887957 -229.397859) (xy 379.839738 -229.388015)
			(xy 379.793722 -229.370563) (xy 379.751101 -229.345956) (xy 379.71298 -229.314831) (xy 379.680345 -229.277994)
			(xy 379.654042 -229.236398) (xy 379.634751 -229.191122) (xy 379.622974 -229.143338) (xy 379.619014 -229.094284)
			(xy 379.300486 -229.094284) (xy 379.299974 -229.11973) (xy 379.29181 -229.169964) (xy 379.275694 -229.218238)
			(xy 379.252043 -229.263301) (xy 379.22147 -229.303987) (xy 379.184766 -229.339242) (xy 379.142882 -229.368152)
			(xy 379.096903 -229.389969) (xy 379.048019 -229.404129) (xy 378.997498 -229.410263) (xy 378.946646 -229.408214)
			(xy 378.896782 -229.398034) (xy 378.849196 -229.379987) (xy 378.805122 -229.354541) (xy 378.7657 -229.322354)
			(xy 378.731952 -229.28426) (xy 378.704751 -229.241246) (xy 378.684803 -229.194426) (xy 378.672624 -229.145012)
			(xy 378.668529 -229.094284) (xy 378.350018 -229.094284) (xy 378.349523 -229.118891) (xy 378.341628 -229.167468)
			(xy 378.326044 -229.214149) (xy 378.303173 -229.257726) (xy 378.273608 -229.29707) (xy 378.238115 -229.331162)
			(xy 378.197612 -229.359118) (xy 378.15315 -229.380216) (xy 378.105879 -229.393908) (xy 378.057024 -229.39984)
			(xy 378.007849 -229.397859) (xy 377.95963 -229.388015) (xy 377.913614 -229.370563) (xy 377.870993 -229.345956)
			(xy 377.832872 -229.314831) (xy 377.800237 -229.277994) (xy 377.773934 -229.236398) (xy 377.754643 -229.191122)
			(xy 377.742866 -229.143338) (xy 377.738906 -229.094284) (xy 377.420632 -229.094284) (xy 377.42012 -229.11973)
			(xy 377.411956 -229.169964) (xy 377.39584 -229.218238) (xy 377.372189 -229.263301) (xy 377.341616 -229.303987)
			(xy 377.304912 -229.339242) (xy 377.263028 -229.368152) (xy 377.217049 -229.389969) (xy 377.168165 -229.404129)
			(xy 377.117644 -229.410263) (xy 377.066792 -229.408214) (xy 377.016928 -229.398034) (xy 376.969342 -229.379987)
			(xy 376.925268 -229.354541) (xy 376.885846 -229.322354) (xy 376.852098 -229.28426) (xy 376.824897 -229.241246)
			(xy 376.804949 -229.194426) (xy 376.79277 -229.145012) (xy 376.788675 -229.094284) (xy 376.480578 -229.094284)
			(xy 376.480066 -229.11973) (xy 376.471902 -229.169964) (xy 376.455786 -229.218238) (xy 376.432135 -229.263301)
			(xy 376.401562 -229.303987) (xy 376.364858 -229.339242) (xy 376.322974 -229.368152) (xy 376.276995 -229.389969)
			(xy 376.228111 -229.404129) (xy 376.17759 -229.410263) (xy 376.126738 -229.408214) (xy 376.076874 -229.398034)
			(xy 376.029288 -229.379987) (xy 375.985214 -229.354541) (xy 375.945792 -229.322354) (xy 375.912044 -229.28426)
			(xy 375.884843 -229.241246) (xy 375.864895 -229.194426) (xy 375.852716 -229.145012) (xy 375.848621 -229.094284)
			(xy 375.11863 -229.094284) (xy 375.11863 -229.904036) (xy 375.378467 -229.904036) (xy 375.382562 -229.853308)
			(xy 375.394741 -229.803894) (xy 375.414689 -229.757074) (xy 375.44189 -229.71406) (xy 375.475638 -229.675966)
			(xy 375.51506 -229.643779) (xy 375.559134 -229.618333) (xy 375.60672 -229.600286) (xy 375.656584 -229.590106)
			(xy 375.707436 -229.588057) (xy 375.757957 -229.594191) (xy 375.806841 -229.608351) (xy 375.85282 -229.630168)
			(xy 375.894704 -229.659078) (xy 375.931408 -229.694333) (xy 375.961981 -229.735019) (xy 375.985632 -229.780082)
			(xy 376.001748 -229.828356) (xy 376.009912 -229.87859) (xy 376.010424 -229.904036) (xy 376.328952 -229.904036)
			(xy 376.332912 -229.854982) (xy 376.344689 -229.807198) (xy 376.36398 -229.761922) (xy 376.390283 -229.720326)
			(xy 376.422918 -229.683489) (xy 376.461039 -229.652364) (xy 376.50366 -229.627757) (xy 376.549676 -229.610305)
			(xy 376.597895 -229.600461) (xy 376.64707 -229.59848) (xy 376.695925 -229.604412) (xy 376.743196 -229.618104)
			(xy 376.787658 -229.639202) (xy 376.828161 -229.667158) (xy 376.863654 -229.70125) (xy 376.893219 -229.740594)
			(xy 376.91609 -229.784171) (xy 376.931674 -229.830852) (xy 376.939569 -229.879429) (xy 376.940064 -229.904036)
			(xy 377.258575 -229.904036) (xy 377.26267 -229.853308) (xy 377.274849 -229.803894) (xy 377.294797 -229.757074)
			(xy 377.321998 -229.71406) (xy 377.355746 -229.675966) (xy 377.395168 -229.643779) (xy 377.439242 -229.618333)
			(xy 377.486828 -229.600286) (xy 377.536692 -229.590106) (xy 377.587544 -229.588057) (xy 377.638065 -229.594191)
			(xy 377.686949 -229.608351) (xy 377.732928 -229.630168) (xy 377.774812 -229.659078) (xy 377.811516 -229.694333)
			(xy 377.842089 -229.735019) (xy 377.86574 -229.780082) (xy 377.881856 -229.828356) (xy 377.89002 -229.87859)
			(xy 377.890532 -229.904036) (xy 379.138683 -229.904036) (xy 379.142778 -229.853308) (xy 379.154957 -229.803894)
			(xy 379.174905 -229.757074) (xy 379.202106 -229.71406) (xy 379.235854 -229.675966) (xy 379.275276 -229.643779)
			(xy 379.31935 -229.618333) (xy 379.366936 -229.600286) (xy 379.4168 -229.590106) (xy 379.467652 -229.588057)
			(xy 379.518173 -229.594191) (xy 379.567057 -229.608351) (xy 379.613036 -229.630168) (xy 379.65492 -229.659078)
			(xy 379.691624 -229.694333) (xy 379.722197 -229.735019) (xy 379.745848 -229.780082) (xy 379.761964 -229.828356)
			(xy 379.770128 -229.87859) (xy 379.77064 -229.904036) (xy 380.078483 -229.904036) (xy 380.082578 -229.853308)
			(xy 380.094757 -229.803894) (xy 380.114705 -229.757074) (xy 380.141906 -229.71406) (xy 380.175654 -229.675966)
			(xy 380.215076 -229.643779) (xy 380.25915 -229.618333) (xy 380.306736 -229.600286) (xy 380.3566 -229.590106)
			(xy 380.407452 -229.588057) (xy 380.457973 -229.594191) (xy 380.506857 -229.608351) (xy 380.552836 -229.630168)
			(xy 380.59472 -229.659078) (xy 380.631424 -229.694333) (xy 380.661997 -229.735019) (xy 380.685648 -229.780082)
			(xy 380.701764 -229.828356) (xy 380.709928 -229.87859) (xy 380.71044 -229.904036) (xy 380.709928 -229.929482)
			(xy 380.701764 -229.979716) (xy 380.685648 -230.02799) (xy 380.661997 -230.073053) (xy 380.631424 -230.113739)
			(xy 380.59472 -230.148994) (xy 380.552836 -230.177904) (xy 380.506857 -230.199721) (xy 380.457973 -230.213881)
			(xy 380.407452 -230.220015) (xy 380.3566 -230.217966) (xy 380.306736 -230.207786) (xy 380.25915 -230.189739)
			(xy 380.215076 -230.164293) (xy 380.175654 -230.132106) (xy 380.141906 -230.094012) (xy 380.114705 -230.050998)
			(xy 380.094757 -230.004178) (xy 380.082578 -229.954764) (xy 380.078483 -229.904036) (xy 379.77064 -229.904036)
			(xy 379.770128 -229.929482) (xy 379.761964 -229.979716) (xy 379.745848 -230.02799) (xy 379.722197 -230.073053)
			(xy 379.691624 -230.113739) (xy 379.65492 -230.148994) (xy 379.613036 -230.177904) (xy 379.567057 -230.199721)
			(xy 379.518173 -230.213881) (xy 379.467652 -230.220015) (xy 379.4168 -230.217966) (xy 379.366936 -230.207786)
			(xy 379.31935 -230.189739) (xy 379.275276 -230.164293) (xy 379.235854 -230.132106) (xy 379.202106 -230.094012)
			(xy 379.174905 -230.050998) (xy 379.154957 -230.004178) (xy 379.142778 -229.954764) (xy 379.138683 -229.904036)
			(xy 377.890532 -229.904036) (xy 377.89002 -229.929482) (xy 377.881856 -229.979716) (xy 377.86574 -230.02799)
			(xy 377.842089 -230.073053) (xy 377.811516 -230.113739) (xy 377.774812 -230.148994) (xy 377.732928 -230.177904)
			(xy 377.686949 -230.199721) (xy 377.638065 -230.213881) (xy 377.587544 -230.220015) (xy 377.536692 -230.217966)
			(xy 377.486828 -230.207786) (xy 377.439242 -230.189739) (xy 377.395168 -230.164293) (xy 377.355746 -230.132106)
			(xy 377.321998 -230.094012) (xy 377.294797 -230.050998) (xy 377.274849 -230.004178) (xy 377.26267 -229.954764)
			(xy 377.258575 -229.904036) (xy 376.940064 -229.904036) (xy 376.939569 -229.928643) (xy 376.931674 -229.97722)
			(xy 376.91609 -230.023901) (xy 376.893219 -230.067478) (xy 376.863654 -230.106822) (xy 376.828161 -230.140914)
			(xy 376.787658 -230.16887) (xy 376.743196 -230.189968) (xy 376.695925 -230.20366) (xy 376.64707 -230.209592)
			(xy 376.597895 -230.207611) (xy 376.549676 -230.197767) (xy 376.50366 -230.180315) (xy 376.461039 -230.155708)
			(xy 376.422918 -230.124583) (xy 376.390283 -230.087746) (xy 376.36398 -230.04615) (xy 376.344689 -230.000874)
			(xy 376.332912 -229.95309) (xy 376.328952 -229.904036) (xy 376.010424 -229.904036) (xy 376.009912 -229.929482)
			(xy 376.001748 -229.979716) (xy 375.985632 -230.02799) (xy 375.961981 -230.073053) (xy 375.931408 -230.113739)
			(xy 375.894704 -230.148994) (xy 375.85282 -230.177904) (xy 375.806841 -230.199721) (xy 375.757957 -230.213881)
			(xy 375.707436 -230.220015) (xy 375.656584 -230.217966) (xy 375.60672 -230.207786) (xy 375.559134 -230.189739)
			(xy 375.51506 -230.164293) (xy 375.475638 -230.132106) (xy 375.44189 -230.094012) (xy 375.414689 -230.050998)
			(xy 375.394741 -230.004178) (xy 375.382562 -229.954764) (xy 375.378467 -229.904036) (xy 375.11863 -229.904036)
			(xy 375.11863 -230.307388) (xy 375.119052 -230.317459) (xy 375.126766 -230.336063) (xy 375.133616 -230.343456)
			(xy 375.184924 -230.394256) (xy 375.192338 -230.40093) (xy 375.210773 -230.408495) (xy 375.220738 -230.408988)
			(xy 375.224802 -230.408988) (xy 375.250058 -230.40951) (xy 375.29988 -230.417824) (xy 375.347654 -230.434225)
			(xy 375.392077 -230.458266) (xy 375.431937 -230.489291) (xy 375.466147 -230.526453) (xy 375.493774 -230.568739)
			(xy 375.514064 -230.614996) (xy 375.526464 -230.663961) (xy 375.530635 -230.714296) (xy 375.848621 -230.714296)
			(xy 375.852716 -230.663568) (xy 375.864895 -230.614154) (xy 375.884843 -230.567334) (xy 375.912044 -230.52432)
			(xy 375.945792 -230.486226) (xy 375.985214 -230.454039) (xy 376.029288 -230.428593) (xy 376.076874 -230.410546)
			(xy 376.126738 -230.400366) (xy 376.17759 -230.398317) (xy 376.228111 -230.404451) (xy 376.276995 -230.418611)
			(xy 376.322974 -230.440428) (xy 376.364858 -230.469338) (xy 376.401562 -230.504593) (xy 376.432135 -230.545279)
			(xy 376.455786 -230.590342) (xy 376.471902 -230.638616) (xy 376.480066 -230.68885) (xy 376.480578 -230.714296)
			(xy 376.788675 -230.714296) (xy 376.79277 -230.663568) (xy 376.804949 -230.614154) (xy 376.824897 -230.567334)
			(xy 376.852098 -230.52432) (xy 376.885846 -230.486226) (xy 376.925268 -230.454039) (xy 376.969342 -230.428593)
			(xy 377.016928 -230.410546) (xy 377.066792 -230.400366) (xy 377.117644 -230.398317) (xy 377.168165 -230.404451)
			(xy 377.217049 -230.418611) (xy 377.263028 -230.440428) (xy 377.304912 -230.469338) (xy 377.341616 -230.504593)
			(xy 377.372189 -230.545279) (xy 377.39584 -230.590342) (xy 377.411956 -230.638616) (xy 377.42012 -230.68885)
			(xy 377.420632 -230.714296) (xy 377.738906 -230.714296) (xy 377.742866 -230.665242) (xy 377.754643 -230.617458)
			(xy 377.773934 -230.572182) (xy 377.800237 -230.530586) (xy 377.832872 -230.493749) (xy 377.870993 -230.462624)
			(xy 377.913614 -230.438017) (xy 377.95963 -230.420565) (xy 378.007849 -230.410721) (xy 378.057024 -230.40874)
			(xy 378.105879 -230.414672) (xy 378.15315 -230.428364) (xy 378.197612 -230.449462) (xy 378.238115 -230.477418)
			(xy 378.273608 -230.51151) (xy 378.303173 -230.550854) (xy 378.326044 -230.594431) (xy 378.341628 -230.641112)
			(xy 378.349523 -230.689689) (xy 378.350018 -230.714296) (xy 378.668529 -230.714296) (xy 378.672624 -230.663568)
			(xy 378.684803 -230.614154) (xy 378.704751 -230.567334) (xy 378.731952 -230.52432) (xy 378.7657 -230.486226)
			(xy 378.805122 -230.454039) (xy 378.849196 -230.428593) (xy 378.896782 -230.410546) (xy 378.946646 -230.400366)
			(xy 378.997498 -230.398317) (xy 379.048019 -230.404451) (xy 379.096903 -230.418611) (xy 379.142882 -230.440428)
			(xy 379.184766 -230.469338) (xy 379.22147 -230.504593) (xy 379.252043 -230.545279) (xy 379.275694 -230.590342)
			(xy 379.29181 -230.638616) (xy 379.299974 -230.68885) (xy 379.300486 -230.714296) (xy 379.619014 -230.714296)
			(xy 379.622974 -230.665242) (xy 379.634751 -230.617458) (xy 379.654042 -230.572182) (xy 379.680345 -230.530586)
			(xy 379.71298 -230.493749) (xy 379.751101 -230.462624) (xy 379.793722 -230.438017) (xy 379.839738 -230.420565)
			(xy 379.887957 -230.410721) (xy 379.937132 -230.40874) (xy 379.985987 -230.414672) (xy 380.033258 -230.428364)
			(xy 380.07772 -230.449462) (xy 380.118223 -230.477418) (xy 380.153716 -230.51151) (xy 380.183281 -230.550854)
			(xy 380.206152 -230.594431) (xy 380.221736 -230.641112) (xy 380.229631 -230.689689) (xy 380.230126 -230.714296)
			(xy 380.548637 -230.714296) (xy 380.552732 -230.663568) (xy 380.564911 -230.614154) (xy 380.584859 -230.567334)
			(xy 380.61206 -230.52432) (xy 380.645808 -230.486226) (xy 380.68523 -230.454039) (xy 380.729304 -230.428593)
			(xy 380.77689 -230.410546) (xy 380.826754 -230.400366) (xy 380.877606 -230.398317) (xy 380.928127 -230.404451)
			(xy 380.977011 -230.418611) (xy 381.02299 -230.440428) (xy 381.064874 -230.469338) (xy 381.101578 -230.504593)
			(xy 381.132151 -230.545279) (xy 381.155802 -230.590342) (xy 381.171918 -230.638616) (xy 381.180082 -230.68885)
			(xy 381.180594 -230.714296) (xy 381.180082 -230.739742) (xy 381.171918 -230.789976) (xy 381.155802 -230.83825)
			(xy 381.132151 -230.883313) (xy 381.101578 -230.923999) (xy 381.064874 -230.959254) (xy 381.02299 -230.988164)
			(xy 380.977011 -231.009981) (xy 380.928127 -231.024141) (xy 380.877606 -231.030275) (xy 380.826754 -231.028226)
			(xy 380.77689 -231.018046) (xy 380.729304 -230.999999) (xy 380.68523 -230.974553) (xy 380.645808 -230.942366)
			(xy 380.61206 -230.904272) (xy 380.584859 -230.861258) (xy 380.564911 -230.814438) (xy 380.552732 -230.765024)
			(xy 380.548637 -230.714296) (xy 380.230126 -230.714296) (xy 380.229631 -230.738903) (xy 380.221736 -230.78748)
			(xy 380.206152 -230.834161) (xy 380.183281 -230.877738) (xy 380.153716 -230.917082) (xy 380.118223 -230.951174)
			(xy 380.07772 -230.97913) (xy 380.033258 -231.000228) (xy 379.985987 -231.01392) (xy 379.937132 -231.019852)
			(xy 379.887957 -231.017871) (xy 379.839738 -231.008027) (xy 379.793722 -230.990575) (xy 379.751101 -230.965968)
			(xy 379.71298 -230.934843) (xy 379.680345 -230.898006) (xy 379.654042 -230.85641) (xy 379.634751 -230.811134)
			(xy 379.622974 -230.76335) (xy 379.619014 -230.714296) (xy 379.300486 -230.714296) (xy 379.299974 -230.739742)
			(xy 379.29181 -230.789976) (xy 379.275694 -230.83825) (xy 379.252043 -230.883313) (xy 379.22147 -230.923999)
			(xy 379.184766 -230.959254) (xy 379.142882 -230.988164) (xy 379.096903 -231.009981) (xy 379.048019 -231.024141)
			(xy 378.997498 -231.030275) (xy 378.946646 -231.028226) (xy 378.896782 -231.018046) (xy 378.849196 -230.999999)
			(xy 378.805122 -230.974553) (xy 378.7657 -230.942366) (xy 378.731952 -230.904272) (xy 378.704751 -230.861258)
			(xy 378.684803 -230.814438) (xy 378.672624 -230.765024) (xy 378.668529 -230.714296) (xy 378.350018 -230.714296)
			(xy 378.349523 -230.738903) (xy 378.341628 -230.78748) (xy 378.326044 -230.834161) (xy 378.303173 -230.877738)
			(xy 378.273608 -230.917082) (xy 378.238115 -230.951174) (xy 378.197612 -230.97913) (xy 378.15315 -231.000228)
			(xy 378.105879 -231.01392) (xy 378.057024 -231.019852) (xy 378.007849 -231.017871) (xy 377.95963 -231.008027)
			(xy 377.913614 -230.990575) (xy 377.870993 -230.965968) (xy 377.832872 -230.934843) (xy 377.800237 -230.898006)
			(xy 377.773934 -230.85641) (xy 377.754643 -230.811134) (xy 377.742866 -230.76335) (xy 377.738906 -230.714296)
			(xy 377.420632 -230.714296) (xy 377.42012 -230.739742) (xy 377.411956 -230.789976) (xy 377.39584 -230.83825)
			(xy 377.372189 -230.883313) (xy 377.341616 -230.923999) (xy 377.304912 -230.959254) (xy 377.263028 -230.988164)
			(xy 377.217049 -231.009981) (xy 377.168165 -231.024141) (xy 377.117644 -231.030275) (xy 377.066792 -231.028226)
			(xy 377.016928 -231.018046) (xy 376.969342 -230.999999) (xy 376.925268 -230.974553) (xy 376.885846 -230.942366)
			(xy 376.852098 -230.904272) (xy 376.824897 -230.861258) (xy 376.804949 -230.814438) (xy 376.79277 -230.765024)
			(xy 376.788675 -230.714296) (xy 376.480578 -230.714296) (xy 376.480066 -230.739742) (xy 376.471902 -230.789976)
			(xy 376.455786 -230.83825) (xy 376.432135 -230.883313) (xy 376.401562 -230.923999) (xy 376.364858 -230.959254)
			(xy 376.322974 -230.988164) (xy 376.276995 -231.009981) (xy 376.228111 -231.024141) (xy 376.17759 -231.030275)
			(xy 376.126738 -231.028226) (xy 376.076874 -231.018046) (xy 376.029288 -230.999999) (xy 375.985214 -230.974553)
			(xy 375.945792 -230.942366) (xy 375.912044 -230.904272) (xy 375.884843 -230.861258) (xy 375.864895 -230.814438)
			(xy 375.852716 -230.765024) (xy 375.848621 -230.714296) (xy 375.530635 -230.714296) (xy 375.530635 -230.7143)
			(xy 375.526464 -230.764639) (xy 375.514064 -230.813604) (xy 375.493774 -230.859861) (xy 375.466147 -230.902147)
			(xy 375.431937 -230.939309) (xy 375.392077 -230.970334) (xy 375.347654 -230.994375) (xy 375.29988 -231.010776)
			(xy 375.250058 -231.01909) (xy 375.224802 -231.019604) (xy 375.220738 -231.019604) (xy 375.210776 -231.02009)
			(xy 375.192351 -231.027677) (xy 375.184924 -231.034336) (xy 375.133616 -231.085136) (xy 375.126773 -231.092536)
			(xy 375.11905 -231.111134) (xy 375.11863 -231.121204) (xy 375.11863 -231.524048) (xy 375.378467 -231.524048)
			(xy 375.382562 -231.47332) (xy 375.394741 -231.423906) (xy 375.414689 -231.377086) (xy 375.44189 -231.334072)
			(xy 375.475638 -231.295978) (xy 375.51506 -231.263791) (xy 375.559134 -231.238345) (xy 375.60672 -231.220298)
			(xy 375.656584 -231.210118) (xy 375.707436 -231.208069) (xy 375.757957 -231.214203) (xy 375.806841 -231.228363)
			(xy 375.85282 -231.25018) (xy 375.894704 -231.27909) (xy 375.931408 -231.314345) (xy 375.961981 -231.355031)
			(xy 375.985632 -231.400094) (xy 376.001748 -231.448368) (xy 376.009912 -231.498602) (xy 376.010424 -231.524048)
			(xy 376.328952 -231.524048) (xy 376.332912 -231.474994) (xy 376.344689 -231.42721) (xy 376.36398 -231.381934)
			(xy 376.390283 -231.340338) (xy 376.422918 -231.303501) (xy 376.461039 -231.272376) (xy 376.50366 -231.247769)
			(xy 376.549676 -231.230317) (xy 376.597895 -231.220473) (xy 376.64707 -231.218492) (xy 376.695925 -231.224424)
			(xy 376.743196 -231.238116) (xy 376.787658 -231.259214) (xy 376.828161 -231.28717) (xy 376.863654 -231.321262)
			(xy 376.893219 -231.360606) (xy 376.91609 -231.404183) (xy 376.931674 -231.450864) (xy 376.939569 -231.499441)
			(xy 376.940064 -231.524048) (xy 377.258575 -231.524048) (xy 377.26267 -231.47332) (xy 377.274849 -231.423906)
			(xy 377.294797 -231.377086) (xy 377.321998 -231.334072) (xy 377.355746 -231.295978) (xy 377.395168 -231.263791)
			(xy 377.439242 -231.238345) (xy 377.486828 -231.220298) (xy 377.536692 -231.210118) (xy 377.587544 -231.208069)
			(xy 377.638065 -231.214203) (xy 377.686949 -231.228363) (xy 377.732928 -231.25018) (xy 377.774812 -231.27909)
			(xy 377.811516 -231.314345) (xy 377.842089 -231.355031) (xy 377.86574 -231.400094) (xy 377.881856 -231.448368)
			(xy 377.89002 -231.498602) (xy 377.890532 -231.524048) (xy 378.20906 -231.524048) (xy 378.21302 -231.474994)
			(xy 378.224797 -231.42721) (xy 378.244088 -231.381934) (xy 378.270391 -231.340338) (xy 378.303026 -231.303501)
			(xy 378.341147 -231.272376) (xy 378.383768 -231.247769) (xy 378.429784 -231.230317) (xy 378.478003 -231.220473)
			(xy 378.527178 -231.218492) (xy 378.576033 -231.224424) (xy 378.623304 -231.238116) (xy 378.667766 -231.259214)
			(xy 378.708269 -231.28717) (xy 378.743762 -231.321262) (xy 378.773327 -231.360606) (xy 378.796198 -231.404183)
			(xy 378.811782 -231.450864) (xy 378.819677 -231.499441) (xy 378.820172 -231.524048) (xy 379.138683 -231.524048)
			(xy 379.142778 -231.47332) (xy 379.154957 -231.423906) (xy 379.174905 -231.377086) (xy 379.202106 -231.334072)
			(xy 379.235854 -231.295978) (xy 379.275276 -231.263791) (xy 379.31935 -231.238345) (xy 379.366936 -231.220298)
			(xy 379.4168 -231.210118) (xy 379.467652 -231.208069) (xy 379.518173 -231.214203) (xy 379.567057 -231.228363)
			(xy 379.613036 -231.25018) (xy 379.65492 -231.27909) (xy 379.691624 -231.314345) (xy 379.722197 -231.355031)
			(xy 379.745848 -231.400094) (xy 379.761964 -231.448368) (xy 379.770128 -231.498602) (xy 379.77064 -231.524048)
			(xy 380.078483 -231.524048) (xy 380.082578 -231.47332) (xy 380.094757 -231.423906) (xy 380.114705 -231.377086)
			(xy 380.141906 -231.334072) (xy 380.175654 -231.295978) (xy 380.215076 -231.263791) (xy 380.25915 -231.238345)
			(xy 380.306736 -231.220298) (xy 380.3566 -231.210118) (xy 380.407452 -231.208069) (xy 380.457973 -231.214203)
			(xy 380.506857 -231.228363) (xy 380.552836 -231.25018) (xy 380.59472 -231.27909) (xy 380.631424 -231.314345)
			(xy 380.661997 -231.355031) (xy 380.685648 -231.400094) (xy 380.701764 -231.448368) (xy 380.709928 -231.498602)
			(xy 380.71044 -231.524048) (xy 380.709928 -231.549494) (xy 380.701764 -231.599728) (xy 380.685648 -231.648002)
			(xy 380.661997 -231.693065) (xy 380.631424 -231.733751) (xy 380.59472 -231.769006) (xy 380.552836 -231.797916)
			(xy 380.506857 -231.819733) (xy 380.457973 -231.833893) (xy 380.407452 -231.840027) (xy 380.3566 -231.837978)
			(xy 380.306736 -231.827798) (xy 380.25915 -231.809751) (xy 380.215076 -231.784305) (xy 380.175654 -231.752118)
			(xy 380.141906 -231.714024) (xy 380.114705 -231.67101) (xy 380.094757 -231.62419) (xy 380.082578 -231.574776)
			(xy 380.078483 -231.524048) (xy 379.77064 -231.524048) (xy 379.770128 -231.549494) (xy 379.761964 -231.599728)
			(xy 379.745848 -231.648002) (xy 379.722197 -231.693065) (xy 379.691624 -231.733751) (xy 379.65492 -231.769006)
			(xy 379.613036 -231.797916) (xy 379.567057 -231.819733) (xy 379.518173 -231.833893) (xy 379.467652 -231.840027)
			(xy 379.4168 -231.837978) (xy 379.366936 -231.827798) (xy 379.31935 -231.809751) (xy 379.275276 -231.784305)
			(xy 379.235854 -231.752118) (xy 379.202106 -231.714024) (xy 379.174905 -231.67101) (xy 379.154957 -231.62419)
			(xy 379.142778 -231.574776) (xy 379.138683 -231.524048) (xy 378.820172 -231.524048) (xy 378.819677 -231.548655)
			(xy 378.811782 -231.597232) (xy 378.796198 -231.643913) (xy 378.773327 -231.68749) (xy 378.743762 -231.726834)
			(xy 378.708269 -231.760926) (xy 378.667766 -231.788882) (xy 378.623304 -231.80998) (xy 378.576033 -231.823672)
			(xy 378.527178 -231.829604) (xy 378.478003 -231.827623) (xy 378.429784 -231.817779) (xy 378.383768 -231.800327)
			(xy 378.341147 -231.77572) (xy 378.303026 -231.744595) (xy 378.270391 -231.707758) (xy 378.244088 -231.666162)
			(xy 378.224797 -231.620886) (xy 378.21302 -231.573102) (xy 378.20906 -231.524048) (xy 377.890532 -231.524048)
			(xy 377.89002 -231.549494) (xy 377.881856 -231.599728) (xy 377.86574 -231.648002) (xy 377.842089 -231.693065)
			(xy 377.811516 -231.733751) (xy 377.774812 -231.769006) (xy 377.732928 -231.797916) (xy 377.686949 -231.819733)
			(xy 377.638065 -231.833893) (xy 377.587544 -231.840027) (xy 377.536692 -231.837978) (xy 377.486828 -231.827798)
			(xy 377.439242 -231.809751) (xy 377.395168 -231.784305) (xy 377.355746 -231.752118) (xy 377.321998 -231.714024)
			(xy 377.294797 -231.67101) (xy 377.274849 -231.62419) (xy 377.26267 -231.574776) (xy 377.258575 -231.524048)
			(xy 376.940064 -231.524048) (xy 376.939569 -231.548655) (xy 376.931674 -231.597232) (xy 376.91609 -231.643913)
			(xy 376.893219 -231.68749) (xy 376.863654 -231.726834) (xy 376.828161 -231.760926) (xy 376.787658 -231.788882)
			(xy 376.743196 -231.80998) (xy 376.695925 -231.823672) (xy 376.64707 -231.829604) (xy 376.597895 -231.827623)
			(xy 376.549676 -231.817779) (xy 376.50366 -231.800327) (xy 376.461039 -231.77572) (xy 376.422918 -231.744595)
			(xy 376.390283 -231.707758) (xy 376.36398 -231.666162) (xy 376.344689 -231.620886) (xy 376.332912 -231.573102)
			(xy 376.328952 -231.524048) (xy 376.010424 -231.524048) (xy 376.009912 -231.549494) (xy 376.001748 -231.599728)
			(xy 375.985632 -231.648002) (xy 375.961981 -231.693065) (xy 375.931408 -231.733751) (xy 375.894704 -231.769006)
			(xy 375.85282 -231.797916) (xy 375.806841 -231.819733) (xy 375.757957 -231.833893) (xy 375.707436 -231.840027)
			(xy 375.656584 -231.837978) (xy 375.60672 -231.827798) (xy 375.559134 -231.809751) (xy 375.51506 -231.784305)
			(xy 375.475638 -231.752118) (xy 375.44189 -231.714024) (xy 375.414689 -231.67101) (xy 375.394741 -231.62419)
			(xy 375.382562 -231.574776) (xy 375.378467 -231.524048) (xy 375.11863 -231.524048) (xy 375.11863 -232.334054)
			(xy 375.848621 -232.334054) (xy 375.852716 -232.283326) (xy 375.864895 -232.233912) (xy 375.884843 -232.187092)
			(xy 375.912044 -232.144078) (xy 375.945792 -232.105984) (xy 375.985214 -232.073797) (xy 376.029288 -232.048351)
			(xy 376.076874 -232.030304) (xy 376.126738 -232.020124) (xy 376.17759 -232.018075) (xy 376.228111 -232.024209)
			(xy 376.276995 -232.038369) (xy 376.322974 -232.060186) (xy 376.364858 -232.089096) (xy 376.401562 -232.124351)
			(xy 376.432135 -232.165037) (xy 376.455786 -232.2101) (xy 376.471902 -232.258374) (xy 376.480066 -232.308608)
			(xy 376.480578 -232.334054) (xy 376.788675 -232.334054) (xy 376.79277 -232.283326) (xy 376.804949 -232.233912)
			(xy 376.824897 -232.187092) (xy 376.852098 -232.144078) (xy 376.885846 -232.105984) (xy 376.925268 -232.073797)
			(xy 376.969342 -232.048351) (xy 377.016928 -232.030304) (xy 377.066792 -232.020124) (xy 377.117644 -232.018075)
			(xy 377.168165 -232.024209) (xy 377.217049 -232.038369) (xy 377.263028 -232.060186) (xy 377.304912 -232.089096)
			(xy 377.341616 -232.124351) (xy 377.372189 -232.165037) (xy 377.39584 -232.2101) (xy 377.411956 -232.258374)
			(xy 377.42012 -232.308608) (xy 377.420632 -232.334054) (xy 378.668529 -232.334054) (xy 378.672624 -232.283326)
			(xy 378.684803 -232.233912) (xy 378.704751 -232.187092) (xy 378.731952 -232.144078) (xy 378.7657 -232.105984)
			(xy 378.805122 -232.073797) (xy 378.849196 -232.048351) (xy 378.896782 -232.030304) (xy 378.946646 -232.020124)
			(xy 378.997498 -232.018075) (xy 379.048019 -232.024209) (xy 379.096903 -232.038369) (xy 379.142882 -232.060186)
			(xy 379.184766 -232.089096) (xy 379.22147 -232.124351) (xy 379.252043 -232.165037) (xy 379.275694 -232.2101)
			(xy 379.29181 -232.258374) (xy 379.299974 -232.308608) (xy 379.300486 -232.334054) (xy 379.619014 -232.334054)
			(xy 379.622974 -232.285) (xy 379.634751 -232.237216) (xy 379.654042 -232.19194) (xy 379.680345 -232.150344)
			(xy 379.71298 -232.113507) (xy 379.751101 -232.082382) (xy 379.793722 -232.057775) (xy 379.839738 -232.040323)
			(xy 379.887957 -232.030479) (xy 379.937132 -232.028498) (xy 379.985987 -232.03443) (xy 380.033258 -232.048122)
			(xy 380.07772 -232.06922) (xy 380.118223 -232.097176) (xy 380.153716 -232.131268) (xy 380.183281 -232.170612)
			(xy 380.206152 -232.214189) (xy 380.221736 -232.26087) (xy 380.229631 -232.309447) (xy 380.230126 -232.334054)
			(xy 380.548637 -232.334054) (xy 380.552732 -232.283326) (xy 380.564911 -232.233912) (xy 380.584859 -232.187092)
			(xy 380.61206 -232.144078) (xy 380.645808 -232.105984) (xy 380.68523 -232.073797) (xy 380.729304 -232.048351)
			(xy 380.77689 -232.030304) (xy 380.826754 -232.020124) (xy 380.877606 -232.018075) (xy 380.928127 -232.024209)
			(xy 380.977011 -232.038369) (xy 381.02299 -232.060186) (xy 381.064874 -232.089096) (xy 381.101578 -232.124351)
			(xy 381.132151 -232.165037) (xy 381.155802 -232.2101) (xy 381.171918 -232.258374) (xy 381.180082 -232.308608)
			(xy 381.180594 -232.334054) (xy 381.180082 -232.3595) (xy 381.171918 -232.409734) (xy 381.155802 -232.458008)
			(xy 381.132151 -232.503071) (xy 381.101578 -232.543757) (xy 381.064874 -232.579012) (xy 381.02299 -232.607922)
			(xy 380.977011 -232.629739) (xy 380.928127 -232.643899) (xy 380.877606 -232.650033) (xy 380.826754 -232.647984)
			(xy 380.77689 -232.637804) (xy 380.729304 -232.619757) (xy 380.68523 -232.594311) (xy 380.645808 -232.562124)
			(xy 380.61206 -232.52403) (xy 380.584859 -232.481016) (xy 380.564911 -232.434196) (xy 380.552732 -232.384782)
			(xy 380.548637 -232.334054) (xy 380.230126 -232.334054) (xy 380.229631 -232.358661) (xy 380.221736 -232.407238)
			(xy 380.206152 -232.453919) (xy 380.183281 -232.497496) (xy 380.153716 -232.53684) (xy 380.118223 -232.570932)
			(xy 380.07772 -232.598888) (xy 380.033258 -232.619986) (xy 379.985987 -232.633678) (xy 379.937132 -232.63961)
			(xy 379.887957 -232.637629) (xy 379.839738 -232.627785) (xy 379.793722 -232.610333) (xy 379.751101 -232.585726)
			(xy 379.71298 -232.554601) (xy 379.680345 -232.517764) (xy 379.654042 -232.476168) (xy 379.634751 -232.430892)
			(xy 379.622974 -232.383108) (xy 379.619014 -232.334054) (xy 379.300486 -232.334054) (xy 379.299974 -232.3595)
			(xy 379.29181 -232.409734) (xy 379.275694 -232.458008) (xy 379.252043 -232.503071) (xy 379.22147 -232.543757)
			(xy 379.184766 -232.579012) (xy 379.142882 -232.607922) (xy 379.096903 -232.629739) (xy 379.048019 -232.643899)
			(xy 378.997498 -232.650033) (xy 378.946646 -232.647984) (xy 378.896782 -232.637804) (xy 378.849196 -232.619757)
			(xy 378.805122 -232.594311) (xy 378.7657 -232.562124) (xy 378.731952 -232.52403) (xy 378.704751 -232.481016)
			(xy 378.684803 -232.434196) (xy 378.672624 -232.384782) (xy 378.668529 -232.334054) (xy 377.420632 -232.334054)
			(xy 377.42012 -232.3595) (xy 377.411956 -232.409734) (xy 377.39584 -232.458008) (xy 377.372189 -232.503071)
			(xy 377.341616 -232.543757) (xy 377.304912 -232.579012) (xy 377.263028 -232.607922) (xy 377.217049 -232.629739)
			(xy 377.168165 -232.643899) (xy 377.117644 -232.650033) (xy 377.066792 -232.647984) (xy 377.016928 -232.637804)
			(xy 376.969342 -232.619757) (xy 376.925268 -232.594311) (xy 376.885846 -232.562124) (xy 376.852098 -232.52403)
			(xy 376.824897 -232.481016) (xy 376.804949 -232.434196) (xy 376.79277 -232.384782) (xy 376.788675 -232.334054)
			(xy 376.480578 -232.334054) (xy 376.480066 -232.3595) (xy 376.471902 -232.409734) (xy 376.455786 -232.458008)
			(xy 376.432135 -232.503071) (xy 376.401562 -232.543757) (xy 376.364858 -232.579012) (xy 376.322974 -232.607922)
			(xy 376.276995 -232.629739) (xy 376.228111 -232.643899) (xy 376.17759 -232.650033) (xy 376.126738 -232.647984)
			(xy 376.076874 -232.637804) (xy 376.029288 -232.619757) (xy 375.985214 -232.594311) (xy 375.945792 -232.562124)
			(xy 375.912044 -232.52403) (xy 375.884843 -232.481016) (xy 375.864895 -232.434196) (xy 375.852716 -232.384782)
			(xy 375.848621 -232.334054) (xy 375.11863 -232.334054) (xy 375.11863 -233.14406) (xy 375.378467 -233.14406)
			(xy 375.382562 -233.093332) (xy 375.394741 -233.043918) (xy 375.414689 -232.997098) (xy 375.44189 -232.954084)
			(xy 375.475638 -232.91599) (xy 375.51506 -232.883803) (xy 375.559134 -232.858357) (xy 375.60672 -232.84031)
			(xy 375.656584 -232.83013) (xy 375.707436 -232.828081) (xy 375.757957 -232.834215) (xy 375.806841 -232.848375)
			(xy 375.85282 -232.870192) (xy 375.894704 -232.899102) (xy 375.931408 -232.934357) (xy 375.961981 -232.975043)
			(xy 375.985632 -233.020106) (xy 376.001748 -233.06838) (xy 376.009912 -233.118614) (xy 376.010424 -233.14406)
			(xy 376.328952 -233.14406) (xy 376.332912 -233.095006) (xy 376.344689 -233.047222) (xy 376.36398 -233.001946)
			(xy 376.390283 -232.96035) (xy 376.422918 -232.923513) (xy 376.461039 -232.892388) (xy 376.50366 -232.867781)
			(xy 376.549676 -232.850329) (xy 376.597895 -232.840485) (xy 376.64707 -232.838504) (xy 376.695925 -232.844436)
			(xy 376.743196 -232.858128) (xy 376.787658 -232.879226) (xy 376.828161 -232.907182) (xy 376.863654 -232.941274)
			(xy 376.893219 -232.980618) (xy 376.91609 -233.024195) (xy 376.931674 -233.070876) (xy 376.939569 -233.119453)
			(xy 376.940064 -233.14406) (xy 377.258575 -233.14406) (xy 377.26267 -233.093332) (xy 377.274849 -233.043918)
			(xy 377.294797 -232.997098) (xy 377.321998 -232.954084) (xy 377.355746 -232.91599) (xy 377.395168 -232.883803)
			(xy 377.439242 -232.858357) (xy 377.486828 -232.84031) (xy 377.536692 -232.83013) (xy 377.587544 -232.828081)
			(xy 377.638065 -232.834215) (xy 377.686949 -232.848375) (xy 377.732928 -232.870192) (xy 377.774812 -232.899102)
			(xy 377.811516 -232.934357) (xy 377.842089 -232.975043) (xy 377.86574 -233.020106) (xy 377.881856 -233.06838)
			(xy 377.89002 -233.118614) (xy 377.890532 -233.14406) (xy 378.20906 -233.14406) (xy 378.21302 -233.095006)
			(xy 378.224797 -233.047222) (xy 378.244088 -233.001946) (xy 378.270391 -232.96035) (xy 378.303026 -232.923513)
			(xy 378.341147 -232.892388) (xy 378.383768 -232.867781) (xy 378.429784 -232.850329) (xy 378.478003 -232.840485)
			(xy 378.527178 -232.838504) (xy 378.576033 -232.844436) (xy 378.623304 -232.858128) (xy 378.667766 -232.879226)
			(xy 378.708269 -232.907182) (xy 378.743762 -232.941274) (xy 378.773327 -232.980618) (xy 378.796198 -233.024195)
			(xy 378.811782 -233.070876) (xy 378.819677 -233.119453) (xy 378.820172 -233.14406) (xy 379.138683 -233.14406)
			(xy 379.142778 -233.093332) (xy 379.154957 -233.043918) (xy 379.174905 -232.997098) (xy 379.202106 -232.954084)
			(xy 379.235854 -232.91599) (xy 379.275276 -232.883803) (xy 379.31935 -232.858357) (xy 379.366936 -232.84031)
			(xy 379.4168 -232.83013) (xy 379.467652 -232.828081) (xy 379.518173 -232.834215) (xy 379.567057 -232.848375)
			(xy 379.613036 -232.870192) (xy 379.65492 -232.899102) (xy 379.691624 -232.934357) (xy 379.722197 -232.975043)
			(xy 379.745848 -233.020106) (xy 379.761964 -233.06838) (xy 379.770128 -233.118614) (xy 379.77064 -233.14406)
			(xy 380.078483 -233.14406) (xy 380.082578 -233.093332) (xy 380.094757 -233.043918) (xy 380.114705 -232.997098)
			(xy 380.141906 -232.954084) (xy 380.175654 -232.91599) (xy 380.215076 -232.883803) (xy 380.25915 -232.858357)
			(xy 380.306736 -232.84031) (xy 380.3566 -232.83013) (xy 380.407452 -232.828081) (xy 380.457973 -232.834215)
			(xy 380.506857 -232.848375) (xy 380.552836 -232.870192) (xy 380.59472 -232.899102) (xy 380.631424 -232.934357)
			(xy 380.661997 -232.975043) (xy 380.685648 -233.020106) (xy 380.701764 -233.06838) (xy 380.709928 -233.118614)
			(xy 380.71044 -233.14406) (xy 380.709928 -233.169506) (xy 380.701764 -233.21974) (xy 380.685648 -233.268014)
			(xy 380.661997 -233.313077) (xy 380.631424 -233.353763) (xy 380.59472 -233.389018) (xy 380.552836 -233.417928)
			(xy 380.506857 -233.439745) (xy 380.457973 -233.453905) (xy 380.407452 -233.460039) (xy 380.3566 -233.45799)
			(xy 380.306736 -233.44781) (xy 380.25915 -233.429763) (xy 380.215076 -233.404317) (xy 380.175654 -233.37213)
			(xy 380.141906 -233.334036) (xy 380.114705 -233.291022) (xy 380.094757 -233.244202) (xy 380.082578 -233.194788)
			(xy 380.078483 -233.14406) (xy 379.77064 -233.14406) (xy 379.770128 -233.169506) (xy 379.761964 -233.21974)
			(xy 379.745848 -233.268014) (xy 379.722197 -233.313077) (xy 379.691624 -233.353763) (xy 379.65492 -233.389018)
			(xy 379.613036 -233.417928) (xy 379.567057 -233.439745) (xy 379.518173 -233.453905) (xy 379.467652 -233.460039)
			(xy 379.4168 -233.45799) (xy 379.366936 -233.44781) (xy 379.31935 -233.429763) (xy 379.275276 -233.404317)
			(xy 379.235854 -233.37213) (xy 379.202106 -233.334036) (xy 379.174905 -233.291022) (xy 379.154957 -233.244202)
			(xy 379.142778 -233.194788) (xy 379.138683 -233.14406) (xy 378.820172 -233.14406) (xy 378.819677 -233.168667)
			(xy 378.811782 -233.217244) (xy 378.796198 -233.263925) (xy 378.773327 -233.307502) (xy 378.743762 -233.346846)
			(xy 378.708269 -233.380938) (xy 378.667766 -233.408894) (xy 378.623304 -233.429992) (xy 378.576033 -233.443684)
			(xy 378.527178 -233.449616) (xy 378.478003 -233.447635) (xy 378.429784 -233.437791) (xy 378.383768 -233.420339)
			(xy 378.341147 -233.395732) (xy 378.303026 -233.364607) (xy 378.270391 -233.32777) (xy 378.244088 -233.286174)
			(xy 378.224797 -233.240898) (xy 378.21302 -233.193114) (xy 378.20906 -233.14406) (xy 377.890532 -233.14406)
			(xy 377.89002 -233.169506) (xy 377.881856 -233.21974) (xy 377.86574 -233.268014) (xy 377.842089 -233.313077)
			(xy 377.811516 -233.353763) (xy 377.774812 -233.389018) (xy 377.732928 -233.417928) (xy 377.686949 -233.439745)
			(xy 377.638065 -233.453905) (xy 377.587544 -233.460039) (xy 377.536692 -233.45799) (xy 377.486828 -233.44781)
			(xy 377.439242 -233.429763) (xy 377.395168 -233.404317) (xy 377.355746 -233.37213) (xy 377.321998 -233.334036)
			(xy 377.294797 -233.291022) (xy 377.274849 -233.244202) (xy 377.26267 -233.194788) (xy 377.258575 -233.14406)
			(xy 376.940064 -233.14406) (xy 376.939569 -233.168667) (xy 376.931674 -233.217244) (xy 376.91609 -233.263925)
			(xy 376.893219 -233.307502) (xy 376.863654 -233.346846) (xy 376.828161 -233.380938) (xy 376.787658 -233.408894)
			(xy 376.743196 -233.429992) (xy 376.695925 -233.443684) (xy 376.64707 -233.449616) (xy 376.597895 -233.447635)
			(xy 376.549676 -233.437791) (xy 376.50366 -233.420339) (xy 376.461039 -233.395732) (xy 376.422918 -233.364607)
			(xy 376.390283 -233.32777) (xy 376.36398 -233.286174) (xy 376.344689 -233.240898) (xy 376.332912 -233.193114)
			(xy 376.328952 -233.14406) (xy 376.010424 -233.14406) (xy 376.009912 -233.169506) (xy 376.001748 -233.21974)
			(xy 375.985632 -233.268014) (xy 375.961981 -233.313077) (xy 375.931408 -233.353763) (xy 375.894704 -233.389018)
			(xy 375.85282 -233.417928) (xy 375.806841 -233.439745) (xy 375.757957 -233.453905) (xy 375.707436 -233.460039)
			(xy 375.656584 -233.45799) (xy 375.60672 -233.44781) (xy 375.559134 -233.429763) (xy 375.51506 -233.404317)
			(xy 375.475638 -233.37213) (xy 375.44189 -233.334036) (xy 375.414689 -233.291022) (xy 375.394741 -233.244202)
			(xy 375.382562 -233.194788) (xy 375.378467 -233.14406) (xy 375.11863 -233.14406) (xy 375.11863 -233.547158)
			(xy 375.119064 -233.557223) (xy 375.126797 -233.575809) (xy 375.133616 -233.583226) (xy 375.184924 -233.634026)
			(xy 375.192336 -233.640704) (xy 375.210772 -233.648273) (xy 375.220738 -233.648758) (xy 375.224802 -233.648758)
			(xy 375.25006 -233.64928) (xy 375.299887 -233.657595) (xy 375.347666 -233.673998) (xy 375.392093 -233.698041)
			(xy 375.431958 -233.729069) (xy 375.466171 -233.766234) (xy 375.493801 -233.808525) (xy 375.514093 -233.854786)
			(xy 375.526493 -233.903756) (xy 375.530662 -233.954066) (xy 375.848621 -233.954066) (xy 375.852716 -233.903338)
			(xy 375.864895 -233.853924) (xy 375.884843 -233.807104) (xy 375.912044 -233.76409) (xy 375.945792 -233.725996)
			(xy 375.985214 -233.693809) (xy 376.029288 -233.668363) (xy 376.076874 -233.650316) (xy 376.126738 -233.640136)
			(xy 376.17759 -233.638087) (xy 376.228111 -233.644221) (xy 376.276995 -233.658381) (xy 376.322974 -233.680198)
			(xy 376.364858 -233.709108) (xy 376.401562 -233.744363) (xy 376.432135 -233.785049) (xy 376.455786 -233.830112)
			(xy 376.471902 -233.878386) (xy 376.480066 -233.92862) (xy 376.480578 -233.954066) (xy 376.788675 -233.954066)
			(xy 376.79277 -233.903338) (xy 376.804949 -233.853924) (xy 376.824897 -233.807104) (xy 376.852098 -233.76409)
			(xy 376.885846 -233.725996) (xy 376.925268 -233.693809) (xy 376.969342 -233.668363) (xy 377.016928 -233.650316)
			(xy 377.066792 -233.640136) (xy 377.117644 -233.638087) (xy 377.168165 -233.644221) (xy 377.217049 -233.658381)
			(xy 377.263028 -233.680198) (xy 377.304912 -233.709108) (xy 377.341616 -233.744363) (xy 377.372189 -233.785049)
			(xy 377.39584 -233.830112) (xy 377.411956 -233.878386) (xy 377.42012 -233.92862) (xy 377.420632 -233.954066)
			(xy 377.738906 -233.954066) (xy 377.742866 -233.905012) (xy 377.754643 -233.857228) (xy 377.773934 -233.811952)
			(xy 377.800237 -233.770356) (xy 377.832872 -233.733519) (xy 377.870993 -233.702394) (xy 377.913614 -233.677787)
			(xy 377.95963 -233.660335) (xy 378.007849 -233.650491) (xy 378.057024 -233.64851) (xy 378.105879 -233.654442)
			(xy 378.15315 -233.668134) (xy 378.197612 -233.689232) (xy 378.238115 -233.717188) (xy 378.273608 -233.75128)
			(xy 378.303173 -233.790624) (xy 378.326044 -233.834201) (xy 378.341628 -233.880882) (xy 378.349523 -233.929459)
			(xy 378.350018 -233.954066) (xy 378.668529 -233.954066) (xy 378.672624 -233.903338) (xy 378.684803 -233.853924)
			(xy 378.704751 -233.807104) (xy 378.731952 -233.76409) (xy 378.7657 -233.725996) (xy 378.805122 -233.693809)
			(xy 378.849196 -233.668363) (xy 378.896782 -233.650316) (xy 378.946646 -233.640136) (xy 378.997498 -233.638087)
			(xy 379.048019 -233.644221) (xy 379.096903 -233.658381) (xy 379.142882 -233.680198) (xy 379.184766 -233.709108)
			(xy 379.22147 -233.744363) (xy 379.252043 -233.785049) (xy 379.275694 -233.830112) (xy 379.29181 -233.878386)
			(xy 379.299974 -233.92862) (xy 379.300486 -233.954066) (xy 379.619014 -233.954066) (xy 379.622974 -233.905012)
			(xy 379.634751 -233.857228) (xy 379.654042 -233.811952) (xy 379.680345 -233.770356) (xy 379.71298 -233.733519)
			(xy 379.751101 -233.702394) (xy 379.793722 -233.677787) (xy 379.839738 -233.660335) (xy 379.887957 -233.650491)
			(xy 379.937132 -233.64851) (xy 379.985987 -233.654442) (xy 380.033258 -233.668134) (xy 380.07772 -233.689232)
			(xy 380.118223 -233.717188) (xy 380.153716 -233.75128) (xy 380.183281 -233.790624) (xy 380.206152 -233.834201)
			(xy 380.221736 -233.880882) (xy 380.229631 -233.929459) (xy 380.230126 -233.954066) (xy 380.548637 -233.954066)
			(xy 380.552732 -233.903338) (xy 380.564911 -233.853924) (xy 380.584859 -233.807104) (xy 380.61206 -233.76409)
			(xy 380.645808 -233.725996) (xy 380.68523 -233.693809) (xy 380.729304 -233.668363) (xy 380.77689 -233.650316)
			(xy 380.826754 -233.640136) (xy 380.877606 -233.638087) (xy 380.928127 -233.644221) (xy 380.977011 -233.658381)
			(xy 381.02299 -233.680198) (xy 381.064874 -233.709108) (xy 381.101578 -233.744363) (xy 381.132151 -233.785049)
			(xy 381.155802 -233.830112) (xy 381.171918 -233.878386) (xy 381.180082 -233.92862) (xy 381.180594 -233.954066)
			(xy 381.180082 -233.979512) (xy 381.171918 -234.029746) (xy 381.155802 -234.07802) (xy 381.132151 -234.123083)
			(xy 381.101578 -234.163769) (xy 381.064874 -234.199024) (xy 381.02299 -234.227934) (xy 380.977011 -234.249751)
			(xy 380.928127 -234.263911) (xy 380.877606 -234.270045) (xy 380.826754 -234.267996) (xy 380.77689 -234.257816)
			(xy 380.729304 -234.239769) (xy 380.68523 -234.214323) (xy 380.645808 -234.182136) (xy 380.61206 -234.144042)
			(xy 380.584859 -234.101028) (xy 380.564911 -234.054208) (xy 380.552732 -234.004794) (xy 380.548637 -233.954066)
			(xy 380.230126 -233.954066) (xy 380.229631 -233.978673) (xy 380.221736 -234.02725) (xy 380.206152 -234.073931)
			(xy 380.183281 -234.117508) (xy 380.153716 -234.156852) (xy 380.118223 -234.190944) (xy 380.07772 -234.2189)
			(xy 380.033258 -234.239998) (xy 379.985987 -234.25369) (xy 379.937132 -234.259622) (xy 379.887957 -234.257641)
			(xy 379.839738 -234.247797) (xy 379.793722 -234.230345) (xy 379.751101 -234.205738) (xy 379.71298 -234.174613)
			(xy 379.680345 -234.137776) (xy 379.654042 -234.09618) (xy 379.634751 -234.050904) (xy 379.622974 -234.00312)
			(xy 379.619014 -233.954066) (xy 379.300486 -233.954066) (xy 379.299974 -233.979512) (xy 379.29181 -234.029746)
			(xy 379.275694 -234.07802) (xy 379.252043 -234.123083) (xy 379.22147 -234.163769) (xy 379.184766 -234.199024)
			(xy 379.142882 -234.227934) (xy 379.096903 -234.249751) (xy 379.048019 -234.263911) (xy 378.997498 -234.270045)
			(xy 378.946646 -234.267996) (xy 378.896782 -234.257816) (xy 378.849196 -234.239769) (xy 378.805122 -234.214323)
			(xy 378.7657 -234.182136) (xy 378.731952 -234.144042) (xy 378.704751 -234.101028) (xy 378.684803 -234.054208)
			(xy 378.672624 -234.004794) (xy 378.668529 -233.954066) (xy 378.350018 -233.954066) (xy 378.349523 -233.978673)
			(xy 378.341628 -234.02725) (xy 378.326044 -234.073931) (xy 378.303173 -234.117508) (xy 378.273608 -234.156852)
			(xy 378.238115 -234.190944) (xy 378.197612 -234.2189) (xy 378.15315 -234.239998) (xy 378.105879 -234.25369)
			(xy 378.057024 -234.259622) (xy 378.007849 -234.257641) (xy 377.95963 -234.247797) (xy 377.913614 -234.230345)
			(xy 377.870993 -234.205738) (xy 377.832872 -234.174613) (xy 377.800237 -234.137776) (xy 377.773934 -234.09618)
			(xy 377.754643 -234.050904) (xy 377.742866 -234.00312) (xy 377.738906 -233.954066) (xy 377.420632 -233.954066)
			(xy 377.42012 -233.979512) (xy 377.411956 -234.029746) (xy 377.39584 -234.07802) (xy 377.372189 -234.123083)
			(xy 377.341616 -234.163769) (xy 377.304912 -234.199024) (xy 377.263028 -234.227934) (xy 377.217049 -234.249751)
			(xy 377.168165 -234.263911) (xy 377.117644 -234.270045) (xy 377.066792 -234.267996) (xy 377.016928 -234.257816)
			(xy 376.969342 -234.239769) (xy 376.925268 -234.214323) (xy 376.885846 -234.182136) (xy 376.852098 -234.144042)
			(xy 376.824897 -234.101028) (xy 376.804949 -234.054208) (xy 376.79277 -234.004794) (xy 376.788675 -233.954066)
			(xy 376.480578 -233.954066) (xy 376.480066 -233.979512) (xy 376.471902 -234.029746) (xy 376.455786 -234.07802)
			(xy 376.432135 -234.123083) (xy 376.401562 -234.163769) (xy 376.364858 -234.199024) (xy 376.322974 -234.227934)
			(xy 376.276995 -234.249751) (xy 376.228111 -234.263911) (xy 376.17759 -234.270045) (xy 376.126738 -234.267996)
			(xy 376.076874 -234.257816) (xy 376.029288 -234.239769) (xy 375.985214 -234.214323) (xy 375.945792 -234.182136)
			(xy 375.912044 -234.144042) (xy 375.884843 -234.101028) (xy 375.864895 -234.054208) (xy 375.852716 -234.004794)
			(xy 375.848621 -233.954066) (xy 375.530662 -233.954066) (xy 375.530665 -233.9541) (xy 375.526493 -234.004444)
			(xy 375.514093 -234.053414) (xy 375.493801 -234.099675) (xy 375.466171 -234.141966) (xy 375.431958 -234.179131)
			(xy 375.392093 -234.210159) (xy 375.347666 -234.234202) (xy 375.299887 -234.250605) (xy 375.25006 -234.25892)
			(xy 375.224802 -234.259374) (xy 375.220738 -234.259374) (xy 375.210775 -234.259859) (xy 375.192347 -234.267442)
			(xy 375.184924 -234.274106) (xy 375.133616 -234.324906) (xy 375.126769 -234.332304) (xy 375.119034 -234.350902)
			(xy 375.11863 -234.360974) (xy 375.11863 -234.764072) (xy 375.378467 -234.764072) (xy 375.382562 -234.713344)
			(xy 375.394741 -234.66393) (xy 375.414689 -234.61711) (xy 375.44189 -234.574096) (xy 375.475638 -234.536002)
			(xy 375.51506 -234.503815) (xy 375.559134 -234.478369) (xy 375.60672 -234.460322) (xy 375.656584 -234.450142)
			(xy 375.707436 -234.448093) (xy 375.757957 -234.454227) (xy 375.806841 -234.468387) (xy 375.85282 -234.490204)
			(xy 375.894704 -234.519114) (xy 375.931408 -234.554369) (xy 375.961981 -234.595055) (xy 375.985632 -234.640118)
			(xy 376.001748 -234.688392) (xy 376.009912 -234.738626) (xy 376.010424 -234.764072) (xy 376.328952 -234.764072)
			(xy 376.332912 -234.715018) (xy 376.344689 -234.667234) (xy 376.36398 -234.621958) (xy 376.390283 -234.580362)
			(xy 376.422918 -234.543525) (xy 376.461039 -234.5124) (xy 376.50366 -234.487793) (xy 376.549676 -234.470341)
			(xy 376.597895 -234.460497) (xy 376.64707 -234.458516) (xy 376.695925 -234.464448) (xy 376.743196 -234.47814)
			(xy 376.787658 -234.499238) (xy 376.828161 -234.527194) (xy 376.863654 -234.561286) (xy 376.893219 -234.60063)
			(xy 376.91609 -234.644207) (xy 376.931674 -234.690888) (xy 376.939569 -234.739465) (xy 376.940064 -234.764072)
			(xy 377.258575 -234.764072) (xy 377.26267 -234.713344) (xy 377.274849 -234.66393) (xy 377.294797 -234.61711)
			(xy 377.321998 -234.574096) (xy 377.355746 -234.536002) (xy 377.395168 -234.503815) (xy 377.439242 -234.478369)
			(xy 377.486828 -234.460322) (xy 377.536692 -234.450142) (xy 377.587544 -234.448093) (xy 377.638065 -234.454227)
			(xy 377.686949 -234.468387) (xy 377.732928 -234.490204) (xy 377.774812 -234.519114) (xy 377.811516 -234.554369)
			(xy 377.842089 -234.595055) (xy 377.86574 -234.640118) (xy 377.881856 -234.688392) (xy 377.89002 -234.738626)
			(xy 377.890532 -234.764072) (xy 379.138683 -234.764072) (xy 379.142778 -234.713344) (xy 379.154957 -234.66393)
			(xy 379.174905 -234.61711) (xy 379.202106 -234.574096) (xy 379.235854 -234.536002) (xy 379.275276 -234.503815)
			(xy 379.31935 -234.478369) (xy 379.366936 -234.460322) (xy 379.4168 -234.450142) (xy 379.467652 -234.448093)
			(xy 379.518173 -234.454227) (xy 379.567057 -234.468387) (xy 379.613036 -234.490204) (xy 379.65492 -234.519114)
			(xy 379.691624 -234.554369) (xy 379.722197 -234.595055) (xy 379.745848 -234.640118) (xy 379.761964 -234.688392)
			(xy 379.770128 -234.738626) (xy 379.77064 -234.764072) (xy 380.078483 -234.764072) (xy 380.082578 -234.713344)
			(xy 380.094757 -234.66393) (xy 380.114705 -234.61711) (xy 380.141906 -234.574096) (xy 380.175654 -234.536002)
			(xy 380.215076 -234.503815) (xy 380.25915 -234.478369) (xy 380.306736 -234.460322) (xy 380.3566 -234.450142)
			(xy 380.407452 -234.448093) (xy 380.457973 -234.454227) (xy 380.506857 -234.468387) (xy 380.552836 -234.490204)
			(xy 380.59472 -234.519114) (xy 380.631424 -234.554369) (xy 380.661997 -234.595055) (xy 380.685648 -234.640118)
			(xy 380.701764 -234.688392) (xy 380.709928 -234.738626) (xy 380.71044 -234.764072) (xy 380.709928 -234.789518)
			(xy 380.701764 -234.839752) (xy 380.685648 -234.888026) (xy 380.661997 -234.933089) (xy 380.631424 -234.973775)
			(xy 380.59472 -235.00903) (xy 380.552836 -235.03794) (xy 380.506857 -235.059757) (xy 380.457973 -235.073917)
			(xy 380.407452 -235.080051) (xy 380.3566 -235.078002) (xy 380.306736 -235.067822) (xy 380.25915 -235.049775)
			(xy 380.215076 -235.024329) (xy 380.175654 -234.992142) (xy 380.141906 -234.954048) (xy 380.114705 -234.911034)
			(xy 380.094757 -234.864214) (xy 380.082578 -234.8148) (xy 380.078483 -234.764072) (xy 379.77064 -234.764072)
			(xy 379.770128 -234.789518) (xy 379.761964 -234.839752) (xy 379.745848 -234.888026) (xy 379.722197 -234.933089)
			(xy 379.691624 -234.973775) (xy 379.65492 -235.00903) (xy 379.613036 -235.03794) (xy 379.567057 -235.059757)
			(xy 379.518173 -235.073917) (xy 379.467652 -235.080051) (xy 379.4168 -235.078002) (xy 379.366936 -235.067822)
			(xy 379.31935 -235.049775) (xy 379.275276 -235.024329) (xy 379.235854 -234.992142) (xy 379.202106 -234.954048)
			(xy 379.174905 -234.911034) (xy 379.154957 -234.864214) (xy 379.142778 -234.8148) (xy 379.138683 -234.764072)
			(xy 377.890532 -234.764072) (xy 377.89002 -234.789518) (xy 377.881856 -234.839752) (xy 377.86574 -234.888026)
			(xy 377.842089 -234.933089) (xy 377.811516 -234.973775) (xy 377.774812 -235.00903) (xy 377.732928 -235.03794)
			(xy 377.686949 -235.059757) (xy 377.638065 -235.073917) (xy 377.587544 -235.080051) (xy 377.536692 -235.078002)
			(xy 377.486828 -235.067822) (xy 377.439242 -235.049775) (xy 377.395168 -235.024329) (xy 377.355746 -234.992142)
			(xy 377.321998 -234.954048) (xy 377.294797 -234.911034) (xy 377.274849 -234.864214) (xy 377.26267 -234.8148)
			(xy 377.258575 -234.764072) (xy 376.940064 -234.764072) (xy 376.939569 -234.788679) (xy 376.931674 -234.837256)
			(xy 376.91609 -234.883937) (xy 376.893219 -234.927514) (xy 376.863654 -234.966858) (xy 376.828161 -235.00095)
			(xy 376.787658 -235.028906) (xy 376.743196 -235.050004) (xy 376.695925 -235.063696) (xy 376.64707 -235.069628)
			(xy 376.597895 -235.067647) (xy 376.549676 -235.057803) (xy 376.50366 -235.040351) (xy 376.461039 -235.015744)
			(xy 376.422918 -234.984619) (xy 376.390283 -234.947782) (xy 376.36398 -234.906186) (xy 376.344689 -234.86091)
			(xy 376.332912 -234.813126) (xy 376.328952 -234.764072) (xy 376.010424 -234.764072) (xy 376.009912 -234.789518)
			(xy 376.001748 -234.839752) (xy 375.985632 -234.888026) (xy 375.961981 -234.933089) (xy 375.931408 -234.973775)
			(xy 375.894704 -235.00903) (xy 375.85282 -235.03794) (xy 375.806841 -235.059757) (xy 375.757957 -235.073917)
			(xy 375.707436 -235.080051) (xy 375.656584 -235.078002) (xy 375.60672 -235.067822) (xy 375.559134 -235.049775)
			(xy 375.51506 -235.024329) (xy 375.475638 -234.992142) (xy 375.44189 -234.954048) (xy 375.414689 -234.911034)
			(xy 375.394741 -234.864214) (xy 375.382562 -234.8148) (xy 375.378467 -234.764072) (xy 375.11863 -234.764072)
			(xy 375.11863 -235.574078) (xy 375.848621 -235.574078) (xy 375.852716 -235.52335) (xy 375.864895 -235.473936)
			(xy 375.884843 -235.427116) (xy 375.912044 -235.384102) (xy 375.945792 -235.346008) (xy 375.985214 -235.313821)
			(xy 376.029288 -235.288375) (xy 376.076874 -235.270328) (xy 376.126738 -235.260148) (xy 376.17759 -235.258099)
			(xy 376.228111 -235.264233) (xy 376.276995 -235.278393) (xy 376.322974 -235.30021) (xy 376.364858 -235.32912)
			(xy 376.401562 -235.364375) (xy 376.432135 -235.405061) (xy 376.455786 -235.450124) (xy 376.471902 -235.498398)
			(xy 376.480066 -235.548632) (xy 376.480578 -235.574078) (xy 376.788675 -235.574078) (xy 376.79277 -235.52335)
			(xy 376.804949 -235.473936) (xy 376.824897 -235.427116) (xy 376.852098 -235.384102) (xy 376.885846 -235.346008)
			(xy 376.925268 -235.313821) (xy 376.969342 -235.288375) (xy 377.016928 -235.270328) (xy 377.066792 -235.260148)
			(xy 377.117644 -235.258099) (xy 377.168165 -235.264233) (xy 377.217049 -235.278393) (xy 377.263028 -235.30021)
			(xy 377.304912 -235.32912) (xy 377.341616 -235.364375) (xy 377.372189 -235.405061) (xy 377.39584 -235.450124)
			(xy 377.411956 -235.498398) (xy 377.42012 -235.548632) (xy 377.420632 -235.574078) (xy 377.738906 -235.574078)
			(xy 377.742866 -235.525024) (xy 377.754643 -235.47724) (xy 377.773934 -235.431964) (xy 377.800237 -235.390368)
			(xy 377.832872 -235.353531) (xy 377.870993 -235.322406) (xy 377.913614 -235.297799) (xy 377.95963 -235.280347)
			(xy 378.007849 -235.270503) (xy 378.057024 -235.268522) (xy 378.105879 -235.274454) (xy 378.15315 -235.288146)
			(xy 378.197612 -235.309244) (xy 378.238115 -235.3372) (xy 378.273608 -235.371292) (xy 378.303173 -235.410636)
			(xy 378.326044 -235.454213) (xy 378.341628 -235.500894) (xy 378.349523 -235.549471) (xy 378.350018 -235.574078)
			(xy 378.668529 -235.574078) (xy 378.672624 -235.52335) (xy 378.684803 -235.473936) (xy 378.704751 -235.427116)
			(xy 378.731952 -235.384102) (xy 378.7657 -235.346008) (xy 378.805122 -235.313821) (xy 378.849196 -235.288375)
			(xy 378.896782 -235.270328) (xy 378.946646 -235.260148) (xy 378.997498 -235.258099) (xy 379.048019 -235.264233)
			(xy 379.096903 -235.278393) (xy 379.142882 -235.30021) (xy 379.184766 -235.32912) (xy 379.22147 -235.364375)
			(xy 379.252043 -235.405061) (xy 379.275694 -235.450124) (xy 379.29181 -235.498398) (xy 379.299974 -235.548632)
			(xy 379.300486 -235.574078) (xy 379.619014 -235.574078) (xy 379.622974 -235.525024) (xy 379.634751 -235.47724)
			(xy 379.654042 -235.431964) (xy 379.680345 -235.390368) (xy 379.71298 -235.353531) (xy 379.751101 -235.322406)
			(xy 379.793722 -235.297799) (xy 379.839738 -235.280347) (xy 379.887957 -235.270503) (xy 379.937132 -235.268522)
			(xy 379.985987 -235.274454) (xy 380.033258 -235.288146) (xy 380.07772 -235.309244) (xy 380.118223 -235.3372)
			(xy 380.153716 -235.371292) (xy 380.183281 -235.410636) (xy 380.206152 -235.454213) (xy 380.221736 -235.500894)
			(xy 380.229631 -235.549471) (xy 380.230126 -235.574078) (xy 380.548637 -235.574078) (xy 380.552732 -235.52335)
			(xy 380.564911 -235.473936) (xy 380.584859 -235.427116) (xy 380.61206 -235.384102) (xy 380.645808 -235.346008)
			(xy 380.68523 -235.313821) (xy 380.729304 -235.288375) (xy 380.77689 -235.270328) (xy 380.826754 -235.260148)
			(xy 380.877606 -235.258099) (xy 380.928127 -235.264233) (xy 380.977011 -235.278393) (xy 381.02299 -235.30021)
			(xy 381.064874 -235.32912) (xy 381.101578 -235.364375) (xy 381.132151 -235.405061) (xy 381.155802 -235.450124)
			(xy 381.171918 -235.498398) (xy 381.180082 -235.548632) (xy 381.180594 -235.574078) (xy 381.180082 -235.599524)
			(xy 381.171918 -235.649758) (xy 381.155802 -235.698032) (xy 381.132151 -235.743095) (xy 381.101578 -235.783781)
			(xy 381.064874 -235.819036) (xy 381.02299 -235.847946) (xy 380.977011 -235.869763) (xy 380.928127 -235.883923)
			(xy 380.877606 -235.890057) (xy 380.826754 -235.888008) (xy 380.77689 -235.877828) (xy 380.729304 -235.859781)
			(xy 380.68523 -235.834335) (xy 380.645808 -235.802148) (xy 380.61206 -235.764054) (xy 380.584859 -235.72104)
			(xy 380.564911 -235.67422) (xy 380.552732 -235.624806) (xy 380.548637 -235.574078) (xy 380.230126 -235.574078)
			(xy 380.229631 -235.598685) (xy 380.221736 -235.647262) (xy 380.206152 -235.693943) (xy 380.183281 -235.73752)
			(xy 380.153716 -235.776864) (xy 380.118223 -235.810956) (xy 380.07772 -235.838912) (xy 380.033258 -235.86001)
			(xy 379.985987 -235.873702) (xy 379.937132 -235.879634) (xy 379.887957 -235.877653) (xy 379.839738 -235.867809)
			(xy 379.793722 -235.850357) (xy 379.751101 -235.82575) (xy 379.71298 -235.794625) (xy 379.680345 -235.757788)
			(xy 379.654042 -235.716192) (xy 379.634751 -235.670916) (xy 379.622974 -235.623132) (xy 379.619014 -235.574078)
			(xy 379.300486 -235.574078) (xy 379.299974 -235.599524) (xy 379.29181 -235.649758) (xy 379.275694 -235.698032)
			(xy 379.252043 -235.743095) (xy 379.22147 -235.783781) (xy 379.184766 -235.819036) (xy 379.142882 -235.847946)
			(xy 379.096903 -235.869763) (xy 379.048019 -235.883923) (xy 378.997498 -235.890057) (xy 378.946646 -235.888008)
			(xy 378.896782 -235.877828) (xy 378.849196 -235.859781) (xy 378.805122 -235.834335) (xy 378.7657 -235.802148)
			(xy 378.731952 -235.764054) (xy 378.704751 -235.72104) (xy 378.684803 -235.67422) (xy 378.672624 -235.624806)
			(xy 378.668529 -235.574078) (xy 378.350018 -235.574078) (xy 378.349523 -235.598685) (xy 378.341628 -235.647262)
			(xy 378.326044 -235.693943) (xy 378.303173 -235.73752) (xy 378.273608 -235.776864) (xy 378.238115 -235.810956)
			(xy 378.197612 -235.838912) (xy 378.15315 -235.86001) (xy 378.105879 -235.873702) (xy 378.057024 -235.879634)
			(xy 378.007849 -235.877653) (xy 377.95963 -235.867809) (xy 377.913614 -235.850357) (xy 377.870993 -235.82575)
			(xy 377.832872 -235.794625) (xy 377.800237 -235.757788) (xy 377.773934 -235.716192) (xy 377.754643 -235.670916)
			(xy 377.742866 -235.623132) (xy 377.738906 -235.574078) (xy 377.420632 -235.574078) (xy 377.42012 -235.599524)
			(xy 377.411956 -235.649758) (xy 377.39584 -235.698032) (xy 377.372189 -235.743095) (xy 377.341616 -235.783781)
			(xy 377.304912 -235.819036) (xy 377.263028 -235.847946) (xy 377.217049 -235.869763) (xy 377.168165 -235.883923)
			(xy 377.117644 -235.890057) (xy 377.066792 -235.888008) (xy 377.016928 -235.877828) (xy 376.969342 -235.859781)
			(xy 376.925268 -235.834335) (xy 376.885846 -235.802148) (xy 376.852098 -235.764054) (xy 376.824897 -235.72104)
			(xy 376.804949 -235.67422) (xy 376.79277 -235.624806) (xy 376.788675 -235.574078) (xy 376.480578 -235.574078)
			(xy 376.480066 -235.599524) (xy 376.471902 -235.649758) (xy 376.455786 -235.698032) (xy 376.432135 -235.743095)
			(xy 376.401562 -235.783781) (xy 376.364858 -235.819036) (xy 376.322974 -235.847946) (xy 376.276995 -235.869763)
			(xy 376.228111 -235.883923) (xy 376.17759 -235.890057) (xy 376.126738 -235.888008) (xy 376.076874 -235.877828)
			(xy 376.029288 -235.859781) (xy 375.985214 -235.834335) (xy 375.945792 -235.802148) (xy 375.912044 -235.764054)
			(xy 375.884843 -235.72104) (xy 375.864895 -235.67422) (xy 375.852716 -235.624806) (xy 375.848621 -235.574078)
			(xy 375.11863 -235.574078) (xy 375.11863 -236.384084) (xy 375.378467 -236.384084) (xy 375.382562 -236.333356)
			(xy 375.394741 -236.283942) (xy 375.414689 -236.237122) (xy 375.44189 -236.194108) (xy 375.475638 -236.156014)
			(xy 375.51506 -236.123827) (xy 375.559134 -236.098381) (xy 375.60672 -236.080334) (xy 375.656584 -236.070154)
			(xy 375.707436 -236.068105) (xy 375.757957 -236.074239) (xy 375.806841 -236.088399) (xy 375.85282 -236.110216)
			(xy 375.894704 -236.139126) (xy 375.931408 -236.174381) (xy 375.961981 -236.215067) (xy 375.985632 -236.26013)
			(xy 376.001748 -236.308404) (xy 376.009912 -236.358638) (xy 376.010424 -236.384084) (xy 376.328952 -236.384084)
			(xy 376.332912 -236.33503) (xy 376.344689 -236.287246) (xy 376.36398 -236.24197) (xy 376.390283 -236.200374)
			(xy 376.422918 -236.163537) (xy 376.461039 -236.132412) (xy 376.50366 -236.107805) (xy 376.549676 -236.090353)
			(xy 376.597895 -236.080509) (xy 376.64707 -236.078528) (xy 376.695925 -236.08446) (xy 376.743196 -236.098152)
			(xy 376.787658 -236.11925) (xy 376.828161 -236.147206) (xy 376.863654 -236.181298) (xy 376.893219 -236.220642)
			(xy 376.91609 -236.264219) (xy 376.931674 -236.3109) (xy 376.939569 -236.359477) (xy 376.940064 -236.384084)
			(xy 377.258575 -236.384084) (xy 377.26267 -236.333356) (xy 377.274849 -236.283942) (xy 377.294797 -236.237122)
			(xy 377.321998 -236.194108) (xy 377.355746 -236.156014) (xy 377.395168 -236.123827) (xy 377.439242 -236.098381)
			(xy 377.486828 -236.080334) (xy 377.536692 -236.070154) (xy 377.587544 -236.068105) (xy 377.638065 -236.074239)
			(xy 377.686949 -236.088399) (xy 377.732928 -236.110216) (xy 377.774812 -236.139126) (xy 377.811516 -236.174381)
			(xy 377.842089 -236.215067) (xy 377.86574 -236.26013) (xy 377.881856 -236.308404) (xy 377.89002 -236.358638)
			(xy 377.890532 -236.384084) (xy 378.20906 -236.384084) (xy 378.21302 -236.33503) (xy 378.224797 -236.287246)
			(xy 378.244088 -236.24197) (xy 378.270391 -236.200374) (xy 378.303026 -236.163537) (xy 378.341147 -236.132412)
			(xy 378.383768 -236.107805) (xy 378.429784 -236.090353) (xy 378.478003 -236.080509) (xy 378.527178 -236.078528)
			(xy 378.576033 -236.08446) (xy 378.623304 -236.098152) (xy 378.667766 -236.11925) (xy 378.708269 -236.147206)
			(xy 378.743762 -236.181298) (xy 378.773327 -236.220642) (xy 378.796198 -236.264219) (xy 378.811782 -236.3109)
			(xy 378.819677 -236.359477) (xy 378.820172 -236.384084) (xy 379.138683 -236.384084) (xy 379.142778 -236.333356)
			(xy 379.154957 -236.283942) (xy 379.174905 -236.237122) (xy 379.202106 -236.194108) (xy 379.235854 -236.156014)
			(xy 379.275276 -236.123827) (xy 379.31935 -236.098381) (xy 379.366936 -236.080334) (xy 379.4168 -236.070154)
			(xy 379.467652 -236.068105) (xy 379.518173 -236.074239) (xy 379.567057 -236.088399) (xy 379.613036 -236.110216)
			(xy 379.65492 -236.139126) (xy 379.691624 -236.174381) (xy 379.722197 -236.215067) (xy 379.745848 -236.26013)
			(xy 379.761964 -236.308404) (xy 379.770128 -236.358638) (xy 379.77064 -236.384084) (xy 380.078483 -236.384084)
			(xy 380.082578 -236.333356) (xy 380.094757 -236.283942) (xy 380.114705 -236.237122) (xy 380.141906 -236.194108)
			(xy 380.175654 -236.156014) (xy 380.215076 -236.123827) (xy 380.25915 -236.098381) (xy 380.306736 -236.080334)
			(xy 380.3566 -236.070154) (xy 380.407452 -236.068105) (xy 380.457973 -236.074239) (xy 380.506857 -236.088399)
			(xy 380.552836 -236.110216) (xy 380.59472 -236.139126) (xy 380.631424 -236.174381) (xy 380.661997 -236.215067)
			(xy 380.685648 -236.26013) (xy 380.701764 -236.308404) (xy 380.709928 -236.358638) (xy 380.71044 -236.384084)
			(xy 380.709928 -236.40953) (xy 380.701764 -236.459764) (xy 380.685648 -236.508038) (xy 380.661997 -236.553101)
			(xy 380.631424 -236.593787) (xy 380.59472 -236.629042) (xy 380.552836 -236.657952) (xy 380.506857 -236.679769)
			(xy 380.457973 -236.693929) (xy 380.407452 -236.700063) (xy 380.3566 -236.698014) (xy 380.306736 -236.687834)
			(xy 380.25915 -236.669787) (xy 380.215076 -236.644341) (xy 380.175654 -236.612154) (xy 380.141906 -236.57406)
			(xy 380.114705 -236.531046) (xy 380.094757 -236.484226) (xy 380.082578 -236.434812) (xy 380.078483 -236.384084)
			(xy 379.77064 -236.384084) (xy 379.770128 -236.40953) (xy 379.761964 -236.459764) (xy 379.745848 -236.508038)
			(xy 379.722197 -236.553101) (xy 379.691624 -236.593787) (xy 379.65492 -236.629042) (xy 379.613036 -236.657952)
			(xy 379.567057 -236.679769) (xy 379.518173 -236.693929) (xy 379.467652 -236.700063) (xy 379.4168 -236.698014)
			(xy 379.366936 -236.687834) (xy 379.31935 -236.669787) (xy 379.275276 -236.644341) (xy 379.235854 -236.612154)
			(xy 379.202106 -236.57406) (xy 379.174905 -236.531046) (xy 379.154957 -236.484226) (xy 379.142778 -236.434812)
			(xy 379.138683 -236.384084) (xy 378.820172 -236.384084) (xy 378.819677 -236.408691) (xy 378.811782 -236.457268)
			(xy 378.796198 -236.503949) (xy 378.773327 -236.547526) (xy 378.743762 -236.58687) (xy 378.708269 -236.620962)
			(xy 378.667766 -236.648918) (xy 378.623304 -236.670016) (xy 378.576033 -236.683708) (xy 378.527178 -236.68964)
			(xy 378.478003 -236.687659) (xy 378.429784 -236.677815) (xy 378.383768 -236.660363) (xy 378.341147 -236.635756)
			(xy 378.303026 -236.604631) (xy 378.270391 -236.567794) (xy 378.244088 -236.526198) (xy 378.224797 -236.480922)
			(xy 378.21302 -236.433138) (xy 378.20906 -236.384084) (xy 377.890532 -236.384084) (xy 377.89002 -236.40953)
			(xy 377.881856 -236.459764) (xy 377.86574 -236.508038) (xy 377.842089 -236.553101) (xy 377.811516 -236.593787)
			(xy 377.774812 -236.629042) (xy 377.732928 -236.657952) (xy 377.686949 -236.679769) (xy 377.638065 -236.693929)
			(xy 377.587544 -236.700063) (xy 377.536692 -236.698014) (xy 377.486828 -236.687834) (xy 377.439242 -236.669787)
			(xy 377.395168 -236.644341) (xy 377.355746 -236.612154) (xy 377.321998 -236.57406) (xy 377.294797 -236.531046)
			(xy 377.274849 -236.484226) (xy 377.26267 -236.434812) (xy 377.258575 -236.384084) (xy 376.940064 -236.384084)
			(xy 376.939569 -236.408691) (xy 376.931674 -236.457268) (xy 376.91609 -236.503949) (xy 376.893219 -236.547526)
			(xy 376.863654 -236.58687) (xy 376.828161 -236.620962) (xy 376.787658 -236.648918) (xy 376.743196 -236.670016)
			(xy 376.695925 -236.683708) (xy 376.64707 -236.68964) (xy 376.597895 -236.687659) (xy 376.549676 -236.677815)
			(xy 376.50366 -236.660363) (xy 376.461039 -236.635756) (xy 376.422918 -236.604631) (xy 376.390283 -236.567794)
			(xy 376.36398 -236.526198) (xy 376.344689 -236.480922) (xy 376.332912 -236.433138) (xy 376.328952 -236.384084)
			(xy 376.010424 -236.384084) (xy 376.009912 -236.40953) (xy 376.001748 -236.459764) (xy 375.985632 -236.508038)
			(xy 375.961981 -236.553101) (xy 375.931408 -236.593787) (xy 375.894704 -236.629042) (xy 375.85282 -236.657952)
			(xy 375.806841 -236.679769) (xy 375.757957 -236.693929) (xy 375.707436 -236.700063) (xy 375.656584 -236.698014)
			(xy 375.60672 -236.687834) (xy 375.559134 -236.669787) (xy 375.51506 -236.644341) (xy 375.475638 -236.612154)
			(xy 375.44189 -236.57406) (xy 375.414689 -236.531046) (xy 375.394741 -236.484226) (xy 375.382562 -236.434812)
			(xy 375.378467 -236.384084) (xy 375.11863 -236.384084) (xy 375.11863 -236.787182) (xy 375.119069 -236.797245)
			(xy 375.126807 -236.815825) (xy 375.133616 -236.82325) (xy 375.184924 -236.87405) (xy 375.192337 -236.880725)
			(xy 375.210773 -236.888291) (xy 375.220738 -236.888782) (xy 375.224802 -236.888782) (xy 375.250058 -236.889304)
			(xy 375.299881 -236.897618) (xy 375.347656 -236.91402) (xy 375.39208 -236.938061) (xy 375.431941 -236.969086)
			(xy 375.466152 -237.006249) (xy 375.493779 -237.048536) (xy 375.51407 -237.094794) (xy 375.52647 -237.14376)
			(xy 375.53064 -237.19409) (xy 375.848621 -237.19409) (xy 375.852716 -237.143362) (xy 375.864895 -237.093948)
			(xy 375.884843 -237.047128) (xy 375.912044 -237.004114) (xy 375.945792 -236.96602) (xy 375.985214 -236.933833)
			(xy 376.029288 -236.908387) (xy 376.076874 -236.89034) (xy 376.126738 -236.88016) (xy 376.17759 -236.878111)
			(xy 376.228111 -236.884245) (xy 376.276995 -236.898405) (xy 376.322974 -236.920222) (xy 376.364858 -236.949132)
			(xy 376.401562 -236.984387) (xy 376.432135 -237.025073) (xy 376.455786 -237.070136) (xy 376.471902 -237.11841)
			(xy 376.480066 -237.168644) (xy 376.480578 -237.19409) (xy 376.788675 -237.19409) (xy 376.79277 -237.143362)
			(xy 376.804949 -237.093948) (xy 376.824897 -237.047128) (xy 376.852098 -237.004114) (xy 376.885846 -236.96602)
			(xy 376.925268 -236.933833) (xy 376.969342 -236.908387) (xy 377.016928 -236.89034) (xy 377.066792 -236.88016)
			(xy 377.117644 -236.878111) (xy 377.168165 -236.884245) (xy 377.217049 -236.898405) (xy 377.263028 -236.920222)
			(xy 377.304912 -236.949132) (xy 377.341616 -236.984387) (xy 377.372189 -237.025073) (xy 377.39584 -237.070136)
			(xy 377.411956 -237.11841) (xy 377.42012 -237.168644) (xy 377.420632 -237.19409) (xy 378.668529 -237.19409)
			(xy 378.672624 -237.143362) (xy 378.684803 -237.093948) (xy 378.704751 -237.047128) (xy 378.731952 -237.004114)
			(xy 378.7657 -236.96602) (xy 378.805122 -236.933833) (xy 378.849196 -236.908387) (xy 378.896782 -236.89034)
			(xy 378.946646 -236.88016) (xy 378.997498 -236.878111) (xy 379.048019 -236.884245) (xy 379.096903 -236.898405)
			(xy 379.142882 -236.920222) (xy 379.184766 -236.949132) (xy 379.22147 -236.984387) (xy 379.252043 -237.025073)
			(xy 379.275694 -237.070136) (xy 379.29181 -237.11841) (xy 379.299974 -237.168644) (xy 379.300486 -237.19409)
			(xy 379.619014 -237.19409) (xy 379.622974 -237.145036) (xy 379.634751 -237.097252) (xy 379.654042 -237.051976)
			(xy 379.680345 -237.01038) (xy 379.71298 -236.973543) (xy 379.751101 -236.942418) (xy 379.793722 -236.917811)
			(xy 379.839738 -236.900359) (xy 379.887957 -236.890515) (xy 379.937132 -236.888534) (xy 379.985987 -236.894466)
			(xy 380.033258 -236.908158) (xy 380.07772 -236.929256) (xy 380.118223 -236.957212) (xy 380.153716 -236.991304)
			(xy 380.183281 -237.030648) (xy 380.206152 -237.074225) (xy 380.221736 -237.120906) (xy 380.229631 -237.169483)
			(xy 380.230126 -237.19409) (xy 380.548637 -237.19409) (xy 380.552732 -237.143362) (xy 380.564911 -237.093948)
			(xy 380.584859 -237.047128) (xy 380.61206 -237.004114) (xy 380.645808 -236.96602) (xy 380.68523 -236.933833)
			(xy 380.729304 -236.908387) (xy 380.77689 -236.89034) (xy 380.826754 -236.88016) (xy 380.877606 -236.878111)
			(xy 380.928127 -236.884245) (xy 380.977011 -236.898405) (xy 381.02299 -236.920222) (xy 381.064874 -236.949132)
			(xy 381.101578 -236.984387) (xy 381.132151 -237.025073) (xy 381.155802 -237.070136) (xy 381.171918 -237.11841)
			(xy 381.180082 -237.168644) (xy 381.180594 -237.19409) (xy 381.180082 -237.219536) (xy 381.171918 -237.26977)
			(xy 381.155802 -237.318044) (xy 381.132151 -237.363107) (xy 381.101578 -237.403793) (xy 381.064874 -237.439048)
			(xy 381.02299 -237.467958) (xy 380.977011 -237.489775) (xy 380.928127 -237.503935) (xy 380.877606 -237.510069)
			(xy 380.826754 -237.50802) (xy 380.77689 -237.49784) (xy 380.729304 -237.479793) (xy 380.68523 -237.454347)
			(xy 380.645808 -237.42216) (xy 380.61206 -237.384066) (xy 380.584859 -237.341052) (xy 380.564911 -237.294232)
			(xy 380.552732 -237.244818) (xy 380.548637 -237.19409) (xy 380.230126 -237.19409) (xy 380.229631 -237.218697)
			(xy 380.221736 -237.267274) (xy 380.206152 -237.313955) (xy 380.183281 -237.357532) (xy 380.153716 -237.396876)
			(xy 380.118223 -237.430968) (xy 380.07772 -237.458924) (xy 380.033258 -237.480022) (xy 379.985987 -237.493714)
			(xy 379.937132 -237.499646) (xy 379.887957 -237.497665) (xy 379.839738 -237.487821) (xy 379.793722 -237.470369)
			(xy 379.751101 -237.445762) (xy 379.71298 -237.414637) (xy 379.680345 -237.3778) (xy 379.654042 -237.336204)
			(xy 379.634751 -237.290928) (xy 379.622974 -237.243144) (xy 379.619014 -237.19409) (xy 379.300486 -237.19409)
			(xy 379.299974 -237.219536) (xy 379.29181 -237.26977) (xy 379.275694 -237.318044) (xy 379.252043 -237.363107)
			(xy 379.22147 -237.403793) (xy 379.184766 -237.439048) (xy 379.142882 -237.467958) (xy 379.096903 -237.489775)
			(xy 379.048019 -237.503935) (xy 378.997498 -237.510069) (xy 378.946646 -237.50802) (xy 378.896782 -237.49784)
			(xy 378.849196 -237.479793) (xy 378.805122 -237.454347) (xy 378.7657 -237.42216) (xy 378.731952 -237.384066)
			(xy 378.704751 -237.341052) (xy 378.684803 -237.294232) (xy 378.672624 -237.244818) (xy 378.668529 -237.19409)
			(xy 377.420632 -237.19409) (xy 377.42012 -237.219536) (xy 377.411956 -237.26977) (xy 377.39584 -237.318044)
			(xy 377.372189 -237.363107) (xy 377.341616 -237.403793) (xy 377.304912 -237.439048) (xy 377.263028 -237.467958)
			(xy 377.217049 -237.489775) (xy 377.168165 -237.503935) (xy 377.117644 -237.510069) (xy 377.066792 -237.50802)
			(xy 377.016928 -237.49784) (xy 376.969342 -237.479793) (xy 376.925268 -237.454347) (xy 376.885846 -237.42216)
			(xy 376.852098 -237.384066) (xy 376.824897 -237.341052) (xy 376.804949 -237.294232) (xy 376.79277 -237.244818)
			(xy 376.788675 -237.19409) (xy 376.480578 -237.19409) (xy 376.480066 -237.219536) (xy 376.471902 -237.26977)
			(xy 376.455786 -237.318044) (xy 376.432135 -237.363107) (xy 376.401562 -237.403793) (xy 376.364858 -237.439048)
			(xy 376.322974 -237.467958) (xy 376.276995 -237.489775) (xy 376.228111 -237.503935) (xy 376.17759 -237.510069)
			(xy 376.126738 -237.50802) (xy 376.076874 -237.49784) (xy 376.029288 -237.479793) (xy 375.985214 -237.454347)
			(xy 375.945792 -237.42216) (xy 375.912044 -237.384066) (xy 375.884843 -237.341052) (xy 375.864895 -237.294232)
			(xy 375.852716 -237.244818) (xy 375.848621 -237.19409) (xy 375.53064 -237.19409) (xy 375.530641 -237.1941)
			(xy 375.52647 -237.24444) (xy 375.51407 -237.293406) (xy 375.493779 -237.339664) (xy 375.466152 -237.381951)
			(xy 375.431941 -237.419114) (xy 375.39208 -237.450139) (xy 375.347656 -237.47418) (xy 375.299881 -237.490582)
			(xy 375.250058 -237.498896) (xy 375.224802 -237.499398) (xy 375.220738 -237.499398) (xy 375.210775 -237.499883)
			(xy 375.19235 -237.50747) (xy 375.184924 -237.51413) (xy 375.133616 -237.56493) (xy 375.126773 -237.572329)
			(xy 375.119046 -237.590928) (xy 375.11863 -237.600998) (xy 375.11863 -238.004096) (xy 375.378467 -238.004096)
			(xy 375.382562 -237.953368) (xy 375.394741 -237.903954) (xy 375.414689 -237.857134) (xy 375.44189 -237.81412)
			(xy 375.475638 -237.776026) (xy 375.51506 -237.743839) (xy 375.559134 -237.718393) (xy 375.60672 -237.700346)
			(xy 375.656584 -237.690166) (xy 375.707436 -237.688117) (xy 375.757957 -237.694251) (xy 375.806841 -237.708411)
			(xy 375.85282 -237.730228) (xy 375.894704 -237.759138) (xy 375.931408 -237.794393) (xy 375.961981 -237.835079)
			(xy 375.985632 -237.880142) (xy 376.001748 -237.928416) (xy 376.009912 -237.97865) (xy 376.010424 -238.004096)
			(xy 376.328952 -238.004096) (xy 376.332912 -237.955042) (xy 376.344689 -237.907258) (xy 376.36398 -237.861982)
			(xy 376.390283 -237.820386) (xy 376.422918 -237.783549) (xy 376.461039 -237.752424) (xy 376.50366 -237.727817)
			(xy 376.549676 -237.710365) (xy 376.597895 -237.700521) (xy 376.64707 -237.69854) (xy 376.695925 -237.704472)
			(xy 376.743196 -237.718164) (xy 376.787658 -237.739262) (xy 376.828161 -237.767218) (xy 376.863654 -237.80131)
			(xy 376.893219 -237.840654) (xy 376.91609 -237.884231) (xy 376.931674 -237.930912) (xy 376.939569 -237.979489)
			(xy 376.940064 -238.004096) (xy 377.258575 -238.004096) (xy 377.26267 -237.953368) (xy 377.274849 -237.903954)
			(xy 377.294797 -237.857134) (xy 377.321998 -237.81412) (xy 377.355746 -237.776026) (xy 377.395168 -237.743839)
			(xy 377.439242 -237.718393) (xy 377.486828 -237.700346) (xy 377.536692 -237.690166) (xy 377.587544 -237.688117)
			(xy 377.638065 -237.694251) (xy 377.686949 -237.708411) (xy 377.732928 -237.730228) (xy 377.774812 -237.759138)
			(xy 377.811516 -237.794393) (xy 377.842089 -237.835079) (xy 377.86574 -237.880142) (xy 377.881856 -237.928416)
			(xy 377.89002 -237.97865) (xy 377.890532 -238.004096) (xy 378.20906 -238.004096) (xy 378.21302 -237.955042)
			(xy 378.224797 -237.907258) (xy 378.244088 -237.861982) (xy 378.270391 -237.820386) (xy 378.303026 -237.783549)
			(xy 378.341147 -237.752424) (xy 378.383768 -237.727817) (xy 378.429784 -237.710365) (xy 378.478003 -237.700521)
			(xy 378.527178 -237.69854) (xy 378.576033 -237.704472) (xy 378.623304 -237.718164) (xy 378.667766 -237.739262)
			(xy 378.708269 -237.767218) (xy 378.743762 -237.80131) (xy 378.773327 -237.840654) (xy 378.796198 -237.884231)
			(xy 378.811782 -237.930912) (xy 378.819677 -237.979489) (xy 378.820172 -238.004096) (xy 379.138683 -238.004096)
			(xy 379.142778 -237.953368) (xy 379.154957 -237.903954) (xy 379.174905 -237.857134) (xy 379.202106 -237.81412)
			(xy 379.235854 -237.776026) (xy 379.275276 -237.743839) (xy 379.31935 -237.718393) (xy 379.366936 -237.700346)
			(xy 379.4168 -237.690166) (xy 379.467652 -237.688117) (xy 379.518173 -237.694251) (xy 379.567057 -237.708411)
			(xy 379.613036 -237.730228) (xy 379.65492 -237.759138) (xy 379.691624 -237.794393) (xy 379.722197 -237.835079)
			(xy 379.745848 -237.880142) (xy 379.761964 -237.928416) (xy 379.770128 -237.97865) (xy 379.77064 -238.004096)
			(xy 380.078483 -238.004096) (xy 380.082578 -237.953368) (xy 380.094757 -237.903954) (xy 380.114705 -237.857134)
			(xy 380.141906 -237.81412) (xy 380.175654 -237.776026) (xy 380.215076 -237.743839) (xy 380.25915 -237.718393)
			(xy 380.306736 -237.700346) (xy 380.3566 -237.690166) (xy 380.407452 -237.688117) (xy 380.457973 -237.694251)
			(xy 380.506857 -237.708411) (xy 380.552836 -237.730228) (xy 380.59472 -237.759138) (xy 380.631424 -237.794393)
			(xy 380.661997 -237.835079) (xy 380.685648 -237.880142) (xy 380.701764 -237.928416) (xy 380.709928 -237.97865)
			(xy 380.71044 -238.004096) (xy 380.709928 -238.029542) (xy 380.701764 -238.079776) (xy 380.685648 -238.12805)
			(xy 380.661997 -238.173113) (xy 380.631424 -238.213799) (xy 380.59472 -238.249054) (xy 380.552836 -238.277964)
			(xy 380.506857 -238.299781) (xy 380.457973 -238.313941) (xy 380.407452 -238.320075) (xy 380.3566 -238.318026)
			(xy 380.306736 -238.307846) (xy 380.25915 -238.289799) (xy 380.215076 -238.264353) (xy 380.175654 -238.232166)
			(xy 380.141906 -238.194072) (xy 380.114705 -238.151058) (xy 380.094757 -238.104238) (xy 380.082578 -238.054824)
			(xy 380.078483 -238.004096) (xy 379.77064 -238.004096) (xy 379.770128 -238.029542) (xy 379.761964 -238.079776)
			(xy 379.745848 -238.12805) (xy 379.722197 -238.173113) (xy 379.691624 -238.213799) (xy 379.65492 -238.249054)
			(xy 379.613036 -238.277964) (xy 379.567057 -238.299781) (xy 379.518173 -238.313941) (xy 379.467652 -238.320075)
			(xy 379.4168 -238.318026) (xy 379.366936 -238.307846) (xy 379.31935 -238.289799) (xy 379.275276 -238.264353)
			(xy 379.235854 -238.232166) (xy 379.202106 -238.194072) (xy 379.174905 -238.151058) (xy 379.154957 -238.104238)
			(xy 379.142778 -238.054824) (xy 379.138683 -238.004096) (xy 378.820172 -238.004096) (xy 378.819677 -238.028703)
			(xy 378.811782 -238.07728) (xy 378.796198 -238.123961) (xy 378.773327 -238.167538) (xy 378.743762 -238.206882)
			(xy 378.708269 -238.240974) (xy 378.667766 -238.26893) (xy 378.623304 -238.290028) (xy 378.576033 -238.30372)
			(xy 378.527178 -238.309652) (xy 378.478003 -238.307671) (xy 378.429784 -238.297827) (xy 378.383768 -238.280375)
			(xy 378.341147 -238.255768) (xy 378.303026 -238.224643) (xy 378.270391 -238.187806) (xy 378.244088 -238.14621)
			(xy 378.224797 -238.100934) (xy 378.21302 -238.05315) (xy 378.20906 -238.004096) (xy 377.890532 -238.004096)
			(xy 377.89002 -238.029542) (xy 377.881856 -238.079776) (xy 377.86574 -238.12805) (xy 377.842089 -238.173113)
			(xy 377.811516 -238.213799) (xy 377.774812 -238.249054) (xy 377.732928 -238.277964) (xy 377.686949 -238.299781)
			(xy 377.638065 -238.313941) (xy 377.587544 -238.320075) (xy 377.536692 -238.318026) (xy 377.486828 -238.307846)
			(xy 377.439242 -238.289799) (xy 377.395168 -238.264353) (xy 377.355746 -238.232166) (xy 377.321998 -238.194072)
			(xy 377.294797 -238.151058) (xy 377.274849 -238.104238) (xy 377.26267 -238.054824) (xy 377.258575 -238.004096)
			(xy 376.940064 -238.004096) (xy 376.939569 -238.028703) (xy 376.931674 -238.07728) (xy 376.91609 -238.123961)
			(xy 376.893219 -238.167538) (xy 376.863654 -238.206882) (xy 376.828161 -238.240974) (xy 376.787658 -238.26893)
			(xy 376.743196 -238.290028) (xy 376.695925 -238.30372) (xy 376.64707 -238.309652) (xy 376.597895 -238.307671)
			(xy 376.549676 -238.297827) (xy 376.50366 -238.280375) (xy 376.461039 -238.255768) (xy 376.422918 -238.224643)
			(xy 376.390283 -238.187806) (xy 376.36398 -238.14621) (xy 376.344689 -238.100934) (xy 376.332912 -238.05315)
			(xy 376.328952 -238.004096) (xy 376.010424 -238.004096) (xy 376.009912 -238.029542) (xy 376.001748 -238.079776)
			(xy 375.985632 -238.12805) (xy 375.961981 -238.173113) (xy 375.931408 -238.213799) (xy 375.894704 -238.249054)
			(xy 375.85282 -238.277964) (xy 375.806841 -238.299781) (xy 375.757957 -238.313941) (xy 375.707436 -238.320075)
			(xy 375.656584 -238.318026) (xy 375.60672 -238.307846) (xy 375.559134 -238.289799) (xy 375.51506 -238.264353)
			(xy 375.475638 -238.232166) (xy 375.44189 -238.194072) (xy 375.414689 -238.151058) (xy 375.394741 -238.104238)
			(xy 375.382562 -238.054824) (xy 375.378467 -238.004096) (xy 375.11863 -238.004096) (xy 375.11863 -238.407194)
			(xy 375.119053 -238.417264) (xy 375.126769 -238.435867) (xy 375.133616 -238.443262) (xy 375.184924 -238.494062)
			(xy 375.192295 -238.500804) (xy 375.210756 -238.508394) (xy 375.220738 -238.508794) (xy 375.224802 -238.508794)
			(xy 375.250057 -238.509316) (xy 375.299878 -238.51763) (xy 375.347651 -238.534031) (xy 375.392074 -238.558071)
			(xy 375.431933 -238.589095) (xy 375.466143 -238.626257) (xy 375.493769 -238.668542) (xy 375.514058 -238.714798)
			(xy 375.526458 -238.763762) (xy 375.530629 -238.8141) (xy 375.530629 -238.814102) (xy 375.848621 -238.814102)
			(xy 375.852716 -238.763374) (xy 375.864895 -238.71396) (xy 375.884843 -238.66714) (xy 375.912044 -238.624126)
			(xy 375.945792 -238.586032) (xy 375.985214 -238.553845) (xy 376.029288 -238.528399) (xy 376.076874 -238.510352)
			(xy 376.126738 -238.500172) (xy 376.17759 -238.498123) (xy 376.228111 -238.504257) (xy 376.276995 -238.518417)
			(xy 376.322974 -238.540234) (xy 376.364858 -238.569144) (xy 376.401562 -238.604399) (xy 376.432135 -238.645085)
			(xy 376.455786 -238.690148) (xy 376.471902 -238.738422) (xy 376.480066 -238.788656) (xy 376.480578 -238.814102)
			(xy 376.788675 -238.814102) (xy 376.79277 -238.763374) (xy 376.804949 -238.71396) (xy 376.824897 -238.66714)
			(xy 376.852098 -238.624126) (xy 376.885846 -238.586032) (xy 376.925268 -238.553845) (xy 376.969342 -238.528399)
			(xy 377.016928 -238.510352) (xy 377.066792 -238.500172) (xy 377.117644 -238.498123) (xy 377.168165 -238.504257)
			(xy 377.217049 -238.518417) (xy 377.263028 -238.540234) (xy 377.304912 -238.569144) (xy 377.341616 -238.604399)
			(xy 377.372189 -238.645085) (xy 377.39584 -238.690148) (xy 377.411956 -238.738422) (xy 377.42012 -238.788656)
			(xy 377.420632 -238.814102) (xy 377.738906 -238.814102) (xy 377.742866 -238.765048) (xy 377.754643 -238.717264)
			(xy 377.773934 -238.671988) (xy 377.800237 -238.630392) (xy 377.832872 -238.593555) (xy 377.870993 -238.56243)
			(xy 377.913614 -238.537823) (xy 377.95963 -238.520371) (xy 378.007849 -238.510527) (xy 378.057024 -238.508546)
			(xy 378.105879 -238.514478) (xy 378.15315 -238.52817) (xy 378.197612 -238.549268) (xy 378.238115 -238.577224)
			(xy 378.273608 -238.611316) (xy 378.303173 -238.65066) (xy 378.326044 -238.694237) (xy 378.341628 -238.740918)
			(xy 378.349523 -238.789495) (xy 378.350018 -238.814102) (xy 378.668529 -238.814102) (xy 378.672624 -238.763374)
			(xy 378.684803 -238.71396) (xy 378.704751 -238.66714) (xy 378.731952 -238.624126) (xy 378.7657 -238.586032)
			(xy 378.805122 -238.553845) (xy 378.849196 -238.528399) (xy 378.896782 -238.510352) (xy 378.946646 -238.500172)
			(xy 378.997498 -238.498123) (xy 379.048019 -238.504257) (xy 379.096903 -238.518417) (xy 379.142882 -238.540234)
			(xy 379.184766 -238.569144) (xy 379.22147 -238.604399) (xy 379.252043 -238.645085) (xy 379.275694 -238.690148)
			(xy 379.29181 -238.738422) (xy 379.299974 -238.788656) (xy 379.300486 -238.814102) (xy 379.619014 -238.814102)
			(xy 379.622974 -238.765048) (xy 379.634751 -238.717264) (xy 379.654042 -238.671988) (xy 379.680345 -238.630392)
			(xy 379.71298 -238.593555) (xy 379.751101 -238.56243) (xy 379.793722 -238.537823) (xy 379.839738 -238.520371)
			(xy 379.887957 -238.510527) (xy 379.937132 -238.508546) (xy 379.985987 -238.514478) (xy 380.033258 -238.52817)
			(xy 380.07772 -238.549268) (xy 380.118223 -238.577224) (xy 380.153716 -238.611316) (xy 380.183281 -238.65066)
			(xy 380.206152 -238.694237) (xy 380.221736 -238.740918) (xy 380.229631 -238.789495) (xy 380.230126 -238.814102)
			(xy 380.548637 -238.814102) (xy 380.552732 -238.763374) (xy 380.564911 -238.71396) (xy 380.584859 -238.66714)
			(xy 380.61206 -238.624126) (xy 380.645808 -238.586032) (xy 380.68523 -238.553845) (xy 380.729304 -238.528399)
			(xy 380.77689 -238.510352) (xy 380.826754 -238.500172) (xy 380.877606 -238.498123) (xy 380.928127 -238.504257)
			(xy 380.977011 -238.518417) (xy 381.02299 -238.540234) (xy 381.064874 -238.569144) (xy 381.101578 -238.604399)
			(xy 381.132151 -238.645085) (xy 381.155802 -238.690148) (xy 381.171918 -238.738422) (xy 381.180082 -238.788656)
			(xy 381.180594 -238.814102) (xy 381.180082 -238.839548) (xy 381.171918 -238.889782) (xy 381.155802 -238.938056)
			(xy 381.132151 -238.983119) (xy 381.101578 -239.023805) (xy 381.064874 -239.05906) (xy 381.02299 -239.08797)
			(xy 380.977011 -239.109787) (xy 380.928127 -239.123947) (xy 380.877606 -239.130081) (xy 380.826754 -239.128032)
			(xy 380.77689 -239.117852) (xy 380.729304 -239.099805) (xy 380.68523 -239.074359) (xy 380.645808 -239.042172)
			(xy 380.61206 -239.004078) (xy 380.584859 -238.961064) (xy 380.564911 -238.914244) (xy 380.552732 -238.86483)
			(xy 380.548637 -238.814102) (xy 380.230126 -238.814102) (xy 380.229631 -238.838709) (xy 380.221736 -238.887286)
			(xy 380.206152 -238.933967) (xy 380.183281 -238.977544) (xy 380.153716 -239.016888) (xy 380.118223 -239.05098)
			(xy 380.07772 -239.078936) (xy 380.033258 -239.100034) (xy 379.985987 -239.113726) (xy 379.937132 -239.119658)
			(xy 379.887957 -239.117677) (xy 379.839738 -239.107833) (xy 379.793722 -239.090381) (xy 379.751101 -239.065774)
			(xy 379.71298 -239.034649) (xy 379.680345 -238.997812) (xy 379.654042 -238.956216) (xy 379.634751 -238.91094)
			(xy 379.622974 -238.863156) (xy 379.619014 -238.814102) (xy 379.300486 -238.814102) (xy 379.299974 -238.839548)
			(xy 379.29181 -238.889782) (xy 379.275694 -238.938056) (xy 379.252043 -238.983119) (xy 379.22147 -239.023805)
			(xy 379.184766 -239.05906) (xy 379.142882 -239.08797) (xy 379.096903 -239.109787) (xy 379.048019 -239.123947)
			(xy 378.997498 -239.130081) (xy 378.946646 -239.128032) (xy 378.896782 -239.117852) (xy 378.849196 -239.099805)
			(xy 378.805122 -239.074359) (xy 378.7657 -239.042172) (xy 378.731952 -239.004078) (xy 378.704751 -238.961064)
			(xy 378.684803 -238.914244) (xy 378.672624 -238.86483) (xy 378.668529 -238.814102) (xy 378.350018 -238.814102)
			(xy 378.349523 -238.838709) (xy 378.341628 -238.887286) (xy 378.326044 -238.933967) (xy 378.303173 -238.977544)
			(xy 378.273608 -239.016888) (xy 378.238115 -239.05098) (xy 378.197612 -239.078936) (xy 378.15315 -239.100034)
			(xy 378.105879 -239.113726) (xy 378.057024 -239.119658) (xy 378.007849 -239.117677) (xy 377.95963 -239.107833)
			(xy 377.913614 -239.090381) (xy 377.870993 -239.065774) (xy 377.832872 -239.034649) (xy 377.800237 -238.997812)
			(xy 377.773934 -238.956216) (xy 377.754643 -238.91094) (xy 377.742866 -238.863156) (xy 377.738906 -238.814102)
			(xy 377.420632 -238.814102) (xy 377.42012 -238.839548) (xy 377.411956 -238.889782) (xy 377.39584 -238.938056)
			(xy 377.372189 -238.983119) (xy 377.341616 -239.023805) (xy 377.304912 -239.05906) (xy 377.263028 -239.08797)
			(xy 377.217049 -239.109787) (xy 377.168165 -239.123947) (xy 377.117644 -239.130081) (xy 377.066792 -239.128032)
			(xy 377.016928 -239.117852) (xy 376.969342 -239.099805) (xy 376.925268 -239.074359) (xy 376.885846 -239.042172)
			(xy 376.852098 -239.004078) (xy 376.824897 -238.961064) (xy 376.804949 -238.914244) (xy 376.79277 -238.86483)
			(xy 376.788675 -238.814102) (xy 376.480578 -238.814102) (xy 376.480066 -238.839548) (xy 376.471902 -238.889782)
			(xy 376.455786 -238.938056) (xy 376.432135 -238.983119) (xy 376.401562 -239.023805) (xy 376.364858 -239.05906)
			(xy 376.322974 -239.08797) (xy 376.276995 -239.109787) (xy 376.228111 -239.123947) (xy 376.17759 -239.130081)
			(xy 376.126738 -239.128032) (xy 376.076874 -239.117852) (xy 376.029288 -239.099805) (xy 375.985214 -239.074359)
			(xy 375.945792 -239.042172) (xy 375.912044 -239.004078) (xy 375.884843 -238.961064) (xy 375.864895 -238.914244)
			(xy 375.852716 -238.86483) (xy 375.848621 -238.814102) (xy 375.530629 -238.814102) (xy 375.526458 -238.864438)
			(xy 375.514058 -238.913402) (xy 375.493769 -238.959658) (xy 375.466143 -239.001943) (xy 375.431933 -239.039105)
			(xy 375.392074 -239.070129) (xy 375.347651 -239.094169) (xy 375.299878 -239.11057) (xy 375.250057 -239.118884)
			(xy 375.224802 -239.11941) (xy 375.220738 -239.11941) (xy 375.210776 -239.119896) (xy 375.192351 -239.127483)
			(xy 375.184924 -239.134142) (xy 375.133616 -239.184942) (xy 375.126774 -239.192342) (xy 375.119053 -239.21094)
			(xy 375.11863 -239.22101) (xy 375.11863 -239.624108) (xy 375.378467 -239.624108) (xy 375.382562 -239.57338)
			(xy 375.394741 -239.523966) (xy 375.414689 -239.477146) (xy 375.44189 -239.434132) (xy 375.475638 -239.396038)
			(xy 375.51506 -239.363851) (xy 375.559134 -239.338405) (xy 375.60672 -239.320358) (xy 375.656584 -239.310178)
			(xy 375.707436 -239.308129) (xy 375.757957 -239.314263) (xy 375.806841 -239.328423) (xy 375.85282 -239.35024)
			(xy 375.894704 -239.37915) (xy 375.931408 -239.414405) (xy 375.961981 -239.455091) (xy 375.985632 -239.500154)
			(xy 376.001748 -239.548428) (xy 376.009912 -239.598662) (xy 376.010424 -239.624108) (xy 376.328952 -239.624108)
			(xy 376.332912 -239.575054) (xy 376.344689 -239.52727) (xy 376.36398 -239.481994) (xy 376.390283 -239.440398)
			(xy 376.422918 -239.403561) (xy 376.461039 -239.372436) (xy 376.50366 -239.347829) (xy 376.549676 -239.330377)
			(xy 376.597895 -239.320533) (xy 376.64707 -239.318552) (xy 376.695925 -239.324484) (xy 376.743196 -239.338176)
			(xy 376.787658 -239.359274) (xy 376.828161 -239.38723) (xy 376.863654 -239.421322) (xy 376.893219 -239.460666)
			(xy 376.91609 -239.504243) (xy 376.931674 -239.550924) (xy 376.939569 -239.599501) (xy 376.940064 -239.624108)
			(xy 377.258575 -239.624108) (xy 377.26267 -239.57338) (xy 377.274849 -239.523966) (xy 377.294797 -239.477146)
			(xy 377.321998 -239.434132) (xy 377.355746 -239.396038) (xy 377.395168 -239.363851) (xy 377.439242 -239.338405)
			(xy 377.486828 -239.320358) (xy 377.536692 -239.310178) (xy 377.587544 -239.308129) (xy 377.638065 -239.314263)
			(xy 377.686949 -239.328423) (xy 377.732928 -239.35024) (xy 377.774812 -239.37915) (xy 377.811516 -239.414405)
			(xy 377.842089 -239.455091) (xy 377.86574 -239.500154) (xy 377.881856 -239.548428) (xy 377.89002 -239.598662)
			(xy 377.890532 -239.624108) (xy 379.138683 -239.624108) (xy 379.142778 -239.57338) (xy 379.154957 -239.523966)
			(xy 379.174905 -239.477146) (xy 379.202106 -239.434132) (xy 379.235854 -239.396038) (xy 379.275276 -239.363851)
			(xy 379.31935 -239.338405) (xy 379.366936 -239.320358) (xy 379.4168 -239.310178) (xy 379.467652 -239.308129)
			(xy 379.518173 -239.314263) (xy 379.567057 -239.328423) (xy 379.613036 -239.35024) (xy 379.65492 -239.37915)
			(xy 379.691624 -239.414405) (xy 379.722197 -239.455091) (xy 379.745848 -239.500154) (xy 379.761964 -239.548428)
			(xy 379.770128 -239.598662) (xy 379.77064 -239.624108) (xy 380.078483 -239.624108) (xy 380.082578 -239.57338)
			(xy 380.094757 -239.523966) (xy 380.114705 -239.477146) (xy 380.141906 -239.434132) (xy 380.175654 -239.396038)
			(xy 380.215076 -239.363851) (xy 380.25915 -239.338405) (xy 380.306736 -239.320358) (xy 380.3566 -239.310178)
			(xy 380.407452 -239.308129) (xy 380.457973 -239.314263) (xy 380.506857 -239.328423) (xy 380.552836 -239.35024)
			(xy 380.59472 -239.37915) (xy 380.631424 -239.414405) (xy 380.661997 -239.455091) (xy 380.685648 -239.500154)
			(xy 380.701764 -239.548428) (xy 380.709928 -239.598662) (xy 380.71044 -239.624108) (xy 380.709928 -239.649554)
			(xy 380.701764 -239.699788) (xy 380.685648 -239.748062) (xy 380.661997 -239.793125) (xy 380.631424 -239.833811)
			(xy 380.59472 -239.869066) (xy 380.552836 -239.897976) (xy 380.506857 -239.919793) (xy 380.457973 -239.933953)
			(xy 380.407452 -239.940087) (xy 380.3566 -239.938038) (xy 380.306736 -239.927858) (xy 380.25915 -239.909811)
			(xy 380.215076 -239.884365) (xy 380.175654 -239.852178) (xy 380.141906 -239.814084) (xy 380.114705 -239.77107)
			(xy 380.094757 -239.72425) (xy 380.082578 -239.674836) (xy 380.078483 -239.624108) (xy 379.77064 -239.624108)
			(xy 379.770128 -239.649554) (xy 379.761964 -239.699788) (xy 379.745848 -239.748062) (xy 379.722197 -239.793125)
			(xy 379.691624 -239.833811) (xy 379.65492 -239.869066) (xy 379.613036 -239.897976) (xy 379.567057 -239.919793)
			(xy 379.518173 -239.933953) (xy 379.467652 -239.940087) (xy 379.4168 -239.938038) (xy 379.366936 -239.927858)
			(xy 379.31935 -239.909811) (xy 379.275276 -239.884365) (xy 379.235854 -239.852178) (xy 379.202106 -239.814084)
			(xy 379.174905 -239.77107) (xy 379.154957 -239.72425) (xy 379.142778 -239.674836) (xy 379.138683 -239.624108)
			(xy 377.890532 -239.624108) (xy 377.89002 -239.649554) (xy 377.881856 -239.699788) (xy 377.86574 -239.748062)
			(xy 377.842089 -239.793125) (xy 377.811516 -239.833811) (xy 377.774812 -239.869066) (xy 377.732928 -239.897976)
			(xy 377.686949 -239.919793) (xy 377.638065 -239.933953) (xy 377.587544 -239.940087) (xy 377.536692 -239.938038)
			(xy 377.486828 -239.927858) (xy 377.439242 -239.909811) (xy 377.395168 -239.884365) (xy 377.355746 -239.852178)
			(xy 377.321998 -239.814084) (xy 377.294797 -239.77107) (xy 377.274849 -239.72425) (xy 377.26267 -239.674836)
			(xy 377.258575 -239.624108) (xy 376.940064 -239.624108) (xy 376.939569 -239.648715) (xy 376.931674 -239.697292)
			(xy 376.91609 -239.743973) (xy 376.893219 -239.78755) (xy 376.863654 -239.826894) (xy 376.828161 -239.860986)
			(xy 376.787658 -239.888942) (xy 376.743196 -239.91004) (xy 376.695925 -239.923732) (xy 376.64707 -239.929664)
			(xy 376.597895 -239.927683) (xy 376.549676 -239.917839) (xy 376.50366 -239.900387) (xy 376.461039 -239.87578)
			(xy 376.422918 -239.844655) (xy 376.390283 -239.807818) (xy 376.36398 -239.766222) (xy 376.344689 -239.720946)
			(xy 376.332912 -239.673162) (xy 376.328952 -239.624108) (xy 376.010424 -239.624108) (xy 376.009912 -239.649554)
			(xy 376.001748 -239.699788) (xy 375.985632 -239.748062) (xy 375.961981 -239.793125) (xy 375.931408 -239.833811)
			(xy 375.894704 -239.869066) (xy 375.85282 -239.897976) (xy 375.806841 -239.919793) (xy 375.757957 -239.933953)
			(xy 375.707436 -239.940087) (xy 375.656584 -239.938038) (xy 375.60672 -239.927858) (xy 375.559134 -239.909811)
			(xy 375.51506 -239.884365) (xy 375.475638 -239.852178) (xy 375.44189 -239.814084) (xy 375.414689 -239.77107)
			(xy 375.394741 -239.72425) (xy 375.382562 -239.674836) (xy 375.378467 -239.624108) (xy 375.11863 -239.624108)
			(xy 375.11863 -240.434114) (xy 375.848621 -240.434114) (xy 375.852716 -240.383386) (xy 375.864895 -240.333972)
			(xy 375.884843 -240.287152) (xy 375.912044 -240.244138) (xy 375.945792 -240.206044) (xy 375.985214 -240.173857)
			(xy 376.029288 -240.148411) (xy 376.076874 -240.130364) (xy 376.126738 -240.120184) (xy 376.17759 -240.118135)
			(xy 376.228111 -240.124269) (xy 376.276995 -240.138429) (xy 376.322974 -240.160246) (xy 376.364858 -240.189156)
			(xy 376.401562 -240.224411) (xy 376.432135 -240.265097) (xy 376.455786 -240.31016) (xy 376.471902 -240.358434)
			(xy 376.480066 -240.408668) (xy 376.480578 -240.434114) (xy 376.788675 -240.434114) (xy 376.79277 -240.383386)
			(xy 376.804949 -240.333972) (xy 376.824897 -240.287152) (xy 376.852098 -240.244138) (xy 376.885846 -240.206044)
			(xy 376.925268 -240.173857) (xy 376.969342 -240.148411) (xy 377.016928 -240.130364) (xy 377.066792 -240.120184)
			(xy 377.117644 -240.118135) (xy 377.168165 -240.124269) (xy 377.217049 -240.138429) (xy 377.263028 -240.160246)
			(xy 377.304912 -240.189156) (xy 377.341616 -240.224411) (xy 377.372189 -240.265097) (xy 377.39584 -240.31016)
			(xy 377.411956 -240.358434) (xy 377.42012 -240.408668) (xy 377.420632 -240.434114) (xy 377.738906 -240.434114)
			(xy 377.742866 -240.38506) (xy 377.754643 -240.337276) (xy 377.773934 -240.292) (xy 377.800237 -240.250404)
			(xy 377.832872 -240.213567) (xy 377.870993 -240.182442) (xy 377.913614 -240.157835) (xy 377.95963 -240.140383)
			(xy 378.007849 -240.130539) (xy 378.057024 -240.128558) (xy 378.105879 -240.13449) (xy 378.15315 -240.148182)
			(xy 378.197612 -240.16928) (xy 378.238115 -240.197236) (xy 378.273608 -240.231328) (xy 378.303173 -240.270672)
			(xy 378.326044 -240.314249) (xy 378.341628 -240.36093) (xy 378.349523 -240.409507) (xy 378.350018 -240.434114)
			(xy 378.668529 -240.434114) (xy 378.672624 -240.383386) (xy 378.684803 -240.333972) (xy 378.704751 -240.287152)
			(xy 378.731952 -240.244138) (xy 378.7657 -240.206044) (xy 378.805122 -240.173857) (xy 378.849196 -240.148411)
			(xy 378.896782 -240.130364) (xy 378.946646 -240.120184) (xy 378.997498 -240.118135) (xy 379.048019 -240.124269)
			(xy 379.096903 -240.138429) (xy 379.142882 -240.160246) (xy 379.184766 -240.189156) (xy 379.22147 -240.224411)
			(xy 379.252043 -240.265097) (xy 379.275694 -240.31016) (xy 379.29181 -240.358434) (xy 379.299974 -240.408668)
			(xy 379.300486 -240.434114) (xy 379.619014 -240.434114) (xy 379.622974 -240.38506) (xy 379.634751 -240.337276)
			(xy 379.654042 -240.292) (xy 379.680345 -240.250404) (xy 379.71298 -240.213567) (xy 379.751101 -240.182442)
			(xy 379.793722 -240.157835) (xy 379.839738 -240.140383) (xy 379.887957 -240.130539) (xy 379.937132 -240.128558)
			(xy 379.985987 -240.13449) (xy 380.033258 -240.148182) (xy 380.07772 -240.16928) (xy 380.118223 -240.197236)
			(xy 380.153716 -240.231328) (xy 380.183281 -240.270672) (xy 380.206152 -240.314249) (xy 380.221736 -240.36093)
			(xy 380.229631 -240.409507) (xy 380.230126 -240.434114) (xy 380.548637 -240.434114) (xy 380.552732 -240.383386)
			(xy 380.564911 -240.333972) (xy 380.584859 -240.287152) (xy 380.61206 -240.244138) (xy 380.645808 -240.206044)
			(xy 380.68523 -240.173857) (xy 380.729304 -240.148411) (xy 380.77689 -240.130364) (xy 380.826754 -240.120184)
			(xy 380.877606 -240.118135) (xy 380.928127 -240.124269) (xy 380.977011 -240.138429) (xy 381.02299 -240.160246)
			(xy 381.064874 -240.189156) (xy 381.101578 -240.224411) (xy 381.132151 -240.265097) (xy 381.155802 -240.31016)
			(xy 381.171918 -240.358434) (xy 381.180082 -240.408668) (xy 381.180594 -240.434114) (xy 381.180082 -240.45956)
			(xy 381.171918 -240.509794) (xy 381.155802 -240.558068) (xy 381.132151 -240.603131) (xy 381.101578 -240.643817)
			(xy 381.064874 -240.679072) (xy 381.02299 -240.707982) (xy 380.977011 -240.729799) (xy 380.928127 -240.743959)
			(xy 380.877606 -240.750093) (xy 380.826754 -240.748044) (xy 380.77689 -240.737864) (xy 380.729304 -240.719817)
			(xy 380.68523 -240.694371) (xy 380.645808 -240.662184) (xy 380.61206 -240.62409) (xy 380.584859 -240.581076)
			(xy 380.564911 -240.534256) (xy 380.552732 -240.484842) (xy 380.548637 -240.434114) (xy 380.230126 -240.434114)
			(xy 380.229631 -240.458721) (xy 380.221736 -240.507298) (xy 380.206152 -240.553979) (xy 380.183281 -240.597556)
			(xy 380.153716 -240.6369) (xy 380.118223 -240.670992) (xy 380.07772 -240.698948) (xy 380.033258 -240.720046)
			(xy 379.985987 -240.733738) (xy 379.937132 -240.73967) (xy 379.887957 -240.737689) (xy 379.839738 -240.727845)
			(xy 379.793722 -240.710393) (xy 379.751101 -240.685786) (xy 379.71298 -240.654661) (xy 379.680345 -240.617824)
			(xy 379.654042 -240.576228) (xy 379.634751 -240.530952) (xy 379.622974 -240.483168) (xy 379.619014 -240.434114)
			(xy 379.300486 -240.434114) (xy 379.299974 -240.45956) (xy 379.29181 -240.509794) (xy 379.275694 -240.558068)
			(xy 379.252043 -240.603131) (xy 379.22147 -240.643817) (xy 379.184766 -240.679072) (xy 379.142882 -240.707982)
			(xy 379.096903 -240.729799) (xy 379.048019 -240.743959) (xy 378.997498 -240.750093) (xy 378.946646 -240.748044)
			(xy 378.896782 -240.737864) (xy 378.849196 -240.719817) (xy 378.805122 -240.694371) (xy 378.7657 -240.662184)
			(xy 378.731952 -240.62409) (xy 378.704751 -240.581076) (xy 378.684803 -240.534256) (xy 378.672624 -240.484842)
			(xy 378.668529 -240.434114) (xy 378.350018 -240.434114) (xy 378.349523 -240.458721) (xy 378.341628 -240.507298)
			(xy 378.326044 -240.553979) (xy 378.303173 -240.597556) (xy 378.273608 -240.6369) (xy 378.238115 -240.670992)
			(xy 378.197612 -240.698948) (xy 378.15315 -240.720046) (xy 378.105879 -240.733738) (xy 378.057024 -240.73967)
			(xy 378.007849 -240.737689) (xy 377.95963 -240.727845) (xy 377.913614 -240.710393) (xy 377.870993 -240.685786)
			(xy 377.832872 -240.654661) (xy 377.800237 -240.617824) (xy 377.773934 -240.576228) (xy 377.754643 -240.530952)
			(xy 377.742866 -240.483168) (xy 377.738906 -240.434114) (xy 377.420632 -240.434114) (xy 377.42012 -240.45956)
			(xy 377.411956 -240.509794) (xy 377.39584 -240.558068) (xy 377.372189 -240.603131) (xy 377.341616 -240.643817)
			(xy 377.304912 -240.679072) (xy 377.263028 -240.707982) (xy 377.217049 -240.729799) (xy 377.168165 -240.743959)
			(xy 377.117644 -240.750093) (xy 377.066792 -240.748044) (xy 377.016928 -240.737864) (xy 376.969342 -240.719817)
			(xy 376.925268 -240.694371) (xy 376.885846 -240.662184) (xy 376.852098 -240.62409) (xy 376.824897 -240.581076)
			(xy 376.804949 -240.534256) (xy 376.79277 -240.484842) (xy 376.788675 -240.434114) (xy 376.480578 -240.434114)
			(xy 376.480066 -240.45956) (xy 376.471902 -240.509794) (xy 376.455786 -240.558068) (xy 376.432135 -240.603131)
			(xy 376.401562 -240.643817) (xy 376.364858 -240.679072) (xy 376.322974 -240.707982) (xy 376.276995 -240.729799)
			(xy 376.228111 -240.743959) (xy 376.17759 -240.750093) (xy 376.126738 -240.748044) (xy 376.076874 -240.737864)
			(xy 376.029288 -240.719817) (xy 375.985214 -240.694371) (xy 375.945792 -240.662184) (xy 375.912044 -240.62409)
			(xy 375.884843 -240.581076) (xy 375.864895 -240.534256) (xy 375.852716 -240.484842) (xy 375.848621 -240.434114)
			(xy 375.11863 -240.434114) (xy 375.11863 -241.24412) (xy 375.378467 -241.24412) (xy 375.382562 -241.193392)
			(xy 375.394741 -241.143978) (xy 375.414689 -241.097158) (xy 375.44189 -241.054144) (xy 375.475638 -241.01605)
			(xy 375.51506 -240.983863) (xy 375.559134 -240.958417) (xy 375.60672 -240.94037) (xy 375.656584 -240.93019)
			(xy 375.707436 -240.928141) (xy 375.757957 -240.934275) (xy 375.806841 -240.948435) (xy 375.85282 -240.970252)
			(xy 375.894704 -240.999162) (xy 375.931408 -241.034417) (xy 375.961981 -241.075103) (xy 375.985632 -241.120166)
			(xy 376.001748 -241.16844) (xy 376.009912 -241.218674) (xy 376.010424 -241.24412) (xy 376.328952 -241.24412)
			(xy 376.332912 -241.195066) (xy 376.344689 -241.147282) (xy 376.36398 -241.102006) (xy 376.390283 -241.06041)
			(xy 376.422918 -241.023573) (xy 376.461039 -240.992448) (xy 376.50366 -240.967841) (xy 376.549676 -240.950389)
			(xy 376.597895 -240.940545) (xy 376.64707 -240.938564) (xy 376.695925 -240.944496) (xy 376.743196 -240.958188)
			(xy 376.787658 -240.979286) (xy 376.828161 -241.007242) (xy 376.863654 -241.041334) (xy 376.893219 -241.080678)
			(xy 376.91609 -241.124255) (xy 376.931674 -241.170936) (xy 376.939569 -241.219513) (xy 376.940064 -241.24412)
			(xy 377.258575 -241.24412) (xy 377.26267 -241.193392) (xy 377.274849 -241.143978) (xy 377.294797 -241.097158)
			(xy 377.321998 -241.054144) (xy 377.355746 -241.01605) (xy 377.395168 -240.983863) (xy 377.439242 -240.958417)
			(xy 377.486828 -240.94037) (xy 377.536692 -240.93019) (xy 377.587544 -240.928141) (xy 377.638065 -240.934275)
			(xy 377.686949 -240.948435) (xy 377.732928 -240.970252) (xy 377.774812 -240.999162) (xy 377.811516 -241.034417)
			(xy 377.842089 -241.075103) (xy 377.86574 -241.120166) (xy 377.881856 -241.16844) (xy 377.89002 -241.218674)
			(xy 377.890532 -241.24412) (xy 378.20906 -241.24412) (xy 378.21302 -241.195066) (xy 378.224797 -241.147282)
			(xy 378.244088 -241.102006) (xy 378.270391 -241.06041) (xy 378.303026 -241.023573) (xy 378.341147 -240.992448)
			(xy 378.383768 -240.967841) (xy 378.429784 -240.950389) (xy 378.478003 -240.940545) (xy 378.527178 -240.938564)
			(xy 378.576033 -240.944496) (xy 378.623304 -240.958188) (xy 378.667766 -240.979286) (xy 378.708269 -241.007242)
			(xy 378.743762 -241.041334) (xy 378.773327 -241.080678) (xy 378.796198 -241.124255) (xy 378.811782 -241.170936)
			(xy 378.819677 -241.219513) (xy 378.820172 -241.24412) (xy 379.138683 -241.24412) (xy 379.142778 -241.193392)
			(xy 379.154957 -241.143978) (xy 379.174905 -241.097158) (xy 379.202106 -241.054144) (xy 379.235854 -241.01605)
			(xy 379.275276 -240.983863) (xy 379.31935 -240.958417) (xy 379.366936 -240.94037) (xy 379.4168 -240.93019)
			(xy 379.467652 -240.928141) (xy 379.518173 -240.934275) (xy 379.567057 -240.948435) (xy 379.613036 -240.970252)
			(xy 379.65492 -240.999162) (xy 379.691624 -241.034417) (xy 379.722197 -241.075103) (xy 379.745848 -241.120166)
			(xy 379.761964 -241.16844) (xy 379.770128 -241.218674) (xy 379.77064 -241.24412) (xy 380.078483 -241.24412)
			(xy 380.082578 -241.193392) (xy 380.094757 -241.143978) (xy 380.114705 -241.097158) (xy 380.141906 -241.054144)
			(xy 380.175654 -241.01605) (xy 380.215076 -240.983863) (xy 380.25915 -240.958417) (xy 380.306736 -240.94037)
			(xy 380.3566 -240.93019) (xy 380.407452 -240.928141) (xy 380.457973 -240.934275) (xy 380.506857 -240.948435)
			(xy 380.552836 -240.970252) (xy 380.59472 -240.999162) (xy 380.631424 -241.034417) (xy 380.661997 -241.075103)
			(xy 380.685648 -241.120166) (xy 380.701764 -241.16844) (xy 380.709928 -241.218674) (xy 380.71044 -241.24412)
			(xy 380.709928 -241.269566) (xy 380.701764 -241.3198) (xy 380.685648 -241.368074) (xy 380.661997 -241.413137)
			(xy 380.631424 -241.453823) (xy 380.59472 -241.489078) (xy 380.552836 -241.517988) (xy 380.506857 -241.539805)
			(xy 380.457973 -241.553965) (xy 380.407452 -241.560099) (xy 380.3566 -241.55805) (xy 380.306736 -241.54787)
			(xy 380.25915 -241.529823) (xy 380.215076 -241.504377) (xy 380.175654 -241.47219) (xy 380.141906 -241.434096)
			(xy 380.114705 -241.391082) (xy 380.094757 -241.344262) (xy 380.082578 -241.294848) (xy 380.078483 -241.24412)
			(xy 379.77064 -241.24412) (xy 379.770128 -241.269566) (xy 379.761964 -241.3198) (xy 379.745848 -241.368074)
			(xy 379.722197 -241.413137) (xy 379.691624 -241.453823) (xy 379.65492 -241.489078) (xy 379.613036 -241.517988)
			(xy 379.567057 -241.539805) (xy 379.518173 -241.553965) (xy 379.467652 -241.560099) (xy 379.4168 -241.55805)
			(xy 379.366936 -241.54787) (xy 379.31935 -241.529823) (xy 379.275276 -241.504377) (xy 379.235854 -241.47219)
			(xy 379.202106 -241.434096) (xy 379.174905 -241.391082) (xy 379.154957 -241.344262) (xy 379.142778 -241.294848)
			(xy 379.138683 -241.24412) (xy 378.820172 -241.24412) (xy 378.819677 -241.268727) (xy 378.811782 -241.317304)
			(xy 378.796198 -241.363985) (xy 378.773327 -241.407562) (xy 378.743762 -241.446906) (xy 378.708269 -241.480998)
			(xy 378.667766 -241.508954) (xy 378.623304 -241.530052) (xy 378.576033 -241.543744) (xy 378.527178 -241.549676)
			(xy 378.478003 -241.547695) (xy 378.429784 -241.537851) (xy 378.383768 -241.520399) (xy 378.341147 -241.495792)
			(xy 378.303026 -241.464667) (xy 378.270391 -241.42783) (xy 378.244088 -241.386234) (xy 378.224797 -241.340958)
			(xy 378.21302 -241.293174) (xy 378.20906 -241.24412) (xy 377.890532 -241.24412) (xy 377.89002 -241.269566)
			(xy 377.881856 -241.3198) (xy 377.86574 -241.368074) (xy 377.842089 -241.413137) (xy 377.811516 -241.453823)
			(xy 377.774812 -241.489078) (xy 377.732928 -241.517988) (xy 377.686949 -241.539805) (xy 377.638065 -241.553965)
			(xy 377.587544 -241.560099) (xy 377.536692 -241.55805) (xy 377.486828 -241.54787) (xy 377.439242 -241.529823)
			(xy 377.395168 -241.504377) (xy 377.355746 -241.47219) (xy 377.321998 -241.434096) (xy 377.294797 -241.391082)
			(xy 377.274849 -241.344262) (xy 377.26267 -241.294848) (xy 377.258575 -241.24412) (xy 376.940064 -241.24412)
			(xy 376.939569 -241.268727) (xy 376.931674 -241.317304) (xy 376.91609 -241.363985) (xy 376.893219 -241.407562)
			(xy 376.863654 -241.446906) (xy 376.828161 -241.480998) (xy 376.787658 -241.508954) (xy 376.743196 -241.530052)
			(xy 376.695925 -241.543744) (xy 376.64707 -241.549676) (xy 376.597895 -241.547695) (xy 376.549676 -241.537851)
			(xy 376.50366 -241.520399) (xy 376.461039 -241.495792) (xy 376.422918 -241.464667) (xy 376.390283 -241.42783)
			(xy 376.36398 -241.386234) (xy 376.344689 -241.340958) (xy 376.332912 -241.293174) (xy 376.328952 -241.24412)
			(xy 376.010424 -241.24412) (xy 376.009912 -241.269566) (xy 376.001748 -241.3198) (xy 375.985632 -241.368074)
			(xy 375.961981 -241.413137) (xy 375.931408 -241.453823) (xy 375.894704 -241.489078) (xy 375.85282 -241.517988)
			(xy 375.806841 -241.539805) (xy 375.757957 -241.553965) (xy 375.707436 -241.560099) (xy 375.656584 -241.55805)
			(xy 375.60672 -241.54787) (xy 375.559134 -241.529823) (xy 375.51506 -241.504377) (xy 375.475638 -241.47219)
			(xy 375.44189 -241.434096) (xy 375.414689 -241.391082) (xy 375.394741 -241.344262) (xy 375.382562 -241.294848)
			(xy 375.378467 -241.24412) (xy 375.11863 -241.24412) (xy 375.11863 -241.647218) (xy 375.119057 -241.657286)
			(xy 375.126779 -241.675883) (xy 375.133616 -241.683286) (xy 375.184924 -241.734086) (xy 375.192334 -241.740768)
			(xy 375.210771 -241.748343) (xy 375.220738 -241.748818) (xy 375.224802 -241.748818) (xy 375.250055 -241.74934)
			(xy 375.299872 -241.757653) (xy 375.347642 -241.774053) (xy 375.392061 -241.798091) (xy 375.431917 -241.829113)
			(xy 375.466124 -241.866271) (xy 375.493748 -241.908553) (xy 375.514036 -241.954806) (xy 375.526434 -242.003766)
			(xy 375.530605 -242.0541) (xy 375.530603 -242.054126) (xy 375.848621 -242.054126) (xy 375.852716 -242.003398)
			(xy 375.864895 -241.953984) (xy 375.884843 -241.907164) (xy 375.912044 -241.86415) (xy 375.945792 -241.826056)
			(xy 375.985214 -241.793869) (xy 376.029288 -241.768423) (xy 376.076874 -241.750376) (xy 376.126738 -241.740196)
			(xy 376.17759 -241.738147) (xy 376.228111 -241.744281) (xy 376.276995 -241.758441) (xy 376.322974 -241.780258)
			(xy 376.364858 -241.809168) (xy 376.401562 -241.844423) (xy 376.432135 -241.885109) (xy 376.455786 -241.930172)
			(xy 376.471902 -241.978446) (xy 376.480066 -242.02868) (xy 376.480578 -242.054126) (xy 376.788675 -242.054126)
			(xy 376.79277 -242.003398) (xy 376.804949 -241.953984) (xy 376.824897 -241.907164) (xy 376.852098 -241.86415)
			(xy 376.885846 -241.826056) (xy 376.925268 -241.793869) (xy 376.969342 -241.768423) (xy 377.016928 -241.750376)
			(xy 377.066792 -241.740196) (xy 377.117644 -241.738147) (xy 377.168165 -241.744281) (xy 377.217049 -241.758441)
			(xy 377.263028 -241.780258) (xy 377.304912 -241.809168) (xy 377.341616 -241.844423) (xy 377.372189 -241.885109)
			(xy 377.39584 -241.930172) (xy 377.411956 -241.978446) (xy 377.42012 -242.02868) (xy 377.420632 -242.054126)
			(xy 378.668529 -242.054126) (xy 378.672624 -242.003398) (xy 378.684803 -241.953984) (xy 378.704751 -241.907164)
			(xy 378.731952 -241.86415) (xy 378.7657 -241.826056) (xy 378.805122 -241.793869) (xy 378.849196 -241.768423)
			(xy 378.896782 -241.750376) (xy 378.946646 -241.740196) (xy 378.997498 -241.738147) (xy 379.048019 -241.744281)
			(xy 379.096903 -241.758441) (xy 379.142882 -241.780258) (xy 379.184766 -241.809168) (xy 379.22147 -241.844423)
			(xy 379.252043 -241.885109) (xy 379.275694 -241.930172) (xy 379.29181 -241.978446) (xy 379.299974 -242.02868)
			(xy 379.300486 -242.054126) (xy 379.619014 -242.054126) (xy 379.622974 -242.005072) (xy 379.634751 -241.957288)
			(xy 379.654042 -241.912012) (xy 379.680345 -241.870416) (xy 379.71298 -241.833579) (xy 379.751101 -241.802454)
			(xy 379.793722 -241.777847) (xy 379.839738 -241.760395) (xy 379.887957 -241.750551) (xy 379.937132 -241.74857)
			(xy 379.985987 -241.754502) (xy 380.033258 -241.768194) (xy 380.07772 -241.789292) (xy 380.118223 -241.817248)
			(xy 380.153716 -241.85134) (xy 380.183281 -241.890684) (xy 380.206152 -241.934261) (xy 380.221736 -241.980942)
			(xy 380.229631 -242.029519) (xy 380.230126 -242.054126) (xy 380.548637 -242.054126) (xy 380.552732 -242.003398)
			(xy 380.564911 -241.953984) (xy 380.584859 -241.907164) (xy 380.61206 -241.86415) (xy 380.645808 -241.826056)
			(xy 380.68523 -241.793869) (xy 380.729304 -241.768423) (xy 380.77689 -241.750376) (xy 380.826754 -241.740196)
			(xy 380.877606 -241.738147) (xy 380.928127 -241.744281) (xy 380.977011 -241.758441) (xy 381.02299 -241.780258)
			(xy 381.064874 -241.809168) (xy 381.101578 -241.844423) (xy 381.132151 -241.885109) (xy 381.155802 -241.930172)
			(xy 381.171918 -241.978446) (xy 381.180082 -242.02868) (xy 381.180594 -242.054126) (xy 381.180082 -242.079572)
			(xy 381.171918 -242.129806) (xy 381.155802 -242.17808) (xy 381.132151 -242.223143) (xy 381.101578 -242.263829)
			(xy 381.064874 -242.299084) (xy 381.02299 -242.327994) (xy 380.977011 -242.349811) (xy 380.928127 -242.363971)
			(xy 380.877606 -242.370105) (xy 380.826754 -242.368056) (xy 380.77689 -242.357876) (xy 380.729304 -242.339829)
			(xy 380.68523 -242.314383) (xy 380.645808 -242.282196) (xy 380.61206 -242.244102) (xy 380.584859 -242.201088)
			(xy 380.564911 -242.154268) (xy 380.552732 -242.104854) (xy 380.548637 -242.054126) (xy 380.230126 -242.054126)
			(xy 380.229631 -242.078733) (xy 380.221736 -242.12731) (xy 380.206152 -242.173991) (xy 380.183281 -242.217568)
			(xy 380.153716 -242.256912) (xy 380.118223 -242.291004) (xy 380.07772 -242.31896) (xy 380.033258 -242.340058)
			(xy 379.985987 -242.35375) (xy 379.937132 -242.359682) (xy 379.887957 -242.357701) (xy 379.839738 -242.347857)
			(xy 379.793722 -242.330405) (xy 379.751101 -242.305798) (xy 379.71298 -242.274673) (xy 379.680345 -242.237836)
			(xy 379.654042 -242.19624) (xy 379.634751 -242.150964) (xy 379.622974 -242.10318) (xy 379.619014 -242.054126)
			(xy 379.300486 -242.054126) (xy 379.299974 -242.079572) (xy 379.29181 -242.129806) (xy 379.275694 -242.17808)
			(xy 379.252043 -242.223143) (xy 379.22147 -242.263829) (xy 379.184766 -242.299084) (xy 379.142882 -242.327994)
			(xy 379.096903 -242.349811) (xy 379.048019 -242.363971) (xy 378.997498 -242.370105) (xy 378.946646 -242.368056)
			(xy 378.896782 -242.357876) (xy 378.849196 -242.339829) (xy 378.805122 -242.314383) (xy 378.7657 -242.282196)
			(xy 378.731952 -242.244102) (xy 378.704751 -242.201088) (xy 378.684803 -242.154268) (xy 378.672624 -242.104854)
			(xy 378.668529 -242.054126) (xy 377.420632 -242.054126) (xy 377.42012 -242.079572) (xy 377.411956 -242.129806)
			(xy 377.39584 -242.17808) (xy 377.372189 -242.223143) (xy 377.341616 -242.263829) (xy 377.304912 -242.299084)
			(xy 377.263028 -242.327994) (xy 377.217049 -242.349811) (xy 377.168165 -242.363971) (xy 377.117644 -242.370105)
			(xy 377.066792 -242.368056) (xy 377.016928 -242.357876) (xy 376.969342 -242.339829) (xy 376.925268 -242.314383)
			(xy 376.885846 -242.282196) (xy 376.852098 -242.244102) (xy 376.824897 -242.201088) (xy 376.804949 -242.154268)
			(xy 376.79277 -242.104854) (xy 376.788675 -242.054126) (xy 376.480578 -242.054126) (xy 376.480066 -242.079572)
			(xy 376.471902 -242.129806) (xy 376.455786 -242.17808) (xy 376.432135 -242.223143) (xy 376.401562 -242.263829)
			(xy 376.364858 -242.299084) (xy 376.322974 -242.327994) (xy 376.276995 -242.349811) (xy 376.228111 -242.363971)
			(xy 376.17759 -242.370105) (xy 376.126738 -242.368056) (xy 376.076874 -242.357876) (xy 376.029288 -242.339829)
			(xy 375.985214 -242.314383) (xy 375.945792 -242.282196) (xy 375.912044 -242.244102) (xy 375.884843 -242.201088)
			(xy 375.864895 -242.154268) (xy 375.852716 -242.104854) (xy 375.848621 -242.054126) (xy 375.530603 -242.054126)
			(xy 375.526434 -242.104434) (xy 375.514036 -242.153394) (xy 375.493748 -242.199647) (xy 375.466124 -242.241929)
			(xy 375.431917 -242.279087) (xy 375.392061 -242.310109) (xy 375.347642 -242.334147) (xy 375.299872 -242.350547)
			(xy 375.250055 -242.35886) (xy 375.224802 -242.359434) (xy 375.220738 -242.359434) (xy 375.210776 -242.359921)
			(xy 375.192354 -242.367511) (xy 375.184924 -242.374166) (xy 375.133616 -242.424966) (xy 375.126778 -242.432367)
			(xy 375.119065 -242.450966) (xy 375.11863 -242.461034) (xy 375.11863 -242.864132) (xy 375.378467 -242.864132)
			(xy 375.382562 -242.813404) (xy 375.394741 -242.76399) (xy 375.414689 -242.71717) (xy 375.44189 -242.674156)
			(xy 375.475638 -242.636062) (xy 375.51506 -242.603875) (xy 375.559134 -242.578429) (xy 375.60672 -242.560382)
			(xy 375.656584 -242.550202) (xy 375.707436 -242.548153) (xy 375.757957 -242.554287) (xy 375.806841 -242.568447)
			(xy 375.85282 -242.590264) (xy 375.894704 -242.619174) (xy 375.931408 -242.654429) (xy 375.961981 -242.695115)
			(xy 375.985632 -242.740178) (xy 376.001748 -242.788452) (xy 376.009912 -242.838686) (xy 376.010424 -242.864132)
			(xy 376.328952 -242.864132) (xy 376.332912 -242.815078) (xy 376.344689 -242.767294) (xy 376.36398 -242.722018)
			(xy 376.390283 -242.680422) (xy 376.422918 -242.643585) (xy 376.461039 -242.61246) (xy 376.50366 -242.587853)
			(xy 376.549676 -242.570401) (xy 376.597895 -242.560557) (xy 376.64707 -242.558576) (xy 376.695925 -242.564508)
			(xy 376.743196 -242.5782) (xy 376.787658 -242.599298) (xy 376.828161 -242.627254) (xy 376.863654 -242.661346)
			(xy 376.893219 -242.70069) (xy 376.91609 -242.744267) (xy 376.931674 -242.790948) (xy 376.939569 -242.839525)
			(xy 376.940064 -242.864132) (xy 377.258575 -242.864132) (xy 377.26267 -242.813404) (xy 377.274849 -242.76399)
			(xy 377.294797 -242.71717) (xy 377.321998 -242.674156) (xy 377.355746 -242.636062) (xy 377.395168 -242.603875)
			(xy 377.439242 -242.578429) (xy 377.486828 -242.560382) (xy 377.536692 -242.550202) (xy 377.587544 -242.548153)
			(xy 377.638065 -242.554287) (xy 377.686949 -242.568447) (xy 377.732928 -242.590264) (xy 377.774812 -242.619174)
			(xy 377.811516 -242.654429) (xy 377.842089 -242.695115) (xy 377.86574 -242.740178) (xy 377.881856 -242.788452)
			(xy 377.89002 -242.838686) (xy 377.890532 -242.864132) (xy 378.20906 -242.864132) (xy 378.21302 -242.815078)
			(xy 378.224797 -242.767294) (xy 378.244088 -242.722018) (xy 378.270391 -242.680422) (xy 378.303026 -242.643585)
			(xy 378.341147 -242.61246) (xy 378.383768 -242.587853) (xy 378.429784 -242.570401) (xy 378.478003 -242.560557)
			(xy 378.527178 -242.558576) (xy 378.576033 -242.564508) (xy 378.623304 -242.5782) (xy 378.667766 -242.599298)
			(xy 378.708269 -242.627254) (xy 378.743762 -242.661346) (xy 378.773327 -242.70069) (xy 378.796198 -242.744267)
			(xy 378.811782 -242.790948) (xy 378.819677 -242.839525) (xy 378.820172 -242.864132) (xy 379.138683 -242.864132)
			(xy 379.142778 -242.813404) (xy 379.154957 -242.76399) (xy 379.174905 -242.71717) (xy 379.202106 -242.674156)
			(xy 379.235854 -242.636062) (xy 379.275276 -242.603875) (xy 379.31935 -242.578429) (xy 379.366936 -242.560382)
			(xy 379.4168 -242.550202) (xy 379.467652 -242.548153) (xy 379.518173 -242.554287) (xy 379.567057 -242.568447)
			(xy 379.613036 -242.590264) (xy 379.65492 -242.619174) (xy 379.691624 -242.654429) (xy 379.722197 -242.695115)
			(xy 379.745848 -242.740178) (xy 379.761964 -242.788452) (xy 379.770128 -242.838686) (xy 379.77064 -242.864132)
			(xy 380.078483 -242.864132) (xy 380.082578 -242.813404) (xy 380.094757 -242.76399) (xy 380.114705 -242.71717)
			(xy 380.141906 -242.674156) (xy 380.175654 -242.636062) (xy 380.215076 -242.603875) (xy 380.25915 -242.578429)
			(xy 380.306736 -242.560382) (xy 380.3566 -242.550202) (xy 380.407452 -242.548153) (xy 380.457973 -242.554287)
			(xy 380.506857 -242.568447) (xy 380.552836 -242.590264) (xy 380.59472 -242.619174) (xy 380.631424 -242.654429)
			(xy 380.661997 -242.695115) (xy 380.685648 -242.740178) (xy 380.701764 -242.788452) (xy 380.709928 -242.838686)
			(xy 380.71044 -242.864132) (xy 380.709928 -242.889578) (xy 380.701764 -242.939812) (xy 380.685648 -242.988086)
			(xy 380.661997 -243.033149) (xy 380.631424 -243.073835) (xy 380.59472 -243.10909) (xy 380.552836 -243.138)
			(xy 380.506857 -243.159817) (xy 380.457973 -243.173977) (xy 380.407452 -243.180111) (xy 380.3566 -243.178062)
			(xy 380.306736 -243.167882) (xy 380.25915 -243.149835) (xy 380.215076 -243.124389) (xy 380.175654 -243.092202)
			(xy 380.141906 -243.054108) (xy 380.114705 -243.011094) (xy 380.094757 -242.964274) (xy 380.082578 -242.91486)
			(xy 380.078483 -242.864132) (xy 379.77064 -242.864132) (xy 379.770128 -242.889578) (xy 379.761964 -242.939812)
			(xy 379.745848 -242.988086) (xy 379.722197 -243.033149) (xy 379.691624 -243.073835) (xy 379.65492 -243.10909)
			(xy 379.613036 -243.138) (xy 379.567057 -243.159817) (xy 379.518173 -243.173977) (xy 379.467652 -243.180111)
			(xy 379.4168 -243.178062) (xy 379.366936 -243.167882) (xy 379.31935 -243.149835) (xy 379.275276 -243.124389)
			(xy 379.235854 -243.092202) (xy 379.202106 -243.054108) (xy 379.174905 -243.011094) (xy 379.154957 -242.964274)
			(xy 379.142778 -242.91486) (xy 379.138683 -242.864132) (xy 378.820172 -242.864132) (xy 378.819677 -242.888739)
			(xy 378.811782 -242.937316) (xy 378.796198 -242.983997) (xy 378.773327 -243.027574) (xy 378.743762 -243.066918)
			(xy 378.708269 -243.10101) (xy 378.667766 -243.128966) (xy 378.623304 -243.150064) (xy 378.576033 -243.163756)
			(xy 378.527178 -243.169688) (xy 378.478003 -243.167707) (xy 378.429784 -243.157863) (xy 378.383768 -243.140411)
			(xy 378.341147 -243.115804) (xy 378.303026 -243.084679) (xy 378.270391 -243.047842) (xy 378.244088 -243.006246)
			(xy 378.224797 -242.96097) (xy 378.21302 -242.913186) (xy 378.20906 -242.864132) (xy 377.890532 -242.864132)
			(xy 377.89002 -242.889578) (xy 377.881856 -242.939812) (xy 377.86574 -242.988086) (xy 377.842089 -243.033149)
			(xy 377.811516 -243.073835) (xy 377.774812 -243.10909) (xy 377.732928 -243.138) (xy 377.686949 -243.159817)
			(xy 377.638065 -243.173977) (xy 377.587544 -243.180111) (xy 377.536692 -243.178062) (xy 377.486828 -243.167882)
			(xy 377.439242 -243.149835) (xy 377.395168 -243.124389) (xy 377.355746 -243.092202) (xy 377.321998 -243.054108)
			(xy 377.294797 -243.011094) (xy 377.274849 -242.964274) (xy 377.26267 -242.91486) (xy 377.258575 -242.864132)
			(xy 376.940064 -242.864132) (xy 376.939569 -242.888739) (xy 376.931674 -242.937316) (xy 376.91609 -242.983997)
			(xy 376.893219 -243.027574) (xy 376.863654 -243.066918) (xy 376.828161 -243.10101) (xy 376.787658 -243.128966)
			(xy 376.743196 -243.150064) (xy 376.695925 -243.163756) (xy 376.64707 -243.169688) (xy 376.597895 -243.167707)
			(xy 376.549676 -243.157863) (xy 376.50366 -243.140411) (xy 376.461039 -243.115804) (xy 376.422918 -243.084679)
			(xy 376.390283 -243.047842) (xy 376.36398 -243.006246) (xy 376.344689 -242.96097) (xy 376.332912 -242.913186)
			(xy 376.328952 -242.864132) (xy 376.010424 -242.864132) (xy 376.009912 -242.889578) (xy 376.001748 -242.939812)
			(xy 375.985632 -242.988086) (xy 375.961981 -243.033149) (xy 375.931408 -243.073835) (xy 375.894704 -243.10909)
			(xy 375.85282 -243.138) (xy 375.806841 -243.159817) (xy 375.757957 -243.173977) (xy 375.707436 -243.180111)
			(xy 375.656584 -243.178062) (xy 375.60672 -243.167882) (xy 375.559134 -243.149835) (xy 375.51506 -243.124389)
			(xy 375.475638 -243.092202) (xy 375.44189 -243.054108) (xy 375.414689 -243.011094) (xy 375.394741 -242.964274)
			(xy 375.382562 -242.91486) (xy 375.378467 -242.864132) (xy 375.11863 -242.864132) (xy 375.11863 -243.674138)
			(xy 375.848621 -243.674138) (xy 375.852716 -243.62341) (xy 375.864895 -243.573996) (xy 375.884843 -243.527176)
			(xy 375.912044 -243.484162) (xy 375.945792 -243.446068) (xy 375.985214 -243.413881) (xy 376.029288 -243.388435)
			(xy 376.076874 -243.370388) (xy 376.126738 -243.360208) (xy 376.17759 -243.358159) (xy 376.228111 -243.364293)
			(xy 376.276995 -243.378453) (xy 376.322974 -243.40027) (xy 376.364858 -243.42918) (xy 376.401562 -243.464435)
			(xy 376.432135 -243.505121) (xy 376.455786 -243.550184) (xy 376.471902 -243.598458) (xy 376.480066 -243.648692)
			(xy 376.480578 -243.674138) (xy 376.788675 -243.674138) (xy 376.79277 -243.62341) (xy 376.804949 -243.573996)
			(xy 376.824897 -243.527176) (xy 376.852098 -243.484162) (xy 376.885846 -243.446068) (xy 376.925268 -243.413881)
			(xy 376.969342 -243.388435) (xy 377.016928 -243.370388) (xy 377.066792 -243.360208) (xy 377.117644 -243.358159)
			(xy 377.168165 -243.364293) (xy 377.217049 -243.378453) (xy 377.263028 -243.40027) (xy 377.304912 -243.42918)
			(xy 377.341616 -243.464435) (xy 377.372189 -243.505121) (xy 377.39584 -243.550184) (xy 377.411956 -243.598458)
			(xy 377.42012 -243.648692) (xy 377.420632 -243.674138) (xy 377.738906 -243.674138) (xy 377.742866 -243.625084)
			(xy 377.754643 -243.5773) (xy 377.773934 -243.532024) (xy 377.800237 -243.490428) (xy 377.832872 -243.453591)
			(xy 377.870993 -243.422466) (xy 377.913614 -243.397859) (xy 377.95963 -243.380407) (xy 378.007849 -243.370563)
			(xy 378.057024 -243.368582) (xy 378.105879 -243.374514) (xy 378.15315 -243.388206) (xy 378.197612 -243.409304)
			(xy 378.238115 -243.43726) (xy 378.273608 -243.471352) (xy 378.303173 -243.510696) (xy 378.326044 -243.554273)
			(xy 378.341628 -243.600954) (xy 378.349523 -243.649531) (xy 378.350018 -243.674138) (xy 378.668529 -243.674138)
			(xy 378.672624 -243.62341) (xy 378.684803 -243.573996) (xy 378.704751 -243.527176) (xy 378.731952 -243.484162)
			(xy 378.7657 -243.446068) (xy 378.805122 -243.413881) (xy 378.849196 -243.388435) (xy 378.896782 -243.370388)
			(xy 378.946646 -243.360208) (xy 378.997498 -243.358159) (xy 379.048019 -243.364293) (xy 379.096903 -243.378453)
			(xy 379.142882 -243.40027) (xy 379.184766 -243.42918) (xy 379.22147 -243.464435) (xy 379.252043 -243.505121)
			(xy 379.275694 -243.550184) (xy 379.29181 -243.598458) (xy 379.299974 -243.648692) (xy 379.300486 -243.674138)
			(xy 379.619014 -243.674138) (xy 379.622974 -243.625084) (xy 379.634751 -243.5773) (xy 379.654042 -243.532024)
			(xy 379.680345 -243.490428) (xy 379.71298 -243.453591) (xy 379.751101 -243.422466) (xy 379.793722 -243.397859)
			(xy 379.839738 -243.380407) (xy 379.887957 -243.370563) (xy 379.937132 -243.368582) (xy 379.985987 -243.374514)
			(xy 380.033258 -243.388206) (xy 380.07772 -243.409304) (xy 380.118223 -243.43726) (xy 380.153716 -243.471352)
			(xy 380.183281 -243.510696) (xy 380.206152 -243.554273) (xy 380.221736 -243.600954) (xy 380.229631 -243.649531)
			(xy 380.230126 -243.674138) (xy 380.548637 -243.674138) (xy 380.552732 -243.62341) (xy 380.564911 -243.573996)
			(xy 380.584859 -243.527176) (xy 380.61206 -243.484162) (xy 380.645808 -243.446068) (xy 380.68523 -243.413881)
			(xy 380.729304 -243.388435) (xy 380.77689 -243.370388) (xy 380.826754 -243.360208) (xy 380.877606 -243.358159)
			(xy 380.928127 -243.364293) (xy 380.977011 -243.378453) (xy 381.02299 -243.40027) (xy 381.064874 -243.42918)
			(xy 381.101578 -243.464435) (xy 381.132151 -243.505121) (xy 381.155802 -243.550184) (xy 381.171918 -243.598458)
			(xy 381.180082 -243.648692) (xy 381.180594 -243.674138) (xy 381.180082 -243.699584) (xy 381.171918 -243.749818)
			(xy 381.155802 -243.798092) (xy 381.132151 -243.843155) (xy 381.101578 -243.883841) (xy 381.064874 -243.919096)
			(xy 381.02299 -243.948006) (xy 380.977011 -243.969823) (xy 380.928127 -243.983983) (xy 380.877606 -243.990117)
			(xy 380.826754 -243.988068) (xy 380.77689 -243.977888) (xy 380.729304 -243.959841) (xy 380.68523 -243.934395)
			(xy 380.645808 -243.902208) (xy 380.61206 -243.864114) (xy 380.584859 -243.8211) (xy 380.564911 -243.77428)
			(xy 380.552732 -243.724866) (xy 380.548637 -243.674138) (xy 380.230126 -243.674138) (xy 380.229631 -243.698745)
			(xy 380.221736 -243.747322) (xy 380.206152 -243.794003) (xy 380.183281 -243.83758) (xy 380.153716 -243.876924)
			(xy 380.118223 -243.911016) (xy 380.07772 -243.938972) (xy 380.033258 -243.96007) (xy 379.985987 -243.973762)
			(xy 379.937132 -243.979694) (xy 379.887957 -243.977713) (xy 379.839738 -243.967869) (xy 379.793722 -243.950417)
			(xy 379.751101 -243.92581) (xy 379.71298 -243.894685) (xy 379.680345 -243.857848) (xy 379.654042 -243.816252)
			(xy 379.634751 -243.770976) (xy 379.622974 -243.723192) (xy 379.619014 -243.674138) (xy 379.300486 -243.674138)
			(xy 379.299974 -243.699584) (xy 379.29181 -243.749818) (xy 379.275694 -243.798092) (xy 379.252043 -243.843155)
			(xy 379.22147 -243.883841) (xy 379.184766 -243.919096) (xy 379.142882 -243.948006) (xy 379.096903 -243.969823)
			(xy 379.048019 -243.983983) (xy 378.997498 -243.990117) (xy 378.946646 -243.988068) (xy 378.896782 -243.977888)
			(xy 378.849196 -243.959841) (xy 378.805122 -243.934395) (xy 378.7657 -243.902208) (xy 378.731952 -243.864114)
			(xy 378.704751 -243.8211) (xy 378.684803 -243.77428) (xy 378.672624 -243.724866) (xy 378.668529 -243.674138)
			(xy 378.350018 -243.674138) (xy 378.349523 -243.698745) (xy 378.341628 -243.747322) (xy 378.326044 -243.794003)
			(xy 378.303173 -243.83758) (xy 378.273608 -243.876924) (xy 378.238115 -243.911016) (xy 378.197612 -243.938972)
			(xy 378.15315 -243.96007) (xy 378.105879 -243.973762) (xy 378.057024 -243.979694) (xy 378.007849 -243.977713)
			(xy 377.95963 -243.967869) (xy 377.913614 -243.950417) (xy 377.870993 -243.92581) (xy 377.832872 -243.894685)
			(xy 377.800237 -243.857848) (xy 377.773934 -243.816252) (xy 377.754643 -243.770976) (xy 377.742866 -243.723192)
			(xy 377.738906 -243.674138) (xy 377.420632 -243.674138) (xy 377.42012 -243.699584) (xy 377.411956 -243.749818)
			(xy 377.39584 -243.798092) (xy 377.372189 -243.843155) (xy 377.341616 -243.883841) (xy 377.304912 -243.919096)
			(xy 377.263028 -243.948006) (xy 377.217049 -243.969823) (xy 377.168165 -243.983983) (xy 377.117644 -243.990117)
			(xy 377.066792 -243.988068) (xy 377.016928 -243.977888) (xy 376.969342 -243.959841) (xy 376.925268 -243.934395)
			(xy 376.885846 -243.902208) (xy 376.852098 -243.864114) (xy 376.824897 -243.8211) (xy 376.804949 -243.77428)
			(xy 376.79277 -243.724866) (xy 376.788675 -243.674138) (xy 376.480578 -243.674138) (xy 376.480066 -243.699584)
			(xy 376.471902 -243.749818) (xy 376.455786 -243.798092) (xy 376.432135 -243.843155) (xy 376.401562 -243.883841)
			(xy 376.364858 -243.919096) (xy 376.322974 -243.948006) (xy 376.276995 -243.969823) (xy 376.228111 -243.983983)
			(xy 376.17759 -243.990117) (xy 376.126738 -243.988068) (xy 376.076874 -243.977888) (xy 376.029288 -243.959841)
			(xy 375.985214 -243.934395) (xy 375.945792 -243.902208) (xy 375.912044 -243.864114) (xy 375.884843 -243.8211)
			(xy 375.864895 -243.77428) (xy 375.852716 -243.724866) (xy 375.848621 -243.674138) (xy 375.11863 -243.674138)
			(xy 375.11863 -244.484144) (xy 375.378467 -244.484144) (xy 375.382562 -244.433416) (xy 375.394741 -244.384002)
			(xy 375.414689 -244.337182) (xy 375.44189 -244.294168) (xy 375.475638 -244.256074) (xy 375.51506 -244.223887)
			(xy 375.559134 -244.198441) (xy 375.60672 -244.180394) (xy 375.656584 -244.170214) (xy 375.707436 -244.168165)
			(xy 375.757957 -244.174299) (xy 375.806841 -244.188459) (xy 375.85282 -244.210276) (xy 375.894704 -244.239186)
			(xy 375.931408 -244.274441) (xy 375.961981 -244.315127) (xy 375.985632 -244.36019) (xy 376.001748 -244.408464)
			(xy 376.009912 -244.458698) (xy 376.010424 -244.484144) (xy 376.328952 -244.484144) (xy 376.332912 -244.43509)
			(xy 376.344689 -244.387306) (xy 376.36398 -244.34203) (xy 376.390283 -244.300434) (xy 376.422918 -244.263597)
			(xy 376.461039 -244.232472) (xy 376.50366 -244.207865) (xy 376.549676 -244.190413) (xy 376.597895 -244.180569)
			(xy 376.64707 -244.178588) (xy 376.695925 -244.18452) (xy 376.743196 -244.198212) (xy 376.787658 -244.21931)
			(xy 376.828161 -244.247266) (xy 376.863654 -244.281358) (xy 376.893219 -244.320702) (xy 376.91609 -244.364279)
			(xy 376.931674 -244.41096) (xy 376.939569 -244.459537) (xy 376.940064 -244.484144) (xy 377.258575 -244.484144)
			(xy 377.26267 -244.433416) (xy 377.274849 -244.384002) (xy 377.294797 -244.337182) (xy 377.321998 -244.294168)
			(xy 377.355746 -244.256074) (xy 377.395168 -244.223887) (xy 377.439242 -244.198441) (xy 377.486828 -244.180394)
			(xy 377.536692 -244.170214) (xy 377.587544 -244.168165) (xy 377.638065 -244.174299) (xy 377.686949 -244.188459)
			(xy 377.732928 -244.210276) (xy 377.774812 -244.239186) (xy 377.811516 -244.274441) (xy 377.842089 -244.315127)
			(xy 377.86574 -244.36019) (xy 377.881856 -244.408464) (xy 377.89002 -244.458698) (xy 377.890532 -244.484144)
			(xy 379.138683 -244.484144) (xy 379.142778 -244.433416) (xy 379.154957 -244.384002) (xy 379.174905 -244.337182)
			(xy 379.202106 -244.294168) (xy 379.235854 -244.256074) (xy 379.275276 -244.223887) (xy 379.31935 -244.198441)
			(xy 379.366936 -244.180394) (xy 379.4168 -244.170214) (xy 379.467652 -244.168165) (xy 379.518173 -244.174299)
			(xy 379.567057 -244.188459) (xy 379.613036 -244.210276) (xy 379.65492 -244.239186) (xy 379.691624 -244.274441)
			(xy 379.722197 -244.315127) (xy 379.745848 -244.36019) (xy 379.761964 -244.408464) (xy 379.770128 -244.458698)
			(xy 379.77064 -244.484144) (xy 380.078483 -244.484144) (xy 380.082578 -244.433416) (xy 380.094757 -244.384002)
			(xy 380.114705 -244.337182) (xy 380.141906 -244.294168) (xy 380.175654 -244.256074) (xy 380.215076 -244.223887)
			(xy 380.25915 -244.198441) (xy 380.306736 -244.180394) (xy 380.3566 -244.170214) (xy 380.407452 -244.168165)
			(xy 380.457973 -244.174299) (xy 380.506857 -244.188459) (xy 380.552836 -244.210276) (xy 380.59472 -244.239186)
			(xy 380.631424 -244.274441) (xy 380.661997 -244.315127) (xy 380.685648 -244.36019) (xy 380.701764 -244.408464)
			(xy 380.709928 -244.458698) (xy 380.71044 -244.484144) (xy 380.709928 -244.50959) (xy 380.701764 -244.559824)
			(xy 380.685648 -244.608098) (xy 380.661997 -244.653161) (xy 380.631424 -244.693847) (xy 380.59472 -244.729102)
			(xy 380.552836 -244.758012) (xy 380.506857 -244.779829) (xy 380.457973 -244.793989) (xy 380.407452 -244.800123)
			(xy 380.3566 -244.798074) (xy 380.306736 -244.787894) (xy 380.25915 -244.769847) (xy 380.215076 -244.744401)
			(xy 380.175654 -244.712214) (xy 380.141906 -244.67412) (xy 380.114705 -244.631106) (xy 380.094757 -244.584286)
			(xy 380.082578 -244.534872) (xy 380.078483 -244.484144) (xy 379.77064 -244.484144) (xy 379.770128 -244.50959)
			(xy 379.761964 -244.559824) (xy 379.745848 -244.608098) (xy 379.722197 -244.653161) (xy 379.691624 -244.693847)
			(xy 379.65492 -244.729102) (xy 379.613036 -244.758012) (xy 379.567057 -244.779829) (xy 379.518173 -244.793989)
			(xy 379.467652 -244.800123) (xy 379.4168 -244.798074) (xy 379.366936 -244.787894) (xy 379.31935 -244.769847)
			(xy 379.275276 -244.744401) (xy 379.235854 -244.712214) (xy 379.202106 -244.67412) (xy 379.174905 -244.631106)
			(xy 379.154957 -244.584286) (xy 379.142778 -244.534872) (xy 379.138683 -244.484144) (xy 377.890532 -244.484144)
			(xy 377.89002 -244.50959) (xy 377.881856 -244.559824) (xy 377.86574 -244.608098) (xy 377.842089 -244.653161)
			(xy 377.811516 -244.693847) (xy 377.774812 -244.729102) (xy 377.732928 -244.758012) (xy 377.686949 -244.779829)
			(xy 377.638065 -244.793989) (xy 377.587544 -244.800123) (xy 377.536692 -244.798074) (xy 377.486828 -244.787894)
			(xy 377.439242 -244.769847) (xy 377.395168 -244.744401) (xy 377.355746 -244.712214) (xy 377.321998 -244.67412)
			(xy 377.294797 -244.631106) (xy 377.274849 -244.584286) (xy 377.26267 -244.534872) (xy 377.258575 -244.484144)
			(xy 376.940064 -244.484144) (xy 376.939569 -244.508751) (xy 376.931674 -244.557328) (xy 376.91609 -244.604009)
			(xy 376.893219 -244.647586) (xy 376.863654 -244.68693) (xy 376.828161 -244.721022) (xy 376.787658 -244.748978)
			(xy 376.743196 -244.770076) (xy 376.695925 -244.783768) (xy 376.64707 -244.7897) (xy 376.597895 -244.787719)
			(xy 376.549676 -244.777875) (xy 376.50366 -244.760423) (xy 376.461039 -244.735816) (xy 376.422918 -244.704691)
			(xy 376.390283 -244.667854) (xy 376.36398 -244.626258) (xy 376.344689 -244.580982) (xy 376.332912 -244.533198)
			(xy 376.328952 -244.484144) (xy 376.010424 -244.484144) (xy 376.009912 -244.50959) (xy 376.001748 -244.559824)
			(xy 375.985632 -244.608098) (xy 375.961981 -244.653161) (xy 375.931408 -244.693847) (xy 375.894704 -244.729102)
			(xy 375.85282 -244.758012) (xy 375.806841 -244.779829) (xy 375.757957 -244.793989) (xy 375.707436 -244.800123)
			(xy 375.656584 -244.798074) (xy 375.60672 -244.787894) (xy 375.559134 -244.769847) (xy 375.51506 -244.744401)
			(xy 375.475638 -244.712214) (xy 375.44189 -244.67412) (xy 375.414689 -244.631106) (xy 375.394741 -244.584286)
			(xy 375.382562 -244.534872) (xy 375.378467 -244.484144) (xy 375.11863 -244.484144) (xy 375.11863 -244.887242)
			(xy 375.119061 -244.897308) (xy 375.12679 -244.915899) (xy 375.133616 -244.92331) (xy 375.184924 -244.97411)
			(xy 375.192335 -244.98079) (xy 375.210771 -244.988361) (xy 375.220738 -244.988842) (xy 375.224802 -244.988842)
			(xy 375.250053 -244.989364) (xy 375.299866 -244.997676) (xy 375.347632 -245.014075) (xy 375.392047 -245.038111)
			(xy 375.431901 -245.06913) (xy 375.466105 -245.106286) (xy 375.493727 -245.148565) (xy 375.514013 -245.194813)
			(xy 375.526411 -245.24377) (xy 375.530581 -245.2941) (xy 375.530577 -245.29415) (xy 375.848621 -245.29415)
			(xy 375.852716 -245.243422) (xy 375.864895 -245.194008) (xy 375.884843 -245.147188) (xy 375.912044 -245.104174)
			(xy 375.945792 -245.06608) (xy 375.985214 -245.033893) (xy 376.029288 -245.008447) (xy 376.076874 -244.9904)
			(xy 376.126738 -244.98022) (xy 376.17759 -244.978171) (xy 376.228111 -244.984305) (xy 376.276995 -244.998465)
			(xy 376.322974 -245.020282) (xy 376.364858 -245.049192) (xy 376.401562 -245.084447) (xy 376.432135 -245.125133)
			(xy 376.455786 -245.170196) (xy 376.471902 -245.21847) (xy 376.480066 -245.268704) (xy 376.480578 -245.29415)
			(xy 376.788675 -245.29415) (xy 376.79277 -245.243422) (xy 376.804949 -245.194008) (xy 376.824897 -245.147188)
			(xy 376.852098 -245.104174) (xy 376.885846 -245.06608) (xy 376.925268 -245.033893) (xy 376.969342 -245.008447)
			(xy 377.016928 -244.9904) (xy 377.066792 -244.98022) (xy 377.117644 -244.978171) (xy 377.168165 -244.984305)
			(xy 377.217049 -244.998465) (xy 377.263028 -245.020282) (xy 377.304912 -245.049192) (xy 377.341616 -245.084447)
			(xy 377.372189 -245.125133) (xy 377.39584 -245.170196) (xy 377.411956 -245.21847) (xy 377.42012 -245.268704)
			(xy 377.420632 -245.29415) (xy 377.738906 -245.29415) (xy 377.742866 -245.245096) (xy 377.754643 -245.197312)
			(xy 377.773934 -245.152036) (xy 377.800237 -245.11044) (xy 377.832872 -245.073603) (xy 377.870993 -245.042478)
			(xy 377.913614 -245.017871) (xy 377.95963 -245.000419) (xy 378.007849 -244.990575) (xy 378.057024 -244.988594)
			(xy 378.105879 -244.994526) (xy 378.15315 -245.008218) (xy 378.197612 -245.029316) (xy 378.238115 -245.057272)
			(xy 378.273608 -245.091364) (xy 378.303173 -245.130708) (xy 378.326044 -245.174285) (xy 378.341628 -245.220966)
			(xy 378.349523 -245.269543) (xy 378.350018 -245.29415) (xy 378.668529 -245.29415) (xy 378.672624 -245.243422)
			(xy 378.684803 -245.194008) (xy 378.704751 -245.147188) (xy 378.731952 -245.104174) (xy 378.7657 -245.06608)
			(xy 378.805122 -245.033893) (xy 378.849196 -245.008447) (xy 378.896782 -244.9904) (xy 378.946646 -244.98022)
			(xy 378.997498 -244.978171) (xy 379.048019 -244.984305) (xy 379.096903 -244.998465) (xy 379.142882 -245.020282)
			(xy 379.184766 -245.049192) (xy 379.22147 -245.084447) (xy 379.252043 -245.125133) (xy 379.275694 -245.170196)
			(xy 379.29181 -245.21847) (xy 379.299974 -245.268704) (xy 379.300486 -245.29415) (xy 379.619014 -245.29415)
			(xy 379.622974 -245.245096) (xy 379.634751 -245.197312) (xy 379.654042 -245.152036) (xy 379.680345 -245.11044)
			(xy 379.71298 -245.073603) (xy 379.751101 -245.042478) (xy 379.793722 -245.017871) (xy 379.839738 -245.000419)
			(xy 379.887957 -244.990575) (xy 379.937132 -244.988594) (xy 379.985987 -244.994526) (xy 380.033258 -245.008218)
			(xy 380.07772 -245.029316) (xy 380.118223 -245.057272) (xy 380.153716 -245.091364) (xy 380.183281 -245.130708)
			(xy 380.206152 -245.174285) (xy 380.221736 -245.220966) (xy 380.229631 -245.269543) (xy 380.230126 -245.29415)
			(xy 380.548637 -245.29415) (xy 380.552732 -245.243422) (xy 380.564911 -245.194008) (xy 380.584859 -245.147188)
			(xy 380.61206 -245.104174) (xy 380.645808 -245.06608) (xy 380.68523 -245.033893) (xy 380.729304 -245.008447)
			(xy 380.77689 -244.9904) (xy 380.826754 -244.98022) (xy 380.877606 -244.978171) (xy 380.928127 -244.984305)
			(xy 380.977011 -244.998465) (xy 381.02299 -245.020282) (xy 381.064874 -245.049192) (xy 381.101578 -245.084447)
			(xy 381.132151 -245.125133) (xy 381.155802 -245.170196) (xy 381.171918 -245.21847) (xy 381.180082 -245.268704)
			(xy 381.180594 -245.29415) (xy 381.180082 -245.319596) (xy 381.171918 -245.36983) (xy 381.155802 -245.418104)
			(xy 381.132151 -245.463167) (xy 381.101578 -245.503853) (xy 381.064874 -245.539108) (xy 381.02299 -245.568018)
			(xy 380.977011 -245.589835) (xy 380.928127 -245.603995) (xy 380.877606 -245.610129) (xy 380.826754 -245.60808)
			(xy 380.77689 -245.5979) (xy 380.729304 -245.579853) (xy 380.68523 -245.554407) (xy 380.645808 -245.52222)
			(xy 380.61206 -245.484126) (xy 380.584859 -245.441112) (xy 380.564911 -245.394292) (xy 380.552732 -245.344878)
			(xy 380.548637 -245.29415) (xy 380.230126 -245.29415) (xy 380.229631 -245.318757) (xy 380.221736 -245.367334)
			(xy 380.206152 -245.414015) (xy 380.183281 -245.457592) (xy 380.153716 -245.496936) (xy 380.118223 -245.531028)
			(xy 380.07772 -245.558984) (xy 380.033258 -245.580082) (xy 379.985987 -245.593774) (xy 379.937132 -245.599706)
			(xy 379.887957 -245.597725) (xy 379.839738 -245.587881) (xy 379.793722 -245.570429) (xy 379.751101 -245.545822)
			(xy 379.71298 -245.514697) (xy 379.680345 -245.47786) (xy 379.654042 -245.436264) (xy 379.634751 -245.390988)
			(xy 379.622974 -245.343204) (xy 379.619014 -245.29415) (xy 379.300486 -245.29415) (xy 379.299974 -245.319596)
			(xy 379.29181 -245.36983) (xy 379.275694 -245.418104) (xy 379.252043 -245.463167) (xy 379.22147 -245.503853)
			(xy 379.184766 -245.539108) (xy 379.142882 -245.568018) (xy 379.096903 -245.589835) (xy 379.048019 -245.603995)
			(xy 378.997498 -245.610129) (xy 378.946646 -245.60808) (xy 378.896782 -245.5979) (xy 378.849196 -245.579853)
			(xy 378.805122 -245.554407) (xy 378.7657 -245.52222) (xy 378.731952 -245.484126) (xy 378.704751 -245.441112)
			(xy 378.684803 -245.394292) (xy 378.672624 -245.344878) (xy 378.668529 -245.29415) (xy 378.350018 -245.29415)
			(xy 378.349523 -245.318757) (xy 378.341628 -245.367334) (xy 378.326044 -245.414015) (xy 378.303173 -245.457592)
			(xy 378.273608 -245.496936) (xy 378.238115 -245.531028) (xy 378.197612 -245.558984) (xy 378.15315 -245.580082)
			(xy 378.105879 -245.593774) (xy 378.057024 -245.599706) (xy 378.007849 -245.597725) (xy 377.95963 -245.587881)
			(xy 377.913614 -245.570429) (xy 377.870993 -245.545822) (xy 377.832872 -245.514697) (xy 377.800237 -245.47786)
			(xy 377.773934 -245.436264) (xy 377.754643 -245.390988) (xy 377.742866 -245.343204) (xy 377.738906 -245.29415)
			(xy 377.420632 -245.29415) (xy 377.42012 -245.319596) (xy 377.411956 -245.36983) (xy 377.39584 -245.418104)
			(xy 377.372189 -245.463167) (xy 377.341616 -245.503853) (xy 377.304912 -245.539108) (xy 377.263028 -245.568018)
			(xy 377.217049 -245.589835) (xy 377.168165 -245.603995) (xy 377.117644 -245.610129) (xy 377.066792 -245.60808)
			(xy 377.016928 -245.5979) (xy 376.969342 -245.579853) (xy 376.925268 -245.554407) (xy 376.885846 -245.52222)
			(xy 376.852098 -245.484126) (xy 376.824897 -245.441112) (xy 376.804949 -245.394292) (xy 376.79277 -245.344878)
			(xy 376.788675 -245.29415) (xy 376.480578 -245.29415) (xy 376.480066 -245.319596) (xy 376.471902 -245.36983)
			(xy 376.455786 -245.418104) (xy 376.432135 -245.463167) (xy 376.401562 -245.503853) (xy 376.364858 -245.539108)
			(xy 376.322974 -245.568018) (xy 376.276995 -245.589835) (xy 376.228111 -245.603995) (xy 376.17759 -245.610129)
			(xy 376.126738 -245.60808) (xy 376.076874 -245.5979) (xy 376.029288 -245.579853) (xy 375.985214 -245.554407)
			(xy 375.945792 -245.52222) (xy 375.912044 -245.484126) (xy 375.884843 -245.441112) (xy 375.864895 -245.394292)
			(xy 375.852716 -245.344878) (xy 375.848621 -245.29415) (xy 375.530577 -245.29415) (xy 375.526411 -245.34443)
			(xy 375.514013 -245.393387) (xy 375.493727 -245.439635) (xy 375.466105 -245.481914) (xy 375.431901 -245.51907)
			(xy 375.392047 -245.550089) (xy 375.347632 -245.574125) (xy 375.299866 -245.590524) (xy 375.250053 -245.598836)
			(xy 375.224802 -245.599458) (xy 375.220738 -245.599458) (xy 375.210775 -245.599942) (xy 375.192345 -245.607524)
			(xy 375.184924 -245.61419) (xy 375.133616 -245.66499) (xy 375.126766 -245.672387) (xy 375.119025 -245.690985)
			(xy 375.11863 -245.701058) (xy 375.11863 -246.104156) (xy 375.378467 -246.104156) (xy 375.382562 -246.053428)
			(xy 375.394741 -246.004014) (xy 375.414689 -245.957194) (xy 375.44189 -245.91418) (xy 375.475638 -245.876086)
			(xy 375.51506 -245.843899) (xy 375.559134 -245.818453) (xy 375.60672 -245.800406) (xy 375.656584 -245.790226)
			(xy 375.707436 -245.788177) (xy 375.757957 -245.794311) (xy 375.806841 -245.808471) (xy 375.85282 -245.830288)
			(xy 375.894704 -245.859198) (xy 375.931408 -245.894453) (xy 375.961981 -245.935139) (xy 375.985632 -245.980202)
			(xy 376.001748 -246.028476) (xy 376.009912 -246.07871) (xy 376.010424 -246.104156) (xy 376.328952 -246.104156)
			(xy 376.332912 -246.055102) (xy 376.344689 -246.007318) (xy 376.36398 -245.962042) (xy 376.390283 -245.920446)
			(xy 376.422918 -245.883609) (xy 376.461039 -245.852484) (xy 376.50366 -245.827877) (xy 376.549676 -245.810425)
			(xy 376.597895 -245.800581) (xy 376.64707 -245.7986) (xy 376.695925 -245.804532) (xy 376.743196 -245.818224)
			(xy 376.787658 -245.839322) (xy 376.828161 -245.867278) (xy 376.863654 -245.90137) (xy 376.893219 -245.940714)
			(xy 376.91609 -245.984291) (xy 376.931674 -246.030972) (xy 376.939569 -246.079549) (xy 376.940064 -246.104156)
			(xy 377.258575 -246.104156) (xy 377.26267 -246.053428) (xy 377.274849 -246.004014) (xy 377.294797 -245.957194)
			(xy 377.321998 -245.91418) (xy 377.355746 -245.876086) (xy 377.395168 -245.843899) (xy 377.439242 -245.818453)
			(xy 377.486828 -245.800406) (xy 377.536692 -245.790226) (xy 377.587544 -245.788177) (xy 377.638065 -245.794311)
			(xy 377.686949 -245.808471) (xy 377.732928 -245.830288) (xy 377.774812 -245.859198) (xy 377.811516 -245.894453)
			(xy 377.842089 -245.935139) (xy 377.86574 -245.980202) (xy 377.881856 -246.028476) (xy 377.89002 -246.07871)
			(xy 377.890532 -246.104156) (xy 378.20906 -246.104156) (xy 378.21302 -246.055102) (xy 378.224797 -246.007318)
			(xy 378.244088 -245.962042) (xy 378.270391 -245.920446) (xy 378.303026 -245.883609) (xy 378.341147 -245.852484)
			(xy 378.383768 -245.827877) (xy 378.429784 -245.810425) (xy 378.478003 -245.800581) (xy 378.527178 -245.7986)
			(xy 378.576033 -245.804532) (xy 378.623304 -245.818224) (xy 378.667766 -245.839322) (xy 378.708269 -245.867278)
			(xy 378.743762 -245.90137) (xy 378.773327 -245.940714) (xy 378.796198 -245.984291) (xy 378.811782 -246.030972)
			(xy 378.819677 -246.079549) (xy 378.820172 -246.104156) (xy 379.138683 -246.104156) (xy 379.142778 -246.053428)
			(xy 379.154957 -246.004014) (xy 379.174905 -245.957194) (xy 379.202106 -245.91418) (xy 379.235854 -245.876086)
			(xy 379.275276 -245.843899) (xy 379.31935 -245.818453) (xy 379.366936 -245.800406) (xy 379.4168 -245.790226)
			(xy 379.467652 -245.788177) (xy 379.518173 -245.794311) (xy 379.567057 -245.808471) (xy 379.613036 -245.830288)
			(xy 379.65492 -245.859198) (xy 379.691624 -245.894453) (xy 379.722197 -245.935139) (xy 379.745848 -245.980202)
			(xy 379.761964 -246.028476) (xy 379.770128 -246.07871) (xy 379.77064 -246.104156) (xy 380.078483 -246.104156)
			(xy 380.082578 -246.053428) (xy 380.094757 -246.004014) (xy 380.114705 -245.957194) (xy 380.141906 -245.91418)
			(xy 380.175654 -245.876086) (xy 380.215076 -245.843899) (xy 380.25915 -245.818453) (xy 380.306736 -245.800406)
			(xy 380.3566 -245.790226) (xy 380.407452 -245.788177) (xy 380.457973 -245.794311) (xy 380.506857 -245.808471)
			(xy 380.552836 -245.830288) (xy 380.59472 -245.859198) (xy 380.631424 -245.894453) (xy 380.661997 -245.935139)
			(xy 380.685648 -245.980202) (xy 380.701764 -246.028476) (xy 380.709928 -246.07871) (xy 380.71044 -246.104156)
			(xy 380.709928 -246.129602) (xy 380.701764 -246.179836) (xy 380.685648 -246.22811) (xy 380.661997 -246.273173)
			(xy 380.631424 -246.313859) (xy 380.59472 -246.349114) (xy 380.552836 -246.378024) (xy 380.506857 -246.399841)
			(xy 380.457973 -246.414001) (xy 380.407452 -246.420135) (xy 380.3566 -246.418086) (xy 380.306736 -246.407906)
			(xy 380.25915 -246.389859) (xy 380.215076 -246.364413) (xy 380.175654 -246.332226) (xy 380.141906 -246.294132)
			(xy 380.114705 -246.251118) (xy 380.094757 -246.204298) (xy 380.082578 -246.154884) (xy 380.078483 -246.104156)
			(xy 379.77064 -246.104156) (xy 379.770128 -246.129602) (xy 379.761964 -246.179836) (xy 379.745848 -246.22811)
			(xy 379.722197 -246.273173) (xy 379.691624 -246.313859) (xy 379.65492 -246.349114) (xy 379.613036 -246.378024)
			(xy 379.567057 -246.399841) (xy 379.518173 -246.414001) (xy 379.467652 -246.420135) (xy 379.4168 -246.418086)
			(xy 379.366936 -246.407906) (xy 379.31935 -246.389859) (xy 379.275276 -246.364413) (xy 379.235854 -246.332226)
			(xy 379.202106 -246.294132) (xy 379.174905 -246.251118) (xy 379.154957 -246.204298) (xy 379.142778 -246.154884)
			(xy 379.138683 -246.104156) (xy 378.820172 -246.104156) (xy 378.819677 -246.128763) (xy 378.811782 -246.17734)
			(xy 378.796198 -246.224021) (xy 378.773327 -246.267598) (xy 378.743762 -246.306942) (xy 378.708269 -246.341034)
			(xy 378.667766 -246.36899) (xy 378.623304 -246.390088) (xy 378.576033 -246.40378) (xy 378.527178 -246.409712)
			(xy 378.478003 -246.407731) (xy 378.429784 -246.397887) (xy 378.383768 -246.380435) (xy 378.341147 -246.355828)
			(xy 378.303026 -246.324703) (xy 378.270391 -246.287866) (xy 378.244088 -246.24627) (xy 378.224797 -246.200994)
			(xy 378.21302 -246.15321) (xy 378.20906 -246.104156) (xy 377.890532 -246.104156) (xy 377.89002 -246.129602)
			(xy 377.881856 -246.179836) (xy 377.86574 -246.22811) (xy 377.842089 -246.273173) (xy 377.811516 -246.313859)
			(xy 377.774812 -246.349114) (xy 377.732928 -246.378024) (xy 377.686949 -246.399841) (xy 377.638065 -246.414001)
			(xy 377.587544 -246.420135) (xy 377.536692 -246.418086) (xy 377.486828 -246.407906) (xy 377.439242 -246.389859)
			(xy 377.395168 -246.364413) (xy 377.355746 -246.332226) (xy 377.321998 -246.294132) (xy 377.294797 -246.251118)
			(xy 377.274849 -246.204298) (xy 377.26267 -246.154884) (xy 377.258575 -246.104156) (xy 376.940064 -246.104156)
			(xy 376.939569 -246.128763) (xy 376.931674 -246.17734) (xy 376.91609 -246.224021) (xy 376.893219 -246.267598)
			(xy 376.863654 -246.306942) (xy 376.828161 -246.341034) (xy 376.787658 -246.36899) (xy 376.743196 -246.390088)
			(xy 376.695925 -246.40378) (xy 376.64707 -246.409712) (xy 376.597895 -246.407731) (xy 376.549676 -246.397887)
			(xy 376.50366 -246.380435) (xy 376.461039 -246.355828) (xy 376.422918 -246.324703) (xy 376.390283 -246.287866)
			(xy 376.36398 -246.24627) (xy 376.344689 -246.200994) (xy 376.332912 -246.15321) (xy 376.328952 -246.104156)
			(xy 376.010424 -246.104156) (xy 376.009912 -246.129602) (xy 376.001748 -246.179836) (xy 375.985632 -246.22811)
			(xy 375.961981 -246.273173) (xy 375.931408 -246.313859) (xy 375.894704 -246.349114) (xy 375.85282 -246.378024)
			(xy 375.806841 -246.399841) (xy 375.757957 -246.414001) (xy 375.707436 -246.420135) (xy 375.656584 -246.418086)
			(xy 375.60672 -246.407906) (xy 375.559134 -246.389859) (xy 375.51506 -246.364413) (xy 375.475638 -246.332226)
			(xy 375.44189 -246.294132) (xy 375.414689 -246.251118) (xy 375.394741 -246.204298) (xy 375.382562 -246.154884)
			(xy 375.378467 -246.104156) (xy 375.11863 -246.104156) (xy 375.11863 -246.914162) (xy 375.848621 -246.914162)
			(xy 375.852716 -246.863434) (xy 375.864895 -246.81402) (xy 375.884843 -246.7672) (xy 375.912044 -246.724186)
			(xy 375.945792 -246.686092) (xy 375.985214 -246.653905) (xy 376.029288 -246.628459) (xy 376.076874 -246.610412)
			(xy 376.126738 -246.600232) (xy 376.17759 -246.598183) (xy 376.228111 -246.604317) (xy 376.276995 -246.618477)
			(xy 376.322974 -246.640294) (xy 376.364858 -246.669204) (xy 376.401562 -246.704459) (xy 376.432135 -246.745145)
			(xy 376.455786 -246.790208) (xy 376.471902 -246.838482) (xy 376.480066 -246.888716) (xy 376.480578 -246.914162)
			(xy 376.788675 -246.914162) (xy 376.79277 -246.863434) (xy 376.804949 -246.81402) (xy 376.824897 -246.7672)
			(xy 376.852098 -246.724186) (xy 376.885846 -246.686092) (xy 376.925268 -246.653905) (xy 376.969342 -246.628459)
			(xy 377.016928 -246.610412) (xy 377.066792 -246.600232) (xy 377.117644 -246.598183) (xy 377.168165 -246.604317)
			(xy 377.217049 -246.618477) (xy 377.263028 -246.640294) (xy 377.304912 -246.669204) (xy 377.341616 -246.704459)
			(xy 377.372189 -246.745145) (xy 377.39584 -246.790208) (xy 377.411956 -246.838482) (xy 377.42012 -246.888716)
			(xy 377.420632 -246.914162) (xy 378.668529 -246.914162) (xy 378.672624 -246.863434) (xy 378.684803 -246.81402)
			(xy 378.704751 -246.7672) (xy 378.731952 -246.724186) (xy 378.7657 -246.686092) (xy 378.805122 -246.653905)
			(xy 378.849196 -246.628459) (xy 378.896782 -246.610412) (xy 378.946646 -246.600232) (xy 378.997498 -246.598183)
			(xy 379.048019 -246.604317) (xy 379.096903 -246.618477) (xy 379.142882 -246.640294) (xy 379.184766 -246.669204)
			(xy 379.22147 -246.704459) (xy 379.252043 -246.745145) (xy 379.275694 -246.790208) (xy 379.29181 -246.838482)
			(xy 379.299974 -246.888716) (xy 379.300486 -246.914162) (xy 379.619014 -246.914162) (xy 379.622974 -246.865108)
			(xy 379.634751 -246.817324) (xy 379.654042 -246.772048) (xy 379.680345 -246.730452) (xy 379.71298 -246.693615)
			(xy 379.751101 -246.66249) (xy 379.793722 -246.637883) (xy 379.839738 -246.620431) (xy 379.887957 -246.610587)
			(xy 379.937132 -246.608606) (xy 379.985987 -246.614538) (xy 380.033258 -246.62823) (xy 380.07772 -246.649328)
			(xy 380.118223 -246.677284) (xy 380.153716 -246.711376) (xy 380.183281 -246.75072) (xy 380.206152 -246.794297)
			(xy 380.221736 -246.840978) (xy 380.229631 -246.889555) (xy 380.230126 -246.914162) (xy 380.548637 -246.914162)
			(xy 380.552732 -246.863434) (xy 380.564911 -246.81402) (xy 380.584859 -246.7672) (xy 380.61206 -246.724186)
			(xy 380.645808 -246.686092) (xy 380.68523 -246.653905) (xy 380.729304 -246.628459) (xy 380.77689 -246.610412)
			(xy 380.826754 -246.600232) (xy 380.877606 -246.598183) (xy 380.928127 -246.604317) (xy 380.977011 -246.618477)
			(xy 381.02299 -246.640294) (xy 381.064874 -246.669204) (xy 381.101578 -246.704459) (xy 381.132151 -246.745145)
			(xy 381.155802 -246.790208) (xy 381.171918 -246.838482) (xy 381.180082 -246.888716) (xy 381.180594 -246.914162)
			(xy 381.180082 -246.939608) (xy 381.171918 -246.989842) (xy 381.155802 -247.038116) (xy 381.132151 -247.083179)
			(xy 381.101578 -247.123865) (xy 381.064874 -247.15912) (xy 381.02299 -247.18803) (xy 380.977011 -247.209847)
			(xy 380.928127 -247.224007) (xy 380.877606 -247.230141) (xy 380.826754 -247.228092) (xy 380.77689 -247.217912)
			(xy 380.729304 -247.199865) (xy 380.68523 -247.174419) (xy 380.645808 -247.142232) (xy 380.61206 -247.104138)
			(xy 380.584859 -247.061124) (xy 380.564911 -247.014304) (xy 380.552732 -246.96489) (xy 380.548637 -246.914162)
			(xy 380.230126 -246.914162) (xy 380.229631 -246.938769) (xy 380.221736 -246.987346) (xy 380.206152 -247.034027)
			(xy 380.183281 -247.077604) (xy 380.153716 -247.116948) (xy 380.118223 -247.15104) (xy 380.07772 -247.178996)
			(xy 380.033258 -247.200094) (xy 379.985987 -247.213786) (xy 379.937132 -247.219718) (xy 379.887957 -247.217737)
			(xy 379.839738 -247.207893) (xy 379.793722 -247.190441) (xy 379.751101 -247.165834) (xy 379.71298 -247.134709)
			(xy 379.680345 -247.097872) (xy 379.654042 -247.056276) (xy 379.634751 -247.011) (xy 379.622974 -246.963216)
			(xy 379.619014 -246.914162) (xy 379.300486 -246.914162) (xy 379.299974 -246.939608) (xy 379.29181 -246.989842)
			(xy 379.275694 -247.038116) (xy 379.252043 -247.083179) (xy 379.22147 -247.123865) (xy 379.184766 -247.15912)
			(xy 379.142882 -247.18803) (xy 379.096903 -247.209847) (xy 379.048019 -247.224007) (xy 378.997498 -247.230141)
			(xy 378.946646 -247.228092) (xy 378.896782 -247.217912) (xy 378.849196 -247.199865) (xy 378.805122 -247.174419)
			(xy 378.7657 -247.142232) (xy 378.731952 -247.104138) (xy 378.704751 -247.061124) (xy 378.684803 -247.014304)
			(xy 378.672624 -246.96489) (xy 378.668529 -246.914162) (xy 377.420632 -246.914162) (xy 377.42012 -246.939608)
			(xy 377.411956 -246.989842) (xy 377.39584 -247.038116) (xy 377.372189 -247.083179) (xy 377.341616 -247.123865)
			(xy 377.304912 -247.15912) (xy 377.263028 -247.18803) (xy 377.217049 -247.209847) (xy 377.168165 -247.224007)
			(xy 377.117644 -247.230141) (xy 377.066792 -247.228092) (xy 377.016928 -247.217912) (xy 376.969342 -247.199865)
			(xy 376.925268 -247.174419) (xy 376.885846 -247.142232) (xy 376.852098 -247.104138) (xy 376.824897 -247.061124)
			(xy 376.804949 -247.014304) (xy 376.79277 -246.96489) (xy 376.788675 -246.914162) (xy 376.480578 -246.914162)
			(xy 376.480066 -246.939608) (xy 376.471902 -246.989842) (xy 376.455786 -247.038116) (xy 376.432135 -247.083179)
			(xy 376.401562 -247.123865) (xy 376.364858 -247.15912) (xy 376.322974 -247.18803) (xy 376.276995 -247.209847)
			(xy 376.228111 -247.224007) (xy 376.17759 -247.230141) (xy 376.126738 -247.228092) (xy 376.076874 -247.217912)
			(xy 376.029288 -247.199865) (xy 375.985214 -247.174419) (xy 375.945792 -247.142232) (xy 375.912044 -247.104138)
			(xy 375.884843 -247.061124) (xy 375.864895 -247.014304) (xy 375.852716 -246.96489) (xy 375.848621 -246.914162)
			(xy 375.11863 -246.914162) (xy 375.11863 -247.724168) (xy 375.378467 -247.724168) (xy 375.382562 -247.67344)
			(xy 375.394741 -247.624026) (xy 375.414689 -247.577206) (xy 375.44189 -247.534192) (xy 375.475638 -247.496098)
			(xy 375.51506 -247.463911) (xy 375.559134 -247.438465) (xy 375.60672 -247.420418) (xy 375.656584 -247.410238)
			(xy 375.707436 -247.408189) (xy 375.757957 -247.414323) (xy 375.806841 -247.428483) (xy 375.85282 -247.4503)
			(xy 375.894704 -247.47921) (xy 375.931408 -247.514465) (xy 375.961981 -247.555151) (xy 375.985632 -247.600214)
			(xy 376.001748 -247.648488) (xy 376.009912 -247.698722) (xy 376.010424 -247.724168) (xy 376.328952 -247.724168)
			(xy 376.332912 -247.675114) (xy 376.344689 -247.62733) (xy 376.36398 -247.582054) (xy 376.390283 -247.540458)
			(xy 376.422918 -247.503621) (xy 376.461039 -247.472496) (xy 376.50366 -247.447889) (xy 376.549676 -247.430437)
			(xy 376.597895 -247.420593) (xy 376.64707 -247.418612) (xy 376.695925 -247.424544) (xy 376.743196 -247.438236)
			(xy 376.787658 -247.459334) (xy 376.828161 -247.48729) (xy 376.863654 -247.521382) (xy 376.893219 -247.560726)
			(xy 376.91609 -247.604303) (xy 376.931674 -247.650984) (xy 376.939569 -247.699561) (xy 376.940064 -247.724168)
			(xy 377.258575 -247.724168) (xy 377.26267 -247.67344) (xy 377.274849 -247.624026) (xy 377.294797 -247.577206)
			(xy 377.321998 -247.534192) (xy 377.355746 -247.496098) (xy 377.395168 -247.463911) (xy 377.439242 -247.438465)
			(xy 377.486828 -247.420418) (xy 377.536692 -247.410238) (xy 377.587544 -247.408189) (xy 377.638065 -247.414323)
			(xy 377.686949 -247.428483) (xy 377.732928 -247.4503) (xy 377.774812 -247.47921) (xy 377.811516 -247.514465)
			(xy 377.842089 -247.555151) (xy 377.86574 -247.600214) (xy 377.881856 -247.648488) (xy 377.89002 -247.698722)
			(xy 377.890532 -247.724168) (xy 378.20906 -247.724168) (xy 378.21302 -247.675114) (xy 378.224797 -247.62733)
			(xy 378.244088 -247.582054) (xy 378.270391 -247.540458) (xy 378.303026 -247.503621) (xy 378.341147 -247.472496)
			(xy 378.383768 -247.447889) (xy 378.429784 -247.430437) (xy 378.478003 -247.420593) (xy 378.527178 -247.418612)
			(xy 378.576033 -247.424544) (xy 378.623304 -247.438236) (xy 378.667766 -247.459334) (xy 378.708269 -247.48729)
			(xy 378.743762 -247.521382) (xy 378.773327 -247.560726) (xy 378.796198 -247.604303) (xy 378.811782 -247.650984)
			(xy 378.819677 -247.699561) (xy 378.820172 -247.724168) (xy 379.138683 -247.724168) (xy 379.142778 -247.67344)
			(xy 379.154957 -247.624026) (xy 379.174905 -247.577206) (xy 379.202106 -247.534192) (xy 379.235854 -247.496098)
			(xy 379.275276 -247.463911) (xy 379.31935 -247.438465) (xy 379.366936 -247.420418) (xy 379.4168 -247.410238)
			(xy 379.467652 -247.408189) (xy 379.518173 -247.414323) (xy 379.567057 -247.428483) (xy 379.613036 -247.4503)
			(xy 379.65492 -247.47921) (xy 379.691624 -247.514465) (xy 379.722197 -247.555151) (xy 379.745848 -247.600214)
			(xy 379.761964 -247.648488) (xy 379.770128 -247.698722) (xy 379.77064 -247.724168) (xy 380.078483 -247.724168)
			(xy 380.082578 -247.67344) (xy 380.094757 -247.624026) (xy 380.114705 -247.577206) (xy 380.141906 -247.534192)
			(xy 380.175654 -247.496098) (xy 380.215076 -247.463911) (xy 380.25915 -247.438465) (xy 380.306736 -247.420418)
			(xy 380.3566 -247.410238) (xy 380.407452 -247.408189) (xy 380.457973 -247.414323) (xy 380.506857 -247.428483)
			(xy 380.552836 -247.4503) (xy 380.59472 -247.47921) (xy 380.631424 -247.514465) (xy 380.661997 -247.555151)
			(xy 380.685648 -247.600214) (xy 380.701764 -247.648488) (xy 380.709928 -247.698722) (xy 380.71044 -247.724168)
			(xy 380.709928 -247.749614) (xy 380.701764 -247.799848) (xy 380.685648 -247.848122) (xy 380.661997 -247.893185)
			(xy 380.631424 -247.933871) (xy 380.59472 -247.969126) (xy 380.552836 -247.998036) (xy 380.506857 -248.019853)
			(xy 380.457973 -248.034013) (xy 380.407452 -248.040147) (xy 380.3566 -248.038098) (xy 380.306736 -248.027918)
			(xy 380.25915 -248.009871) (xy 380.215076 -247.984425) (xy 380.175654 -247.952238) (xy 380.141906 -247.914144)
			(xy 380.114705 -247.87113) (xy 380.094757 -247.82431) (xy 380.082578 -247.774896) (xy 380.078483 -247.724168)
			(xy 379.77064 -247.724168) (xy 379.770128 -247.749614) (xy 379.761964 -247.799848) (xy 379.745848 -247.848122)
			(xy 379.722197 -247.893185) (xy 379.691624 -247.933871) (xy 379.65492 -247.969126) (xy 379.613036 -247.998036)
			(xy 379.567057 -248.019853) (xy 379.518173 -248.034013) (xy 379.467652 -248.040147) (xy 379.4168 -248.038098)
			(xy 379.366936 -248.027918) (xy 379.31935 -248.009871) (xy 379.275276 -247.984425) (xy 379.235854 -247.952238)
			(xy 379.202106 -247.914144) (xy 379.174905 -247.87113) (xy 379.154957 -247.82431) (xy 379.142778 -247.774896)
			(xy 379.138683 -247.724168) (xy 378.820172 -247.724168) (xy 378.819677 -247.748775) (xy 378.811782 -247.797352)
			(xy 378.796198 -247.844033) (xy 378.773327 -247.88761) (xy 378.743762 -247.926954) (xy 378.708269 -247.961046)
			(xy 378.667766 -247.989002) (xy 378.623304 -248.0101) (xy 378.576033 -248.023792) (xy 378.527178 -248.029724)
			(xy 378.478003 -248.027743) (xy 378.429784 -248.017899) (xy 378.383768 -248.000447) (xy 378.341147 -247.97584)
			(xy 378.303026 -247.944715) (xy 378.270391 -247.907878) (xy 378.244088 -247.866282) (xy 378.224797 -247.821006)
			(xy 378.21302 -247.773222) (xy 378.20906 -247.724168) (xy 377.890532 -247.724168) (xy 377.89002 -247.749614)
			(xy 377.881856 -247.799848) (xy 377.86574 -247.848122) (xy 377.842089 -247.893185) (xy 377.811516 -247.933871)
			(xy 377.774812 -247.969126) (xy 377.732928 -247.998036) (xy 377.686949 -248.019853) (xy 377.638065 -248.034013)
			(xy 377.587544 -248.040147) (xy 377.536692 -248.038098) (xy 377.486828 -248.027918) (xy 377.439242 -248.009871)
			(xy 377.395168 -247.984425) (xy 377.355746 -247.952238) (xy 377.321998 -247.914144) (xy 377.294797 -247.87113)
			(xy 377.274849 -247.82431) (xy 377.26267 -247.774896) (xy 377.258575 -247.724168) (xy 376.940064 -247.724168)
			(xy 376.939569 -247.748775) (xy 376.931674 -247.797352) (xy 376.91609 -247.844033) (xy 376.893219 -247.88761)
			(xy 376.863654 -247.926954) (xy 376.828161 -247.961046) (xy 376.787658 -247.989002) (xy 376.743196 -248.0101)
			(xy 376.695925 -248.023792) (xy 376.64707 -248.029724) (xy 376.597895 -248.027743) (xy 376.549676 -248.017899)
			(xy 376.50366 -248.000447) (xy 376.461039 -247.97584) (xy 376.422918 -247.944715) (xy 376.390283 -247.907878)
			(xy 376.36398 -247.866282) (xy 376.344689 -247.821006) (xy 376.332912 -247.773222) (xy 376.328952 -247.724168)
			(xy 376.010424 -247.724168) (xy 376.009912 -247.749614) (xy 376.001748 -247.799848) (xy 375.985632 -247.848122)
			(xy 375.961981 -247.893185) (xy 375.931408 -247.933871) (xy 375.894704 -247.969126) (xy 375.85282 -247.998036)
			(xy 375.806841 -248.019853) (xy 375.757957 -248.034013) (xy 375.707436 -248.040147) (xy 375.656584 -248.038098)
			(xy 375.60672 -248.027918) (xy 375.559134 -248.009871) (xy 375.51506 -247.984425) (xy 375.475638 -247.952238)
			(xy 375.44189 -247.914144) (xy 375.414689 -247.87113) (xy 375.394741 -247.82431) (xy 375.382562 -247.774896)
			(xy 375.378467 -247.724168) (xy 375.11863 -247.724168) (xy 375.11863 -248.127266) (xy 375.119066 -248.13733)
			(xy 375.1268 -248.155915) (xy 375.133616 -248.163334) (xy 375.184924 -248.214134) (xy 375.192336 -248.220811)
			(xy 375.210772 -248.228379) (xy 375.220738 -248.228866) (xy 375.224802 -248.228866) (xy 375.250059 -248.229388)
			(xy 375.299885 -248.237703) (xy 375.347663 -248.254105) (xy 375.392089 -248.278147) (xy 375.431952 -248.309174)
			(xy 375.466165 -248.346339) (xy 375.493794 -248.388629) (xy 375.514085 -248.434889) (xy 375.526486 -248.483858)
			(xy 375.530655 -248.534174) (xy 375.848621 -248.534174) (xy 375.852716 -248.483446) (xy 375.864895 -248.434032)
			(xy 375.884843 -248.387212) (xy 375.912044 -248.344198) (xy 375.945792 -248.306104) (xy 375.985214 -248.273917)
			(xy 376.029288 -248.248471) (xy 376.076874 -248.230424) (xy 376.126738 -248.220244) (xy 376.17759 -248.218195)
			(xy 376.228111 -248.224329) (xy 376.276995 -248.238489) (xy 376.322974 -248.260306) (xy 376.364858 -248.289216)
			(xy 376.401562 -248.324471) (xy 376.432135 -248.365157) (xy 376.455786 -248.41022) (xy 376.471902 -248.458494)
			(xy 376.480066 -248.508728) (xy 376.480578 -248.534174) (xy 376.788675 -248.534174) (xy 376.79277 -248.483446)
			(xy 376.804949 -248.434032) (xy 376.824897 -248.387212) (xy 376.852098 -248.344198) (xy 376.885846 -248.306104)
			(xy 376.925268 -248.273917) (xy 376.969342 -248.248471) (xy 377.016928 -248.230424) (xy 377.066792 -248.220244)
			(xy 377.117644 -248.218195) (xy 377.168165 -248.224329) (xy 377.217049 -248.238489) (xy 377.263028 -248.260306)
			(xy 377.304912 -248.289216) (xy 377.341616 -248.324471) (xy 377.372189 -248.365157) (xy 377.39584 -248.41022)
			(xy 377.411956 -248.458494) (xy 377.42012 -248.508728) (xy 377.420632 -248.534174) (xy 377.738906 -248.534174)
			(xy 377.742866 -248.48512) (xy 377.754643 -248.437336) (xy 377.773934 -248.39206) (xy 377.800237 -248.350464)
			(xy 377.832872 -248.313627) (xy 377.870993 -248.282502) (xy 377.913614 -248.257895) (xy 377.95963 -248.240443)
			(xy 378.007849 -248.230599) (xy 378.057024 -248.228618) (xy 378.105879 -248.23455) (xy 378.15315 -248.248242)
			(xy 378.197612 -248.26934) (xy 378.238115 -248.297296) (xy 378.273608 -248.331388) (xy 378.303173 -248.370732)
			(xy 378.326044 -248.414309) (xy 378.341628 -248.46099) (xy 378.349523 -248.509567) (xy 378.350018 -248.534174)
			(xy 378.668529 -248.534174) (xy 378.672624 -248.483446) (xy 378.684803 -248.434032) (xy 378.704751 -248.387212)
			(xy 378.731952 -248.344198) (xy 378.7657 -248.306104) (xy 378.805122 -248.273917) (xy 378.849196 -248.248471)
			(xy 378.896782 -248.230424) (xy 378.946646 -248.220244) (xy 378.997498 -248.218195) (xy 379.048019 -248.224329)
			(xy 379.096903 -248.238489) (xy 379.142882 -248.260306) (xy 379.184766 -248.289216) (xy 379.22147 -248.324471)
			(xy 379.252043 -248.365157) (xy 379.275694 -248.41022) (xy 379.29181 -248.458494) (xy 379.299974 -248.508728)
			(xy 379.300486 -248.534174) (xy 379.619014 -248.534174) (xy 379.622974 -248.48512) (xy 379.634751 -248.437336)
			(xy 379.654042 -248.39206) (xy 379.680345 -248.350464) (xy 379.71298 -248.313627) (xy 379.751101 -248.282502)
			(xy 379.793722 -248.257895) (xy 379.839738 -248.240443) (xy 379.887957 -248.230599) (xy 379.937132 -248.228618)
			(xy 379.985987 -248.23455) (xy 380.033258 -248.248242) (xy 380.07772 -248.26934) (xy 380.118223 -248.297296)
			(xy 380.153716 -248.331388) (xy 380.183281 -248.370732) (xy 380.206152 -248.414309) (xy 380.221736 -248.46099)
			(xy 380.229631 -248.509567) (xy 380.230126 -248.534174) (xy 380.548637 -248.534174) (xy 380.552732 -248.483446)
			(xy 380.564911 -248.434032) (xy 380.584859 -248.387212) (xy 380.61206 -248.344198) (xy 380.645808 -248.306104)
			(xy 380.68523 -248.273917) (xy 380.729304 -248.248471) (xy 380.77689 -248.230424) (xy 380.826754 -248.220244)
			(xy 380.877606 -248.218195) (xy 380.928127 -248.224329) (xy 380.977011 -248.238489) (xy 381.02299 -248.260306)
			(xy 381.064874 -248.289216) (xy 381.101578 -248.324471) (xy 381.132151 -248.365157) (xy 381.155802 -248.41022)
			(xy 381.171918 -248.458494) (xy 381.180082 -248.508728) (xy 381.180594 -248.534174) (xy 381.180082 -248.55962)
			(xy 381.171918 -248.609854) (xy 381.155802 -248.658128) (xy 381.132151 -248.703191) (xy 381.101578 -248.743877)
			(xy 381.064874 -248.779132) (xy 381.02299 -248.808042) (xy 380.977011 -248.829859) (xy 380.928127 -248.844019)
			(xy 380.877606 -248.850153) (xy 380.826754 -248.848104) (xy 380.77689 -248.837924) (xy 380.729304 -248.819877)
			(xy 380.68523 -248.794431) (xy 380.645808 -248.762244) (xy 380.61206 -248.72415) (xy 380.584859 -248.681136)
			(xy 380.564911 -248.634316) (xy 380.552732 -248.584902) (xy 380.548637 -248.534174) (xy 380.230126 -248.534174)
			(xy 380.229631 -248.558781) (xy 380.221736 -248.607358) (xy 380.206152 -248.654039) (xy 380.183281 -248.697616)
			(xy 380.153716 -248.73696) (xy 380.118223 -248.771052) (xy 380.07772 -248.799008) (xy 380.033258 -248.820106)
			(xy 379.985987 -248.833798) (xy 379.937132 -248.83973) (xy 379.887957 -248.837749) (xy 379.839738 -248.827905)
			(xy 379.793722 -248.810453) (xy 379.751101 -248.785846) (xy 379.71298 -248.754721) (xy 379.680345 -248.717884)
			(xy 379.654042 -248.676288) (xy 379.634751 -248.631012) (xy 379.622974 -248.583228) (xy 379.619014 -248.534174)
			(xy 379.300486 -248.534174) (xy 379.299974 -248.55962) (xy 379.29181 -248.609854) (xy 379.275694 -248.658128)
			(xy 379.252043 -248.703191) (xy 379.22147 -248.743877) (xy 379.184766 -248.779132) (xy 379.142882 -248.808042)
			(xy 379.096903 -248.829859) (xy 379.048019 -248.844019) (xy 378.997498 -248.850153) (xy 378.946646 -248.848104)
			(xy 378.896782 -248.837924) (xy 378.849196 -248.819877) (xy 378.805122 -248.794431) (xy 378.7657 -248.762244)
			(xy 378.731952 -248.72415) (xy 378.704751 -248.681136) (xy 378.684803 -248.634316) (xy 378.672624 -248.584902)
			(xy 378.668529 -248.534174) (xy 378.350018 -248.534174) (xy 378.349523 -248.558781) (xy 378.341628 -248.607358)
			(xy 378.326044 -248.654039) (xy 378.303173 -248.697616) (xy 378.273608 -248.73696) (xy 378.238115 -248.771052)
			(xy 378.197612 -248.799008) (xy 378.15315 -248.820106) (xy 378.105879 -248.833798) (xy 378.057024 -248.83973)
			(xy 378.007849 -248.837749) (xy 377.95963 -248.827905) (xy 377.913614 -248.810453) (xy 377.870993 -248.785846)
			(xy 377.832872 -248.754721) (xy 377.800237 -248.717884) (xy 377.773934 -248.676288) (xy 377.754643 -248.631012)
			(xy 377.742866 -248.583228) (xy 377.738906 -248.534174) (xy 377.420632 -248.534174) (xy 377.42012 -248.55962)
			(xy 377.411956 -248.609854) (xy 377.39584 -248.658128) (xy 377.372189 -248.703191) (xy 377.341616 -248.743877)
			(xy 377.304912 -248.779132) (xy 377.263028 -248.808042) (xy 377.217049 -248.829859) (xy 377.168165 -248.844019)
			(xy 377.117644 -248.850153) (xy 377.066792 -248.848104) (xy 377.016928 -248.837924) (xy 376.969342 -248.819877)
			(xy 376.925268 -248.794431) (xy 376.885846 -248.762244) (xy 376.852098 -248.72415) (xy 376.824897 -248.681136)
			(xy 376.804949 -248.634316) (xy 376.79277 -248.584902) (xy 376.788675 -248.534174) (xy 376.480578 -248.534174)
			(xy 376.480066 -248.55962) (xy 376.471902 -248.609854) (xy 376.455786 -248.658128) (xy 376.432135 -248.703191)
			(xy 376.401562 -248.743877) (xy 376.364858 -248.779132) (xy 376.322974 -248.808042) (xy 376.276995 -248.829859)
			(xy 376.228111 -248.844019) (xy 376.17759 -248.850153) (xy 376.126738 -248.848104) (xy 376.076874 -248.837924)
			(xy 376.029288 -248.819877) (xy 375.985214 -248.794431) (xy 375.945792 -248.762244) (xy 375.912044 -248.72415)
			(xy 375.884843 -248.681136) (xy 375.864895 -248.634316) (xy 375.852716 -248.584902) (xy 375.848621 -248.534174)
			(xy 375.530655 -248.534174) (xy 375.530657 -248.5342) (xy 375.526486 -248.584542) (xy 375.514085 -248.633511)
			(xy 375.493794 -248.679771) (xy 375.466165 -248.722061) (xy 375.431952 -248.759226) (xy 375.392089 -248.790253)
			(xy 375.347663 -248.814295) (xy 375.299885 -248.830697) (xy 375.250059 -248.839012) (xy 375.224802 -248.839482)
			(xy 375.220738 -248.839482) (xy 375.210775 -248.839967) (xy 375.192348 -248.847551) (xy 375.184924 -248.854214)
			(xy 375.133616 -248.905014) (xy 375.12677 -248.912413) (xy 375.119038 -248.931011) (xy 375.11863 -248.941082)
			(xy 375.11863 -249.34418) (xy 375.378467 -249.34418) (xy 375.382562 -249.293452) (xy 375.394741 -249.244038)
			(xy 375.414689 -249.197218) (xy 375.44189 -249.154204) (xy 375.475638 -249.11611) (xy 375.51506 -249.083923)
			(xy 375.559134 -249.058477) (xy 375.60672 -249.04043) (xy 375.656584 -249.03025) (xy 375.707436 -249.028201)
			(xy 375.757957 -249.034335) (xy 375.806841 -249.048495) (xy 375.85282 -249.070312) (xy 375.894704 -249.099222)
			(xy 375.931408 -249.134477) (xy 375.961981 -249.175163) (xy 375.985632 -249.220226) (xy 376.001748 -249.2685)
			(xy 376.009912 -249.318734) (xy 376.010424 -249.34418) (xy 376.328952 -249.34418) (xy 376.332912 -249.295126)
			(xy 376.344689 -249.247342) (xy 376.36398 -249.202066) (xy 376.390283 -249.16047) (xy 376.422918 -249.123633)
			(xy 376.461039 -249.092508) (xy 376.50366 -249.067901) (xy 376.549676 -249.050449) (xy 376.597895 -249.040605)
			(xy 376.64707 -249.038624) (xy 376.695925 -249.044556) (xy 376.743196 -249.058248) (xy 376.787658 -249.079346)
			(xy 376.828161 -249.107302) (xy 376.863654 -249.141394) (xy 376.893219 -249.180738) (xy 376.91609 -249.224315)
			(xy 376.931674 -249.270996) (xy 376.939569 -249.319573) (xy 376.940064 -249.34418) (xy 377.269006 -249.34418)
			(xy 377.272966 -249.295126) (xy 377.284743 -249.247342) (xy 377.304034 -249.202066) (xy 377.330337 -249.16047)
			(xy 377.362972 -249.123633) (xy 377.401093 -249.092508) (xy 377.443714 -249.067901) (xy 377.48973 -249.050449)
			(xy 377.537949 -249.040605) (xy 377.587124 -249.038624) (xy 377.635979 -249.044556) (xy 377.68325 -249.058248)
			(xy 377.727712 -249.079346) (xy 377.768215 -249.107302) (xy 377.803708 -249.141394) (xy 377.833273 -249.180738)
			(xy 377.856144 -249.224315) (xy 377.871728 -249.270996) (xy 377.879623 -249.319573) (xy 377.880118 -249.34418)
			(xy 379.138683 -249.34418) (xy 379.142778 -249.293452) (xy 379.154957 -249.244038) (xy 379.174905 -249.197218)
			(xy 379.202106 -249.154204) (xy 379.235854 -249.11611) (xy 379.275276 -249.083923) (xy 379.31935 -249.058477)
			(xy 379.366936 -249.04043) (xy 379.4168 -249.03025) (xy 379.467652 -249.028201) (xy 379.518173 -249.034335)
			(xy 379.567057 -249.048495) (xy 379.613036 -249.070312) (xy 379.65492 -249.099222) (xy 379.691624 -249.134477)
			(xy 379.722197 -249.175163) (xy 379.745848 -249.220226) (xy 379.761964 -249.2685) (xy 379.770128 -249.318734)
			(xy 379.77064 -249.34418) (xy 380.088914 -249.34418) (xy 380.092874 -249.295126) (xy 380.104651 -249.247342)
			(xy 380.123942 -249.202066) (xy 380.150245 -249.16047) (xy 380.18288 -249.123633) (xy 380.221001 -249.092508)
			(xy 380.263622 -249.067901) (xy 380.309638 -249.050449) (xy 380.357857 -249.040605) (xy 380.407032 -249.038624)
			(xy 380.455887 -249.044556) (xy 380.503158 -249.058248) (xy 380.54762 -249.079346) (xy 380.588123 -249.107302)
			(xy 380.623616 -249.141394) (xy 380.653181 -249.180738) (xy 380.676052 -249.224315) (xy 380.691636 -249.270996)
			(xy 380.699531 -249.319573) (xy 380.700026 -249.34418) (xy 380.699531 -249.368787) (xy 380.691636 -249.417364)
			(xy 380.676052 -249.464045) (xy 380.653181 -249.507622) (xy 380.623616 -249.546966) (xy 380.588123 -249.581058)
			(xy 380.54762 -249.609014) (xy 380.503158 -249.630112) (xy 380.455887 -249.643804) (xy 380.407032 -249.649736)
			(xy 380.357857 -249.647755) (xy 380.309638 -249.637911) (xy 380.263622 -249.620459) (xy 380.221001 -249.595852)
			(xy 380.18288 -249.564727) (xy 380.150245 -249.52789) (xy 380.123942 -249.486294) (xy 380.104651 -249.441018)
			(xy 380.092874 -249.393234) (xy 380.088914 -249.34418) (xy 379.77064 -249.34418) (xy 379.770128 -249.369626)
			(xy 379.761964 -249.41986) (xy 379.745848 -249.468134) (xy 379.722197 -249.513197) (xy 379.691624 -249.553883)
			(xy 379.65492 -249.589138) (xy 379.613036 -249.618048) (xy 379.567057 -249.639865) (xy 379.518173 -249.654025)
			(xy 379.467652 -249.660159) (xy 379.4168 -249.65811) (xy 379.366936 -249.64793) (xy 379.31935 -249.629883)
			(xy 379.275276 -249.604437) (xy 379.235854 -249.57225) (xy 379.202106 -249.534156) (xy 379.174905 -249.491142)
			(xy 379.154957 -249.444322) (xy 379.142778 -249.394908) (xy 379.138683 -249.34418) (xy 377.880118 -249.34418)
			(xy 377.879623 -249.368787) (xy 377.871728 -249.417364) (xy 377.856144 -249.464045) (xy 377.833273 -249.507622)
			(xy 377.803708 -249.546966) (xy 377.768215 -249.581058) (xy 377.727712 -249.609014) (xy 377.68325 -249.630112)
			(xy 377.635979 -249.643804) (xy 377.587124 -249.649736) (xy 377.537949 -249.647755) (xy 377.48973 -249.637911)
			(xy 377.443714 -249.620459) (xy 377.401093 -249.595852) (xy 377.362972 -249.564727) (xy 377.330337 -249.52789)
			(xy 377.304034 -249.486294) (xy 377.284743 -249.441018) (xy 377.272966 -249.393234) (xy 377.269006 -249.34418)
			(xy 376.940064 -249.34418) (xy 376.939569 -249.368787) (xy 376.931674 -249.417364) (xy 376.91609 -249.464045)
			(xy 376.893219 -249.507622) (xy 376.863654 -249.546966) (xy 376.828161 -249.581058) (xy 376.787658 -249.609014)
			(xy 376.743196 -249.630112) (xy 376.695925 -249.643804) (xy 376.64707 -249.649736) (xy 376.597895 -249.647755)
			(xy 376.549676 -249.637911) (xy 376.50366 -249.620459) (xy 376.461039 -249.595852) (xy 376.422918 -249.564727)
			(xy 376.390283 -249.52789) (xy 376.36398 -249.486294) (xy 376.344689 -249.441018) (xy 376.332912 -249.393234)
			(xy 376.328952 -249.34418) (xy 376.010424 -249.34418) (xy 376.009912 -249.369626) (xy 376.001748 -249.41986)
			(xy 375.985632 -249.468134) (xy 375.961981 -249.513197) (xy 375.931408 -249.553883) (xy 375.894704 -249.589138)
			(xy 375.85282 -249.618048) (xy 375.806841 -249.639865) (xy 375.757957 -249.654025) (xy 375.707436 -249.660159)
			(xy 375.656584 -249.65811) (xy 375.60672 -249.64793) (xy 375.559134 -249.629883) (xy 375.51506 -249.604437)
			(xy 375.475638 -249.57225) (xy 375.44189 -249.534156) (xy 375.414689 -249.491142) (xy 375.394741 -249.444322)
			(xy 375.382562 -249.394908) (xy 375.378467 -249.34418) (xy 375.11863 -249.34418) (xy 375.11863 -250.154186)
			(xy 375.848621 -250.154186) (xy 375.852716 -250.103458) (xy 375.864895 -250.054044) (xy 375.884843 -250.007224)
			(xy 375.912044 -249.96421) (xy 375.945792 -249.926116) (xy 375.985214 -249.893929) (xy 376.029288 -249.868483)
			(xy 376.076874 -249.850436) (xy 376.126738 -249.840256) (xy 376.17759 -249.838207) (xy 376.228111 -249.844341)
			(xy 376.276995 -249.858501) (xy 376.322974 -249.880318) (xy 376.364858 -249.909228) (xy 376.401562 -249.944483)
			(xy 376.432135 -249.985169) (xy 376.455786 -250.030232) (xy 376.471902 -250.078506) (xy 376.480066 -250.12874)
			(xy 376.480578 -250.154186) (xy 376.799106 -250.154186) (xy 376.803066 -250.105132) (xy 376.814843 -250.057348)
			(xy 376.834134 -250.012072) (xy 376.860437 -249.970476) (xy 376.893072 -249.933639) (xy 376.931193 -249.902514)
			(xy 376.973814 -249.877907) (xy 377.01983 -249.860455) (xy 377.068049 -249.850611) (xy 377.117224 -249.84863)
			(xy 377.166079 -249.854562) (xy 377.21335 -249.868254) (xy 377.257812 -249.889352) (xy 377.298315 -249.917308)
			(xy 377.333808 -249.9514) (xy 377.363373 -249.990744) (xy 377.386244 -250.034321) (xy 377.401828 -250.081002)
			(xy 377.409723 -250.129579) (xy 377.410218 -250.154186) (xy 377.738906 -250.154186) (xy 377.742866 -250.105132)
			(xy 377.754643 -250.057348) (xy 377.773934 -250.012072) (xy 377.800237 -249.970476) (xy 377.832872 -249.933639)
			(xy 377.870993 -249.902514) (xy 377.913614 -249.877907) (xy 377.95963 -249.860455) (xy 378.007849 -249.850611)
			(xy 378.057024 -249.84863) (xy 378.105879 -249.854562) (xy 378.15315 -249.868254) (xy 378.197612 -249.889352)
			(xy 378.238115 -249.917308) (xy 378.273608 -249.9514) (xy 378.303173 -249.990744) (xy 378.326044 -250.034321)
			(xy 378.341628 -250.081002) (xy 378.349523 -250.129579) (xy 378.350018 -250.154186) (xy 378.668529 -250.154186)
			(xy 378.672624 -250.103458) (xy 378.684803 -250.054044) (xy 378.704751 -250.007224) (xy 378.731952 -249.96421)
			(xy 378.7657 -249.926116) (xy 378.805122 -249.893929) (xy 378.849196 -249.868483) (xy 378.896782 -249.850436)
			(xy 378.946646 -249.840256) (xy 378.997498 -249.838207) (xy 379.048019 -249.844341) (xy 379.096903 -249.858501)
			(xy 379.142882 -249.880318) (xy 379.184766 -249.909228) (xy 379.22147 -249.944483) (xy 379.252043 -249.985169)
			(xy 379.275694 -250.030232) (xy 379.29181 -250.078506) (xy 379.299974 -250.12874) (xy 379.300486 -250.154186)
			(xy 379.619014 -250.154186) (xy 379.622974 -250.105132) (xy 379.634751 -250.057348) (xy 379.654042 -250.012072)
			(xy 379.680345 -249.970476) (xy 379.71298 -249.933639) (xy 379.751101 -249.902514) (xy 379.793722 -249.877907)
			(xy 379.839738 -249.860455) (xy 379.887957 -249.850611) (xy 379.937132 -249.84863) (xy 379.985987 -249.854562)
			(xy 380.033258 -249.868254) (xy 380.07772 -249.889352) (xy 380.118223 -249.917308) (xy 380.153716 -249.9514)
			(xy 380.183281 -249.990744) (xy 380.206152 -250.034321) (xy 380.221736 -250.081002) (xy 380.229631 -250.129579)
			(xy 380.230126 -250.154186) (xy 380.559068 -250.154186) (xy 380.563028 -250.105132) (xy 380.574805 -250.057348)
			(xy 380.594096 -250.012072) (xy 380.620399 -249.970476) (xy 380.653034 -249.933639) (xy 380.691155 -249.902514)
			(xy 380.733776 -249.877907) (xy 380.779792 -249.860455) (xy 380.828011 -249.850611) (xy 380.877186 -249.84863)
			(xy 380.926041 -249.854562) (xy 380.973312 -249.868254) (xy 381.017774 -249.889352) (xy 381.058277 -249.917308)
			(xy 381.09377 -249.9514) (xy 381.123335 -249.990744) (xy 381.146206 -250.034321) (xy 381.16179 -250.081002)
			(xy 381.169685 -250.129579) (xy 381.17018 -250.154186) (xy 381.169685 -250.178793) (xy 381.16179 -250.22737)
			(xy 381.146206 -250.274051) (xy 381.123335 -250.317628) (xy 381.09377 -250.356972) (xy 381.058277 -250.391064)
			(xy 381.017774 -250.41902) (xy 380.973312 -250.440118) (xy 380.926041 -250.45381) (xy 380.877186 -250.459742)
			(xy 380.828011 -250.457761) (xy 380.779792 -250.447917) (xy 380.733776 -250.430465) (xy 380.691155 -250.405858)
			(xy 380.653034 -250.374733) (xy 380.620399 -250.337896) (xy 380.594096 -250.2963) (xy 380.574805 -250.251024)
			(xy 380.563028 -250.20324) (xy 380.559068 -250.154186) (xy 380.230126 -250.154186) (xy 380.229631 -250.178793)
			(xy 380.221736 -250.22737) (xy 380.206152 -250.274051) (xy 380.183281 -250.317628) (xy 380.153716 -250.356972)
			(xy 380.118223 -250.391064) (xy 380.07772 -250.41902) (xy 380.033258 -250.440118) (xy 379.985987 -250.45381)
			(xy 379.937132 -250.459742) (xy 379.887957 -250.457761) (xy 379.839738 -250.447917) (xy 379.793722 -250.430465)
			(xy 379.751101 -250.405858) (xy 379.71298 -250.374733) (xy 379.680345 -250.337896) (xy 379.654042 -250.2963)
			(xy 379.634751 -250.251024) (xy 379.622974 -250.20324) (xy 379.619014 -250.154186) (xy 379.300486 -250.154186)
			(xy 379.299974 -250.179632) (xy 379.29181 -250.229866) (xy 379.275694 -250.27814) (xy 379.252043 -250.323203)
			(xy 379.22147 -250.363889) (xy 379.184766 -250.399144) (xy 379.142882 -250.428054) (xy 379.096903 -250.449871)
			(xy 379.048019 -250.464031) (xy 378.997498 -250.470165) (xy 378.946646 -250.468116) (xy 378.896782 -250.457936)
			(xy 378.849196 -250.439889) (xy 378.805122 -250.414443) (xy 378.7657 -250.382256) (xy 378.731952 -250.344162)
			(xy 378.704751 -250.301148) (xy 378.684803 -250.254328) (xy 378.672624 -250.204914) (xy 378.668529 -250.154186)
			(xy 378.350018 -250.154186) (xy 378.349523 -250.178793) (xy 378.341628 -250.22737) (xy 378.326044 -250.274051)
			(xy 378.303173 -250.317628) (xy 378.273608 -250.356972) (xy 378.238115 -250.391064) (xy 378.197612 -250.41902)
			(xy 378.15315 -250.440118) (xy 378.105879 -250.45381) (xy 378.057024 -250.459742) (xy 378.007849 -250.457761)
			(xy 377.95963 -250.447917) (xy 377.913614 -250.430465) (xy 377.870993 -250.405858) (xy 377.832872 -250.374733)
			(xy 377.800237 -250.337896) (xy 377.773934 -250.2963) (xy 377.754643 -250.251024) (xy 377.742866 -250.20324)
			(xy 377.738906 -250.154186) (xy 377.410218 -250.154186) (xy 377.409723 -250.178793) (xy 377.401828 -250.22737)
			(xy 377.386244 -250.274051) (xy 377.363373 -250.317628) (xy 377.333808 -250.356972) (xy 377.298315 -250.391064)
			(xy 377.257812 -250.41902) (xy 377.21335 -250.440118) (xy 377.166079 -250.45381) (xy 377.117224 -250.459742)
			(xy 377.068049 -250.457761) (xy 377.01983 -250.447917) (xy 376.973814 -250.430465) (xy 376.931193 -250.405858)
			(xy 376.893072 -250.374733) (xy 376.860437 -250.337896) (xy 376.834134 -250.2963) (xy 376.814843 -250.251024)
			(xy 376.803066 -250.20324) (xy 376.799106 -250.154186) (xy 376.480578 -250.154186) (xy 376.480066 -250.179632)
			(xy 376.471902 -250.229866) (xy 376.455786 -250.27814) (xy 376.432135 -250.323203) (xy 376.401562 -250.363889)
			(xy 376.364858 -250.399144) (xy 376.322974 -250.428054) (xy 376.276995 -250.449871) (xy 376.228111 -250.464031)
			(xy 376.17759 -250.470165) (xy 376.126738 -250.468116) (xy 376.076874 -250.457936) (xy 376.029288 -250.439889)
			(xy 375.985214 -250.414443) (xy 375.945792 -250.382256) (xy 375.912044 -250.344162) (xy 375.884843 -250.301148)
			(xy 375.864895 -250.254328) (xy 375.852716 -250.204914) (xy 375.848621 -250.154186) (xy 375.11863 -250.154186)
			(xy 375.11863 -250.478036) (xy 375.118201 -250.488104) (xy 375.110481 -250.506702) (xy 375.103644 -250.514104)
			(xy 374.991122 -250.626626) (xy 374.984727 -250.633614) (xy 374.977161 -250.650967) (xy 374.97639 -250.660408)
			(xy 374.973342 -250.739402) (xy 374.979692 -250.757182) (xy 374.986042 -250.764802) (xy 375.003354 -250.785764)
			(xy 375.031026 -250.832555) (xy 375.049969 -250.883508) (xy 375.059585 -250.937011) (xy 375.06021 -250.964192)
			(xy 375.378467 -250.964192) (xy 375.382562 -250.913464) (xy 375.394741 -250.86405) (xy 375.414689 -250.81723)
			(xy 375.44189 -250.774216) (xy 375.475638 -250.736122) (xy 375.51506 -250.703935) (xy 375.559134 -250.678489)
			(xy 375.60672 -250.660442) (xy 375.656584 -250.650262) (xy 375.707436 -250.648213) (xy 375.757957 -250.654347)
			(xy 375.806841 -250.668507) (xy 375.85282 -250.690324) (xy 375.894704 -250.719234) (xy 375.931408 -250.754489)
			(xy 375.961981 -250.795175) (xy 375.985632 -250.840238) (xy 376.001748 -250.888512) (xy 376.009912 -250.938746)
			(xy 376.010424 -250.964192) (xy 376.328952 -250.964192) (xy 376.332912 -250.915138) (xy 376.344689 -250.867354)
			(xy 376.36398 -250.822078) (xy 376.390283 -250.780482) (xy 376.422918 -250.743645) (xy 376.461039 -250.71252)
			(xy 376.50366 -250.687913) (xy 376.549676 -250.670461) (xy 376.597895 -250.660617) (xy 376.64707 -250.658636)
			(xy 376.695925 -250.664568) (xy 376.743196 -250.67826) (xy 376.787658 -250.699358) (xy 376.828161 -250.727314)
			(xy 376.863654 -250.761406) (xy 376.893219 -250.80075) (xy 376.91609 -250.844327) (xy 376.931674 -250.891008)
			(xy 376.939569 -250.939585) (xy 376.940064 -250.964192) (xy 377.258575 -250.964192) (xy 377.26267 -250.913464)
			(xy 377.274849 -250.86405) (xy 377.294797 -250.81723) (xy 377.321998 -250.774216) (xy 377.355746 -250.736122)
			(xy 377.395168 -250.703935) (xy 377.439242 -250.678489) (xy 377.486828 -250.660442) (xy 377.536692 -250.650262)
			(xy 377.587544 -250.648213) (xy 377.638065 -250.654347) (xy 377.686949 -250.668507) (xy 377.732928 -250.690324)
			(xy 377.774812 -250.719234) (xy 377.811516 -250.754489) (xy 377.842089 -250.795175) (xy 377.86574 -250.840238)
			(xy 377.881856 -250.888512) (xy 377.89002 -250.938746) (xy 377.890532 -250.964192) (xy 378.20906 -250.964192)
			(xy 378.21302 -250.915138) (xy 378.224797 -250.867354) (xy 378.244088 -250.822078) (xy 378.270391 -250.780482)
			(xy 378.303026 -250.743645) (xy 378.341147 -250.71252) (xy 378.383768 -250.687913) (xy 378.429784 -250.670461)
			(xy 378.478003 -250.660617) (xy 378.527178 -250.658636) (xy 378.576033 -250.664568) (xy 378.623304 -250.67826)
			(xy 378.667766 -250.699358) (xy 378.708269 -250.727314) (xy 378.743762 -250.761406) (xy 378.773327 -250.80075)
			(xy 378.796198 -250.844327) (xy 378.811782 -250.891008) (xy 378.819677 -250.939585) (xy 378.820172 -250.964192)
			(xy 379.138683 -250.964192) (xy 379.142778 -250.913464) (xy 379.154957 -250.86405) (xy 379.174905 -250.81723)
			(xy 379.202106 -250.774216) (xy 379.235854 -250.736122) (xy 379.275276 -250.703935) (xy 379.31935 -250.678489)
			(xy 379.366936 -250.660442) (xy 379.4168 -250.650262) (xy 379.467652 -250.648213) (xy 379.518173 -250.654347)
			(xy 379.567057 -250.668507) (xy 379.613036 -250.690324) (xy 379.65492 -250.719234) (xy 379.691624 -250.754489)
			(xy 379.722197 -250.795175) (xy 379.745848 -250.840238) (xy 379.761964 -250.888512) (xy 379.770128 -250.938746)
			(xy 379.77064 -250.964192) (xy 380.078483 -250.964192) (xy 380.082578 -250.913464) (xy 380.094757 -250.86405)
			(xy 380.114705 -250.81723) (xy 380.141906 -250.774216) (xy 380.175654 -250.736122) (xy 380.215076 -250.703935)
			(xy 380.25915 -250.678489) (xy 380.306736 -250.660442) (xy 380.3566 -250.650262) (xy 380.407452 -250.648213)
			(xy 380.457973 -250.654347) (xy 380.506857 -250.668507) (xy 380.552836 -250.690324) (xy 380.59472 -250.719234)
			(xy 380.631424 -250.754489) (xy 380.661997 -250.795175) (xy 380.685648 -250.840238) (xy 380.701764 -250.888512)
			(xy 380.709928 -250.938746) (xy 380.71044 -250.964192) (xy 380.709928 -250.989638) (xy 380.701764 -251.039872)
			(xy 380.685648 -251.088146) (xy 380.661997 -251.133209) (xy 380.631424 -251.173895) (xy 380.59472 -251.20915)
			(xy 380.552836 -251.23806) (xy 380.506857 -251.259877) (xy 380.457973 -251.274037) (xy 380.407452 -251.280171)
			(xy 380.3566 -251.278122) (xy 380.306736 -251.267942) (xy 380.25915 -251.249895) (xy 380.215076 -251.224449)
			(xy 380.175654 -251.192262) (xy 380.141906 -251.154168) (xy 380.114705 -251.111154) (xy 380.094757 -251.064334)
			(xy 380.082578 -251.01492) (xy 380.078483 -250.964192) (xy 379.77064 -250.964192) (xy 379.770128 -250.989638)
			(xy 379.761964 -251.039872) (xy 379.745848 -251.088146) (xy 379.722197 -251.133209) (xy 379.691624 -251.173895)
			(xy 379.65492 -251.20915) (xy 379.613036 -251.23806) (xy 379.567057 -251.259877) (xy 379.518173 -251.274037)
			(xy 379.467652 -251.280171) (xy 379.4168 -251.278122) (xy 379.366936 -251.267942) (xy 379.31935 -251.249895)
			(xy 379.275276 -251.224449) (xy 379.235854 -251.192262) (xy 379.202106 -251.154168) (xy 379.174905 -251.111154)
			(xy 379.154957 -251.064334) (xy 379.142778 -251.01492) (xy 379.138683 -250.964192) (xy 378.820172 -250.964192)
			(xy 378.819677 -250.988799) (xy 378.811782 -251.037376) (xy 378.796198 -251.084057) (xy 378.773327 -251.127634)
			(xy 378.743762 -251.166978) (xy 378.708269 -251.20107) (xy 378.667766 -251.229026) (xy 378.623304 -251.250124)
			(xy 378.576033 -251.263816) (xy 378.527178 -251.269748) (xy 378.478003 -251.267767) (xy 378.429784 -251.257923)
			(xy 378.383768 -251.240471) (xy 378.341147 -251.215864) (xy 378.303026 -251.184739) (xy 378.270391 -251.147902)
			(xy 378.244088 -251.106306) (xy 378.224797 -251.06103) (xy 378.21302 -251.013246) (xy 378.20906 -250.964192)
			(xy 377.890532 -250.964192) (xy 377.89002 -250.989638) (xy 377.881856 -251.039872) (xy 377.86574 -251.088146)
			(xy 377.842089 -251.133209) (xy 377.811516 -251.173895) (xy 377.774812 -251.20915) (xy 377.732928 -251.23806)
			(xy 377.686949 -251.259877) (xy 377.638065 -251.274037) (xy 377.587544 -251.280171) (xy 377.536692 -251.278122)
			(xy 377.486828 -251.267942) (xy 377.439242 -251.249895) (xy 377.395168 -251.224449) (xy 377.355746 -251.192262)
			(xy 377.321998 -251.154168) (xy 377.294797 -251.111154) (xy 377.274849 -251.064334) (xy 377.26267 -251.01492)
			(xy 377.258575 -250.964192) (xy 376.940064 -250.964192) (xy 376.939569 -250.988799) (xy 376.931674 -251.037376)
			(xy 376.91609 -251.084057) (xy 376.893219 -251.127634) (xy 376.863654 -251.166978) (xy 376.828161 -251.20107)
			(xy 376.787658 -251.229026) (xy 376.743196 -251.250124) (xy 376.695925 -251.263816) (xy 376.64707 -251.269748)
			(xy 376.597895 -251.267767) (xy 376.549676 -251.257923) (xy 376.50366 -251.240471) (xy 376.461039 -251.215864)
			(xy 376.422918 -251.184739) (xy 376.390283 -251.147902) (xy 376.36398 -251.106306) (xy 376.344689 -251.06103)
			(xy 376.332912 -251.013246) (xy 376.328952 -250.964192) (xy 376.010424 -250.964192) (xy 376.009912 -250.989638)
			(xy 376.001748 -251.039872) (xy 375.985632 -251.088146) (xy 375.961981 -251.133209) (xy 375.931408 -251.173895)
			(xy 375.894704 -251.20915) (xy 375.85282 -251.23806) (xy 375.806841 -251.259877) (xy 375.757957 -251.274037)
			(xy 375.707436 -251.280171) (xy 375.656584 -251.278122) (xy 375.60672 -251.267942) (xy 375.559134 -251.249895)
			(xy 375.51506 -251.224449) (xy 375.475638 -251.192262) (xy 375.44189 -251.154168) (xy 375.414689 -251.111154)
			(xy 375.394741 -251.064334) (xy 375.382562 -251.01492) (xy 375.378467 -250.964192) (xy 375.06021 -250.964192)
			(xy 375.059764 -250.988186) (xy 375.052259 -251.035582) (xy 375.037431 -251.081221) (xy 375.015646 -251.123978)
			(xy 374.987441 -251.162801) (xy 374.953509 -251.196734) (xy 374.914687 -251.224941) (xy 374.87193 -251.246727)
			(xy 374.826292 -251.261556) (xy 374.778896 -251.269064) (xy 374.754902 -251.2695) (xy 374.72772 -251.268906)
			(xy 374.674216 -251.259277) (xy 374.623264 -251.240325) (xy 374.576474 -251.212647) (xy 374.555512 -251.195332)
			(xy 374.547892 -251.188982) (xy 374.530112 -251.182632) (xy 374.451118 -251.18568) (xy 374.441671 -251.186435)
			(xy 374.424308 -251.193995) (xy 374.417336 -251.200412) (xy 374.310402 -251.307346) (xy 374.304335 -251.31396)
			(xy 374.296844 -251.330259) (xy 374.295395 -251.348139) (xy 374.297448 -251.356876) (xy 374.32488 -251.455428)
			(xy 374.344438 -251.474478) (xy 374.3579 -251.47778) (xy 374.382417 -251.484344) (xy 374.429005 -251.504476)
			(xy 374.471622 -251.532036) (xy 374.509095 -251.566263) (xy 374.540392 -251.606216) (xy 374.564651 -251.650794)
			(xy 374.581205 -251.698769) (xy 374.589598 -251.748822) (xy 374.590056 -251.774198) (xy 375.848621 -251.774198)
			(xy 375.852716 -251.72347) (xy 375.864895 -251.674056) (xy 375.884843 -251.627236) (xy 375.912044 -251.584222)
			(xy 375.945792 -251.546128) (xy 375.985214 -251.513941) (xy 376.029288 -251.488495) (xy 376.076874 -251.470448)
			(xy 376.126738 -251.460268) (xy 376.17759 -251.458219) (xy 376.228111 -251.464353) (xy 376.276995 -251.478513)
			(xy 376.322974 -251.50033) (xy 376.364858 -251.52924) (xy 376.401562 -251.564495) (xy 376.432135 -251.605181)
			(xy 376.455786 -251.650244) (xy 376.471902 -251.698518) (xy 376.480066 -251.748752) (xy 376.480578 -251.774198)
			(xy 376.799106 -251.774198) (xy 376.803066 -251.725144) (xy 376.814843 -251.67736) (xy 376.834134 -251.632084)
			(xy 376.860437 -251.590488) (xy 376.893072 -251.553651) (xy 376.931193 -251.522526) (xy 376.973814 -251.497919)
			(xy 377.01983 -251.480467) (xy 377.068049 -251.470623) (xy 377.117224 -251.468642) (xy 377.166079 -251.474574)
			(xy 377.21335 -251.488266) (xy 377.257812 -251.509364) (xy 377.298315 -251.53732) (xy 377.333808 -251.571412)
			(xy 377.363373 -251.610756) (xy 377.386244 -251.654333) (xy 377.401828 -251.701014) (xy 377.409723 -251.749591)
			(xy 377.410218 -251.774198) (xy 378.668529 -251.774198) (xy 378.672624 -251.72347) (xy 378.684803 -251.674056)
			(xy 378.704751 -251.627236) (xy 378.731952 -251.584222) (xy 378.7657 -251.546128) (xy 378.805122 -251.513941)
			(xy 378.849196 -251.488495) (xy 378.896782 -251.470448) (xy 378.946646 -251.460268) (xy 378.997498 -251.458219)
			(xy 379.048019 -251.464353) (xy 379.096903 -251.478513) (xy 379.142882 -251.50033) (xy 379.184766 -251.52924)
			(xy 379.22147 -251.564495) (xy 379.252043 -251.605181) (xy 379.275694 -251.650244) (xy 379.29181 -251.698518)
			(xy 379.299974 -251.748752) (xy 379.300486 -251.774198) (xy 379.619014 -251.774198) (xy 379.622974 -251.725144)
			(xy 379.634751 -251.67736) (xy 379.654042 -251.632084) (xy 379.680345 -251.590488) (xy 379.71298 -251.553651)
			(xy 379.751101 -251.522526) (xy 379.793722 -251.497919) (xy 379.839738 -251.480467) (xy 379.887957 -251.470623)
			(xy 379.937132 -251.468642) (xy 379.985987 -251.474574) (xy 380.033258 -251.488266) (xy 380.07772 -251.509364)
			(xy 380.118223 -251.53732) (xy 380.153716 -251.571412) (xy 380.183281 -251.610756) (xy 380.206152 -251.654333)
			(xy 380.221736 -251.701014) (xy 380.229631 -251.749591) (xy 380.230126 -251.774198) (xy 380.559068 -251.774198)
			(xy 380.563028 -251.725144) (xy 380.574805 -251.67736) (xy 380.594096 -251.632084) (xy 380.620399 -251.590488)
			(xy 380.653034 -251.553651) (xy 380.691155 -251.522526) (xy 380.733776 -251.497919) (xy 380.779792 -251.480467)
			(xy 380.828011 -251.470623) (xy 380.877186 -251.468642) (xy 380.926041 -251.474574) (xy 380.973312 -251.488266)
			(xy 381.017774 -251.509364) (xy 381.058277 -251.53732) (xy 381.09377 -251.571412) (xy 381.123335 -251.610756)
			(xy 381.146206 -251.654333) (xy 381.16179 -251.701014) (xy 381.169685 -251.749591) (xy 381.17018 -251.774198)
			(xy 381.169685 -251.798805) (xy 381.16179 -251.847382) (xy 381.146206 -251.894063) (xy 381.123335 -251.93764)
			(xy 381.09377 -251.976984) (xy 381.058277 -252.011076) (xy 381.017774 -252.039032) (xy 380.973312 -252.06013)
			(xy 380.926041 -252.073822) (xy 380.877186 -252.079754) (xy 380.828011 -252.077773) (xy 380.779792 -252.067929)
			(xy 380.733776 -252.050477) (xy 380.691155 -252.02587) (xy 380.653034 -251.994745) (xy 380.620399 -251.957908)
			(xy 380.594096 -251.916312) (xy 380.574805 -251.871036) (xy 380.563028 -251.823252) (xy 380.559068 -251.774198)
			(xy 380.230126 -251.774198) (xy 380.229631 -251.798805) (xy 380.221736 -251.847382) (xy 380.206152 -251.894063)
			(xy 380.183281 -251.93764) (xy 380.153716 -251.976984) (xy 380.118223 -252.011076) (xy 380.07772 -252.039032)
			(xy 380.033258 -252.06013) (xy 379.985987 -252.073822) (xy 379.937132 -252.079754) (xy 379.887957 -252.077773)
			(xy 379.839738 -252.067929) (xy 379.793722 -252.050477) (xy 379.751101 -252.02587) (xy 379.71298 -251.994745)
			(xy 379.680345 -251.957908) (xy 379.654042 -251.916312) (xy 379.634751 -251.871036) (xy 379.622974 -251.823252)
			(xy 379.619014 -251.774198) (xy 379.300486 -251.774198) (xy 379.299974 -251.799644) (xy 379.29181 -251.849878)
			(xy 379.275694 -251.898152) (xy 379.252043 -251.943215) (xy 379.22147 -251.983901) (xy 379.184766 -252.019156)
			(xy 379.142882 -252.048066) (xy 379.096903 -252.069883) (xy 379.048019 -252.084043) (xy 378.997498 -252.090177)
			(xy 378.946646 -252.088128) (xy 378.896782 -252.077948) (xy 378.849196 -252.059901) (xy 378.805122 -252.034455)
			(xy 378.7657 -252.002268) (xy 378.731952 -251.964174) (xy 378.704751 -251.92116) (xy 378.684803 -251.87434)
			(xy 378.672624 -251.824926) (xy 378.668529 -251.774198) (xy 377.410218 -251.774198) (xy 377.409723 -251.798805)
			(xy 377.401828 -251.847382) (xy 377.386244 -251.894063) (xy 377.363373 -251.93764) (xy 377.333808 -251.976984)
			(xy 377.298315 -252.011076) (xy 377.257812 -252.039032) (xy 377.21335 -252.06013) (xy 377.166079 -252.073822)
			(xy 377.117224 -252.079754) (xy 377.068049 -252.077773) (xy 377.01983 -252.067929) (xy 376.973814 -252.050477)
			(xy 376.931193 -252.02587) (xy 376.893072 -251.994745) (xy 376.860437 -251.957908) (xy 376.834134 -251.916312)
			(xy 376.814843 -251.871036) (xy 376.803066 -251.823252) (xy 376.799106 -251.774198) (xy 376.480578 -251.774198)
			(xy 376.480066 -251.799644) (xy 376.471902 -251.849878) (xy 376.455786 -251.898152) (xy 376.432135 -251.943215)
			(xy 376.401562 -251.983901) (xy 376.364858 -252.019156) (xy 376.322974 -252.048066) (xy 376.276995 -252.069883)
			(xy 376.228111 -252.084043) (xy 376.17759 -252.090177) (xy 376.126738 -252.088128) (xy 376.076874 -252.077948)
			(xy 376.029288 -252.059901) (xy 375.985214 -252.034455) (xy 375.945792 -252.002268) (xy 375.912044 -251.964174)
			(xy 375.884843 -251.92116) (xy 375.864895 -251.87434) (xy 375.852716 -251.824926) (xy 375.848621 -251.774198)
			(xy 374.590056 -251.774198) (xy 374.589534 -251.799453) (xy 374.581221 -251.849275) (xy 374.56482 -251.897049)
			(xy 374.540779 -251.941472) (xy 374.509755 -251.981332) (xy 374.472593 -252.015542) (xy 374.430307 -252.043168)
			(xy 374.384051 -252.063458) (xy 374.335086 -252.075858) (xy 374.284748 -252.080029) (xy 374.23441 -252.075858)
			(xy 374.185445 -252.063458) (xy 374.139189 -252.043168) (xy 374.096903 -252.015542) (xy 374.059741 -251.981332)
			(xy 374.028717 -251.941472) (xy 374.004676 -251.897049) (xy 373.988275 -251.849275) (xy 373.979962 -251.799453)
			(xy 373.97944 -251.774198) (xy 373.979995 -251.748079) (xy 373.988936 -251.696612) (xy 373.99722 -251.671836)
			(xy 374.001284 -251.659898) (xy 373.997982 -251.635768) (xy 373.942864 -251.55779) (xy 373.935248 -251.548146)
			(xy 373.913477 -251.536838) (xy 373.901208 -251.5362) (xy 372.788434 -251.5362) (xy 372.776183 -251.536919)
			(xy 372.75443 -251.548196) (xy 372.746778 -251.55779) (xy 372.69166 -251.635768) (xy 372.688358 -251.659898)
			(xy 372.692422 -251.671836) (xy 372.700696 -251.696615) (xy 372.709634 -251.748081) (xy 372.710202 -251.774198)
			(xy 372.70968 -251.799453) (xy 372.701367 -251.849275) (xy 372.684966 -251.897049) (xy 372.660925 -251.941472)
			(xy 372.629901 -251.981332) (xy 372.592739 -252.015542) (xy 372.550453 -252.043168) (xy 372.504197 -252.063458)
			(xy 372.455232 -252.075858) (xy 372.404894 -252.080029) (xy 372.354556 -252.075858) (xy 372.305591 -252.063458)
			(xy 372.259335 -252.043168) (xy 372.217049 -252.015542) (xy 372.179887 -251.981332) (xy 372.148863 -251.941472)
			(xy 372.124822 -251.897049) (xy 372.108421 -251.849275) (xy 372.100108 -251.799453) (xy 372.099586 -251.774198)
			(xy 372.100141 -251.748079) (xy 372.10908 -251.696612) (xy 372.117366 -251.671836) (xy 372.12143 -251.659898)
			(xy 372.118128 -251.635768) (xy 372.06301 -251.55779) (xy 372.05539 -251.548156) (xy 372.033619 -251.53687)
			(xy 372.021354 -251.5362) (xy 370.908326 -251.5362) (xy 370.896076 -251.536921) (xy 370.874325 -251.548199)
			(xy 370.86667 -251.55779) (xy 370.811552 -251.635768) (xy 370.80825 -251.659898) (xy 370.812314 -251.671836)
			(xy 370.820588 -251.696615) (xy 370.829527 -251.748081) (xy 370.830094 -251.774198) (xy 370.829572 -251.799453)
			(xy 370.821259 -251.849275) (xy 370.804858 -251.897049) (xy 370.780817 -251.941472) (xy 370.749793 -251.981332)
			(xy 370.712631 -252.015542) (xy 370.670345 -252.043168) (xy 370.624089 -252.063458) (xy 370.575124 -252.075858)
			(xy 370.524786 -252.080029) (xy 370.474448 -252.075858) (xy 370.425483 -252.063458) (xy 370.379227 -252.043168)
			(xy 370.336941 -252.015542) (xy 370.299779 -251.981332) (xy 370.268755 -251.941472) (xy 370.244714 -251.897049)
			(xy 370.228313 -251.849275) (xy 370.22 -251.799453) (xy 370.219478 -251.774198) (xy 370.220033 -251.748079)
			(xy 370.228972 -251.696612) (xy 370.237258 -251.671836) (xy 370.241322 -251.659898) (xy 370.23802 -251.635768)
			(xy 370.182902 -251.55779) (xy 370.175282 -251.548157) (xy 370.15351 -251.536875) (xy 370.141246 -251.5362)
			(xy 369.028218 -251.5362) (xy 369.015969 -251.536923) (xy 368.994221 -251.548203) (xy 368.986562 -251.55779)
			(xy 368.931444 -251.635768) (xy 368.928142 -251.659898) (xy 368.932206 -251.671836) (xy 368.94048 -251.696615)
			(xy 368.949419 -251.748081) (xy 368.949986 -251.774198) (xy 368.949464 -251.799453) (xy 368.941151 -251.849275)
			(xy 368.92475 -251.897049) (xy 368.900709 -251.941472) (xy 368.869685 -251.981332) (xy 368.832523 -252.015542)
			(xy 368.790237 -252.043168) (xy 368.743981 -252.063458) (xy 368.695016 -252.075858) (xy 368.644678 -252.080029)
			(xy 368.59434 -252.075858) (xy 368.545375 -252.063458) (xy 368.499119 -252.043168) (xy 368.456833 -252.015542)
			(xy 368.419671 -251.981332) (xy 368.388647 -251.941472) (xy 368.364606 -251.897049) (xy 368.348205 -251.849275)
			(xy 368.339892 -251.799453) (xy 368.33937 -251.774198) (xy 368.339925 -251.748079) (xy 368.348864 -251.696612)
			(xy 368.35715 -251.671836) (xy 368.361214 -251.659898) (xy 368.357912 -251.635768) (xy 368.302794 -251.55779)
			(xy 368.295173 -251.548158) (xy 368.273402 -251.53688) (xy 368.261138 -251.5362) (xy 367.148364 -251.5362)
			(xy 367.13611 -251.536913) (xy 367.114345 -251.548182) (xy 367.106708 -251.55779) (xy 367.05159 -251.635768)
			(xy 367.048288 -251.659898) (xy 367.052352 -251.671836) (xy 367.060628 -251.696614) (xy 367.069568 -251.74808)
			(xy 367.070132 -251.774198) (xy 367.06961 -251.799453) (xy 367.061297 -251.849275) (xy 367.044896 -251.897049)
			(xy 367.020855 -251.941472) (xy 366.989831 -251.981332) (xy 366.952669 -252.015542) (xy 366.910383 -252.043168)
			(xy 366.864127 -252.063458) (xy 366.815162 -252.075858) (xy 366.764824 -252.080029) (xy 366.714486 -252.075858)
			(xy 366.665521 -252.063458) (xy 366.619265 -252.043168) (xy 366.576979 -252.015542) (xy 366.539817 -251.981332)
			(xy 366.508793 -251.941472) (xy 366.484752 -251.897049) (xy 366.468351 -251.849275) (xy 366.460038 -251.799453)
			(xy 366.459516 -251.774198) (xy 366.460071 -251.748079) (xy 366.469011 -251.696612) (xy 366.477296 -251.671836)
			(xy 366.48136 -251.659898) (xy 366.478058 -251.635768) (xy 366.42294 -251.55779) (xy 366.415323 -251.54815)
			(xy 366.393551 -251.536852) (xy 366.381284 -251.5362) (xy 365.268256 -251.5362) (xy 365.256003 -251.536914)
			(xy 365.234241 -251.548186) (xy 365.2266 -251.55779) (xy 365.171482 -251.635768) (xy 365.16818 -251.659898)
			(xy 365.172244 -251.671836) (xy 365.18052 -251.696614) (xy 365.189461 -251.74808) (xy 365.190024 -251.774198)
			(xy 365.189502 -251.799453) (xy 365.181189 -251.849275) (xy 365.164788 -251.897049) (xy 365.140747 -251.941472)
			(xy 365.109723 -251.981332) (xy 365.072561 -252.015542) (xy 365.030275 -252.043168) (xy 364.984019 -252.063458)
			(xy 364.935054 -252.075858) (xy 364.884716 -252.080029) (xy 364.834378 -252.075858) (xy 364.785413 -252.063458)
			(xy 364.739157 -252.043168) (xy 364.696871 -252.015542) (xy 364.659709 -251.981332) (xy 364.628685 -251.941472)
			(xy 364.604644 -251.897049) (xy 364.588243 -251.849275) (xy 364.57993 -251.799453) (xy 364.579408 -251.774198)
			(xy 364.579963 -251.748079) (xy 364.588903 -251.696612) (xy 364.597188 -251.671836) (xy 364.601252 -251.659898)
			(xy 364.59795 -251.635768) (xy 364.542832 -251.55779) (xy 364.535214 -251.548152) (xy 364.513443 -251.536857)
			(xy 364.501176 -251.5362) (xy 363.388402 -251.5362) (xy 363.376155 -251.536926) (xy 363.354413 -251.54821)
			(xy 363.346746 -251.55779) (xy 363.291628 -251.635768) (xy 363.288326 -251.659898) (xy 363.29239 -251.671836)
			(xy 363.300665 -251.696614) (xy 363.309604 -251.74808) (xy 363.31017 -251.774198) (xy 363.309648 -251.799453)
			(xy 363.301335 -251.849275) (xy 363.284934 -251.897049) (xy 363.260893 -251.941472) (xy 363.229869 -251.981332)
			(xy 363.192707 -252.015542) (xy 363.150421 -252.043168) (xy 363.104165 -252.063458) (xy 363.0552 -252.075858)
			(xy 363.004862 -252.080029) (xy 362.954524 -252.075858) (xy 362.905559 -252.063458) (xy 362.859303 -252.043168)
			(xy 362.817017 -252.015542) (xy 362.779855 -251.981332) (xy 362.748831 -251.941472) (xy 362.72479 -251.897049)
			(xy 362.708389 -251.849275) (xy 362.700076 -251.799453) (xy 362.699554 -251.774198) (xy 362.700109 -251.748079)
			(xy 362.70905 -251.696612) (xy 362.717334 -251.671836) (xy 362.721398 -251.659898) (xy 362.718096 -251.635768)
			(xy 362.662978 -251.55779) (xy 362.655357 -251.548161) (xy 362.633584 -251.536889) (xy 362.621322 -251.5362)
			(xy 361.508294 -251.5362) (xy 361.496048 -251.536928) (xy 361.474309 -251.548214) (xy 361.466638 -251.55779)
			(xy 361.41152 -251.635768) (xy 361.408218 -251.659898) (xy 361.412282 -251.671836) (xy 361.420557 -251.696614)
			(xy 361.429497 -251.74808) (xy 361.430062 -251.774198) (xy 361.42954 -251.799453) (xy 361.421227 -251.849275)
			(xy 361.404826 -251.897049) (xy 361.380785 -251.941472) (xy 361.349761 -251.981332) (xy 361.312599 -252.015542)
			(xy 361.270313 -252.043168) (xy 361.224057 -252.063458) (xy 361.175092 -252.075858) (xy 361.124754 -252.080029)
			(xy 361.074416 -252.075858) (xy 361.025451 -252.063458) (xy 360.979195 -252.043168) (xy 360.936909 -252.015542)
			(xy 360.899747 -251.981332) (xy 360.868723 -251.941472) (xy 360.844682 -251.897049) (xy 360.828281 -251.849275)
			(xy 360.819968 -251.799453) (xy 360.819446 -251.774198) (xy 360.820001 -251.748079) (xy 360.828942 -251.696612)
			(xy 360.837226 -251.671836) (xy 360.84129 -251.659898) (xy 360.837988 -251.635768) (xy 360.78287 -251.55779)
			(xy 360.775255 -251.548145) (xy 360.753483 -251.536834) (xy 360.741214 -251.5362) (xy 360.549698 -251.5362)
			(xy 360.525822 -251.550424) (xy 360.519218 -251.56287) (xy 360.506268 -251.585939) (xy 360.474377 -251.628149)
			(xy 360.43639 -251.664968) (xy 360.393206 -251.695527) (xy 360.345846 -251.719102) (xy 360.295432 -251.735135)
			(xy 360.243155 -251.743248) (xy 360.190253 -251.743248) (xy 360.137976 -251.735135) (xy 360.087562 -251.719102)
			(xy 360.040202 -251.695527) (xy 359.997018 -251.664968) (xy 359.959031 -251.628149) (xy 359.92714 -251.585939)
			(xy 359.91419 -251.56287) (xy 359.907586 -251.550424) (xy 359.88371 -251.5362) (xy 359.678224 -251.5362)
			(xy 359.671183 -251.536418) (xy 359.657641 -251.540276) (xy 359.651554 -251.54382) (xy 359.645204 -251.54763)
			(xy 359.635806 -251.558044) (xy 359.632504 -251.564394) (xy 359.61993 -251.588626) (xy 359.588719 -251.633417)
			(xy 359.551243 -251.673114) (xy 359.508322 -251.706849) (xy 359.460895 -251.733885) (xy 359.409998 -251.753631)
			(xy 359.356747 -251.765653) (xy 359.302304 -251.76969) (xy 359.247861 -251.765653) (xy 359.19461 -251.753631)
			(xy 359.143713 -251.733885) (xy 359.096286 -251.706849) (xy 359.053365 -251.673114) (xy 359.015889 -251.633417)
			(xy 358.984678 -251.588626) (xy 358.972104 -251.564394) (xy 358.968802 -251.558044) (xy 358.959404 -251.54763)
			(xy 358.953054 -251.54382) (xy 358.946939 -251.540337) (xy 358.933416 -251.536467) (xy 358.926384 -251.5362)
			(xy 357.754682 -251.5362) (xy 357.742438 -251.53693) (xy 357.720702 -251.548219) (xy 357.713026 -251.55779)
			(xy 357.657908 -251.635768) (xy 357.654606 -251.659898) (xy 357.65867 -251.671836) (xy 357.666945 -251.696614)
			(xy 357.675885 -251.74808) (xy 357.67645 -251.774198) (xy 357.675928 -251.799453) (xy 357.667615 -251.849275)
			(xy 357.651214 -251.897049) (xy 357.627173 -251.941472) (xy 357.596149 -251.981332) (xy 357.558987 -252.015542)
			(xy 357.516701 -252.043168) (xy 357.470445 -252.063458) (xy 357.42148 -252.075858) (xy 357.371142 -252.080029)
			(xy 357.320804 -252.075858) (xy 357.271839 -252.063458) (xy 357.225583 -252.043168) (xy 357.183297 -252.015542)
			(xy 357.146135 -251.981332) (xy 357.115111 -251.941472) (xy 357.09107 -251.897049) (xy 357.074669 -251.849275)
			(xy 357.066356 -251.799453) (xy 357.065834 -251.774198) (xy 357.066389 -251.748079) (xy 357.07533 -251.696612)
			(xy 357.083614 -251.671836) (xy 357.087678 -251.659898) (xy 357.084376 -251.635768) (xy 357.029258 -251.55779)
			(xy 357.021642 -251.548147) (xy 356.999871 -251.536841) (xy 356.987602 -251.5362) (xy 355.874574 -251.5362)
			(xy 355.862331 -251.536932) (xy 355.840598 -251.548223) (xy 355.832918 -251.55779) (xy 355.7778 -251.635768)
			(xy 355.774498 -251.659898) (xy 355.778562 -251.671836) (xy 355.786838 -251.696614) (xy 355.795778 -251.74808)
			(xy 355.796342 -251.774198) (xy 355.79582 -251.799453) (xy 355.787507 -251.849275) (xy 355.771106 -251.897049)
			(xy 355.747065 -251.941472) (xy 355.716041 -251.981332) (xy 355.678879 -252.015542) (xy 355.636593 -252.043168)
			(xy 355.590337 -252.063458) (xy 355.541372 -252.075858) (xy 355.491034 -252.080029) (xy 355.440696 -252.075858)
			(xy 355.391731 -252.063458) (xy 355.345475 -252.043168) (xy 355.303189 -252.015542) (xy 355.266027 -251.981332)
			(xy 355.235003 -251.941472) (xy 355.210962 -251.897049) (xy 355.194561 -251.849275) (xy 355.186248 -251.799453)
			(xy 355.185726 -251.774198) (xy 355.186281 -251.748079) (xy 355.195222 -251.696612) (xy 355.203506 -251.671836)
			(xy 355.20757 -251.659898) (xy 355.204268 -251.635768) (xy 355.14915 -251.55779) (xy 355.141533 -251.548149)
			(xy 355.119762 -251.536846) (xy 355.107494 -251.5362) (xy 353.99472 -251.5362) (xy 353.982471 -251.536922)
			(xy 353.960722 -251.548202) (xy 353.953064 -251.55779) (xy 353.897946 -251.635768) (xy 353.894644 -251.659898)
			(xy 353.898708 -251.671836) (xy 353.906982 -251.696615) (xy 353.915921 -251.748081) (xy 353.916488 -251.774198)
			(xy 353.915966 -251.799453) (xy 353.907653 -251.849275) (xy 353.891252 -251.897049) (xy 353.867211 -251.941472)
			(xy 353.836187 -251.981332) (xy 353.799025 -252.015542) (xy 353.756739 -252.043168) (xy 353.710483 -252.063458)
			(xy 353.661518 -252.075858) (xy 353.61118 -252.080029) (xy 353.560842 -252.075858) (xy 353.511877 -252.063458)
			(xy 353.465621 -252.043168) (xy 353.423335 -252.015542) (xy 353.386173 -251.981332) (xy 353.355149 -251.941472)
			(xy 353.331108 -251.897049) (xy 353.314707 -251.849275) (xy 353.306394 -251.799453) (xy 353.305872 -251.774198)
			(xy 353.306427 -251.748079) (xy 353.315366 -251.696612) (xy 353.323652 -251.671836) (xy 353.327716 -251.659898)
			(xy 353.324414 -251.635768) (xy 353.269296 -251.55779) (xy 353.261676 -251.548158) (xy 353.239904 -251.536878)
			(xy 353.22764 -251.5362) (xy 352.114612 -251.5362) (xy 352.102364 -251.536924) (xy 352.080618 -251.548206)
			(xy 352.072956 -251.55779) (xy 352.017838 -251.635768) (xy 352.014536 -251.659898) (xy 352.0186 -251.671836)
			(xy 352.026875 -251.696615) (xy 352.035814 -251.74808) (xy 352.03638 -251.774198) (xy 352.035858 -251.799453)
			(xy 352.027545 -251.849275) (xy 352.011144 -251.897049) (xy 351.987103 -251.941472) (xy 351.956079 -251.981332)
			(xy 351.918917 -252.015542) (xy 351.876631 -252.043168) (xy 351.830375 -252.063458) (xy 351.78141 -252.075858)
			(xy 351.731072 -252.080029) (xy 351.680734 -252.075858) (xy 351.631769 -252.063458) (xy 351.585513 -252.043168)
			(xy 351.543227 -252.015542) (xy 351.506065 -251.981332) (xy 351.475041 -251.941472) (xy 351.451 -251.897049)
			(xy 351.434599 -251.849275) (xy 351.426286 -251.799453) (xy 351.425764 -251.774198) (xy 351.426319 -251.748079)
			(xy 351.435258 -251.696612) (xy 351.443544 -251.671836) (xy 351.447608 -251.659898) (xy 351.444306 -251.635768)
			(xy 351.389188 -251.55779) (xy 351.381567 -251.548159) (xy 351.359795 -251.536883) (xy 351.347532 -251.5362)
			(xy 350.160082 -251.5362) (xy 350.150013 -251.536627) (xy 350.131414 -251.544346) (xy 350.124014 -251.551186)
			(xy 350.108012 -251.567188) (xy 350.103694 -251.601732) (xy 350.112838 -251.616718) (xy 350.126566 -251.640666)
			(xy 350.146067 -251.692299) (xy 350.155952 -251.746601) (xy 350.156526 -251.774198) (xy 350.156526 -251.780294)
			(xy 350.155606 -251.80397) (xy 350.147354 -251.850624) (xy 350.131993 -251.895444) (xy 350.109892 -251.937352)
			(xy 350.081582 -251.975343) (xy 350.047743 -252.008504) (xy 350.009187 -252.03604) (xy 349.966841 -252.057288)
			(xy 349.921719 -252.071739) (xy 349.874908 -252.079046) (xy 349.851218 -252.079506) (xy 349.823624 -252.07891)
			(xy 349.769331 -252.069004) (xy 349.717694 -252.049526) (xy 349.693738 -252.035818) (xy 349.678752 -252.026674)
			(xy 349.644208 -252.030992) (xy 349.514414 -252.160786) (xy 349.506571 -252.169454) (xy 349.499021 -252.191551)
			(xy 349.499936 -252.203204) (xy 349.51162 -252.294898) (xy 349.52432 -252.314456) (xy 349.534988 -252.320552)
			(xy 349.557613 -252.334427) (xy 349.598123 -252.368708) (xy 349.632098 -252.409475) (xy 349.636021 -252.41631)
			(xy 359.853741 -252.41631) (xy 359.857771 -252.363812) (xy 359.869768 -252.312544) (xy 359.889451 -252.263709)
			(xy 359.916357 -252.21845) (xy 359.949857 -252.177829) (xy 359.989165 -252.142798) (xy 360.03336 -252.114178)
			(xy 360.081405 -252.092639) (xy 360.132176 -252.078687) (xy 360.184481 -252.072649) (xy 360.237095 -252.074666)
			(xy 360.288785 -252.08469) (xy 360.338338 -252.102488) (xy 360.384594 -252.127641) (xy 360.426468 -252.15956)
			(xy 360.46298 -252.197498) (xy 360.493272 -252.240564) (xy 360.516635 -252.287749) (xy 360.532521 -252.337948)
			(xy 360.540558 -252.389984) (xy 360.541062 -252.41631) (xy 360.540558 -252.442636) (xy 360.532521 -252.494672)
			(xy 360.516635 -252.544871) (xy 360.49716 -252.584204) (xy 368.809028 -252.584204) (xy 368.812988 -252.53515)
			(xy 368.824765 -252.487366) (xy 368.844056 -252.44209) (xy 368.870359 -252.400494) (xy 368.902994 -252.363657)
			(xy 368.941115 -252.332532) (xy 368.983736 -252.307925) (xy 369.029752 -252.290473) (xy 369.077971 -252.280629)
			(xy 369.127146 -252.278648) (xy 369.176001 -252.28458) (xy 369.223272 -252.298272) (xy 369.267734 -252.31937)
			(xy 369.308237 -252.347326) (xy 369.34373 -252.381418) (xy 369.373295 -252.420762) (xy 369.396166 -252.464339)
			(xy 369.41175 -252.51102) (xy 369.419645 -252.559597) (xy 369.42014 -252.584204) (xy 370.688882 -252.584204)
			(xy 370.692842 -252.53515) (xy 370.704619 -252.487366) (xy 370.72391 -252.44209) (xy 370.750213 -252.400494)
			(xy 370.782848 -252.363657) (xy 370.820969 -252.332532) (xy 370.86359 -252.307925) (xy 370.909606 -252.290473)
			(xy 370.957825 -252.280629) (xy 371.007 -252.278648) (xy 371.055855 -252.28458) (xy 371.103126 -252.298272)
			(xy 371.147588 -252.31937) (xy 371.188091 -252.347326) (xy 371.223584 -252.381418) (xy 371.253149 -252.420762)
			(xy 371.27602 -252.464339) (xy 371.291604 -252.51102) (xy 371.299499 -252.559597) (xy 371.299994 -252.584204)
			(xy 372.56899 -252.584204) (xy 372.57295 -252.53515) (xy 372.584727 -252.487366) (xy 372.604018 -252.44209)
			(xy 372.630321 -252.400494) (xy 372.662956 -252.363657) (xy 372.701077 -252.332532) (xy 372.743698 -252.307925)
			(xy 372.789714 -252.290473) (xy 372.837933 -252.280629) (xy 372.887108 -252.278648) (xy 372.935963 -252.28458)
			(xy 372.983234 -252.298272) (xy 373.027696 -252.31937) (xy 373.068199 -252.347326) (xy 373.103692 -252.381418)
			(xy 373.133257 -252.420762) (xy 373.156128 -252.464339) (xy 373.171712 -252.51102) (xy 373.179607 -252.559597)
			(xy 373.180102 -252.584204) (xy 374.449098 -252.584204) (xy 374.453058 -252.53515) (xy 374.464835 -252.487366)
			(xy 374.484126 -252.44209) (xy 374.510429 -252.400494) (xy 374.543064 -252.363657) (xy 374.581185 -252.332532)
			(xy 374.623806 -252.307925) (xy 374.669822 -252.290473) (xy 374.718041 -252.280629) (xy 374.767216 -252.278648)
			(xy 374.816071 -252.28458) (xy 374.863342 -252.298272) (xy 374.907804 -252.31937) (xy 374.948307 -252.347326)
			(xy 374.9838 -252.381418) (xy 375.013365 -252.420762) (xy 375.036236 -252.464339) (xy 375.05182 -252.51102)
			(xy 375.059715 -252.559597) (xy 375.06021 -252.584204) (xy 375.388898 -252.584204) (xy 375.392858 -252.53515)
			(xy 375.404635 -252.487366) (xy 375.423926 -252.44209) (xy 375.450229 -252.400494) (xy 375.482864 -252.363657)
			(xy 375.520985 -252.332532) (xy 375.563606 -252.307925) (xy 375.609622 -252.290473) (xy 375.657841 -252.280629)
			(xy 375.707016 -252.278648) (xy 375.755871 -252.28458) (xy 375.803142 -252.298272) (xy 375.847604 -252.31937)
			(xy 375.888107 -252.347326) (xy 375.9236 -252.381418) (xy 375.953165 -252.420762) (xy 375.976036 -252.464339)
			(xy 375.99162 -252.51102) (xy 375.999515 -252.559597) (xy 376.00001 -252.584204) (xy 376.328952 -252.584204)
			(xy 376.332912 -252.53515) (xy 376.344689 -252.487366) (xy 376.36398 -252.44209) (xy 376.390283 -252.400494)
			(xy 376.422918 -252.363657) (xy 376.461039 -252.332532) (xy 376.50366 -252.307925) (xy 376.549676 -252.290473)
			(xy 376.597895 -252.280629) (xy 376.64707 -252.278648) (xy 376.695925 -252.28458) (xy 376.743196 -252.298272)
			(xy 376.787658 -252.31937) (xy 376.828161 -252.347326) (xy 376.863654 -252.381418) (xy 376.893219 -252.420762)
			(xy 376.91609 -252.464339) (xy 376.931674 -252.51102) (xy 376.939569 -252.559597) (xy 376.940064 -252.584204)
			(xy 377.258575 -252.584204) (xy 377.26267 -252.533476) (xy 377.274849 -252.484062) (xy 377.294797 -252.437242)
			(xy 377.321998 -252.394228) (xy 377.355746 -252.356134) (xy 377.395168 -252.323947) (xy 377.439242 -252.298501)
			(xy 377.486828 -252.280454) (xy 377.536692 -252.270274) (xy 377.587544 -252.268225) (xy 377.638065 -252.274359)
			(xy 377.686949 -252.288519) (xy 377.732928 -252.310336) (xy 377.774812 -252.339246) (xy 377.811516 -252.374501)
			(xy 377.842089 -252.415187) (xy 377.86574 -252.46025) (xy 377.881856 -252.508524) (xy 377.89002 -252.558758)
			(xy 377.890532 -252.584204) (xy 378.20906 -252.584204) (xy 378.21302 -252.53515) (xy 378.224797 -252.487366)
			(xy 378.244088 -252.44209) (xy 378.270391 -252.400494) (xy 378.303026 -252.363657) (xy 378.341147 -252.332532)
			(xy 378.383768 -252.307925) (xy 378.429784 -252.290473) (xy 378.478003 -252.280629) (xy 378.527178 -252.278648)
			(xy 378.576033 -252.28458) (xy 378.623304 -252.298272) (xy 378.667766 -252.31937) (xy 378.708269 -252.347326)
			(xy 378.743762 -252.381418) (xy 378.773327 -252.420762) (xy 378.796198 -252.464339) (xy 378.811782 -252.51102)
			(xy 378.819677 -252.559597) (xy 378.820172 -252.584204) (xy 379.149114 -252.584204) (xy 379.153074 -252.53515)
			(xy 379.164851 -252.487366) (xy 379.184142 -252.44209) (xy 379.210445 -252.400494) (xy 379.24308 -252.363657)
			(xy 379.281201 -252.332532) (xy 379.323822 -252.307925) (xy 379.369838 -252.290473) (xy 379.418057 -252.280629)
			(xy 379.467232 -252.278648) (xy 379.516087 -252.28458) (xy 379.563358 -252.298272) (xy 379.60782 -252.31937)
			(xy 379.648323 -252.347326) (xy 379.683816 -252.381418) (xy 379.713381 -252.420762) (xy 379.736252 -252.464339)
			(xy 379.751836 -252.51102) (xy 379.759731 -252.559597) (xy 379.760226 -252.584204) (xy 380.078483 -252.584204)
			(xy 380.082578 -252.533476) (xy 380.094757 -252.484062) (xy 380.114705 -252.437242) (xy 380.141906 -252.394228)
			(xy 380.175654 -252.356134) (xy 380.215076 -252.323947) (xy 380.25915 -252.298501) (xy 380.306736 -252.280454)
			(xy 380.3566 -252.270274) (xy 380.407452 -252.268225) (xy 380.457973 -252.274359) (xy 380.506857 -252.288519)
			(xy 380.552836 -252.310336) (xy 380.59472 -252.339246) (xy 380.631424 -252.374501) (xy 380.661997 -252.415187)
			(xy 380.685648 -252.46025) (xy 380.701764 -252.508524) (xy 380.709928 -252.558758) (xy 380.71044 -252.584204)
			(xy 380.709928 -252.60965) (xy 380.701764 -252.659884) (xy 380.685648 -252.708158) (xy 380.661997 -252.753221)
			(xy 380.631424 -252.793907) (xy 380.59472 -252.829162) (xy 380.552836 -252.858072) (xy 380.506857 -252.879889)
			(xy 380.457973 -252.894049) (xy 380.407452 -252.900183) (xy 380.3566 -252.898134) (xy 380.306736 -252.887954)
			(xy 380.25915 -252.869907) (xy 380.215076 -252.844461) (xy 380.175654 -252.812274) (xy 380.141906 -252.77418)
			(xy 380.114705 -252.731166) (xy 380.094757 -252.684346) (xy 380.082578 -252.634932) (xy 380.078483 -252.584204)
			(xy 379.760226 -252.584204) (xy 379.759731 -252.608811) (xy 379.751836 -252.657388) (xy 379.736252 -252.704069)
			(xy 379.713381 -252.747646) (xy 379.683816 -252.78699) (xy 379.648323 -252.821082) (xy 379.60782 -252.849038)
			(xy 379.563358 -252.870136) (xy 379.516087 -252.883828) (xy 379.467232 -252.88976) (xy 379.418057 -252.887779)
			(xy 379.369838 -252.877935) (xy 379.323822 -252.860483) (xy 379.281201 -252.835876) (xy 379.24308 -252.804751)
			(xy 379.210445 -252.767914) (xy 379.184142 -252.726318) (xy 379.164851 -252.681042) (xy 379.153074 -252.633258)
			(xy 379.149114 -252.584204) (xy 378.820172 -252.584204) (xy 378.819677 -252.608811) (xy 378.811782 -252.657388)
			(xy 378.796198 -252.704069) (xy 378.773327 -252.747646) (xy 378.743762 -252.78699) (xy 378.708269 -252.821082)
			(xy 378.667766 -252.849038) (xy 378.623304 -252.870136) (xy 378.576033 -252.883828) (xy 378.527178 -252.88976)
			(xy 378.478003 -252.887779) (xy 378.429784 -252.877935) (xy 378.383768 -252.860483) (xy 378.341147 -252.835876)
			(xy 378.303026 -252.804751) (xy 378.270391 -252.767914) (xy 378.244088 -252.726318) (xy 378.224797 -252.681042)
			(xy 378.21302 -252.633258) (xy 378.20906 -252.584204) (xy 377.890532 -252.584204) (xy 377.89002 -252.60965)
			(xy 377.881856 -252.659884) (xy 377.86574 -252.708158) (xy 377.842089 -252.753221) (xy 377.811516 -252.793907)
			(xy 377.774812 -252.829162) (xy 377.732928 -252.858072) (xy 377.686949 -252.879889) (xy 377.638065 -252.894049)
			(xy 377.587544 -252.900183) (xy 377.536692 -252.898134) (xy 377.486828 -252.887954) (xy 377.439242 -252.869907)
			(xy 377.395168 -252.844461) (xy 377.355746 -252.812274) (xy 377.321998 -252.77418) (xy 377.294797 -252.731166)
			(xy 377.274849 -252.684346) (xy 377.26267 -252.634932) (xy 377.258575 -252.584204) (xy 376.940064 -252.584204)
			(xy 376.939569 -252.608811) (xy 376.931674 -252.657388) (xy 376.91609 -252.704069) (xy 376.893219 -252.747646)
			(xy 376.863654 -252.78699) (xy 376.828161 -252.821082) (xy 376.787658 -252.849038) (xy 376.743196 -252.870136)
			(xy 376.695925 -252.883828) (xy 376.64707 -252.88976) (xy 376.597895 -252.887779) (xy 376.549676 -252.877935)
			(xy 376.50366 -252.860483) (xy 376.461039 -252.835876) (xy 376.422918 -252.804751) (xy 376.390283 -252.767914)
			(xy 376.36398 -252.726318) (xy 376.344689 -252.681042) (xy 376.332912 -252.633258) (xy 376.328952 -252.584204)
			(xy 376.00001 -252.584204) (xy 375.999515 -252.608811) (xy 375.99162 -252.657388) (xy 375.976036 -252.704069)
			(xy 375.953165 -252.747646) (xy 375.9236 -252.78699) (xy 375.888107 -252.821082) (xy 375.847604 -252.849038)
			(xy 375.803142 -252.870136) (xy 375.755871 -252.883828) (xy 375.707016 -252.88976) (xy 375.657841 -252.887779)
			(xy 375.609622 -252.877935) (xy 375.563606 -252.860483) (xy 375.520985 -252.835876) (xy 375.482864 -252.804751)
			(xy 375.450229 -252.767914) (xy 375.423926 -252.726318) (xy 375.404635 -252.681042) (xy 375.392858 -252.633258)
			(xy 375.388898 -252.584204) (xy 375.06021 -252.584204) (xy 375.059715 -252.608811) (xy 375.05182 -252.657388)
			(xy 375.036236 -252.704069) (xy 375.013365 -252.747646) (xy 374.9838 -252.78699) (xy 374.948307 -252.821082)
			(xy 374.907804 -252.849038) (xy 374.863342 -252.870136) (xy 374.816071 -252.883828) (xy 374.767216 -252.88976)
			(xy 374.718041 -252.887779) (xy 374.669822 -252.877935) (xy 374.623806 -252.860483) (xy 374.581185 -252.835876)
			(xy 374.543064 -252.804751) (xy 374.510429 -252.767914) (xy 374.484126 -252.726318) (xy 374.464835 -252.681042)
			(xy 374.453058 -252.633258) (xy 374.449098 -252.584204) (xy 373.180102 -252.584204) (xy 373.179607 -252.608811)
			(xy 373.171712 -252.657388) (xy 373.156128 -252.704069) (xy 373.133257 -252.747646) (xy 373.103692 -252.78699)
			(xy 373.068199 -252.821082) (xy 373.027696 -252.849038) (xy 372.983234 -252.870136) (xy 372.935963 -252.883828)
			(xy 372.887108 -252.88976) (xy 372.837933 -252.887779) (xy 372.789714 -252.877935) (xy 372.743698 -252.860483)
			(xy 372.701077 -252.835876) (xy 372.662956 -252.804751) (xy 372.630321 -252.767914) (xy 372.604018 -252.726318)
			(xy 372.584727 -252.681042) (xy 372.57295 -252.633258) (xy 372.56899 -252.584204) (xy 371.299994 -252.584204)
			(xy 371.299499 -252.608811) (xy 371.291604 -252.657388) (xy 371.27602 -252.704069) (xy 371.253149 -252.747646)
			(xy 371.223584 -252.78699) (xy 371.188091 -252.821082) (xy 371.147588 -252.849038) (xy 371.103126 -252.870136)
			(xy 371.055855 -252.883828) (xy 371.007 -252.88976) (xy 370.957825 -252.887779) (xy 370.909606 -252.877935)
			(xy 370.86359 -252.860483) (xy 370.820969 -252.835876) (xy 370.782848 -252.804751) (xy 370.750213 -252.767914)
			(xy 370.72391 -252.726318) (xy 370.704619 -252.681042) (xy 370.692842 -252.633258) (xy 370.688882 -252.584204)
			(xy 369.42014 -252.584204) (xy 369.419645 -252.608811) (xy 369.41175 -252.657388) (xy 369.396166 -252.704069)
			(xy 369.373295 -252.747646) (xy 369.34373 -252.78699) (xy 369.308237 -252.821082) (xy 369.267734 -252.849038)
			(xy 369.223272 -252.870136) (xy 369.176001 -252.883828) (xy 369.127146 -252.88976) (xy 369.077971 -252.887779)
			(xy 369.029752 -252.877935) (xy 368.983736 -252.860483) (xy 368.941115 -252.835876) (xy 368.902994 -252.804751)
			(xy 368.870359 -252.767914) (xy 368.844056 -252.726318) (xy 368.824765 -252.681042) (xy 368.812988 -252.633258)
			(xy 368.809028 -252.584204) (xy 360.49716 -252.584204) (xy 360.493272 -252.592056) (xy 360.46298 -252.635122)
			(xy 360.426468 -252.67306) (xy 360.384594 -252.704979) (xy 360.338338 -252.730132) (xy 360.288785 -252.74793)
			(xy 360.237095 -252.757954) (xy 360.184481 -252.759971) (xy 360.132176 -252.753933) (xy 360.081405 -252.739981)
			(xy 360.03336 -252.718442) (xy 359.989165 -252.689822) (xy 359.949857 -252.654791) (xy 359.916357 -252.61417)
			(xy 359.889451 -252.568911) (xy 359.869768 -252.520076) (xy 359.857771 -252.468808) (xy 359.853741 -252.41631)
			(xy 349.636021 -252.41631) (xy 349.658517 -252.455501) (xy 349.676583 -252.5054) (xy 349.685754 -252.55767)
			(xy 349.686372 -252.584204) (xy 349.685925 -252.608196) (xy 349.678418 -252.655589) (xy 349.663589 -252.701224)
			(xy 349.641803 -252.743977) (xy 349.613596 -252.782795) (xy 349.579664 -252.816722) (xy 349.540842 -252.844923)
			(xy 349.498087 -252.866704) (xy 349.45245 -252.881527) (xy 349.405056 -252.889029) (xy 349.381064 -252.889512)
			(xy 349.35453 -252.888938) (xy 349.302261 -252.879757) (xy 349.252367 -252.861678) (xy 349.20635 -252.835244)
			(xy 349.165596 -252.801253) (xy 349.131332 -252.760727) (xy 349.117412 -252.738128) (xy 349.111316 -252.72746)
			(xy 349.091758 -252.71476) (xy 349.000064 -252.703076) (xy 348.988403 -252.702125) (xy 348.966284 -252.709664)
			(xy 348.957646 -252.717554) (xy 348.624906 -253.050294) (xy 348.61754 -253.057406) (xy 348.60992 -253.076202)
			(xy 348.60992 -253.39421) (xy 349.545414 -253.39421) (xy 349.549374 -253.345156) (xy 349.561151 -253.297372)
			(xy 349.580442 -253.252096) (xy 349.606745 -253.2105) (xy 349.63938 -253.173663) (xy 349.677501 -253.142538)
			(xy 349.720122 -253.117931) (xy 349.766138 -253.100479) (xy 349.814357 -253.090635) (xy 349.863532 -253.088654)
			(xy 349.912387 -253.094586) (xy 349.959658 -253.108278) (xy 350.00412 -253.129376) (xy 350.044623 -253.157332)
			(xy 350.080116 -253.191424) (xy 350.109681 -253.230768) (xy 350.132552 -253.274345) (xy 350.148136 -253.321026)
			(xy 350.156031 -253.369603) (xy 350.156485 -253.392178) (xy 351.42222 -253.392178) (xy 351.42618 -253.343124)
			(xy 351.437957 -253.29534) (xy 351.457248 -253.250064) (xy 351.483551 -253.208468) (xy 351.516186 -253.171631)
			(xy 351.554307 -253.140506) (xy 351.596928 -253.115899) (xy 351.642944 -253.098447) (xy 351.691163 -253.088603)
			(xy 351.740338 -253.086622) (xy 351.789193 -253.092554) (xy 351.836464 -253.106246) (xy 351.880926 -253.127344)
			(xy 351.921429 -253.1553) (xy 351.956922 -253.189392) (xy 351.986487 -253.228736) (xy 352.009358 -253.272313)
			(xy 352.024942 -253.318994) (xy 352.032837 -253.367571) (xy 352.033332 -253.392178) (xy 353.302074 -253.392178)
			(xy 353.306034 -253.343124) (xy 353.317811 -253.29534) (xy 353.337102 -253.250064) (xy 353.363405 -253.208468)
			(xy 353.39604 -253.171631) (xy 353.434161 -253.140506) (xy 353.476782 -253.115899) (xy 353.522798 -253.098447)
			(xy 353.571017 -253.088603) (xy 353.620192 -253.086622) (xy 353.669047 -253.092554) (xy 353.716318 -253.106246)
			(xy 353.76078 -253.127344) (xy 353.801283 -253.1553) (xy 353.836776 -253.189392) (xy 353.866341 -253.228736)
			(xy 353.889212 -253.272313) (xy 353.904796 -253.318994) (xy 353.912691 -253.367571) (xy 353.913186 -253.392178)
			(xy 355.182182 -253.392178) (xy 355.186142 -253.343124) (xy 355.197919 -253.29534) (xy 355.21721 -253.250064)
			(xy 355.243513 -253.208468) (xy 355.276148 -253.171631) (xy 355.314269 -253.140506) (xy 355.35689 -253.115899)
			(xy 355.402906 -253.098447) (xy 355.451125 -253.088603) (xy 355.5003 -253.086622) (xy 355.549155 -253.092554)
			(xy 355.596426 -253.106246) (xy 355.640888 -253.127344) (xy 355.681391 -253.1553) (xy 355.716884 -253.189392)
			(xy 355.746449 -253.228736) (xy 355.76932 -253.272313) (xy 355.784904 -253.318994) (xy 355.792799 -253.367571)
			(xy 355.793294 -253.392178) (xy 357.06229 -253.392178) (xy 357.06625 -253.343124) (xy 357.078027 -253.29534)
			(xy 357.097318 -253.250064) (xy 357.123621 -253.208468) (xy 357.156256 -253.171631) (xy 357.194377 -253.140506)
			(xy 357.236998 -253.115899) (xy 357.283014 -253.098447) (xy 357.331233 -253.088603) (xy 357.380408 -253.086622)
			(xy 357.429263 -253.092554) (xy 357.476534 -253.106246) (xy 357.520996 -253.127344) (xy 357.561499 -253.1553)
			(xy 357.596992 -253.189392) (xy 357.626557 -253.228736) (xy 357.649428 -253.272313) (xy 357.665012 -253.318994)
			(xy 357.672907 -253.367571) (xy 357.673402 -253.392178) (xy 357.672907 -253.416785) (xy 357.670384 -253.43231)
			(xy 359.853741 -253.43231) (xy 359.857771 -253.379812) (xy 359.869768 -253.328544) (xy 359.889451 -253.279709)
			(xy 359.916357 -253.23445) (xy 359.949857 -253.193829) (xy 359.989165 -253.158798) (xy 360.03336 -253.130178)
			(xy 360.081405 -253.108639) (xy 360.132176 -253.094687) (xy 360.184481 -253.088649) (xy 360.237095 -253.090666)
			(xy 360.288785 -253.10069) (xy 360.338338 -253.118488) (xy 360.384594 -253.143641) (xy 360.426468 -253.17556)
			(xy 360.46298 -253.213498) (xy 360.493272 -253.256564) (xy 360.516635 -253.303749) (xy 360.532521 -253.353948)
			(xy 360.538426 -253.392178) (xy 360.822252 -253.392178) (xy 360.826212 -253.343124) (xy 360.837989 -253.29534)
			(xy 360.85728 -253.250064) (xy 360.883583 -253.208468) (xy 360.916218 -253.171631) (xy 360.954339 -253.140506)
			(xy 360.99696 -253.115899) (xy 361.042976 -253.098447) (xy 361.091195 -253.088603) (xy 361.14037 -253.086622)
			(xy 361.189225 -253.092554) (xy 361.236496 -253.106246) (xy 361.280958 -253.127344) (xy 361.321461 -253.1553)
			(xy 361.356954 -253.189392) (xy 361.386519 -253.228736) (xy 361.40939 -253.272313) (xy 361.424974 -253.318994)
			(xy 361.432869 -253.367571) (xy 361.433364 -253.392178) (xy 362.702106 -253.392178) (xy 362.706066 -253.343124)
			(xy 362.717843 -253.29534) (xy 362.737134 -253.250064) (xy 362.763437 -253.208468) (xy 362.796072 -253.171631)
			(xy 362.834193 -253.140506) (xy 362.876814 -253.115899) (xy 362.92283 -253.098447) (xy 362.971049 -253.088603)
			(xy 363.020224 -253.086622) (xy 363.069079 -253.092554) (xy 363.11635 -253.106246) (xy 363.160812 -253.127344)
			(xy 363.201315 -253.1553) (xy 363.236808 -253.189392) (xy 363.266373 -253.228736) (xy 363.289244 -253.272313)
			(xy 363.304828 -253.318994) (xy 363.312723 -253.367571) (xy 363.313218 -253.392178) (xy 364.582214 -253.392178)
			(xy 364.586174 -253.343124) (xy 364.597951 -253.29534) (xy 364.617242 -253.250064) (xy 364.643545 -253.208468)
			(xy 364.67618 -253.171631) (xy 364.714301 -253.140506) (xy 364.756922 -253.115899) (xy 364.802938 -253.098447)
			(xy 364.851157 -253.088603) (xy 364.900332 -253.086622) (xy 364.949187 -253.092554) (xy 364.996458 -253.106246)
			(xy 365.04092 -253.127344) (xy 365.081423 -253.1553) (xy 365.116916 -253.189392) (xy 365.146481 -253.228736)
			(xy 365.169352 -253.272313) (xy 365.184936 -253.318994) (xy 365.192831 -253.367571) (xy 365.193326 -253.392178)
			(xy 366.462068 -253.392178) (xy 366.466028 -253.343124) (xy 366.477805 -253.29534) (xy 366.497096 -253.250064)
			(xy 366.523399 -253.208468) (xy 366.556034 -253.171631) (xy 366.594155 -253.140506) (xy 366.636776 -253.115899)
			(xy 366.682792 -253.098447) (xy 366.731011 -253.088603) (xy 366.780186 -253.086622) (xy 366.829041 -253.092554)
			(xy 366.876312 -253.106246) (xy 366.920774 -253.127344) (xy 366.961277 -253.1553) (xy 366.99677 -253.189392)
			(xy 367.026335 -253.228736) (xy 367.049206 -253.272313) (xy 367.06479 -253.318994) (xy 367.072685 -253.367571)
			(xy 367.07318 -253.392178) (xy 367.073139 -253.39421) (xy 370.218982 -253.39421) (xy 370.222942 -253.345156)
			(xy 370.234719 -253.297372) (xy 370.25401 -253.252096) (xy 370.280313 -253.2105) (xy 370.312948 -253.173663)
			(xy 370.351069 -253.142538) (xy 370.39369 -253.117931) (xy 370.439706 -253.100479) (xy 370.487925 -253.090635)
			(xy 370.5371 -253.088654) (xy 370.585955 -253.094586) (xy 370.633226 -253.108278) (xy 370.677688 -253.129376)
			(xy 370.718191 -253.157332) (xy 370.753684 -253.191424) (xy 370.783249 -253.230768) (xy 370.80612 -253.274345)
			(xy 370.821704 -253.321026) (xy 370.829599 -253.369603) (xy 370.830094 -253.39421) (xy 372.09909 -253.39421)
			(xy 372.10305 -253.345156) (xy 372.114827 -253.297372) (xy 372.134118 -253.252096) (xy 372.160421 -253.2105)
			(xy 372.193056 -253.173663) (xy 372.231177 -253.142538) (xy 372.273798 -253.117931) (xy 372.319814 -253.100479)
			(xy 372.368033 -253.090635) (xy 372.417208 -253.088654) (xy 372.466063 -253.094586) (xy 372.513334 -253.108278)
			(xy 372.557796 -253.129376) (xy 372.598299 -253.157332) (xy 372.633792 -253.191424) (xy 372.663357 -253.230768)
			(xy 372.686228 -253.274345) (xy 372.701812 -253.321026) (xy 372.709707 -253.369603) (xy 372.710202 -253.39421)
			(xy 373.978944 -253.39421) (xy 373.982904 -253.345156) (xy 373.994681 -253.297372) (xy 374.013972 -253.252096)
			(xy 374.040275 -253.2105) (xy 374.07291 -253.173663) (xy 374.111031 -253.142538) (xy 374.153652 -253.117931)
			(xy 374.199668 -253.100479) (xy 374.247887 -253.090635) (xy 374.297062 -253.088654) (xy 374.345917 -253.094586)
			(xy 374.393188 -253.108278) (xy 374.43765 -253.129376) (xy 374.478153 -253.157332) (xy 374.513646 -253.191424)
			(xy 374.543211 -253.230768) (xy 374.566082 -253.274345) (xy 374.581666 -253.321026) (xy 374.589561 -253.369603)
			(xy 374.590056 -253.39421) (xy 375.848621 -253.39421) (xy 375.852716 -253.343482) (xy 375.864895 -253.294068)
			(xy 375.884843 -253.247248) (xy 375.912044 -253.204234) (xy 375.945792 -253.16614) (xy 375.985214 -253.133953)
			(xy 376.029288 -253.108507) (xy 376.076874 -253.09046) (xy 376.126738 -253.08028) (xy 376.17759 -253.078231)
			(xy 376.228111 -253.084365) (xy 376.276995 -253.098525) (xy 376.322974 -253.120342) (xy 376.364858 -253.149252)
			(xy 376.401562 -253.184507) (xy 376.432135 -253.225193) (xy 376.455786 -253.270256) (xy 376.471902 -253.31853)
			(xy 376.480066 -253.368764) (xy 376.480578 -253.39421) (xy 376.788675 -253.39421) (xy 376.79277 -253.343482)
			(xy 376.804949 -253.294068) (xy 376.824897 -253.247248) (xy 376.852098 -253.204234) (xy 376.885846 -253.16614)
			(xy 376.925268 -253.133953) (xy 376.969342 -253.108507) (xy 377.016928 -253.09046) (xy 377.066792 -253.08028)
			(xy 377.117644 -253.078231) (xy 377.168165 -253.084365) (xy 377.217049 -253.098525) (xy 377.263028 -253.120342)
			(xy 377.304912 -253.149252) (xy 377.341616 -253.184507) (xy 377.372189 -253.225193) (xy 377.39584 -253.270256)
			(xy 377.411956 -253.31853) (xy 377.42012 -253.368764) (xy 377.420632 -253.39421) (xy 377.738906 -253.39421)
			(xy 377.742866 -253.345156) (xy 377.754643 -253.297372) (xy 377.773934 -253.252096) (xy 377.800237 -253.2105)
			(xy 377.832872 -253.173663) (xy 377.870993 -253.142538) (xy 377.913614 -253.117931) (xy 377.95963 -253.100479)
			(xy 378.007849 -253.090635) (xy 378.057024 -253.088654) (xy 378.105879 -253.094586) (xy 378.15315 -253.108278)
			(xy 378.197612 -253.129376) (xy 378.238115 -253.157332) (xy 378.273608 -253.191424) (xy 378.303173 -253.230768)
			(xy 378.326044 -253.274345) (xy 378.341628 -253.321026) (xy 378.349523 -253.369603) (xy 378.350018 -253.39421)
			(xy 378.668529 -253.39421) (xy 378.672624 -253.343482) (xy 378.684803 -253.294068) (xy 378.704751 -253.247248)
			(xy 378.731952 -253.204234) (xy 378.7657 -253.16614) (xy 378.805122 -253.133953) (xy 378.849196 -253.108507)
			(xy 378.896782 -253.09046) (xy 378.946646 -253.08028) (xy 378.997498 -253.078231) (xy 379.048019 -253.084365)
			(xy 379.096903 -253.098525) (xy 379.142882 -253.120342) (xy 379.184766 -253.149252) (xy 379.22147 -253.184507)
			(xy 379.252043 -253.225193) (xy 379.275694 -253.270256) (xy 379.29181 -253.31853) (xy 379.299974 -253.368764)
			(xy 379.300486 -253.39421) (xy 379.619014 -253.39421) (xy 379.622974 -253.345156) (xy 379.634751 -253.297372)
			(xy 379.654042 -253.252096) (xy 379.680345 -253.2105) (xy 379.71298 -253.173663) (xy 379.751101 -253.142538)
			(xy 379.793722 -253.117931) (xy 379.839738 -253.100479) (xy 379.887957 -253.090635) (xy 379.937132 -253.088654)
			(xy 379.985987 -253.094586) (xy 380.033258 -253.108278) (xy 380.07772 -253.129376) (xy 380.118223 -253.157332)
			(xy 380.153716 -253.191424) (xy 380.183281 -253.230768) (xy 380.206152 -253.274345) (xy 380.221736 -253.321026)
			(xy 380.229631 -253.369603) (xy 380.230126 -253.39421) (xy 380.548637 -253.39421) (xy 380.552732 -253.343482)
			(xy 380.564911 -253.294068) (xy 380.584859 -253.247248) (xy 380.61206 -253.204234) (xy 380.645808 -253.16614)
			(xy 380.68523 -253.133953) (xy 380.729304 -253.108507) (xy 380.77689 -253.09046) (xy 380.826754 -253.08028)
			(xy 380.877606 -253.078231) (xy 380.928127 -253.084365) (xy 380.977011 -253.098525) (xy 381.02299 -253.120342)
			(xy 381.064874 -253.149252) (xy 381.101578 -253.184507) (xy 381.132151 -253.225193) (xy 381.155802 -253.270256)
			(xy 381.171918 -253.31853) (xy 381.180082 -253.368764) (xy 381.180594 -253.39421) (xy 381.180082 -253.419656)
			(xy 381.171918 -253.46989) (xy 381.155802 -253.518164) (xy 381.132151 -253.563227) (xy 381.101578 -253.603913)
			(xy 381.064874 -253.639168) (xy 381.02299 -253.668078) (xy 380.977011 -253.689895) (xy 380.928127 -253.704055)
			(xy 380.877606 -253.710189) (xy 380.826754 -253.70814) (xy 380.77689 -253.69796) (xy 380.729304 -253.679913)
			(xy 380.68523 -253.654467) (xy 380.645808 -253.62228) (xy 380.61206 -253.584186) (xy 380.584859 -253.541172)
			(xy 380.564911 -253.494352) (xy 380.552732 -253.444938) (xy 380.548637 -253.39421) (xy 380.230126 -253.39421)
			(xy 380.229631 -253.418817) (xy 380.221736 -253.467394) (xy 380.206152 -253.514075) (xy 380.183281 -253.557652)
			(xy 380.153716 -253.596996) (xy 380.118223 -253.631088) (xy 380.07772 -253.659044) (xy 380.033258 -253.680142)
			(xy 379.985987 -253.693834) (xy 379.937132 -253.699766) (xy 379.887957 -253.697785) (xy 379.839738 -253.687941)
			(xy 379.793722 -253.670489) (xy 379.751101 -253.645882) (xy 379.71298 -253.614757) (xy 379.680345 -253.57792)
			(xy 379.654042 -253.536324) (xy 379.634751 -253.491048) (xy 379.622974 -253.443264) (xy 379.619014 -253.39421)
			(xy 379.300486 -253.39421) (xy 379.299974 -253.419656) (xy 379.29181 -253.46989) (xy 379.275694 -253.518164)
			(xy 379.252043 -253.563227) (xy 379.22147 -253.603913) (xy 379.184766 -253.639168) (xy 379.142882 -253.668078)
			(xy 379.096903 -253.689895) (xy 379.048019 -253.704055) (xy 378.997498 -253.710189) (xy 378.946646 -253.70814)
			(xy 378.896782 -253.69796) (xy 378.849196 -253.679913) (xy 378.805122 -253.654467) (xy 378.7657 -253.62228)
			(xy 378.731952 -253.584186) (xy 378.704751 -253.541172) (xy 378.684803 -253.494352) (xy 378.672624 -253.444938)
			(xy 378.668529 -253.39421) (xy 378.350018 -253.39421) (xy 378.349523 -253.418817) (xy 378.341628 -253.467394)
			(xy 378.326044 -253.514075) (xy 378.303173 -253.557652) (xy 378.273608 -253.596996) (xy 378.238115 -253.631088)
			(xy 378.197612 -253.659044) (xy 378.15315 -253.680142) (xy 378.105879 -253.693834) (xy 378.057024 -253.699766)
			(xy 378.007849 -253.697785) (xy 377.95963 -253.687941) (xy 377.913614 -253.670489) (xy 377.870993 -253.645882)
			(xy 377.832872 -253.614757) (xy 377.800237 -253.57792) (xy 377.773934 -253.536324) (xy 377.754643 -253.491048)
			(xy 377.742866 -253.443264) (xy 377.738906 -253.39421) (xy 377.420632 -253.39421) (xy 377.42012 -253.419656)
			(xy 377.411956 -253.46989) (xy 377.39584 -253.518164) (xy 377.372189 -253.563227) (xy 377.341616 -253.603913)
			(xy 377.304912 -253.639168) (xy 377.263028 -253.668078) (xy 377.217049 -253.689895) (xy 377.168165 -253.704055)
			(xy 377.117644 -253.710189) (xy 377.066792 -253.70814) (xy 377.016928 -253.69796) (xy 376.969342 -253.679913)
			(xy 376.925268 -253.654467) (xy 376.885846 -253.62228) (xy 376.852098 -253.584186) (xy 376.824897 -253.541172)
			(xy 376.804949 -253.494352) (xy 376.79277 -253.444938) (xy 376.788675 -253.39421) (xy 376.480578 -253.39421)
			(xy 376.480066 -253.419656) (xy 376.471902 -253.46989) (xy 376.455786 -253.518164) (xy 376.432135 -253.563227)
			(xy 376.401562 -253.603913) (xy 376.364858 -253.639168) (xy 376.322974 -253.668078) (xy 376.276995 -253.689895)
			(xy 376.228111 -253.704055) (xy 376.17759 -253.710189) (xy 376.126738 -253.70814) (xy 376.076874 -253.69796)
			(xy 376.029288 -253.679913) (xy 375.985214 -253.654467) (xy 375.945792 -253.62228) (xy 375.912044 -253.584186)
			(xy 375.884843 -253.541172) (xy 375.864895 -253.494352) (xy 375.852716 -253.444938) (xy 375.848621 -253.39421)
			(xy 374.590056 -253.39421) (xy 374.589561 -253.418817) (xy 374.581666 -253.467394) (xy 374.566082 -253.514075)
			(xy 374.543211 -253.557652) (xy 374.513646 -253.596996) (xy 374.478153 -253.631088) (xy 374.43765 -253.659044)
			(xy 374.393188 -253.680142) (xy 374.345917 -253.693834) (xy 374.297062 -253.699766) (xy 374.247887 -253.697785)
			(xy 374.199668 -253.687941) (xy 374.153652 -253.670489) (xy 374.111031 -253.645882) (xy 374.07291 -253.614757)
			(xy 374.040275 -253.57792) (xy 374.013972 -253.536324) (xy 373.994681 -253.491048) (xy 373.982904 -253.443264)
			(xy 373.978944 -253.39421) (xy 372.710202 -253.39421) (xy 372.709707 -253.418817) (xy 372.701812 -253.467394)
			(xy 372.686228 -253.514075) (xy 372.663357 -253.557652) (xy 372.633792 -253.596996) (xy 372.598299 -253.631088)
			(xy 372.557796 -253.659044) (xy 372.513334 -253.680142) (xy 372.466063 -253.693834) (xy 372.417208 -253.699766)
			(xy 372.368033 -253.697785) (xy 372.319814 -253.687941) (xy 372.273798 -253.670489) (xy 372.231177 -253.645882)
			(xy 372.193056 -253.614757) (xy 372.160421 -253.57792) (xy 372.134118 -253.536324) (xy 372.114827 -253.491048)
			(xy 372.10305 -253.443264) (xy 372.09909 -253.39421) (xy 370.830094 -253.39421) (xy 370.829599 -253.418817)
			(xy 370.821704 -253.467394) (xy 370.80612 -253.514075) (xy 370.783249 -253.557652) (xy 370.753684 -253.596996)
			(xy 370.718191 -253.631088) (xy 370.677688 -253.659044) (xy 370.633226 -253.680142) (xy 370.585955 -253.693834)
			(xy 370.5371 -253.699766) (xy 370.487925 -253.697785) (xy 370.439706 -253.687941) (xy 370.39369 -253.670489)
			(xy 370.351069 -253.645882) (xy 370.312948 -253.614757) (xy 370.280313 -253.57792) (xy 370.25401 -253.536324)
			(xy 370.234719 -253.491048) (xy 370.222942 -253.443264) (xy 370.218982 -253.39421) (xy 367.073139 -253.39421)
			(xy 367.072685 -253.416785) (xy 367.06479 -253.465362) (xy 367.049206 -253.512043) (xy 367.026335 -253.55562)
			(xy 366.99677 -253.594964) (xy 366.961277 -253.629056) (xy 366.920774 -253.657012) (xy 366.876312 -253.67811)
			(xy 366.829041 -253.691802) (xy 366.780186 -253.697734) (xy 366.731011 -253.695753) (xy 366.682792 -253.685909)
			(xy 366.636776 -253.668457) (xy 366.594155 -253.64385) (xy 366.556034 -253.612725) (xy 366.523399 -253.575888)
			(xy 366.497096 -253.534292) (xy 366.477805 -253.489016) (xy 366.466028 -253.441232) (xy 366.462068 -253.392178)
			(xy 365.193326 -253.392178) (xy 365.192831 -253.416785) (xy 365.184936 -253.465362) (xy 365.169352 -253.512043)
			(xy 365.146481 -253.55562) (xy 365.116916 -253.594964) (xy 365.081423 -253.629056) (xy 365.04092 -253.657012)
			(xy 364.996458 -253.67811) (xy 364.949187 -253.691802) (xy 364.900332 -253.697734) (xy 364.851157 -253.695753)
			(xy 364.802938 -253.685909) (xy 364.756922 -253.668457) (xy 364.714301 -253.64385) (xy 364.67618 -253.612725)
			(xy 364.643545 -253.575888) (xy 364.617242 -253.534292) (xy 364.597951 -253.489016) (xy 364.586174 -253.441232)
			(xy 364.582214 -253.392178) (xy 363.313218 -253.392178) (xy 363.312723 -253.416785) (xy 363.304828 -253.465362)
			(xy 363.289244 -253.512043) (xy 363.266373 -253.55562) (xy 363.236808 -253.594964) (xy 363.201315 -253.629056)
			(xy 363.160812 -253.657012) (xy 363.11635 -253.67811) (xy 363.069079 -253.691802) (xy 363.020224 -253.697734)
			(xy 362.971049 -253.695753) (xy 362.92283 -253.685909) (xy 362.876814 -253.668457) (xy 362.834193 -253.64385)
			(xy 362.796072 -253.612725) (xy 362.763437 -253.575888) (xy 362.737134 -253.534292) (xy 362.717843 -253.489016)
			(xy 362.706066 -253.441232) (xy 362.702106 -253.392178) (xy 361.433364 -253.392178) (xy 361.432869 -253.416785)
			(xy 361.424974 -253.465362) (xy 361.40939 -253.512043) (xy 361.386519 -253.55562) (xy 361.356954 -253.594964)
			(xy 361.321461 -253.629056) (xy 361.280958 -253.657012) (xy 361.236496 -253.67811) (xy 361.189225 -253.691802)
			(xy 361.14037 -253.697734) (xy 361.091195 -253.695753) (xy 361.042976 -253.685909) (xy 360.99696 -253.668457)
			(xy 360.954339 -253.64385) (xy 360.916218 -253.612725) (xy 360.883583 -253.575888) (xy 360.85728 -253.534292)
			(xy 360.837989 -253.489016) (xy 360.826212 -253.441232) (xy 360.822252 -253.392178) (xy 360.538426 -253.392178)
			(xy 360.540558 -253.405984) (xy 360.541062 -253.43231) (xy 360.540558 -253.458636) (xy 360.532521 -253.510672)
			(xy 360.516635 -253.560871) (xy 360.493272 -253.608056) (xy 360.46298 -253.651122) (xy 360.426468 -253.68906)
			(xy 360.384594 -253.720979) (xy 360.338338 -253.746132) (xy 360.288785 -253.76393) (xy 360.237095 -253.773954)
			(xy 360.184481 -253.775971) (xy 360.132176 -253.769933) (xy 360.081405 -253.755981) (xy 360.03336 -253.734442)
			(xy 359.989165 -253.705822) (xy 359.949857 -253.670791) (xy 359.916357 -253.63017) (xy 359.889451 -253.584911)
			(xy 359.869768 -253.536076) (xy 359.857771 -253.484808) (xy 359.853741 -253.43231) (xy 357.670384 -253.43231)
			(xy 357.665012 -253.465362) (xy 357.649428 -253.512043) (xy 357.626557 -253.55562) (xy 357.596992 -253.594964)
			(xy 357.561499 -253.629056) (xy 357.520996 -253.657012) (xy 357.476534 -253.67811) (xy 357.429263 -253.691802)
			(xy 357.380408 -253.697734) (xy 357.331233 -253.695753) (xy 357.283014 -253.685909) (xy 357.236998 -253.668457)
			(xy 357.194377 -253.64385) (xy 357.156256 -253.612725) (xy 357.123621 -253.575888) (xy 357.097318 -253.534292)
			(xy 357.078027 -253.489016) (xy 357.06625 -253.441232) (xy 357.06229 -253.392178) (xy 355.793294 -253.392178)
			(xy 355.792799 -253.416785) (xy 355.784904 -253.465362) (xy 355.76932 -253.512043) (xy 355.746449 -253.55562)
			(xy 355.716884 -253.594964) (xy 355.681391 -253.629056) (xy 355.640888 -253.657012) (xy 355.596426 -253.67811)
			(xy 355.549155 -253.691802) (xy 355.5003 -253.697734) (xy 355.451125 -253.695753) (xy 355.402906 -253.685909)
			(xy 355.35689 -253.668457) (xy 355.314269 -253.64385) (xy 355.276148 -253.612725) (xy 355.243513 -253.575888)
			(xy 355.21721 -253.534292) (xy 355.197919 -253.489016) (xy 355.186142 -253.441232) (xy 355.182182 -253.392178)
			(xy 353.913186 -253.392178) (xy 353.912691 -253.416785) (xy 353.904796 -253.465362) (xy 353.889212 -253.512043)
			(xy 353.866341 -253.55562) (xy 353.836776 -253.594964) (xy 353.801283 -253.629056) (xy 353.76078 -253.657012)
			(xy 353.716318 -253.67811) (xy 353.669047 -253.691802) (xy 353.620192 -253.697734) (xy 353.571017 -253.695753)
			(xy 353.522798 -253.685909) (xy 353.476782 -253.668457) (xy 353.434161 -253.64385) (xy 353.39604 -253.612725)
			(xy 353.363405 -253.575888) (xy 353.337102 -253.534292) (xy 353.317811 -253.489016) (xy 353.306034 -253.441232)
			(xy 353.302074 -253.392178) (xy 352.033332 -253.392178) (xy 352.032837 -253.416785) (xy 352.024942 -253.465362)
			(xy 352.009358 -253.512043) (xy 351.986487 -253.55562) (xy 351.956922 -253.594964) (xy 351.921429 -253.629056)
			(xy 351.880926 -253.657012) (xy 351.836464 -253.67811) (xy 351.789193 -253.691802) (xy 351.740338 -253.697734)
			(xy 351.691163 -253.695753) (xy 351.642944 -253.685909) (xy 351.596928 -253.668457) (xy 351.554307 -253.64385)
			(xy 351.516186 -253.612725) (xy 351.483551 -253.575888) (xy 351.457248 -253.534292) (xy 351.437957 -253.489016)
			(xy 351.42618 -253.441232) (xy 351.42222 -253.392178) (xy 350.156485 -253.392178) (xy 350.156526 -253.39421)
			(xy 350.156031 -253.418817) (xy 350.148136 -253.467394) (xy 350.132552 -253.514075) (xy 350.109681 -253.557652)
			(xy 350.080116 -253.596996) (xy 350.044623 -253.631088) (xy 350.00412 -253.659044) (xy 349.959658 -253.680142)
			(xy 349.912387 -253.693834) (xy 349.863532 -253.699766) (xy 349.814357 -253.697785) (xy 349.766138 -253.687941)
			(xy 349.720122 -253.670489) (xy 349.677501 -253.645882) (xy 349.63938 -253.614757) (xy 349.606745 -253.57792)
			(xy 349.580442 -253.536324) (xy 349.561151 -253.491048) (xy 349.549374 -253.443264) (xy 349.545414 -253.39421)
			(xy 348.60992 -253.39421) (xy 348.60992 -253.91237) (xy 348.610043 -253.91816) (xy 348.612603 -253.929451)
			(xy 348.615 -253.934722) (xy 348.629224 -253.963424) (xy 348.637606 -253.970536) (xy 348.655818 -253.986479)
			(xy 348.687458 -254.023105) (xy 348.712926 -254.064262) (xy 348.731587 -254.10892) (xy 348.742973 -254.155962)
			(xy 348.746799 -254.20421) (xy 348.746799 -254.204216) (xy 349.07526 -254.204216) (xy 349.07922 -254.155162)
			(xy 349.090997 -254.107378) (xy 349.110288 -254.062102) (xy 349.136591 -254.020506) (xy 349.169226 -253.983669)
			(xy 349.207347 -253.952544) (xy 349.249968 -253.927937) (xy 349.295984 -253.910485) (xy 349.344203 -253.900641)
			(xy 349.393378 -253.89866) (xy 349.442233 -253.904592) (xy 349.489504 -253.918284) (xy 349.533966 -253.939382)
			(xy 349.574469 -253.967338) (xy 349.609962 -254.00143) (xy 349.639527 -254.040774) (xy 349.662398 -254.084351)
			(xy 349.677982 -254.131032) (xy 349.685877 -254.179609) (xy 349.686372 -254.204216) (xy 349.685877 -254.228823)
			(xy 349.677982 -254.2774) (xy 349.662398 -254.324081) (xy 349.639527 -254.367658) (xy 349.609962 -254.407002)
			(xy 349.574469 -254.441094) (xy 349.564014 -254.44831) (xy 359.853741 -254.44831) (xy 359.857771 -254.395812)
			(xy 359.869768 -254.344544) (xy 359.889451 -254.295709) (xy 359.916357 -254.25045) (xy 359.949857 -254.209829)
			(xy 359.989165 -254.174798) (xy 360.03336 -254.146178) (xy 360.081405 -254.124639) (xy 360.132176 -254.110687)
			(xy 360.184481 -254.104649) (xy 360.237095 -254.106666) (xy 360.288785 -254.11669) (xy 360.338338 -254.134488)
			(xy 360.384594 -254.159641) (xy 360.426468 -254.19156) (xy 360.438648 -254.204216) (xy 368.809028 -254.204216)
			(xy 368.812988 -254.155162) (xy 368.824765 -254.107378) (xy 368.844056 -254.062102) (xy 368.870359 -254.020506)
			(xy 368.902994 -253.983669) (xy 368.941115 -253.952544) (xy 368.983736 -253.927937) (xy 369.029752 -253.910485)
			(xy 369.077971 -253.900641) (xy 369.127146 -253.89866) (xy 369.176001 -253.904592) (xy 369.223272 -253.918284)
			(xy 369.267734 -253.939382) (xy 369.308237 -253.967338) (xy 369.34373 -254.00143) (xy 369.373295 -254.040774)
			(xy 369.396166 -254.084351) (xy 369.41175 -254.131032) (xy 369.419645 -254.179609) (xy 369.42014 -254.204216)
			(xy 370.688882 -254.204216) (xy 370.692842 -254.155162) (xy 370.704619 -254.107378) (xy 370.72391 -254.062102)
			(xy 370.750213 -254.020506) (xy 370.782848 -253.983669) (xy 370.820969 -253.952544) (xy 370.86359 -253.927937)
			(xy 370.909606 -253.910485) (xy 370.957825 -253.900641) (xy 371.007 -253.89866) (xy 371.055855 -253.904592)
			(xy 371.103126 -253.918284) (xy 371.147588 -253.939382) (xy 371.188091 -253.967338) (xy 371.223584 -254.00143)
			(xy 371.253149 -254.040774) (xy 371.27602 -254.084351) (xy 371.291604 -254.131032) (xy 371.299499 -254.179609)
			(xy 371.299994 -254.204216) (xy 372.56899 -254.204216) (xy 372.57295 -254.155162) (xy 372.584727 -254.107378)
			(xy 372.604018 -254.062102) (xy 372.630321 -254.020506) (xy 372.662956 -253.983669) (xy 372.701077 -253.952544)
			(xy 372.743698 -253.927937) (xy 372.789714 -253.910485) (xy 372.837933 -253.900641) (xy 372.887108 -253.89866)
			(xy 372.935963 -253.904592) (xy 372.983234 -253.918284) (xy 373.027696 -253.939382) (xy 373.068199 -253.967338)
			(xy 373.103692 -254.00143) (xy 373.133257 -254.040774) (xy 373.156128 -254.084351) (xy 373.171712 -254.131032)
			(xy 373.179607 -254.179609) (xy 373.180102 -254.204216) (xy 374.449098 -254.204216) (xy 374.453058 -254.155162)
			(xy 374.464835 -254.107378) (xy 374.484126 -254.062102) (xy 374.510429 -254.020506) (xy 374.543064 -253.983669)
			(xy 374.581185 -253.952544) (xy 374.623806 -253.927937) (xy 374.669822 -253.910485) (xy 374.718041 -253.900641)
			(xy 374.767216 -253.89866) (xy 374.816071 -253.904592) (xy 374.863342 -253.918284) (xy 374.907804 -253.939382)
			(xy 374.948307 -253.967338) (xy 374.9838 -254.00143) (xy 375.013365 -254.040774) (xy 375.036236 -254.084351)
			(xy 375.05182 -254.131032) (xy 375.059715 -254.179609) (xy 375.06021 -254.204216) (xy 375.378467 -254.204216)
			(xy 375.382562 -254.153488) (xy 375.394741 -254.104074) (xy 375.414689 -254.057254) (xy 375.44189 -254.01424)
			(xy 375.475638 -253.976146) (xy 375.51506 -253.943959) (xy 375.559134 -253.918513) (xy 375.60672 -253.900466)
			(xy 375.656584 -253.890286) (xy 375.707436 -253.888237) (xy 375.757957 -253.894371) (xy 375.806841 -253.908531)
			(xy 375.85282 -253.930348) (xy 375.894704 -253.959258) (xy 375.931408 -253.994513) (xy 375.961981 -254.035199)
			(xy 375.985632 -254.080262) (xy 376.001748 -254.128536) (xy 376.009912 -254.17877) (xy 376.010424 -254.204216)
			(xy 376.328952 -254.204216) (xy 376.332912 -254.155162) (xy 376.344689 -254.107378) (xy 376.36398 -254.062102)
			(xy 376.390283 -254.020506) (xy 376.422918 -253.983669) (xy 376.461039 -253.952544) (xy 376.50366 -253.927937)
			(xy 376.549676 -253.910485) (xy 376.597895 -253.900641) (xy 376.64707 -253.89866) (xy 376.695925 -253.904592)
			(xy 376.743196 -253.918284) (xy 376.787658 -253.939382) (xy 376.828161 -253.967338) (xy 376.863654 -254.00143)
			(xy 376.893219 -254.040774) (xy 376.91609 -254.084351) (xy 376.931674 -254.131032) (xy 376.939569 -254.179609)
			(xy 376.940064 -254.204216) (xy 377.258575 -254.204216) (xy 377.26267 -254.153488) (xy 377.274849 -254.104074)
			(xy 377.294797 -254.057254) (xy 377.321998 -254.01424) (xy 377.355746 -253.976146) (xy 377.395168 -253.943959)
			(xy 377.439242 -253.918513) (xy 377.486828 -253.900466) (xy 377.536692 -253.890286) (xy 377.587544 -253.888237)
			(xy 377.638065 -253.894371) (xy 377.686949 -253.908531) (xy 377.732928 -253.930348) (xy 377.774812 -253.959258)
			(xy 377.811516 -253.994513) (xy 377.842089 -254.035199) (xy 377.86574 -254.080262) (xy 377.881856 -254.128536)
			(xy 377.89002 -254.17877) (xy 377.890532 -254.204216) (xy 379.138683 -254.204216) (xy 379.142778 -254.153488)
			(xy 379.154957 -254.104074) (xy 379.174905 -254.057254) (xy 379.202106 -254.01424) (xy 379.235854 -253.976146)
			(xy 379.275276 -253.943959) (xy 379.31935 -253.918513) (xy 379.366936 -253.900466) (xy 379.4168 -253.890286)
			(xy 379.467652 -253.888237) (xy 379.518173 -253.894371) (xy 379.567057 -253.908531) (xy 379.613036 -253.930348)
			(xy 379.65492 -253.959258) (xy 379.691624 -253.994513) (xy 379.722197 -254.035199) (xy 379.745848 -254.080262)
			(xy 379.761964 -254.128536) (xy 379.770128 -254.17877) (xy 379.77064 -254.204216) (xy 380.078483 -254.204216)
			(xy 380.082578 -254.153488) (xy 380.094757 -254.104074) (xy 380.114705 -254.057254) (xy 380.141906 -254.01424)
			(xy 380.175654 -253.976146) (xy 380.215076 -253.943959) (xy 380.25915 -253.918513) (xy 380.306736 -253.900466)
			(xy 380.3566 -253.890286) (xy 380.407452 -253.888237) (xy 380.457973 -253.894371) (xy 380.506857 -253.908531)
			(xy 380.552836 -253.930348) (xy 380.59472 -253.959258) (xy 380.631424 -253.994513) (xy 380.661997 -254.035199)
			(xy 380.685648 -254.080262) (xy 380.701764 -254.128536) (xy 380.709928 -254.17877) (xy 380.71044 -254.204216)
			(xy 380.709928 -254.229662) (xy 380.701764 -254.279896) (xy 380.685648 -254.32817) (xy 380.661997 -254.373233)
			(xy 380.631424 -254.413919) (xy 380.59472 -254.449174) (xy 380.552836 -254.478084) (xy 380.506857 -254.499901)
			(xy 380.457973 -254.514061) (xy 380.407452 -254.520195) (xy 380.3566 -254.518146) (xy 380.306736 -254.507966)
			(xy 380.25915 -254.489919) (xy 380.215076 -254.464473) (xy 380.175654 -254.432286) (xy 380.141906 -254.394192)
			(xy 380.114705 -254.351178) (xy 380.094757 -254.304358) (xy 380.082578 -254.254944) (xy 380.078483 -254.204216)
			(xy 379.77064 -254.204216) (xy 379.770128 -254.229662) (xy 379.761964 -254.279896) (xy 379.745848 -254.32817)
			(xy 379.722197 -254.373233) (xy 379.691624 -254.413919) (xy 379.65492 -254.449174) (xy 379.613036 -254.478084)
			(xy 379.567057 -254.499901) (xy 379.518173 -254.514061) (xy 379.467652 -254.520195) (xy 379.4168 -254.518146)
			(xy 379.366936 -254.507966) (xy 379.31935 -254.489919) (xy 379.275276 -254.464473) (xy 379.235854 -254.432286)
			(xy 379.202106 -254.394192) (xy 379.174905 -254.351178) (xy 379.154957 -254.304358) (xy 379.142778 -254.254944)
			(xy 379.138683 -254.204216) (xy 377.890532 -254.204216) (xy 377.89002 -254.229662) (xy 377.881856 -254.279896)
			(xy 377.86574 -254.32817) (xy 377.842089 -254.373233) (xy 377.811516 -254.413919) (xy 377.774812 -254.449174)
			(xy 377.732928 -254.478084) (xy 377.686949 -254.499901) (xy 377.638065 -254.514061) (xy 377.587544 -254.520195)
			(xy 377.536692 -254.518146) (xy 377.486828 -254.507966) (xy 377.439242 -254.489919) (xy 377.395168 -254.464473)
			(xy 377.355746 -254.432286) (xy 377.321998 -254.394192) (xy 377.294797 -254.351178) (xy 377.274849 -254.304358)
			(xy 377.26267 -254.254944) (xy 377.258575 -254.204216) (xy 376.940064 -254.204216) (xy 376.939569 -254.228823)
			(xy 376.931674 -254.2774) (xy 376.91609 -254.324081) (xy 376.893219 -254.367658) (xy 376.863654 -254.407002)
			(xy 376.828161 -254.441094) (xy 376.787658 -254.46905) (xy 376.743196 -254.490148) (xy 376.695925 -254.50384)
			(xy 376.64707 -254.509772) (xy 376.597895 -254.507791) (xy 376.549676 -254.497947) (xy 376.50366 -254.480495)
			(xy 376.461039 -254.455888) (xy 376.422918 -254.424763) (xy 376.390283 -254.387926) (xy 376.36398 -254.34633)
			(xy 376.344689 -254.301054) (xy 376.332912 -254.25327) (xy 376.328952 -254.204216) (xy 376.010424 -254.204216)
			(xy 376.009912 -254.229662) (xy 376.001748 -254.279896) (xy 375.985632 -254.32817) (xy 375.961981 -254.373233)
			(xy 375.931408 -254.413919) (xy 375.894704 -254.449174) (xy 375.85282 -254.478084) (xy 375.806841 -254.499901)
			(xy 375.757957 -254.514061) (xy 375.707436 -254.520195) (xy 375.656584 -254.518146) (xy 375.60672 -254.507966)
			(xy 375.559134 -254.489919) (xy 375.51506 -254.464473) (xy 375.475638 -254.432286) (xy 375.44189 -254.394192)
			(xy 375.414689 -254.351178) (xy 375.394741 -254.304358) (xy 375.382562 -254.254944) (xy 375.378467 -254.204216)
			(xy 375.06021 -254.204216) (xy 375.059715 -254.228823) (xy 375.05182 -254.2774) (xy 375.036236 -254.324081)
			(xy 375.013365 -254.367658) (xy 374.9838 -254.407002) (xy 374.948307 -254.441094) (xy 374.907804 -254.46905)
			(xy 374.863342 -254.490148) (xy 374.816071 -254.50384) (xy 374.767216 -254.509772) (xy 374.718041 -254.507791)
			(xy 374.669822 -254.497947) (xy 374.623806 -254.480495) (xy 374.581185 -254.455888) (xy 374.543064 -254.424763)
			(xy 374.510429 -254.387926) (xy 374.484126 -254.34633) (xy 374.464835 -254.301054) (xy 374.453058 -254.25327)
			(xy 374.449098 -254.204216) (xy 373.180102 -254.204216) (xy 373.179607 -254.228823) (xy 373.171712 -254.2774)
			(xy 373.156128 -254.324081) (xy 373.133257 -254.367658) (xy 373.103692 -254.407002) (xy 373.068199 -254.441094)
			(xy 373.027696 -254.46905) (xy 372.983234 -254.490148) (xy 372.935963 -254.50384) (xy 372.887108 -254.509772)
			(xy 372.837933 -254.507791) (xy 372.789714 -254.497947) (xy 372.743698 -254.480495) (xy 372.701077 -254.455888)
			(xy 372.662956 -254.424763) (xy 372.630321 -254.387926) (xy 372.604018 -254.34633) (xy 372.584727 -254.301054)
			(xy 372.57295 -254.25327) (xy 372.56899 -254.204216) (xy 371.299994 -254.204216) (xy 371.299499 -254.228823)
			(xy 371.291604 -254.2774) (xy 371.27602 -254.324081) (xy 371.253149 -254.367658) (xy 371.223584 -254.407002)
			(xy 371.188091 -254.441094) (xy 371.147588 -254.46905) (xy 371.103126 -254.490148) (xy 371.055855 -254.50384)
			(xy 371.007 -254.509772) (xy 370.957825 -254.507791) (xy 370.909606 -254.497947) (xy 370.86359 -254.480495)
			(xy 370.820969 -254.455888) (xy 370.782848 -254.424763) (xy 370.750213 -254.387926) (xy 370.72391 -254.34633)
			(xy 370.704619 -254.301054) (xy 370.692842 -254.25327) (xy 370.688882 -254.204216) (xy 369.42014 -254.204216)
			(xy 369.419645 -254.228823) (xy 369.41175 -254.2774) (xy 369.396166 -254.324081) (xy 369.373295 -254.367658)
			(xy 369.34373 -254.407002) (xy 369.308237 -254.441094) (xy 369.267734 -254.46905) (xy 369.223272 -254.490148)
			(xy 369.176001 -254.50384) (xy 369.127146 -254.509772) (xy 369.077971 -254.507791) (xy 369.029752 -254.497947)
			(xy 368.983736 -254.480495) (xy 368.941115 -254.455888) (xy 368.902994 -254.424763) (xy 368.870359 -254.387926)
			(xy 368.844056 -254.34633) (xy 368.824765 -254.301054) (xy 368.812988 -254.25327) (xy 368.809028 -254.204216)
			(xy 360.438648 -254.204216) (xy 360.46298 -254.229498) (xy 360.493272 -254.272564) (xy 360.516635 -254.319749)
			(xy 360.532521 -254.369948) (xy 360.540558 -254.421984) (xy 360.541062 -254.44831) (xy 360.540558 -254.474636)
			(xy 360.532521 -254.526672) (xy 360.516635 -254.576871) (xy 360.493272 -254.624056) (xy 360.46298 -254.667122)
			(xy 360.426468 -254.70506) (xy 360.384594 -254.736979) (xy 360.338338 -254.762132) (xy 360.288785 -254.77993)
			(xy 360.237095 -254.789954) (xy 360.184481 -254.791971) (xy 360.132176 -254.785933) (xy 360.081405 -254.771981)
			(xy 360.03336 -254.750442) (xy 359.989165 -254.721822) (xy 359.949857 -254.686791) (xy 359.916357 -254.64617)
			(xy 359.889451 -254.600911) (xy 359.869768 -254.552076) (xy 359.857771 -254.500808) (xy 359.853741 -254.44831)
			(xy 349.564014 -254.44831) (xy 349.533966 -254.46905) (xy 349.489504 -254.490148) (xy 349.442233 -254.50384)
			(xy 349.393378 -254.509772) (xy 349.344203 -254.507791) (xy 349.295984 -254.497947) (xy 349.249968 -254.480495)
			(xy 349.207347 -254.455888) (xy 349.169226 -254.424763) (xy 349.136591 -254.387926) (xy 349.110288 -254.34633)
			(xy 349.090997 -254.301054) (xy 349.07922 -254.25327) (xy 349.07526 -254.204216) (xy 348.746799 -254.204216)
			(xy 348.74297 -254.252459) (xy 348.731581 -254.299499) (xy 348.712917 -254.344156) (xy 348.687445 -254.385312)
			(xy 348.655803 -254.421936) (xy 348.637606 -254.437896) (xy 348.629224 -254.445008) (xy 348.615 -254.47371)
			(xy 348.612629 -254.47899) (xy 348.610072 -254.490276) (xy 348.60992 -254.496062) (xy 348.60992 -255.014222)
			(xy 349.545414 -255.014222) (xy 349.549374 -254.965168) (xy 349.561151 -254.917384) (xy 349.580442 -254.872108)
			(xy 349.606745 -254.830512) (xy 349.63938 -254.793675) (xy 349.677501 -254.76255) (xy 349.720122 -254.737943)
			(xy 349.766138 -254.720491) (xy 349.814357 -254.710647) (xy 349.863532 -254.708666) (xy 349.912387 -254.714598)
			(xy 349.959658 -254.72829) (xy 350.00412 -254.749388) (xy 350.044623 -254.777344) (xy 350.080116 -254.811436)
			(xy 350.109681 -254.85078) (xy 350.132552 -254.894357) (xy 350.148136 -254.941038) (xy 350.156031 -254.989615)
			(xy 350.156526 -255.014222) (xy 370.218982 -255.014222) (xy 370.222942 -254.965168) (xy 370.234719 -254.917384)
			(xy 370.25401 -254.872108) (xy 370.280313 -254.830512) (xy 370.312948 -254.793675) (xy 370.351069 -254.76255)
			(xy 370.39369 -254.737943) (xy 370.439706 -254.720491) (xy 370.487925 -254.710647) (xy 370.5371 -254.708666)
			(xy 370.585955 -254.714598) (xy 370.633226 -254.72829) (xy 370.677688 -254.749388) (xy 370.718191 -254.777344)
			(xy 370.753684 -254.811436) (xy 370.783249 -254.85078) (xy 370.80612 -254.894357) (xy 370.821704 -254.941038)
			(xy 370.829599 -254.989615) (xy 370.830094 -255.014222) (xy 372.09909 -255.014222) (xy 372.10305 -254.965168)
			(xy 372.114827 -254.917384) (xy 372.134118 -254.872108) (xy 372.160421 -254.830512) (xy 372.193056 -254.793675)
			(xy 372.231177 -254.76255) (xy 372.273798 -254.737943) (xy 372.319814 -254.720491) (xy 372.368033 -254.710647)
			(xy 372.417208 -254.708666) (xy 372.466063 -254.714598) (xy 372.513334 -254.72829) (xy 372.557796 -254.749388)
			(xy 372.598299 -254.777344) (xy 372.633792 -254.811436) (xy 372.663357 -254.85078) (xy 372.686228 -254.894357)
			(xy 372.701812 -254.941038) (xy 372.709707 -254.989615) (xy 372.710202 -255.014222) (xy 373.978944 -255.014222)
			(xy 373.982904 -254.965168) (xy 373.994681 -254.917384) (xy 374.013972 -254.872108) (xy 374.040275 -254.830512)
			(xy 374.07291 -254.793675) (xy 374.111031 -254.76255) (xy 374.153652 -254.737943) (xy 374.199668 -254.720491)
			(xy 374.247887 -254.710647) (xy 374.297062 -254.708666) (xy 374.345917 -254.714598) (xy 374.393188 -254.72829)
			(xy 374.43765 -254.749388) (xy 374.478153 -254.777344) (xy 374.513646 -254.811436) (xy 374.543211 -254.85078)
			(xy 374.566082 -254.894357) (xy 374.581666 -254.941038) (xy 374.589561 -254.989615) (xy 374.590056 -255.014222)
			(xy 375.848621 -255.014222) (xy 375.852716 -254.963494) (xy 375.864895 -254.91408) (xy 375.884843 -254.86726)
			(xy 375.912044 -254.824246) (xy 375.945792 -254.786152) (xy 375.985214 -254.753965) (xy 376.029288 -254.728519)
			(xy 376.076874 -254.710472) (xy 376.126738 -254.700292) (xy 376.17759 -254.698243) (xy 376.228111 -254.704377)
			(xy 376.276995 -254.718537) (xy 376.322974 -254.740354) (xy 376.364858 -254.769264) (xy 376.401562 -254.804519)
			(xy 376.432135 -254.845205) (xy 376.455786 -254.890268) (xy 376.471902 -254.938542) (xy 376.480066 -254.988776)
			(xy 376.480578 -255.014222) (xy 376.788675 -255.014222) (xy 376.79277 -254.963494) (xy 376.804949 -254.91408)
			(xy 376.824897 -254.86726) (xy 376.852098 -254.824246) (xy 376.885846 -254.786152) (xy 376.925268 -254.753965)
			(xy 376.969342 -254.728519) (xy 377.016928 -254.710472) (xy 377.066792 -254.700292) (xy 377.117644 -254.698243)
			(xy 377.168165 -254.704377) (xy 377.217049 -254.718537) (xy 377.263028 -254.740354) (xy 377.304912 -254.769264)
			(xy 377.341616 -254.804519) (xy 377.372189 -254.845205) (xy 377.39584 -254.890268) (xy 377.411956 -254.938542)
			(xy 377.42012 -254.988776) (xy 377.420632 -255.014222) (xy 377.738906 -255.014222) (xy 377.742866 -254.965168)
			(xy 377.754643 -254.917384) (xy 377.773934 -254.872108) (xy 377.800237 -254.830512) (xy 377.832872 -254.793675)
			(xy 377.870993 -254.76255) (xy 377.913614 -254.737943) (xy 377.95963 -254.720491) (xy 378.007849 -254.710647)
			(xy 378.057024 -254.708666) (xy 378.105879 -254.714598) (xy 378.15315 -254.72829) (xy 378.197612 -254.749388)
			(xy 378.238115 -254.777344) (xy 378.273608 -254.811436) (xy 378.303173 -254.85078) (xy 378.326044 -254.894357)
			(xy 378.341628 -254.941038) (xy 378.349523 -254.989615) (xy 378.350018 -255.014222) (xy 378.668529 -255.014222)
			(xy 378.672624 -254.963494) (xy 378.684803 -254.91408) (xy 378.704751 -254.86726) (xy 378.731952 -254.824246)
			(xy 378.7657 -254.786152) (xy 378.805122 -254.753965) (xy 378.849196 -254.728519) (xy 378.896782 -254.710472)
			(xy 378.946646 -254.700292) (xy 378.997498 -254.698243) (xy 379.048019 -254.704377) (xy 379.096903 -254.718537)
			(xy 379.142882 -254.740354) (xy 379.184766 -254.769264) (xy 379.22147 -254.804519) (xy 379.252043 -254.845205)
			(xy 379.275694 -254.890268) (xy 379.29181 -254.938542) (xy 379.299974 -254.988776) (xy 379.300486 -255.014222)
			(xy 379.619014 -255.014222) (xy 379.622974 -254.965168) (xy 379.634751 -254.917384) (xy 379.654042 -254.872108)
			(xy 379.680345 -254.830512) (xy 379.71298 -254.793675) (xy 379.751101 -254.76255) (xy 379.793722 -254.737943)
			(xy 379.839738 -254.720491) (xy 379.887957 -254.710647) (xy 379.937132 -254.708666) (xy 379.985987 -254.714598)
			(xy 380.033258 -254.72829) (xy 380.07772 -254.749388) (xy 380.118223 -254.777344) (xy 380.153716 -254.811436)
			(xy 380.183281 -254.85078) (xy 380.206152 -254.894357) (xy 380.221736 -254.941038) (xy 380.229631 -254.989615)
			(xy 380.230126 -255.014222) (xy 380.548637 -255.014222) (xy 380.552732 -254.963494) (xy 380.564911 -254.91408)
			(xy 380.584859 -254.86726) (xy 380.61206 -254.824246) (xy 380.645808 -254.786152) (xy 380.68523 -254.753965)
			(xy 380.729304 -254.728519) (xy 380.77689 -254.710472) (xy 380.826754 -254.700292) (xy 380.877606 -254.698243)
			(xy 380.928127 -254.704377) (xy 380.977011 -254.718537) (xy 381.02299 -254.740354) (xy 381.064874 -254.769264)
			(xy 381.101578 -254.804519) (xy 381.132151 -254.845205) (xy 381.155802 -254.890268) (xy 381.171918 -254.938542)
			(xy 381.180082 -254.988776) (xy 381.180594 -255.014222) (xy 381.180082 -255.039668) (xy 381.171918 -255.089902)
			(xy 381.155802 -255.138176) (xy 381.132151 -255.183239) (xy 381.101578 -255.223925) (xy 381.064874 -255.25918)
			(xy 381.02299 -255.28809) (xy 380.977011 -255.309907) (xy 380.928127 -255.324067) (xy 380.877606 -255.330201)
			(xy 380.826754 -255.328152) (xy 380.77689 -255.317972) (xy 380.729304 -255.299925) (xy 380.68523 -255.274479)
			(xy 380.645808 -255.242292) (xy 380.61206 -255.204198) (xy 380.584859 -255.161184) (xy 380.564911 -255.114364)
			(xy 380.552732 -255.06495) (xy 380.548637 -255.014222) (xy 380.230126 -255.014222) (xy 380.229631 -255.038829)
			(xy 380.221736 -255.087406) (xy 380.206152 -255.134087) (xy 380.183281 -255.177664) (xy 380.153716 -255.217008)
			(xy 380.118223 -255.2511) (xy 380.07772 -255.279056) (xy 380.033258 -255.300154) (xy 379.985987 -255.313846)
			(xy 379.937132 -255.319778) (xy 379.887957 -255.317797) (xy 379.839738 -255.307953) (xy 379.793722 -255.290501)
			(xy 379.751101 -255.265894) (xy 379.71298 -255.234769) (xy 379.680345 -255.197932) (xy 379.654042 -255.156336)
			(xy 379.634751 -255.11106) (xy 379.622974 -255.063276) (xy 379.619014 -255.014222) (xy 379.300486 -255.014222)
			(xy 379.299974 -255.039668) (xy 379.29181 -255.089902) (xy 379.275694 -255.138176) (xy 379.252043 -255.183239)
			(xy 379.22147 -255.223925) (xy 379.184766 -255.25918) (xy 379.142882 -255.28809) (xy 379.096903 -255.309907)
			(xy 379.048019 -255.324067) (xy 378.997498 -255.330201) (xy 378.946646 -255.328152) (xy 378.896782 -255.317972)
			(xy 378.849196 -255.299925) (xy 378.805122 -255.274479) (xy 378.7657 -255.242292) (xy 378.731952 -255.204198)
			(xy 378.704751 -255.161184) (xy 378.684803 -255.114364) (xy 378.672624 -255.06495) (xy 378.668529 -255.014222)
			(xy 378.350018 -255.014222) (xy 378.349523 -255.038829) (xy 378.341628 -255.087406) (xy 378.326044 -255.134087)
			(xy 378.303173 -255.177664) (xy 378.273608 -255.217008) (xy 378.238115 -255.2511) (xy 378.197612 -255.279056)
			(xy 378.15315 -255.300154) (xy 378.105879 -255.313846) (xy 378.057024 -255.319778) (xy 378.007849 -255.317797)
			(xy 377.95963 -255.307953) (xy 377.913614 -255.290501) (xy 377.870993 -255.265894) (xy 377.832872 -255.234769)
			(xy 377.800237 -255.197932) (xy 377.773934 -255.156336) (xy 377.754643 -255.11106) (xy 377.742866 -255.063276)
			(xy 377.738906 -255.014222) (xy 377.420632 -255.014222) (xy 377.42012 -255.039668) (xy 377.411956 -255.089902)
			(xy 377.39584 -255.138176) (xy 377.372189 -255.183239) (xy 377.341616 -255.223925) (xy 377.304912 -255.25918)
			(xy 377.263028 -255.28809) (xy 377.217049 -255.309907) (xy 377.168165 -255.324067) (xy 377.117644 -255.330201)
			(xy 377.066792 -255.328152) (xy 377.016928 -255.317972) (xy 376.969342 -255.299925) (xy 376.925268 -255.274479)
			(xy 376.885846 -255.242292) (xy 376.852098 -255.204198) (xy 376.824897 -255.161184) (xy 376.804949 -255.114364)
			(xy 376.79277 -255.06495) (xy 376.788675 -255.014222) (xy 376.480578 -255.014222) (xy 376.480066 -255.039668)
			(xy 376.471902 -255.089902) (xy 376.455786 -255.138176) (xy 376.432135 -255.183239) (xy 376.401562 -255.223925)
			(xy 376.364858 -255.25918) (xy 376.322974 -255.28809) (xy 376.276995 -255.309907) (xy 376.228111 -255.324067)
			(xy 376.17759 -255.330201) (xy 376.126738 -255.328152) (xy 376.076874 -255.317972) (xy 376.029288 -255.299925)
			(xy 375.985214 -255.274479) (xy 375.945792 -255.242292) (xy 375.912044 -255.204198) (xy 375.884843 -255.161184)
			(xy 375.864895 -255.114364) (xy 375.852716 -255.06495) (xy 375.848621 -255.014222) (xy 374.590056 -255.014222)
			(xy 374.589561 -255.038829) (xy 374.581666 -255.087406) (xy 374.566082 -255.134087) (xy 374.543211 -255.177664)
			(xy 374.513646 -255.217008) (xy 374.478153 -255.2511) (xy 374.43765 -255.279056) (xy 374.393188 -255.300154)
			(xy 374.345917 -255.313846) (xy 374.297062 -255.319778) (xy 374.247887 -255.317797) (xy 374.199668 -255.307953)
			(xy 374.153652 -255.290501) (xy 374.111031 -255.265894) (xy 374.07291 -255.234769) (xy 374.040275 -255.197932)
			(xy 374.013972 -255.156336) (xy 373.994681 -255.11106) (xy 373.982904 -255.063276) (xy 373.978944 -255.014222)
			(xy 372.710202 -255.014222) (xy 372.709707 -255.038829) (xy 372.701812 -255.087406) (xy 372.686228 -255.134087)
			(xy 372.663357 -255.177664) (xy 372.633792 -255.217008) (xy 372.598299 -255.2511) (xy 372.557796 -255.279056)
			(xy 372.513334 -255.300154) (xy 372.466063 -255.313846) (xy 372.417208 -255.319778) (xy 372.368033 -255.317797)
			(xy 372.319814 -255.307953) (xy 372.273798 -255.290501) (xy 372.231177 -255.265894) (xy 372.193056 -255.234769)
			(xy 372.160421 -255.197932) (xy 372.134118 -255.156336) (xy 372.114827 -255.11106) (xy 372.10305 -255.063276)
			(xy 372.09909 -255.014222) (xy 370.830094 -255.014222) (xy 370.829599 -255.038829) (xy 370.821704 -255.087406)
			(xy 370.80612 -255.134087) (xy 370.783249 -255.177664) (xy 370.753684 -255.217008) (xy 370.718191 -255.2511)
			(xy 370.677688 -255.279056) (xy 370.633226 -255.300154) (xy 370.585955 -255.313846) (xy 370.5371 -255.319778)
			(xy 370.487925 -255.317797) (xy 370.439706 -255.307953) (xy 370.39369 -255.290501) (xy 370.351069 -255.265894)
			(xy 370.312948 -255.234769) (xy 370.280313 -255.197932) (xy 370.25401 -255.156336) (xy 370.234719 -255.11106)
			(xy 370.222942 -255.063276) (xy 370.218982 -255.014222) (xy 350.156526 -255.014222) (xy 350.156031 -255.038829)
			(xy 350.148136 -255.087406) (xy 350.132552 -255.134087) (xy 350.109681 -255.177664) (xy 350.080116 -255.217008)
			(xy 350.044623 -255.2511) (xy 350.00412 -255.279056) (xy 349.959658 -255.300154) (xy 349.912387 -255.313846)
			(xy 349.863532 -255.319778) (xy 349.814357 -255.317797) (xy 349.766138 -255.307953) (xy 349.720122 -255.290501)
			(xy 349.677501 -255.265894) (xy 349.63938 -255.234769) (xy 349.606745 -255.197932) (xy 349.580442 -255.156336)
			(xy 349.561151 -255.11106) (xy 349.549374 -255.063276) (xy 349.545414 -255.014222) (xy 348.60992 -255.014222)
			(xy 348.60992 -255.532382) (xy 348.610044 -255.538171) (xy 348.612607 -255.549461) (xy 348.615 -255.554734)
			(xy 348.629224 -255.583436) (xy 348.637606 -255.590548) (xy 348.655817 -255.606491) (xy 348.687455 -255.643117)
			(xy 348.712922 -255.684273) (xy 348.731581 -255.72893) (xy 348.742965 -255.775971) (xy 348.74679 -255.824218)
			(xy 348.746789 -255.824228) (xy 349.07526 -255.824228) (xy 349.07922 -255.775174) (xy 349.090997 -255.72739)
			(xy 349.110288 -255.682114) (xy 349.136591 -255.640518) (xy 349.169226 -255.603681) (xy 349.207347 -255.572556)
			(xy 349.249968 -255.547949) (xy 349.295984 -255.530497) (xy 349.344203 -255.520653) (xy 349.393378 -255.518672)
			(xy 349.442233 -255.524604) (xy 349.489504 -255.538296) (xy 349.533966 -255.559394) (xy 349.574469 -255.58735)
			(xy 349.609962 -255.621442) (xy 349.639527 -255.660786) (xy 349.662398 -255.704363) (xy 349.677982 -255.751044)
			(xy 349.685877 -255.799621) (xy 349.686331 -255.822196) (xy 351.89212 -255.822196) (xy 351.89608 -255.773142)
			(xy 351.907857 -255.725358) (xy 351.927148 -255.680082) (xy 351.953451 -255.638486) (xy 351.986086 -255.601649)
			(xy 352.024207 -255.570524) (xy 352.066828 -255.545917) (xy 352.112844 -255.528465) (xy 352.161063 -255.518621)
			(xy 352.210238 -255.51664) (xy 352.259093 -255.522572) (xy 352.285069 -255.530096) (xy 353.086927 -255.530096)
			(xy 353.090957 -255.477598) (xy 353.102954 -255.42633) (xy 353.122637 -255.377495) (xy 353.149543 -255.332236)
			(xy 353.183043 -255.291615) (xy 353.222351 -255.256584) (xy 353.266546 -255.227964) (xy 353.314591 -255.206425)
			(xy 353.365362 -255.192473) (xy 353.417667 -255.186435) (xy 353.470281 -255.188452) (xy 353.521971 -255.198476)
			(xy 353.571524 -255.216274) (xy 353.61778 -255.241427) (xy 353.659654 -255.273346) (xy 353.696166 -255.311284)
			(xy 353.726458 -255.35435) (xy 353.749821 -255.401535) (xy 353.765707 -255.451734) (xy 353.773744 -255.50377)
			(xy 353.774248 -255.530096) (xy 354.001327 -255.530096) (xy 354.005357 -255.477598) (xy 354.017354 -255.42633)
			(xy 354.037037 -255.377495) (xy 354.063943 -255.332236) (xy 354.097443 -255.291615) (xy 354.136751 -255.256584)
			(xy 354.180946 -255.227964) (xy 354.228991 -255.206425) (xy 354.279762 -255.192473) (xy 354.332067 -255.186435)
			(xy 354.384681 -255.188452) (xy 354.436371 -255.198476) (xy 354.485924 -255.216274) (xy 354.53218 -255.241427)
			(xy 354.574054 -255.273346) (xy 354.610566 -255.311284) (xy 354.640858 -255.35435) (xy 354.664221 -255.401535)
			(xy 354.680107 -255.451734) (xy 354.688144 -255.50377) (xy 354.688648 -255.530096) (xy 365.036865 -255.530096)
			(xy 365.040895 -255.477598) (xy 365.052892 -255.42633) (xy 365.072575 -255.377495) (xy 365.099481 -255.332236)
			(xy 365.132981 -255.291615) (xy 365.172289 -255.256584) (xy 365.216484 -255.227964) (xy 365.264529 -255.206425)
			(xy 365.3153 -255.192473) (xy 365.367605 -255.186435) (xy 365.420219 -255.188452) (xy 365.471909 -255.198476)
			(xy 365.521462 -255.216274) (xy 365.567718 -255.241427) (xy 365.609592 -255.273346) (xy 365.646104 -255.311284)
			(xy 365.676396 -255.35435) (xy 365.699759 -255.401535) (xy 365.715645 -255.451734) (xy 365.723682 -255.50377)
			(xy 365.724186 -255.530096) (xy 365.723682 -255.556422) (xy 365.715645 -255.608458) (xy 365.699759 -255.658657)
			(xy 365.676396 -255.705842) (xy 365.646104 -255.748908) (xy 365.609592 -255.786846) (xy 365.567718 -255.818765)
			(xy 365.557672 -255.824228) (xy 368.809028 -255.824228) (xy 368.812988 -255.775174) (xy 368.824765 -255.72739)
			(xy 368.844056 -255.682114) (xy 368.870359 -255.640518) (xy 368.902994 -255.603681) (xy 368.941115 -255.572556)
			(xy 368.983736 -255.547949) (xy 369.029752 -255.530497) (xy 369.077971 -255.520653) (xy 369.127146 -255.518672)
			(xy 369.176001 -255.524604) (xy 369.223272 -255.538296) (xy 369.267734 -255.559394) (xy 369.308237 -255.58735)
			(xy 369.34373 -255.621442) (xy 369.373295 -255.660786) (xy 369.396166 -255.704363) (xy 369.41175 -255.751044)
			(xy 369.419645 -255.799621) (xy 369.42014 -255.824228) (xy 370.688882 -255.824228) (xy 370.692842 -255.775174)
			(xy 370.704619 -255.72739) (xy 370.72391 -255.682114) (xy 370.750213 -255.640518) (xy 370.782848 -255.603681)
			(xy 370.820969 -255.572556) (xy 370.86359 -255.547949) (xy 370.909606 -255.530497) (xy 370.957825 -255.520653)
			(xy 371.007 -255.518672) (xy 371.055855 -255.524604) (xy 371.103126 -255.538296) (xy 371.147588 -255.559394)
			(xy 371.188091 -255.58735) (xy 371.223584 -255.621442) (xy 371.253149 -255.660786) (xy 371.27602 -255.704363)
			(xy 371.291604 -255.751044) (xy 371.299499 -255.799621) (xy 371.299994 -255.824228) (xy 372.56899 -255.824228)
			(xy 372.57295 -255.775174) (xy 372.584727 -255.72739) (xy 372.604018 -255.682114) (xy 372.630321 -255.640518)
			(xy 372.662956 -255.603681) (xy 372.701077 -255.572556) (xy 372.743698 -255.547949) (xy 372.789714 -255.530497)
			(xy 372.837933 -255.520653) (xy 372.887108 -255.518672) (xy 372.935963 -255.524604) (xy 372.983234 -255.538296)
			(xy 373.027696 -255.559394) (xy 373.068199 -255.58735) (xy 373.103692 -255.621442) (xy 373.133257 -255.660786)
			(xy 373.156128 -255.704363) (xy 373.171712 -255.751044) (xy 373.179607 -255.799621) (xy 373.180102 -255.824228)
			(xy 374.449098 -255.824228) (xy 374.453058 -255.775174) (xy 374.464835 -255.72739) (xy 374.484126 -255.682114)
			(xy 374.510429 -255.640518) (xy 374.543064 -255.603681) (xy 374.581185 -255.572556) (xy 374.623806 -255.547949)
			(xy 374.669822 -255.530497) (xy 374.718041 -255.520653) (xy 374.767216 -255.518672) (xy 374.816071 -255.524604)
			(xy 374.863342 -255.538296) (xy 374.907804 -255.559394) (xy 374.948307 -255.58735) (xy 374.9838 -255.621442)
			(xy 375.013365 -255.660786) (xy 375.036236 -255.704363) (xy 375.05182 -255.751044) (xy 375.059715 -255.799621)
			(xy 375.06021 -255.824228) (xy 375.378467 -255.824228) (xy 375.382562 -255.7735) (xy 375.394741 -255.724086)
			(xy 375.414689 -255.677266) (xy 375.44189 -255.634252) (xy 375.475638 -255.596158) (xy 375.51506 -255.563971)
			(xy 375.559134 -255.538525) (xy 375.60672 -255.520478) (xy 375.656584 -255.510298) (xy 375.707436 -255.508249)
			(xy 375.757957 -255.514383) (xy 375.806841 -255.528543) (xy 375.85282 -255.55036) (xy 375.894704 -255.57927)
			(xy 375.931408 -255.614525) (xy 375.961981 -255.655211) (xy 375.985632 -255.700274) (xy 376.001748 -255.748548)
			(xy 376.009912 -255.798782) (xy 376.010424 -255.824228) (xy 376.328952 -255.824228) (xy 376.332912 -255.775174)
			(xy 376.344689 -255.72739) (xy 376.36398 -255.682114) (xy 376.390283 -255.640518) (xy 376.422918 -255.603681)
			(xy 376.461039 -255.572556) (xy 376.50366 -255.547949) (xy 376.549676 -255.530497) (xy 376.597895 -255.520653)
			(xy 376.64707 -255.518672) (xy 376.695925 -255.524604) (xy 376.743196 -255.538296) (xy 376.787658 -255.559394)
			(xy 376.828161 -255.58735) (xy 376.863654 -255.621442) (xy 376.893219 -255.660786) (xy 376.91609 -255.704363)
			(xy 376.931674 -255.751044) (xy 376.939569 -255.799621) (xy 376.940064 -255.824228) (xy 377.258575 -255.824228)
			(xy 377.26267 -255.7735) (xy 377.274849 -255.724086) (xy 377.294797 -255.677266) (xy 377.321998 -255.634252)
			(xy 377.355746 -255.596158) (xy 377.395168 -255.563971) (xy 377.439242 -255.538525) (xy 377.486828 -255.520478)
			(xy 377.536692 -255.510298) (xy 377.587544 -255.508249) (xy 377.638065 -255.514383) (xy 377.686949 -255.528543)
			(xy 377.732928 -255.55036) (xy 377.774812 -255.57927) (xy 377.811516 -255.614525) (xy 377.842089 -255.655211)
			(xy 377.86574 -255.700274) (xy 377.881856 -255.748548) (xy 377.89002 -255.798782) (xy 377.890532 -255.824228)
			(xy 378.20906 -255.824228) (xy 378.21302 -255.775174) (xy 378.224797 -255.72739) (xy 378.244088 -255.682114)
			(xy 378.270391 -255.640518) (xy 378.303026 -255.603681) (xy 378.341147 -255.572556) (xy 378.383768 -255.547949)
			(xy 378.429784 -255.530497) (xy 378.478003 -255.520653) (xy 378.527178 -255.518672) (xy 378.576033 -255.524604)
			(xy 378.623304 -255.538296) (xy 378.667766 -255.559394) (xy 378.708269 -255.58735) (xy 378.743762 -255.621442)
			(xy 378.773327 -255.660786) (xy 378.796198 -255.704363) (xy 378.811782 -255.751044) (xy 378.819677 -255.799621)
			(xy 378.820172 -255.824228) (xy 379.138683 -255.824228) (xy 379.142778 -255.7735) (xy 379.154957 -255.724086)
			(xy 379.174905 -255.677266) (xy 379.202106 -255.634252) (xy 379.235854 -255.596158) (xy 379.275276 -255.563971)
			(xy 379.31935 -255.538525) (xy 379.366936 -255.520478) (xy 379.4168 -255.510298) (xy 379.467652 -255.508249)
			(xy 379.518173 -255.514383) (xy 379.567057 -255.528543) (xy 379.613036 -255.55036) (xy 379.65492 -255.57927)
			(xy 379.691624 -255.614525) (xy 379.722197 -255.655211) (xy 379.745848 -255.700274) (xy 379.761964 -255.748548)
			(xy 379.770128 -255.798782) (xy 379.77064 -255.824228) (xy 380.078483 -255.824228) (xy 380.082578 -255.7735)
			(xy 380.094757 -255.724086) (xy 380.114705 -255.677266) (xy 380.141906 -255.634252) (xy 380.175654 -255.596158)
			(xy 380.215076 -255.563971) (xy 380.25915 -255.538525) (xy 380.306736 -255.520478) (xy 380.3566 -255.510298)
			(xy 380.407452 -255.508249) (xy 380.457973 -255.514383) (xy 380.506857 -255.528543) (xy 380.552836 -255.55036)
			(xy 380.59472 -255.57927) (xy 380.631424 -255.614525) (xy 380.661997 -255.655211) (xy 380.685648 -255.700274)
			(xy 380.701764 -255.748548) (xy 380.709928 -255.798782) (xy 380.71044 -255.824228) (xy 380.709928 -255.849674)
			(xy 380.701764 -255.899908) (xy 380.685648 -255.948182) (xy 380.661997 -255.993245) (xy 380.631424 -256.033931)
			(xy 380.59472 -256.069186) (xy 380.552836 -256.098096) (xy 380.506857 -256.119913) (xy 380.457973 -256.134073)
			(xy 380.407452 -256.140207) (xy 380.3566 -256.138158) (xy 380.306736 -256.127978) (xy 380.25915 -256.109931)
			(xy 380.215076 -256.084485) (xy 380.175654 -256.052298) (xy 380.141906 -256.014204) (xy 380.114705 -255.97119)
			(xy 380.094757 -255.92437) (xy 380.082578 -255.874956) (xy 380.078483 -255.824228) (xy 379.77064 -255.824228)
			(xy 379.770128 -255.849674) (xy 379.761964 -255.899908) (xy 379.745848 -255.948182) (xy 379.722197 -255.993245)
			(xy 379.691624 -256.033931) (xy 379.65492 -256.069186) (xy 379.613036 -256.098096) (xy 379.567057 -256.119913)
			(xy 379.518173 -256.134073) (xy 379.467652 -256.140207) (xy 379.4168 -256.138158) (xy 379.366936 -256.127978)
			(xy 379.31935 -256.109931) (xy 379.275276 -256.084485) (xy 379.235854 -256.052298) (xy 379.202106 -256.014204)
			(xy 379.174905 -255.97119) (xy 379.154957 -255.92437) (xy 379.142778 -255.874956) (xy 379.138683 -255.824228)
			(xy 378.820172 -255.824228) (xy 378.819677 -255.848835) (xy 378.811782 -255.897412) (xy 378.796198 -255.944093)
			(xy 378.773327 -255.98767) (xy 378.743762 -256.027014) (xy 378.708269 -256.061106) (xy 378.667766 -256.089062)
			(xy 378.623304 -256.11016) (xy 378.576033 -256.123852) (xy 378.527178 -256.129784) (xy 378.478003 -256.127803)
			(xy 378.429784 -256.117959) (xy 378.383768 -256.100507) (xy 378.341147 -256.0759) (xy 378.303026 -256.044775)
			(xy 378.270391 -256.007938) (xy 378.244088 -255.966342) (xy 378.224797 -255.921066) (xy 378.21302 -255.873282)
			(xy 378.20906 -255.824228) (xy 377.890532 -255.824228) (xy 377.89002 -255.849674) (xy 377.881856 -255.899908)
			(xy 377.86574 -255.948182) (xy 377.842089 -255.993245) (xy 377.811516 -256.033931) (xy 377.774812 -256.069186)
			(xy 377.732928 -256.098096) (xy 377.686949 -256.119913) (xy 377.638065 -256.134073) (xy 377.587544 -256.140207)
			(xy 377.536692 -256.138158) (xy 377.486828 -256.127978) (xy 377.439242 -256.109931) (xy 377.395168 -256.084485)
			(xy 377.355746 -256.052298) (xy 377.321998 -256.014204) (xy 377.294797 -255.97119) (xy 377.274849 -255.92437)
			(xy 377.26267 -255.874956) (xy 377.258575 -255.824228) (xy 376.940064 -255.824228) (xy 376.939569 -255.848835)
			(xy 376.931674 -255.897412) (xy 376.91609 -255.944093) (xy 376.893219 -255.98767) (xy 376.863654 -256.027014)
			(xy 376.828161 -256.061106) (xy 376.787658 -256.089062) (xy 376.743196 -256.11016) (xy 376.695925 -256.123852)
			(xy 376.64707 -256.129784) (xy 376.597895 -256.127803) (xy 376.549676 -256.117959) (xy 376.50366 -256.100507)
			(xy 376.461039 -256.0759) (xy 376.422918 -256.044775) (xy 376.390283 -256.007938) (xy 376.36398 -255.966342)
			(xy 376.344689 -255.921066) (xy 376.332912 -255.873282) (xy 376.328952 -255.824228) (xy 376.010424 -255.824228)
			(xy 376.009912 -255.849674) (xy 376.001748 -255.899908) (xy 375.985632 -255.948182) (xy 375.961981 -255.993245)
			(xy 375.931408 -256.033931) (xy 375.894704 -256.069186) (xy 375.85282 -256.098096) (xy 375.806841 -256.119913)
			(xy 375.757957 -256.134073) (xy 375.707436 -256.140207) (xy 375.656584 -256.138158) (xy 375.60672 -256.127978)
			(xy 375.559134 -256.109931) (xy 375.51506 -256.084485) (xy 375.475638 -256.052298) (xy 375.44189 -256.014204)
			(xy 375.414689 -255.97119) (xy 375.394741 -255.92437) (xy 375.382562 -255.874956) (xy 375.378467 -255.824228)
			(xy 375.06021 -255.824228) (xy 375.059715 -255.848835) (xy 375.05182 -255.897412) (xy 375.036236 -255.944093)
			(xy 375.013365 -255.98767) (xy 374.9838 -256.027014) (xy 374.948307 -256.061106) (xy 374.907804 -256.089062)
			(xy 374.863342 -256.11016) (xy 374.816071 -256.123852) (xy 374.767216 -256.129784) (xy 374.718041 -256.127803)
			(xy 374.669822 -256.117959) (xy 374.623806 -256.100507) (xy 374.581185 -256.0759) (xy 374.543064 -256.044775)
			(xy 374.510429 -256.007938) (xy 374.484126 -255.966342) (xy 374.464835 -255.921066) (xy 374.453058 -255.873282)
			(xy 374.449098 -255.824228) (xy 373.180102 -255.824228) (xy 373.179607 -255.848835) (xy 373.171712 -255.897412)
			(xy 373.156128 -255.944093) (xy 373.133257 -255.98767) (xy 373.103692 -256.027014) (xy 373.068199 -256.061106)
			(xy 373.027696 -256.089062) (xy 372.983234 -256.11016) (xy 372.935963 -256.123852) (xy 372.887108 -256.129784)
			(xy 372.837933 -256.127803) (xy 372.789714 -256.117959) (xy 372.743698 -256.100507) (xy 372.701077 -256.0759)
			(xy 372.662956 -256.044775) (xy 372.630321 -256.007938) (xy 372.604018 -255.966342) (xy 372.584727 -255.921066)
			(xy 372.57295 -255.873282) (xy 372.56899 -255.824228) (xy 371.299994 -255.824228) (xy 371.299499 -255.848835)
			(xy 371.291604 -255.897412) (xy 371.27602 -255.944093) (xy 371.253149 -255.98767) (xy 371.223584 -256.027014)
			(xy 371.188091 -256.061106) (xy 371.147588 -256.089062) (xy 371.103126 -256.11016) (xy 371.055855 -256.123852)
			(xy 371.007 -256.129784) (xy 370.957825 -256.127803) (xy 370.909606 -256.117959) (xy 370.86359 -256.100507)
			(xy 370.820969 -256.0759) (xy 370.782848 -256.044775) (xy 370.750213 -256.007938) (xy 370.72391 -255.966342)
			(xy 370.704619 -255.921066) (xy 370.692842 -255.873282) (xy 370.688882 -255.824228) (xy 369.42014 -255.824228)
			(xy 369.419645 -255.848835) (xy 369.41175 -255.897412) (xy 369.396166 -255.944093) (xy 369.373295 -255.98767)
			(xy 369.34373 -256.027014) (xy 369.308237 -256.061106) (xy 369.267734 -256.089062) (xy 369.223272 -256.11016)
			(xy 369.176001 -256.123852) (xy 369.127146 -256.129784) (xy 369.077971 -256.127803) (xy 369.029752 -256.117959)
			(xy 368.983736 -256.100507) (xy 368.941115 -256.0759) (xy 368.902994 -256.044775) (xy 368.870359 -256.007938)
			(xy 368.844056 -255.966342) (xy 368.824765 -255.921066) (xy 368.812988 -255.873282) (xy 368.809028 -255.824228)
			(xy 365.557672 -255.824228) (xy 365.521462 -255.843918) (xy 365.471909 -255.861716) (xy 365.420219 -255.87174)
			(xy 365.367605 -255.873757) (xy 365.3153 -255.867719) (xy 365.264529 -255.853767) (xy 365.216484 -255.832228)
			(xy 365.172289 -255.803608) (xy 365.132981 -255.768577) (xy 365.099481 -255.727956) (xy 365.072575 -255.682697)
			(xy 365.052892 -255.633862) (xy 365.040895 -255.582594) (xy 365.036865 -255.530096) (xy 354.688648 -255.530096)
			(xy 354.688144 -255.556422) (xy 354.680107 -255.608458) (xy 354.664221 -255.658657) (xy 354.640858 -255.705842)
			(xy 354.610566 -255.748908) (xy 354.574054 -255.786846) (xy 354.53218 -255.818765) (xy 354.485924 -255.843918)
			(xy 354.436371 -255.861716) (xy 354.384681 -255.87174) (xy 354.332067 -255.873757) (xy 354.279762 -255.867719)
			(xy 354.228991 -255.853767) (xy 354.180946 -255.832228) (xy 354.136751 -255.803608) (xy 354.097443 -255.768577)
			(xy 354.063943 -255.727956) (xy 354.037037 -255.682697) (xy 354.017354 -255.633862) (xy 354.005357 -255.582594)
			(xy 354.001327 -255.530096) (xy 353.774248 -255.530096) (xy 353.773744 -255.556422) (xy 353.765707 -255.608458)
			(xy 353.749821 -255.658657) (xy 353.726458 -255.705842) (xy 353.696166 -255.748908) (xy 353.659654 -255.786846)
			(xy 353.61778 -255.818765) (xy 353.571524 -255.843918) (xy 353.521971 -255.861716) (xy 353.470281 -255.87174)
			(xy 353.417667 -255.873757) (xy 353.365362 -255.867719) (xy 353.314591 -255.853767) (xy 353.266546 -255.832228)
			(xy 353.222351 -255.803608) (xy 353.183043 -255.768577) (xy 353.149543 -255.727956) (xy 353.122637 -255.682697)
			(xy 353.102954 -255.633862) (xy 353.090957 -255.582594) (xy 353.086927 -255.530096) (xy 352.285069 -255.530096)
			(xy 352.306364 -255.536264) (xy 352.350826 -255.557362) (xy 352.391329 -255.585318) (xy 352.426822 -255.61941)
			(xy 352.456387 -255.658754) (xy 352.479258 -255.702331) (xy 352.494842 -255.749012) (xy 352.502737 -255.797589)
			(xy 352.503232 -255.822196) (xy 352.502737 -255.846803) (xy 352.494842 -255.89538) (xy 352.479258 -255.942061)
			(xy 352.456387 -255.985638) (xy 352.426822 -256.024982) (xy 352.391329 -256.059074) (xy 352.350826 -256.08703)
			(xy 352.306364 -256.108128) (xy 352.259093 -256.12182) (xy 352.210238 -256.127752) (xy 352.161063 -256.125771)
			(xy 352.112844 -256.115927) (xy 352.066828 -256.098475) (xy 352.024207 -256.073868) (xy 351.986086 -256.042743)
			(xy 351.953451 -256.005906) (xy 351.927148 -255.96431) (xy 351.907857 -255.919034) (xy 351.89608 -255.87125)
			(xy 351.89212 -255.822196) (xy 349.686331 -255.822196) (xy 349.686372 -255.824228) (xy 349.685877 -255.848835)
			(xy 349.677982 -255.897412) (xy 349.662398 -255.944093) (xy 349.639527 -255.98767) (xy 349.609962 -256.027014)
			(xy 349.574469 -256.061106) (xy 349.533966 -256.089062) (xy 349.489504 -256.11016) (xy 349.442233 -256.123852)
			(xy 349.393378 -256.129784) (xy 349.344203 -256.127803) (xy 349.295984 -256.117959) (xy 349.249968 -256.100507)
			(xy 349.207347 -256.0759) (xy 349.169226 -256.044775) (xy 349.136591 -256.007938) (xy 349.110288 -255.966342)
			(xy 349.090997 -255.921066) (xy 349.07922 -255.873282) (xy 349.07526 -255.824228) (xy 348.746789 -255.824228)
			(xy 348.742959 -255.872465) (xy 348.73157 -255.919504) (xy 348.712905 -255.964159) (xy 348.687434 -256.005312)
			(xy 348.655792 -256.041935) (xy 348.637606 -256.057908) (xy 348.629224 -256.06502) (xy 348.615 -256.093722)
			(xy 348.612619 -256.099) (xy 348.610043 -256.110286) (xy 348.60992 -256.116074) (xy 348.60992 -256.27965)
			(xy 348.610302 -256.288503) (xy 348.616318 -256.305156) (xy 348.627622 -256.318785) (xy 348.635066 -256.323592)
			(xy 348.722696 -256.374646) (xy 348.74962 -256.3749) (xy 348.761304 -256.368296) (xy 348.78433 -256.355938)
			(xy 348.833552 -256.338399) (xy 348.885038 -256.329471) (xy 348.911164 -256.328926) (xy 348.936421 -256.329416)
			(xy 348.986246 -256.337725) (xy 349.034025 -256.354122) (xy 349.078452 -256.37816) (xy 349.118316 -256.409184)
			(xy 349.15253 -256.446346) (xy 349.180161 -256.488633) (xy 349.200453 -256.534891) (xy 349.212854 -256.583859)
			(xy 349.216903 -256.63271) (xy 350.484706 -256.63271) (xy 350.488666 -256.583656) (xy 350.500443 -256.535872)
			(xy 350.519734 -256.490596) (xy 350.546037 -256.449) (xy 350.578672 -256.412163) (xy 350.616793 -256.381038)
			(xy 350.659414 -256.356431) (xy 350.70543 -256.338979) (xy 350.753649 -256.329135) (xy 350.802824 -256.327154)
			(xy 350.851679 -256.333086) (xy 350.89895 -256.346778) (xy 350.943412 -256.367876) (xy 350.983915 -256.395832)
			(xy 351.019408 -256.429924) (xy 351.048973 -256.469268) (xy 351.054635 -256.480056) (xy 353.086927 -256.480056)
			(xy 353.090957 -256.427558) (xy 353.102954 -256.37629) (xy 353.122637 -256.327455) (xy 353.149543 -256.282196)
			(xy 353.183043 -256.241575) (xy 353.222351 -256.206544) (xy 353.266546 -256.177924) (xy 353.314591 -256.156385)
			(xy 353.365362 -256.142433) (xy 353.417667 -256.136395) (xy 353.470281 -256.138412) (xy 353.521971 -256.148436)
			(xy 353.571524 -256.166234) (xy 353.61778 -256.191387) (xy 353.659654 -256.223306) (xy 353.696166 -256.261244)
			(xy 353.726458 -256.30431) (xy 353.749821 -256.351495) (xy 353.765707 -256.401694) (xy 353.773744 -256.45373)
			(xy 353.774248 -256.480056) (xy 354.001327 -256.480056) (xy 354.005357 -256.427558) (xy 354.017354 -256.37629)
			(xy 354.037037 -256.327455) (xy 354.063943 -256.282196) (xy 354.097443 -256.241575) (xy 354.136751 -256.206544)
			(xy 354.180946 -256.177924) (xy 354.228991 -256.156385) (xy 354.279762 -256.142433) (xy 354.332067 -256.136395)
			(xy 354.384681 -256.138412) (xy 354.436371 -256.148436) (xy 354.485924 -256.166234) (xy 354.53218 -256.191387)
			(xy 354.574054 -256.223306) (xy 354.610566 -256.261244) (xy 354.640858 -256.30431) (xy 354.664221 -256.351495)
			(xy 354.675566 -256.387346) (xy 355.244149 -256.387346) (xy 355.248179 -256.334848) (xy 355.260176 -256.28358)
			(xy 355.279859 -256.234745) (xy 355.306765 -256.189486) (xy 355.340265 -256.148865) (xy 355.379573 -256.113834)
			(xy 355.423768 -256.085214) (xy 355.471813 -256.063675) (xy 355.522584 -256.049723) (xy 355.574889 -256.043685)
			(xy 355.627503 -256.045702) (xy 355.679193 -256.055726) (xy 355.728746 -256.073524) (xy 355.775002 -256.098677)
			(xy 355.816876 -256.130596) (xy 355.853388 -256.168534) (xy 355.88368 -256.2116) (xy 355.907043 -256.258785)
			(xy 355.922929 -256.308984) (xy 355.930966 -256.36102) (xy 355.93147 -256.387346) (xy 356.194109 -256.387346)
			(xy 356.198139 -256.334848) (xy 356.210136 -256.28358) (xy 356.229819 -256.234745) (xy 356.256725 -256.189486)
			(xy 356.290225 -256.148865) (xy 356.329533 -256.113834) (xy 356.373728 -256.085214) (xy 356.421773 -256.063675)
			(xy 356.472544 -256.049723) (xy 356.524849 -256.043685) (xy 356.577463 -256.045702) (xy 356.629153 -256.055726)
			(xy 356.678706 -256.073524) (xy 356.724962 -256.098677) (xy 356.766836 -256.130596) (xy 356.803348 -256.168534)
			(xy 356.83364 -256.2116) (xy 356.857003 -256.258785) (xy 356.872889 -256.308984) (xy 356.880926 -256.36102)
			(xy 356.88143 -256.387346) (xy 357.144069 -256.387346) (xy 357.148099 -256.334848) (xy 357.160096 -256.28358)
			(xy 357.179779 -256.234745) (xy 357.206685 -256.189486) (xy 357.240185 -256.148865) (xy 357.279493 -256.113834)
			(xy 357.323688 -256.085214) (xy 357.371733 -256.063675) (xy 357.422504 -256.049723) (xy 357.474809 -256.043685)
			(xy 357.527423 -256.045702) (xy 357.579113 -256.055726) (xy 357.628666 -256.073524) (xy 357.674922 -256.098677)
			(xy 357.716796 -256.130596) (xy 357.753308 -256.168534) (xy 357.7836 -256.2116) (xy 357.806963 -256.258785)
			(xy 357.822849 -256.308984) (xy 357.830886 -256.36102) (xy 357.83139 -256.387346) (xy 358.094029 -256.387346)
			(xy 358.098059 -256.334848) (xy 358.110056 -256.28358) (xy 358.129739 -256.234745) (xy 358.156645 -256.189486)
			(xy 358.190145 -256.148865) (xy 358.229453 -256.113834) (xy 358.273648 -256.085214) (xy 358.321693 -256.063675)
			(xy 358.372464 -256.049723) (xy 358.424769 -256.043685) (xy 358.477383 -256.045702) (xy 358.529073 -256.055726)
			(xy 358.578626 -256.073524) (xy 358.624882 -256.098677) (xy 358.666756 -256.130596) (xy 358.703268 -256.168534)
			(xy 358.73356 -256.2116) (xy 358.756923 -256.258785) (xy 358.772809 -256.308984) (xy 358.780846 -256.36102)
			(xy 358.78135 -256.387346) (xy 359.043989 -256.387346) (xy 359.048019 -256.334848) (xy 359.060016 -256.28358)
			(xy 359.079699 -256.234745) (xy 359.106605 -256.189486) (xy 359.140105 -256.148865) (xy 359.179413 -256.113834)
			(xy 359.223608 -256.085214) (xy 359.271653 -256.063675) (xy 359.322424 -256.049723) (xy 359.374729 -256.043685)
			(xy 359.427343 -256.045702) (xy 359.479033 -256.055726) (xy 359.528586 -256.073524) (xy 359.574842 -256.098677)
			(xy 359.616716 -256.130596) (xy 359.653228 -256.168534) (xy 359.68352 -256.2116) (xy 359.706883 -256.258785)
			(xy 359.722769 -256.308984) (xy 359.730806 -256.36102) (xy 359.73131 -256.387346) (xy 359.993949 -256.387346)
			(xy 359.997979 -256.334848) (xy 360.009976 -256.28358) (xy 360.029659 -256.234745) (xy 360.056565 -256.189486)
			(xy 360.090065 -256.148865) (xy 360.129373 -256.113834) (xy 360.173568 -256.085214) (xy 360.221613 -256.063675)
			(xy 360.272384 -256.049723) (xy 360.324689 -256.043685) (xy 360.377303 -256.045702) (xy 360.428993 -256.055726)
			(xy 360.478546 -256.073524) (xy 360.524802 -256.098677) (xy 360.566676 -256.130596) (xy 360.603188 -256.168534)
			(xy 360.63348 -256.2116) (xy 360.656843 -256.258785) (xy 360.672729 -256.308984) (xy 360.680766 -256.36102)
			(xy 360.68127 -256.387346) (xy 360.944163 -256.387346) (xy 360.948193 -256.334848) (xy 360.96019 -256.28358)
			(xy 360.979873 -256.234745) (xy 361.006779 -256.189486) (xy 361.040279 -256.148865) (xy 361.079587 -256.113834)
			(xy 361.123782 -256.085214) (xy 361.171827 -256.063675) (xy 361.222598 -256.049723) (xy 361.274903 -256.043685)
			(xy 361.327517 -256.045702) (xy 361.379207 -256.055726) (xy 361.42876 -256.073524) (xy 361.475016 -256.098677)
			(xy 361.51689 -256.130596) (xy 361.553402 -256.168534) (xy 361.583694 -256.2116) (xy 361.607057 -256.258785)
			(xy 361.622943 -256.308984) (xy 361.63098 -256.36102) (xy 361.631484 -256.387346) (xy 361.894123 -256.387346)
			(xy 361.898153 -256.334848) (xy 361.91015 -256.28358) (xy 361.929833 -256.234745) (xy 361.956739 -256.189486)
			(xy 361.990239 -256.148865) (xy 362.029547 -256.113834) (xy 362.073742 -256.085214) (xy 362.121787 -256.063675)
			(xy 362.172558 -256.049723) (xy 362.224863 -256.043685) (xy 362.277477 -256.045702) (xy 362.329167 -256.055726)
			(xy 362.37872 -256.073524) (xy 362.424976 -256.098677) (xy 362.46685 -256.130596) (xy 362.503362 -256.168534)
			(xy 362.533654 -256.2116) (xy 362.557017 -256.258785) (xy 362.572903 -256.308984) (xy 362.58094 -256.36102)
			(xy 362.581444 -256.387346) (xy 362.844083 -256.387346) (xy 362.848113 -256.334848) (xy 362.86011 -256.28358)
			(xy 362.879793 -256.234745) (xy 362.906699 -256.189486) (xy 362.940199 -256.148865) (xy 362.979507 -256.113834)
			(xy 363.023702 -256.085214) (xy 363.071747 -256.063675) (xy 363.122518 -256.049723) (xy 363.174823 -256.043685)
			(xy 363.227437 -256.045702) (xy 363.279127 -256.055726) (xy 363.32868 -256.073524) (xy 363.374936 -256.098677)
			(xy 363.41681 -256.130596) (xy 363.453322 -256.168534) (xy 363.483614 -256.2116) (xy 363.506977 -256.258785)
			(xy 363.522863 -256.308984) (xy 363.5309 -256.36102) (xy 363.531404 -256.387346) (xy 363.794043 -256.387346)
			(xy 363.798073 -256.334848) (xy 363.81007 -256.28358) (xy 363.829753 -256.234745) (xy 363.856659 -256.189486)
			(xy 363.890159 -256.148865) (xy 363.929467 -256.113834) (xy 363.973662 -256.085214) (xy 364.021707 -256.063675)
			(xy 364.072478 -256.049723) (xy 364.124783 -256.043685) (xy 364.177397 -256.045702) (xy 364.229087 -256.055726)
			(xy 364.27864 -256.073524) (xy 364.324896 -256.098677) (xy 364.36677 -256.130596) (xy 364.403282 -256.168534)
			(xy 364.433574 -256.2116) (xy 364.456937 -256.258785) (xy 364.472823 -256.308984) (xy 364.48086 -256.36102)
			(xy 364.481364 -256.387346) (xy 364.48086 -256.413672) (xy 364.472823 -256.465708) (xy 364.468282 -256.480056)
			(xy 365.036865 -256.480056) (xy 365.040895 -256.427558) (xy 365.052892 -256.37629) (xy 365.072575 -256.327455)
			(xy 365.099481 -256.282196) (xy 365.132981 -256.241575) (xy 365.172289 -256.206544) (xy 365.216484 -256.177924)
			(xy 365.264529 -256.156385) (xy 365.3153 -256.142433) (xy 365.367605 -256.136395) (xy 365.420219 -256.138412)
			(xy 365.471909 -256.148436) (xy 365.521462 -256.166234) (xy 365.567718 -256.191387) (xy 365.609592 -256.223306)
			(xy 365.646104 -256.261244) (xy 365.676396 -256.30431) (xy 365.699759 -256.351495) (xy 365.715645 -256.401694)
			(xy 365.723682 -256.45373) (xy 365.724186 -256.480056) (xy 365.723682 -256.506382) (xy 365.715645 -256.558418)
			(xy 365.699759 -256.608617) (xy 365.687075 -256.634234) (xy 370.218982 -256.634234) (xy 370.222942 -256.58518)
			(xy 370.234719 -256.537396) (xy 370.25401 -256.49212) (xy 370.280313 -256.450524) (xy 370.312948 -256.413687)
			(xy 370.351069 -256.382562) (xy 370.39369 -256.357955) (xy 370.439706 -256.340503) (xy 370.487925 -256.330659)
			(xy 370.5371 -256.328678) (xy 370.585955 -256.33461) (xy 370.633226 -256.348302) (xy 370.677688 -256.3694)
			(xy 370.718191 -256.397356) (xy 370.753684 -256.431448) (xy 370.783249 -256.470792) (xy 370.80612 -256.514369)
			(xy 370.821704 -256.56105) (xy 370.829599 -256.609627) (xy 370.830094 -256.634234) (xy 372.09909 -256.634234)
			(xy 372.10305 -256.58518) (xy 372.114827 -256.537396) (xy 372.134118 -256.49212) (xy 372.160421 -256.450524)
			(xy 372.193056 -256.413687) (xy 372.231177 -256.382562) (xy 372.273798 -256.357955) (xy 372.319814 -256.340503)
			(xy 372.368033 -256.330659) (xy 372.417208 -256.328678) (xy 372.466063 -256.33461) (xy 372.513334 -256.348302)
			(xy 372.557796 -256.3694) (xy 372.598299 -256.397356) (xy 372.633792 -256.431448) (xy 372.663357 -256.470792)
			(xy 372.686228 -256.514369) (xy 372.701812 -256.56105) (xy 372.709707 -256.609627) (xy 372.710202 -256.634234)
			(xy 373.978944 -256.634234) (xy 373.982904 -256.58518) (xy 373.994681 -256.537396) (xy 374.013972 -256.49212)
			(xy 374.040275 -256.450524) (xy 374.07291 -256.413687) (xy 374.111031 -256.382562) (xy 374.153652 -256.357955)
			(xy 374.199668 -256.340503) (xy 374.247887 -256.330659) (xy 374.297062 -256.328678) (xy 374.345917 -256.33461)
			(xy 374.393188 -256.348302) (xy 374.43765 -256.3694) (xy 374.478153 -256.397356) (xy 374.513646 -256.431448)
			(xy 374.543211 -256.470792) (xy 374.566082 -256.514369) (xy 374.581666 -256.56105) (xy 374.589561 -256.609627)
			(xy 374.590056 -256.634234) (xy 375.859052 -256.634234) (xy 375.863012 -256.58518) (xy 375.874789 -256.537396)
			(xy 375.89408 -256.49212) (xy 375.920383 -256.450524) (xy 375.953018 -256.413687) (xy 375.991139 -256.382562)
			(xy 376.03376 -256.357955) (xy 376.079776 -256.340503) (xy 376.127995 -256.330659) (xy 376.17717 -256.328678)
			(xy 376.226025 -256.33461) (xy 376.273296 -256.348302) (xy 376.317758 -256.3694) (xy 376.358261 -256.397356)
			(xy 376.393754 -256.431448) (xy 376.423319 -256.470792) (xy 376.44619 -256.514369) (xy 376.461774 -256.56105)
			(xy 376.469669 -256.609627) (xy 376.470164 -256.634234) (xy 376.788675 -256.634234) (xy 376.79277 -256.583506)
			(xy 376.804949 -256.534092) (xy 376.824897 -256.487272) (xy 376.852098 -256.444258) (xy 376.885846 -256.406164)
			(xy 376.925268 -256.373977) (xy 376.969342 -256.348531) (xy 377.016928 -256.330484) (xy 377.066792 -256.320304)
			(xy 377.117644 -256.318255) (xy 377.168165 -256.324389) (xy 377.217049 -256.338549) (xy 377.263028 -256.360366)
			(xy 377.304912 -256.389276) (xy 377.341616 -256.424531) (xy 377.372189 -256.465217) (xy 377.39584 -256.51028)
			(xy 377.411956 -256.558554) (xy 377.42012 -256.608788) (xy 377.420632 -256.634234) (xy 378.67896 -256.634234)
			(xy 378.68292 -256.58518) (xy 378.694697 -256.537396) (xy 378.713988 -256.49212) (xy 378.740291 -256.450524)
			(xy 378.772926 -256.413687) (xy 378.811047 -256.382562) (xy 378.853668 -256.357955) (xy 378.899684 -256.340503)
			(xy 378.947903 -256.330659) (xy 378.997078 -256.328678) (xy 379.045933 -256.33461) (xy 379.093204 -256.348302)
			(xy 379.137666 -256.3694) (xy 379.178169 -256.397356) (xy 379.213662 -256.431448) (xy 379.243227 -256.470792)
			(xy 379.266098 -256.514369) (xy 379.281682 -256.56105) (xy 379.289577 -256.609627) (xy 379.290072 -256.634234)
			(xy 379.619014 -256.634234) (xy 379.622974 -256.58518) (xy 379.634751 -256.537396) (xy 379.654042 -256.49212)
			(xy 379.680345 -256.450524) (xy 379.71298 -256.413687) (xy 379.751101 -256.382562) (xy 379.793722 -256.357955)
			(xy 379.839738 -256.340503) (xy 379.887957 -256.330659) (xy 379.937132 -256.328678) (xy 379.985987 -256.33461)
			(xy 380.033258 -256.348302) (xy 380.07772 -256.3694) (xy 380.118223 -256.397356) (xy 380.153716 -256.431448)
			(xy 380.183281 -256.470792) (xy 380.206152 -256.514369) (xy 380.221736 -256.56105) (xy 380.229631 -256.609627)
			(xy 380.230126 -256.634234) (xy 380.548637 -256.634234) (xy 380.552732 -256.583506) (xy 380.564911 -256.534092)
			(xy 380.584859 -256.487272) (xy 380.61206 -256.444258) (xy 380.645808 -256.406164) (xy 380.68523 -256.373977)
			(xy 380.729304 -256.348531) (xy 380.77689 -256.330484) (xy 380.826754 -256.320304) (xy 380.877606 -256.318255)
			(xy 380.928127 -256.324389) (xy 380.977011 -256.338549) (xy 381.02299 -256.360366) (xy 381.064874 -256.389276)
			(xy 381.101578 -256.424531) (xy 381.132151 -256.465217) (xy 381.155802 -256.51028) (xy 381.171918 -256.558554)
			(xy 381.180082 -256.608788) (xy 381.180594 -256.634234) (xy 381.180082 -256.65968) (xy 381.171918 -256.709914)
			(xy 381.155802 -256.758188) (xy 381.132151 -256.803251) (xy 381.101578 -256.843937) (xy 381.064874 -256.879192)
			(xy 381.02299 -256.908102) (xy 380.977011 -256.929919) (xy 380.928127 -256.944079) (xy 380.877606 -256.950213)
			(xy 380.826754 -256.948164) (xy 380.77689 -256.937984) (xy 380.729304 -256.919937) (xy 380.68523 -256.894491)
			(xy 380.645808 -256.862304) (xy 380.61206 -256.82421) (xy 380.584859 -256.781196) (xy 380.564911 -256.734376)
			(xy 380.552732 -256.684962) (xy 380.548637 -256.634234) (xy 380.230126 -256.634234) (xy 380.229631 -256.658841)
			(xy 380.221736 -256.707418) (xy 380.206152 -256.754099) (xy 380.183281 -256.797676) (xy 380.153716 -256.83702)
			(xy 380.118223 -256.871112) (xy 380.07772 -256.899068) (xy 380.033258 -256.920166) (xy 379.985987 -256.933858)
			(xy 379.937132 -256.93979) (xy 379.887957 -256.937809) (xy 379.839738 -256.927965) (xy 379.793722 -256.910513)
			(xy 379.751101 -256.885906) (xy 379.71298 -256.854781) (xy 379.680345 -256.817944) (xy 379.654042 -256.776348)
			(xy 379.634751 -256.731072) (xy 379.622974 -256.683288) (xy 379.619014 -256.634234) (xy 379.290072 -256.634234)
			(xy 379.289577 -256.658841) (xy 379.281682 -256.707418) (xy 379.266098 -256.754099) (xy 379.243227 -256.797676)
			(xy 379.213662 -256.83702) (xy 379.178169 -256.871112) (xy 379.137666 -256.899068) (xy 379.093204 -256.920166)
			(xy 379.045933 -256.933858) (xy 378.997078 -256.93979) (xy 378.947903 -256.937809) (xy 378.899684 -256.927965)
			(xy 378.853668 -256.910513) (xy 378.811047 -256.885906) (xy 378.772926 -256.854781) (xy 378.740291 -256.817944)
			(xy 378.713988 -256.776348) (xy 378.694697 -256.731072) (xy 378.68292 -256.683288) (xy 378.67896 -256.634234)
			(xy 377.420632 -256.634234) (xy 377.42012 -256.65968) (xy 377.411956 -256.709914) (xy 377.39584 -256.758188)
			(xy 377.372189 -256.803251) (xy 377.341616 -256.843937) (xy 377.304912 -256.879192) (xy 377.263028 -256.908102)
			(xy 377.217049 -256.929919) (xy 377.168165 -256.944079) (xy 377.117644 -256.950213) (xy 377.066792 -256.948164)
			(xy 377.016928 -256.937984) (xy 376.969342 -256.919937) (xy 376.925268 -256.894491) (xy 376.885846 -256.862304)
			(xy 376.852098 -256.82421) (xy 376.824897 -256.781196) (xy 376.804949 -256.734376) (xy 376.79277 -256.684962)
			(xy 376.788675 -256.634234) (xy 376.470164 -256.634234) (xy 376.469669 -256.658841) (xy 376.461774 -256.707418)
			(xy 376.44619 -256.754099) (xy 376.423319 -256.797676) (xy 376.393754 -256.83702) (xy 376.358261 -256.871112)
			(xy 376.317758 -256.899068) (xy 376.273296 -256.920166) (xy 376.226025 -256.933858) (xy 376.17717 -256.93979)
			(xy 376.127995 -256.937809) (xy 376.079776 -256.927965) (xy 376.03376 -256.910513) (xy 375.991139 -256.885906)
			(xy 375.953018 -256.854781) (xy 375.920383 -256.817944) (xy 375.89408 -256.776348) (xy 375.874789 -256.731072)
			(xy 375.863012 -256.683288) (xy 375.859052 -256.634234) (xy 374.590056 -256.634234) (xy 374.589561 -256.658841)
			(xy 374.581666 -256.707418) (xy 374.566082 -256.754099) (xy 374.543211 -256.797676) (xy 374.513646 -256.83702)
			(xy 374.478153 -256.871112) (xy 374.43765 -256.899068) (xy 374.393188 -256.920166) (xy 374.345917 -256.933858)
			(xy 374.297062 -256.93979) (xy 374.247887 -256.937809) (xy 374.199668 -256.927965) (xy 374.153652 -256.910513)
			(xy 374.111031 -256.885906) (xy 374.07291 -256.854781) (xy 374.040275 -256.817944) (xy 374.013972 -256.776348)
			(xy 373.994681 -256.731072) (xy 373.982904 -256.683288) (xy 373.978944 -256.634234) (xy 372.710202 -256.634234)
			(xy 372.709707 -256.658841) (xy 372.701812 -256.707418) (xy 372.686228 -256.754099) (xy 372.663357 -256.797676)
			(xy 372.633792 -256.83702) (xy 372.598299 -256.871112) (xy 372.557796 -256.899068) (xy 372.513334 -256.920166)
			(xy 372.466063 -256.933858) (xy 372.417208 -256.93979) (xy 372.368033 -256.937809) (xy 372.319814 -256.927965)
			(xy 372.273798 -256.910513) (xy 372.231177 -256.885906) (xy 372.193056 -256.854781) (xy 372.160421 -256.817944)
			(xy 372.134118 -256.776348) (xy 372.114827 -256.731072) (xy 372.10305 -256.683288) (xy 372.09909 -256.634234)
			(xy 370.830094 -256.634234) (xy 370.829599 -256.658841) (xy 370.821704 -256.707418) (xy 370.80612 -256.754099)
			(xy 370.783249 -256.797676) (xy 370.753684 -256.83702) (xy 370.718191 -256.871112) (xy 370.677688 -256.899068)
			(xy 370.633226 -256.920166) (xy 370.585955 -256.933858) (xy 370.5371 -256.93979) (xy 370.487925 -256.937809)
			(xy 370.439706 -256.927965) (xy 370.39369 -256.910513) (xy 370.351069 -256.885906) (xy 370.312948 -256.854781)
			(xy 370.280313 -256.817944) (xy 370.25401 -256.776348) (xy 370.234719 -256.731072) (xy 370.222942 -256.683288)
			(xy 370.218982 -256.634234) (xy 365.687075 -256.634234) (xy 365.676396 -256.655802) (xy 365.646104 -256.698868)
			(xy 365.609592 -256.736806) (xy 365.567718 -256.768725) (xy 365.521462 -256.793878) (xy 365.471909 -256.811676)
			(xy 365.420219 -256.8217) (xy 365.367605 -256.823717) (xy 365.3153 -256.817679) (xy 365.264529 -256.803727)
			(xy 365.216484 -256.782188) (xy 365.172289 -256.753568) (xy 365.132981 -256.718537) (xy 365.099481 -256.677916)
			(xy 365.072575 -256.632657) (xy 365.052892 -256.583822) (xy 365.040895 -256.532554) (xy 365.036865 -256.480056)
			(xy 364.468282 -256.480056) (xy 364.456937 -256.515907) (xy 364.433574 -256.563092) (xy 364.403282 -256.606158)
			(xy 364.36677 -256.644096) (xy 364.324896 -256.676015) (xy 364.27864 -256.701168) (xy 364.229087 -256.718966)
			(xy 364.177397 -256.72899) (xy 364.124783 -256.731007) (xy 364.072478 -256.724969) (xy 364.021707 -256.711017)
			(xy 363.973662 -256.689478) (xy 363.929467 -256.660858) (xy 363.890159 -256.625827) (xy 363.856659 -256.585206)
			(xy 363.829753 -256.539947) (xy 363.81007 -256.491112) (xy 363.798073 -256.439844) (xy 363.794043 -256.387346)
			(xy 363.531404 -256.387346) (xy 363.5309 -256.413672) (xy 363.522863 -256.465708) (xy 363.506977 -256.515907)
			(xy 363.483614 -256.563092) (xy 363.453322 -256.606158) (xy 363.41681 -256.644096) (xy 363.374936 -256.676015)
			(xy 363.32868 -256.701168) (xy 363.279127 -256.718966) (xy 363.227437 -256.72899) (xy 363.174823 -256.731007)
			(xy 363.122518 -256.724969) (xy 363.071747 -256.711017) (xy 363.023702 -256.689478) (xy 362.979507 -256.660858)
			(xy 362.940199 -256.625827) (xy 362.906699 -256.585206) (xy 362.879793 -256.539947) (xy 362.86011 -256.491112)
			(xy 362.848113 -256.439844) (xy 362.844083 -256.387346) (xy 362.581444 -256.387346) (xy 362.58094 -256.413672)
			(xy 362.572903 -256.465708) (xy 362.557017 -256.515907) (xy 362.533654 -256.563092) (xy 362.503362 -256.606158)
			(xy 362.46685 -256.644096) (xy 362.424976 -256.676015) (xy 362.37872 -256.701168) (xy 362.329167 -256.718966)
			(xy 362.277477 -256.72899) (xy 362.224863 -256.731007) (xy 362.172558 -256.724969) (xy 362.121787 -256.711017)
			(xy 362.073742 -256.689478) (xy 362.029547 -256.660858) (xy 361.990239 -256.625827) (xy 361.956739 -256.585206)
			(xy 361.929833 -256.539947) (xy 361.91015 -256.491112) (xy 361.898153 -256.439844) (xy 361.894123 -256.387346)
			(xy 361.631484 -256.387346) (xy 361.63098 -256.413672) (xy 361.622943 -256.465708) (xy 361.607057 -256.515907)
			(xy 361.583694 -256.563092) (xy 361.553402 -256.606158) (xy 361.51689 -256.644096) (xy 361.475016 -256.676015)
			(xy 361.42876 -256.701168) (xy 361.379207 -256.718966) (xy 361.327517 -256.72899) (xy 361.274903 -256.731007)
			(xy 361.222598 -256.724969) (xy 361.171827 -256.711017) (xy 361.123782 -256.689478) (xy 361.079587 -256.660858)
			(xy 361.040279 -256.625827) (xy 361.006779 -256.585206) (xy 360.979873 -256.539947) (xy 360.96019 -256.491112)
			(xy 360.948193 -256.439844) (xy 360.944163 -256.387346) (xy 360.68127 -256.387346) (xy 360.680766 -256.413672)
			(xy 360.672729 -256.465708) (xy 360.656843 -256.515907) (xy 360.63348 -256.563092) (xy 360.603188 -256.606158)
			(xy 360.566676 -256.644096) (xy 360.524802 -256.676015) (xy 360.478546 -256.701168) (xy 360.428993 -256.718966)
			(xy 360.377303 -256.72899) (xy 360.324689 -256.731007) (xy 360.272384 -256.724969) (xy 360.221613 -256.711017)
			(xy 360.173568 -256.689478) (xy 360.129373 -256.660858) (xy 360.090065 -256.625827) (xy 360.056565 -256.585206)
			(xy 360.029659 -256.539947) (xy 360.009976 -256.491112) (xy 359.997979 -256.439844) (xy 359.993949 -256.387346)
			(xy 359.73131 -256.387346) (xy 359.730806 -256.413672) (xy 359.722769 -256.465708) (xy 359.706883 -256.515907)
			(xy 359.68352 -256.563092) (xy 359.653228 -256.606158) (xy 359.616716 -256.644096) (xy 359.574842 -256.676015)
			(xy 359.528586 -256.701168) (xy 359.479033 -256.718966) (xy 359.427343 -256.72899) (xy 359.374729 -256.731007)
			(xy 359.322424 -256.724969) (xy 359.271653 -256.711017) (xy 359.223608 -256.689478) (xy 359.179413 -256.660858)
			(xy 359.140105 -256.625827) (xy 359.106605 -256.585206) (xy 359.079699 -256.539947) (xy 359.060016 -256.491112)
			(xy 359.048019 -256.439844) (xy 359.043989 -256.387346) (xy 358.78135 -256.387346) (xy 358.780846 -256.413672)
			(xy 358.772809 -256.465708) (xy 358.756923 -256.515907) (xy 358.73356 -256.563092) (xy 358.703268 -256.606158)
			(xy 358.666756 -256.644096) (xy 358.624882 -256.676015) (xy 358.578626 -256.701168) (xy 358.529073 -256.718966)
			(xy 358.477383 -256.72899) (xy 358.424769 -256.731007) (xy 358.372464 -256.724969) (xy 358.321693 -256.711017)
			(xy 358.273648 -256.689478) (xy 358.229453 -256.660858) (xy 358.190145 -256.625827) (xy 358.156645 -256.585206)
			(xy 358.129739 -256.539947) (xy 358.110056 -256.491112) (xy 358.098059 -256.439844) (xy 358.094029 -256.387346)
			(xy 357.83139 -256.387346) (xy 357.830886 -256.413672) (xy 357.822849 -256.465708) (xy 357.806963 -256.515907)
			(xy 357.7836 -256.563092) (xy 357.753308 -256.606158) (xy 357.716796 -256.644096) (xy 357.674922 -256.676015)
			(xy 357.628666 -256.701168) (xy 357.579113 -256.718966) (xy 357.527423 -256.72899) (xy 357.474809 -256.731007)
			(xy 357.422504 -256.724969) (xy 357.371733 -256.711017) (xy 357.323688 -256.689478) (xy 357.279493 -256.660858)
			(xy 357.240185 -256.625827) (xy 357.206685 -256.585206) (xy 357.179779 -256.539947) (xy 357.160096 -256.491112)
			(xy 357.148099 -256.439844) (xy 357.144069 -256.387346) (xy 356.88143 -256.387346) (xy 356.880926 -256.413672)
			(xy 356.872889 -256.465708) (xy 356.857003 -256.515907) (xy 356.83364 -256.563092) (xy 356.803348 -256.606158)
			(xy 356.766836 -256.644096) (xy 356.724962 -256.676015) (xy 356.678706 -256.701168) (xy 356.629153 -256.718966)
			(xy 356.577463 -256.72899) (xy 356.524849 -256.731007) (xy 356.472544 -256.724969) (xy 356.421773 -256.711017)
			(xy 356.373728 -256.689478) (xy 356.329533 -256.660858) (xy 356.290225 -256.625827) (xy 356.256725 -256.585206)
			(xy 356.229819 -256.539947) (xy 356.210136 -256.491112) (xy 356.198139 -256.439844) (xy 356.194109 -256.387346)
			(xy 355.93147 -256.387346) (xy 355.930966 -256.413672) (xy 355.922929 -256.465708) (xy 355.907043 -256.515907)
			(xy 355.88368 -256.563092) (xy 355.853388 -256.606158) (xy 355.816876 -256.644096) (xy 355.775002 -256.676015)
			(xy 355.728746 -256.701168) (xy 355.679193 -256.718966) (xy 355.627503 -256.72899) (xy 355.574889 -256.731007)
			(xy 355.522584 -256.724969) (xy 355.471813 -256.711017) (xy 355.423768 -256.689478) (xy 355.379573 -256.660858)
			(xy 355.340265 -256.625827) (xy 355.306765 -256.585206) (xy 355.279859 -256.539947) (xy 355.260176 -256.491112)
			(xy 355.248179 -256.439844) (xy 355.244149 -256.387346) (xy 354.675566 -256.387346) (xy 354.680107 -256.401694)
			(xy 354.688144 -256.45373) (xy 354.688648 -256.480056) (xy 354.688144 -256.506382) (xy 354.680107 -256.558418)
			(xy 354.664221 -256.608617) (xy 354.640858 -256.655802) (xy 354.610566 -256.698868) (xy 354.574054 -256.736806)
			(xy 354.53218 -256.768725) (xy 354.485924 -256.793878) (xy 354.436371 -256.811676) (xy 354.384681 -256.8217)
			(xy 354.332067 -256.823717) (xy 354.279762 -256.817679) (xy 354.228991 -256.803727) (xy 354.180946 -256.782188)
			(xy 354.136751 -256.753568) (xy 354.097443 -256.718537) (xy 354.063943 -256.677916) (xy 354.037037 -256.632657)
			(xy 354.017354 -256.583822) (xy 354.005357 -256.532554) (xy 354.001327 -256.480056) (xy 353.774248 -256.480056)
			(xy 353.773744 -256.506382) (xy 353.765707 -256.558418) (xy 353.749821 -256.608617) (xy 353.726458 -256.655802)
			(xy 353.696166 -256.698868) (xy 353.659654 -256.736806) (xy 353.61778 -256.768725) (xy 353.571524 -256.793878)
			(xy 353.521971 -256.811676) (xy 353.470281 -256.8217) (xy 353.417667 -256.823717) (xy 353.365362 -256.817679)
			(xy 353.314591 -256.803727) (xy 353.266546 -256.782188) (xy 353.222351 -256.753568) (xy 353.183043 -256.718537)
			(xy 353.149543 -256.677916) (xy 353.122637 -256.632657) (xy 353.102954 -256.583822) (xy 353.090957 -256.532554)
			(xy 353.086927 -256.480056) (xy 351.054635 -256.480056) (xy 351.071844 -256.512845) (xy 351.087428 -256.559526)
			(xy 351.095323 -256.608103) (xy 351.095818 -256.63271) (xy 351.095323 -256.657317) (xy 351.087428 -256.705894)
			(xy 351.071844 -256.752575) (xy 351.048973 -256.796152) (xy 351.019408 -256.835496) (xy 350.983915 -256.869588)
			(xy 350.943412 -256.897544) (xy 350.89895 -256.918642) (xy 350.851679 -256.932334) (xy 350.802824 -256.938266)
			(xy 350.753649 -256.936285) (xy 350.70543 -256.926441) (xy 350.659414 -256.908989) (xy 350.616793 -256.884382)
			(xy 350.578672 -256.853257) (xy 350.546037 -256.81642) (xy 350.519734 -256.774824) (xy 350.500443 -256.729548)
			(xy 350.488666 -256.681764) (xy 350.484706 -256.63271) (xy 349.216903 -256.63271) (xy 349.217026 -256.6342)
			(xy 349.212854 -256.684541) (xy 349.200453 -256.733509) (xy 349.180161 -256.779767) (xy 349.15253 -256.822054)
			(xy 349.118316 -256.859216) (xy 349.078452 -256.89024) (xy 349.034025 -256.914278) (xy 348.986246 -256.930675)
			(xy 348.936421 -256.938984) (xy 348.911164 -256.939542) (xy 348.885036 -256.939008) (xy 348.833543 -256.930102)
			(xy 348.784326 -256.912541) (xy 348.761304 -256.900172) (xy 348.74962 -256.893568) (xy 348.722696 -256.893822)
			(xy 348.635066 -256.944876) (xy 348.62757 -256.949628) (xy 348.616218 -256.963257) (xy 348.610218 -256.979948)
			(xy 348.60992 -256.988818) (xy 348.60992 -257.430016) (xy 353.086927 -257.430016) (xy 353.090957 -257.377518)
			(xy 353.102954 -257.32625) (xy 353.122637 -257.277415) (xy 353.149543 -257.232156) (xy 353.183043 -257.191535)
			(xy 353.222351 -257.156504) (xy 353.266546 -257.127884) (xy 353.314591 -257.106345) (xy 353.365362 -257.092393)
			(xy 353.417667 -257.086355) (xy 353.470281 -257.088372) (xy 353.521971 -257.098396) (xy 353.571524 -257.116194)
			(xy 353.61778 -257.141347) (xy 353.659654 -257.173266) (xy 353.696166 -257.211204) (xy 353.726458 -257.25427)
			(xy 353.749821 -257.301455) (xy 353.765707 -257.351654) (xy 353.773744 -257.40369) (xy 353.774248 -257.430016)
			(xy 354.001327 -257.430016) (xy 354.005357 -257.377518) (xy 354.017354 -257.32625) (xy 354.037037 -257.277415)
			(xy 354.063943 -257.232156) (xy 354.097443 -257.191535) (xy 354.136751 -257.156504) (xy 354.180946 -257.127884)
			(xy 354.228991 -257.106345) (xy 354.279762 -257.092393) (xy 354.332067 -257.086355) (xy 354.384681 -257.088372)
			(xy 354.436371 -257.098396) (xy 354.485924 -257.116194) (xy 354.53218 -257.141347) (xy 354.574054 -257.173266)
			(xy 354.610566 -257.211204) (xy 354.640858 -257.25427) (xy 354.664221 -257.301455) (xy 354.680107 -257.351654)
			(xy 354.688144 -257.40369) (xy 354.688648 -257.430016) (xy 354.688144 -257.456342) (xy 354.680107 -257.508378)
			(xy 354.664221 -257.558577) (xy 354.640858 -257.605762) (xy 354.610566 -257.648828) (xy 354.574054 -257.686766)
			(xy 354.53218 -257.718685) (xy 354.485924 -257.743838) (xy 354.482756 -257.744976) (xy 355.513897 -257.744976)
			(xy 355.517927 -257.692478) (xy 355.529924 -257.64121) (xy 355.549607 -257.592375) (xy 355.576513 -257.547116)
			(xy 355.610013 -257.506495) (xy 355.649321 -257.471464) (xy 355.693516 -257.442844) (xy 355.741561 -257.421305)
			(xy 355.792332 -257.407353) (xy 355.844637 -257.401315) (xy 355.897251 -257.403332) (xy 355.948941 -257.413356)
			(xy 355.998494 -257.431154) (xy 356.04475 -257.456307) (xy 356.086624 -257.488226) (xy 356.123136 -257.526164)
			(xy 356.153428 -257.56923) (xy 356.176791 -257.616415) (xy 356.192677 -257.666614) (xy 356.200714 -257.71865)
			(xy 356.201218 -257.744976) (xy 356.428297 -257.744976) (xy 356.432327 -257.692478) (xy 356.444324 -257.64121)
			(xy 356.464007 -257.592375) (xy 356.490913 -257.547116) (xy 356.524413 -257.506495) (xy 356.563721 -257.471464)
			(xy 356.607916 -257.442844) (xy 356.655961 -257.421305) (xy 356.706732 -257.407353) (xy 356.759037 -257.401315)
			(xy 356.811651 -257.403332) (xy 356.863341 -257.413356) (xy 356.912894 -257.431154) (xy 356.95915 -257.456307)
			(xy 357.001024 -257.488226) (xy 357.037536 -257.526164) (xy 357.067828 -257.56923) (xy 357.091191 -257.616415)
			(xy 357.107077 -257.666614) (xy 357.115114 -257.71865) (xy 357.115618 -257.744976) (xy 358.928419 -257.744976)
			(xy 358.932449 -257.692478) (xy 358.944446 -257.64121) (xy 358.964129 -257.592375) (xy 358.991035 -257.547116)
			(xy 359.024535 -257.506495) (xy 359.063843 -257.471464) (xy 359.108038 -257.442844) (xy 359.156083 -257.421305)
			(xy 359.206854 -257.407353) (xy 359.259159 -257.401315) (xy 359.311773 -257.403332) (xy 359.363463 -257.413356)
			(xy 359.413016 -257.431154) (xy 359.459272 -257.456307) (xy 359.501146 -257.488226) (xy 359.537658 -257.526164)
			(xy 359.56795 -257.56923) (xy 359.591313 -257.616415) (xy 359.607199 -257.666614) (xy 359.615236 -257.71865)
			(xy 359.61574 -257.744976) (xy 361.178351 -257.744976) (xy 361.182381 -257.692478) (xy 361.194378 -257.64121)
			(xy 361.214061 -257.592375) (xy 361.240967 -257.547116) (xy 361.274467 -257.506495) (xy 361.313775 -257.471464)
			(xy 361.35797 -257.442844) (xy 361.406015 -257.421305) (xy 361.456786 -257.407353) (xy 361.509091 -257.401315)
			(xy 361.561705 -257.403332) (xy 361.613395 -257.413356) (xy 361.662948 -257.431154) (xy 361.709204 -257.456307)
			(xy 361.751078 -257.488226) (xy 361.78759 -257.526164) (xy 361.817882 -257.56923) (xy 361.841245 -257.616415)
			(xy 361.857131 -257.666614) (xy 361.865168 -257.71865) (xy 361.865672 -257.744976) (xy 363.778295 -257.744976)
			(xy 363.782325 -257.692478) (xy 363.794322 -257.64121) (xy 363.814005 -257.592375) (xy 363.840911 -257.547116)
			(xy 363.874411 -257.506495) (xy 363.913719 -257.471464) (xy 363.957914 -257.442844) (xy 364.005959 -257.421305)
			(xy 364.05673 -257.407353) (xy 364.109035 -257.401315) (xy 364.161649 -257.403332) (xy 364.213339 -257.413356)
			(xy 364.259724 -257.430016) (xy 365.036865 -257.430016) (xy 365.040895 -257.377518) (xy 365.052892 -257.32625)
			(xy 365.072575 -257.277415) (xy 365.099481 -257.232156) (xy 365.132981 -257.191535) (xy 365.172289 -257.156504)
			(xy 365.216484 -257.127884) (xy 365.264529 -257.106345) (xy 365.3153 -257.092393) (xy 365.367605 -257.086355)
			(xy 365.420219 -257.088372) (xy 365.471909 -257.098396) (xy 365.521462 -257.116194) (xy 365.567718 -257.141347)
			(xy 365.609592 -257.173266) (xy 365.646104 -257.211204) (xy 365.676396 -257.25427) (xy 365.699759 -257.301455)
			(xy 365.715645 -257.351654) (xy 365.723682 -257.40369) (xy 365.724186 -257.430016) (xy 365.723682 -257.456342)
			(xy 365.715645 -257.508378) (xy 365.699759 -257.558577) (xy 365.676396 -257.605762) (xy 365.646104 -257.648828)
			(xy 365.609592 -257.686766) (xy 365.567718 -257.718685) (xy 365.521462 -257.743838) (xy 365.471909 -257.761636)
			(xy 365.420219 -257.77166) (xy 365.367605 -257.773677) (xy 365.3153 -257.767639) (xy 365.264529 -257.753687)
			(xy 365.216484 -257.732148) (xy 365.172289 -257.703528) (xy 365.132981 -257.668497) (xy 365.099481 -257.627876)
			(xy 365.072575 -257.582617) (xy 365.052892 -257.533782) (xy 365.040895 -257.482514) (xy 365.036865 -257.430016)
			(xy 364.259724 -257.430016) (xy 364.262892 -257.431154) (xy 364.309148 -257.456307) (xy 364.351022 -257.488226)
			(xy 364.387534 -257.526164) (xy 364.417826 -257.56923) (xy 364.441189 -257.616415) (xy 364.457075 -257.666614)
			(xy 364.465112 -257.71865) (xy 364.465616 -257.744976) (xy 364.465112 -257.771302) (xy 364.457075 -257.823338)
			(xy 364.441189 -257.873537) (xy 364.417826 -257.920722) (xy 364.4112 -257.930142) (xy 368.805717 -257.930142)
			(xy 368.809747 -257.877644) (xy 368.821744 -257.826376) (xy 368.841427 -257.777541) (xy 368.868333 -257.732282)
			(xy 368.901833 -257.691661) (xy 368.941141 -257.65663) (xy 368.985336 -257.62801) (xy 369.033381 -257.606471)
			(xy 369.084152 -257.592519) (xy 369.136457 -257.586481) (xy 369.189071 -257.588498) (xy 369.240761 -257.598522)
			(xy 369.290314 -257.61632) (xy 369.33657 -257.641473) (xy 369.378444 -257.673392) (xy 369.414956 -257.71133)
			(xy 369.445248 -257.754396) (xy 369.468611 -257.801581) (xy 369.484497 -257.85178) (xy 369.492534 -257.903816)
			(xy 369.493038 -257.930142) (xy 370.731291 -257.930142) (xy 370.735321 -257.877644) (xy 370.747318 -257.826376)
			(xy 370.767001 -257.777541) (xy 370.793907 -257.732282) (xy 370.827407 -257.691661) (xy 370.866715 -257.65663)
			(xy 370.91091 -257.62801) (xy 370.958955 -257.606471) (xy 371.009726 -257.592519) (xy 371.062031 -257.586481)
			(xy 371.114645 -257.588498) (xy 371.166335 -257.598522) (xy 371.215888 -257.61632) (xy 371.262144 -257.641473)
			(xy 371.304018 -257.673392) (xy 371.34053 -257.71133) (xy 371.370822 -257.754396) (xy 371.394185 -257.801581)
			(xy 371.410071 -257.85178) (xy 371.418108 -257.903816) (xy 371.418612 -257.930142) (xy 372.509291 -257.930142)
			(xy 372.513321 -257.877644) (xy 372.525318 -257.826376) (xy 372.545001 -257.777541) (xy 372.571907 -257.732282)
			(xy 372.605407 -257.691661) (xy 372.644715 -257.65663) (xy 372.68891 -257.62801) (xy 372.736955 -257.606471)
			(xy 372.787726 -257.592519) (xy 372.840031 -257.586481) (xy 372.892645 -257.588498) (xy 372.944335 -257.598522)
			(xy 372.993888 -257.61632) (xy 373.040144 -257.641473) (xy 373.082018 -257.673392) (xy 373.11853 -257.71133)
			(xy 373.148822 -257.754396) (xy 373.172185 -257.801581) (xy 373.188071 -257.85178) (xy 373.196108 -257.903816)
			(xy 373.196612 -257.930142) (xy 373.196108 -257.956468) (xy 373.188071 -258.008504) (xy 373.172185 -258.058703)
			(xy 373.148822 -258.105888) (xy 373.11853 -258.148954) (xy 373.082018 -258.186892) (xy 373.040144 -258.218811)
			(xy 372.993888 -258.243964) (xy 372.944335 -258.261762) (xy 372.892645 -258.271786) (xy 372.840031 -258.273803)
			(xy 372.787726 -258.267765) (xy 372.736955 -258.253813) (xy 372.68891 -258.232274) (xy 372.644715 -258.203654)
			(xy 372.605407 -258.168623) (xy 372.571907 -258.128002) (xy 372.545001 -258.082743) (xy 372.525318 -258.033908)
			(xy 372.513321 -257.98264) (xy 372.509291 -257.930142) (xy 371.418612 -257.930142) (xy 371.418108 -257.956468)
			(xy 371.410071 -258.008504) (xy 371.394185 -258.058703) (xy 371.370822 -258.105888) (xy 371.34053 -258.148954)
			(xy 371.304018 -258.186892) (xy 371.262144 -258.218811) (xy 371.215888 -258.243964) (xy 371.166335 -258.261762)
			(xy 371.114645 -258.271786) (xy 371.062031 -258.273803) (xy 371.009726 -258.267765) (xy 370.958955 -258.253813)
			(xy 370.91091 -258.232274) (xy 370.866715 -258.203654) (xy 370.827407 -258.168623) (xy 370.793907 -258.128002)
			(xy 370.767001 -258.082743) (xy 370.747318 -258.033908) (xy 370.735321 -257.98264) (xy 370.731291 -257.930142)
			(xy 369.493038 -257.930142) (xy 369.492534 -257.956468) (xy 369.484497 -258.008504) (xy 369.468611 -258.058703)
			(xy 369.445248 -258.105888) (xy 369.414956 -258.148954) (xy 369.378444 -258.186892) (xy 369.33657 -258.218811)
			(xy 369.290314 -258.243964) (xy 369.240761 -258.261762) (xy 369.189071 -258.271786) (xy 369.136457 -258.273803)
			(xy 369.084152 -258.267765) (xy 369.033381 -258.253813) (xy 368.985336 -258.232274) (xy 368.941141 -258.203654)
			(xy 368.901833 -258.168623) (xy 368.868333 -258.128002) (xy 368.841427 -258.082743) (xy 368.821744 -258.033908)
			(xy 368.809747 -257.98264) (xy 368.805717 -257.930142) (xy 364.4112 -257.930142) (xy 364.387534 -257.963788)
			(xy 364.351022 -258.001726) (xy 364.309148 -258.033645) (xy 364.262892 -258.058798) (xy 364.213339 -258.076596)
			(xy 364.161649 -258.08662) (xy 364.109035 -258.088637) (xy 364.05673 -258.082599) (xy 364.005959 -258.068647)
			(xy 363.957914 -258.047108) (xy 363.913719 -258.018488) (xy 363.874411 -257.983457) (xy 363.840911 -257.942836)
			(xy 363.814005 -257.897577) (xy 363.794322 -257.848742) (xy 363.782325 -257.797474) (xy 363.778295 -257.744976)
			(xy 361.865672 -257.744976) (xy 361.865168 -257.771302) (xy 361.857131 -257.823338) (xy 361.841245 -257.873537)
			(xy 361.817882 -257.920722) (xy 361.78759 -257.963788) (xy 361.751078 -258.001726) (xy 361.709204 -258.033645)
			(xy 361.662948 -258.058798) (xy 361.613395 -258.076596) (xy 361.561705 -258.08662) (xy 361.509091 -258.088637)
			(xy 361.456786 -258.082599) (xy 361.406015 -258.068647) (xy 361.35797 -258.047108) (xy 361.313775 -258.018488)
			(xy 361.274467 -257.983457) (xy 361.240967 -257.942836) (xy 361.214061 -257.897577) (xy 361.194378 -257.848742)
			(xy 361.182381 -257.797474) (xy 361.178351 -257.744976) (xy 359.61574 -257.744976) (xy 359.615236 -257.771302)
			(xy 359.607199 -257.823338) (xy 359.591313 -257.873537) (xy 359.56795 -257.920722) (xy 359.537658 -257.963788)
			(xy 359.501146 -258.001726) (xy 359.459272 -258.033645) (xy 359.413016 -258.058798) (xy 359.363463 -258.076596)
			(xy 359.311773 -258.08662) (xy 359.259159 -258.088637) (xy 359.206854 -258.082599) (xy 359.156083 -258.068647)
			(xy 359.108038 -258.047108) (xy 359.063843 -258.018488) (xy 359.024535 -257.983457) (xy 358.991035 -257.942836)
			(xy 358.964129 -257.897577) (xy 358.944446 -257.848742) (xy 358.932449 -257.797474) (xy 358.928419 -257.744976)
			(xy 357.115618 -257.744976) (xy 357.115114 -257.771302) (xy 357.107077 -257.823338) (xy 357.091191 -257.873537)
			(xy 357.067828 -257.920722) (xy 357.037536 -257.963788) (xy 357.001024 -258.001726) (xy 356.95915 -258.033645)
			(xy 356.912894 -258.058798) (xy 356.863341 -258.076596) (xy 356.811651 -258.08662) (xy 356.759037 -258.088637)
			(xy 356.706732 -258.082599) (xy 356.655961 -258.068647) (xy 356.607916 -258.047108) (xy 356.563721 -258.018488)
			(xy 356.524413 -257.983457) (xy 356.490913 -257.942836) (xy 356.464007 -257.897577) (xy 356.444324 -257.848742)
			(xy 356.432327 -257.797474) (xy 356.428297 -257.744976) (xy 356.201218 -257.744976) (xy 356.200714 -257.771302)
			(xy 356.192677 -257.823338) (xy 356.176791 -257.873537) (xy 356.153428 -257.920722) (xy 356.123136 -257.963788)
			(xy 356.086624 -258.001726) (xy 356.04475 -258.033645) (xy 355.998494 -258.058798) (xy 355.948941 -258.076596)
			(xy 355.897251 -258.08662) (xy 355.844637 -258.088637) (xy 355.792332 -258.082599) (xy 355.741561 -258.068647)
			(xy 355.693516 -258.047108) (xy 355.649321 -258.018488) (xy 355.610013 -257.983457) (xy 355.576513 -257.942836)
			(xy 355.549607 -257.897577) (xy 355.529924 -257.848742) (xy 355.517927 -257.797474) (xy 355.513897 -257.744976)
			(xy 354.482756 -257.744976) (xy 354.436371 -257.761636) (xy 354.384681 -257.77166) (xy 354.332067 -257.773677)
			(xy 354.279762 -257.767639) (xy 354.228991 -257.753687) (xy 354.180946 -257.732148) (xy 354.136751 -257.703528)
			(xy 354.097443 -257.668497) (xy 354.063943 -257.627876) (xy 354.037037 -257.582617) (xy 354.017354 -257.533782)
			(xy 354.005357 -257.482514) (xy 354.001327 -257.430016) (xy 353.774248 -257.430016) (xy 353.773744 -257.456342)
			(xy 353.765707 -257.508378) (xy 353.749821 -257.558577) (xy 353.726458 -257.605762) (xy 353.696166 -257.648828)
			(xy 353.659654 -257.686766) (xy 353.61778 -257.718685) (xy 353.571524 -257.743838) (xy 353.521971 -257.761636)
			(xy 353.470281 -257.77166) (xy 353.417667 -257.773677) (xy 353.365362 -257.767639) (xy 353.314591 -257.753687)
			(xy 353.266546 -257.732148) (xy 353.222351 -257.703528) (xy 353.183043 -257.668497) (xy 353.149543 -257.627876)
			(xy 353.122637 -257.582617) (xy 353.102954 -257.533782) (xy 353.090957 -257.482514) (xy 353.086927 -257.430016)
			(xy 348.60992 -257.430016) (xy 348.60992 -257.524758) (xy 348.610618 -257.537493) (xy 348.622745 -257.559894)
			(xy 348.633034 -257.56743) (xy 348.715838 -257.62077) (xy 348.741746 -257.622802) (xy 348.75343 -257.617214)
			(xy 348.775798 -257.607566) (xy 348.822575 -257.593973) (xy 348.870805 -257.587133) (xy 348.895162 -257.586734)
			(xy 348.920861 -257.587188) (xy 348.971687 -257.594843) (xy 349.020803 -257.609989) (xy 349.067114 -257.632286)
			(xy 349.109583 -257.661237) (xy 349.147263 -257.696195) (xy 349.179311 -257.736379) (xy 349.205012 -257.78089)
			(xy 349.223792 -257.828735) (xy 349.23523 -257.878845) (xy 349.239071 -257.9301) (xy 349.239068 -257.930142)
			(xy 349.536769 -257.930142) (xy 349.540799 -257.877644) (xy 349.552796 -257.826376) (xy 349.572479 -257.777541)
			(xy 349.599385 -257.732282) (xy 349.632885 -257.691661) (xy 349.672193 -257.65663) (xy 349.716388 -257.62801)
			(xy 349.764433 -257.606471) (xy 349.815204 -257.592519) (xy 349.867509 -257.586481) (xy 349.920123 -257.588498)
			(xy 349.971813 -257.598522) (xy 350.021366 -257.61632) (xy 350.067622 -257.641473) (xy 350.109496 -257.673392)
			(xy 350.146008 -257.71133) (xy 350.1763 -257.754396) (xy 350.199663 -257.801581) (xy 350.215549 -257.85178)
			(xy 350.223586 -257.903816) (xy 350.22409 -257.930142) (xy 350.451169 -257.930142) (xy 350.455199 -257.877644)
			(xy 350.467196 -257.826376) (xy 350.486879 -257.777541) (xy 350.513785 -257.732282) (xy 350.547285 -257.691661)
			(xy 350.586593 -257.65663) (xy 350.630788 -257.62801) (xy 350.678833 -257.606471) (xy 350.729604 -257.592519)
			(xy 350.781909 -257.586481) (xy 350.834523 -257.588498) (xy 350.886213 -257.598522) (xy 350.935766 -257.61632)
			(xy 350.982022 -257.641473) (xy 351.023896 -257.673392) (xy 351.060408 -257.71133) (xy 351.0907 -257.754396)
			(xy 351.114063 -257.801581) (xy 351.129949 -257.85178) (xy 351.137986 -257.903816) (xy 351.13849 -257.930142)
			(xy 351.137986 -257.956468) (xy 351.129949 -258.008504) (xy 351.114063 -258.058703) (xy 351.0907 -258.105888)
			(xy 351.060408 -258.148954) (xy 351.023896 -258.186892) (xy 350.982022 -258.218811) (xy 350.935766 -258.243964)
			(xy 350.886213 -258.261762) (xy 350.834523 -258.271786) (xy 350.781909 -258.273803) (xy 350.729604 -258.267765)
			(xy 350.678833 -258.253813) (xy 350.630788 -258.232274) (xy 350.586593 -258.203654) (xy 350.547285 -258.168623)
			(xy 350.513785 -258.128002) (xy 350.486879 -258.082743) (xy 350.467196 -258.033908) (xy 350.455199 -257.98264)
			(xy 350.451169 -257.930142) (xy 350.22409 -257.930142) (xy 350.223586 -257.956468) (xy 350.215549 -258.008504)
			(xy 350.199663 -258.058703) (xy 350.1763 -258.105888) (xy 350.146008 -258.148954) (xy 350.109496 -258.186892)
			(xy 350.067622 -258.218811) (xy 350.021366 -258.243964) (xy 349.971813 -258.261762) (xy 349.920123 -258.271786)
			(xy 349.867509 -258.273803) (xy 349.815204 -258.267765) (xy 349.764433 -258.253813) (xy 349.716388 -258.232274)
			(xy 349.672193 -258.203654) (xy 349.632885 -258.168623) (xy 349.599385 -258.128002) (xy 349.572479 -258.082743)
			(xy 349.552796 -258.033908) (xy 349.540799 -257.98264) (xy 349.536769 -257.930142) (xy 349.239068 -257.930142)
			(xy 349.23523 -257.981355) (xy 349.223792 -258.031465) (xy 349.205012 -258.07931) (xy 349.179311 -258.123821)
			(xy 349.147263 -258.164005) (xy 349.109583 -258.198963) (xy 349.067114 -258.227914) (xy 349.020803 -258.250211)
			(xy 348.971687 -258.265357) (xy 348.920861 -258.273012) (xy 348.895162 -258.27355) (xy 348.870806 -258.273145)
			(xy 348.822576 -258.266305) (xy 348.775795 -258.252724) (xy 348.75343 -258.24307) (xy 348.741746 -258.237482)
			(xy 348.715838 -258.239514) (xy 348.633034 -258.292854) (xy 348.626104 -258.297716) (xy 348.615692 -258.311053)
			(xy 348.610223 -258.327065) (xy 348.60992 -258.335526) (xy 348.60992 -258.379976) (xy 353.086927 -258.379976)
			(xy 353.090957 -258.327478) (xy 353.102954 -258.27621) (xy 353.122637 -258.227375) (xy 353.149543 -258.182116)
			(xy 353.183043 -258.141495) (xy 353.222351 -258.106464) (xy 353.266546 -258.077844) (xy 353.314591 -258.056305)
			(xy 353.365362 -258.042353) (xy 353.417667 -258.036315) (xy 353.470281 -258.038332) (xy 353.521971 -258.048356)
			(xy 353.571524 -258.066154) (xy 353.61778 -258.091307) (xy 353.659654 -258.123226) (xy 353.696166 -258.161164)
			(xy 353.726458 -258.20423) (xy 353.749821 -258.251415) (xy 353.765707 -258.301614) (xy 353.773744 -258.35365)
			(xy 353.774248 -258.379976) (xy 354.001327 -258.379976) (xy 354.005357 -258.327478) (xy 354.017354 -258.27621)
			(xy 354.037037 -258.227375) (xy 354.063943 -258.182116) (xy 354.097443 -258.141495) (xy 354.136751 -258.106464)
			(xy 354.180946 -258.077844) (xy 354.228991 -258.056305) (xy 354.279762 -258.042353) (xy 354.332067 -258.036315)
			(xy 354.384681 -258.038332) (xy 354.436371 -258.048356) (xy 354.485924 -258.066154) (xy 354.53218 -258.091307)
			(xy 354.574054 -258.123226) (xy 354.610566 -258.161164) (xy 354.640858 -258.20423) (xy 354.664221 -258.251415)
			(xy 354.680107 -258.301614) (xy 354.688144 -258.35365) (xy 354.688648 -258.379976) (xy 365.036865 -258.379976)
			(xy 365.040895 -258.327478) (xy 365.052892 -258.27621) (xy 365.072575 -258.227375) (xy 365.099481 -258.182116)
			(xy 365.132981 -258.141495) (xy 365.172289 -258.106464) (xy 365.216484 -258.077844) (xy 365.264529 -258.056305)
			(xy 365.3153 -258.042353) (xy 365.367605 -258.036315) (xy 365.420219 -258.038332) (xy 365.471909 -258.048356)
			(xy 365.521462 -258.066154) (xy 365.567718 -258.091307) (xy 365.609592 -258.123226) (xy 365.646104 -258.161164)
			(xy 365.676396 -258.20423) (xy 365.699759 -258.251415) (xy 365.715645 -258.301614) (xy 365.723682 -258.35365)
			(xy 365.724186 -258.379976) (xy 365.723682 -258.406302) (xy 365.715645 -258.458338) (xy 365.699759 -258.508537)
			(xy 365.676396 -258.555722) (xy 365.646104 -258.598788) (xy 365.609592 -258.636726) (xy 365.567718 -258.668645)
			(xy 365.521462 -258.693798) (xy 365.471909 -258.711596) (xy 365.420219 -258.72162) (xy 365.367605 -258.723637)
			(xy 365.3153 -258.717599) (xy 365.264529 -258.703647) (xy 365.216484 -258.682108) (xy 365.172289 -258.653488)
			(xy 365.132981 -258.618457) (xy 365.099481 -258.577836) (xy 365.072575 -258.532577) (xy 365.052892 -258.483742)
			(xy 365.040895 -258.432474) (xy 365.036865 -258.379976) (xy 354.688648 -258.379976) (xy 354.688144 -258.406302)
			(xy 354.680107 -258.458338) (xy 354.664221 -258.508537) (xy 354.640858 -258.555722) (xy 354.610566 -258.598788)
			(xy 354.574054 -258.636726) (xy 354.53218 -258.668645) (xy 354.485924 -258.693798) (xy 354.436371 -258.711596)
			(xy 354.384681 -258.72162) (xy 354.332067 -258.723637) (xy 354.279762 -258.717599) (xy 354.228991 -258.703647)
			(xy 354.180946 -258.682108) (xy 354.136751 -258.653488) (xy 354.097443 -258.618457) (xy 354.063943 -258.577836)
			(xy 354.037037 -258.532577) (xy 354.017354 -258.483742) (xy 354.005357 -258.432474) (xy 354.001327 -258.379976)
			(xy 353.774248 -258.379976) (xy 353.773744 -258.406302) (xy 353.765707 -258.458338) (xy 353.749821 -258.508537)
			(xy 353.726458 -258.555722) (xy 353.696166 -258.598788) (xy 353.659654 -258.636726) (xy 353.61778 -258.668645)
			(xy 353.571524 -258.693798) (xy 353.521971 -258.711596) (xy 353.470281 -258.72162) (xy 353.417667 -258.723637)
			(xy 353.365362 -258.717599) (xy 353.314591 -258.703647) (xy 353.266546 -258.682108) (xy 353.222351 -258.653488)
			(xy 353.183043 -258.618457) (xy 353.149543 -258.577836) (xy 353.122637 -258.532577) (xy 353.102954 -258.483742)
			(xy 353.090957 -258.432474) (xy 353.086927 -258.379976) (xy 348.60992 -258.379976) (xy 348.60992 -258.42468)
			(xy 348.610623 -258.437413) (xy 348.622755 -258.459804) (xy 348.633034 -258.467352) (xy 348.715838 -258.520692)
			(xy 348.741746 -258.522724) (xy 348.75343 -258.517136) (xy 348.775798 -258.507487) (xy 348.822575 -258.493893)
			(xy 348.870805 -258.487053) (xy 348.895162 -258.486656) (xy 348.920867 -258.48711) (xy 348.971704 -258.494767)
			(xy 349.020832 -258.509916) (xy 349.067153 -258.532218) (xy 349.109632 -258.561176) (xy 349.147321 -258.596142)
			(xy 349.179376 -258.636334) (xy 349.205083 -258.680856) (xy 349.223867 -258.728712) (xy 349.235307 -258.778833)
			(xy 349.239147 -258.830064) (xy 349.536769 -258.830064) (xy 349.540799 -258.777566) (xy 349.552796 -258.726298)
			(xy 349.572479 -258.677463) (xy 349.599385 -258.632204) (xy 349.632885 -258.591583) (xy 349.672193 -258.556552)
			(xy 349.716388 -258.527932) (xy 349.764433 -258.506393) (xy 349.815204 -258.492441) (xy 349.867509 -258.486403)
			(xy 349.920123 -258.48842) (xy 349.971813 -258.498444) (xy 350.021366 -258.516242) (xy 350.067622 -258.541395)
			(xy 350.109496 -258.573314) (xy 350.146008 -258.611252) (xy 350.1763 -258.654318) (xy 350.199663 -258.701503)
			(xy 350.215549 -258.751702) (xy 350.223586 -258.803738) (xy 350.22409 -258.830064) (xy 350.451169 -258.830064)
			(xy 350.455199 -258.777566) (xy 350.467196 -258.726298) (xy 350.486879 -258.677463) (xy 350.513785 -258.632204)
			(xy 350.547285 -258.591583) (xy 350.586593 -258.556552) (xy 350.630788 -258.527932) (xy 350.678833 -258.506393)
			(xy 350.729604 -258.492441) (xy 350.781909 -258.486403) (xy 350.834523 -258.48842) (xy 350.886213 -258.498444)
			(xy 350.935766 -258.516242) (xy 350.982022 -258.541395) (xy 351.023896 -258.573314) (xy 351.060408 -258.611252)
			(xy 351.0907 -258.654318) (xy 351.114063 -258.701503) (xy 351.129949 -258.751702) (xy 351.136638 -258.795012)
			(xy 355.513897 -258.795012) (xy 355.517927 -258.742514) (xy 355.529924 -258.691246) (xy 355.549607 -258.642411)
			(xy 355.576513 -258.597152) (xy 355.610013 -258.556531) (xy 355.649321 -258.5215) (xy 355.693516 -258.49288)
			(xy 355.741561 -258.471341) (xy 355.792332 -258.457389) (xy 355.844637 -258.451351) (xy 355.897251 -258.453368)
			(xy 355.948941 -258.463392) (xy 355.998494 -258.48119) (xy 356.04475 -258.506343) (xy 356.086624 -258.538262)
			(xy 356.123136 -258.5762) (xy 356.153428 -258.619266) (xy 356.176791 -258.666451) (xy 356.192677 -258.71665)
			(xy 356.200714 -258.768686) (xy 356.201218 -258.795012) (xy 356.428297 -258.795012) (xy 356.432327 -258.742514)
			(xy 356.444324 -258.691246) (xy 356.464007 -258.642411) (xy 356.490913 -258.597152) (xy 356.524413 -258.556531)
			(xy 356.563721 -258.5215) (xy 356.607916 -258.49288) (xy 356.655961 -258.471341) (xy 356.706732 -258.457389)
			(xy 356.759037 -258.451351) (xy 356.811651 -258.453368) (xy 356.863341 -258.463392) (xy 356.912894 -258.48119)
			(xy 356.95915 -258.506343) (xy 357.001024 -258.538262) (xy 357.037536 -258.5762) (xy 357.067828 -258.619266)
			(xy 357.091191 -258.666451) (xy 357.107077 -258.71665) (xy 357.115114 -258.768686) (xy 357.115618 -258.795012)
			(xy 358.014019 -258.795012) (xy 358.018049 -258.742514) (xy 358.030046 -258.691246) (xy 358.049729 -258.642411)
			(xy 358.076635 -258.597152) (xy 358.110135 -258.556531) (xy 358.149443 -258.5215) (xy 358.193638 -258.49288)
			(xy 358.241683 -258.471341) (xy 358.292454 -258.457389) (xy 358.344759 -258.451351) (xy 358.397373 -258.453368)
			(xy 358.449063 -258.463392) (xy 358.498616 -258.48119) (xy 358.544872 -258.506343) (xy 358.586746 -258.538262)
			(xy 358.623258 -258.5762) (xy 358.65355 -258.619266) (xy 358.676913 -258.666451) (xy 358.692799 -258.71665)
			(xy 358.700836 -258.768686) (xy 358.70134 -258.795012) (xy 358.928419 -258.795012) (xy 358.932449 -258.742514)
			(xy 358.944446 -258.691246) (xy 358.964129 -258.642411) (xy 358.991035 -258.597152) (xy 359.024535 -258.556531)
			(xy 359.063843 -258.5215) (xy 359.108038 -258.49288) (xy 359.156083 -258.471341) (xy 359.206854 -258.457389)
			(xy 359.259159 -258.451351) (xy 359.311773 -258.453368) (xy 359.363463 -258.463392) (xy 359.413016 -258.48119)
			(xy 359.459272 -258.506343) (xy 359.501146 -258.538262) (xy 359.537658 -258.5762) (xy 359.56795 -258.619266)
			(xy 359.591313 -258.666451) (xy 359.607199 -258.71665) (xy 359.615236 -258.768686) (xy 359.61574 -258.795012)
			(xy 361.178351 -258.795012) (xy 361.182381 -258.742514) (xy 361.194378 -258.691246) (xy 361.214061 -258.642411)
			(xy 361.240967 -258.597152) (xy 361.274467 -258.556531) (xy 361.313775 -258.5215) (xy 361.35797 -258.49288)
			(xy 361.406015 -258.471341) (xy 361.456786 -258.457389) (xy 361.509091 -258.451351) (xy 361.561705 -258.453368)
			(xy 361.613395 -258.463392) (xy 361.662948 -258.48119) (xy 361.709204 -258.506343) (xy 361.751078 -258.538262)
			(xy 361.78759 -258.5762) (xy 361.817882 -258.619266) (xy 361.841245 -258.666451) (xy 361.857131 -258.71665)
			(xy 361.865168 -258.768686) (xy 361.865672 -258.795012) (xy 363.778295 -258.795012) (xy 363.782325 -258.742514)
			(xy 363.794322 -258.691246) (xy 363.814005 -258.642411) (xy 363.840911 -258.597152) (xy 363.874411 -258.556531)
			(xy 363.913719 -258.5215) (xy 363.957914 -258.49288) (xy 364.005959 -258.471341) (xy 364.05673 -258.457389)
			(xy 364.109035 -258.451351) (xy 364.161649 -258.453368) (xy 364.213339 -258.463392) (xy 364.262892 -258.48119)
			(xy 364.309148 -258.506343) (xy 364.351022 -258.538262) (xy 364.387534 -258.5762) (xy 364.417826 -258.619266)
			(xy 364.441189 -258.666451) (xy 364.457075 -258.71665) (xy 364.465112 -258.768686) (xy 364.465616 -258.795012)
			(xy 364.465112 -258.821338) (xy 364.463764 -258.830064) (xy 368.805717 -258.830064) (xy 368.809747 -258.777566)
			(xy 368.821744 -258.726298) (xy 368.841427 -258.677463) (xy 368.868333 -258.632204) (xy 368.901833 -258.591583)
			(xy 368.941141 -258.556552) (xy 368.985336 -258.527932) (xy 369.033381 -258.506393) (xy 369.084152 -258.492441)
			(xy 369.136457 -258.486403) (xy 369.189071 -258.48842) (xy 369.240761 -258.498444) (xy 369.290314 -258.516242)
			(xy 369.33657 -258.541395) (xy 369.378444 -258.573314) (xy 369.414956 -258.611252) (xy 369.445248 -258.654318)
			(xy 369.468611 -258.701503) (xy 369.484497 -258.751702) (xy 369.492534 -258.803738) (xy 369.493038 -258.830064)
			(xy 370.731291 -258.830064) (xy 370.735321 -258.777566) (xy 370.747318 -258.726298) (xy 370.767001 -258.677463)
			(xy 370.793907 -258.632204) (xy 370.827407 -258.591583) (xy 370.866715 -258.556552) (xy 370.91091 -258.527932)
			(xy 370.958955 -258.506393) (xy 371.009726 -258.492441) (xy 371.062031 -258.486403) (xy 371.114645 -258.48842)
			(xy 371.166335 -258.498444) (xy 371.215888 -258.516242) (xy 371.262144 -258.541395) (xy 371.304018 -258.573314)
			(xy 371.34053 -258.611252) (xy 371.370822 -258.654318) (xy 371.394185 -258.701503) (xy 371.410071 -258.751702)
			(xy 371.418108 -258.803738) (xy 371.418612 -258.830064) (xy 372.509291 -258.830064) (xy 372.513321 -258.777566)
			(xy 372.525318 -258.726298) (xy 372.545001 -258.677463) (xy 372.571907 -258.632204) (xy 372.605407 -258.591583)
			(xy 372.644715 -258.556552) (xy 372.68891 -258.527932) (xy 372.736955 -258.506393) (xy 372.787726 -258.492441)
			(xy 372.840031 -258.486403) (xy 372.892645 -258.48842) (xy 372.944335 -258.498444) (xy 372.993888 -258.516242)
			(xy 373.040144 -258.541395) (xy 373.082018 -258.573314) (xy 373.11853 -258.611252) (xy 373.148822 -258.654318)
			(xy 373.172185 -258.701503) (xy 373.188071 -258.751702) (xy 373.196108 -258.803738) (xy 373.196612 -258.830064)
			(xy 373.196108 -258.85639) (xy 373.188071 -258.908426) (xy 373.172185 -258.958625) (xy 373.148822 -259.00581)
			(xy 373.11853 -259.048876) (xy 373.082018 -259.086814) (xy 373.040144 -259.118733) (xy 372.993888 -259.143886)
			(xy 372.944335 -259.161684) (xy 372.892645 -259.171708) (xy 372.840031 -259.173725) (xy 372.787726 -259.167687)
			(xy 372.736955 -259.153735) (xy 372.68891 -259.132196) (xy 372.644715 -259.103576) (xy 372.605407 -259.068545)
			(xy 372.571907 -259.027924) (xy 372.545001 -258.982665) (xy 372.525318 -258.93383) (xy 372.513321 -258.882562)
			(xy 372.509291 -258.830064) (xy 371.418612 -258.830064) (xy 371.418108 -258.85639) (xy 371.410071 -258.908426)
			(xy 371.394185 -258.958625) (xy 371.370822 -259.00581) (xy 371.34053 -259.048876) (xy 371.304018 -259.086814)
			(xy 371.262144 -259.118733) (xy 371.215888 -259.143886) (xy 371.166335 -259.161684) (xy 371.114645 -259.171708)
			(xy 371.062031 -259.173725) (xy 371.009726 -259.167687) (xy 370.958955 -259.153735) (xy 370.91091 -259.132196)
			(xy 370.866715 -259.103576) (xy 370.827407 -259.068545) (xy 370.793907 -259.027924) (xy 370.767001 -258.982665)
			(xy 370.747318 -258.93383) (xy 370.735321 -258.882562) (xy 370.731291 -258.830064) (xy 369.493038 -258.830064)
			(xy 369.492534 -258.85639) (xy 369.484497 -258.908426) (xy 369.468611 -258.958625) (xy 369.445248 -259.00581)
			(xy 369.414956 -259.048876) (xy 369.378444 -259.086814) (xy 369.33657 -259.118733) (xy 369.290314 -259.143886)
			(xy 369.240761 -259.161684) (xy 369.189071 -259.171708) (xy 369.136457 -259.173725) (xy 369.084152 -259.167687)
			(xy 369.033381 -259.153735) (xy 368.985336 -259.132196) (xy 368.941141 -259.103576) (xy 368.901833 -259.068545)
			(xy 368.868333 -259.027924) (xy 368.841427 -258.982665) (xy 368.821744 -258.93383) (xy 368.809747 -258.882562)
			(xy 368.805717 -258.830064) (xy 364.463764 -258.830064) (xy 364.457075 -258.873374) (xy 364.441189 -258.923573)
			(xy 364.417826 -258.970758) (xy 364.387534 -259.013824) (xy 364.351022 -259.051762) (xy 364.309148 -259.083681)
			(xy 364.262892 -259.108834) (xy 364.213339 -259.126632) (xy 364.161649 -259.136656) (xy 364.109035 -259.138673)
			(xy 364.05673 -259.132635) (xy 364.005959 -259.118683) (xy 363.957914 -259.097144) (xy 363.913719 -259.068524)
			(xy 363.874411 -259.033493) (xy 363.840911 -258.992872) (xy 363.814005 -258.947613) (xy 363.794322 -258.898778)
			(xy 363.782325 -258.84751) (xy 363.778295 -258.795012) (xy 361.865672 -258.795012) (xy 361.865168 -258.821338)
			(xy 361.857131 -258.873374) (xy 361.841245 -258.923573) (xy 361.817882 -258.970758) (xy 361.78759 -259.013824)
			(xy 361.751078 -259.051762) (xy 361.709204 -259.083681) (xy 361.662948 -259.108834) (xy 361.613395 -259.126632)
			(xy 361.561705 -259.136656) (xy 361.509091 -259.138673) (xy 361.456786 -259.132635) (xy 361.406015 -259.118683)
			(xy 361.35797 -259.097144) (xy 361.313775 -259.068524) (xy 361.274467 -259.033493) (xy 361.240967 -258.992872)
			(xy 361.214061 -258.947613) (xy 361.194378 -258.898778) (xy 361.182381 -258.84751) (xy 361.178351 -258.795012)
			(xy 359.61574 -258.795012) (xy 359.615236 -258.821338) (xy 359.607199 -258.873374) (xy 359.591313 -258.923573)
			(xy 359.56795 -258.970758) (xy 359.537658 -259.013824) (xy 359.501146 -259.051762) (xy 359.459272 -259.083681)
			(xy 359.413016 -259.108834) (xy 359.363463 -259.126632) (xy 359.311773 -259.136656) (xy 359.259159 -259.138673)
			(xy 359.206854 -259.132635) (xy 359.156083 -259.118683) (xy 359.108038 -259.097144) (xy 359.063843 -259.068524)
			(xy 359.024535 -259.033493) (xy 358.991035 -258.992872) (xy 358.964129 -258.947613) (xy 358.944446 -258.898778)
			(xy 358.932449 -258.84751) (xy 358.928419 -258.795012) (xy 358.70134 -258.795012) (xy 358.700836 -258.821338)
			(xy 358.692799 -258.873374) (xy 358.676913 -258.923573) (xy 358.65355 -258.970758) (xy 358.623258 -259.013824)
			(xy 358.586746 -259.051762) (xy 358.544872 -259.083681) (xy 358.498616 -259.108834) (xy 358.449063 -259.126632)
			(xy 358.397373 -259.136656) (xy 358.344759 -259.138673) (xy 358.292454 -259.132635) (xy 358.241683 -259.118683)
			(xy 358.193638 -259.097144) (xy 358.149443 -259.068524) (xy 358.110135 -259.033493) (xy 358.076635 -258.992872)
			(xy 358.049729 -258.947613) (xy 358.030046 -258.898778) (xy 358.018049 -258.84751) (xy 358.014019 -258.795012)
			(xy 357.115618 -258.795012) (xy 357.115114 -258.821338) (xy 357.107077 -258.873374) (xy 357.091191 -258.923573)
			(xy 357.067828 -258.970758) (xy 357.037536 -259.013824) (xy 357.001024 -259.051762) (xy 356.95915 -259.083681)
			(xy 356.912894 -259.108834) (xy 356.863341 -259.126632) (xy 356.811651 -259.136656) (xy 356.759037 -259.138673)
			(xy 356.706732 -259.132635) (xy 356.655961 -259.118683) (xy 356.607916 -259.097144) (xy 356.563721 -259.068524)
			(xy 356.524413 -259.033493) (xy 356.490913 -258.992872) (xy 356.464007 -258.947613) (xy 356.444324 -258.898778)
			(xy 356.432327 -258.84751) (xy 356.428297 -258.795012) (xy 356.201218 -258.795012) (xy 356.200714 -258.821338)
			(xy 356.192677 -258.873374) (xy 356.176791 -258.923573) (xy 356.153428 -258.970758) (xy 356.123136 -259.013824)
			(xy 356.086624 -259.051762) (xy 356.04475 -259.083681) (xy 355.998494 -259.108834) (xy 355.948941 -259.126632)
			(xy 355.897251 -259.136656) (xy 355.844637 -259.138673) (xy 355.792332 -259.132635) (xy 355.741561 -259.118683)
			(xy 355.693516 -259.097144) (xy 355.649321 -259.068524) (xy 355.610013 -259.033493) (xy 355.576513 -258.992872)
			(xy 355.549607 -258.947613) (xy 355.529924 -258.898778) (xy 355.517927 -258.84751) (xy 355.513897 -258.795012)
			(xy 351.136638 -258.795012) (xy 351.137986 -258.803738) (xy 351.13849 -258.830064) (xy 351.137986 -258.85639)
			(xy 351.129949 -258.908426) (xy 351.114063 -258.958625) (xy 351.0907 -259.00581) (xy 351.060408 -259.048876)
			(xy 351.023896 -259.086814) (xy 350.982022 -259.118733) (xy 350.935766 -259.143886) (xy 350.886213 -259.161684)
			(xy 350.834523 -259.171708) (xy 350.781909 -259.173725) (xy 350.729604 -259.167687) (xy 350.678833 -259.153735)
			(xy 350.630788 -259.132196) (xy 350.586593 -259.103576) (xy 350.547285 -259.068545) (xy 350.513785 -259.027924)
			(xy 350.486879 -258.982665) (xy 350.467196 -258.93383) (xy 350.455199 -258.882562) (xy 350.451169 -258.830064)
			(xy 350.22409 -258.830064) (xy 350.223586 -258.85639) (xy 350.215549 -258.908426) (xy 350.199663 -258.958625)
			(xy 350.1763 -259.00581) (xy 350.146008 -259.048876) (xy 350.109496 -259.086814) (xy 350.067622 -259.118733)
			(xy 350.021366 -259.143886) (xy 349.971813 -259.161684) (xy 349.920123 -259.171708) (xy 349.867509 -259.173725)
			(xy 349.815204 -259.167687) (xy 349.764433 -259.153735) (xy 349.716388 -259.132196) (xy 349.672193 -259.103576)
			(xy 349.632885 -259.068545) (xy 349.599385 -259.027924) (xy 349.572479 -258.982665) (xy 349.552796 -258.93383)
			(xy 349.540799 -258.882562) (xy 349.536769 -258.830064) (xy 349.239147 -258.830064) (xy 349.23915 -258.8301)
			(xy 349.235307 -258.881367) (xy 349.223867 -258.931488) (xy 349.205083 -258.979344) (xy 349.179376 -259.023866)
			(xy 349.14732 -259.064058) (xy 349.109632 -259.099024) (xy 349.067153 -259.127982) (xy 349.020832 -259.150284)
			(xy 348.971704 -259.165433) (xy 348.920867 -259.17309) (xy 348.895162 -259.173472) (xy 348.870805 -259.173067)
			(xy 348.822576 -259.166227) (xy 348.775794 -259.152648) (xy 348.75343 -259.142992) (xy 348.741746 -259.137404)
			(xy 348.715838 -259.139436) (xy 348.633034 -259.192776) (xy 348.626095 -259.197635) (xy 348.615663 -259.210969)
			(xy 348.610169 -259.226982) (xy 348.60992 -259.235448) (xy 348.60992 -259.324602) (xy 348.610231 -259.33019)
			(xy 353.086927 -259.33019) (xy 353.090957 -259.277692) (xy 353.102954 -259.226424) (xy 353.122637 -259.177589)
			(xy 353.149543 -259.13233) (xy 353.183043 -259.091709) (xy 353.222351 -259.056678) (xy 353.266546 -259.028058)
			(xy 353.314591 -259.006519) (xy 353.365362 -258.992567) (xy 353.417667 -258.986529) (xy 353.470281 -258.988546)
			(xy 353.521971 -258.99857) (xy 353.571524 -259.016368) (xy 353.61778 -259.041521) (xy 353.659654 -259.07344)
			(xy 353.696166 -259.111378) (xy 353.726458 -259.154444) (xy 353.749821 -259.201629) (xy 353.765707 -259.251828)
			(xy 353.773744 -259.303864) (xy 353.774248 -259.33019) (xy 354.001327 -259.33019) (xy 354.005357 -259.277692)
			(xy 354.017354 -259.226424) (xy 354.037037 -259.177589) (xy 354.063943 -259.13233) (xy 354.097443 -259.091709)
			(xy 354.136751 -259.056678) (xy 354.180946 -259.028058) (xy 354.228991 -259.006519) (xy 354.279762 -258.992567)
			(xy 354.332067 -258.986529) (xy 354.384681 -258.988546) (xy 354.436371 -258.99857) (xy 354.485924 -259.016368)
			(xy 354.53218 -259.041521) (xy 354.574054 -259.07344) (xy 354.610566 -259.111378) (xy 354.640858 -259.154444)
			(xy 354.664221 -259.201629) (xy 354.680107 -259.251828) (xy 354.688144 -259.303864) (xy 354.688648 -259.33019)
			(xy 365.036865 -259.33019) (xy 365.040895 -259.277692) (xy 365.052892 -259.226424) (xy 365.072575 -259.177589)
			(xy 365.099481 -259.13233) (xy 365.132981 -259.091709) (xy 365.172289 -259.056678) (xy 365.216484 -259.028058)
			(xy 365.264529 -259.006519) (xy 365.3153 -258.992567) (xy 365.367605 -258.986529) (xy 365.420219 -258.988546)
			(xy 365.471909 -258.99857) (xy 365.521462 -259.016368) (xy 365.567718 -259.041521) (xy 365.609592 -259.07344)
			(xy 365.646104 -259.111378) (xy 365.676396 -259.154444) (xy 365.699759 -259.201629) (xy 365.715645 -259.251828)
			(xy 365.723682 -259.303864) (xy 365.724186 -259.33019) (xy 365.723682 -259.356516) (xy 365.715645 -259.408552)
			(xy 365.699759 -259.458751) (xy 365.676396 -259.505936) (xy 365.646104 -259.549002) (xy 365.609592 -259.58694)
			(xy 365.567718 -259.618859) (xy 365.521462 -259.644012) (xy 365.471909 -259.66181) (xy 365.420219 -259.671834)
			(xy 365.367605 -259.673851) (xy 365.3153 -259.667813) (xy 365.264529 -259.653861) (xy 365.216484 -259.632322)
			(xy 365.172289 -259.603702) (xy 365.132981 -259.568671) (xy 365.099481 -259.52805) (xy 365.072575 -259.482791)
			(xy 365.052892 -259.433956) (xy 365.040895 -259.382688) (xy 365.036865 -259.33019) (xy 354.688648 -259.33019)
			(xy 354.688144 -259.356516) (xy 354.680107 -259.408552) (xy 354.664221 -259.458751) (xy 354.640858 -259.505936)
			(xy 354.610566 -259.549002) (xy 354.574054 -259.58694) (xy 354.53218 -259.618859) (xy 354.485924 -259.644012)
			(xy 354.436371 -259.66181) (xy 354.384681 -259.671834) (xy 354.332067 -259.673851) (xy 354.279762 -259.667813)
			(xy 354.228991 -259.653861) (xy 354.180946 -259.632322) (xy 354.136751 -259.603702) (xy 354.097443 -259.568671)
			(xy 354.063943 -259.52805) (xy 354.037037 -259.482791) (xy 354.017354 -259.433956) (xy 354.005357 -259.382688)
			(xy 354.001327 -259.33019) (xy 353.774248 -259.33019) (xy 353.773744 -259.356516) (xy 353.765707 -259.408552)
			(xy 353.749821 -259.458751) (xy 353.726458 -259.505936) (xy 353.696166 -259.549002) (xy 353.659654 -259.58694)
			(xy 353.61778 -259.618859) (xy 353.571524 -259.644012) (xy 353.521971 -259.66181) (xy 353.470281 -259.671834)
			(xy 353.417667 -259.673851) (xy 353.365362 -259.667813) (xy 353.314591 -259.653861) (xy 353.266546 -259.632322)
			(xy 353.222351 -259.603702) (xy 353.183043 -259.568671) (xy 353.149543 -259.52805) (xy 353.122637 -259.482791)
			(xy 353.102954 -259.433956) (xy 353.090957 -259.382688) (xy 353.086927 -259.33019) (xy 348.610231 -259.33019)
			(xy 348.610628 -259.337332) (xy 348.622765 -259.359715) (xy 348.633034 -259.367274) (xy 348.715838 -259.420614)
			(xy 348.741746 -259.422646) (xy 348.75343 -259.417058) (xy 348.775798 -259.407412) (xy 348.822576 -259.393821)
			(xy 348.870806 -259.386982) (xy 348.895162 -259.386578) (xy 348.920866 -259.387031) (xy 348.971699 -259.394688)
			(xy 349.020824 -259.409836) (xy 349.067142 -259.432137) (xy 349.109618 -259.461093) (xy 349.147304 -259.496057)
			(xy 349.179358 -259.536247) (xy 349.205063 -259.580766) (xy 349.223846 -259.628619) (xy 349.235286 -259.678737)
			(xy 349.239127 -259.729986) (xy 349.536769 -259.729986) (xy 349.540799 -259.677488) (xy 349.552796 -259.62622)
			(xy 349.572479 -259.577385) (xy 349.599385 -259.532126) (xy 349.632885 -259.491505) (xy 349.672193 -259.456474)
			(xy 349.716388 -259.427854) (xy 349.764433 -259.406315) (xy 349.815204 -259.392363) (xy 349.867509 -259.386325)
			(xy 349.920123 -259.388342) (xy 349.971813 -259.398366) (xy 350.021366 -259.416164) (xy 350.067622 -259.441317)
			(xy 350.109496 -259.473236) (xy 350.146008 -259.511174) (xy 350.1763 -259.55424) (xy 350.199663 -259.601425)
			(xy 350.215549 -259.651624) (xy 350.223586 -259.70366) (xy 350.22409 -259.729986) (xy 350.451169 -259.729986)
			(xy 350.455199 -259.677488) (xy 350.467196 -259.62622) (xy 350.486879 -259.577385) (xy 350.513785 -259.532126)
			(xy 350.547285 -259.491505) (xy 350.586593 -259.456474) (xy 350.630788 -259.427854) (xy 350.678833 -259.406315)
			(xy 350.729604 -259.392363) (xy 350.781909 -259.386325) (xy 350.834523 -259.388342) (xy 350.886213 -259.398366)
			(xy 350.935766 -259.416164) (xy 350.982022 -259.441317) (xy 351.023896 -259.473236) (xy 351.060408 -259.511174)
			(xy 351.0907 -259.55424) (xy 351.114063 -259.601425) (xy 351.129949 -259.651624) (xy 351.137986 -259.70366)
			(xy 351.13849 -259.729986) (xy 351.137986 -259.756312) (xy 351.129949 -259.808348) (xy 351.118335 -259.845048)
			(xy 355.513897 -259.845048) (xy 355.517927 -259.79255) (xy 355.529924 -259.741282) (xy 355.549607 -259.692447)
			(xy 355.576513 -259.647188) (xy 355.610013 -259.606567) (xy 355.649321 -259.571536) (xy 355.693516 -259.542916)
			(xy 355.741561 -259.521377) (xy 355.792332 -259.507425) (xy 355.844637 -259.501387) (xy 355.897251 -259.503404)
			(xy 355.948941 -259.513428) (xy 355.998494 -259.531226) (xy 356.04475 -259.556379) (xy 356.086624 -259.588298)
			(xy 356.123136 -259.626236) (xy 356.153428 -259.669302) (xy 356.176791 -259.716487) (xy 356.192677 -259.766686)
			(xy 356.200714 -259.818722) (xy 356.201218 -259.845048) (xy 356.428297 -259.845048) (xy 356.432327 -259.79255)
			(xy 356.444324 -259.741282) (xy 356.464007 -259.692447) (xy 356.490913 -259.647188) (xy 356.524413 -259.606567)
			(xy 356.563721 -259.571536) (xy 356.607916 -259.542916) (xy 356.655961 -259.521377) (xy 356.706732 -259.507425)
			(xy 356.759037 -259.501387) (xy 356.811651 -259.503404) (xy 356.863341 -259.513428) (xy 356.912894 -259.531226)
			(xy 356.95915 -259.556379) (xy 357.001024 -259.588298) (xy 357.037536 -259.626236) (xy 357.067828 -259.669302)
			(xy 357.091191 -259.716487) (xy 357.107077 -259.766686) (xy 357.115114 -259.818722) (xy 357.115618 -259.845048)
			(xy 358.014019 -259.845048) (xy 358.018049 -259.79255) (xy 358.030046 -259.741282) (xy 358.049729 -259.692447)
			(xy 358.076635 -259.647188) (xy 358.110135 -259.606567) (xy 358.149443 -259.571536) (xy 358.193638 -259.542916)
			(xy 358.241683 -259.521377) (xy 358.292454 -259.507425) (xy 358.344759 -259.501387) (xy 358.397373 -259.503404)
			(xy 358.449063 -259.513428) (xy 358.498616 -259.531226) (xy 358.544872 -259.556379) (xy 358.586746 -259.588298)
			(xy 358.623258 -259.626236) (xy 358.65355 -259.669302) (xy 358.676913 -259.716487) (xy 358.692799 -259.766686)
			(xy 358.700836 -259.818722) (xy 358.70134 -259.845048) (xy 358.928419 -259.845048) (xy 358.932449 -259.79255)
			(xy 358.944446 -259.741282) (xy 358.964129 -259.692447) (xy 358.991035 -259.647188) (xy 359.024535 -259.606567)
			(xy 359.063843 -259.571536) (xy 359.108038 -259.542916) (xy 359.156083 -259.521377) (xy 359.206854 -259.507425)
			(xy 359.259159 -259.501387) (xy 359.311773 -259.503404) (xy 359.363463 -259.513428) (xy 359.413016 -259.531226)
			(xy 359.459272 -259.556379) (xy 359.501146 -259.588298) (xy 359.537658 -259.626236) (xy 359.56795 -259.669302)
			(xy 359.591313 -259.716487) (xy 359.607199 -259.766686) (xy 359.615236 -259.818722) (xy 359.61574 -259.845048)
			(xy 360.263951 -259.845048) (xy 360.267981 -259.79255) (xy 360.279978 -259.741282) (xy 360.299661 -259.692447)
			(xy 360.326567 -259.647188) (xy 360.360067 -259.606567) (xy 360.399375 -259.571536) (xy 360.44357 -259.542916)
			(xy 360.491615 -259.521377) (xy 360.542386 -259.507425) (xy 360.594691 -259.501387) (xy 360.647305 -259.503404)
			(xy 360.698995 -259.513428) (xy 360.748548 -259.531226) (xy 360.794804 -259.556379) (xy 360.836678 -259.588298)
			(xy 360.87319 -259.626236) (xy 360.903482 -259.669302) (xy 360.926845 -259.716487) (xy 360.942731 -259.766686)
			(xy 360.950768 -259.818722) (xy 360.951272 -259.845048) (xy 361.178351 -259.845048) (xy 361.182381 -259.79255)
			(xy 361.194378 -259.741282) (xy 361.214061 -259.692447) (xy 361.240967 -259.647188) (xy 361.274467 -259.606567)
			(xy 361.313775 -259.571536) (xy 361.35797 -259.542916) (xy 361.406015 -259.521377) (xy 361.456786 -259.507425)
			(xy 361.509091 -259.501387) (xy 361.561705 -259.503404) (xy 361.613395 -259.513428) (xy 361.662948 -259.531226)
			(xy 361.709204 -259.556379) (xy 361.751078 -259.588298) (xy 361.78759 -259.626236) (xy 361.817882 -259.669302)
			(xy 361.841245 -259.716487) (xy 361.857131 -259.766686) (xy 361.865168 -259.818722) (xy 361.865672 -259.845048)
			(xy 362.863895 -259.845048) (xy 362.867925 -259.79255) (xy 362.879922 -259.741282) (xy 362.899605 -259.692447)
			(xy 362.926511 -259.647188) (xy 362.960011 -259.606567) (xy 362.999319 -259.571536) (xy 363.043514 -259.542916)
			(xy 363.091559 -259.521377) (xy 363.14233 -259.507425) (xy 363.194635 -259.501387) (xy 363.247249 -259.503404)
			(xy 363.298939 -259.513428) (xy 363.348492 -259.531226) (xy 363.394748 -259.556379) (xy 363.436622 -259.588298)
			(xy 363.473134 -259.626236) (xy 363.503426 -259.669302) (xy 363.526789 -259.716487) (xy 363.542675 -259.766686)
			(xy 363.550712 -259.818722) (xy 363.551216 -259.845048) (xy 363.778295 -259.845048) (xy 363.782325 -259.79255)
			(xy 363.794322 -259.741282) (xy 363.814005 -259.692447) (xy 363.840911 -259.647188) (xy 363.874411 -259.606567)
			(xy 363.913719 -259.571536) (xy 363.957914 -259.542916) (xy 364.005959 -259.521377) (xy 364.05673 -259.507425)
			(xy 364.109035 -259.501387) (xy 364.161649 -259.503404) (xy 364.213339 -259.513428) (xy 364.262892 -259.531226)
			(xy 364.309148 -259.556379) (xy 364.351022 -259.588298) (xy 364.387534 -259.626236) (xy 364.417826 -259.669302)
			(xy 364.441189 -259.716487) (xy 364.445461 -259.729986) (xy 368.805717 -259.729986) (xy 368.809747 -259.677488)
			(xy 368.821744 -259.62622) (xy 368.841427 -259.577385) (xy 368.868333 -259.532126) (xy 368.901833 -259.491505)
			(xy 368.941141 -259.456474) (xy 368.985336 -259.427854) (xy 369.033381 -259.406315) (xy 369.084152 -259.392363)
			(xy 369.136457 -259.386325) (xy 369.189071 -259.388342) (xy 369.240761 -259.398366) (xy 369.290314 -259.416164)
			(xy 369.33657 -259.441317) (xy 369.378444 -259.473236) (xy 369.414956 -259.511174) (xy 369.445248 -259.55424)
			(xy 369.468611 -259.601425) (xy 369.484497 -259.651624) (xy 369.492534 -259.70366) (xy 369.493038 -259.729986)
			(xy 370.731291 -259.729986) (xy 370.735321 -259.677488) (xy 370.747318 -259.62622) (xy 370.767001 -259.577385)
			(xy 370.793907 -259.532126) (xy 370.827407 -259.491505) (xy 370.866715 -259.456474) (xy 370.91091 -259.427854)
			(xy 370.958955 -259.406315) (xy 371.009726 -259.392363) (xy 371.062031 -259.386325) (xy 371.114645 -259.388342)
			(xy 371.166335 -259.398366) (xy 371.215888 -259.416164) (xy 371.262144 -259.441317) (xy 371.304018 -259.473236)
			(xy 371.34053 -259.511174) (xy 371.370822 -259.55424) (xy 371.394185 -259.601425) (xy 371.410071 -259.651624)
			(xy 371.418108 -259.70366) (xy 371.418612 -259.729986) (xy 372.509291 -259.729986) (xy 372.513321 -259.677488)
			(xy 372.525318 -259.62622) (xy 372.545001 -259.577385) (xy 372.571907 -259.532126) (xy 372.605407 -259.491505)
			(xy 372.644715 -259.456474) (xy 372.68891 -259.427854) (xy 372.736955 -259.406315) (xy 372.787726 -259.392363)
			(xy 372.840031 -259.386325) (xy 372.892645 -259.388342) (xy 372.944335 -259.398366) (xy 372.993888 -259.416164)
			(xy 373.040144 -259.441317) (xy 373.082018 -259.473236) (xy 373.11853 -259.511174) (xy 373.148822 -259.55424)
			(xy 373.172185 -259.601425) (xy 373.188071 -259.651624) (xy 373.196108 -259.70366) (xy 373.196612 -259.729986)
			(xy 373.196108 -259.756312) (xy 373.188071 -259.808348) (xy 373.172185 -259.858547) (xy 373.148822 -259.905732)
			(xy 373.11853 -259.948798) (xy 373.082018 -259.986736) (xy 373.040144 -260.018655) (xy 372.993888 -260.043808)
			(xy 372.944335 -260.061606) (xy 372.892645 -260.07163) (xy 372.840031 -260.073647) (xy 372.787726 -260.067609)
			(xy 372.736955 -260.053657) (xy 372.68891 -260.032118) (xy 372.644715 -260.003498) (xy 372.605407 -259.968467)
			(xy 372.571907 -259.927846) (xy 372.545001 -259.882587) (xy 372.525318 -259.833752) (xy 372.513321 -259.782484)
			(xy 372.509291 -259.729986) (xy 371.418612 -259.729986) (xy 371.418108 -259.756312) (xy 371.410071 -259.808348)
			(xy 371.394185 -259.858547) (xy 371.370822 -259.905732) (xy 371.34053 -259.948798) (xy 371.304018 -259.986736)
			(xy 371.262144 -260.018655) (xy 371.215888 -260.043808) (xy 371.166335 -260.061606) (xy 371.114645 -260.07163)
			(xy 371.062031 -260.073647) (xy 371.009726 -260.067609) (xy 370.958955 -260.053657) (xy 370.91091 -260.032118)
			(xy 370.866715 -260.003498) (xy 370.827407 -259.968467) (xy 370.793907 -259.927846) (xy 370.767001 -259.882587)
			(xy 370.747318 -259.833752) (xy 370.735321 -259.782484) (xy 370.731291 -259.729986) (xy 369.493038 -259.729986)
			(xy 369.492534 -259.756312) (xy 369.484497 -259.808348) (xy 369.468611 -259.858547) (xy 369.445248 -259.905732)
			(xy 369.414956 -259.948798) (xy 369.378444 -259.986736) (xy 369.33657 -260.018655) (xy 369.290314 -260.043808)
			(xy 369.240761 -260.061606) (xy 369.189071 -260.07163) (xy 369.136457 -260.073647) (xy 369.084152 -260.067609)
			(xy 369.033381 -260.053657) (xy 368.985336 -260.032118) (xy 368.941141 -260.003498) (xy 368.901833 -259.968467)
			(xy 368.868333 -259.927846) (xy 368.841427 -259.882587) (xy 368.821744 -259.833752) (xy 368.809747 -259.782484)
			(xy 368.805717 -259.729986) (xy 364.445461 -259.729986) (xy 364.457075 -259.766686) (xy 364.465112 -259.818722)
			(xy 364.465616 -259.845048) (xy 364.465112 -259.871374) (xy 364.457075 -259.92341) (xy 364.441189 -259.973609)
			(xy 364.417826 -260.020794) (xy 364.387534 -260.06386) (xy 364.351022 -260.101798) (xy 364.309148 -260.133717)
			(xy 364.262892 -260.15887) (xy 364.213339 -260.176668) (xy 364.161649 -260.186692) (xy 364.109035 -260.188709)
			(xy 364.05673 -260.182671) (xy 364.005959 -260.168719) (xy 363.957914 -260.14718) (xy 363.913719 -260.11856)
			(xy 363.874411 -260.083529) (xy 363.840911 -260.042908) (xy 363.814005 -259.997649) (xy 363.794322 -259.948814)
			(xy 363.782325 -259.897546) (xy 363.778295 -259.845048) (xy 363.551216 -259.845048) (xy 363.550712 -259.871374)
			(xy 363.542675 -259.92341) (xy 363.526789 -259.973609) (xy 363.503426 -260.020794) (xy 363.473134 -260.06386)
			(xy 363.436622 -260.101798) (xy 363.394748 -260.133717) (xy 363.348492 -260.15887) (xy 363.298939 -260.176668)
			(xy 363.247249 -260.186692) (xy 363.194635 -260.188709) (xy 363.14233 -260.182671) (xy 363.091559 -260.168719)
			(xy 363.043514 -260.14718) (xy 362.999319 -260.11856) (xy 362.960011 -260.083529) (xy 362.926511 -260.042908)
			(xy 362.899605 -259.997649) (xy 362.879922 -259.948814) (xy 362.867925 -259.897546) (xy 362.863895 -259.845048)
			(xy 361.865672 -259.845048) (xy 361.865168 -259.871374) (xy 361.857131 -259.92341) (xy 361.841245 -259.973609)
			(xy 361.817882 -260.020794) (xy 361.78759 -260.06386) (xy 361.751078 -260.101798) (xy 361.709204 -260.133717)
			(xy 361.662948 -260.15887) (xy 361.613395 -260.176668) (xy 361.561705 -260.186692) (xy 361.509091 -260.188709)
			(xy 361.456786 -260.182671) (xy 361.406015 -260.168719) (xy 361.35797 -260.14718) (xy 361.313775 -260.11856)
			(xy 361.274467 -260.083529) (xy 361.240967 -260.042908) (xy 361.214061 -259.997649) (xy 361.194378 -259.948814)
			(xy 361.182381 -259.897546) (xy 361.178351 -259.845048) (xy 360.951272 -259.845048) (xy 360.950768 -259.871374)
			(xy 360.942731 -259.92341) (xy 360.926845 -259.973609) (xy 360.903482 -260.020794) (xy 360.87319 -260.06386)
			(xy 360.836678 -260.101798) (xy 360.794804 -260.133717) (xy 360.748548 -260.15887) (xy 360.698995 -260.176668)
			(xy 360.647305 -260.186692) (xy 360.594691 -260.188709) (xy 360.542386 -260.182671) (xy 360.491615 -260.168719)
			(xy 360.44357 -260.14718) (xy 360.399375 -260.11856) (xy 360.360067 -260.083529) (xy 360.326567 -260.042908)
			(xy 360.299661 -259.997649) (xy 360.279978 -259.948814) (xy 360.267981 -259.897546) (xy 360.263951 -259.845048)
			(xy 359.61574 -259.845048) (xy 359.615236 -259.871374) (xy 359.607199 -259.92341) (xy 359.591313 -259.973609)
			(xy 359.56795 -260.020794) (xy 359.537658 -260.06386) (xy 359.501146 -260.101798) (xy 359.459272 -260.133717)
			(xy 359.413016 -260.15887) (xy 359.363463 -260.176668) (xy 359.311773 -260.186692) (xy 359.259159 -260.188709)
			(xy 359.206854 -260.182671) (xy 359.156083 -260.168719) (xy 359.108038 -260.14718) (xy 359.063843 -260.11856)
			(xy 359.024535 -260.083529) (xy 358.991035 -260.042908) (xy 358.964129 -259.997649) (xy 358.944446 -259.948814)
			(xy 358.932449 -259.897546) (xy 358.928419 -259.845048) (xy 358.70134 -259.845048) (xy 358.700836 -259.871374)
			(xy 358.692799 -259.92341) (xy 358.676913 -259.973609) (xy 358.65355 -260.020794) (xy 358.623258 -260.06386)
			(xy 358.586746 -260.101798) (xy 358.544872 -260.133717) (xy 358.498616 -260.15887) (xy 358.449063 -260.176668)
			(xy 358.397373 -260.186692) (xy 358.344759 -260.188709) (xy 358.292454 -260.182671) (xy 358.241683 -260.168719)
			(xy 358.193638 -260.14718) (xy 358.149443 -260.11856) (xy 358.110135 -260.083529) (xy 358.076635 -260.042908)
			(xy 358.049729 -259.997649) (xy 358.030046 -259.948814) (xy 358.018049 -259.897546) (xy 358.014019 -259.845048)
			(xy 357.115618 -259.845048) (xy 357.115114 -259.871374) (xy 357.107077 -259.92341) (xy 357.091191 -259.973609)
			(xy 357.067828 -260.020794) (xy 357.037536 -260.06386) (xy 357.001024 -260.101798) (xy 356.95915 -260.133717)
			(xy 356.912894 -260.15887) (xy 356.863341 -260.176668) (xy 356.811651 -260.186692) (xy 356.759037 -260.188709)
			(xy 356.706732 -260.182671) (xy 356.655961 -260.168719) (xy 356.607916 -260.14718) (xy 356.563721 -260.11856)
			(xy 356.524413 -260.083529) (xy 356.490913 -260.042908) (xy 356.464007 -259.997649) (xy 356.444324 -259.948814)
			(xy 356.432327 -259.897546) (xy 356.428297 -259.845048) (xy 356.201218 -259.845048) (xy 356.200714 -259.871374)
			(xy 356.192677 -259.92341) (xy 356.176791 -259.973609) (xy 356.153428 -260.020794) (xy 356.123136 -260.06386)
			(xy 356.086624 -260.101798) (xy 356.04475 -260.133717) (xy 355.998494 -260.15887) (xy 355.948941 -260.176668)
			(xy 355.897251 -260.186692) (xy 355.844637 -260.188709) (xy 355.792332 -260.182671) (xy 355.741561 -260.168719)
			(xy 355.693516 -260.14718) (xy 355.649321 -260.11856) (xy 355.610013 -260.083529) (xy 355.576513 -260.042908)
			(xy 355.549607 -259.997649) (xy 355.529924 -259.948814) (xy 355.517927 -259.897546) (xy 355.513897 -259.845048)
			(xy 351.118335 -259.845048) (xy 351.114063 -259.858547) (xy 351.0907 -259.905732) (xy 351.060408 -259.948798)
			(xy 351.023896 -259.986736) (xy 350.982022 -260.018655) (xy 350.935766 -260.043808) (xy 350.886213 -260.061606)
			(xy 350.834523 -260.07163) (xy 350.781909 -260.073647) (xy 350.729604 -260.067609) (xy 350.678833 -260.053657)
			(xy 350.630788 -260.032118) (xy 350.586593 -260.003498) (xy 350.547285 -259.968467) (xy 350.513785 -259.927846)
			(xy 350.486879 -259.882587) (xy 350.467196 -259.833752) (xy 350.455199 -259.782484) (xy 350.451169 -259.729986)
			(xy 350.22409 -259.729986) (xy 350.223586 -259.756312) (xy 350.215549 -259.808348) (xy 350.199663 -259.858547)
			(xy 350.1763 -259.905732) (xy 350.146008 -259.948798) (xy 350.109496 -259.986736) (xy 350.067622 -260.018655)
			(xy 350.021366 -260.043808) (xy 349.971813 -260.061606) (xy 349.920123 -260.07163) (xy 349.867509 -260.073647)
			(xy 349.815204 -260.067609) (xy 349.764433 -260.053657) (xy 349.716388 -260.032118) (xy 349.672193 -260.003498)
			(xy 349.632885 -259.968467) (xy 349.599385 -259.927846) (xy 349.572479 -259.882587) (xy 349.552796 -259.833752)
			(xy 349.540799 -259.782484) (xy 349.536769 -259.729986) (xy 349.239127 -259.729986) (xy 349.239128 -259.73)
			(xy 349.235286 -259.781263) (xy 349.223846 -259.831381) (xy 349.205063 -259.879234) (xy 349.179358 -259.923753)
			(xy 349.147304 -259.963943) (xy 349.109618 -259.998907) (xy 349.067142 -260.027863) (xy 349.020824 -260.050164)
			(xy 348.971699 -260.065312) (xy 348.920866 -260.072969) (xy 348.895162 -260.073394) (xy 348.870805 -260.072989)
			(xy 348.822575 -260.06615) (xy 348.775794 -260.052571) (xy 348.75343 -260.042914) (xy 348.741746 -260.037326)
			(xy 348.715838 -260.039358) (xy 348.633034 -260.092698) (xy 348.626098 -260.097558) (xy 348.615671 -260.110892)
			(xy 348.610184 -260.126906) (xy 348.60992 -260.13537) (xy 348.60992 -260.28015) (xy 353.086927 -260.28015)
			(xy 353.090957 -260.227652) (xy 353.102954 -260.176384) (xy 353.122637 -260.127549) (xy 353.149543 -260.08229)
			(xy 353.183043 -260.041669) (xy 353.222351 -260.006638) (xy 353.266546 -259.978018) (xy 353.314591 -259.956479)
			(xy 353.365362 -259.942527) (xy 353.417667 -259.936489) (xy 353.470281 -259.938506) (xy 353.521971 -259.94853)
			(xy 353.571524 -259.966328) (xy 353.61778 -259.991481) (xy 353.659654 -260.0234) (xy 353.696166 -260.061338)
			(xy 353.726458 -260.104404) (xy 353.749821 -260.151589) (xy 353.765707 -260.201788) (xy 353.773744 -260.253824)
			(xy 353.774248 -260.28015) (xy 354.001327 -260.28015) (xy 354.005357 -260.227652) (xy 354.017354 -260.176384)
			(xy 354.037037 -260.127549) (xy 354.063943 -260.08229) (xy 354.097443 -260.041669) (xy 354.136751 -260.006638)
			(xy 354.180946 -259.978018) (xy 354.228991 -259.956479) (xy 354.279762 -259.942527) (xy 354.332067 -259.936489)
			(xy 354.384681 -259.938506) (xy 354.436371 -259.94853) (xy 354.485924 -259.966328) (xy 354.53218 -259.991481)
			(xy 354.574054 -260.0234) (xy 354.610566 -260.061338) (xy 354.640858 -260.104404) (xy 354.664221 -260.151589)
			(xy 354.680107 -260.201788) (xy 354.688144 -260.253824) (xy 354.688648 -260.28015) (xy 365.036865 -260.28015)
			(xy 365.040895 -260.227652) (xy 365.052892 -260.176384) (xy 365.072575 -260.127549) (xy 365.099481 -260.08229)
			(xy 365.132981 -260.041669) (xy 365.172289 -260.006638) (xy 365.216484 -259.978018) (xy 365.264529 -259.956479)
			(xy 365.3153 -259.942527) (xy 365.367605 -259.936489) (xy 365.420219 -259.938506) (xy 365.471909 -259.94853)
			(xy 365.521462 -259.966328) (xy 365.567718 -259.991481) (xy 365.609592 -260.0234) (xy 365.646104 -260.061338)
			(xy 365.676396 -260.104404) (xy 365.699759 -260.151589) (xy 365.715645 -260.201788) (xy 365.723682 -260.253824)
			(xy 365.724186 -260.28015) (xy 365.723682 -260.306476) (xy 365.715645 -260.358512) (xy 365.699759 -260.408711)
			(xy 365.676396 -260.455896) (xy 365.646104 -260.498962) (xy 365.609592 -260.5369) (xy 365.567718 -260.568819)
			(xy 365.521462 -260.593972) (xy 365.471909 -260.61177) (xy 365.420219 -260.621794) (xy 365.367605 -260.623811)
			(xy 365.3153 -260.617773) (xy 365.264529 -260.603821) (xy 365.216484 -260.582282) (xy 365.172289 -260.553662)
			(xy 365.132981 -260.518631) (xy 365.099481 -260.47801) (xy 365.072575 -260.432751) (xy 365.052892 -260.383916)
			(xy 365.040895 -260.332648) (xy 365.036865 -260.28015) (xy 354.688648 -260.28015) (xy 354.688144 -260.306476)
			(xy 354.680107 -260.358512) (xy 354.664221 -260.408711) (xy 354.640858 -260.455896) (xy 354.610566 -260.498962)
			(xy 354.574054 -260.5369) (xy 354.53218 -260.568819) (xy 354.485924 -260.593972) (xy 354.436371 -260.61177)
			(xy 354.384681 -260.621794) (xy 354.332067 -260.623811) (xy 354.279762 -260.617773) (xy 354.228991 -260.603821)
			(xy 354.180946 -260.582282) (xy 354.136751 -260.553662) (xy 354.097443 -260.518631) (xy 354.063943 -260.47801)
			(xy 354.037037 -260.432751) (xy 354.017354 -260.383916) (xy 354.005357 -260.332648) (xy 354.001327 -260.28015)
			(xy 353.774248 -260.28015) (xy 353.773744 -260.306476) (xy 353.765707 -260.358512) (xy 353.749821 -260.408711)
			(xy 353.726458 -260.455896) (xy 353.696166 -260.498962) (xy 353.659654 -260.5369) (xy 353.61778 -260.568819)
			(xy 353.571524 -260.593972) (xy 353.521971 -260.61177) (xy 353.470281 -260.621794) (xy 353.417667 -260.623811)
			(xy 353.365362 -260.617773) (xy 353.314591 -260.603821) (xy 353.266546 -260.582282) (xy 353.222351 -260.553662)
			(xy 353.183043 -260.518631) (xy 353.149543 -260.47801) (xy 353.122637 -260.432751) (xy 353.102954 -260.383916)
			(xy 353.090957 -260.332648) (xy 353.086927 -260.28015) (xy 348.60992 -260.28015) (xy 348.60992 -261.12597)
			(xy 348.905334 -261.12597) (xy 348.909294 -261.076916) (xy 348.921071 -261.029132) (xy 348.940362 -260.983856)
			(xy 348.966665 -260.94226) (xy 348.9993 -260.905423) (xy 349.037421 -260.874298) (xy 349.080042 -260.849691)
			(xy 349.126058 -260.832239) (xy 349.174277 -260.822395) (xy 349.223452 -260.820414) (xy 349.272307 -260.826346)
			(xy 349.319578 -260.840038) (xy 349.36404 -260.861136) (xy 349.404543 -260.889092) (xy 349.440036 -260.923184)
			(xy 349.469601 -260.962528) (xy 349.492472 -261.006105) (xy 349.508056 -261.052786) (xy 349.515951 -261.101363)
			(xy 349.516446 -261.12597) (xy 349.516405 -261.128002) (xy 351.722194 -261.128002) (xy 351.726154 -261.078948)
			(xy 351.737931 -261.031164) (xy 351.757222 -260.985888) (xy 351.783525 -260.944292) (xy 351.81616 -260.907455)
			(xy 351.854281 -260.87633) (xy 351.896902 -260.851723) (xy 351.942918 -260.834271) (xy 351.991137 -260.824427)
			(xy 352.040312 -260.822446) (xy 352.089167 -260.828378) (xy 352.136438 -260.84207) (xy 352.1809 -260.863168)
			(xy 352.221403 -260.891124) (xy 352.256896 -260.925216) (xy 352.286461 -260.96456) (xy 352.309332 -261.008137)
			(xy 352.324916 -261.054818) (xy 352.332811 -261.103395) (xy 352.333306 -261.128002) (xy 352.332811 -261.152609)
			(xy 352.324916 -261.201186) (xy 352.309332 -261.247867) (xy 352.286461 -261.291444) (xy 352.256896 -261.330788)
			(xy 352.221403 -261.36488) (xy 352.1809 -261.392836) (xy 352.136438 -261.413934) (xy 352.089167 -261.427626)
			(xy 352.040312 -261.433558) (xy 351.991137 -261.431577) (xy 351.942918 -261.421733) (xy 351.896902 -261.404281)
			(xy 351.854281 -261.379674) (xy 351.81616 -261.348549) (xy 351.783525 -261.311712) (xy 351.757222 -261.270116)
			(xy 351.737931 -261.22484) (xy 351.726154 -261.177056) (xy 351.722194 -261.128002) (xy 349.516405 -261.128002)
			(xy 349.515951 -261.150577) (xy 349.508056 -261.199154) (xy 349.492472 -261.245835) (xy 349.469601 -261.289412)
			(xy 349.440036 -261.328756) (xy 349.404543 -261.362848) (xy 349.36404 -261.390804) (xy 349.319578 -261.411902)
			(xy 349.272307 -261.425594) (xy 349.223452 -261.431526) (xy 349.174277 -261.429545) (xy 349.126058 -261.419701)
			(xy 349.080042 -261.402249) (xy 349.037421 -261.377642) (xy 348.9993 -261.346517) (xy 348.966665 -261.30968)
			(xy 348.940362 -261.268084) (xy 348.921071 -261.222808) (xy 348.909294 -261.175024) (xy 348.905334 -261.12597)
			(xy 348.60992 -261.12597) (xy 348.60992 -261.530084) (xy 348.610392 -261.539955) (xy 348.617855 -261.558235)
			(xy 348.624398 -261.565644) (xy 348.625414 -261.56666) (xy 348.680532 -261.617968) (xy 348.688516 -261.624698)
			(xy 348.70819 -261.631627) (xy 348.718632 -261.63143) (xy 348.718886 -261.63143) (xy 348.741238 -261.630668)
			(xy 348.766493 -261.631193) (xy 348.816314 -261.639512) (xy 348.864086 -261.655917) (xy 348.908507 -261.679962)
			(xy 348.948365 -261.710989) (xy 348.982572 -261.748153) (xy 349.010197 -261.79044) (xy 349.030486 -261.836697)
			(xy 349.042884 -261.885662) (xy 349.047053 -261.935976) (xy 349.375234 -261.935976) (xy 349.379194 -261.886922)
			(xy 349.390971 -261.839138) (xy 349.410262 -261.793862) (xy 349.436565 -261.752266) (xy 349.4692 -261.715429)
			(xy 349.507321 -261.684304) (xy 349.549942 -261.659697) (xy 349.595958 -261.642245) (xy 349.644177 -261.632401)
			(xy 349.693352 -261.63042) (xy 349.742207 -261.636352) (xy 349.789478 -261.650044) (xy 349.83394 -261.671142)
			(xy 349.874443 -261.699098) (xy 349.909936 -261.73319) (xy 349.939501 -261.772534) (xy 349.962372 -261.816111)
			(xy 349.977956 -261.862792) (xy 349.985851 -261.911369) (xy 349.986346 -261.935976) (xy 349.985851 -261.960583)
			(xy 349.977956 -262.00916) (xy 349.962372 -262.055841) (xy 349.939501 -262.099418) (xy 349.909936 -262.138762)
			(xy 349.874443 -262.172854) (xy 349.83394 -262.20081) (xy 349.789478 -262.221908) (xy 349.742207 -262.2356)
			(xy 349.693352 -262.241532) (xy 349.644177 -262.239551) (xy 349.595958 -262.229707) (xy 349.549942 -262.212255)
			(xy 349.507321 -262.187648) (xy 349.4692 -262.156523) (xy 349.436565 -262.119686) (xy 349.410262 -262.07809)
			(xy 349.390971 -262.032814) (xy 349.379194 -261.98503) (xy 349.375234 -261.935976) (xy 349.047053 -261.935976)
			(xy 349.047055 -261.936) (xy 349.042884 -261.986338) (xy 349.030486 -262.035303) (xy 349.010197 -262.08156)
			(xy 348.982572 -262.123847) (xy 348.948365 -262.161011) (xy 348.908507 -262.192038) (xy 348.864086 -262.216083)
			(xy 348.816314 -262.232488) (xy 348.766493 -262.240807) (xy 348.741238 -262.241284) (xy 348.718886 -262.240522)
			(xy 348.718632 -262.240522) (xy 348.708191 -262.2403) (xy 348.688523 -262.247259) (xy 348.680532 -262.253984)
			(xy 348.626176 -262.30453) (xy 348.618302 -262.311896) (xy 348.60992 -262.330946) (xy 348.60992 -262.745982)
			(xy 348.905334 -262.745982) (xy 348.909294 -262.696928) (xy 348.921071 -262.649144) (xy 348.940362 -262.603868)
			(xy 348.966665 -262.562272) (xy 348.9993 -262.525435) (xy 349.037421 -262.49431) (xy 349.080042 -262.469703)
			(xy 349.126058 -262.452251) (xy 349.174277 -262.442407) (xy 349.223452 -262.440426) (xy 349.272307 -262.446358)
			(xy 349.319578 -262.46005) (xy 349.36404 -262.481148) (xy 349.404543 -262.509104) (xy 349.440036 -262.543196)
			(xy 349.469601 -262.58254) (xy 349.492472 -262.626117) (xy 349.508056 -262.672798) (xy 349.515951 -262.721375)
			(xy 349.516446 -262.745982) (xy 349.515951 -262.770589) (xy 349.508056 -262.819166) (xy 349.492472 -262.865847)
			(xy 349.469601 -262.909424) (xy 349.440036 -262.948768) (xy 349.404543 -262.98286) (xy 349.36404 -263.010816)
			(xy 349.319578 -263.031914) (xy 349.272307 -263.045606) (xy 349.223452 -263.051538) (xy 349.174277 -263.049557)
			(xy 349.126058 -263.039713) (xy 349.080042 -263.022261) (xy 349.037421 -262.997654) (xy 348.9993 -262.966529)
			(xy 348.966665 -262.929692) (xy 348.940362 -262.888096) (xy 348.921071 -262.84282) (xy 348.909294 -262.795036)
			(xy 348.905334 -262.745982) (xy 348.60992 -262.745982) (xy 348.60992 -263.199118) (xy 348.61038 -263.208995)
			(xy 348.617826 -263.227291) (xy 348.624398 -263.234678) (xy 348.624652 -263.234932) (xy 348.633034 -263.243314)
			(xy 348.642369 -263.251685) (xy 348.666354 -263.258882) (xy 348.678754 -263.25703) (xy 348.679516 -263.25703)
			(xy 348.694774 -263.254065) (xy 348.725696 -263.250882) (xy 348.741238 -263.25068) (xy 348.765475 -263.251148)
			(xy 348.81334 -263.258811) (xy 348.859394 -263.273938) (xy 348.90248 -263.29615) (xy 348.941517 -263.324889)
			(xy 348.975524 -263.359434) (xy 349.003647 -263.398916) (xy 349.025181 -263.442345) (xy 349.039584 -263.48863)
			(xy 349.043498 -263.512554) (xy 349.045276 -263.526016) (xy 349.0468 -263.555988) (xy 349.046612 -263.571657)
			(xy 349.043428 -263.602833) (xy 349.04045 -263.618218) (xy 349.03791 -263.630918) (xy 349.045022 -263.655302)
			(xy 349.158814 -263.769094) (xy 349.159322 -263.769602) (xy 349.166699 -263.776195) (xy 349.184999 -263.783664)
			(xy 349.194882 -263.78408)
		)
		(stroke
			(width 0)
			(type solid)
		)
		(fill yes)
		(layer "In13.Cu")
		(net "PVDDCR_SOC_P0")
	)
)
